(kicad_pcb
	(version 20260206)
	(generator "pcbnew")
	(generator_version "10.0")
	(general
		(thickness 1.6)
		(legacy_teardrops no)
	)
	(paper "A4")
	(layers
		(0 "F.Cu" signal "TOP")
		(4 "In1.Cu" signal "GND")
		(6 "In2.Cu" signal "IN1")
		(8 "In3.Cu" signal "GND1")
		(10 "In4.Cu" signal "IN2")
		(12 "In5.Cu" signal "GND2")
		(14 "In6.Cu" signal "IN3")
		(16 "In7.Cu" signal "GND3")
		(18 "In8.Cu" signal "VCC")
		(20 "In9.Cu" signal "VCC1")
		(22 "In10.Cu" signal "GND4")
		(24 "In11.Cu" signal "IN4")
		(26 "In12.Cu" signal "GND5")
		(28 "In13.Cu" signal "IN5")
		(30 "In14.Cu" signal "GND6")
		(32 "In15.Cu" signal "IN6")
		(34 "In16.Cu" signal "GND7")
		(2 "B.Cu" signal "BOTTOM")
		(9 "F.Adhes" user "F.Adhesive")
		(11 "B.Adhes" user "B.Adhesive")
		(13 "F.Paste" user "Package Geometry/Pastemask Top")
		(15 "B.Paste" user "Package Geometry/Pastemask Bottom")
		(5 "F.SilkS" user "Ref Des/Silkscreen Top")
		(7 "B.SilkS" user "Ref Des/Silkscreen Bottom")
		(1 "F.Mask" user "Board Geometry/Soldermask Top")
		(3 "B.Mask" user "Board Geometry/Soldermask Bottom")
		(17 "Dwgs.User" user "User.Drawings")
		(19 "Cmts.User" user "User.Comments")
		(21 "Eco1.User" user "User.Eco1")
		(23 "Eco2.User" user "User.Eco2")
		(25 "Edge.Cuts" user "Board Geometry/Outline")
		(27 "Margin" user)
		(31 "F.CrtYd" user "Package Geometry/Place Bound Top")
		(29 "B.CrtYd" user "Package Geometry/Place Bound Bottom")
		(35 "F.Fab" user "Ref Des/Assembly Top")
		(33 "B.Fab" user "Ref Des/Assembly Bottom")
	)
	(setup
		(pad_to_mask_clearance 0)
		(allow_soldermask_bridges_in_footprints no)
		(tenting
			(front yes)
			(back yes)
		)
		(covering
			(front no)
			(back no)
		)
		(plugging
			(front no)
			(back no)
		)
		(capping no)
		(filling no)
		(pcbplotparams
			(layerselection 0x00000000_00000000_55555555_5755f5ff)
			(plot_on_all_layers_selection 0x00000000_00000000_00000000_00000000)
			(disableapertmacros no)
			(usegerberextensions no)
			(usegerberattributes yes)
			(usegerberadvancedattributes yes)
			(creategerberjobfile yes)
			(dashed_line_dash_ratio 12)
			(dashed_line_gap_ratio 3)
			(svgprecision 4)
			(plotframeref no)
			(mode 1)
			(useauxorigin no)
			(pdf_front_fp_property_popups yes)
			(pdf_back_fp_property_popups yes)
			(pdf_metadata yes)
			(pdf_single_document no)
			(dxfpolygonmode yes)
			(dxfimperialunits yes)
			(dxfusepcbnewfont yes)
			(psnegative no)
			(psa4output no)
			(plot_black_and_white yes)
			(sketchpadsonfab no)
			(plotpadnumbers no)
			(hidednponfab no)
			(sketchdnponfab yes)
			(crossoutdnponfab yes)
			(subtractmaskfromsilk no)
			(outputformat 1)
			(mirror no)
			(drillshape 1)
			(scaleselection 1)
			(outputdirectory "")
		)
	)
	(gr_poly
		(pts
			(xy 194.495928 -441.17006) (xy 194.49641 -441.126022) (xy 194.50409 -441.03828) (xy 194.519387 -440.951542)
			(xy 194.542185 -440.866466) (xy 194.572311 -440.783702) (xy 194.609536 -440.703878) (xy 194.653576 -440.627602)
			(xy 194.704095 -440.555454) (xy 194.760711 -440.487984) (xy 194.822991 -440.425704) (xy 194.890462 -440.369089)
			(xy 194.96261 -440.31857) (xy 195.038887 -440.274531) (xy 195.118711 -440.237308) (xy 195.201476 -440.207182)
			(xy 195.286551 -440.184385) (xy 195.37329 -440.169088) (xy 195.461032 -440.16141) (xy 195.50507 -440.160918)
			(xy 276.314916 -440.160918) (xy 276.358955 -440.161399) (xy 276.446699 -440.169077) (xy 276.533439 -440.184372)
			(xy 276.618516 -440.207169) (xy 276.701283 -440.237294) (xy 276.781109 -440.274518) (xy 276.857388 -440.318557)
			(xy 276.929538 -440.369076) (xy 276.99701 -440.425692) (xy 277.059292 -440.487972) (xy 277.115909 -440.555443)
			(xy 277.16643 -440.627592) (xy 277.210471 -440.703869) (xy 277.247697 -440.783695) (xy 277.277823 -440.866461)
			(xy 277.300622 -440.951538) (xy 277.31592 -441.038278) (xy 277.3236 -441.126021) (xy 277.324058 -441.17006)
			(xy 277.324058 -441.480956) (xy 463.300064 -441.480956) (xy 463.355834 -441.480449) (xy 463.467062 -441.472116)
			(xy 463.577357 -441.455494) (xy 463.686101 -441.430676) (xy 463.792686 -441.397801) (xy 463.896517 -441.357052)
			(xy 463.997011 -441.308658) (xy 464.093608 -441.252889) (xy 464.185768 -441.190057) (xy 464.272974 -441.120513)
			(xy 464.354739 -441.044647) (xy 464.430606 -440.962883) (xy 464.50015 -440.875677) (xy 464.562982 -440.783519)
			(xy 464.618752 -440.686922) (xy 464.667147 -440.586428) (xy 464.707897 -440.482598) (xy 464.740773 -440.376013)
			(xy 464.765592 -440.267269) (xy 464.782215 -440.156974) (xy 464.790548 -440.045746) (xy 464.791044 -439.989976)
			(xy 464.791044 -419.236652) (xy 464.79206 -419.236652) (xy 464.79206 -419.160198) (xy 464.791552 -419.157912)
			(xy 464.783498 -419.125745) (xy 464.774831 -419.060003) (xy 464.77428 -419.026848) (xy 464.774826 -418.994155)
			(xy 464.783231 -418.929312) (xy 464.791044 -418.897562) (xy 464.791044 -409.528264) (xy 464.791527 -409.457889)
			(xy 464.799416 -409.317359) (xy 464.815173 -409.177493) (xy 464.838748 -409.03873) (xy 464.870067 -408.901508)
			(xy 464.909031 -408.766258) (xy 464.955519 -408.633405) (xy 465.009383 -408.503369) (xy 465.070454 -408.376557)
			(xy 465.138539 -408.25337) (xy 465.213426 -408.134194) (xy 465.294877 -408.019405) (xy 465.382637 -407.909364)
			(xy 465.47643 -407.804418) (xy 465.525866 -407.754328) (xy 467.354412 -405.925782) (xy 467.391723 -405.887821)
			(xy 467.461438 -405.807375) (xy 467.525236 -405.722161) (xy 467.582791 -405.632611) (xy 467.633809 -405.539182)
			(xy 467.678031 -405.442352) (xy 467.715231 -405.342613) (xy 467.74522 -405.240474) (xy 467.767844 -405.136455)
			(xy 467.782988 -405.031087) (xy 467.790575 -404.924907) (xy 467.791038 -404.871682) (xy 467.791038 -82.82813)
			(xy 467.791541 -82.757757) (xy 467.799451 -82.617233) (xy 467.815226 -82.477373) (xy 467.838815 -82.338618)
			(xy 467.870145 -82.201402) (xy 467.909116 -82.066159) (xy 467.955608 -81.933313) (xy 468.009473 -81.803282)
			(xy 468.070541 -81.676474) (xy 468.138622 -81.553289) (xy 468.213501 -81.434114) (xy 468.294942 -81.319323)
			(xy 468.382689 -81.209278) (xy 468.476467 -81.104324) (xy 468.52586 -81.054194) (xy 470.854278 -78.725776)
			(xy 470.891589 -78.687815) (xy 470.961306 -78.60737) (xy 471.025105 -78.522156) (xy 471.082661 -78.432606)
			(xy 471.13368 -78.339178) (xy 471.177903 -78.242348) (xy 471.215103 -78.142608) (xy 471.245092 -78.040469)
			(xy 471.267716 -77.93645) (xy 471.28286 -77.831082) (xy 471.290447 -77.724901) (xy 471.290904 -77.671676)
			(xy 471.290904 -13.780008) (xy 471.290383 -13.724238) (xy 471.282048 -13.613011) (xy 471.265425 -13.502718)
			(xy 471.240606 -13.393975) (xy 471.20773 -13.287391) (xy 471.166981 -13.183562) (xy 471.118587 -13.083068)
			(xy 471.062818 -12.986472) (xy 470.999987 -12.894314) (xy 470.930444 -12.807108) (xy 470.854579 -12.725344)
			(xy 470.772816 -12.649477) (xy 470.685612 -12.579932) (xy 470.593455 -12.517099) (xy 470.49686 -12.461328)
			(xy 470.396367 -12.412932) (xy 470.292539 -12.372181) (xy 470.185956 -12.339303) (xy 470.077214 -12.314481)
			(xy 469.966921 -12.297855) (xy 469.855694 -12.289518) (xy 469.799924 -12.289028) (xy 464.613244 -12.289028)
			(xy 464.613244 -12.288012) (xy 464.272376 -12.288012) (xy 464.272376 -12.289028) (xy 458.20203 -12.289028)
			(xy 458.131647 -12.288544) (xy 457.991102 -12.280653) (xy 457.85122 -12.264894) (xy 457.712443 -12.241316)
			(xy 457.575205 -12.209994) (xy 457.43994 -12.171027) (xy 457.307072 -12.124536) (xy 457.177021 -12.070668)
			(xy 457.050194 -12.009593) (xy 456.926991 -11.941503) (xy 456.8078 -11.866612) (xy 456.692996 -11.785156)
			(xy 456.582939 -11.69739) (xy 456.477977 -11.603592) (xy 456.378439 -11.504056) (xy 456.284639 -11.399096)
			(xy 456.196872 -11.289041) (xy 456.115413 -11.174238) (xy 456.04052 -11.055048) (xy 455.972428 -10.931847)
			(xy 455.911351 -10.805021) (xy 455.857481 -10.674971) (xy 455.810987 -10.542104) (xy 455.772017 -10.406839)
			(xy 455.740693 -10.269603) (xy 455.717113 -10.130825) (xy 455.701351 -9.990944) (xy 455.693457 -9.850399)
			(xy 455.693018 -9.780016) (xy 455.693018 -0.999998) (xy 455.692493 -0.967851) (xy 455.684101 -0.904107)
			(xy 455.667461 -0.842004) (xy 455.642857 -0.782603) (xy 455.610712 -0.726922) (xy 455.571573 -0.675913)
			(xy 455.526112 -0.630449) (xy 455.475106 -0.591307) (xy 455.419427 -0.559158) (xy 455.360029 -0.53455)
			(xy 455.297926 -0.517906) (xy 455.234183 -0.50951) (xy 455.202036 -0.509016) (xy 388.601966 -0.509016)
			(xy 388.569821 -0.509544) (xy 388.506082 -0.517939) (xy 388.443984 -0.534582) (xy 388.384589 -0.559188)
			(xy 388.328914 -0.591335) (xy 388.277911 -0.630474) (xy 388.232453 -0.675936) (xy 388.193318 -0.726941)
			(xy 388.161174 -0.782618) (xy 388.136572 -0.842014) (xy 388.119933 -0.904114) (xy 388.111542 -0.967853)
			(xy 388.110984 -0.999998) (xy 388.110984 -5.169916) (xy 388.850131 -5.169916) (xy 388.854136 -5.082008)
			(xy 388.866119 -4.994828) (xy 388.885979 -4.909099) (xy 388.913554 -4.825531) (xy 388.948613 -4.744817)
			(xy 388.990866 -4.667625) (xy 389.039964 -4.594596) (xy 389.0955 -4.526334) (xy 389.157012 -4.463404)
			(xy 389.223993 -4.40633) (xy 389.295886 -4.355582) (xy 389.372095 -4.311582) (xy 389.45199 -4.274695)
			(xy 389.534909 -4.245226) (xy 389.620164 -4.223419) (xy 389.707048 -4.209455) (xy 389.794842 -4.203449)
			(xy 389.882819 -4.205453) (xy 389.970249 -4.215448) (xy 390.056408 -4.233352) (xy 390.140582 -4.259016)
			(xy 390.222073 -4.292229) (xy 390.300207 -4.332715) (xy 390.374335 -4.380137) (xy 390.443843 -4.434104)
			(xy 390.508157 -4.494169) (xy 390.566741 -4.559833) (xy 390.619112 -4.630552) (xy 390.664835 -4.70574)
			(xy 390.703532 -4.784775) (xy 390.734881 -4.867001) (xy 390.758623 -4.951737) (xy 390.763638 -4.978969)
			(xy 394.947631 -4.978969) (xy 394.947631 -4.924431) (xy 394.955393 -4.870448) (xy 394.970758 -4.81812)
			(xy 394.993414 -4.76851) (xy 395.0229 -4.72263) (xy 395.058614 -4.681413) (xy 395.099832 -4.645698)
			(xy 395.145712 -4.616213) (xy 395.195321 -4.593557) (xy 395.24765 -4.578193) (xy 395.301633 -4.570431)
			(xy 395.328902 -4.569968) (xy 396.192502 -4.569968) (xy 396.219773 -4.570395) (xy 396.273761 -4.578157)
			(xy 396.326094 -4.593524) (xy 396.375708 -4.616182) (xy 396.421593 -4.64567) (xy 396.462813 -4.681388)
			(xy 396.498531 -4.722609) (xy 396.528019 -4.768493) (xy 396.550677 -4.818107) (xy 396.566043 -4.870441)
			(xy 396.573806 -4.924429) (xy 396.573806 -4.978971) (xy 398.547532 -4.978971) (xy 398.547532 -4.924429)
			(xy 398.555294 -4.870443) (xy 398.570661 -4.818111) (xy 398.593321 -4.768498) (xy 398.62281 -4.722616)
			(xy 398.658529 -4.681398) (xy 398.699751 -4.645684) (xy 398.745637 -4.616199) (xy 398.795252 -4.593546)
			(xy 398.847586 -4.578185) (xy 398.901573 -4.570428) (xy 398.928844 -4.569968) (xy 399.792444 -4.569968)
			(xy 399.819713 -4.570398) (xy 399.873697 -4.578165) (xy 399.926025 -4.593535) (xy 399.975633 -4.616196)
			(xy 400.021512 -4.645685) (xy 400.062728 -4.681403) (xy 400.098441 -4.722623) (xy 400.127925 -4.768505)
			(xy 400.15058 -4.818116) (xy 400.165944 -4.870447) (xy 400.173706 -4.92443) (xy 400.173706 -4.978967)
			(xy 402.147554 -4.978967) (xy 402.147554 -4.924433) (xy 402.155315 -4.870455) (xy 402.170678 -4.818131)
			(xy 402.193332 -4.768526) (xy 402.222814 -4.722649) (xy 402.258525 -4.681435) (xy 402.299738 -4.645722)
			(xy 402.345613 -4.616239) (xy 402.395218 -4.593583) (xy 402.447542 -4.578218) (xy 402.501519 -4.570455)
			(xy 402.528786 -4.569968) (xy 403.392386 -4.569968) (xy 403.41966 -4.570371) (xy 403.473652 -4.578132)
			(xy 403.525991 -4.593498) (xy 403.57561 -4.616157) (xy 403.621499 -4.645646) (xy 403.662724 -4.681366)
			(xy 403.698445 -4.72259) (xy 403.727937 -4.768478) (xy 403.750597 -4.818096) (xy 403.765965 -4.870434)
			(xy 403.773728 -4.924426) (xy 403.773728 -4.978966) (xy 405.747754 -4.978966) (xy 405.747754 -4.924434)
			(xy 405.755515 -4.870456) (xy 405.770878 -4.818132) (xy 405.793531 -4.768527) (xy 405.823013 -4.72265)
			(xy 405.858724 -4.681436) (xy 405.899936 -4.645724) (xy 405.945811 -4.61624) (xy 405.995415 -4.593584)
			(xy 406.047738 -4.578219) (xy 406.101716 -4.570456) (xy 406.128982 -4.569968) (xy 406.992582 -4.569968)
			(xy 407.019856 -4.57037) (xy 407.073849 -4.578131) (xy 407.126188 -4.593497) (xy 407.175807 -4.616155)
			(xy 407.221697 -4.645645) (xy 407.262922 -4.681365) (xy 407.298644 -4.722589) (xy 407.328136 -4.768477)
			(xy 407.350797 -4.818095) (xy 407.366165 -4.870433) (xy 407.373928 -4.924426) (xy 407.373928 -4.978971)
			(xy 414.857632 -4.978971) (xy 414.857632 -4.924429) (xy 414.865394 -4.870442) (xy 414.880762 -4.81811)
			(xy 414.903421 -4.768498) (xy 414.93291 -4.722616) (xy 414.96863 -4.681397) (xy 415.009852 -4.645683)
			(xy 415.055738 -4.616199) (xy 415.105353 -4.593546) (xy 415.157687 -4.578184) (xy 415.211675 -4.570428)
			(xy 415.238946 -4.569968) (xy 416.102546 -4.569968) (xy 416.129815 -4.570398) (xy 416.183798 -4.578165)
			(xy 416.236126 -4.593536) (xy 416.285735 -4.616196) (xy 416.331613 -4.645686) (xy 416.372829 -4.681404)
			(xy 416.408542 -4.722624) (xy 416.438026 -4.768506) (xy 416.46068 -4.818117) (xy 416.476045 -4.870447)
			(xy 416.483806 -4.924431) (xy 416.483806 -4.978967) (xy 418.457654 -4.978967) (xy 418.457654 -4.924433)
			(xy 418.465415 -4.870455) (xy 418.480779 -4.818131) (xy 418.503432 -4.768525) (xy 418.532915 -4.722648)
			(xy 418.568626 -4.681434) (xy 418.609839 -4.645722) (xy 418.655715 -4.616238) (xy 418.705319 -4.593583)
			(xy 418.757643 -4.578218) (xy 418.811621 -4.570455) (xy 418.838888 -4.569968) (xy 419.702488 -4.569968)
			(xy 419.729762 -4.570371) (xy 419.783754 -4.578132) (xy 419.836092 -4.593499) (xy 419.885711 -4.616157)
			(xy 419.9316 -4.645647) (xy 419.972824 -4.681367) (xy 420.008546 -4.722591) (xy 420.038037 -4.768479)
			(xy 420.060697 -4.818096) (xy 420.076065 -4.870434) (xy 420.083828 -4.924426) (xy 420.083828 -4.978966)
			(xy 426.067754 -4.978966) (xy 426.067754 -4.924434) (xy 426.075515 -4.870456) (xy 426.090878 -4.818132)
			(xy 426.113531 -4.768527) (xy 426.143013 -4.72265) (xy 426.178724 -4.681436) (xy 426.219936 -4.645724)
			(xy 426.265811 -4.61624) (xy 426.315415 -4.593584) (xy 426.367738 -4.578219) (xy 426.421716 -4.570456)
			(xy 426.448982 -4.569968) (xy 427.312582 -4.569968) (xy 427.339856 -4.57037) (xy 427.393849 -4.578131)
			(xy 427.446188 -4.593497) (xy 427.495807 -4.616155) (xy 427.541697 -4.645645) (xy 427.582922 -4.681365)
			(xy 427.618644 -4.722589) (xy 427.648136 -4.768477) (xy 427.670797 -4.818095) (xy 427.686165 -4.870433)
			(xy 427.693928 -4.924426) (xy 427.693928 -4.97897) (xy 429.667631 -4.97897) (xy 429.667631 -4.92443)
			(xy 429.675394 -4.870445) (xy 429.69076 -4.818115) (xy 429.713417 -4.768504) (xy 429.742905 -4.722623)
			(xy 429.778622 -4.681405) (xy 429.819842 -4.645691) (xy 429.865725 -4.616206) (xy 429.915337 -4.593552)
			(xy 429.967669 -4.578189) (xy 430.021654 -4.57043) (xy 430.048924 -4.569968) (xy 430.912524 -4.569968)
			(xy 430.939794 -4.570396) (xy 430.99378 -4.578161) (xy 431.04611 -4.59353) (xy 431.095721 -4.616189)
			(xy 431.141603 -4.645678) (xy 431.182821 -4.681396) (xy 431.218536 -4.722616) (xy 431.248022 -4.7685)
			(xy 431.270679 -4.818112) (xy 431.286044 -4.870444) (xy 431.293806 -4.92443) (xy 431.293806 -4.97897)
			(xy 431.286044 -5.032956) (xy 431.270679 -5.085288) (xy 431.248022 -5.1349) (xy 431.218536 -5.180784)
			(xy 431.182821 -5.222004) (xy 431.141603 -5.257722) (xy 431.095721 -5.287211) (xy 431.04611 -5.30987)
			(xy 430.99378 -5.325239) (xy 430.939794 -5.333004) (xy 430.912524 -5.333492) (xy 430.048924 -5.333492)
			(xy 430.021654 -5.33297) (xy 429.967669 -5.325211) (xy 429.915337 -5.309848) (xy 429.865725 -5.287194)
			(xy 429.819842 -5.257709) (xy 429.778622 -5.221995) (xy 429.742905 -5.180777) (xy 429.713417 -5.134896)
			(xy 429.69076 -5.085285) (xy 429.675394 -5.032955) (xy 429.667631 -4.97897) (xy 427.693928 -4.97897)
			(xy 427.693928 -4.978974) (xy 427.686165 -5.032967) (xy 427.670797 -5.085305) (xy 427.648136 -5.134923)
			(xy 427.618644 -5.180811) (xy 427.582922 -5.222035) (xy 427.541697 -5.257755) (xy 427.495807 -5.287245)
			(xy 427.446188 -5.309903) (xy 427.393849 -5.325269) (xy 427.339856 -5.33303) (xy 427.312582 -5.333492)
			(xy 426.448982 -5.333492) (xy 426.421716 -5.332944) (xy 426.367738 -5.325181) (xy 426.315415 -5.309816)
			(xy 426.265811 -5.28716) (xy 426.219936 -5.257676) (xy 426.178724 -5.221964) (xy 426.143013 -5.18075)
			(xy 426.113531 -5.134873) (xy 426.090878 -5.085268) (xy 426.075515 -5.032944) (xy 426.067754 -4.978966)
			(xy 420.083828 -4.978966) (xy 420.083828 -4.978974) (xy 420.076065 -5.032966) (xy 420.060697 -5.085304)
			(xy 420.038037 -5.134921) (xy 420.008546 -5.180809) (xy 419.972824 -5.222033) (xy 419.9316 -5.257753)
			(xy 419.885711 -5.287243) (xy 419.836092 -5.309901) (xy 419.783754 -5.325268) (xy 419.729762 -5.333029)
			(xy 419.702488 -5.333492) (xy 418.838888 -5.333492) (xy 418.811621 -5.332945) (xy 418.757643 -5.325182)
			(xy 418.705319 -5.309817) (xy 418.655715 -5.287162) (xy 418.609839 -5.257678) (xy 418.568626 -5.221966)
			(xy 418.532915 -5.180752) (xy 418.503432 -5.134875) (xy 418.480779 -5.085269) (xy 418.465415 -5.032945)
			(xy 418.457654 -4.978967) (xy 416.483806 -4.978967) (xy 416.483806 -4.978969) (xy 416.476045 -5.032953)
			(xy 416.46068 -5.085283) (xy 416.438026 -5.134894) (xy 416.408542 -5.180776) (xy 416.372829 -5.221996)
			(xy 416.331613 -5.257714) (xy 416.285735 -5.287204) (xy 416.236126 -5.309864) (xy 416.183798 -5.325235)
			(xy 416.129815 -5.333002) (xy 416.102546 -5.333492) (xy 415.238946 -5.333492) (xy 415.211675 -5.332972)
			(xy 415.157687 -5.325216) (xy 415.105353 -5.309854) (xy 415.055738 -5.287201) (xy 415.009852 -5.257717)
			(xy 414.96863 -5.222003) (xy 414.93291 -5.180784) (xy 414.903421 -5.134902) (xy 414.880762 -5.08529)
			(xy 414.865394 -5.032958) (xy 414.857632 -4.978971) (xy 407.373928 -4.978971) (xy 407.373928 -4.978974)
			(xy 407.366165 -5.032967) (xy 407.350797 -5.085305) (xy 407.328136 -5.134923) (xy 407.298644 -5.180811)
			(xy 407.262922 -5.222035) (xy 407.221697 -5.257755) (xy 407.175807 -5.287245) (xy 407.126188 -5.309903)
			(xy 407.073849 -5.325269) (xy 407.019856 -5.33303) (xy 406.992582 -5.333492) (xy 406.128982 -5.333492)
			(xy 406.101716 -5.332944) (xy 406.047738 -5.325181) (xy 405.995415 -5.309816) (xy 405.945811 -5.28716)
			(xy 405.899936 -5.257676) (xy 405.858724 -5.221964) (xy 405.823013 -5.18075) (xy 405.793531 -5.134873)
			(xy 405.770878 -5.085268) (xy 405.755515 -5.032944) (xy 405.747754 -4.978966) (xy 403.773728 -4.978966)
			(xy 403.773728 -4.978974) (xy 403.765965 -5.032966) (xy 403.750597 -5.085304) (xy 403.727937 -5.134922)
			(xy 403.698445 -5.18081) (xy 403.662724 -5.222034) (xy 403.621499 -5.257754) (xy 403.57561 -5.287243)
			(xy 403.525991 -5.309902) (xy 403.473652 -5.325268) (xy 403.41966 -5.333029) (xy 403.392386 -5.333492)
			(xy 402.528786 -5.333492) (xy 402.501519 -5.332945) (xy 402.447542 -5.325182) (xy 402.395218 -5.309817)
			(xy 402.345613 -5.287161) (xy 402.299738 -5.257678) (xy 402.258525 -5.221965) (xy 402.222814 -5.180751)
			(xy 402.193332 -5.134874) (xy 402.170678 -5.085269) (xy 402.155315 -5.032945) (xy 402.147554 -4.978967)
			(xy 400.173706 -4.978967) (xy 400.173706 -4.97897) (xy 400.165944 -5.032953) (xy 400.15058 -5.085284)
			(xy 400.127925 -5.134895) (xy 400.098441 -5.180777) (xy 400.062728 -5.221997) (xy 400.021512 -5.257715)
			(xy 399.975633 -5.287204) (xy 399.926025 -5.309865) (xy 399.873697 -5.325235) (xy 399.819713 -5.333002)
			(xy 399.792444 -5.333492) (xy 398.928844 -5.333492) (xy 398.901573 -5.332972) (xy 398.847586 -5.325215)
			(xy 398.795252 -5.309854) (xy 398.745637 -5.287201) (xy 398.699751 -5.257716) (xy 398.658529 -5.222002)
			(xy 398.62281 -5.180784) (xy 398.593321 -5.134902) (xy 398.570661 -5.085289) (xy 398.555294 -5.032957)
			(xy 398.547532 -4.978971) (xy 396.573806 -4.978971) (xy 396.566043 -5.032959) (xy 396.550677 -5.085293)
			(xy 396.528019 -5.134907) (xy 396.498531 -5.180791) (xy 396.462813 -5.222012) (xy 396.421593 -5.25773)
			(xy 396.375708 -5.287218) (xy 396.326094 -5.309876) (xy 396.273761 -5.325243) (xy 396.219773 -5.333005)
			(xy 396.192502 -5.333492) (xy 395.328902 -5.333492) (xy 395.301633 -5.332969) (xy 395.24765 -5.325207)
			(xy 395.195321 -5.309843) (xy 395.145712 -5.287187) (xy 395.099832 -5.257702) (xy 395.058614 -5.221987)
			(xy 395.0229 -5.18077) (xy 394.993414 -5.13489) (xy 394.970758 -5.08528) (xy 394.955393 -5.032952)
			(xy 394.947631 -4.978969) (xy 390.763638 -4.978969) (xy 390.774561 -5.038281) (xy 390.782563 -5.125916)
			(xy 390.783064 -5.169916) (xy 390.782563 -5.213916) (xy 390.774561 -5.301551) (xy 390.758623 -5.388095)
			(xy 390.734881 -5.472831) (xy 390.703532 -5.555057) (xy 390.664835 -5.634092) (xy 390.619112 -5.70928)
			(xy 390.566741 -5.779999) (xy 390.508157 -5.845663) (xy 390.443843 -5.905728) (xy 390.374335 -5.959695)
			(xy 390.300207 -6.007117) (xy 390.222073 -6.047603) (xy 390.140582 -6.080816) (xy 390.056408 -6.10648)
			(xy 389.970249 -6.124384) (xy 389.882819 -6.134379) (xy 389.794842 -6.136383) (xy 389.707048 -6.130377)
			(xy 389.620164 -6.116413) (xy 389.534909 -6.094606) (xy 389.45199 -6.065137) (xy 389.372095 -6.02825)
			(xy 389.295886 -5.98425) (xy 389.223993 -5.933502) (xy 389.157012 -5.876428) (xy 389.0955 -5.813498)
			(xy 389.039964 -5.745236) (xy 388.990866 -5.672207) (xy 388.948613 -5.595015) (xy 388.913554 -5.514301)
			(xy 388.885979 -5.430733) (xy 388.866119 -5.345004) (xy 388.854136 -5.257824) (xy 388.850131 -5.169916)
			(xy 388.110984 -5.169916) (xy 388.110984 -6.169914) (xy 453.015103 -6.169914) (xy 453.019108 -6.082006)
			(xy 453.031091 -5.994826) (xy 453.050951 -5.909097) (xy 453.078526 -5.825529) (xy 453.113585 -5.744815)
			(xy 453.155838 -5.667623) (xy 453.204936 -5.594594) (xy 453.260472 -5.526332) (xy 453.321984 -5.463402)
			(xy 453.388965 -5.406328) (xy 453.460858 -5.35558) (xy 453.537067 -5.31158) (xy 453.616962 -5.274693)
			(xy 453.699881 -5.245224) (xy 453.785136 -5.223417) (xy 453.87202 -5.209453) (xy 453.959814 -5.203447)
			(xy 454.047791 -5.205451) (xy 454.135221 -5.215446) (xy 454.22138 -5.23335) (xy 454.305554 -5.259014)
			(xy 454.387045 -5.292227) (xy 454.465179 -5.332713) (xy 454.539307 -5.380135) (xy 454.608815 -5.434102)
			(xy 454.673129 -5.494167) (xy 454.731713 -5.559831) (xy 454.784084 -5.63055) (xy 454.829807 -5.705738)
			(xy 454.868504 -5.784773) (xy 454.899853 -5.866999) (xy 454.923595 -5.951735) (xy 454.939533 -6.038279)
			(xy 454.947535 -6.125914) (xy 454.948036 -6.169914) (xy 454.947535 -6.213914) (xy 454.939533 -6.301549)
			(xy 454.923595 -6.388093) (xy 454.899853 -6.472829) (xy 454.868504 -6.555055) (xy 454.829807 -6.63409)
			(xy 454.784084 -6.709278) (xy 454.731713 -6.779997) (xy 454.673129 -6.845661) (xy 454.608815 -6.905726)
			(xy 454.539307 -6.959693) (xy 454.465179 -7.007115) (xy 454.387045 -7.047601) (xy 454.305554 -7.080814)
			(xy 454.22138 -7.106478) (xy 454.135221 -7.124382) (xy 454.047791 -7.134377) (xy 453.959814 -7.136381)
			(xy 453.87202 -7.130375) (xy 453.785136 -7.116411) (xy 453.699881 -7.094604) (xy 453.616962 -7.065135)
			(xy 453.537067 -7.028248) (xy 453.460858 -6.984248) (xy 453.388965 -6.9335) (xy 453.321984 -6.876426)
			(xy 453.260472 -6.813496) (xy 453.204936 -6.745234) (xy 453.155838 -6.672205) (xy 453.113585 -6.595013)
			(xy 453.078526 -6.514299) (xy 453.050951 -6.430731) (xy 453.031091 -6.345002) (xy 453.019108 -6.257822)
			(xy 453.015103 -6.169914) (xy 388.110984 -6.169914) (xy 388.110984 -6.740774) (xy 393.142876 -6.740774)
			(xy 393.142876 -6.686226) (xy 393.150639 -6.632232) (xy 393.166008 -6.579894) (xy 393.18867 -6.530275)
			(xy 393.218162 -6.484387) (xy 393.253885 -6.443163) (xy 393.295112 -6.407443) (xy 393.341003 -6.377954)
			(xy 393.390624 -6.355297) (xy 393.442964 -6.339932) (xy 393.496958 -6.332173) (xy 393.524232 -6.331712)
			(xy 394.387832 -6.331712) (xy 394.415098 -6.332253) (xy 394.469074 -6.340017) (xy 394.521397 -6.355384)
			(xy 394.570999 -6.378041) (xy 394.616873 -6.407526) (xy 394.658084 -6.443238) (xy 394.693794 -6.484452)
			(xy 394.723274 -6.530329) (xy 394.745927 -6.579933) (xy 394.761289 -6.632257) (xy 394.76905 -6.686234)
			(xy 394.76905 -6.740766) (xy 394.769049 -6.74077) (xy 396.742898 -6.74077) (xy 396.742898 -6.68623)
			(xy 396.75066 -6.632245) (xy 396.766025 -6.579914) (xy 396.788681 -6.530302) (xy 396.818166 -6.484419)
			(xy 396.853881 -6.4432) (xy 396.895099 -6.407482) (xy 396.940979 -6.377993) (xy 396.99059 -6.355334)
			(xy 397.04292 -6.339965) (xy 397.096904 -6.3322) (xy 397.124174 -6.331712) (xy 397.987774 -6.331712)
			(xy 398.015044 -6.332226) (xy 398.06903 -6.339984) (xy 398.121363 -6.355347) (xy 398.170976 -6.378002)
			(xy 398.216859 -6.407487) (xy 398.25808 -6.443202) (xy 398.293798 -6.48442) (xy 398.323286 -6.530301)
			(xy 398.345944 -6.579913) (xy 398.36131 -6.632244) (xy 398.369072 -6.68623) (xy 398.369072 -6.74077)
			(xy 398.369071 -6.740774) (xy 400.342776 -6.740774) (xy 400.342776 -6.686226) (xy 400.350539 -6.632234)
			(xy 400.365907 -6.579897) (xy 400.388567 -6.530279) (xy 400.418058 -6.484392) (xy 400.45378 -6.443168)
			(xy 400.495005 -6.407449) (xy 400.540893 -6.377959) (xy 400.590512 -6.355301) (xy 400.64285 -6.339935)
			(xy 400.696842 -6.332174) (xy 400.724116 -6.331712) (xy 401.587716 -6.331712) (xy 401.614983 -6.332251)
			(xy 401.668961 -6.340014) (xy 401.721285 -6.35538) (xy 401.77089 -6.378036) (xy 401.816766 -6.40752)
			(xy 401.857978 -6.443233) (xy 401.89369 -6.484447) (xy 401.923172 -6.530324) (xy 401.945825 -6.57993)
			(xy 401.961189 -6.632255) (xy 401.96895 -6.686233) (xy 401.96895 -6.740767) (xy 401.968949 -6.740773)
			(xy 403.942976 -6.740773) (xy 403.942976 -6.686227) (xy 403.950739 -6.632235) (xy 403.966106 -6.579898)
			(xy 403.988766 -6.53028) (xy 404.018257 -6.484393) (xy 404.053978 -6.44317) (xy 404.095203 -6.40745)
			(xy 404.141091 -6.377961) (xy 404.190709 -6.355302) (xy 404.243047 -6.339936) (xy 404.297039 -6.332175)
			(xy 404.324312 -6.331712) (xy 405.187912 -6.331712) (xy 405.215179 -6.332251) (xy 405.269158 -6.340014)
			(xy 405.321482 -6.355379) (xy 405.371087 -6.378034) (xy 405.416964 -6.407519) (xy 405.458177 -6.443231)
			(xy 405.493889 -6.484446) (xy 405.523371 -6.530323) (xy 405.546025 -6.579929) (xy 405.561389 -6.632254)
			(xy 405.56915 -6.686233) (xy 405.56915 -6.740767) (xy 405.56915 -6.74077) (xy 413.052998 -6.74077)
			(xy 413.052998 -6.68623) (xy 413.06076 -6.632245) (xy 413.076125 -6.579914) (xy 413.098781 -6.530302)
			(xy 413.128267 -6.484419) (xy 413.163982 -6.443199) (xy 413.205199 -6.407481) (xy 413.25108 -6.377993)
			(xy 413.300691 -6.355334) (xy 413.353021 -6.339965) (xy 413.407006 -6.3322) (xy 413.434276 -6.331712)
			(xy 414.297876 -6.331712) (xy 414.325146 -6.332226) (xy 414.379132 -6.339985) (xy 414.431464 -6.355348)
			(xy 414.481077 -6.378002) (xy 414.52696 -6.407487) (xy 414.568181 -6.443202) (xy 414.603898 -6.48442)
			(xy 414.633386 -6.530302) (xy 414.656044 -6.579913) (xy 414.67141 -6.632244) (xy 414.679173 -6.68623)
			(xy 414.679173 -6.74077) (xy 414.679172 -6.740774) (xy 416.652876 -6.740774) (xy 416.652876 -6.686226)
			(xy 416.660639 -6.632234) (xy 416.676007 -6.579897) (xy 416.698667 -6.530279) (xy 416.728159 -6.484391)
			(xy 416.763881 -6.443168) (xy 416.805106 -6.407448) (xy 416.850995 -6.377959) (xy 416.900613 -6.355301)
			(xy 416.952952 -6.339935) (xy 417.006944 -6.332174) (xy 417.034218 -6.331712) (xy 417.897818 -6.331712)
			(xy 417.925085 -6.332252) (xy 417.979063 -6.340015) (xy 418.031386 -6.355381) (xy 418.080991 -6.378036)
			(xy 418.126867 -6.407521) (xy 418.168079 -6.443234) (xy 418.20379 -6.484448) (xy 418.233272 -6.530325)
			(xy 418.255926 -6.57993) (xy 418.271289 -6.632255) (xy 418.27905 -6.686233) (xy 418.27905 -6.740767)
			(xy 418.279049 -6.740773) (xy 424.262976 -6.740773) (xy 424.262976 -6.686227) (xy 424.270739 -6.632235)
			(xy 424.286106 -6.579898) (xy 424.308766 -6.53028) (xy 424.338257 -6.484393) (xy 424.373978 -6.44317)
			(xy 424.415203 -6.40745) (xy 424.461091 -6.377961) (xy 424.510709 -6.355302) (xy 424.563047 -6.339936)
			(xy 424.617039 -6.332175) (xy 424.644312 -6.331712) (xy 425.507912 -6.331712) (xy 425.535179 -6.332251)
			(xy 425.589158 -6.340014) (xy 425.641482 -6.355379) (xy 425.691087 -6.378034) (xy 425.736964 -6.407519)
			(xy 425.778177 -6.443231) (xy 425.813889 -6.484446) (xy 425.843371 -6.530323) (xy 425.866025 -6.579929)
			(xy 425.881389 -6.632254) (xy 425.88915 -6.686233) (xy 425.88915 -6.740767) (xy 425.88915 -6.740769)
			(xy 427.862998 -6.740769) (xy 427.862998 -6.686231) (xy 427.870759 -6.632248) (xy 427.886123 -6.579918)
			(xy 427.908778 -6.530308) (xy 427.938261 -6.484426) (xy 427.973974 -6.443207) (xy 428.015189 -6.407489)
			(xy 428.061067 -6.378) (xy 428.110675 -6.35534) (xy 428.163003 -6.339969) (xy 428.216985 -6.332202)
			(xy 428.244254 -6.331712) (xy 429.107854 -6.331712) (xy 429.135125 -6.332224) (xy 429.189113 -6.339981)
			(xy 429.241448 -6.355342) (xy 429.291064 -6.377995) (xy 429.33695 -6.40748) (xy 429.378173 -6.443195)
			(xy 429.413893 -6.484413) (xy 429.443383 -6.530296) (xy 429.466042 -6.579909) (xy 429.48141 -6.632242)
			(xy 429.489172 -6.686229) (xy 429.489172 -6.740771) (xy 429.488151 -6.747873) (xy 431.473788 -6.747873)
			(xy 431.473788 -6.693327) (xy 431.48155 -6.639337) (xy 431.496918 -6.587001) (xy 431.519578 -6.537385)
			(xy 431.549068 -6.491498) (xy 431.584789 -6.450276) (xy 431.626013 -6.414558) (xy 431.6719 -6.385069)
			(xy 431.721518 -6.362412) (xy 431.773854 -6.347047) (xy 431.827845 -6.339286) (xy 431.855118 -6.338824)
			(xy 432.718718 -6.338824) (xy 432.745986 -6.33934) (xy 432.799965 -6.347103) (xy 432.852291 -6.362469)
			(xy 432.901897 -6.385126) (xy 432.947774 -6.414611) (xy 432.988988 -6.450325) (xy 433.0247 -6.491541)
			(xy 433.054183 -6.537419) (xy 433.076837 -6.587026) (xy 433.092201 -6.639352) (xy 433.099962 -6.693332)
			(xy 433.099962 -6.740771) (xy 445.457798 -6.740771) (xy 445.457798 -6.686229) (xy 445.46556 -6.632243)
			(xy 445.480926 -6.579911) (xy 445.503583 -6.530298) (xy 445.53307 -6.484415) (xy 445.568786 -6.443195)
			(xy 445.610005 -6.407477) (xy 445.655888 -6.377989) (xy 445.7055 -6.35533) (xy 445.757831 -6.339963)
			(xy 445.811817 -6.332199) (xy 445.839088 -6.331712) (xy 446.702688 -6.331712) (xy 446.729958 -6.332227)
			(xy 446.783942 -6.339987) (xy 446.836273 -6.355351) (xy 446.885884 -6.378006) (xy 446.931766 -6.407492)
			(xy 446.972985 -6.443207) (xy 447.008701 -6.484424) (xy 447.038188 -6.530305) (xy 447.060845 -6.579916)
			(xy 447.076211 -6.632246) (xy 447.083973 -6.68623) (xy 447.083973 -6.74077) (xy 447.076211 -6.794754)
			(xy 447.060845 -6.847084) (xy 447.038188 -6.896695) (xy 447.008701 -6.942576) (xy 446.972985 -6.983793)
			(xy 446.931766 -7.019508) (xy 446.885884 -7.048994) (xy 446.836273 -7.071649) (xy 446.783942 -7.087013)
			(xy 446.729958 -7.094773) (xy 446.702688 -7.095236) (xy 445.839088 -7.095236) (xy 445.811817 -7.094801)
			(xy 445.757831 -7.087037) (xy 445.7055 -7.07167) (xy 445.655888 -7.049011) (xy 445.610005 -7.019523)
			(xy 445.568786 -6.983805) (xy 445.53307 -6.942585) (xy 445.503583 -6.896702) (xy 445.480926 -6.847089)
			(xy 445.46556 -6.794757) (xy 445.457798 -6.740771) (xy 433.099962 -6.740771) (xy 433.099962 -6.747868)
			(xy 433.092201 -6.801848) (xy 433.076837 -6.854174) (xy 433.054183 -6.903781) (xy 433.0247 -6.949659)
			(xy 432.988988 -6.990875) (xy 432.947774 -7.026589) (xy 432.901897 -7.056074) (xy 432.852291 -7.078731)
			(xy 432.799965 -7.094097) (xy 432.745986 -7.10186) (xy 432.718718 -7.102348) (xy 431.855118 -7.102348)
			(xy 431.827845 -7.101914) (xy 431.773854 -7.094153) (xy 431.721518 -7.078788) (xy 431.6719 -7.056131)
			(xy 431.626013 -7.026642) (xy 431.584789 -6.990924) (xy 431.549068 -6.949702) (xy 431.519578 -6.903815)
			(xy 431.496918 -6.854199) (xy 431.48155 -6.801863) (xy 431.473788 -6.747873) (xy 429.488151 -6.747873)
			(xy 429.48141 -6.794758) (xy 429.466042 -6.847091) (xy 429.443383 -6.896704) (xy 429.413893 -6.942587)
			(xy 429.378173 -6.983805) (xy 429.33695 -7.01952) (xy 429.291064 -7.049005) (xy 429.241448 -7.071658)
			(xy 429.189113 -7.087019) (xy 429.135125 -7.094776) (xy 429.107854 -7.095236) (xy 428.244254 -7.095236)
			(xy 428.216985 -7.094798) (xy 428.163003 -7.087031) (xy 428.110675 -7.07166) (xy 428.061067 -7.049)
			(xy 428.015189 -7.019511) (xy 427.973974 -6.983793) (xy 427.938261 -6.942574) (xy 427.908778 -6.896692)
			(xy 427.886123 -6.847082) (xy 427.870759 -6.794752) (xy 427.862998 -6.740769) (xy 425.88915 -6.740769)
			(xy 425.881389 -6.794746) (xy 425.866025 -6.847071) (xy 425.843371 -6.896677) (xy 425.813889 -6.942554)
			(xy 425.778177 -6.983769) (xy 425.736964 -7.019481) (xy 425.691087 -7.048966) (xy 425.641482 -7.071621)
			(xy 425.589158 -7.086986) (xy 425.535179 -7.094749) (xy 425.507912 -7.095236) (xy 424.644312 -7.095236)
			(xy 424.617039 -7.094825) (xy 424.563047 -7.087064) (xy 424.510709 -7.071698) (xy 424.461091 -7.049039)
			(xy 424.415203 -7.01955) (xy 424.373978 -6.98383) (xy 424.338257 -6.942607) (xy 424.308766 -6.89672)
			(xy 424.286106 -6.847102) (xy 424.270739 -6.794765) (xy 424.262976 -6.740773) (xy 418.279049 -6.740773)
			(xy 418.271289 -6.794745) (xy 418.255926 -6.84707) (xy 418.233272 -6.896675) (xy 418.20379 -6.942552)
			(xy 418.168079 -6.983766) (xy 418.126867 -7.019479) (xy 418.080991 -7.048964) (xy 418.031386 -7.071619)
			(xy 417.979063 -7.086985) (xy 417.925085 -7.094748) (xy 417.897818 -7.095236) (xy 417.034218 -7.095236)
			(xy 417.006944 -7.094826) (xy 416.952952 -7.087065) (xy 416.900613 -7.071699) (xy 416.850995 -7.049041)
			(xy 416.805106 -7.019552) (xy 416.763881 -6.983832) (xy 416.728159 -6.942609) (xy 416.698667 -6.896721)
			(xy 416.676007 -6.847103) (xy 416.660639 -6.794766) (xy 416.652876 -6.740774) (xy 414.679172 -6.740774)
			(xy 414.67141 -6.794756) (xy 414.656044 -6.847087) (xy 414.633386 -6.896698) (xy 414.603898 -6.94258)
			(xy 414.568181 -6.983798) (xy 414.52696 -7.019513) (xy 414.481077 -7.048998) (xy 414.431464 -7.071652)
			(xy 414.379132 -7.087015) (xy 414.325146 -7.094774) (xy 414.297876 -7.095236) (xy 413.434276 -7.095236)
			(xy 413.407006 -7.0948) (xy 413.353021 -7.087035) (xy 413.300691 -7.071666) (xy 413.25108 -7.049007)
			(xy 413.205199 -7.019519) (xy 413.163982 -6.983801) (xy 413.128267 -6.942581) (xy 413.098781 -6.896698)
			(xy 413.076125 -6.847086) (xy 413.06076 -6.794755) (xy 413.052998 -6.74077) (xy 405.56915 -6.74077)
			(xy 405.561389 -6.794746) (xy 405.546025 -6.847071) (xy 405.523371 -6.896677) (xy 405.493889 -6.942554)
			(xy 405.458177 -6.983769) (xy 405.416964 -7.019481) (xy 405.371087 -7.048966) (xy 405.321482 -7.071621)
			(xy 405.269158 -7.086986) (xy 405.215179 -7.094749) (xy 405.187912 -7.095236) (xy 404.324312 -7.095236)
			(xy 404.297039 -7.094825) (xy 404.243047 -7.087064) (xy 404.190709 -7.071698) (xy 404.141091 -7.049039)
			(xy 404.095203 -7.01955) (xy 404.053978 -6.98383) (xy 404.018257 -6.942607) (xy 403.988766 -6.89672)
			(xy 403.966106 -6.847102) (xy 403.950739 -6.794765) (xy 403.942976 -6.740773) (xy 401.968949 -6.740773)
			(xy 401.961189 -6.794745) (xy 401.945825 -6.84707) (xy 401.923172 -6.896676) (xy 401.89369 -6.942553)
			(xy 401.857978 -6.983767) (xy 401.816766 -7.01948) (xy 401.77089 -7.048964) (xy 401.721285 -7.07162)
			(xy 401.668961 -7.086986) (xy 401.614983 -7.094749) (xy 401.587716 -7.095236) (xy 400.724116 -7.095236)
			(xy 400.696842 -7.094826) (xy 400.64285 -7.087065) (xy 400.590512 -7.071699) (xy 400.540893 -7.049041)
			(xy 400.495005 -7.019551) (xy 400.45378 -6.983832) (xy 400.418058 -6.942608) (xy 400.388567 -6.896721)
			(xy 400.365907 -6.847103) (xy 400.350539 -6.794766) (xy 400.342776 -6.740774) (xy 398.369071 -6.740774)
			(xy 398.36131 -6.794756) (xy 398.345944 -6.847087) (xy 398.323286 -6.896699) (xy 398.293798 -6.94258)
			(xy 398.25808 -6.983798) (xy 398.216859 -7.019513) (xy 398.170976 -7.048998) (xy 398.121363 -7.071653)
			(xy 398.06903 -7.087016) (xy 398.015044 -7.094774) (xy 397.987774 -7.095236) (xy 397.124174 -7.095236)
			(xy 397.096904 -7.0948) (xy 397.04292 -7.087035) (xy 396.99059 -7.071666) (xy 396.940979 -7.049007)
			(xy 396.895099 -7.019518) (xy 396.853881 -6.9838) (xy 396.818166 -6.942581) (xy 396.788681 -6.896698)
			(xy 396.766025 -6.847086) (xy 396.75066 -6.794755) (xy 396.742898 -6.74077) (xy 394.769049 -6.74077)
			(xy 394.761289 -6.794743) (xy 394.745927 -6.847067) (xy 394.723274 -6.896671) (xy 394.693794 -6.942548)
			(xy 394.658084 -6.983762) (xy 394.616873 -7.019474) (xy 394.570999 -7.048959) (xy 394.521397 -7.071616)
			(xy 394.469074 -7.086983) (xy 394.415098 -7.094747) (xy 394.387832 -7.095236) (xy 393.524232 -7.095236)
			(xy 393.496958 -7.094827) (xy 393.442964 -7.087068) (xy 393.390624 -7.071703) (xy 393.341003 -7.049046)
			(xy 393.295112 -7.019557) (xy 393.253885 -6.983837) (xy 393.218162 -6.942613) (xy 393.18867 -6.896725)
			(xy 393.166008 -6.847106) (xy 393.150639 -6.794768) (xy 393.142876 -6.740774) (xy 388.110984 -6.740774)
			(xy 388.110984 -9.780016) (xy 388.110499 -9.850398) (xy 388.102605 -9.99094) (xy 388.086844 -10.130819)
			(xy 388.063264 -10.269594) (xy 388.03194 -10.406828) (xy 387.992971 -10.54209) (xy 387.946478 -10.674954)
			(xy 387.892609 -10.805003) (xy 387.831533 -10.931826) (xy 387.763442 -11.055026) (xy 387.68855 -11.174213)
			(xy 387.607093 -11.289014) (xy 387.519328 -11.399067) (xy 387.425529 -11.504025) (xy 387.325993 -11.60356)
			(xy 387.221033 -11.697356) (xy 387.110979 -11.78512) (xy 386.996176 -11.866575) (xy 386.876988 -11.941465)
			(xy 386.753787 -12.009554) (xy 386.626963 -12.070627) (xy 386.496913 -12.124494) (xy 386.364048 -12.170984)
			(xy 386.228785 -12.209951) (xy 386.091551 -12.241273) (xy 385.952775 -12.26485) (xy 385.812896 -12.280609)
			(xy 385.672354 -12.2885) (xy 385.601972 -12.289028) (xy 260.800088 -12.289028) (xy 260.744319 -12.28955)
			(xy 260.633094 -12.297886) (xy 260.522803 -12.314511) (xy 260.414062 -12.339331) (xy 260.30748 -12.372208)
			(xy 260.203654 -12.412958) (xy 260.103162 -12.461353) (xy 260.006569 -12.517122) (xy 259.914413 -12.579954)
			(xy 259.82721 -12.649497) (xy 259.745448 -12.725362) (xy 259.669584 -12.807125) (xy 259.601847 -12.892065)
			(xy 431.46197 -12.892065) (xy 431.46197 -12.837535) (xy 431.46973 -12.783559) (xy 431.485093 -12.731238)
			(xy 431.507745 -12.681635) (xy 431.537225 -12.635761) (xy 431.572934 -12.594548) (xy 431.614145 -12.558837)
			(xy 431.660017 -12.529355) (xy 431.709619 -12.5067) (xy 431.76194 -12.491335) (xy 431.815915 -12.483572)
			(xy 431.84318 -12.483084) (xy 432.70678 -12.483084) (xy 432.734055 -12.483454) (xy 432.788051 -12.491215)
			(xy 432.840392 -12.506581) (xy 432.890014 -12.529241) (xy 432.935905 -12.558731) (xy 432.977133 -12.594453)
			(xy 433.012857 -12.635678) (xy 433.04235 -12.681569) (xy 433.065012 -12.731189) (xy 433.080381 -12.78353)
			(xy 433.088144 -12.837525) (xy 433.088144 -12.864846) (xy 445.45631 -12.864846) (xy 445.45631 -12.864592)
			(xy 445.456564 -12.850622) (xy 445.45717 -12.823469) (xy 445.46523 -12.769758) (xy 445.48082 -12.717731)
			(xy 445.503625 -12.668439) (xy 445.533186 -12.622876) (xy 445.568905 -12.581962) (xy 445.610062 -12.546522)
			(xy 445.655826 -12.517273) (xy 445.705273 -12.494804) (xy 445.757405 -12.47957) (xy 445.81117 -12.471876)
			(xy 445.838326 -12.4714) (xy 446.701926 -12.4714) (xy 446.72908 -12.471883) (xy 446.782838 -12.479582)
			(xy 446.834964 -12.494821) (xy 446.884404 -12.517293) (xy 446.93016 -12.546543) (xy 446.971311 -12.581982)
			(xy 447.007024 -12.622895) (xy 447.03658 -12.668455) (xy 447.059381 -12.717744) (xy 447.074968 -12.769766)
			(xy 447.083027 -12.823472) (xy 447.083688 -12.850622) (xy 447.083942 -12.864592) (xy 447.083942 -12.864846)
			(xy 447.083472 -12.892133) (xy 447.0757 -12.946152) (xy 447.06032 -12.998515) (xy 447.037645 -13.048157)
			(xy 447.008137 -13.094067) (xy 446.972397 -13.135311) (xy 446.931151 -13.171049) (xy 446.885239 -13.200555)
			(xy 446.835597 -13.223227) (xy 446.783233 -13.238604) (xy 446.729214 -13.246374) (xy 446.701926 -13.246862)
			(xy 446.679426 -13.246581) (xy 446.634732 -13.241355) (xy 446.612772 -13.236448) (xy 446.60693 -13.234924)
			(xy 445.933322 -13.234924) (xy 445.92748 -13.236448) (xy 445.905519 -13.241348) (xy 445.860825 -13.246566)
			(xy 445.838326 -13.246862) (xy 445.811041 -13.246305) (xy 445.757027 -13.238543) (xy 445.704666 -13.223173)
			(xy 445.655026 -13.200508) (xy 445.609117 -13.17101) (xy 445.567873 -13.135278) (xy 445.532133 -13.094041)
			(xy 445.502626 -13.048137) (xy 445.479952 -12.998501) (xy 445.464572 -12.946144) (xy 445.4568 -12.892131)
			(xy 445.45631 -12.864846) (xy 433.088144 -12.864846) (xy 433.088144 -12.892075) (xy 433.080381 -12.94607)
			(xy 433.065012 -12.998411) (xy 433.04235 -13.048031) (xy 433.012857 -13.093921) (xy 432.977133 -13.135147)
			(xy 432.935905 -13.170869) (xy 432.890014 -13.200359) (xy 432.840392 -13.223019) (xy 432.788051 -13.238385)
			(xy 432.734055 -13.246146) (xy 432.70678 -13.246608) (xy 431.84318 -13.246608) (xy 431.815915 -13.246028)
			(xy 431.76194 -13.238265) (xy 431.709619 -13.2229) (xy 431.660017 -13.200245) (xy 431.614145 -13.170763)
			(xy 431.572934 -13.135052) (xy 431.537225 -13.093839) (xy 431.507745 -13.047965) (xy 431.485093 -12.998362)
			(xy 431.46973 -12.946041) (xy 431.46197 -12.892065) (xy 259.601847 -12.892065) (xy 259.600042 -12.894329)
			(xy 259.537211 -12.986486) (xy 259.481443 -13.08308) (xy 259.43305 -13.183572) (xy 259.392301 -13.287399)
			(xy 259.359426 -13.393981) (xy 259.334607 -13.502722) (xy 259.317984 -13.613014) (xy 259.309649 -13.724239)
			(xy 259.309108 -13.780008) (xy 259.309108 -17.628666) (xy 389.660162 -17.628666) (xy 389.660162 -17.574134)
			(xy 389.667923 -17.520157) (xy 389.683286 -17.467834) (xy 389.705939 -17.41823) (xy 389.73542 -17.372354)
			(xy 389.77113 -17.331141) (xy 389.812342 -17.29543) (xy 389.858216 -17.265946) (xy 389.907819 -17.243291)
			(xy 389.960142 -17.227926) (xy 390.014118 -17.220163) (xy 390.041384 -17.219676) (xy 390.904984 -17.219676)
			(xy 390.932258 -17.220062) (xy 390.986252 -17.227824) (xy 391.038592 -17.24319) (xy 391.088212 -17.265849)
			(xy 391.134103 -17.295339) (xy 391.175329 -17.33106) (xy 391.211051 -17.372285) (xy 391.240543 -17.418174)
			(xy 391.263204 -17.467793) (xy 391.278573 -17.520132) (xy 391.286336 -17.574126) (xy 391.286336 -17.628666)
			(xy 395.248162 -17.628666) (xy 395.248162 -17.574134) (xy 395.255923 -17.520157) (xy 395.271286 -17.467834)
			(xy 395.293939 -17.41823) (xy 395.32342 -17.372354) (xy 395.35913 -17.331141) (xy 395.400342 -17.29543)
			(xy 395.446216 -17.265946) (xy 395.495819 -17.243291) (xy 395.548142 -17.227926) (xy 395.602118 -17.220163)
			(xy 395.629384 -17.219676) (xy 396.492984 -17.219676) (xy 396.520258 -17.220062) (xy 396.574252 -17.227824)
			(xy 396.626592 -17.24319) (xy 396.676212 -17.265849) (xy 396.722103 -17.295339) (xy 396.763329 -17.33106)
			(xy 396.799051 -17.372285) (xy 396.828543 -17.418174) (xy 396.851204 -17.467793) (xy 396.866573 -17.520132)
			(xy 396.874336 -17.574126) (xy 396.874336 -17.628666) (xy 400.836162 -17.628666) (xy 400.836162 -17.574134)
			(xy 400.843923 -17.520157) (xy 400.859286 -17.467834) (xy 400.881939 -17.41823) (xy 400.91142 -17.372354)
			(xy 400.94713 -17.331141) (xy 400.988342 -17.29543) (xy 401.034216 -17.265946) (xy 401.083819 -17.243291)
			(xy 401.136142 -17.227926) (xy 401.190118 -17.220163) (xy 401.217384 -17.219676) (xy 402.080984 -17.219676)
			(xy 402.108258 -17.220062) (xy 402.162252 -17.227824) (xy 402.214592 -17.24319) (xy 402.264212 -17.265849)
			(xy 402.310103 -17.295339) (xy 402.351329 -17.33106) (xy 402.387051 -17.372285) (xy 402.416543 -17.418174)
			(xy 402.439204 -17.467793) (xy 402.454573 -17.520132) (xy 402.462336 -17.574126) (xy 402.462336 -17.628666)
			(xy 406.424162 -17.628666) (xy 406.424162 -17.574134) (xy 406.431923 -17.520157) (xy 406.447286 -17.467834)
			(xy 406.469939 -17.41823) (xy 406.49942 -17.372354) (xy 406.53513 -17.331141) (xy 406.576342 -17.29543)
			(xy 406.622216 -17.265946) (xy 406.671819 -17.243291) (xy 406.724142 -17.227926) (xy 406.778118 -17.220163)
			(xy 406.805384 -17.219676) (xy 407.668984 -17.219676) (xy 407.696258 -17.220062) (xy 407.750252 -17.227824)
			(xy 407.802592 -17.24319) (xy 407.852212 -17.265849) (xy 407.898103 -17.295339) (xy 407.939329 -17.33106)
			(xy 407.975051 -17.372285) (xy 408.004543 -17.418174) (xy 408.027204 -17.467793) (xy 408.042573 -17.520132)
			(xy 408.050336 -17.574126) (xy 408.050336 -17.628666) (xy 412.012162 -17.628666) (xy 412.012162 -17.574134)
			(xy 412.019923 -17.520157) (xy 412.035286 -17.467834) (xy 412.057939 -17.41823) (xy 412.08742 -17.372354)
			(xy 412.12313 -17.331141) (xy 412.164342 -17.29543) (xy 412.210216 -17.265946) (xy 412.259819 -17.243291)
			(xy 412.312142 -17.227926) (xy 412.366118 -17.220163) (xy 412.393384 -17.219676) (xy 413.256984 -17.219676)
			(xy 413.284258 -17.220062) (xy 413.338252 -17.227824) (xy 413.390592 -17.24319) (xy 413.440212 -17.265849)
			(xy 413.486103 -17.295339) (xy 413.527329 -17.33106) (xy 413.563051 -17.372285) (xy 413.592543 -17.418174)
			(xy 413.615204 -17.467793) (xy 413.630573 -17.520132) (xy 413.638336 -17.574126) (xy 413.638336 -17.628667)
			(xy 417.905962 -17.628667) (xy 417.905962 -17.574133) (xy 417.913723 -17.520155) (xy 417.929087 -17.467831)
			(xy 417.951741 -17.418226) (xy 417.981224 -17.372349) (xy 418.016936 -17.331136) (xy 418.058149 -17.295424)
			(xy 418.104026 -17.265941) (xy 418.153631 -17.243287) (xy 418.205955 -17.227923) (xy 418.259933 -17.220162)
			(xy 418.2872 -17.219676) (xy 419.1508 -17.219676) (xy 419.178072 -17.220087) (xy 419.232061 -17.227849)
			(xy 419.284396 -17.243216) (xy 419.334011 -17.265874) (xy 419.379896 -17.295363) (xy 419.421118 -17.331082)
			(xy 419.456837 -17.372304) (xy 419.486326 -17.418189) (xy 419.508984 -17.467804) (xy 419.524351 -17.520139)
			(xy 419.532113 -17.574128) (xy 419.532113 -17.628667) (xy 423.493962 -17.628667) (xy 423.493962 -17.574133)
			(xy 423.501723 -17.520155) (xy 423.517087 -17.467831) (xy 423.539741 -17.418226) (xy 423.569224 -17.372349)
			(xy 423.604936 -17.331136) (xy 423.646149 -17.295424) (xy 423.692026 -17.265941) (xy 423.741631 -17.243287)
			(xy 423.793955 -17.227923) (xy 423.847933 -17.220162) (xy 423.8752 -17.219676) (xy 424.7388 -17.219676)
			(xy 424.766072 -17.220087) (xy 424.820061 -17.227849) (xy 424.872396 -17.243216) (xy 424.922011 -17.265874)
			(xy 424.967896 -17.295363) (xy 425.009118 -17.331082) (xy 425.044837 -17.372304) (xy 425.074326 -17.418189)
			(xy 425.096984 -17.467804) (xy 425.112351 -17.520139) (xy 425.120113 -17.574128) (xy 425.120113 -17.62867)
			(xy 429.11594 -17.62867) (xy 429.11594 -17.57413) (xy 429.123702 -17.520145) (xy 429.139068 -17.467815)
			(xy 429.161726 -17.418204) (xy 429.191214 -17.372324) (xy 429.226932 -17.331107) (xy 429.268152 -17.295393)
			(xy 429.314036 -17.265909) (xy 429.363649 -17.243256) (xy 429.415981 -17.227894) (xy 429.469966 -17.220137)
			(xy 429.497236 -17.219676) (xy 430.360836 -17.219676) (xy 430.388106 -17.220089) (xy 430.442091 -17.227856)
			(xy 430.494422 -17.243226) (xy 430.544032 -17.265886) (xy 430.589913 -17.295376) (xy 430.631131 -17.331095)
			(xy 430.666846 -17.372315) (xy 430.696331 -17.418199) (xy 430.718987 -17.467812) (xy 430.734352 -17.520144)
			(xy 430.742114 -17.57413) (xy 430.742114 -17.62867) (xy 430.734352 -17.682656) (xy 430.718987 -17.734988)
			(xy 430.696331 -17.784601) (xy 430.666846 -17.830485) (xy 430.631131 -17.871705) (xy 430.589913 -17.907424)
			(xy 430.544032 -17.936914) (xy 430.494422 -17.959574) (xy 430.442091 -17.974944) (xy 430.388106 -17.982711)
			(xy 430.360836 -17.9832) (xy 429.497236 -17.9832) (xy 429.469966 -17.982663) (xy 429.415981 -17.974906)
			(xy 429.363649 -17.959544) (xy 429.314036 -17.936891) (xy 429.268152 -17.907407) (xy 429.226932 -17.871693)
			(xy 429.191214 -17.830476) (xy 429.161726 -17.784596) (xy 429.139068 -17.734985) (xy 429.123702 -17.682655)
			(xy 429.11594 -17.62867) (xy 425.120113 -17.62867) (xy 425.120113 -17.628672) (xy 425.112351 -17.682661)
			(xy 425.096984 -17.734996) (xy 425.074326 -17.784611) (xy 425.044837 -17.830496) (xy 425.009118 -17.871718)
			(xy 424.967896 -17.907437) (xy 424.922011 -17.936926) (xy 424.872396 -17.959584) (xy 424.820061 -17.974951)
			(xy 424.766072 -17.982713) (xy 424.7388 -17.9832) (xy 423.8752 -17.9832) (xy 423.847933 -17.982638)
			(xy 423.793955 -17.974877) (xy 423.741631 -17.959513) (xy 423.692026 -17.936859) (xy 423.646149 -17.907376)
			(xy 423.604936 -17.871664) (xy 423.569224 -17.830451) (xy 423.539741 -17.784574) (xy 423.517087 -17.734969)
			(xy 423.501723 -17.682645) (xy 423.493962 -17.628667) (xy 419.532113 -17.628667) (xy 419.532113 -17.628672)
			(xy 419.524351 -17.682661) (xy 419.508984 -17.734996) (xy 419.486326 -17.784611) (xy 419.456837 -17.830496)
			(xy 419.421118 -17.871718) (xy 419.379896 -17.907437) (xy 419.334011 -17.936926) (xy 419.284396 -17.959584)
			(xy 419.232061 -17.974951) (xy 419.178072 -17.982713) (xy 419.1508 -17.9832) (xy 418.2872 -17.9832)
			(xy 418.259933 -17.982638) (xy 418.205955 -17.974877) (xy 418.153631 -17.959513) (xy 418.104026 -17.936859)
			(xy 418.058149 -17.907376) (xy 418.016936 -17.871664) (xy 417.981224 -17.830451) (xy 417.951741 -17.784574)
			(xy 417.929087 -17.734969) (xy 417.913723 -17.682645) (xy 417.905962 -17.628667) (xy 413.638336 -17.628667)
			(xy 413.638336 -17.628674) (xy 413.630573 -17.682668) (xy 413.615204 -17.735007) (xy 413.592543 -17.784626)
			(xy 413.563051 -17.830515) (xy 413.527329 -17.87174) (xy 413.486103 -17.907461) (xy 413.440212 -17.936951)
			(xy 413.390592 -17.95961) (xy 413.338252 -17.974976) (xy 413.284258 -17.982738) (xy 413.256984 -17.9832)
			(xy 412.393384 -17.9832) (xy 412.366118 -17.982637) (xy 412.312142 -17.974874) (xy 412.259819 -17.959509)
			(xy 412.210216 -17.936854) (xy 412.164342 -17.90737) (xy 412.12313 -17.871659) (xy 412.08742 -17.830446)
			(xy 412.057939 -17.78457) (xy 412.035286 -17.734966) (xy 412.019923 -17.682643) (xy 412.012162 -17.628666)
			(xy 408.050336 -17.628666) (xy 408.050336 -17.628674) (xy 408.042573 -17.682668) (xy 408.027204 -17.735007)
			(xy 408.004543 -17.784626) (xy 407.975051 -17.830515) (xy 407.939329 -17.87174) (xy 407.898103 -17.907461)
			(xy 407.852212 -17.936951) (xy 407.802592 -17.95961) (xy 407.750252 -17.974976) (xy 407.696258 -17.982738)
			(xy 407.668984 -17.9832) (xy 406.805384 -17.9832) (xy 406.778118 -17.982637) (xy 406.724142 -17.974874)
			(xy 406.671819 -17.959509) (xy 406.622216 -17.936854) (xy 406.576342 -17.90737) (xy 406.53513 -17.871659)
			(xy 406.49942 -17.830446) (xy 406.469939 -17.78457) (xy 406.447286 -17.734966) (xy 406.431923 -17.682643)
			(xy 406.424162 -17.628666) (xy 402.462336 -17.628666) (xy 402.462336 -17.628674) (xy 402.454573 -17.682668)
			(xy 402.439204 -17.735007) (xy 402.416543 -17.784626) (xy 402.387051 -17.830515) (xy 402.351329 -17.87174)
			(xy 402.310103 -17.907461) (xy 402.264212 -17.936951) (xy 402.214592 -17.95961) (xy 402.162252 -17.974976)
			(xy 402.108258 -17.982738) (xy 402.080984 -17.9832) (xy 401.217384 -17.9832) (xy 401.190118 -17.982637)
			(xy 401.136142 -17.974874) (xy 401.083819 -17.959509) (xy 401.034216 -17.936854) (xy 400.988342 -17.90737)
			(xy 400.94713 -17.871659) (xy 400.91142 -17.830446) (xy 400.881939 -17.78457) (xy 400.859286 -17.734966)
			(xy 400.843923 -17.682643) (xy 400.836162 -17.628666) (xy 396.874336 -17.628666) (xy 396.874336 -17.628674)
			(xy 396.866573 -17.682668) (xy 396.851204 -17.735007) (xy 396.828543 -17.784626) (xy 396.799051 -17.830515)
			(xy 396.763329 -17.87174) (xy 396.722103 -17.907461) (xy 396.676212 -17.936951) (xy 396.626592 -17.95961)
			(xy 396.574252 -17.974976) (xy 396.520258 -17.982738) (xy 396.492984 -17.9832) (xy 395.629384 -17.9832)
			(xy 395.602118 -17.982637) (xy 395.548142 -17.974874) (xy 395.495819 -17.959509) (xy 395.446216 -17.936854)
			(xy 395.400342 -17.90737) (xy 395.35913 -17.871659) (xy 395.32342 -17.830446) (xy 395.293939 -17.78457)
			(xy 395.271286 -17.734966) (xy 395.255923 -17.682643) (xy 395.248162 -17.628666) (xy 391.286336 -17.628666)
			(xy 391.286336 -17.628674) (xy 391.278573 -17.682668) (xy 391.263204 -17.735007) (xy 391.240543 -17.784626)
			(xy 391.211051 -17.830515) (xy 391.175329 -17.87174) (xy 391.134103 -17.907461) (xy 391.088212 -17.936951)
			(xy 391.038592 -17.95961) (xy 390.986252 -17.974976) (xy 390.932258 -17.982738) (xy 390.904984 -17.9832)
			(xy 390.041384 -17.9832) (xy 390.014118 -17.982637) (xy 389.960142 -17.974874) (xy 389.907819 -17.959509)
			(xy 389.858216 -17.936854) (xy 389.812342 -17.90737) (xy 389.77113 -17.871659) (xy 389.73542 -17.830446)
			(xy 389.705939 -17.78457) (xy 389.683286 -17.734966) (xy 389.667923 -17.682643) (xy 389.660162 -17.628666)
			(xy 259.309108 -17.628666) (xy 259.309108 -19.152666) (xy 392.454162 -19.152666) (xy 392.454162 -19.098134)
			(xy 392.461923 -19.044157) (xy 392.477286 -18.991834) (xy 392.499939 -18.94223) (xy 392.52942 -18.896354)
			(xy 392.56513 -18.855141) (xy 392.606342 -18.81943) (xy 392.652216 -18.789946) (xy 392.701819 -18.767291)
			(xy 392.754142 -18.751926) (xy 392.808118 -18.744163) (xy 392.835384 -18.743676) (xy 393.698984 -18.743676)
			(xy 393.726258 -18.744062) (xy 393.780252 -18.751824) (xy 393.832592 -18.76719) (xy 393.882212 -18.789849)
			(xy 393.928103 -18.819339) (xy 393.969329 -18.85506) (xy 394.005051 -18.896285) (xy 394.034543 -18.942174)
			(xy 394.057204 -18.991793) (xy 394.072573 -19.044132) (xy 394.080336 -19.098126) (xy 394.080336 -19.152666)
			(xy 398.042162 -19.152666) (xy 398.042162 -19.098134) (xy 398.049923 -19.044157) (xy 398.065286 -18.991834)
			(xy 398.087939 -18.94223) (xy 398.11742 -18.896354) (xy 398.15313 -18.855141) (xy 398.194342 -18.81943)
			(xy 398.240216 -18.789946) (xy 398.289819 -18.767291) (xy 398.342142 -18.751926) (xy 398.396118 -18.744163)
			(xy 398.423384 -18.743676) (xy 399.286984 -18.743676) (xy 399.314258 -18.744062) (xy 399.368252 -18.751824)
			(xy 399.420592 -18.76719) (xy 399.470212 -18.789849) (xy 399.516103 -18.819339) (xy 399.557329 -18.85506)
			(xy 399.593051 -18.896285) (xy 399.622543 -18.942174) (xy 399.645204 -18.991793) (xy 399.660573 -19.044132)
			(xy 399.668336 -19.098126) (xy 399.668336 -19.152666) (xy 403.630162 -19.152666) (xy 403.630162 -19.098134)
			(xy 403.637923 -19.044157) (xy 403.653286 -18.991834) (xy 403.675939 -18.94223) (xy 403.70542 -18.896354)
			(xy 403.74113 -18.855141) (xy 403.782342 -18.81943) (xy 403.828216 -18.789946) (xy 403.877819 -18.767291)
			(xy 403.930142 -18.751926) (xy 403.984118 -18.744163) (xy 404.011384 -18.743676) (xy 404.874984 -18.743676)
			(xy 404.902258 -18.744062) (xy 404.956252 -18.751824) (xy 405.008592 -18.76719) (xy 405.058212 -18.789849)
			(xy 405.104103 -18.819339) (xy 405.145329 -18.85506) (xy 405.181051 -18.896285) (xy 405.210543 -18.942174)
			(xy 405.233204 -18.991793) (xy 405.248573 -19.044132) (xy 405.256336 -19.098126) (xy 405.256336 -19.152666)
			(xy 409.218162 -19.152666) (xy 409.218162 -19.098134) (xy 409.225923 -19.044157) (xy 409.241286 -18.991834)
			(xy 409.263939 -18.94223) (xy 409.29342 -18.896354) (xy 409.32913 -18.855141) (xy 409.370342 -18.81943)
			(xy 409.416216 -18.789946) (xy 409.465819 -18.767291) (xy 409.518142 -18.751926) (xy 409.572118 -18.744163)
			(xy 409.599384 -18.743676) (xy 410.462984 -18.743676) (xy 410.490258 -18.744062) (xy 410.544252 -18.751824)
			(xy 410.596592 -18.76719) (xy 410.646212 -18.789849) (xy 410.692103 -18.819339) (xy 410.733329 -18.85506)
			(xy 410.769051 -18.896285) (xy 410.798543 -18.942174) (xy 410.821204 -18.991793) (xy 410.836573 -19.044132)
			(xy 410.844336 -19.098126) (xy 410.844336 -19.152667) (xy 415.111962 -19.152667) (xy 415.111962 -19.098133)
			(xy 415.119723 -19.044155) (xy 415.135087 -18.991831) (xy 415.157741 -18.942226) (xy 415.187224 -18.896349)
			(xy 415.222936 -18.855136) (xy 415.264149 -18.819424) (xy 415.310026 -18.789941) (xy 415.359631 -18.767287)
			(xy 415.411955 -18.751923) (xy 415.465933 -18.744162) (xy 415.4932 -18.743676) (xy 416.3568 -18.743676)
			(xy 416.384072 -18.744087) (xy 416.438061 -18.751849) (xy 416.490396 -18.767216) (xy 416.540011 -18.789874)
			(xy 416.585896 -18.819363) (xy 416.627118 -18.855082) (xy 416.662837 -18.896304) (xy 416.692326 -18.942189)
			(xy 416.714984 -18.991804) (xy 416.730351 -19.044139) (xy 416.738113 -19.098128) (xy 416.738113 -19.152667)
			(xy 420.699962 -19.152667) (xy 420.699962 -19.098133) (xy 420.707723 -19.044155) (xy 420.723087 -18.991831)
			(xy 420.745741 -18.942226) (xy 420.775224 -18.896349) (xy 420.810936 -18.855136) (xy 420.852149 -18.819424)
			(xy 420.898026 -18.789941) (xy 420.947631 -18.767287) (xy 420.999955 -18.751923) (xy 421.053933 -18.744162)
			(xy 421.0812 -18.743676) (xy 421.9448 -18.743676) (xy 421.972072 -18.744087) (xy 422.026061 -18.751849)
			(xy 422.078396 -18.767216) (xy 422.128011 -18.789874) (xy 422.173896 -18.819363) (xy 422.215118 -18.855082)
			(xy 422.250837 -18.896304) (xy 422.280326 -18.942189) (xy 422.302984 -18.991804) (xy 422.318351 -19.044139)
			(xy 422.326113 -19.098128) (xy 422.326113 -19.15267) (xy 426.32194 -19.15267) (xy 426.32194 -19.09813)
			(xy 426.329702 -19.044145) (xy 426.345068 -18.991815) (xy 426.367726 -18.942204) (xy 426.397214 -18.896324)
			(xy 426.432932 -18.855107) (xy 426.474152 -18.819393) (xy 426.520036 -18.789909) (xy 426.569649 -18.767256)
			(xy 426.621981 -18.751894) (xy 426.675966 -18.744137) (xy 426.703236 -18.743676) (xy 427.566836 -18.743676)
			(xy 427.594106 -18.744089) (xy 427.648091 -18.751856) (xy 427.700422 -18.767226) (xy 427.750032 -18.789886)
			(xy 427.795913 -18.819376) (xy 427.837131 -18.855095) (xy 427.872846 -18.896315) (xy 427.902331 -18.942199)
			(xy 427.924987 -18.991812) (xy 427.940352 -19.044144) (xy 427.948114 -19.09813) (xy 427.948114 -19.15267)
			(xy 431.90994 -19.15267) (xy 431.90994 -19.09813) (xy 431.917702 -19.044145) (xy 431.933068 -18.991815)
			(xy 431.955726 -18.942204) (xy 431.985214 -18.896324) (xy 432.020932 -18.855107) (xy 432.062152 -18.819393)
			(xy 432.108036 -18.789909) (xy 432.157649 -18.767256) (xy 432.209981 -18.751894) (xy 432.263966 -18.744137)
			(xy 432.291236 -18.743676) (xy 433.154836 -18.743676) (xy 433.182106 -18.744089) (xy 433.236091 -18.751856)
			(xy 433.288422 -18.767226) (xy 433.338032 -18.789886) (xy 433.383913 -18.819376) (xy 433.425131 -18.855095)
			(xy 433.460846 -18.896315) (xy 433.490331 -18.942199) (xy 433.512987 -18.991812) (xy 433.528352 -19.044144)
			(xy 433.536114 -19.09813) (xy 433.536114 -19.15267) (xy 433.528352 -19.206656) (xy 433.512987 -19.258988)
			(xy 433.490331 -19.308601) (xy 433.460846 -19.354485) (xy 433.425131 -19.395705) (xy 433.383913 -19.431424)
			(xy 433.338032 -19.460914) (xy 433.288422 -19.483574) (xy 433.236091 -19.498944) (xy 433.182106 -19.506711)
			(xy 433.154836 -19.5072) (xy 432.291236 -19.5072) (xy 432.263966 -19.506663) (xy 432.209981 -19.498906)
			(xy 432.157649 -19.483544) (xy 432.108036 -19.460891) (xy 432.062152 -19.431407) (xy 432.020932 -19.395693)
			(xy 431.985214 -19.354476) (xy 431.955726 -19.308596) (xy 431.933068 -19.258985) (xy 431.917702 -19.206655)
			(xy 431.90994 -19.15267) (xy 427.948114 -19.15267) (xy 427.940352 -19.206656) (xy 427.924987 -19.258988)
			(xy 427.902331 -19.308601) (xy 427.872846 -19.354485) (xy 427.837131 -19.395705) (xy 427.795913 -19.431424)
			(xy 427.750032 -19.460914) (xy 427.700422 -19.483574) (xy 427.648091 -19.498944) (xy 427.594106 -19.506711)
			(xy 427.566836 -19.5072) (xy 426.703236 -19.5072) (xy 426.675966 -19.506663) (xy 426.621981 -19.498906)
			(xy 426.569649 -19.483544) (xy 426.520036 -19.460891) (xy 426.474152 -19.431407) (xy 426.432932 -19.395693)
			(xy 426.397214 -19.354476) (xy 426.367726 -19.308596) (xy 426.345068 -19.258985) (xy 426.329702 -19.206655)
			(xy 426.32194 -19.15267) (xy 422.326113 -19.15267) (xy 422.326113 -19.152672) (xy 422.318351 -19.206661)
			(xy 422.302984 -19.258996) (xy 422.280326 -19.308611) (xy 422.250837 -19.354496) (xy 422.215118 -19.395718)
			(xy 422.173896 -19.431437) (xy 422.128011 -19.460926) (xy 422.078396 -19.483584) (xy 422.026061 -19.498951)
			(xy 421.972072 -19.506713) (xy 421.9448 -19.5072) (xy 421.0812 -19.5072) (xy 421.053933 -19.506638)
			(xy 420.999955 -19.498877) (xy 420.947631 -19.483513) (xy 420.898026 -19.460859) (xy 420.852149 -19.431376)
			(xy 420.810936 -19.395664) (xy 420.775224 -19.354451) (xy 420.745741 -19.308574) (xy 420.723087 -19.258969)
			(xy 420.707723 -19.206645) (xy 420.699962 -19.152667) (xy 416.738113 -19.152667) (xy 416.738113 -19.152672)
			(xy 416.730351 -19.206661) (xy 416.714984 -19.258996) (xy 416.692326 -19.308611) (xy 416.662837 -19.354496)
			(xy 416.627118 -19.395718) (xy 416.585896 -19.431437) (xy 416.540011 -19.460926) (xy 416.490396 -19.483584)
			(xy 416.438061 -19.498951) (xy 416.384072 -19.506713) (xy 416.3568 -19.5072) (xy 415.4932 -19.5072)
			(xy 415.465933 -19.506638) (xy 415.411955 -19.498877) (xy 415.359631 -19.483513) (xy 415.310026 -19.460859)
			(xy 415.264149 -19.431376) (xy 415.222936 -19.395664) (xy 415.187224 -19.354451) (xy 415.157741 -19.308574)
			(xy 415.135087 -19.258969) (xy 415.119723 -19.206645) (xy 415.111962 -19.152667) (xy 410.844336 -19.152667)
			(xy 410.844336 -19.152674) (xy 410.836573 -19.206668) (xy 410.821204 -19.259007) (xy 410.798543 -19.308626)
			(xy 410.769051 -19.354515) (xy 410.733329 -19.39574) (xy 410.692103 -19.431461) (xy 410.646212 -19.460951)
			(xy 410.596592 -19.48361) (xy 410.544252 -19.498976) (xy 410.490258 -19.506738) (xy 410.462984 -19.5072)
			(xy 409.599384 -19.5072) (xy 409.572118 -19.506637) (xy 409.518142 -19.498874) (xy 409.465819 -19.483509)
			(xy 409.416216 -19.460854) (xy 409.370342 -19.43137) (xy 409.32913 -19.395659) (xy 409.29342 -19.354446)
			(xy 409.263939 -19.30857) (xy 409.241286 -19.258966) (xy 409.225923 -19.206643) (xy 409.218162 -19.152666)
			(xy 405.256336 -19.152666) (xy 405.256336 -19.152674) (xy 405.248573 -19.206668) (xy 405.233204 -19.259007)
			(xy 405.210543 -19.308626) (xy 405.181051 -19.354515) (xy 405.145329 -19.39574) (xy 405.104103 -19.431461)
			(xy 405.058212 -19.460951) (xy 405.008592 -19.48361) (xy 404.956252 -19.498976) (xy 404.902258 -19.506738)
			(xy 404.874984 -19.5072) (xy 404.011384 -19.5072) (xy 403.984118 -19.506637) (xy 403.930142 -19.498874)
			(xy 403.877819 -19.483509) (xy 403.828216 -19.460854) (xy 403.782342 -19.43137) (xy 403.74113 -19.395659)
			(xy 403.70542 -19.354446) (xy 403.675939 -19.30857) (xy 403.653286 -19.258966) (xy 403.637923 -19.206643)
			(xy 403.630162 -19.152666) (xy 399.668336 -19.152666) (xy 399.668336 -19.152674) (xy 399.660573 -19.206668)
			(xy 399.645204 -19.259007) (xy 399.622543 -19.308626) (xy 399.593051 -19.354515) (xy 399.557329 -19.39574)
			(xy 399.516103 -19.431461) (xy 399.470212 -19.460951) (xy 399.420592 -19.48361) (xy 399.368252 -19.498976)
			(xy 399.314258 -19.506738) (xy 399.286984 -19.5072) (xy 398.423384 -19.5072) (xy 398.396118 -19.506637)
			(xy 398.342142 -19.498874) (xy 398.289819 -19.483509) (xy 398.240216 -19.460854) (xy 398.194342 -19.43137)
			(xy 398.15313 -19.395659) (xy 398.11742 -19.354446) (xy 398.087939 -19.30857) (xy 398.065286 -19.258966)
			(xy 398.049923 -19.206643) (xy 398.042162 -19.152666) (xy 394.080336 -19.152666) (xy 394.080336 -19.152674)
			(xy 394.072573 -19.206668) (xy 394.057204 -19.259007) (xy 394.034543 -19.308626) (xy 394.005051 -19.354515)
			(xy 393.969329 -19.39574) (xy 393.928103 -19.431461) (xy 393.882212 -19.460951) (xy 393.832592 -19.48361)
			(xy 393.780252 -19.498976) (xy 393.726258 -19.506738) (xy 393.698984 -19.5072) (xy 392.835384 -19.5072)
			(xy 392.808118 -19.506637) (xy 392.754142 -19.498874) (xy 392.701819 -19.483509) (xy 392.652216 -19.460854)
			(xy 392.606342 -19.43137) (xy 392.56513 -19.395659) (xy 392.52942 -19.354446) (xy 392.499939 -19.30857)
			(xy 392.477286 -19.258966) (xy 392.461923 -19.206643) (xy 392.454162 -19.152666) (xy 259.309108 -19.152666)
			(xy 259.309108 -25.468351) (xy 388.406603 -25.468351) (xy 388.406603 -25.413849) (xy 388.41436 -25.359901)
			(xy 388.429716 -25.307607) (xy 388.452359 -25.25803) (xy 388.481827 -25.212181) (xy 388.517521 -25.170992)
			(xy 388.558713 -25.135303) (xy 388.604565 -25.10584) (xy 388.654144 -25.083202) (xy 388.70644 -25.067852)
			(xy 388.760389 -25.0601) (xy 388.78764 -25.05964) (xy 389.65124 -25.05964) (xy 389.678493 -25.060033)
			(xy 389.732443 -25.067795) (xy 389.78474 -25.083155) (xy 389.834318 -25.105802) (xy 389.880169 -25.135273)
			(xy 389.92136 -25.170969) (xy 389.957051 -25.212163) (xy 389.986518 -25.258017) (xy 390.009159 -25.307598)
			(xy 390.024514 -25.359896) (xy 390.03227 -25.413847) (xy 390.03227 -25.468353) (xy 390.024514 -25.522304)
			(xy 390.009159 -25.574602) (xy 389.986518 -25.624183) (xy 389.957051 -25.670037) (xy 389.92136 -25.711231)
			(xy 389.880169 -25.746927) (xy 389.834318 -25.776398) (xy 389.78474 -25.799045) (xy 389.732443 -25.814405)
			(xy 389.678493 -25.822167) (xy 389.65124 -25.822656) (xy 388.78764 -25.822656) (xy 388.760389 -25.8221)
			(xy 388.70644 -25.814348) (xy 388.654144 -25.798998) (xy 388.604565 -25.77636) (xy 388.558713 -25.746897)
			(xy 388.517521 -25.711208) (xy 388.481827 -25.670019) (xy 388.452359 -25.62417) (xy 388.429716 -25.574593)
			(xy 388.41436 -25.522299) (xy 388.406603 -25.468351) (xy 259.309108 -25.468351) (xy 259.309108 -28.450032)
			(xy 354.840804 -28.450032) (xy 354.844787 -28.322014) (xy 354.856722 -28.194492) (xy 354.876561 -28.067958)
			(xy 354.904228 -27.942902) (xy 354.939617 -27.819809) (xy 354.98259 -27.699153) (xy 355.032981 -27.581403)
			(xy 355.090595 -27.467013) (xy 355.155209 -27.356426) (xy 355.226573 -27.25007) (xy 355.304411 -27.148357)
			(xy 355.388422 -27.051679) (xy 355.478281 -26.960412) (xy 355.57364 -26.874907) (xy 355.674131 -26.795497)
			(xy 355.779364 -26.722487) (xy 355.888933 -26.656161) (xy 356.002413 -26.596775) (xy 356.119365 -26.544559)
			(xy 356.239338 -26.499715) (xy 356.361866 -26.462417) (xy 356.486477 -26.432808) (xy 356.612686 -26.411003)
			(xy 356.740008 -26.397087) (xy 356.867948 -26.391113) (xy 356.996012 -26.393105) (xy 357.123705 -26.403055)
			(xy 357.250532 -26.420924) (xy 357.376003 -26.446643) (xy 357.499632 -26.480113) (xy 357.620941 -26.521204)
			(xy 357.739461 -26.569758) (xy 357.854733 -26.625586) (xy 357.966311 -26.688472) (xy 358.073764 -26.758174)
			(xy 358.176676 -26.834421) (xy 358.274648 -26.916918) (xy 358.367302 -27.005347) (xy 358.454279 -27.099365)
			(xy 358.535243 -27.198608) (xy 358.60988 -27.302693) (xy 358.677902 -27.411217) (xy 358.739046 -27.52376)
			(xy 358.793074 -27.639886) (xy 358.839779 -27.759147) (xy 358.878979 -27.88108) (xy 358.910522 -28.005215)
			(xy 358.934287 -28.131071) (xy 358.950181 -28.25816) (xy 358.958144 -28.385992) (xy 358.958642 -28.450032)
			(xy 358.958144 -28.514072) (xy 358.950181 -28.641904) (xy 358.934287 -28.768993) (xy 358.910522 -28.894849)
			(xy 358.878979 -29.018984) (xy 358.839779 -29.140917) (xy 358.793074 -29.260178) (xy 358.739046 -29.376304)
			(xy 358.677902 -29.488847) (xy 358.60988 -29.597371) (xy 358.535243 -29.701456) (xy 358.454279 -29.800699)
			(xy 358.367302 -29.894717) (xy 358.274648 -29.983146) (xy 358.176676 -30.065643) (xy 358.073764 -30.14189)
			(xy 357.966311 -30.211592) (xy 357.854733 -30.274478) (xy 357.739461 -30.330306) (xy 357.620941 -30.37886)
			(xy 357.499632 -30.419951) (xy 357.376003 -30.453421) (xy 357.250532 -30.47914) (xy 357.123705 -30.497009)
			(xy 356.996012 -30.506959) (xy 356.867948 -30.508951) (xy 356.740008 -30.502977) (xy 356.612686 -30.489061)
			(xy 356.486477 -30.467256) (xy 356.361866 -30.437647) (xy 356.239338 -30.400349) (xy 356.119365 -30.355505)
			(xy 356.002413 -30.303289) (xy 355.888933 -30.243903) (xy 355.779364 -30.177577) (xy 355.674131 -30.104567)
			(xy 355.57364 -30.025157) (xy 355.478281 -29.939652) (xy 355.388422 -29.848385) (xy 355.304411 -29.751707)
			(xy 355.226573 -29.649994) (xy 355.155209 -29.543638) (xy 355.090595 -29.433051) (xy 355.032981 -29.318661)
			(xy 354.98259 -29.200911) (xy 354.939617 -29.080255) (xy 354.904228 -28.957162) (xy 354.876561 -28.832106)
			(xy 354.856722 -28.705572) (xy 354.844787 -28.57805) (xy 354.840804 -28.450032) (xy 259.309108 -28.450032)
			(xy 259.309108 -33.275016) (xy 259.308614 -33.345398) (xy 259.30072 -33.48594) (xy 259.284959 -33.625819)
			(xy 259.261379 -33.764594) (xy 259.230448 -33.90011) (xy 462.69148 -33.90011) (xy 462.69148 -32.29991)
			(xy 462.691988 -32.23523) (xy 462.700111 -32.106124) (xy 462.716324 -31.977784) (xy 462.740564 -31.850714)
			(xy 462.772734 -31.725418) (xy 462.812709 -31.602388) (xy 462.86033 -31.482112) (xy 462.915409 -31.365063)
			(xy 462.977729 -31.251703) (xy 463.047044 -31.14248) (xy 463.12308 -31.037825) (xy 463.205538 -30.938151)
			(xy 463.294091 -30.843851) (xy 463.388391 -30.755298) (xy 463.488065 -30.67284) (xy 463.59272 -30.596804)
			(xy 463.701943 -30.527489) (xy 463.815303 -30.465169) (xy 463.932352 -30.41009) (xy 464.052628 -30.362469)
			(xy 464.175658 -30.322494) (xy 464.300954 -30.290324) (xy 464.428024 -30.266084) (xy 464.556364 -30.249871)
			(xy 464.68547 -30.241748) (xy 464.81483 -30.241748) (xy 464.943936 -30.249871) (xy 465.072276 -30.266084)
			(xy 465.199346 -30.290324) (xy 465.324642 -30.322494) (xy 465.447672 -30.362469) (xy 465.567948 -30.41009)
			(xy 465.684997 -30.465169) (xy 465.798357 -30.527489) (xy 465.90758 -30.596804) (xy 466.012235 -30.67284)
			(xy 466.111909 -30.755298) (xy 466.206209 -30.843851) (xy 466.294762 -30.938151) (xy 466.37722 -31.037825)
			(xy 466.453256 -31.14248) (xy 466.522571 -31.251703) (xy 466.584891 -31.365063) (xy 466.63997 -31.482112)
			(xy 466.687591 -31.602388) (xy 466.727566 -31.725418) (xy 466.759736 -31.850714) (xy 466.783976 -31.977784)
			(xy 466.800189 -32.106124) (xy 466.808312 -32.23523) (xy 466.80882 -32.29991) (xy 466.80882 -33.90011)
			(xy 466.808312 -33.96479) (xy 466.800189 -34.093896) (xy 466.783976 -34.222236) (xy 466.759736 -34.349306)
			(xy 466.727566 -34.474602) (xy 466.687591 -34.597632) (xy 466.63997 -34.717908) (xy 466.584891 -34.834957)
			(xy 466.522571 -34.948317) (xy 466.453256 -35.05754) (xy 466.37722 -35.162195) (xy 466.294762 -35.261869)
			(xy 466.206209 -35.356169) (xy 466.111909 -35.444722) (xy 466.012235 -35.52718) (xy 465.90758 -35.603216)
			(xy 465.798357 -35.672531) (xy 465.684997 -35.734851) (xy 465.567948 -35.78993) (xy 465.447672 -35.837551)
			(xy 465.324642 -35.877526) (xy 465.199346 -35.909696) (xy 465.072276 -35.933936) (xy 464.943936 -35.950149)
			(xy 464.81483 -35.958272) (xy 464.68547 -35.958272) (xy 464.556364 -35.950149) (xy 464.428024 -35.933936)
			(xy 464.300954 -35.909696) (xy 464.175658 -35.877526) (xy 464.052628 -35.837551) (xy 463.932352 -35.78993)
			(xy 463.815303 -35.734851) (xy 463.701943 -35.672531) (xy 463.59272 -35.603216) (xy 463.488065 -35.52718)
			(xy 463.388391 -35.444722) (xy 463.294091 -35.356169) (xy 463.205538 -35.261869) (xy 463.12308 -35.162195)
			(xy 463.047044 -35.05754) (xy 462.977729 -34.948317) (xy 462.915409 -34.834957) (xy 462.86033 -34.717908)
			(xy 462.812709 -34.597632) (xy 462.772734 -34.474602) (xy 462.740564 -34.349306) (xy 462.716324 -34.222236)
			(xy 462.700111 -34.093896) (xy 462.691988 -33.96479) (xy 462.69148 -33.90011) (xy 259.230448 -33.90011)
			(xy 259.230056 -33.901828) (xy 259.191086 -34.03709) (xy 259.144594 -34.169955) (xy 259.090726 -34.300003)
			(xy 259.02965 -34.426827) (xy 258.961559 -34.550026) (xy 258.886668 -34.669214) (xy 258.805211 -34.784015)
			(xy 258.717446 -34.894068) (xy 258.623648 -34.999027) (xy 258.524113 -35.098562) (xy 258.419153 -35.192359)
			(xy 258.324611 -35.267753) (xy 356.989346 -35.267753) (xy 356.989346 -35.213247) (xy 356.997102 -35.159297)
			(xy 357.012458 -35.106999) (xy 357.035099 -35.057419) (xy 357.064566 -35.011566) (xy 357.100259 -34.970373)
			(xy 357.14145 -34.934678) (xy 357.187302 -34.905209) (xy 357.236881 -34.882565) (xy 357.289177 -34.867207)
			(xy 357.343127 -34.859447) (xy 357.37038 -34.85896) (xy 358.23398 -34.85896) (xy 358.261232 -34.859486)
			(xy 358.31518 -34.86724) (xy 358.367476 -34.882593) (xy 358.417054 -34.905232) (xy 358.462906 -34.934697)
			(xy 358.504098 -34.970388) (xy 358.539791 -35.011578) (xy 358.569258 -35.057428) (xy 358.5919 -35.107005)
			(xy 358.607256 -35.1593) (xy 358.615013 -35.213249) (xy 358.615013 -35.267751) (xy 358.607256 -35.3217)
			(xy 358.5919 -35.373995) (xy 358.569258 -35.423572) (xy 358.539791 -35.469422) (xy 358.504098 -35.510612)
			(xy 358.462906 -35.546303) (xy 358.417054 -35.575768) (xy 358.367476 -35.598407) (xy 358.31518 -35.61376)
			(xy 358.261232 -35.621514) (xy 358.23398 -35.621976) (xy 357.37038 -35.621976) (xy 357.343127 -35.621553)
			(xy 357.289177 -35.613793) (xy 357.236881 -35.598435) (xy 357.187302 -35.575791) (xy 357.14145 -35.546322)
			(xy 357.100259 -35.510627) (xy 357.064566 -35.469434) (xy 357.035099 -35.423581) (xy 357.012458 -35.374001)
			(xy 356.997102 -35.321703) (xy 356.989346 -35.267753) (xy 258.324611 -35.267753) (xy 258.309099 -35.280123)
			(xy 258.194297 -35.361579) (xy 258.075109 -35.436469) (xy 257.951909 -35.504559) (xy 257.825085 -35.565634)
			(xy 257.695036 -35.619502) (xy 257.562171 -35.665993) (xy 257.426909 -35.704961) (xy 257.289674 -35.736283)
			(xy 257.150899 -35.759862) (xy 257.01102 -35.775622) (xy 256.870478 -35.783514) (xy 256.800096 -35.784028)
			(xy 225.300032 -35.784028) (xy 225.229649 -35.783544) (xy 225.089104 -35.775653) (xy 224.949222 -35.759894)
			(xy 224.810444 -35.736316) (xy 224.673207 -35.704995) (xy 224.537941 -35.666027) (xy 224.405074 -35.619536)
			(xy 224.275022 -35.565669) (xy 224.148195 -35.504594) (xy 224.024992 -35.436504) (xy 223.905801 -35.361613)
			(xy 223.790997 -35.280156) (xy 223.68094 -35.192391) (xy 223.575978 -35.098593) (xy 223.47644 -34.999057)
			(xy 223.38264 -34.894096) (xy 223.294872 -34.784042) (xy 223.213414 -34.669239) (xy 223.138521 -34.550049)
			(xy 223.070428 -34.426848) (xy 223.009351 -34.300022) (xy 222.955481 -34.169971) (xy 222.908988 -34.037104)
			(xy 222.870017 -33.90184) (xy 222.838693 -33.764603) (xy 222.815113 -33.625825) (xy 222.799351 -33.485944)
			(xy 222.791457 -33.345399) (xy 222.79102 -33.275016) (xy 222.79102 -13.780008) (xy 222.790499 -13.724238)
			(xy 222.782164 -13.613011) (xy 222.765541 -13.502717) (xy 222.740722 -13.393974) (xy 222.707846 -13.287389)
			(xy 222.667097 -13.183559) (xy 222.618703 -13.083065) (xy 222.562935 -12.986469) (xy 222.500103 -12.894309)
			(xy 222.430561 -12.807103) (xy 222.354696 -12.725338) (xy 222.272933 -12.64947) (xy 222.185729 -12.579925)
			(xy 222.093572 -12.517091) (xy 221.996977 -12.461319) (xy 221.896485 -12.412922) (xy 221.792656 -12.37217)
			(xy 221.686073 -12.339291) (xy 221.57733 -12.314468) (xy 221.467037 -12.297841) (xy 221.35581 -12.289503)
			(xy 221.30004 -12.289028) (xy 196.701918 -12.289028) (xy 196.631535 -12.288544) (xy 196.49099 -12.280652)
			(xy 196.35111 -12.264892) (xy 196.212332 -12.241314) (xy 196.075095 -12.209992) (xy 195.939831 -12.171024)
			(xy 195.806964 -12.124532) (xy 195.676913 -12.070665) (xy 195.550086 -12.009589) (xy 195.426884 -11.941499)
			(xy 195.307694 -11.866608) (xy 195.19289 -11.785152) (xy 195.082834 -11.697386) (xy 194.977873 -11.603588)
			(xy 194.878335 -11.504052) (xy 194.784536 -11.399092) (xy 194.696769 -11.289037) (xy 194.615311 -11.174234)
			(xy 194.540418 -11.055045) (xy 194.472326 -10.931844) (xy 194.411249 -10.805018) (xy 194.35738 -10.674968)
			(xy 194.310887 -10.542102) (xy 194.271917 -10.406837) (xy 194.240593 -10.269601) (xy 194.217013 -10.130824)
			(xy 194.201251 -9.990943) (xy 194.193357 -9.850399) (xy 194.192906 -9.780016) (xy 194.192906 -6.279896)
			(xy 194.19238 -6.247749) (xy 194.183988 -6.184006) (xy 194.167348 -6.121904) (xy 194.142744 -6.062504)
			(xy 194.110598 -6.006824) (xy 194.07146 -5.955816) (xy 194.025999 -5.910353) (xy 193.974992 -5.871213)
			(xy 193.919314 -5.839064) (xy 193.859915 -5.814458) (xy 193.797813 -5.797816) (xy 193.734071 -5.789421)
			(xy 193.701924 -5.788914) (xy 127.102108 -5.788914) (xy 127.06996 -5.789416) (xy 127.006214 -5.797808)
			(xy 126.944108 -5.814448) (xy 126.884706 -5.839052) (xy 126.829023 -5.8712) (xy 126.778013 -5.91034)
			(xy 126.732548 -5.955804) (xy 126.693406 -6.006813) (xy 126.661257 -6.062495) (xy 126.636652 -6.121897)
			(xy 126.62001 -6.184002) (xy 126.611617 -6.247748) (xy 126.611126 -6.279896) (xy 126.611126 -9.780016)
			(xy 126.610632 -9.850398) (xy 126.602738 -9.990941) (xy 126.586977 -10.13082) (xy 126.563397 -10.269595)
			(xy 126.532074 -10.40683) (xy 126.519617 -10.450068) (xy 127.350273 -10.450068) (xy 127.354278 -10.36216)
			(xy 127.366261 -10.27498) (xy 127.386121 -10.189251) (xy 127.413696 -10.105683) (xy 127.448755 -10.024969)
			(xy 127.491008 -9.947777) (xy 127.540106 -9.874748) (xy 127.595642 -9.806486) (xy 127.657154 -9.743556)
			(xy 127.724135 -9.686482) (xy 127.796028 -9.635734) (xy 127.872237 -9.591734) (xy 127.952132 -9.554847)
			(xy 128.035051 -9.525378) (xy 128.120306 -9.503571) (xy 128.20719 -9.489607) (xy 128.294984 -9.483601)
			(xy 128.382961 -9.485605) (xy 128.470391 -9.4956) (xy 128.55655 -9.513504) (xy 128.640724 -9.539168)
			(xy 128.722215 -9.572381) (xy 128.800349 -9.612867) (xy 128.874477 -9.660289) (xy 128.943985 -9.714256)
			(xy 129.008299 -9.774321) (xy 129.066883 -9.839985) (xy 129.119254 -9.910704) (xy 129.164977 -9.985892)
			(xy 129.203674 -10.064927) (xy 129.235023 -10.147153) (xy 129.258765 -10.231889) (xy 129.265884 -10.270548)
			(xy 131.63909 -10.270548) (xy 131.63909 -10.216052) (xy 131.646845 -10.16211) (xy 131.662198 -10.10982)
			(xy 131.684835 -10.060247) (xy 131.714296 -10.014401) (xy 131.749982 -9.973213) (xy 131.791165 -9.937522)
			(xy 131.837009 -9.908056) (xy 131.886579 -9.885413) (xy 131.938866 -9.870055) (xy 131.992808 -9.862293)
			(xy 132.020056 -9.861804) (xy 132.883656 -9.861804) (xy 132.910912 -9.86224) (xy 132.964869 -9.869992)
			(xy 133.017174 -9.885345) (xy 133.066761 -9.907985) (xy 133.112622 -9.937453) (xy 133.153821 -9.973148)
			(xy 133.18952 -10.014343) (xy 133.218993 -10.0602) (xy 133.24164 -10.109785) (xy 133.256999 -10.162088)
			(xy 133.264757 -10.216044) (xy 133.264757 -10.270556) (xy 133.256999 -10.324512) (xy 133.24164 -10.376815)
			(xy 133.218993 -10.4264) (xy 133.18952 -10.472257) (xy 133.153821 -10.513452) (xy 133.112622 -10.549147)
			(xy 133.066761 -10.578615) (xy 133.017174 -10.601255) (xy 132.964869 -10.616608) (xy 132.910912 -10.62436)
			(xy 132.883656 -10.62482) (xy 132.020056 -10.62482) (xy 131.992808 -10.624307) (xy 131.938866 -10.616545)
			(xy 131.886579 -10.601187) (xy 131.837009 -10.578544) (xy 131.791165 -10.549078) (xy 131.749982 -10.513387)
			(xy 131.714296 -10.472199) (xy 131.684835 -10.426353) (xy 131.662198 -10.37678) (xy 131.646845 -10.32449)
			(xy 131.63909 -10.270548) (xy 129.265884 -10.270548) (xy 129.274703 -10.318433) (xy 129.282705 -10.406068)
			(xy 129.283206 -10.450068) (xy 129.282705 -10.494068) (xy 129.274703 -10.581703) (xy 129.258765 -10.668247)
			(xy 129.235023 -10.752983) (xy 129.203674 -10.835209) (xy 129.164977 -10.914244) (xy 129.119254 -10.989432)
			(xy 129.087321 -11.032553) (xy 168.158867 -11.032553) (xy 168.158867 -10.978047) (xy 168.166625 -10.924096)
			(xy 168.181981 -10.871798) (xy 168.204625 -10.822218) (xy 168.234094 -10.776365) (xy 168.269789 -10.735173)
			(xy 168.310983 -10.699481) (xy 168.356837 -10.670014) (xy 168.406419 -10.647374) (xy 168.458717 -10.63202)
			(xy 168.512669 -10.624266) (xy 168.539922 -10.623804) (xy 169.403522 -10.623804) (xy 169.430773 -10.624267)
			(xy 169.48472 -10.632027) (xy 169.537014 -10.647384) (xy 169.58659 -10.670027) (xy 169.632439 -10.699495)
			(xy 169.673628 -10.735188) (xy 169.709318 -10.776379) (xy 169.738783 -10.822229) (xy 169.761424 -10.871807)
			(xy 169.776778 -10.924101) (xy 169.784534 -10.978049) (xy 169.784534 -11.032551) (xy 169.776778 -11.086499)
			(xy 169.761424 -11.138793) (xy 169.738783 -11.188371) (xy 169.709318 -11.234221) (xy 169.673628 -11.275412)
			(xy 169.632439 -11.311105) (xy 169.58659 -11.340573) (xy 169.537014 -11.363216) (xy 169.48472 -11.378573)
			(xy 169.430773 -11.386333) (xy 169.403522 -11.38682) (xy 168.539922 -11.38682) (xy 168.512669 -11.386334)
			(xy 168.458717 -11.37858) (xy 168.406419 -11.363226) (xy 168.356837 -11.340586) (xy 168.310983 -11.311119)
			(xy 168.269789 -11.275427) (xy 168.234094 -11.234235) (xy 168.204625 -11.188382) (xy 168.181981 -11.138802)
			(xy 168.166625 -11.086504) (xy 168.158867 -11.032553) (xy 129.087321 -11.032553) (xy 129.066883 -11.060151)
			(xy 129.008299 -11.125815) (xy 128.943985 -11.18588) (xy 128.874477 -11.239847) (xy 128.800349 -11.287269)
			(xy 128.722215 -11.327755) (xy 128.640724 -11.360968) (xy 128.55655 -11.386632) (xy 128.470391 -11.404536)
			(xy 128.382961 -11.414531) (xy 128.294984 -11.416535) (xy 128.20719 -11.410529) (xy 128.120306 -11.396565)
			(xy 128.035051 -11.374758) (xy 127.952132 -11.345289) (xy 127.872237 -11.308402) (xy 127.796028 -11.264402)
			(xy 127.724135 -11.213654) (xy 127.657154 -11.15658) (xy 127.595642 -11.09365) (xy 127.540106 -11.025388)
			(xy 127.491008 -10.952359) (xy 127.448755 -10.875167) (xy 127.413696 -10.794453) (xy 127.386121 -10.710885)
			(xy 127.366261 -10.625156) (xy 127.354278 -10.537976) (xy 127.350273 -10.450068) (xy 126.519617 -10.450068)
			(xy 126.493105 -10.542092) (xy 126.446613 -10.674957) (xy 126.392744 -10.805006) (xy 126.331668 -10.93183)
			(xy 126.263578 -11.05503) (xy 126.188687 -11.174218) (xy 126.10723 -11.28902) (xy 126.019465 -11.399074)
			(xy 125.973895 -11.450066) (xy 191.515245 -11.450066) (xy 191.51925 -11.362158) (xy 191.531233 -11.274978)
			(xy 191.551093 -11.189249) (xy 191.578668 -11.105681) (xy 191.613727 -11.024967) (xy 191.65598 -10.947775)
			(xy 191.705078 -10.874746) (xy 191.760614 -10.806484) (xy 191.822126 -10.743554) (xy 191.889107 -10.68648)
			(xy 191.961 -10.635732) (xy 192.037209 -10.591732) (xy 192.117104 -10.554845) (xy 192.200023 -10.525376)
			(xy 192.285278 -10.503569) (xy 192.372162 -10.489605) (xy 192.459956 -10.483599) (xy 192.547933 -10.485603)
			(xy 192.635363 -10.495598) (xy 192.721522 -10.513502) (xy 192.805696 -10.539166) (xy 192.887187 -10.572379)
			(xy 192.965321 -10.612865) (xy 193.039449 -10.660287) (xy 193.108957 -10.714254) (xy 193.173271 -10.774319)
			(xy 193.231855 -10.839983) (xy 193.284226 -10.910702) (xy 193.329949 -10.98589) (xy 193.368646 -11.064925)
			(xy 193.399995 -11.147151) (xy 193.423737 -11.231887) (xy 193.439675 -11.318431) (xy 193.447677 -11.406066)
			(xy 193.448178 -11.450066) (xy 193.447677 -11.494066) (xy 193.439675 -11.581701) (xy 193.423737 -11.668245)
			(xy 193.399995 -11.752981) (xy 193.368646 -11.835207) (xy 193.329949 -11.914242) (xy 193.284226 -11.98943)
			(xy 193.231855 -12.060149) (xy 193.173271 -12.125813) (xy 193.108957 -12.185878) (xy 193.039449 -12.239845)
			(xy 192.965321 -12.287267) (xy 192.887187 -12.327753) (xy 192.805696 -12.360966) (xy 192.721522 -12.38663)
			(xy 192.635363 -12.404534) (xy 192.547933 -12.414529) (xy 192.459956 -12.416533) (xy 192.372162 -12.410527)
			(xy 192.285278 -12.396563) (xy 192.200023 -12.374756) (xy 192.117104 -12.345287) (xy 192.037209 -12.3084)
			(xy 191.961 -12.2644) (xy 191.889107 -12.213652) (xy 191.822126 -12.156578) (xy 191.760614 -12.093648)
			(xy 191.705078 -12.025386) (xy 191.65598 -11.952357) (xy 191.613727 -11.875165) (xy 191.578668 -11.794451)
			(xy 191.551093 -11.710883) (xy 191.531233 -11.625154) (xy 191.51925 -11.537974) (xy 191.515245 -11.450066)
			(xy 125.973895 -11.450066) (xy 125.925667 -11.504033) (xy 125.826132 -11.603569) (xy 125.721172 -11.697366)
			(xy 125.611118 -11.785131) (xy 125.496317 -11.866588) (xy 125.377128 -11.941479) (xy 125.253928 -12.009569)
			(xy 125.206611 -12.032356) (xy 166.354411 -12.032356) (xy 166.354411 -11.977844) (xy 166.362169 -11.923886)
			(xy 166.377527 -11.871582) (xy 166.400173 -11.821995) (xy 166.429645 -11.776137) (xy 166.465343 -11.734939)
			(xy 166.506541 -11.699241) (xy 166.552401 -11.66977) (xy 166.601987 -11.647125) (xy 166.654292 -11.631768)
			(xy 166.70825 -11.624011) (xy 166.735506 -11.623548) (xy 167.599106 -11.623548) (xy 167.626354 -11.624123)
			(xy 167.680295 -11.631879) (xy 167.732583 -11.647233) (xy 167.782153 -11.669872) (xy 167.827998 -11.699335)
			(xy 167.869182 -11.735022) (xy 167.904869 -11.776207) (xy 167.934331 -11.822052) (xy 167.956969 -11.871623)
			(xy 167.972322 -11.923911) (xy 167.980078 -11.977852) (xy 167.980078 -12.032348) (xy 167.980077 -12.032358)
			(xy 169.954311 -12.032358) (xy 169.954311 -11.977842) (xy 169.96207 -11.92388) (xy 169.97743 -11.871573)
			(xy 170.000079 -11.821984) (xy 170.029555 -11.776123) (xy 170.065258 -11.734924) (xy 170.106461 -11.699226)
			(xy 170.152326 -11.669756) (xy 170.201918 -11.647114) (xy 170.254227 -11.63176) (xy 170.30819 -11.624008)
			(xy 170.335448 -11.623548) (xy 171.199048 -11.623548) (xy 171.226294 -11.624125) (xy 171.28023 -11.631887)
			(xy 171.332513 -11.647244) (xy 171.382078 -11.669885) (xy 171.427917 -11.699349) (xy 171.469097 -11.735037)
			(xy 171.504779 -11.776221) (xy 171.534238 -11.822064) (xy 171.556873 -11.871632) (xy 171.572224 -11.923917)
			(xy 171.579978 -11.977854) (xy 171.579978 -12.032346) (xy 171.572224 -12.086283) (xy 171.556873 -12.138568)
			(xy 171.534238 -12.188136) (xy 171.504779 -12.233979) (xy 171.469097 -12.275163) (xy 171.427917 -12.310851)
			(xy 171.382078 -12.340315) (xy 171.332513 -12.362956) (xy 171.28023 -12.378313) (xy 171.226294 -12.386075)
			(xy 171.199048 -12.386564) (xy 170.335448 -12.386564) (xy 170.30819 -12.386192) (xy 170.254227 -12.37844)
			(xy 170.201918 -12.363086) (xy 170.152326 -12.340444) (xy 170.106461 -12.310974) (xy 170.065258 -12.275276)
			(xy 170.029555 -12.234077) (xy 170.000079 -12.188216) (xy 169.97743 -12.138627) (xy 169.96207 -12.08632)
			(xy 169.954311 -12.032358) (xy 167.980077 -12.032358) (xy 167.972322 -12.086289) (xy 167.956969 -12.138577)
			(xy 167.934331 -12.188148) (xy 167.904869 -12.233993) (xy 167.869182 -12.275178) (xy 167.827998 -12.310865)
			(xy 167.782153 -12.340328) (xy 167.732583 -12.362967) (xy 167.680295 -12.378321) (xy 167.626354 -12.386077)
			(xy 167.599106 -12.386564) (xy 166.735506 -12.386564) (xy 166.70825 -12.386189) (xy 166.654292 -12.378432)
			(xy 166.601987 -12.363075) (xy 166.552401 -12.34043) (xy 166.506541 -12.310959) (xy 166.465343 -12.275261)
			(xy 166.429645 -12.234063) (xy 166.400173 -12.188205) (xy 166.377527 -12.138618) (xy 166.362169 -12.086314)
			(xy 166.354411 -12.032356) (xy 125.206611 -12.032356) (xy 125.127104 -12.070645) (xy 124.997055 -12.124513)
			(xy 124.86419 -12.171005) (xy 124.728928 -12.209974) (xy 124.591693 -12.241298) (xy 124.452918 -12.264877)
			(xy 124.313039 -12.280639) (xy 124.172496 -12.288532) (xy 124.102114 -12.289028) (xy 83.70189 -12.289028)
			(xy 83.631508 -12.288534) (xy 83.490965 -12.280641) (xy 83.351086 -12.26488) (xy 83.21231 -12.2413)
			(xy 83.075075 -12.209977) (xy 82.939812 -12.171008) (xy 82.806947 -12.124516) (xy 82.676898 -12.070648)
			(xy 82.550073 -12.009572) (xy 82.426873 -11.941482) (xy 82.307684 -11.866591) (xy 82.192882 -11.785134)
			(xy 82.082828 -11.697369) (xy 81.977868 -11.603571) (xy 81.878333 -11.504036) (xy 81.784535 -11.399076)
			(xy 81.696769 -11.289022) (xy 81.615313 -11.174221) (xy 81.540421 -11.055032) (xy 81.47233 -10.931832)
			(xy 81.411254 -10.805008) (xy 81.357386 -10.674959) (xy 81.310894 -10.542094) (xy 81.271924 -10.406831)
			(xy 81.240601 -10.269596) (xy 81.217021 -10.13082) (xy 81.20126 -9.990941) (xy 81.193366 -9.850398)
			(xy 81.192878 -9.780016) (xy 81.192878 -0.999998) (xy 81.192375 -0.96785) (xy 81.183982 -0.904106)
			(xy 81.167341 -0.842001) (xy 81.142736 -0.782601) (xy 81.110589 -0.72692) (xy 81.071448 -0.675911)
			(xy 81.025984 -0.630448) (xy 80.974975 -0.591308) (xy 80.919294 -0.559161) (xy 80.859893 -0.534557)
			(xy 80.797789 -0.517916) (xy 80.734044 -0.509525) (xy 80.701896 -0.509016) (xy 14.10208 -0.509016)
			(xy 14.069935 -0.509543) (xy 14.006194 -0.517937) (xy 13.944095 -0.534579) (xy 13.884698 -0.559184)
			(xy 13.829022 -0.59133) (xy 13.778017 -0.630469) (xy 13.732558 -0.675931) (xy 13.69342 -0.726937)
			(xy 13.661276 -0.782614) (xy 13.636673 -0.842012) (xy 13.620034 -0.904112) (xy 13.611642 -0.967853)
			(xy 13.611098 -0.999998) (xy 13.611098 -5.184498) (xy 14.350702 -5.184498) (xy 14.35331 -5.097781)
			(xy 14.363685 -5.011647) (xy 14.381743 -4.926791) (xy 14.40734 -4.843896) (xy 14.440268 -4.763631)
			(xy 14.480262 -4.686643) (xy 14.526999 -4.613552) (xy 14.580104 -4.544948) (xy 14.639148 -4.481383)
			(xy 14.703655 -4.42337) (xy 14.738096 -4.396994) (xy 14.773029 -4.371293) (xy 14.846784 -4.325653)
			(xy 14.924335 -4.28681) (xy 15.005056 -4.255076) (xy 15.088297 -4.230709) (xy 15.173387 -4.213903)
			(xy 15.259642 -4.204794) (xy 15.346366 -4.203455) (xy 15.432861 -4.209898) (xy 15.518429 -4.224071)
			(xy 15.602382 -4.245858) (xy 15.684044 -4.275086) (xy 15.762756 -4.311517) (xy 15.837884 -4.35486)
			(xy 15.908824 -4.404764) (xy 15.975003 -4.460828) (xy 16.035889 -4.5226) (xy 16.090991 -4.589582)
			(xy 16.139865 -4.661235) (xy 16.182118 -4.736981) (xy 16.217409 -4.816211) (xy 16.245454 -4.898286)
			(xy 16.266027 -4.982545) (xy 16.267136 -4.989901) (xy 20.44038 -4.989901) (xy 20.44038 -4.935399)
			(xy 20.448136 -4.881452) (xy 20.463491 -4.829158) (xy 20.486132 -4.779581) (xy 20.515597 -4.733731)
			(xy 20.551288 -4.692541) (xy 20.592478 -4.65685) (xy 20.638328 -4.627384) (xy 20.687904 -4.604742)
			(xy 20.740198 -4.589387) (xy 20.794145 -4.58163) (xy 20.821396 -4.581144) (xy 21.684996 -4.581144)
			(xy 21.712249 -4.581603) (xy 21.766201 -4.58936) (xy 21.818499 -4.604715) (xy 21.86808 -4.627358)
			(xy 21.913934 -4.656826) (xy 21.955128 -4.69252) (xy 21.990822 -4.733713) (xy 22.02029 -4.779566)
			(xy 22.042933 -4.829147) (xy 22.05829 -4.881445) (xy 22.066047 -4.935397) (xy 22.066047 -4.989901)
			(xy 24.04032 -4.989901) (xy 24.04032 -4.935399) (xy 24.048076 -4.881452) (xy 24.063431 -4.829157)
			(xy 24.086072 -4.779581) (xy 24.115538 -4.73373) (xy 24.151229 -4.692541) (xy 24.192419 -4.656849)
			(xy 24.238269 -4.627383) (xy 24.287846 -4.604742) (xy 24.34014 -4.589387) (xy 24.394087 -4.58163)
			(xy 24.421338 -4.581144) (xy 25.284938 -4.581144) (xy 25.312191 -4.581603) (xy 25.366143 -4.58936)
			(xy 25.418441 -4.604716) (xy 25.468021 -4.627358) (xy 25.513875 -4.656827) (xy 25.555068 -4.69252)
			(xy 25.590762 -4.733713) (xy 25.620231 -4.779567) (xy 25.642873 -4.829147) (xy 25.65823 -4.881446)
			(xy 25.665987 -4.935397) (xy 25.665987 -4.989903) (xy 25.66598 -4.989954) (xy 27.64023 -4.989954)
			(xy 27.64023 -4.935446) (xy 27.647987 -4.881493) (xy 27.663343 -4.829194) (xy 27.685985 -4.779612)
			(xy 27.715454 -4.733756) (xy 27.751147 -4.692562) (xy 27.79234 -4.656866) (xy 27.838194 -4.627395)
			(xy 27.887775 -4.60475) (xy 27.940074 -4.589391) (xy 27.994026 -4.581631) (xy 28.02128 -4.581144)
			(xy 28.88488 -4.581144) (xy 28.91213 -4.581702) (xy 28.966077 -4.589456) (xy 29.01837 -4.604808)
			(xy 29.067947 -4.627446) (xy 29.113797 -4.65691) (xy 29.154986 -4.692599) (xy 29.190678 -4.733787)
			(xy 29.220144 -4.779636) (xy 29.242785 -4.829211) (xy 29.25814 -4.881504) (xy 29.265897 -4.93545)
			(xy 29.265897 -4.98995) (xy 29.265896 -4.989954) (xy 31.24043 -4.989954) (xy 31.24043 -4.935446)
			(xy 31.248187 -4.881494) (xy 31.263543 -4.829195) (xy 31.286185 -4.779613) (xy 31.315653 -4.733758)
			(xy 31.351346 -4.692563) (xy 31.392538 -4.656867) (xy 31.438392 -4.627396) (xy 31.487972 -4.604751)
			(xy 31.540271 -4.589392) (xy 31.594222 -4.581632) (xy 31.621476 -4.581144) (xy 32.485076 -4.581144)
			(xy 32.512327 -4.581702) (xy 32.566273 -4.589455) (xy 32.618567 -4.604807) (xy 32.668144 -4.627445)
			(xy 32.713995 -4.656909) (xy 32.755185 -4.692598) (xy 32.790877 -4.733786) (xy 32.820343 -4.779635)
			(xy 32.842985 -4.82921) (xy 32.85834 -4.881503) (xy 32.866097 -4.935449) (xy 32.866097 -4.989951)
			(xy 32.866096 -4.989958) (xy 40.350307 -4.989958) (xy 40.350307 -4.935442) (xy 40.358066 -4.881481)
			(xy 40.373426 -4.829173) (xy 40.396074 -4.779584) (xy 40.42555 -4.733723) (xy 40.461252 -4.692524)
			(xy 40.502455 -4.656826) (xy 40.548319 -4.627355) (xy 40.59791 -4.604712) (xy 40.65022 -4.589358)
			(xy 40.704182 -4.581604) (xy 40.73144 -4.581144) (xy 41.59504 -4.581144) (xy 41.622286 -4.581729)
			(xy 41.676222 -4.589489) (xy 41.728506 -4.604846) (xy 41.778072 -4.627486) (xy 41.823911 -4.65695)
			(xy 41.865091 -4.692637) (xy 41.900774 -4.733821) (xy 41.930233 -4.779663) (xy 41.952868 -4.829232)
			(xy 41.968219 -4.881517) (xy 41.975974 -4.935454) (xy 41.975974 -4.989946) (xy 41.975973 -4.989954)
			(xy 43.95033 -4.989954) (xy 43.95033 -4.935446) (xy 43.958087 -4.881493) (xy 43.973443 -4.829193)
			(xy 43.996086 -4.779611) (xy 44.025554 -4.733756) (xy 44.061248 -4.692561) (xy 44.102441 -4.656865)
			(xy 44.148295 -4.627394) (xy 44.197876 -4.604749) (xy 44.250176 -4.589391) (xy 44.304128 -4.581631)
			(xy 44.331382 -4.581144) (xy 45.194982 -4.581144) (xy 45.222232 -4.581702) (xy 45.276178 -4.589456)
			(xy 45.328472 -4.604808) (xy 45.378048 -4.627447) (xy 45.423898 -4.656911) (xy 45.465087 -4.6926)
			(xy 45.500778 -4.733788) (xy 45.530244 -4.779636) (xy 45.552885 -4.829211) (xy 45.56824 -4.881504)
			(xy 45.575997 -4.93545) (xy 45.575997 -4.98995) (xy 45.575996 -4.989954) (xy 51.56043 -4.989954)
			(xy 51.56043 -4.935446) (xy 51.568187 -4.881494) (xy 51.583543 -4.829195) (xy 51.606185 -4.779613)
			(xy 51.635653 -4.733758) (xy 51.671346 -4.692563) (xy 51.712538 -4.656867) (xy 51.758392 -4.627396)
			(xy 51.807972 -4.604751) (xy 51.860271 -4.589392) (xy 51.914222 -4.581632) (xy 51.941476 -4.581144)
			(xy 52.805076 -4.581144) (xy 52.832327 -4.581702) (xy 52.886273 -4.589455) (xy 52.938567 -4.604807)
			(xy 52.988144 -4.627445) (xy 53.033995 -4.656909) (xy 53.075185 -4.692598) (xy 53.110877 -4.733786)
			(xy 53.140343 -4.779635) (xy 53.162985 -4.82921) (xy 53.17834 -4.881503) (xy 53.186097 -4.935449)
			(xy 53.186097 -4.989951) (xy 53.186096 -4.989957) (xy 55.160307 -4.989957) (xy 55.160307 -4.935443)
			(xy 55.168065 -4.881484) (xy 55.183424 -4.829178) (xy 55.206071 -4.77959) (xy 55.235544 -4.73373)
			(xy 55.271245 -4.692532) (xy 55.312445 -4.656834) (xy 55.358306 -4.627362) (xy 55.407894 -4.604718)
			(xy 55.460201 -4.589362) (xy 55.514161 -4.581606) (xy 55.541418 -4.581144) (xy 56.405018 -4.581144)
			(xy 56.432265 -4.581727) (xy 56.486204 -4.589485) (xy 56.53849 -4.60484) (xy 56.588058 -4.627479)
			(xy 56.633901 -4.656942) (xy 56.675084 -4.692629) (xy 56.710769 -4.733814) (xy 56.74023 -4.779657)
			(xy 56.762867 -4.829227) (xy 56.778219 -4.881514) (xy 56.785974 -4.935453) (xy 56.785974 -4.989947)
			(xy 56.778219 -5.043886) (xy 56.762867 -5.096173) (xy 56.74023 -5.145743) (xy 56.710769 -5.191586)
			(xy 56.675084 -5.232771) (xy 56.633901 -5.268458) (xy 56.588058 -5.297921) (xy 56.53849 -5.32056)
			(xy 56.486204 -5.335915) (xy 56.432265 -5.343673) (xy 56.405018 -5.34416) (xy 55.541418 -5.34416)
			(xy 55.514161 -5.343794) (xy 55.460201 -5.336038) (xy 55.407894 -5.320682) (xy 55.358306 -5.298038)
			(xy 55.312445 -5.268566) (xy 55.271245 -5.232868) (xy 55.235544 -5.19167) (xy 55.206071 -5.14581)
			(xy 55.183424 -5.096222) (xy 55.168065 -5.043916) (xy 55.160307 -4.989957) (xy 53.186096 -4.989957)
			(xy 53.17834 -5.043897) (xy 53.162985 -5.09619) (xy 53.140343 -5.145765) (xy 53.110877 -5.191614)
			(xy 53.075185 -5.232802) (xy 53.033995 -5.268491) (xy 52.988144 -5.297955) (xy 52.938567 -5.320593)
			(xy 52.886273 -5.335945) (xy 52.832327 -5.343698) (xy 52.805076 -5.34416) (xy 51.941476 -5.34416)
			(xy 51.914222 -5.343768) (xy 51.860271 -5.336008) (xy 51.807972 -5.320649) (xy 51.758392 -5.298004)
			(xy 51.712538 -5.268533) (xy 51.671346 -5.232837) (xy 51.635653 -5.191642) (xy 51.606185 -5.145787)
			(xy 51.583543 -5.096205) (xy 51.568187 -5.043906) (xy 51.56043 -4.989954) (xy 45.575996 -4.989954)
			(xy 45.56824 -5.043896) (xy 45.552885 -5.096189) (xy 45.530244 -5.145764) (xy 45.500778 -5.191612)
			(xy 45.465087 -5.2328) (xy 45.423898 -5.268489) (xy 45.378048 -5.297953) (xy 45.328472 -5.320592)
			(xy 45.276178 -5.335944) (xy 45.222232 -5.343698) (xy 45.194982 -5.34416) (xy 44.331382 -5.34416)
			(xy 44.304128 -5.343769) (xy 44.250176 -5.336009) (xy 44.197876 -5.320651) (xy 44.148295 -5.298006)
			(xy 44.102441 -5.268535) (xy 44.061248 -5.232839) (xy 44.025554 -5.191644) (xy 43.996086 -5.145789)
			(xy 43.973443 -5.096207) (xy 43.958087 -5.043907) (xy 43.95033 -4.989954) (xy 41.975973 -4.989954)
			(xy 41.968219 -5.043883) (xy 41.952868 -5.096168) (xy 41.930233 -5.145737) (xy 41.900774 -5.191579)
			(xy 41.865091 -5.232763) (xy 41.823911 -5.26845) (xy 41.778072 -5.297914) (xy 41.728506 -5.320554)
			(xy 41.676222 -5.335911) (xy 41.622286 -5.343671) (xy 41.59504 -5.34416) (xy 40.73144 -5.34416) (xy 40.704182 -5.343796)
			(xy 40.65022 -5.336042) (xy 40.59791 -5.320688) (xy 40.548319 -5.298045) (xy 40.502455 -5.268574)
			(xy 40.461252 -5.232876) (xy 40.42555 -5.191677) (xy 40.396074 -5.145816) (xy 40.373426 -5.096227)
			(xy 40.358066 -5.043919) (xy 40.350307 -4.989958) (xy 32.866096 -4.989958) (xy 32.85834 -5.043897)
			(xy 32.842985 -5.09619) (xy 32.820343 -5.145765) (xy 32.790877 -5.191614) (xy 32.755185 -5.232802)
			(xy 32.713995 -5.268491) (xy 32.668144 -5.297955) (xy 32.618567 -5.320593) (xy 32.566273 -5.335945)
			(xy 32.512327 -5.343698) (xy 32.485076 -5.34416) (xy 31.621476 -5.34416) (xy 31.594222 -5.343768)
			(xy 31.540271 -5.336008) (xy 31.487972 -5.320649) (xy 31.438392 -5.298004) (xy 31.392538 -5.268533)
			(xy 31.351346 -5.232837) (xy 31.315653 -5.191642) (xy 31.286185 -5.145787) (xy 31.263543 -5.096205)
			(xy 31.248187 -5.043906) (xy 31.24043 -4.989954) (xy 29.265896 -4.989954) (xy 29.25814 -5.043896)
			(xy 29.242785 -5.096189) (xy 29.220144 -5.145764) (xy 29.190678 -5.191613) (xy 29.154986 -5.232801)
			(xy 29.113797 -5.26849) (xy 29.067947 -5.297954) (xy 29.01837 -5.320592) (xy 28.966077 -5.335944)
			(xy 28.91213 -5.343698) (xy 28.88488 -5.34416) (xy 28.02128 -5.34416) (xy 27.994026 -5.343769) (xy 27.940074 -5.336009)
			(xy 27.887775 -5.32065) (xy 27.838194 -5.298005) (xy 27.79234 -5.268534) (xy 27.751147 -5.232838)
			(xy 27.715454 -5.191644) (xy 27.685985 -5.145788) (xy 27.663343 -5.096206) (xy 27.647987 -5.043907)
			(xy 27.64023 -4.989954) (xy 25.66598 -4.989954) (xy 25.65823 -5.043854) (xy 25.642873 -5.096153)
			(xy 25.620231 -5.145733) (xy 25.590762 -5.191587) (xy 25.555068 -5.23278) (xy 25.513875 -5.268473)
			(xy 25.468021 -5.297942) (xy 25.418441 -5.320584) (xy 25.366143 -5.33594) (xy 25.312191 -5.343697)
			(xy 25.284938 -5.34416) (xy 24.421338 -5.34416) (xy 24.394087 -5.34367) (xy 24.34014 -5.335913) (xy 24.287846 -5.320558)
			(xy 24.238269 -5.297917) (xy 24.192419 -5.268451) (xy 24.151229 -5.232759) (xy 24.115538 -5.19157)
			(xy 24.086072 -5.145719) (xy 24.063431 -5.096143) (xy 24.048076 -5.043848) (xy 24.04032 -4.989901)
			(xy 22.066047 -4.989901) (xy 22.066047 -4.989903) (xy 22.05829 -5.043855) (xy 22.042933 -5.096153)
			(xy 22.02029 -5.145734) (xy 21.990822 -5.191587) (xy 21.955128 -5.23278) (xy 21.913934 -5.268474)
			(xy 21.86808 -5.297942) (xy 21.818499 -5.320585) (xy 21.766201 -5.33594) (xy 21.712249 -5.343697)
			(xy 21.684996 -5.34416) (xy 20.821396 -5.34416) (xy 20.794145 -5.34367) (xy 20.740198 -5.335913)
			(xy 20.687904 -5.320558) (xy 20.638328 -5.297916) (xy 20.592478 -5.26845) (xy 20.551288 -5.232759)
			(xy 20.515597 -5.191569) (xy 20.486132 -5.145719) (xy 20.463491 -5.096142) (xy 20.448136 -5.043848)
			(xy 20.44038 -4.989901) (xy 16.267136 -4.989901) (xy 16.278962 -5.06831) (xy 16.284155 -5.154889)
			(xy 16.281564 -5.241584) (xy 16.27121 -5.327698) (xy 16.253177 -5.412537) (xy 16.22761 -5.495418)
			(xy 16.194714 -5.575672) (xy 16.154755 -5.652653) (xy 16.108054 -5.725741) (xy 16.054988 -5.794348)
			(xy 15.995985 -5.85792) (xy 15.931519 -5.915946) (xy 15.897098 -5.94233) (xy 15.862132 -5.968006)
			(xy 15.788377 -6.013689) (xy 15.710822 -6.052572) (xy 15.630093 -6.084344) (xy 15.546839 -6.108746)
			(xy 15.461732 -6.125584) (xy 15.375458 -6.13472) (xy 15.288712 -6.136082) (xy 15.202194 -6.129659)
			(xy 15.116601 -6.115502) (xy 15.032622 -6.093724) (xy 14.950935 -6.064503) (xy 14.872197 -6.028073)
			(xy 14.797045 -5.984729) (xy 14.726083 -5.934818) (xy 14.659883 -5.878744) (xy 14.598979 -5.816959)
			(xy 14.543862 -5.749961) (xy 14.494977 -5.678289) (xy 14.452716 -5.602521) (xy 14.417421 -5.523269)
			(xy 14.389376 -5.44117) (xy 14.368808 -5.356887) (xy 14.355882 -5.271099) (xy 14.350702 -5.184498)
			(xy 13.611098 -5.184498) (xy 13.611098 -6.169914) (xy 78.515217 -6.169914) (xy 78.519222 -6.082006)
			(xy 78.531205 -5.994826) (xy 78.551065 -5.909097) (xy 78.57864 -5.825529) (xy 78.613699 -5.744815)
			(xy 78.655952 -5.667623) (xy 78.70505 -5.594594) (xy 78.760586 -5.526332) (xy 78.822098 -5.463402)
			(xy 78.889079 -5.406328) (xy 78.960972 -5.35558) (xy 79.037181 -5.31158) (xy 79.117076 -5.274693)
			(xy 79.199995 -5.245224) (xy 79.28525 -5.223417) (xy 79.372134 -5.209453) (xy 79.459928 -5.203447)
			(xy 79.547905 -5.205451) (xy 79.635335 -5.215446) (xy 79.721494 -5.23335) (xy 79.805668 -5.259014)
			(xy 79.887159 -5.292227) (xy 79.965293 -5.332713) (xy 80.039421 -5.380135) (xy 80.108929 -5.434102)
			(xy 80.173243 -5.494167) (xy 80.231827 -5.559831) (xy 80.284198 -5.63055) (xy 80.329921 -5.705738)
			(xy 80.368618 -5.784773) (xy 80.399967 -5.866999) (xy 80.423709 -5.951735) (xy 80.439647 -6.038279)
			(xy 80.447649 -6.125914) (xy 80.44815 -6.169914) (xy 80.447649 -6.213914) (xy 80.439647 -6.301549)
			(xy 80.423709 -6.388093) (xy 80.399967 -6.472829) (xy 80.368618 -6.555055) (xy 80.329921 -6.63409)
			(xy 80.284198 -6.709278) (xy 80.231827 -6.779997) (xy 80.173243 -6.845661) (xy 80.108929 -6.905726)
			(xy 80.039421 -6.959693) (xy 79.965293 -7.007115) (xy 79.887159 -7.047601) (xy 79.805668 -7.080814)
			(xy 79.721494 -7.106478) (xy 79.635335 -7.124382) (xy 79.547905 -7.134377) (xy 79.459928 -7.136381)
			(xy 79.372134 -7.130375) (xy 79.28525 -7.116411) (xy 79.199995 -7.094604) (xy 79.117076 -7.065135)
			(xy 79.037181 -7.028248) (xy 78.960972 -6.984248) (xy 78.889079 -6.9335) (xy 78.822098 -6.876426)
			(xy 78.760586 -6.813496) (xy 78.70505 -6.745234) (xy 78.655952 -6.672205) (xy 78.613699 -6.595013)
			(xy 78.57864 -6.514299) (xy 78.551065 -6.430731) (xy 78.531205 -6.345002) (xy 78.519222 -6.257822)
			(xy 78.515217 -6.169914) (xy 13.611098 -6.169914) (xy 13.611098 -6.751654) (xy 18.635651 -6.751654)
			(xy 18.635651 -6.697146) (xy 18.643409 -6.643192) (xy 18.658767 -6.590891) (xy 18.681411 -6.541309)
			(xy 18.710882 -6.495454) (xy 18.746579 -6.45426) (xy 18.787775 -6.418566) (xy 18.833632 -6.389099)
			(xy 18.883216 -6.366458) (xy 18.935517 -6.351104) (xy 18.989472 -6.34335) (xy 19.016726 -6.342888)
			(xy 19.880326 -6.342888) (xy 19.907576 -6.343384) (xy 19.96152 -6.351143) (xy 20.013811 -6.3665)
			(xy 20.063385 -6.389143) (xy 20.109231 -6.418609) (xy 20.150418 -6.4543) (xy 20.186106 -6.49549)
			(xy 20.21557 -6.541338) (xy 20.238209 -6.590913) (xy 20.253563 -6.643205) (xy 20.261318 -6.69715)
			(xy 20.261318 -6.75165) (xy 22.235674 -6.75165) (xy 22.235674 -6.69715) (xy 22.243429 -6.643204)
			(xy 22.258783 -6.590912) (xy 22.281422 -6.541336) (xy 22.310886 -6.495487) (xy 22.346574 -6.454297)
			(xy 22.387761 -6.418605) (xy 22.433608 -6.389138) (xy 22.483182 -6.366494) (xy 22.535473 -6.351136)
			(xy 22.589418 -6.343376) (xy 22.616668 -6.342888) (xy 23.480268 -6.342888) (xy 23.507522 -6.343357)
			(xy 23.561476 -6.35111) (xy 23.613777 -6.366463) (xy 23.663361 -6.389104) (xy 23.709217 -6.418571)
			(xy 23.750413 -6.454264) (xy 23.78611 -6.495457) (xy 23.815581 -6.541311) (xy 23.838225 -6.590893)
			(xy 23.853583 -6.643193) (xy 23.861341 -6.697146) (xy 23.861341 -6.751654) (xy 25.835551 -6.751654)
			(xy 25.835551 -6.697146) (xy 25.843309 -6.643194) (xy 25.858665 -6.590895) (xy 25.881309 -6.541314)
			(xy 25.910778 -6.495459) (xy 25.946473 -6.454266) (xy 25.987667 -6.418572) (xy 26.033522 -6.389104)
			(xy 26.083104 -6.366462) (xy 26.135404 -6.351107) (xy 26.189356 -6.343351) (xy 26.21661 -6.342888)
			(xy 27.08021 -6.342888) (xy 27.10746 -6.343382) (xy 27.161407 -6.35114) (xy 27.2137 -6.366496) (xy 27.263275 -6.389137)
			(xy 27.309124 -6.418604) (xy 27.350312 -6.454295) (xy 27.386002 -6.495484) (xy 27.415467 -6.541334)
			(xy 27.438108 -6.59091) (xy 27.453462 -6.643203) (xy 27.461218 -6.697149) (xy 27.461218 -6.751651)
			(xy 27.461218 -6.751653) (xy 29.435751 -6.751653) (xy 29.435751 -6.697147) (xy 29.443509 -6.643195)
			(xy 29.458865 -6.590896) (xy 29.481508 -6.541315) (xy 29.510977 -6.495461) (xy 29.546672 -6.454268)
			(xy 29.587866 -6.418574) (xy 29.63372 -6.389105) (xy 29.683301 -6.366463) (xy 29.7356 -6.351107)
			(xy 29.789553 -6.343351) (xy 29.816806 -6.342888) (xy 30.680406 -6.342888) (xy 30.707657 -6.343382)
			(xy 30.761603 -6.351139) (xy 30.813897 -6.366495) (xy 30.863473 -6.389136) (xy 30.909322 -6.418602)
			(xy 30.950511 -6.454293) (xy 30.986201 -6.495483) (xy 31.015667 -6.541333) (xy 31.038307 -6.590909)
			(xy 31.053662 -6.643203) (xy 31.061418 -6.697149) (xy 31.061418 -6.75165) (xy 38.545774 -6.75165)
			(xy 38.545774 -6.69715) (xy 38.55353 -6.643204) (xy 38.568883 -6.590911) (xy 38.591522 -6.541336)
			(xy 38.620986 -6.495486) (xy 38.656675 -6.454296) (xy 38.697862 -6.418604) (xy 38.743709 -6.389137)
			(xy 38.793283 -6.366494) (xy 38.845575 -6.351136) (xy 38.89952 -6.343376) (xy 38.92677 -6.342888)
			(xy 39.79037 -6.342888) (xy 39.817624 -6.343357) (xy 39.871578 -6.351111) (xy 39.923878 -6.366464)
			(xy 39.973462 -6.389105) (xy 40.019318 -6.418571) (xy 40.060514 -6.454265) (xy 40.096211 -6.495458)
			(xy 40.125681 -6.541312) (xy 40.148326 -6.590893) (xy 40.163683 -6.643193) (xy 40.171441 -6.697146)
			(xy 40.171441 -6.751654) (xy 42.145651 -6.751654) (xy 42.145651 -6.697146) (xy 42.153409 -6.643194)
			(xy 42.168766 -6.590894) (xy 42.191409 -6.541313) (xy 42.220879 -6.495459) (xy 42.256574 -6.454265)
			(xy 42.297768 -6.418571) (xy 42.343624 -6.389103) (xy 42.393206 -6.366461) (xy 42.445506 -6.351106)
			(xy 42.499458 -6.343351) (xy 42.526712 -6.342888) (xy 43.390312 -6.342888) (xy 43.417562 -6.343383)
			(xy 43.471508 -6.35114) (xy 43.523801 -6.366496) (xy 43.573376 -6.389138) (xy 43.619225 -6.418604)
			(xy 43.660413 -6.454295) (xy 43.696103 -6.495485) (xy 43.725568 -6.541334) (xy 43.748208 -6.59091)
			(xy 43.763562 -6.643203) (xy 43.771318 -6.69715) (xy 43.771318 -6.75165) (xy 43.771318 -6.751653)
			(xy 49.755751 -6.751653) (xy 49.755751 -6.697147) (xy 49.763509 -6.643195) (xy 49.778865 -6.590896)
			(xy 49.801508 -6.541315) (xy 49.830977 -6.495461) (xy 49.866672 -6.454268) (xy 49.907866 -6.418574)
			(xy 49.95372 -6.389105) (xy 50.003301 -6.366463) (xy 50.0556 -6.351107) (xy 50.109553 -6.343351)
			(xy 50.136806 -6.342888) (xy 51.000406 -6.342888) (xy 51.027657 -6.343382) (xy 51.081603 -6.351139)
			(xy 51.133897 -6.366495) (xy 51.183473 -6.389136) (xy 51.229322 -6.418602) (xy 51.270511 -6.454293)
			(xy 51.306201 -6.495483) (xy 51.335667 -6.541333) (xy 51.358307 -6.590909) (xy 51.373662 -6.643203)
			(xy 51.381418 -6.697149) (xy 51.381418 -6.751651) (xy 51.381417 -6.751655) (xy 53.355652 -6.751655)
			(xy 53.355652 -6.697145) (xy 53.36341 -6.643189) (xy 53.378768 -6.590887) (xy 53.401415 -6.541303)
			(xy 53.430887 -6.495447) (xy 53.466587 -6.454253) (xy 53.507785 -6.418559) (xy 53.553645 -6.389092)
			(xy 53.603232 -6.366452) (xy 53.655536 -6.3511) (xy 53.709493 -6.343348) (xy 53.736748 -6.342888)
			(xy 54.600348 -6.342888) (xy 54.627597 -6.343385) (xy 54.681539 -6.351147) (xy 54.733827 -6.366506)
			(xy 54.783398 -6.38915) (xy 54.829242 -6.418617) (xy 54.870426 -6.454308) (xy 54.906112 -6.495497)
			(xy 54.935573 -6.541344) (xy 54.958211 -6.590918) (xy 54.973563 -6.643208) (xy 54.981318 -6.697151)
			(xy 54.981318 -6.751649) (xy 54.981318 -6.751651) (xy 56.955674 -6.751651) (xy 56.955674 -6.697149)
			(xy 56.96343 -6.643201) (xy 56.978785 -6.590907) (xy 57.001426 -6.54133) (xy 57.030891 -6.49548)
			(xy 57.066582 -6.454289) (xy 57.107771 -6.418597) (xy 57.153621 -6.38913) (xy 57.203198 -6.366488)
			(xy 57.255492 -6.351132) (xy 57.309439 -6.343374) (xy 57.33669 -6.342888) (xy 58.20029 -6.342888)
			(xy 58.227543 -6.343359) (xy 58.281494 -6.351114) (xy 58.333793 -6.366469) (xy 58.383374 -6.389111)
			(xy 58.429228 -6.418578) (xy 58.470421 -6.454272) (xy 58.506116 -6.495464) (xy 58.535584 -6.541317)
			(xy 58.558227 -6.590898) (xy 58.573583 -6.643196) (xy 58.581341 -6.697147) (xy 58.581341 -6.751651)
			(xy 70.950574 -6.751651) (xy 70.950574 -6.697149) (xy 70.95833 -6.643203) (xy 70.973684 -6.590909)
			(xy 70.996324 -6.541332) (xy 71.025789 -6.495482) (xy 71.061479 -6.454292) (xy 71.102668 -6.4186)
			(xy 71.148516 -6.389133) (xy 71.198092 -6.366491) (xy 71.250385 -6.351134) (xy 71.304331 -6.343375)
			(xy 71.331582 -6.342888) (xy 72.195182 -6.342888) (xy 72.222435 -6.343358) (xy 72.276388 -6.351113)
			(xy 72.328687 -6.366467) (xy 72.378269 -6.389108) (xy 72.424124 -6.418576) (xy 72.465318 -6.454269)
			(xy 72.501014 -6.495462) (xy 72.530483 -6.541315) (xy 72.553126 -6.590896) (xy 72.568483 -6.643195)
			(xy 72.576241 -6.697147) (xy 72.576241 -6.751653) (xy 72.568483 -6.805605) (xy 72.553126 -6.857904)
			(xy 72.530483 -6.907485) (xy 72.501014 -6.953338) (xy 72.465318 -6.994531) (xy 72.424124 -7.030224)
			(xy 72.378269 -7.059692) (xy 72.328687 -7.082333) (xy 72.276388 -7.097687) (xy 72.222435 -7.105442)
			(xy 72.195182 -7.105904) (xy 71.331582 -7.105904) (xy 71.304331 -7.105425) (xy 71.250385 -7.097666)
			(xy 71.198092 -7.082309) (xy 71.148516 -7.059667) (xy 71.102668 -7.0302) (xy 71.061479 -6.994508)
			(xy 71.025789 -6.953318) (xy 70.996324 -6.907468) (xy 70.973684 -6.857891) (xy 70.95833 -6.805597)
			(xy 70.950574 -6.751651) (xy 58.581341 -6.751651) (xy 58.581341 -6.751653) (xy 58.573583 -6.805604)
			(xy 58.558227 -6.857902) (xy 58.535584 -6.907483) (xy 58.506116 -6.953336) (xy 58.470421 -6.994528)
			(xy 58.429228 -7.030222) (xy 58.383374 -7.059689) (xy 58.333793 -7.082331) (xy 58.281494 -7.097686)
			(xy 58.227543 -7.105441) (xy 58.20029 -7.105904) (xy 57.33669 -7.105904) (xy 57.309439 -7.105426)
			(xy 57.255492 -7.097668) (xy 57.203198 -7.082312) (xy 57.153621 -7.05967) (xy 57.107771 -7.030203)
			(xy 57.066582 -6.994511) (xy 57.030891 -6.95332) (xy 57.001426 -6.90747) (xy 56.978785 -6.857893)
			(xy 56.96343 -6.805599) (xy 56.955674 -6.751651) (xy 54.981318 -6.751651) (xy 54.973563 -6.805592)
			(xy 54.958211 -6.857882) (xy 54.935573 -6.907456) (xy 54.906112 -6.953303) (xy 54.870426 -6.994492)
			(xy 54.829242 -7.030183) (xy 54.783398 -7.05965) (xy 54.733827 -7.082294) (xy 54.681539 -7.097653)
			(xy 54.627597 -7.105415) (xy 54.600348 -7.105904) (xy 53.736748 -7.105904) (xy 53.709493 -7.105452)
			(xy 53.655536 -7.0977) (xy 53.603232 -7.082348) (xy 53.553645 -7.059708) (xy 53.507785 -7.030241)
			(xy 53.466587 -6.994547) (xy 53.430887 -6.953353) (xy 53.401415 -6.907497) (xy 53.378768 -6.857913)
			(xy 53.36341 -6.805611) (xy 53.355652 -6.751655) (xy 51.381417 -6.751655) (xy 51.373662 -6.805597)
			(xy 51.358307 -6.857891) (xy 51.335667 -6.907467) (xy 51.306201 -6.953317) (xy 51.270511 -6.994507)
			(xy 51.229322 -7.030198) (xy 51.183473 -7.059664) (xy 51.133897 -7.082305) (xy 51.081603 -7.097661)
			(xy 51.027657 -7.105418) (xy 51.000406 -7.105904) (xy 50.136806 -7.105904) (xy 50.109553 -7.105449)
			(xy 50.0556 -7.097693) (xy 50.003301 -7.082337) (xy 49.95372 -7.059695) (xy 49.907866 -7.030226)
			(xy 49.866672 -6.994532) (xy 49.830977 -6.953339) (xy 49.801508 -6.907485) (xy 49.778865 -6.857904)
			(xy 49.763509 -6.805605) (xy 49.755751 -6.751653) (xy 43.771318 -6.751653) (xy 43.763562 -6.805597)
			(xy 43.748208 -6.85789) (xy 43.725568 -6.907466) (xy 43.696103 -6.953315) (xy 43.660413 -6.994505)
			(xy 43.619225 -7.030196) (xy 43.573376 -7.059662) (xy 43.523801 -7.082304) (xy 43.471508 -7.09766)
			(xy 43.417562 -7.105417) (xy 43.390312 -7.105904) (xy 42.526712 -7.105904) (xy 42.499458 -7.105449)
			(xy 42.445506 -7.097694) (xy 42.393206 -7.082339) (xy 42.343624 -7.059697) (xy 42.297768 -7.030229)
			(xy 42.256574 -6.994535) (xy 42.220879 -6.953341) (xy 42.191409 -6.907487) (xy 42.168766 -6.857906)
			(xy 42.153409 -6.805606) (xy 42.145651 -6.751654) (xy 40.171441 -6.751654) (xy 40.163683 -6.805607)
			(xy 40.148326 -6.857907) (xy 40.125681 -6.907488) (xy 40.096211 -6.953342) (xy 40.060514 -6.994535)
			(xy 40.019318 -7.030229) (xy 39.973462 -7.059695) (xy 39.923878 -7.082336) (xy 39.871578 -7.097689)
			(xy 39.817624 -7.105443) (xy 39.79037 -7.105904) (xy 38.92677 -7.105904) (xy 38.89952 -7.105424)
			(xy 38.845575 -7.097664) (xy 38.793283 -7.082306) (xy 38.743709 -7.059663) (xy 38.697862 -7.030196)
			(xy 38.656675 -6.994504) (xy 38.620986 -6.953314) (xy 38.591522 -6.907464) (xy 38.568883 -6.857889)
			(xy 38.55353 -6.805596) (xy 38.545774 -6.75165) (xy 31.061418 -6.75165) (xy 31.061418 -6.751651)
			(xy 31.053662 -6.805597) (xy 31.038307 -6.857891) (xy 31.015667 -6.907467) (xy 30.986201 -6.953317)
			(xy 30.950511 -6.994507) (xy 30.909322 -7.030198) (xy 30.863473 -7.059664) (xy 30.813897 -7.082305)
			(xy 30.761603 -7.097661) (xy 30.707657 -7.105418) (xy 30.680406 -7.105904) (xy 29.816806 -7.105904)
			(xy 29.789553 -7.105449) (xy 29.7356 -7.097693) (xy 29.683301 -7.082337) (xy 29.63372 -7.059695)
			(xy 29.587866 -7.030226) (xy 29.546672 -6.994532) (xy 29.510977 -6.953339) (xy 29.481508 -6.907485)
			(xy 29.458865 -6.857904) (xy 29.443509 -6.805605) (xy 29.435751 -6.751653) (xy 27.461218 -6.751653)
			(xy 27.453462 -6.805597) (xy 27.438108 -6.85789) (xy 27.415467 -6.907466) (xy 27.386002 -6.953316)
			(xy 27.350312 -6.994505) (xy 27.309124 -7.030196) (xy 27.263275 -7.059663) (xy 27.2137 -7.082304)
			(xy 27.161407 -7.09766) (xy 27.10746 -7.105418) (xy 27.08021 -7.105904) (xy 26.21661 -7.105904) (xy 26.189356 -7.105449)
			(xy 26.135404 -7.097693) (xy 26.083104 -7.082338) (xy 26.033522 -7.059696) (xy 25.987667 -7.030228)
			(xy 25.946473 -6.994534) (xy 25.910778 -6.953341) (xy 25.881309 -6.907486) (xy 25.858665 -6.857905)
			(xy 25.843309 -6.805606) (xy 25.835551 -6.751654) (xy 23.861341 -6.751654) (xy 23.853583 -6.805607)
			(xy 23.838225 -6.857907) (xy 23.815581 -6.907489) (xy 23.78611 -6.953343) (xy 23.750413 -6.994536)
			(xy 23.709217 -7.030229) (xy 23.663361 -7.059696) (xy 23.613777 -7.082337) (xy 23.561476 -7.09769)
			(xy 23.507522 -7.105443) (xy 23.480268 -7.105904) (xy 22.616668 -7.105904) (xy 22.589418 -7.105424)
			(xy 22.535473 -7.097664) (xy 22.483182 -7.082306) (xy 22.433608 -7.059662) (xy 22.387761 -7.030195)
			(xy 22.346574 -6.994503) (xy 22.310886 -6.953313) (xy 22.281422 -6.907464) (xy 22.258783 -6.857888)
			(xy 22.243429 -6.805596) (xy 22.235674 -6.75165) (xy 20.261318 -6.75165) (xy 20.253563 -6.805595)
			(xy 20.238209 -6.857887) (xy 20.21557 -6.907462) (xy 20.186106 -6.95331) (xy 20.150418 -6.9945) (xy 20.109231 -7.030191)
			(xy 20.063385 -7.059657) (xy 20.013811 -7.0823) (xy 19.96152 -7.097657) (xy 19.907576 -7.105416)
			(xy 19.880326 -7.105904) (xy 19.016726 -7.105904) (xy 18.989472 -7.10545) (xy 18.935517 -7.097696)
			(xy 18.883216 -7.082342) (xy 18.833632 -7.059701) (xy 18.787775 -7.030234) (xy 18.746579 -6.99454)
			(xy 18.710882 -6.953346) (xy 18.681411 -6.907491) (xy 18.658767 -6.857909) (xy 18.643409 -6.805608)
			(xy 18.635651 -6.751654) (xy 13.611098 -6.751654) (xy 13.611098 -9.780016) (xy 13.610604 -9.850398)
			(xy 13.602711 -9.990941) (xy 13.58695 -10.13082) (xy 13.563371 -10.269596) (xy 13.532048 -10.406831)
			(xy 13.493079 -10.542094) (xy 13.446587 -10.674959) (xy 13.392719 -10.805008) (xy 13.331643 -10.931832)
			(xy 13.263553 -11.055033) (xy 13.188662 -11.174221) (xy 13.107205 -11.289023) (xy 13.01944 -11.399077)
			(xy 12.925642 -11.504037) (xy 12.826107 -11.603572) (xy 12.721147 -11.69737) (xy 12.611093 -11.785135)
			(xy 12.496291 -11.866592) (xy 12.377103 -11.941483) (xy 12.253902 -12.009573) (xy 12.127078 -12.070649)
			(xy 11.997029 -12.124517) (xy 11.864164 -12.171009) (xy 11.728901 -12.209978) (xy 11.591666 -12.241301)
			(xy 11.45289 -12.26488) (xy 11.313011 -12.280641) (xy 11.172468 -12.288534) (xy 11.102086 -12.289028)
			(xy 1.999996 -12.289028) (xy 1.944227 -12.289537) (xy 1.833 -12.297872) (xy 1.722707 -12.314497)
			(xy 1.613965 -12.339317) (xy 1.507382 -12.372193) (xy 1.403554 -12.412943) (xy 1.303061 -12.461339)
			(xy 1.206466 -12.517108) (xy 1.114309 -12.579941) (xy 1.027105 -12.649484) (xy 0.945341 -12.72535)
			(xy 0.869476 -12.807114) (xy 0.802299 -12.891351) (xy 56.954662 -12.891351) (xy 56.954662 -12.836849)
			(xy 56.962418 -12.782901) (xy 56.977772 -12.730606) (xy 57.000413 -12.681029) (xy 57.029878 -12.635178)
			(xy 57.065568 -12.593986) (xy 57.106757 -12.558293) (xy 57.152606 -12.528825) (xy 57.202182 -12.506181)
			(xy 57.254476 -12.490823) (xy 57.308423 -12.483064) (xy 57.335674 -12.482576) (xy 58.199274 -12.482576)
			(xy 58.226527 -12.48307) (xy 58.280478 -12.490823) (xy 58.332777 -12.506176) (xy 58.382358 -12.528816)
			(xy 58.428213 -12.558282) (xy 58.469407 -12.593975) (xy 58.505102 -12.635166) (xy 58.534571 -12.681019)
			(xy 58.557215 -12.730598) (xy 58.572571 -12.782896) (xy 58.580329 -12.836847) (xy 58.580329 -12.891353)
			(xy 58.580329 -12.891355) (xy 70.949739 -12.891355) (xy 70.949739 -12.836845) (xy 70.957497 -12.78289)
			(xy 70.972854 -12.730588) (xy 70.995499 -12.681005) (xy 71.024971 -12.635149) (xy 71.060668 -12.593954)
			(xy 71.101865 -12.558259) (xy 71.147722 -12.52879) (xy 71.197307 -12.506147) (xy 71.24961 -12.490793)
			(xy 71.303565 -12.483038) (xy 71.33082 -12.482576) (xy 72.19442 -12.482576) (xy 72.221669 -12.483096)
			(xy 72.275612 -12.490854) (xy 72.327902 -12.50621) (xy 72.377475 -12.528852) (xy 72.423321 -12.558317)
			(xy 72.464507 -12.594007) (xy 72.500195 -12.635195) (xy 72.529658 -12.681043) (xy 72.552297 -12.730616)
			(xy 72.56765 -12.782907) (xy 72.575406 -12.836851) (xy 72.575406 -12.891349) (xy 72.56765 -12.945293)
			(xy 72.552297 -12.997584) (xy 72.529658 -13.047157) (xy 72.500195 -13.093005) (xy 72.464507 -13.134193)
			(xy 72.423321 -13.169883) (xy 72.377475 -13.199348) (xy 72.327902 -13.22199) (xy 72.275612 -13.237346)
			(xy 72.221669 -13.245104) (xy 72.19442 -13.245592) (xy 71.33082 -13.245592) (xy 71.303565 -13.245162)
			(xy 71.24961 -13.237407) (xy 71.197307 -13.222053) (xy 71.147722 -13.19941) (xy 71.101865 -13.169941)
			(xy 71.060668 -13.134246) (xy 71.024971 -13.093051) (xy 70.995499 -13.047195) (xy 70.972854 -12.997612)
			(xy 70.957497 -12.94531) (xy 70.949739 -12.891355) (xy 58.580329 -12.891355) (xy 58.572571 -12.945304)
			(xy 58.557215 -12.997602) (xy 58.534571 -13.047181) (xy 58.505102 -13.093034) (xy 58.469407 -13.134225)
			(xy 58.428213 -13.169918) (xy 58.382358 -13.199384) (xy 58.332777 -13.222024) (xy 58.280478 -13.237377)
			(xy 58.226527 -13.24513) (xy 58.199274 -13.245592) (xy 57.335674 -13.245592) (xy 57.308423 -13.245136)
			(xy 57.254476 -13.237377) (xy 57.202182 -13.222019) (xy 57.152606 -13.199375) (xy 57.106757 -13.169907)
			(xy 57.065568 -13.134214) (xy 57.029878 -13.093022) (xy 57.000413 -13.047171) (xy 56.977772 -12.997594)
			(xy 56.962418 -12.945299) (xy 56.954662 -12.891351) (xy 0.802299 -12.891351) (xy 0.799933 -12.894318)
			(xy 0.737102 -12.986476) (xy 0.681333 -13.083072) (xy 0.632939 -13.183565) (xy 0.59219 -13.287393)
			(xy 0.559313 -13.393977) (xy 0.534494 -13.502719) (xy 0.517871 -13.613012) (xy 0.509536 -13.724239)
			(xy 0.509016 -13.780008) (xy 0.509016 -15.222054) (xy 135.233343 -15.222054) (xy 135.233343 -15.167546)
			(xy 135.2411 -15.113592) (xy 135.256457 -15.061292) (xy 135.279101 -15.011709) (xy 135.308571 -14.965854)
			(xy 135.344267 -14.92466) (xy 135.385462 -14.888965) (xy 135.431318 -14.859497) (xy 135.480901 -14.836854)
			(xy 135.533202 -14.821498) (xy 135.587156 -14.813742) (xy 135.61441 -14.81328) (xy 136.47801 -14.81328)
			(xy 136.50526 -14.813791) (xy 136.559205 -14.821548) (xy 136.611497 -14.836904) (xy 136.661071 -14.859545)
			(xy 136.706919 -14.88901) (xy 136.748106 -14.924701) (xy 136.783796 -14.965889) (xy 136.81326 -15.011738)
			(xy 136.8359 -15.061313) (xy 136.851254 -15.113605) (xy 136.85901 -15.16755) (xy 136.85901 -15.22205)
			(xy 136.851254 -15.275995) (xy 136.8359 -15.328287) (xy 136.81326 -15.377862) (xy 136.783796 -15.423711)
			(xy 136.748106 -15.464899) (xy 136.706919 -15.50059) (xy 136.661071 -15.530055) (xy 136.611497 -15.552696)
			(xy 136.559205 -15.568052) (xy 136.50526 -15.575809) (xy 136.47801 -15.576296) (xy 135.61441 -15.576296)
			(xy 135.587156 -15.575858) (xy 135.533202 -15.568102) (xy 135.480901 -15.552746) (xy 135.431318 -15.530103)
			(xy 135.385462 -15.500635) (xy 135.344267 -15.46494) (xy 135.308571 -15.423746) (xy 135.279101 -15.377891)
			(xy 135.256457 -15.328308) (xy 135.2411 -15.276008) (xy 135.233343 -15.222054) (xy 0.509016 -15.222054)
			(xy 0.509016 -17.639611) (xy 15.152858 -17.639611) (xy 15.152858 -17.585109) (xy 15.160614 -17.531161)
			(xy 15.175969 -17.478867) (xy 15.19861 -17.42929) (xy 15.228076 -17.383439) (xy 15.263768 -17.342249)
			(xy 15.304958 -17.306558) (xy 15.350808 -17.277091) (xy 15.400385 -17.25445) (xy 15.452679 -17.239095)
			(xy 15.506627 -17.231338) (xy 15.533878 -17.230852) (xy 16.397478 -17.230852) (xy 16.424731 -17.231315)
			(xy 16.478682 -17.239072) (xy 16.53098 -17.254428) (xy 16.580561 -17.27707) (xy 16.626414 -17.306538)
			(xy 16.667607 -17.342232) (xy 16.703301 -17.383424) (xy 16.732769 -17.429278) (xy 16.755412 -17.478858)
			(xy 16.770768 -17.531156) (xy 16.778525 -17.585107) (xy 16.778525 -17.639611) (xy 20.740858 -17.639611)
			(xy 20.740858 -17.585109) (xy 20.748614 -17.531161) (xy 20.763969 -17.478867) (xy 20.78661 -17.42929)
			(xy 20.816076 -17.383439) (xy 20.851768 -17.342249) (xy 20.892958 -17.306558) (xy 20.938808 -17.277091)
			(xy 20.988385 -17.25445) (xy 21.040679 -17.239095) (xy 21.094627 -17.231338) (xy 21.121878 -17.230852)
			(xy 21.985478 -17.230852) (xy 22.012729 -17.231394) (xy 22.066677 -17.239147) (xy 22.118972 -17.2545)
			(xy 22.168549 -17.277139) (xy 22.2144 -17.306603) (xy 22.255591 -17.342293) (xy 22.291284 -17.383482)
			(xy 22.320751 -17.429331) (xy 22.343392 -17.478908) (xy 22.358748 -17.531202) (xy 22.366505 -17.585149)
			(xy 22.366505 -17.639651) (xy 22.366505 -17.639653) (xy 26.328838 -17.639653) (xy 26.328838 -17.585147)
			(xy 26.336595 -17.531195) (xy 26.35195 -17.478897) (xy 26.374592 -17.429316) (xy 26.404059 -17.383462)
			(xy 26.439752 -17.342268) (xy 26.480944 -17.306573) (xy 26.526797 -17.277103) (xy 26.576376 -17.254458)
			(xy 26.628674 -17.239099) (xy 26.682625 -17.231339) (xy 26.709878 -17.230852) (xy 27.573478 -17.230852)
			(xy 27.600729 -17.231394) (xy 27.654677 -17.239147) (xy 27.706972 -17.2545) (xy 27.756549 -17.277139)
			(xy 27.8024 -17.306603) (xy 27.843591 -17.342293) (xy 27.879284 -17.383482) (xy 27.908751 -17.429331)
			(xy 27.931392 -17.478908) (xy 27.946748 -17.531202) (xy 27.954505 -17.585149) (xy 27.954505 -17.639651)
			(xy 27.954505 -17.639653) (xy 31.916838 -17.639653) (xy 31.916838 -17.585147) (xy 31.924595 -17.531195)
			(xy 31.93995 -17.478897) (xy 31.962592 -17.429316) (xy 31.992059 -17.383462) (xy 32.027752 -17.342268)
			(xy 32.068944 -17.306573) (xy 32.114797 -17.277103) (xy 32.164376 -17.254458) (xy 32.216674 -17.239099)
			(xy 32.270625 -17.231339) (xy 32.297878 -17.230852) (xy 33.161478 -17.230852) (xy 33.188729 -17.231394)
			(xy 33.242677 -17.239147) (xy 33.294972 -17.2545) (xy 33.344549 -17.277139) (xy 33.3904 -17.306603)
			(xy 33.431591 -17.342293) (xy 33.467284 -17.383482) (xy 33.496751 -17.429331) (xy 33.519392 -17.478908)
			(xy 33.534748 -17.531202) (xy 33.542505 -17.585149) (xy 33.542505 -17.639651) (xy 33.542505 -17.639653)
			(xy 37.504838 -17.639653) (xy 37.504838 -17.585147) (xy 37.512595 -17.531195) (xy 37.52795 -17.478897)
			(xy 37.550592 -17.429316) (xy 37.580059 -17.383462) (xy 37.615752 -17.342268) (xy 37.656944 -17.306573)
			(xy 37.702797 -17.277103) (xy 37.752376 -17.254458) (xy 37.804674 -17.239099) (xy 37.858625 -17.231339)
			(xy 37.885878 -17.230852) (xy 38.749478 -17.230852) (xy 38.776729 -17.231394) (xy 38.830677 -17.239147)
			(xy 38.882972 -17.2545) (xy 38.932549 -17.277139) (xy 38.9784 -17.306603) (xy 39.019591 -17.342293)
			(xy 39.055284 -17.383482) (xy 39.084751 -17.429331) (xy 39.107392 -17.478908) (xy 39.122748 -17.531202)
			(xy 39.130505 -17.585149) (xy 39.130505 -17.639651) (xy 39.130505 -17.639654) (xy 43.398638 -17.639654)
			(xy 43.398638 -17.585146) (xy 43.406395 -17.531193) (xy 43.421751 -17.478894) (xy 43.444395 -17.429312)
			(xy 43.473863 -17.383457) (xy 43.509558 -17.342262) (xy 43.550752 -17.306567) (xy 43.596606 -17.277097)
			(xy 43.646188 -17.254454) (xy 43.698487 -17.239096) (xy 43.75244 -17.231338) (xy 43.779694 -17.230852)
			(xy 44.643294 -17.230852) (xy 44.670544 -17.231395) (xy 44.72449 -17.23915) (xy 44.776783 -17.254504)
			(xy 44.826359 -17.277144) (xy 44.872208 -17.306609) (xy 44.913397 -17.342299) (xy 44.949088 -17.383487)
			(xy 44.978553 -17.429336) (xy 45.001194 -17.478911) (xy 45.016548 -17.531204) (xy 45.024305 -17.58515)
			(xy 45.024305 -17.63965) (xy 45.024304 -17.639654) (xy 48.986638 -17.639654) (xy 48.986638 -17.585146)
			(xy 48.994395 -17.531193) (xy 49.009751 -17.478894) (xy 49.032395 -17.429312) (xy 49.061863 -17.383457)
			(xy 49.097558 -17.342262) (xy 49.138752 -17.306567) (xy 49.184606 -17.277097) (xy 49.234188 -17.254454)
			(xy 49.286487 -17.239096) (xy 49.34044 -17.231338) (xy 49.367694 -17.230852) (xy 50.231294 -17.230852)
			(xy 50.258544 -17.231395) (xy 50.31249 -17.23915) (xy 50.364783 -17.254504) (xy 50.414359 -17.277144)
			(xy 50.460208 -17.306609) (xy 50.501397 -17.342299) (xy 50.537088 -17.383487) (xy 50.566553 -17.429336)
			(xy 50.589194 -17.478911) (xy 50.604548 -17.531204) (xy 50.612305 -17.58515) (xy 50.612305 -17.63965)
			(xy 50.612304 -17.639657) (xy 54.608615 -17.639657) (xy 54.608615 -17.585143) (xy 54.616374 -17.531184)
			(xy 54.631733 -17.478878) (xy 54.65438 -17.42929) (xy 54.683854 -17.383431) (xy 54.719554 -17.342233)
			(xy 54.760755 -17.306536) (xy 54.806617 -17.277065) (xy 54.856206 -17.254422) (xy 54.908513 -17.239067)
			(xy 54.962473 -17.231313) (xy 54.98973 -17.230852) (xy 55.85333 -17.230852) (xy 55.880577 -17.23142)
			(xy 55.934516 -17.239179) (xy 55.986801 -17.254535) (xy 56.03637 -17.277176) (xy 56.082211 -17.30664)
			(xy 56.123394 -17.342328) (xy 56.159078 -17.383513) (xy 56.188538 -17.429357) (xy 56.211175 -17.478927)
			(xy 56.226527 -17.531214) (xy 56.234282 -17.585153) (xy 56.234282 -17.639647) (xy 56.226527 -17.693586)
			(xy 56.211175 -17.745873) (xy 56.188538 -17.795443) (xy 56.159078 -17.841287) (xy 56.123394 -17.882472)
			(xy 56.082211 -17.91816) (xy 56.03637 -17.947624) (xy 55.986801 -17.970265) (xy 55.934516 -17.985621)
			(xy 55.880577 -17.99338) (xy 55.85333 -17.993868) (xy 54.98973 -17.993868) (xy 54.962473 -17.993487)
			(xy 54.908513 -17.985733) (xy 54.856206 -17.970378) (xy 54.806617 -17.947735) (xy 54.760755 -17.918264)
			(xy 54.719554 -17.882567) (xy 54.683854 -17.841369) (xy 54.65438 -17.79551) (xy 54.631733 -17.745922)
			(xy 54.616374 -17.693616) (xy 54.608615 -17.639657) (xy 50.612304 -17.639657) (xy 50.604548 -17.693596)
			(xy 50.589194 -17.745889) (xy 50.566553 -17.795464) (xy 50.537088 -17.841313) (xy 50.501397 -17.882501)
			(xy 50.460208 -17.918191) (xy 50.414359 -17.947656) (xy 50.364783 -17.970296) (xy 50.31249 -17.98565)
			(xy 50.258544 -17.993405) (xy 50.231294 -17.993868) (xy 49.367694 -17.993868) (xy 49.34044 -17.993462)
			(xy 49.286487 -17.985704) (xy 49.234188 -17.970346) (xy 49.184606 -17.947703) (xy 49.138752 -17.918233)
			(xy 49.097558 -17.882538) (xy 49.061863 -17.841343) (xy 49.032395 -17.795488) (xy 49.009751 -17.745906)
			(xy 48.994395 -17.693607) (xy 48.986638 -17.639654) (xy 45.024304 -17.639654) (xy 45.016548 -17.693596)
			(xy 45.001194 -17.745889) (xy 44.978553 -17.795464) (xy 44.949088 -17.841313) (xy 44.913397 -17.882501)
			(xy 44.872208 -17.918191) (xy 44.826359 -17.947656) (xy 44.776783 -17.970296) (xy 44.72449 -17.98565)
			(xy 44.670544 -17.993405) (xy 44.643294 -17.993868) (xy 43.779694 -17.993868) (xy 43.75244 -17.993462)
			(xy 43.698487 -17.985704) (xy 43.646188 -17.970346) (xy 43.596606 -17.947703) (xy 43.550752 -17.918233)
			(xy 43.509558 -17.882538) (xy 43.473863 -17.841343) (xy 43.444395 -17.795488) (xy 43.421751 -17.745906)
			(xy 43.406395 -17.693607) (xy 43.398638 -17.639654) (xy 39.130505 -17.639654) (xy 39.122748 -17.693598)
			(xy 39.107392 -17.745892) (xy 39.084751 -17.795469) (xy 39.055284 -17.841318) (xy 39.019591 -17.882507)
			(xy 38.9784 -17.918197) (xy 38.932549 -17.947661) (xy 38.882972 -17.9703) (xy 38.830677 -17.985653)
			(xy 38.776729 -17.993406) (xy 38.749478 -17.993868) (xy 37.885878 -17.993868) (xy 37.858625 -17.993461)
			(xy 37.804674 -17.985701) (xy 37.752376 -17.970342) (xy 37.702797 -17.947697) (xy 37.656944 -17.918227)
			(xy 37.615752 -17.882532) (xy 37.580059 -17.841338) (xy 37.550592 -17.795484) (xy 37.52795 -17.745903)
			(xy 37.512595 -17.693605) (xy 37.504838 -17.639653) (xy 33.542505 -17.639653) (xy 33.534748 -17.693598)
			(xy 33.519392 -17.745892) (xy 33.496751 -17.795469) (xy 33.467284 -17.841318) (xy 33.431591 -17.882507)
			(xy 33.3904 -17.918197) (xy 33.344549 -17.947661) (xy 33.294972 -17.9703) (xy 33.242677 -17.985653)
			(xy 33.188729 -17.993406) (xy 33.161478 -17.993868) (xy 32.297878 -17.993868) (xy 32.270625 -17.993461)
			(xy 32.216674 -17.985701) (xy 32.164376 -17.970342) (xy 32.114797 -17.947697) (xy 32.068944 -17.918227)
			(xy 32.027752 -17.882532) (xy 31.992059 -17.841338) (xy 31.962592 -17.795484) (xy 31.93995 -17.745903)
			(xy 31.924595 -17.693605) (xy 31.916838 -17.639653) (xy 27.954505 -17.639653) (xy 27.946748 -17.693598)
			(xy 27.931392 -17.745892) (xy 27.908751 -17.795469) (xy 27.879284 -17.841318) (xy 27.843591 -17.882507)
			(xy 27.8024 -17.918197) (xy 27.756549 -17.947661) (xy 27.706972 -17.9703) (xy 27.654677 -17.985653)
			(xy 27.600729 -17.993406) (xy 27.573478 -17.993868) (xy 26.709878 -17.993868) (xy 26.682625 -17.993461)
			(xy 26.628674 -17.985701) (xy 26.576376 -17.970342) (xy 26.526797 -17.947697) (xy 26.480944 -17.918227)
			(xy 26.439752 -17.882532) (xy 26.404059 -17.841338) (xy 26.374592 -17.795484) (xy 26.35195 -17.745903)
			(xy 26.336595 -17.693605) (xy 26.328838 -17.639653) (xy 22.366505 -17.639653) (xy 22.358748 -17.693598)
			(xy 22.343392 -17.745892) (xy 22.320751 -17.795469) (xy 22.291284 -17.841318) (xy 22.255591 -17.882507)
			(xy 22.2144 -17.918197) (xy 22.168549 -17.947661) (xy 22.118972 -17.9703) (xy 22.066677 -17.985653)
			(xy 22.012729 -17.993406) (xy 21.985478 -17.993868) (xy 21.121878 -17.993868) (xy 21.094627 -17.993382)
			(xy 21.040679 -17.985625) (xy 20.988385 -17.97027) (xy 20.938808 -17.947629) (xy 20.892958 -17.918162)
			(xy 20.851768 -17.882471) (xy 20.816076 -17.841281) (xy 20.78661 -17.79543) (xy 20.763969 -17.745853)
			(xy 20.748614 -17.693559) (xy 20.740858 -17.639611) (xy 16.778525 -17.639611) (xy 16.778525 -17.639613)
			(xy 16.770768 -17.693564) (xy 16.755412 -17.745862) (xy 16.732769 -17.795442) (xy 16.703301 -17.841296)
			(xy 16.667607 -17.882488) (xy 16.626414 -17.918182) (xy 16.580561 -17.94765) (xy 16.53098 -17.970292)
			(xy 16.478682 -17.985648) (xy 16.424731 -17.993405) (xy 16.397478 -17.993868) (xy 15.533878 -17.993868)
			(xy 15.506627 -17.993382) (xy 15.452679 -17.985625) (xy 15.400385 -17.97027) (xy 15.350808 -17.947629)
			(xy 15.304958 -17.918162) (xy 15.263768 -17.882471) (xy 15.228076 -17.841281) (xy 15.19861 -17.79543)
			(xy 15.175969 -17.745853) (xy 15.160614 -17.693559) (xy 15.152858 -17.639611) (xy 0.509016 -17.639611)
			(xy 0.509016 -18.171947) (xy 131.633522 -18.171947) (xy 131.633522 -18.117453) (xy 131.641277 -18.063515)
			(xy 131.656629 -18.011229) (xy 131.679265 -17.961659) (xy 131.708725 -17.915816) (xy 131.744409 -17.874631)
			(xy 131.78559 -17.838944) (xy 131.831431 -17.80948) (xy 131.880999 -17.78684) (xy 131.933283 -17.771484)
			(xy 131.987221 -17.763724) (xy 132.014468 -17.763236) (xy 132.878068 -17.763236) (xy 132.905326 -17.763609)
			(xy 132.959286 -17.771363) (xy 133.011594 -17.786718) (xy 133.061184 -17.809361) (xy 133.107046 -17.838832)
			(xy 133.148248 -17.87453) (xy 133.183949 -17.915728) (xy 133.213423 -17.961588) (xy 133.236071 -18.011176)
			(xy 133.25143 -18.063483) (xy 133.259189 -18.117443) (xy 133.259189 -18.17195) (xy 137.033499 -18.17195)
			(xy 137.033499 -18.11745) (xy 137.041256 -18.063505) (xy 137.05661 -18.011212) (xy 137.079251 -17.961637)
			(xy 137.108716 -17.915789) (xy 137.144406 -17.874601) (xy 137.185595 -17.838911) (xy 137.231444 -17.809447)
			(xy 137.28102 -17.786807) (xy 137.333312 -17.771454) (xy 137.387258 -17.763699) (xy 137.414508 -17.763236)
			(xy 138.278108 -17.763236) (xy 138.305362 -17.763634) (xy 138.359315 -17.771393) (xy 138.411615 -17.78675)
			(xy 138.461197 -17.809395) (xy 138.507052 -17.838864) (xy 138.548246 -17.87456) (xy 138.58394 -17.915755)
			(xy 138.613409 -17.96161) (xy 138.636052 -18.011193) (xy 138.651409 -18.063493) (xy 138.659166 -18.117446)
			(xy 138.659166 -18.171946) (xy 140.633522 -18.171946) (xy 140.633522 -18.117454) (xy 140.641276 -18.063517)
			(xy 140.656627 -18.011232) (xy 140.679262 -17.961664) (xy 140.70872 -17.915822) (xy 140.744402 -17.874638)
			(xy 140.785582 -17.83895) (xy 140.83142 -17.809486) (xy 140.880986 -17.786845) (xy 140.933268 -17.771487)
			(xy 140.987204 -17.763726) (xy 141.01445 -17.763236) (xy 141.87805 -17.763236) (xy 141.905308 -17.763608)
			(xy 141.959271 -17.77136) (xy 142.011581 -17.786713) (xy 142.061173 -17.809355) (xy 142.107038 -17.838825)
			(xy 142.148241 -17.874523) (xy 142.183945 -17.915722) (xy 142.213421 -17.961583) (xy 142.236069 -18.011172)
			(xy 142.25143 -18.06348) (xy 142.259189 -18.117442) (xy 142.259189 -18.171951) (xy 185.748399 -18.171951)
			(xy 185.748399 -18.117449) (xy 185.756156 -18.063503) (xy 185.771511 -18.011209) (xy 185.794153 -17.961633)
			(xy 185.823619 -17.915784) (xy 185.859311 -17.874596) (xy 185.900502 -17.838906) (xy 185.946353 -17.809442)
			(xy 185.99593 -17.786804) (xy 186.048224 -17.771451) (xy 186.102171 -17.763698) (xy 186.129422 -17.763236)
			(xy 186.993022 -17.763236) (xy 187.020275 -17.763635) (xy 187.074227 -17.771395) (xy 187.126525 -17.786754)
			(xy 187.176105 -17.809399) (xy 187.201242 -17.825555) (xy 218.803143 -17.825555) (xy 218.803143 -17.771045)
			(xy 218.810901 -17.717091) (xy 218.826258 -17.66479) (xy 218.848903 -17.615207) (xy 218.878374 -17.569351)
			(xy 218.914071 -17.528157) (xy 218.955267 -17.492462) (xy 219.001124 -17.462993) (xy 219.050709 -17.440351)
			(xy 219.10301 -17.424996) (xy 219.156965 -17.417242) (xy 219.18422 -17.41678) (xy 220.04782 -17.41678)
			(xy 220.075069 -17.417292) (xy 220.129013 -17.42505) (xy 220.181304 -17.440407) (xy 220.230877 -17.463048)
			(xy 220.276723 -17.492514) (xy 220.31791 -17.528204) (xy 220.353598 -17.569393) (xy 220.383062 -17.615241)
			(xy 220.4057 -17.664815) (xy 220.421054 -17.717106) (xy 220.42881 -17.771051) (xy 220.42881 -17.825549)
			(xy 220.421054 -17.879494) (xy 220.4057 -17.931785) (xy 220.383062 -17.981359) (xy 220.353598 -18.027207)
			(xy 220.31791 -18.068396) (xy 220.276723 -18.104086) (xy 220.230877 -18.133552) (xy 220.181304 -18.156193)
			(xy 220.129013 -18.17155) (xy 220.075069 -18.179308) (xy 220.04782 -18.179796) (xy 219.18422 -18.179796)
			(xy 219.156965 -18.179358) (xy 219.10301 -18.171604) (xy 219.050709 -18.156249) (xy 219.001124 -18.133607)
			(xy 218.955267 -18.104138) (xy 218.914071 -18.068443) (xy 218.878374 -18.027249) (xy 218.848903 -17.981393)
			(xy 218.826258 -17.93181) (xy 218.810901 -17.879509) (xy 218.803143 -17.825555) (xy 187.201242 -17.825555)
			(xy 187.221958 -17.838869) (xy 187.263151 -17.874565) (xy 187.298844 -17.915759) (xy 187.328311 -17.961614)
			(xy 187.350954 -18.011196) (xy 187.366309 -18.063495) (xy 187.374066 -18.117447) (xy 187.374066 -18.171953)
			(xy 187.366309 -18.225905) (xy 187.350954 -18.278204) (xy 187.328311 -18.327786) (xy 187.298844 -18.373641)
			(xy 187.263151 -18.414835) (xy 187.221958 -18.450531) (xy 187.176105 -18.480001) (xy 187.126525 -18.502646)
			(xy 187.074227 -18.518005) (xy 187.020275 -18.525765) (xy 186.993022 -18.526252) (xy 186.129422 -18.526252)
			(xy 186.102171 -18.525702) (xy 186.048224 -18.517949) (xy 185.99593 -18.502596) (xy 185.946353 -18.479958)
			(xy 185.900502 -18.450494) (xy 185.859311 -18.414804) (xy 185.823619 -18.373616) (xy 185.794153 -18.327767)
			(xy 185.771511 -18.278191) (xy 185.756156 -18.225897) (xy 185.748399 -18.171951) (xy 142.259189 -18.171951)
			(xy 142.259189 -18.171958) (xy 142.25143 -18.22592) (xy 142.236069 -18.278228) (xy 142.213421 -18.327817)
			(xy 142.183945 -18.373678) (xy 142.148241 -18.414877) (xy 142.107038 -18.450575) (xy 142.061173 -18.480045)
			(xy 142.011581 -18.502687) (xy 141.959271 -18.51804) (xy 141.905308 -18.525792) (xy 141.87805 -18.526252)
			(xy 141.01445 -18.526252) (xy 140.987204 -18.525674) (xy 140.933268 -18.517913) (xy 140.880986 -18.502555)
			(xy 140.83142 -18.479914) (xy 140.785582 -18.45045) (xy 140.744402 -18.414762) (xy 140.70872 -18.373578)
			(xy 140.679262 -18.327736) (xy 140.656627 -18.278168) (xy 140.641276 -18.225883) (xy 140.633522 -18.171946)
			(xy 138.659166 -18.171946) (xy 138.659166 -18.171954) (xy 138.651409 -18.225907) (xy 138.636052 -18.278207)
			(xy 138.613409 -18.32779) (xy 138.58394 -18.373645) (xy 138.548246 -18.41484) (xy 138.507052 -18.450536)
			(xy 138.461197 -18.480005) (xy 138.411615 -18.50265) (xy 138.359315 -18.518007) (xy 138.305362 -18.525766)
			(xy 138.278108 -18.526252) (xy 137.414508 -18.526252) (xy 137.387258 -18.525701) (xy 137.333312 -18.517946)
			(xy 137.28102 -18.502593) (xy 137.231444 -18.479953) (xy 137.185595 -18.450489) (xy 137.144406 -18.414799)
			(xy 137.108716 -18.373611) (xy 137.079251 -18.327763) (xy 137.05661 -18.278188) (xy 137.041256 -18.225895)
			(xy 137.033499 -18.17195) (xy 133.259189 -18.17195) (xy 133.259189 -18.171957) (xy 133.25143 -18.225917)
			(xy 133.236071 -18.278224) (xy 133.213423 -18.327812) (xy 133.183949 -18.373672) (xy 133.148248 -18.41487)
			(xy 133.107046 -18.450568) (xy 133.061184 -18.480039) (xy 133.011594 -18.502682) (xy 132.959286 -18.518037)
			(xy 132.905326 -18.525791) (xy 132.878068 -18.526252) (xy 132.014468 -18.526252) (xy 131.987221 -18.525676)
			(xy 131.933283 -18.517916) (xy 131.880999 -18.50256) (xy 131.831431 -18.47992) (xy 131.78559 -18.450456)
			(xy 131.744409 -18.414769) (xy 131.708725 -18.373584) (xy 131.679265 -18.327741) (xy 131.656629 -18.278171)
			(xy 131.641277 -18.225885) (xy 131.633522 -18.171947) (xy 0.509016 -18.171947) (xy 0.509016 -19.163611)
			(xy 17.946858 -19.163611) (xy 17.946858 -19.109109) (xy 17.954614 -19.055161) (xy 17.969969 -19.002867)
			(xy 17.99261 -18.95329) (xy 18.022076 -18.907439) (xy 18.057768 -18.866249) (xy 18.098958 -18.830558)
			(xy 18.144808 -18.801091) (xy 18.194385 -18.77845) (xy 18.246679 -18.763095) (xy 18.300627 -18.755338)
			(xy 18.327878 -18.754852) (xy 19.191478 -18.754852) (xy 19.218731 -18.755315) (xy 19.272682 -18.763072)
			(xy 19.32498 -18.778428) (xy 19.374561 -18.80107) (xy 19.420414 -18.830538) (xy 19.461607 -18.866232)
			(xy 19.497301 -18.907424) (xy 19.526769 -18.953278) (xy 19.549412 -19.002858) (xy 19.564768 -19.055156)
			(xy 19.572525 -19.109107) (xy 19.572525 -19.163613) (xy 19.572519 -19.163653) (xy 23.534838 -19.163653)
			(xy 23.534838 -19.109147) (xy 23.542595 -19.055195) (xy 23.55795 -19.002897) (xy 23.580592 -18.953316)
			(xy 23.610059 -18.907462) (xy 23.645752 -18.866268) (xy 23.686944 -18.830573) (xy 23.732797 -18.801103)
			(xy 23.782376 -18.778458) (xy 23.834674 -18.763099) (xy 23.888625 -18.755339) (xy 23.915878 -18.754852)
			(xy 24.779478 -18.754852) (xy 24.806729 -18.755394) (xy 24.860677 -18.763147) (xy 24.912972 -18.7785)
			(xy 24.962549 -18.801139) (xy 25.0084 -18.830603) (xy 25.049591 -18.866293) (xy 25.085284 -18.907482)
			(xy 25.114751 -18.953331) (xy 25.137392 -19.002908) (xy 25.152748 -19.055202) (xy 25.160505 -19.109149)
			(xy 25.160505 -19.163651) (xy 25.160505 -19.163653) (xy 29.122838 -19.163653) (xy 29.122838 -19.109147)
			(xy 29.130595 -19.055195) (xy 29.14595 -19.002897) (xy 29.168592 -18.953316) (xy 29.198059 -18.907462)
			(xy 29.233752 -18.866268) (xy 29.274944 -18.830573) (xy 29.320797 -18.801103) (xy 29.370376 -18.778458)
			(xy 29.422674 -18.763099) (xy 29.476625 -18.755339) (xy 29.503878 -18.754852) (xy 30.367478 -18.754852)
			(xy 30.394729 -18.755394) (xy 30.448677 -18.763147) (xy 30.500972 -18.7785) (xy 30.550549 -18.801139)
			(xy 30.5964 -18.830603) (xy 30.637591 -18.866293) (xy 30.673284 -18.907482) (xy 30.702751 -18.953331)
			(xy 30.725392 -19.002908) (xy 30.740748 -19.055202) (xy 30.748505 -19.109149) (xy 30.748505 -19.163651)
			(xy 30.748505 -19.163653) (xy 34.710838 -19.163653) (xy 34.710838 -19.109147) (xy 34.718595 -19.055195)
			(xy 34.73395 -19.002897) (xy 34.756592 -18.953316) (xy 34.786059 -18.907462) (xy 34.821752 -18.866268)
			(xy 34.862944 -18.830573) (xy 34.908797 -18.801103) (xy 34.958376 -18.778458) (xy 35.010674 -18.763099)
			(xy 35.064625 -18.755339) (xy 35.091878 -18.754852) (xy 35.955478 -18.754852) (xy 35.982729 -18.755394)
			(xy 36.036677 -18.763147) (xy 36.088972 -18.7785) (xy 36.138549 -18.801139) (xy 36.1844 -18.830603)
			(xy 36.225591 -18.866293) (xy 36.261284 -18.907482) (xy 36.290751 -18.953331) (xy 36.313392 -19.002908)
			(xy 36.328748 -19.055202) (xy 36.336505 -19.109149) (xy 36.336505 -19.163651) (xy 36.336505 -19.163654)
			(xy 40.604638 -19.163654) (xy 40.604638 -19.109146) (xy 40.612395 -19.055193) (xy 40.627751 -19.002894)
			(xy 40.650395 -18.953312) (xy 40.679863 -18.907457) (xy 40.715558 -18.866262) (xy 40.756752 -18.830567)
			(xy 40.802606 -18.801097) (xy 40.852188 -18.778454) (xy 40.904487 -18.763096) (xy 40.95844 -18.755338)
			(xy 40.985694 -18.754852) (xy 41.849294 -18.754852) (xy 41.876544 -18.755395) (xy 41.93049 -18.76315)
			(xy 41.982783 -18.778504) (xy 42.032359 -18.801144) (xy 42.078208 -18.830609) (xy 42.119397 -18.866299)
			(xy 42.155088 -18.907487) (xy 42.184553 -18.953336) (xy 42.207194 -19.002911) (xy 42.222548 -19.055204)
			(xy 42.230305 -19.10915) (xy 42.230305 -19.16365) (xy 42.230304 -19.163654) (xy 46.192638 -19.163654)
			(xy 46.192638 -19.109146) (xy 46.200395 -19.055193) (xy 46.215751 -19.002894) (xy 46.238395 -18.953312)
			(xy 46.267863 -18.907457) (xy 46.303558 -18.866262) (xy 46.344752 -18.830567) (xy 46.390606 -18.801097)
			(xy 46.440188 -18.778454) (xy 46.492487 -18.763096) (xy 46.54644 -18.755338) (xy 46.573694 -18.754852)
			(xy 47.437294 -18.754852) (xy 47.464544 -18.755395) (xy 47.51849 -18.76315) (xy 47.570783 -18.778504)
			(xy 47.620359 -18.801144) (xy 47.666208 -18.830609) (xy 47.707397 -18.866299) (xy 47.743088 -18.907487)
			(xy 47.772553 -18.953336) (xy 47.795194 -19.002911) (xy 47.810548 -19.055204) (xy 47.818305 -19.10915)
			(xy 47.818305 -19.16365) (xy 47.818304 -19.163657) (xy 51.814615 -19.163657) (xy 51.814615 -19.109143)
			(xy 51.822374 -19.055184) (xy 51.837733 -19.002878) (xy 51.86038 -18.95329) (xy 51.889854 -18.907431)
			(xy 51.925554 -18.866233) (xy 51.966755 -18.830536) (xy 52.012617 -18.801065) (xy 52.062206 -18.778422)
			(xy 52.114513 -18.763067) (xy 52.168473 -18.755313) (xy 52.19573 -18.754852) (xy 53.05933 -18.754852)
			(xy 53.086577 -18.75542) (xy 53.140516 -18.763179) (xy 53.192801 -18.778535) (xy 53.24237 -18.801176)
			(xy 53.288211 -18.83064) (xy 53.329394 -18.866328) (xy 53.365078 -18.907513) (xy 53.394538 -18.953357)
			(xy 53.417175 -19.002927) (xy 53.432527 -19.055214) (xy 53.440282 -19.109153) (xy 53.440282 -19.163647)
			(xy 53.440281 -19.163657) (xy 57.402615 -19.163657) (xy 57.402615 -19.109143) (xy 57.410374 -19.055184)
			(xy 57.425733 -19.002878) (xy 57.44838 -18.95329) (xy 57.477854 -18.907431) (xy 57.513554 -18.866233)
			(xy 57.554755 -18.830536) (xy 57.600617 -18.801065) (xy 57.650206 -18.778422) (xy 57.702513 -18.763067)
			(xy 57.756473 -18.755313) (xy 57.78373 -18.754852) (xy 58.64733 -18.754852) (xy 58.674577 -18.75542)
			(xy 58.728516 -18.763179) (xy 58.780801 -18.778535) (xy 58.83037 -18.801176) (xy 58.876211 -18.83064)
			(xy 58.917394 -18.866328) (xy 58.953078 -18.907513) (xy 58.982538 -18.953357) (xy 59.005175 -19.002927)
			(xy 59.020527 -19.055214) (xy 59.028282 -19.109153) (xy 59.028282 -19.163647) (xy 59.020527 -19.217586)
			(xy 59.005175 -19.269873) (xy 58.982538 -19.319443) (xy 58.953078 -19.365287) (xy 58.917394 -19.406472)
			(xy 58.876211 -19.44216) (xy 58.83037 -19.471624) (xy 58.780801 -19.494265) (xy 58.728516 -19.509621)
			(xy 58.674577 -19.51738) (xy 58.64733 -19.517868) (xy 57.78373 -19.517868) (xy 57.756473 -19.517487)
			(xy 57.702513 -19.509733) (xy 57.650206 -19.494378) (xy 57.600617 -19.471735) (xy 57.554755 -19.442264)
			(xy 57.513554 -19.406567) (xy 57.477854 -19.365369) (xy 57.44838 -19.31951) (xy 57.425733 -19.269922)
			(xy 57.410374 -19.217616) (xy 57.402615 -19.163657) (xy 53.440281 -19.163657) (xy 53.432527 -19.217586)
			(xy 53.417175 -19.269873) (xy 53.394538 -19.319443) (xy 53.365078 -19.365287) (xy 53.329394 -19.406472)
			(xy 53.288211 -19.44216) (xy 53.24237 -19.471624) (xy 53.192801 -19.494265) (xy 53.140516 -19.509621)
			(xy 53.086577 -19.51738) (xy 53.05933 -19.517868) (xy 52.19573 -19.517868) (xy 52.168473 -19.517487)
			(xy 52.114513 -19.509733) (xy 52.062206 -19.494378) (xy 52.012617 -19.471735) (xy 51.966755 -19.442264)
			(xy 51.925554 -19.406567) (xy 51.889854 -19.365369) (xy 51.86038 -19.31951) (xy 51.837733 -19.269922)
			(xy 51.822374 -19.217616) (xy 51.814615 -19.163657) (xy 47.818304 -19.163657) (xy 47.810548 -19.217596)
			(xy 47.795194 -19.269889) (xy 47.772553 -19.319464) (xy 47.743088 -19.365313) (xy 47.707397 -19.406501)
			(xy 47.666208 -19.442191) (xy 47.620359 -19.471656) (xy 47.570783 -19.494296) (xy 47.51849 -19.50965)
			(xy 47.464544 -19.517405) (xy 47.437294 -19.517868) (xy 46.573694 -19.517868) (xy 46.54644 -19.517462)
			(xy 46.492487 -19.509704) (xy 46.440188 -19.494346) (xy 46.390606 -19.471703) (xy 46.344752 -19.442233)
			(xy 46.303558 -19.406538) (xy 46.267863 -19.365343) (xy 46.238395 -19.319488) (xy 46.215751 -19.269906)
			(xy 46.200395 -19.217607) (xy 46.192638 -19.163654) (xy 42.230304 -19.163654) (xy 42.222548 -19.217596)
			(xy 42.207194 -19.269889) (xy 42.184553 -19.319464) (xy 42.155088 -19.365313) (xy 42.119397 -19.406501)
			(xy 42.078208 -19.442191) (xy 42.032359 -19.471656) (xy 41.982783 -19.494296) (xy 41.93049 -19.50965)
			(xy 41.876544 -19.517405) (xy 41.849294 -19.517868) (xy 40.985694 -19.517868) (xy 40.95844 -19.517462)
			(xy 40.904487 -19.509704) (xy 40.852188 -19.494346) (xy 40.802606 -19.471703) (xy 40.756752 -19.442233)
			(xy 40.715558 -19.406538) (xy 40.679863 -19.365343) (xy 40.650395 -19.319488) (xy 40.627751 -19.269906)
			(xy 40.612395 -19.217607) (xy 40.604638 -19.163654) (xy 36.336505 -19.163654) (xy 36.328748 -19.217598)
			(xy 36.313392 -19.269892) (xy 36.290751 -19.319469) (xy 36.261284 -19.365318) (xy 36.225591 -19.406507)
			(xy 36.1844 -19.442197) (xy 36.138549 -19.471661) (xy 36.088972 -19.4943) (xy 36.036677 -19.509653)
			(xy 35.982729 -19.517406) (xy 35.955478 -19.517868) (xy 35.091878 -19.517868) (xy 35.064625 -19.517461)
			(xy 35.010674 -19.509701) (xy 34.958376 -19.494342) (xy 34.908797 -19.471697) (xy 34.862944 -19.442227)
			(xy 34.821752 -19.406532) (xy 34.786059 -19.365338) (xy 34.756592 -19.319484) (xy 34.73395 -19.269903)
			(xy 34.718595 -19.217605) (xy 34.710838 -19.163653) (xy 30.748505 -19.163653) (xy 30.740748 -19.217598)
			(xy 30.725392 -19.269892) (xy 30.702751 -19.319469) (xy 30.673284 -19.365318) (xy 30.637591 -19.406507)
			(xy 30.5964 -19.442197) (xy 30.550549 -19.471661) (xy 30.500972 -19.4943) (xy 30.448677 -19.509653)
			(xy 30.394729 -19.517406) (xy 30.367478 -19.517868) (xy 29.503878 -19.517868) (xy 29.476625 -19.517461)
			(xy 29.422674 -19.509701) (xy 29.370376 -19.494342) (xy 29.320797 -19.471697) (xy 29.274944 -19.442227)
			(xy 29.233752 -19.406532) (xy 29.198059 -19.365338) (xy 29.168592 -19.319484) (xy 29.14595 -19.269903)
			(xy 29.130595 -19.217605) (xy 29.122838 -19.163653) (xy 25.160505 -19.163653) (xy 25.152748 -19.217598)
			(xy 25.137392 -19.269892) (xy 25.114751 -19.319469) (xy 25.085284 -19.365318) (xy 25.049591 -19.406507)
			(xy 25.0084 -19.442197) (xy 24.962549 -19.471661) (xy 24.912972 -19.4943) (xy 24.860677 -19.509653)
			(xy 24.806729 -19.517406) (xy 24.779478 -19.517868) (xy 23.915878 -19.517868) (xy 23.888625 -19.517461)
			(xy 23.834674 -19.509701) (xy 23.782376 -19.494342) (xy 23.732797 -19.471697) (xy 23.686944 -19.442227)
			(xy 23.645752 -19.406532) (xy 23.610059 -19.365338) (xy 23.580592 -19.319484) (xy 23.55795 -19.269903)
			(xy 23.542595 -19.217605) (xy 23.534838 -19.163653) (xy 19.572519 -19.163653) (xy 19.564768 -19.217564)
			(xy 19.549412 -19.269862) (xy 19.526769 -19.319442) (xy 19.497301 -19.365296) (xy 19.461607 -19.406488)
			(xy 19.420414 -19.442182) (xy 19.374561 -19.47165) (xy 19.32498 -19.494292) (xy 19.272682 -19.509648)
			(xy 19.218731 -19.517405) (xy 19.191478 -19.517868) (xy 18.327878 -19.517868) (xy 18.300627 -19.517382)
			(xy 18.246679 -19.509625) (xy 18.194385 -19.49427) (xy 18.144808 -19.471629) (xy 18.098958 -19.442162)
			(xy 18.057768 -19.406471) (xy 18.022076 -19.365281) (xy 17.99261 -19.31943) (xy 17.969969 -19.269853)
			(xy 17.954614 -19.217559) (xy 17.946858 -19.163611) (xy 0.509016 -19.163611) (xy 0.509016 -20.187751)
			(xy 138.828766 -20.187751) (xy 138.828766 -20.133249) (xy 138.836522 -20.079301) (xy 138.851877 -20.027006)
			(xy 138.874517 -19.977429) (xy 138.903982 -19.931578) (xy 138.939673 -19.890387) (xy 138.980862 -19.854694)
			(xy 139.026711 -19.825227) (xy 139.076288 -19.802584) (xy 139.128582 -19.787226) (xy 139.182529 -19.779467)
			(xy 139.20978 -19.77898) (xy 140.07338 -19.77898) (xy 140.100633 -19.779466) (xy 140.154584 -19.78722)
			(xy 140.206883 -19.802574) (xy 140.256464 -19.825215) (xy 140.302318 -19.854681) (xy 140.343512 -19.890374)
			(xy 140.379207 -19.931566) (xy 140.408676 -19.977418) (xy 140.431319 -20.026998) (xy 140.446675 -20.079296)
			(xy 140.454433 -20.133247) (xy 140.454433 -20.187753) (xy 140.446675 -20.241704) (xy 140.431319 -20.294002)
			(xy 140.408676 -20.343582) (xy 140.379207 -20.389434) (xy 140.343512 -20.430626) (xy 140.302318 -20.466319)
			(xy 140.256464 -20.495785) (xy 140.206883 -20.518426) (xy 140.154584 -20.53378) (xy 140.100633 -20.541534)
			(xy 140.07338 -20.541996) (xy 139.20978 -20.541996) (xy 139.182529 -20.541533) (xy 139.128582 -20.533774)
			(xy 139.076288 -20.518416) (xy 139.026711 -20.495773) (xy 138.980862 -20.466306) (xy 138.939673 -20.430613)
			(xy 138.903982 -20.389422) (xy 138.874517 -20.343571) (xy 138.851877 -20.293994) (xy 138.836522 -20.241699)
			(xy 138.828766 -20.187751) (xy 0.509016 -20.187751) (xy 0.509016 -21.521251) (xy 15.232366 -21.521251)
			(xy 15.232366 -21.466749) (xy 15.240122 -21.412801) (xy 15.255477 -21.360506) (xy 15.278117 -21.310929)
			(xy 15.307582 -21.265078) (xy 15.343273 -21.223887) (xy 15.384462 -21.188194) (xy 15.430311 -21.158727)
			(xy 15.479888 -21.136084) (xy 15.532182 -21.120726) (xy 15.586129 -21.112967) (xy 15.61338 -21.11248)
			(xy 16.47698 -21.11248) (xy 16.504233 -21.112966) (xy 16.558184 -21.12072) (xy 16.610483 -21.136074)
			(xy 16.660064 -21.158715) (xy 16.705918 -21.188181) (xy 16.747112 -21.223874) (xy 16.782807 -21.265066)
			(xy 16.812276 -21.310918) (xy 16.834919 -21.360498) (xy 16.850275 -21.412796) (xy 16.858033 -21.466747)
			(xy 16.858033 -21.521253) (xy 16.850275 -21.575204) (xy 16.834919 -21.627502) (xy 16.812276 -21.677082)
			(xy 16.782807 -21.722934) (xy 16.747112 -21.764126) (xy 16.705918 -21.799819) (xy 16.660064 -21.829285)
			(xy 16.610483 -21.851926) (xy 16.558184 -21.86728) (xy 16.504233 -21.875034) (xy 16.47698 -21.875496)
			(xy 15.61338 -21.875496) (xy 15.586129 -21.875033) (xy 15.532182 -21.867274) (xy 15.479888 -21.851916)
			(xy 15.430311 -21.829273) (xy 15.384462 -21.799806) (xy 15.343273 -21.764113) (xy 15.307582 -21.722922)
			(xy 15.278117 -21.677071) (xy 15.255477 -21.627494) (xy 15.240122 -21.575199) (xy 15.232366 -21.521251)
			(xy 0.509016 -21.521251) (xy 0.509016 -24.929338) (xy 133.555232 -24.929338) (xy 133.555232 -24.065738)
			(xy 133.555718 -24.038487) (xy 133.563474 -23.984539) (xy 133.578829 -23.932244) (xy 133.601471 -23.882667)
			(xy 133.630937 -23.836817) (xy 133.666628 -23.795626) (xy 133.707819 -23.759935) (xy 133.753669 -23.730469)
			(xy 133.803246 -23.707827) (xy 133.855541 -23.692472) (xy 133.909489 -23.684716) (xy 133.963991 -23.684716)
			(xy 134.017939 -23.692472) (xy 134.070234 -23.707827) (xy 134.119811 -23.730469) (xy 134.165661 -23.759935)
			(xy 134.206852 -23.795626) (xy 134.242543 -23.836817) (xy 134.272009 -23.882667) (xy 134.294651 -23.932244)
			(xy 134.310006 -23.984539) (xy 134.317762 -24.038487) (xy 134.318248 -24.065738) (xy 134.318248 -24.929338)
			(xy 134.317762 -24.956589) (xy 134.310006 -25.010537) (xy 134.294651 -25.062832) (xy 134.272009 -25.112409)
			(xy 134.242543 -25.158259) (xy 134.206852 -25.19945) (xy 134.165661 -25.235141) (xy 134.119811 -25.264607)
			(xy 134.070234 -25.287249) (xy 134.017939 -25.302604) (xy 133.963991 -25.31036) (xy 133.909489 -25.31036)
			(xy 133.855541 -25.302604) (xy 133.803246 -25.287249) (xy 133.753669 -25.264607) (xy 133.707819 -25.235141)
			(xy 133.666628 -25.19945) (xy 133.630937 -25.158259) (xy 133.601471 -25.112409) (xy 133.578829 -25.062832)
			(xy 133.563474 -25.010537) (xy 133.555718 -24.956589) (xy 133.555232 -24.929338) (xy 0.509016 -24.929338)
			(xy 0.509016 -29.070615) (xy 12.244307 -29.070615) (xy 12.252198 -28.941486) (xy 12.268182 -28.813107)
			(xy 12.292195 -28.685984) (xy 12.324144 -28.560621) (xy 12.363901 -28.437511) (xy 12.41131 -28.31714)
			(xy 12.466183 -28.199984) (xy 12.528305 -28.086504) (xy 12.59743 -27.97715) (xy 12.673285 -27.872351)
			(xy 12.75557 -27.772522) (xy 12.843962 -27.678057) (xy 12.938111 -27.589329) (xy 13.037646 -27.506688)
			(xy 13.142173 -27.43046) (xy 13.25128 -27.360945) (xy 13.364537 -27.298419) (xy 13.481497 -27.243128)
			(xy 13.601698 -27.19529) (xy 13.724665 -27.155093) (xy 13.849914 -27.122698) (xy 13.97695 -27.098231)
			(xy 14.105271 -27.081789) (xy 14.234372 -27.073437) (xy 14.363742 -27.073208) (xy 14.492871 -27.081103)
			(xy 14.62125 -27.097091) (xy 14.748372 -27.121108) (xy 14.873734 -27.15306) (xy 14.996843 -27.19282)
			(xy 15.117212 -27.240232) (xy 15.234367 -27.295109) (xy 15.347845 -27.357234) (xy 15.457198 -27.426362)
			(xy 15.561994 -27.50222) (xy 15.661821 -27.584508) (xy 15.709392 -27.628342) (xy 16.877792 -28.721304)
			(xy 16.92464 -28.765906) (xy 17.013363 -28.860052) (xy 17.096 -28.959584) (xy 17.172224 -29.064107)
			(xy 17.241734 -29.17321) (xy 17.304257 -29.286463) (xy 17.359545 -29.403418) (xy 17.407381 -29.523614)
			(xy 17.447575 -29.646576) (xy 17.479969 -29.771819) (xy 17.504435 -29.898849) (xy 17.520877 -30.027165)
			(xy 17.529229 -30.15626) (xy 17.529459 -30.285624) (xy 17.521566 -30.414748) (xy 17.50558 -30.543122)
			(xy 17.481566 -30.670238) (xy 17.449617 -30.795596) (xy 17.40986 -30.9187) (xy 17.362452 -31.039065)
			(xy 17.30758 -31.156215) (xy 17.24546 -31.26969) (xy 17.176338 -31.379039) (xy 17.100486 -31.483833)
			(xy 17.018204 -31.583657) (xy 16.929816 -31.678118) (xy 16.835671 -31.766843) (xy 16.736141 -31.849481)
			(xy 16.631619 -31.925706) (xy 16.522517 -31.995218) (xy 16.409265 -32.057743) (xy 16.292311 -32.113033)
			(xy 16.172116 -32.16087) (xy 16.049154 -32.201066) (xy 15.923911 -32.233462) (xy 15.796882 -32.25793)
			(xy 15.668566 -32.274374) (xy 15.539471 -32.282728) (xy 15.410107 -32.28296) (xy 15.280983 -32.275069)
			(xy 15.152609 -32.259085) (xy 15.025493 -32.235073) (xy 14.900134 -32.203126) (xy 14.77703 -32.163371)
			(xy 14.656664 -32.115965) (xy 14.539512 -32.061094) (xy 14.426037 -31.998976) (xy 14.316687 -31.929855)
			(xy 14.211892 -31.854005) (xy 14.112066 -31.771724) (xy 14.064488 -31.727902) (xy 12.896088 -30.63494)
			(xy 12.849198 -30.590378) (xy 12.760467 -30.496232) (xy 12.677823 -30.3967) (xy 12.601592 -30.292174)
			(xy 12.532074 -30.183069) (xy 12.469545 -30.069814) (xy 12.41425 -29.952855) (xy 12.366409 -29.832656)
			(xy 12.32621 -29.70969) (xy 12.293811 -29.584442) (xy 12.26934 -29.457407) (xy 12.252895 -29.329086)
			(xy 12.244539 -29.199985) (xy 12.244307 -29.070615) (xy 0.509016 -29.070615) (xy 0.509016 -37.099629)
			(xy 170.600616 -37.099629) (xy 170.600616 -37.000299) (xy 170.608608 -36.901292) (xy 170.624542 -36.803249)
			(xy 170.648313 -36.706806) (xy 170.679768 -36.612588) (xy 170.718701 -36.521208) (xy 170.764862 -36.433256)
			(xy 170.81795 -36.349304) (xy 170.877621 -36.269895) (xy 170.943489 -36.195546) (xy 171.015126 -36.126738)
			(xy 171.092067 -36.063918) (xy 171.173813 -36.007493) (xy 171.259835 -35.957828) (xy 171.349574 -35.915246)
			(xy 171.442448 -35.880024) (xy 171.537856 -35.852388) (xy 171.635178 -35.83252) (xy 171.733783 -35.820547)
			(xy 171.833032 -35.816548) (xy 171.932281 -35.820547) (xy 172.030886 -35.83252) (xy 172.128208 -35.852388)
			(xy 172.223616 -35.880024) (xy 172.31649 -35.915246) (xy 172.406229 -35.957828) (xy 172.492251 -36.007493)
			(xy 172.573997 -36.063918) (xy 172.650938 -36.126738) (xy 172.722575 -36.195546) (xy 172.788443 -36.269895)
			(xy 172.848114 -36.349304) (xy 172.901202 -36.433256) (xy 172.947363 -36.521208) (xy 172.986296 -36.612588)
			(xy 173.017751 -36.706806) (xy 173.041522 -36.803249) (xy 173.057456 -36.901292) (xy 173.065448 -37.000299)
			(xy 173.065948 -37.049964) (xy 173.065448 -37.099629) (xy 173.057456 -37.198636) (xy 173.041522 -37.296679)
			(xy 173.017751 -37.393122) (xy 172.986296 -37.48734) (xy 172.947363 -37.57872) (xy 172.901202 -37.666672)
			(xy 172.848114 -37.750624) (xy 172.788443 -37.830033) (xy 172.722575 -37.904382) (xy 172.650938 -37.97319)
			(xy 172.573997 -38.03601) (xy 172.492251 -38.092435) (xy 172.406229 -38.1421) (xy 172.31649 -38.184682)
			(xy 172.223616 -38.219904) (xy 172.128208 -38.24754) (xy 172.030886 -38.267408) (xy 171.932281 -38.279381)
			(xy 171.833032 -38.283381) (xy 171.733783 -38.279381) (xy 171.635178 -38.267408) (xy 171.537856 -38.24754)
			(xy 171.442448 -38.219904) (xy 171.349574 -38.184682) (xy 171.259835 -38.1421) (xy 171.173813 -38.092435)
			(xy 171.092067 -38.03601) (xy 171.015126 -37.97319) (xy 170.943489 -37.904382) (xy 170.877621 -37.830033)
			(xy 170.81795 -37.750624) (xy 170.764862 -37.666672) (xy 170.718701 -37.57872) (xy 170.679768 -37.48734)
			(xy 170.648313 -37.393122) (xy 170.624542 -37.296679) (xy 170.608608 -37.198636) (xy 170.600616 -37.099629)
			(xy 0.509016 -37.099629) (xy 0.509016 -39.657528) (xy 357.003604 -39.657528) (xy 357.003604 -38.793928)
			(xy 357.00409 -38.766659) (xy 357.011852 -38.712675) (xy 357.027217 -38.660345) (xy 357.049874 -38.610735)
			(xy 357.07936 -38.564854) (xy 357.115075 -38.523637) (xy 357.156292 -38.487922) (xy 357.202173 -38.458436)
			(xy 357.251783 -38.435779) (xy 357.304113 -38.420414) (xy 357.358097 -38.412652) (xy 357.412635 -38.412652)
			(xy 357.466619 -38.420414) (xy 357.518949 -38.435779) (xy 357.568559 -38.458436) (xy 357.61444 -38.487922)
			(xy 357.655657 -38.523637) (xy 357.691372 -38.564854) (xy 357.720858 -38.610735) (xy 357.743515 -38.660345)
			(xy 357.75888 -38.712675) (xy 357.766642 -38.766659) (xy 357.767128 -38.793928) (xy 357.767128 -39.657528)
			(xy 357.766642 -39.684797) (xy 357.75888 -39.738781) (xy 357.743515 -39.791111) (xy 357.720858 -39.840721)
			(xy 357.691372 -39.886602) (xy 357.655657 -39.927819) (xy 357.61444 -39.963534) (xy 357.568559 -39.99302)
			(xy 357.518949 -40.015677) (xy 357.466619 -40.031042) (xy 357.412635 -40.038804) (xy 357.358097 -40.038804)
			(xy 357.304113 -40.031042) (xy 357.251783 -40.015677) (xy 357.202173 -39.99302) (xy 357.156292 -39.963534)
			(xy 357.115075 -39.927819) (xy 357.07936 -39.886602) (xy 357.049874 -39.840721) (xy 357.027217 -39.791111)
			(xy 357.011852 -39.738781) (xy 357.00409 -39.684797) (xy 357.003604 -39.657528) (xy 0.509016 -39.657528)
			(xy 0.509016 -40.744902) (xy 235.083357 -40.744902) (xy 235.087362 -40.656994) (xy 235.099345 -40.569814)
			(xy 235.119205 -40.484085) (xy 235.14678 -40.400517) (xy 235.181839 -40.319803) (xy 235.224092 -40.242611)
			(xy 235.27319 -40.169582) (xy 235.328726 -40.10132) (xy 235.390238 -40.03839) (xy 235.457219 -39.981316)
			(xy 235.529112 -39.930568) (xy 235.605321 -39.886568) (xy 235.685216 -39.849681) (xy 235.768135 -39.820212)
			(xy 235.85339 -39.798405) (xy 235.940274 -39.784441) (xy 236.028068 -39.778435) (xy 236.116045 -39.780439)
			(xy 236.203475 -39.790434) (xy 236.289634 -39.808338) (xy 236.373808 -39.834002) (xy 236.455299 -39.867215)
			(xy 236.533433 -39.907701) (xy 236.607561 -39.955123) (xy 236.677069 -40.00909) (xy 236.741383 -40.069155)
			(xy 236.799967 -40.134819) (xy 236.852338 -40.205538) (xy 236.898061 -40.280726) (xy 236.936758 -40.359761)
			(xy 236.968107 -40.441987) (xy 236.991849 -40.526723) (xy 237.007787 -40.613267) (xy 237.015789 -40.700902)
			(xy 237.01629 -40.744902) (xy 237.015789 -40.788902) (xy 237.007787 -40.876537) (xy 236.991849 -40.963081)
			(xy 236.968107 -41.047817) (xy 236.936758 -41.130043) (xy 236.898061 -41.209078) (xy 236.852338 -41.284266)
			(xy 236.799967 -41.354985) (xy 236.741383 -41.420649) (xy 236.677069 -41.480714) (xy 236.607561 -41.534681)
			(xy 236.533433 -41.582103) (xy 236.455299 -41.622589) (xy 236.373808 -41.655802) (xy 236.289634 -41.681466)
			(xy 236.203475 -41.69937) (xy 236.116045 -41.709365) (xy 236.028068 -41.711369) (xy 235.940274 -41.705363)
			(xy 235.85339 -41.691399) (xy 235.768135 -41.669592) (xy 235.685216 -41.640123) (xy 235.605321 -41.603236)
			(xy 235.529112 -41.559236) (xy 235.457219 -41.508488) (xy 235.390238 -41.451414) (xy 235.328726 -41.388484)
			(xy 235.27319 -41.320222) (xy 235.224092 -41.247193) (xy 235.181839 -41.170001) (xy 235.14678 -41.089287)
			(xy 235.119205 -41.005719) (xy 235.099345 -40.91999) (xy 235.087362 -40.83281) (xy 235.083357 -40.744902)
			(xy 0.509016 -40.744902) (xy 0.509016 -43.999912) (xy 16.983969 -43.999912) (xy 16.987993 -43.914144)
			(xy 17.000031 -43.82913) (xy 17.019978 -43.745616) (xy 17.047657 -43.664337) (xy 17.082825 -43.586008)
			(xy 17.125174 -43.511315) (xy 17.174331 -43.440917) (xy 17.229864 -43.375431) (xy 17.291286 -43.315433)
			(xy 17.358055 -43.26145) (xy 17.429587 -43.213957) (xy 17.505251 -43.173371) (xy 17.584384 -43.140048)
			(xy 17.666289 -43.114282) (xy 17.750247 -43.096299) (xy 17.835521 -43.086257) (xy 17.92136 -43.084244)
			(xy 18.00701 -43.090278) (xy 18.091718 -43.104306) (xy 18.174741 -43.126205) (xy 18.255349 -43.155782)
			(xy 18.332833 -43.192777) (xy 18.406512 -43.236865) (xy 18.475738 -43.287659) (xy 18.539905 -43.344712)
			(xy 18.598446 -43.407523) (xy 18.650849 -43.47554) (xy 18.696652 -43.548165) (xy 18.735453 -43.62476)
			(xy 18.766912 -43.704652) (xy 18.790751 -43.787139) (xy 18.806761 -43.871496) (xy 18.814801 -43.956981)
			(xy 18.815304 -43.999912) (xy 18.814801 -44.042843) (xy 18.806761 -44.128328) (xy 18.790751 -44.212685)
			(xy 18.766912 -44.295172) (xy 18.735453 -44.375064) (xy 18.696652 -44.451659) (xy 18.650849 -44.524284)
			(xy 18.598446 -44.592301) (xy 18.539905 -44.655112) (xy 18.475738 -44.712165) (xy 18.406512 -44.762959)
			(xy 18.332833 -44.807047) (xy 18.255349 -44.844042) (xy 18.174741 -44.873619) (xy 18.091718 -44.895518)
			(xy 18.00701 -44.909546) (xy 17.92136 -44.91558) (xy 17.835521 -44.913567) (xy 17.750247 -44.903525)
			(xy 17.666289 -44.885542) (xy 17.584384 -44.859776) (xy 17.505251 -44.826453) (xy 17.429587 -44.785867)
			(xy 17.358055 -44.738374) (xy 17.291286 -44.684391) (xy 17.229864 -44.624393) (xy 17.174331 -44.558907)
			(xy 17.125174 -44.488509) (xy 17.082825 -44.413816) (xy 17.047657 -44.335487) (xy 17.019978 -44.254208)
			(xy 17.000031 -44.170694) (xy 16.987993 -44.08568) (xy 16.983969 -43.999912) (xy 0.509016 -43.999912)
			(xy 0.509016 -47.049813) (xy 59.781451 -47.049813) (xy 59.785436 -46.895317) (xy 59.79737 -46.74123)
			(xy 59.817219 -46.587962) (xy 59.844933 -46.43592) (xy 59.880436 -46.285505) (xy 59.923635 -46.137118)
			(xy 59.974415 -45.991151) (xy 60.032642 -45.847991) (xy 60.098162 -45.708019) (xy 60.1708 -45.571605)
			(xy 60.250363 -45.439111) (xy 60.336642 -45.310889) (xy 60.429407 -45.187278) (xy 60.528412 -45.068606)
			(xy 60.633395 -44.955188) (xy 60.744077 -44.847324) (xy 60.860165 -44.745302) (xy 60.981351 -44.64939)
			(xy 61.107313 -44.559844) (xy 61.237718 -44.476901) (xy 61.37222 -44.400781) (xy 61.510462 -44.331685)
			(xy 61.652077 -44.269798) (xy 61.796691 -44.215282) (xy 61.943919 -44.168283) (xy 62.093371 -44.128926)
			(xy 62.244652 -44.097314) (xy 62.397358 -44.073531) (xy 62.551087 -44.057641) (xy 62.70543 -44.049685)
			(xy 62.782704 -44.049188) (xy 64.383158 -44.049188) (xy 64.460432 -44.049684) (xy 64.614774 -44.057653)
			(xy 64.768502 -44.073557) (xy 64.921207 -44.097353) (xy 65.072484 -44.128978) (xy 65.221933 -44.168349)
			(xy 65.369158 -44.21536) (xy 65.513767 -44.269888) (xy 65.655377 -44.331788) (xy 65.793613 -44.400896)
			(xy 65.928108 -44.477028) (xy 66.058506 -44.559982) (xy 66.184461 -44.649539) (xy 66.305639 -44.745461)
			(xy 66.421718 -44.847494) (xy 66.532391 -44.955367) (xy 66.637364 -45.068794) (xy 66.736359 -45.187475)
			(xy 66.829113 -45.311094) (xy 66.915381 -45.439324) (xy 66.994934 -45.571824) (xy 67.06756 -45.708245)
			(xy 67.133068 -45.848223) (xy 67.191283 -45.991387) (xy 67.242051 -46.137359) (xy 67.285237 -46.28575)
			(xy 67.320727 -46.436168) (xy 67.348428 -46.588213) (xy 67.368264 -46.741483) (xy 67.380185 -46.89557)
			(xy 67.384154 -47.04994) (xy 89.78165 -47.04994) (xy 89.78563 -46.895439) (xy 89.797557 -46.741349)
			(xy 89.817402 -46.588076) (xy 89.84511 -46.436028) (xy 89.880608 -46.285609) (xy 89.923803 -46.137216)
			(xy 89.97458 -45.991243) (xy 90.032804 -45.848078) (xy 90.098321 -45.708101) (xy 90.170957 -45.571681)
			(xy 90.250519 -45.439181) (xy 90.336796 -45.310953) (xy 90.42956 -45.187337) (xy 90.528565 -45.068659)
			(xy 90.633548 -44.955236) (xy 90.74423 -44.847368) (xy 90.860319 -44.74534) (xy 90.981506 -44.649424)
			(xy 91.10747 -44.559873) (xy 91.237877 -44.476926) (xy 91.372381 -44.400801) (xy 91.510626 -44.331702)
			(xy 91.652244 -44.269811) (xy 91.796861 -44.215293) (xy 91.944092 -44.168291) (xy 92.093548 -44.128931)
			(xy 92.244832 -44.097317) (xy 92.397543 -44.073533) (xy 92.551275 -44.057642) (xy 92.705622 -44.049686)
			(xy 92.782898 -44.049188) (xy 94.383098 -44.049188) (xy 94.460374 -44.049669) (xy 94.614722 -44.057625)
			(xy 94.768456 -44.073516) (xy 94.921168 -44.0973) (xy 95.072452 -44.128914) (xy 95.221909 -44.168274)
			(xy 95.369142 -44.215276) (xy 95.513759 -44.269795) (xy 95.655379 -44.331686) (xy 95.793624 -44.400785)
			(xy 95.928129 -44.47691) (xy 96.058537 -44.559858) (xy 96.184502 -44.649409) (xy 96.30569 -44.745326)
			(xy 96.421779 -44.847354) (xy 96.532463 -44.955223) (xy 96.637446 -45.068647) (xy 96.736452 -45.187325)
			(xy 96.829216 -45.310943) (xy 96.915495 -45.439171) (xy 96.995057 -45.571672) (xy 97.038059 -45.652436)
			(xy 155.97378 -45.652436) (xy 155.97378 -44.788836) (xy 155.974266 -44.761567) (xy 155.982028 -44.707583)
			(xy 155.997393 -44.655253) (xy 156.02005 -44.605643) (xy 156.049536 -44.559762) (xy 156.085251 -44.518545)
			(xy 156.126468 -44.48283) (xy 156.172349 -44.453344) (xy 156.221959 -44.430687) (xy 156.274289 -44.415322)
			(xy 156.328273 -44.40756) (xy 156.382811 -44.40756) (xy 156.436795 -44.415322) (xy 156.489125 -44.430687)
			(xy 156.538735 -44.453344) (xy 156.584616 -44.48283) (xy 156.625833 -44.518545) (xy 156.661548 -44.559762)
			(xy 156.691034 -44.605643) (xy 156.713691 -44.655253) (xy 156.72159 -44.682156) (xy 159.179768 -44.682156)
			(xy 159.179768 -43.818556) (xy 159.180254 -43.791287) (xy 159.188016 -43.737303) (xy 159.203381 -43.684973)
			(xy 159.226038 -43.635363) (xy 159.255524 -43.589482) (xy 159.291239 -43.548265) (xy 159.332456 -43.51255)
			(xy 159.378337 -43.483064) (xy 159.427947 -43.460407) (xy 159.480277 -43.445042) (xy 159.534261 -43.43728)
			(xy 159.588799 -43.43728) (xy 159.642783 -43.445042) (xy 159.695113 -43.460407) (xy 159.74185 -43.481752)
			(xy 178.891692 -43.481752) (xy 178.891692 -42.618152) (xy 178.892178 -42.590901) (xy 178.899934 -42.536953)
			(xy 178.915289 -42.484658) (xy 178.937931 -42.435081) (xy 178.967397 -42.389231) (xy 179.003088 -42.34804)
			(xy 179.044279 -42.312349) (xy 179.090129 -42.282883) (xy 179.139706 -42.260241) (xy 179.192001 -42.244886)
			(xy 179.245949 -42.23713) (xy 179.300451 -42.23713) (xy 179.354399 -42.244886) (xy 179.406694 -42.260241)
			(xy 179.456271 -42.282883) (xy 179.502121 -42.312349) (xy 179.543312 -42.34804) (xy 179.579003 -42.389231)
			(xy 179.608469 -42.435081) (xy 179.631111 -42.484658) (xy 179.646466 -42.536953) (xy 179.654222 -42.590901)
			(xy 179.654708 -42.618152) (xy 179.654708 -43.481752) (xy 179.654222 -43.509003) (xy 179.647839 -43.5534)
			(xy 353.767583 -43.5534) (xy 353.771544 -43.500544) (xy 353.783339 -43.44887) (xy 353.802705 -43.39953)
			(xy 353.829208 -43.353628) (xy 353.862256 -43.312189) (xy 353.901112 -43.276139) (xy 353.944908 -43.246283)
			(xy 353.992664 -43.223289) (xy 354.043314 -43.207669) (xy 354.095726 -43.199773) (xy 354.122228 -43.199304)
			(xy 354.122736 -43.199304) (xy 354.153713 -43.199978) (xy 354.214715 -43.210807) (xy 354.272905 -43.232077)
			(xy 354.300028 -43.247056) (xy 354.328004 -43.238767) (xy 354.385663 -43.229845) (xy 354.414836 -43.229276)
			(xy 354.99548 -43.229276) (xy 355.004624 -43.225466) (xy 355.025917 -43.217194) (xy 355.070087 -43.205543)
			(xy 355.115388 -43.199665) (xy 355.138228 -43.199304) (xy 355.162681 -43.199729) (xy 355.211118 -43.206478)
			(xy 355.25817 -43.219815) (xy 355.280722 -43.229276) (xy 355.307866 -43.229907) (xy 355.361565 -43.237931)
			(xy 355.413585 -43.253486) (xy 355.462874 -43.276259) (xy 355.508436 -43.305789) (xy 355.549352 -43.341481)
			(xy 355.584795 -43.382612) (xy 355.61405 -43.428352) (xy 355.636524 -43.477777) (xy 355.651765 -43.52989)
			(xy 355.659465 -43.583636) (xy 355.659944 -43.610784) (xy 355.659468 -43.634951) (xy 356.178591 -43.634951)
			(xy 356.178591 -43.580449) (xy 356.186348 -43.526502) (xy 356.201703 -43.474208) (xy 356.224344 -43.424632)
			(xy 356.253811 -43.378783) (xy 356.289502 -43.337594) (xy 356.330692 -43.301903) (xy 356.376543 -43.272438)
			(xy 356.42612 -43.249799) (xy 356.478414 -43.234445) (xy 356.532361 -43.22669) (xy 356.559612 -43.226228)
			(xy 357.423212 -43.226228) (xy 357.450465 -43.226643) (xy 357.504417 -43.234401) (xy 357.556715 -43.249759)
			(xy 357.606295 -43.272403) (xy 357.652149 -43.301872) (xy 357.693341 -43.337567) (xy 357.729035 -43.378761)
			(xy 357.758503 -43.424615) (xy 357.781145 -43.474196) (xy 357.796501 -43.526495) (xy 357.804258 -43.580447)
			(xy 357.804258 -43.634953) (xy 357.803812 -43.638056) (xy 358.339039 -43.638056) (xy 358.339039 -43.583544)
			(xy 358.346797 -43.529588) (xy 358.362156 -43.477285) (xy 358.384802 -43.4277) (xy 358.414274 -43.381843)
			(xy 358.449974 -43.340648) (xy 358.491172 -43.304953) (xy 358.537032 -43.275485) (xy 358.586619 -43.252843)
			(xy 358.638923 -43.23749) (xy 358.69288 -43.229736) (xy 358.720136 -43.229276) (xy 359.583736 -43.229276)
			(xy 359.610984 -43.229797) (xy 359.664926 -43.237557) (xy 359.717214 -43.252915) (xy 359.766785 -43.275557)
			(xy 359.812629 -43.305023) (xy 359.853813 -43.340713) (xy 359.889499 -43.3819) (xy 359.91896 -43.427747)
			(xy 359.941598 -43.47732) (xy 359.956951 -43.529609) (xy 359.964706 -43.583552) (xy 359.964706 -43.638048)
			(xy 359.956951 -43.691991) (xy 359.941598 -43.74428) (xy 359.91896 -43.793853) (xy 359.889499 -43.8397)
			(xy 359.853813 -43.880887) (xy 359.812629 -43.916577) (xy 359.766785 -43.946043) (xy 359.717214 -43.968685)
			(xy 359.664926 -43.984043) (xy 359.610984 -43.991803) (xy 359.583736 -43.992292) (xy 358.720136 -43.992292)
			(xy 358.69288 -43.991864) (xy 358.638923 -43.98411) (xy 358.586619 -43.968757) (xy 358.537032 -43.946115)
			(xy 358.491172 -43.916647) (xy 358.449974 -43.880952) (xy 358.414274 -43.839757) (xy 358.384802 -43.7939)
			(xy 358.362156 -43.744315) (xy 358.346797 -43.692012) (xy 358.339039 -43.638056) (xy 357.803812 -43.638056)
			(xy 357.796501 -43.688905) (xy 357.781145 -43.741204) (xy 357.758503 -43.790785) (xy 357.729035 -43.836639)
			(xy 357.693341 -43.877833) (xy 357.652149 -43.913528) (xy 357.606295 -43.942997) (xy 357.556715 -43.965641)
			(xy 357.504417 -43.980999) (xy 357.450465 -43.988757) (xy 357.423212 -43.989244) (xy 356.559612 -43.989244)
			(xy 356.532361 -43.98871) (xy 356.478414 -43.980955) (xy 356.42612 -43.965601) (xy 356.376543 -43.942962)
			(xy 356.330692 -43.913497) (xy 356.289502 -43.877806) (xy 356.253811 -43.836617) (xy 356.224344 -43.790768)
			(xy 356.201703 -43.741192) (xy 356.186348 -43.688898) (xy 356.178591 -43.634951) (xy 355.659468 -43.634951)
			(xy 355.659407 -43.638033) (xy 355.651654 -43.691977) (xy 355.636302 -43.744269) (xy 355.613666 -43.793843)
			(xy 355.584204 -43.839692) (xy 355.548518 -43.880882) (xy 355.507334 -43.916573) (xy 355.461489 -43.946041)
			(xy 355.411917 -43.968684) (xy 355.359628 -43.984043) (xy 355.305685 -43.991803) (xy 355.278436 -43.992292)
			(xy 354.414836 -43.992292) (xy 354.388369 -43.991825) (xy 354.335944 -43.984518) (xy 354.285033 -43.970025)
			(xy 354.236619 -43.948625) (xy 354.191633 -43.920731) (xy 354.170996 -43.904154) (xy 354.158864 -43.905712)
			(xy 354.134459 -43.907367) (xy 354.122228 -43.907456) (xy 354.095726 -43.907027) (xy 354.043314 -43.899131)
			(xy 353.992664 -43.883511) (xy 353.944908 -43.860517) (xy 353.901112 -43.830661) (xy 353.862256 -43.794611)
			(xy 353.829208 -43.753172) (xy 353.802705 -43.70727) (xy 353.783339 -43.65793) (xy 353.771544 -43.606256)
			(xy 353.767583 -43.5534) (xy 179.647839 -43.5534) (xy 179.646466 -43.562951) (xy 179.631111 -43.615246)
			(xy 179.608469 -43.664823) (xy 179.579003 -43.710673) (xy 179.543312 -43.751864) (xy 179.502121 -43.787555)
			(xy 179.456271 -43.817021) (xy 179.406694 -43.839663) (xy 179.354399 -43.855018) (xy 179.300451 -43.862774)
			(xy 179.245949 -43.862774) (xy 179.192001 -43.855018) (xy 179.139706 -43.839663) (xy 179.090129 -43.817021)
			(xy 179.044279 -43.787555) (xy 179.003088 -43.751864) (xy 178.967397 -43.710673) (xy 178.937931 -43.664823)
			(xy 178.915289 -43.615246) (xy 178.899934 -43.562951) (xy 178.892178 -43.509003) (xy 178.891692 -43.481752)
			(xy 159.74185 -43.481752) (xy 159.744723 -43.483064) (xy 159.790604 -43.51255) (xy 159.831821 -43.548265)
			(xy 159.867536 -43.589482) (xy 159.897022 -43.635363) (xy 159.919679 -43.684973) (xy 159.935044 -43.737303)
			(xy 159.942806 -43.791287) (xy 159.943292 -43.818556) (xy 159.943292 -44.682156) (xy 159.942806 -44.709425)
			(xy 159.935044 -44.763409) (xy 159.919679 -44.815739) (xy 159.897022 -44.865349) (xy 159.867536 -44.91123)
			(xy 159.831821 -44.952447) (xy 159.79991 -44.980098) (xy 181.659784 -44.980098) (xy 181.659784 -44.116498)
			(xy 181.66027 -44.089247) (xy 181.668026 -44.035299) (xy 181.683381 -43.983004) (xy 181.706023 -43.933427)
			(xy 181.735489 -43.887577) (xy 181.77118 -43.846386) (xy 181.812371 -43.810695) (xy 181.858221 -43.781229)
			(xy 181.907798 -43.758587) (xy 181.960093 -43.743232) (xy 182.014041 -43.735476) (xy 182.068543 -43.735476)
			(xy 182.122491 -43.743232) (xy 182.174786 -43.758587) (xy 182.224363 -43.781229) (xy 182.270213 -43.810695)
			(xy 182.311404 -43.846386) (xy 182.347095 -43.887577) (xy 182.376561 -43.933427) (xy 182.399203 -43.983004)
			(xy 182.414558 -44.035299) (xy 182.422314 -44.089247) (xy 182.4228 -44.116498) (xy 182.4228 -44.840452)
			(xy 348.511075 -44.840452) (xy 348.511075 -44.785948) (xy 348.518832 -44.731999) (xy 348.534188 -44.679702)
			(xy 348.556831 -44.630124) (xy 348.586298 -44.584273) (xy 348.621992 -44.543082) (xy 348.663184 -44.50739)
			(xy 348.709036 -44.477924) (xy 348.758616 -44.455283) (xy 348.810912 -44.439929) (xy 348.864862 -44.432174)
			(xy 348.892114 -44.431712) (xy 349.755714 -44.431712) (xy 349.782966 -44.432159) (xy 349.836915 -44.439917)
			(xy 349.889211 -44.455274) (xy 349.938789 -44.477918) (xy 349.98464 -44.507386) (xy 350.025831 -44.543079)
			(xy 350.061523 -44.584271) (xy 350.090989 -44.630123) (xy 350.11363 -44.679702) (xy 350.128986 -44.731999)
			(xy 350.136742 -44.785948) (xy 350.136742 -44.840452) (xy 350.128986 -44.894401) (xy 350.11363 -44.946698)
			(xy 350.090989 -44.996277) (xy 350.072098 -45.025673) (xy 355.559288 -45.025673) (xy 355.559288 -44.971127)
			(xy 355.56705 -44.917137) (xy 355.582418 -44.864802) (xy 355.605077 -44.815186) (xy 355.634567 -44.7693)
			(xy 355.670288 -44.728078) (xy 355.711511 -44.692359) (xy 355.757398 -44.662871) (xy 355.807015 -44.640213)
			(xy 355.859351 -44.624847) (xy 355.913341 -44.617087) (xy 355.940614 -44.616624) (xy 356.804214 -44.616624)
			(xy 356.831482 -44.617139) (xy 356.885462 -44.624902) (xy 356.937788 -44.640268) (xy 356.987394 -44.662925)
			(xy 357.033272 -44.69241) (xy 357.074486 -44.728124) (xy 357.110199 -44.769339) (xy 357.139682 -44.815218)
			(xy 357.162337 -44.864825) (xy 357.177701 -44.917152) (xy 357.185462 -44.971132) (xy 357.185462 -45.025668)
			(xy 357.177701 -45.079648) (xy 357.162337 -45.131975) (xy 357.139682 -45.181582) (xy 357.110199 -45.227461)
			(xy 357.074486 -45.268676) (xy 357.033272 -45.30439) (xy 356.987394 -45.333875) (xy 356.937788 -45.356532)
			(xy 356.885462 -45.371898) (xy 356.831482 -45.379661) (xy 356.804214 -45.380148) (xy 355.940614 -45.380148)
			(xy 355.913341 -45.379713) (xy 355.859351 -45.371953) (xy 355.807015 -45.356587) (xy 355.757398 -45.333929)
			(xy 355.711511 -45.304441) (xy 355.670288 -45.268722) (xy 355.634567 -45.2275) (xy 355.605077 -45.181614)
			(xy 355.582418 -45.131998) (xy 355.56705 -45.079663) (xy 355.559288 -45.025673) (xy 350.072098 -45.025673)
			(xy 350.061523 -45.042129) (xy 350.025831 -45.083321) (xy 349.98464 -45.119014) (xy 349.938789 -45.148482)
			(xy 349.889211 -45.171126) (xy 349.836915 -45.186483) (xy 349.782966 -45.194241) (xy 349.755714 -45.194728)
			(xy 348.892114 -45.194728) (xy 348.864862 -45.194226) (xy 348.810912 -45.186471) (xy 348.758616 -45.171117)
			(xy 348.709036 -45.148476) (xy 348.663184 -45.11901) (xy 348.621992 -45.083318) (xy 348.586298 -45.042127)
			(xy 348.556831 -44.996276) (xy 348.534188 -44.946698) (xy 348.518832 -44.894401) (xy 348.511075 -44.840452)
			(xy 182.4228 -44.840452) (xy 182.4228 -44.980098) (xy 182.422314 -45.007349) (xy 182.414558 -45.061297)
			(xy 182.399203 -45.113592) (xy 182.376561 -45.163169) (xy 182.347095 -45.209019) (xy 182.311404 -45.25021)
			(xy 182.270213 -45.285901) (xy 182.224363 -45.315367) (xy 182.174786 -45.338009) (xy 182.122491 -45.353364)
			(xy 182.068543 -45.36112) (xy 182.014041 -45.36112) (xy 181.960093 -45.353364) (xy 181.907798 -45.338009)
			(xy 181.858221 -45.315367) (xy 181.812371 -45.285901) (xy 181.77118 -45.25021) (xy 181.735489 -45.209019)
			(xy 181.706023 -45.163169) (xy 181.683381 -45.113592) (xy 181.668026 -45.061297) (xy 181.66027 -45.007349)
			(xy 181.659784 -44.980098) (xy 159.79991 -44.980098) (xy 159.790604 -44.988162) (xy 159.744723 -45.017648)
			(xy 159.695113 -45.040305) (xy 159.642783 -45.05567) (xy 159.588799 -45.063432) (xy 159.534261 -45.063432)
			(xy 159.480277 -45.05567) (xy 159.427947 -45.040305) (xy 159.378337 -45.017648) (xy 159.332456 -44.988162)
			(xy 159.291239 -44.952447) (xy 159.255524 -44.91123) (xy 159.226038 -44.865349) (xy 159.203381 -44.815739)
			(xy 159.188016 -44.763409) (xy 159.180254 -44.709425) (xy 159.179768 -44.682156) (xy 156.72159 -44.682156)
			(xy 156.729056 -44.707583) (xy 156.736818 -44.761567) (xy 156.737304 -44.788836) (xy 156.737304 -45.652436)
			(xy 156.736818 -45.679705) (xy 156.729056 -45.733689) (xy 156.713691 -45.786019) (xy 156.691034 -45.835629)
			(xy 156.661548 -45.88151) (xy 156.625833 -45.922727) (xy 156.584616 -45.958442) (xy 156.538735 -45.987928)
			(xy 156.489125 -46.010585) (xy 156.436795 -46.02595) (xy 156.382811 -46.033712) (xy 156.328273 -46.033712)
			(xy 156.274289 -46.02595) (xy 156.221959 -46.010585) (xy 156.172349 -45.987928) (xy 156.126468 -45.958442)
			(xy 156.085251 -45.922727) (xy 156.049536 -45.88151) (xy 156.02005 -45.835629) (xy 155.997393 -45.786019)
			(xy 155.982028 -45.733689) (xy 155.974266 -45.679705) (xy 155.97378 -45.652436) (xy 97.038059 -45.652436)
			(xy 97.067693 -45.708092) (xy 97.133211 -45.848071) (xy 97.191435 -45.991237) (xy 97.242212 -46.13721)
			(xy 97.285407 -46.285604) (xy 97.320906 -46.436025) (xy 97.329238 -46.481746) (xy 178.630072 -46.481746)
			(xy 178.630072 -45.618146) (xy 178.630558 -45.590895) (xy 178.638314 -45.536947) (xy 178.653669 -45.484652)
			(xy 178.676311 -45.435075) (xy 178.705777 -45.389225) (xy 178.741468 -45.348034) (xy 178.782659 -45.312343)
			(xy 178.828509 -45.282877) (xy 178.878086 -45.260235) (xy 178.930381 -45.24488) (xy 178.984329 -45.237124)
			(xy 179.038831 -45.237124) (xy 179.092779 -45.24488) (xy 179.145074 -45.260235) (xy 179.194651 -45.282877)
			(xy 179.240501 -45.312343) (xy 179.281692 -45.348034) (xy 179.317383 -45.389225) (xy 179.346849 -45.435075)
			(xy 179.369491 -45.484652) (xy 179.384846 -45.536947) (xy 179.392602 -45.590895) (xy 179.393088 -45.618146)
			(xy 179.393088 -46.481746) (xy 179.392602 -46.508997) (xy 179.384846 -46.562945) (xy 179.369491 -46.61524)
			(xy 179.346849 -46.664817) (xy 179.317383 -46.710667) (xy 179.281692 -46.751858) (xy 179.240501 -46.787549)
			(xy 179.194651 -46.817015) (xy 179.145074 -46.839657) (xy 179.092779 -46.855012) (xy 179.038831 -46.862768)
			(xy 178.984329 -46.862768) (xy 178.930381 -46.855012) (xy 178.878086 -46.839657) (xy 178.828509 -46.817015)
			(xy 178.782659 -46.787549) (xy 178.741468 -46.751858) (xy 178.705777 -46.710667) (xy 178.676311 -46.664817)
			(xy 178.653669 -46.61524) (xy 178.638314 -46.562945) (xy 178.630558 -46.508997) (xy 178.630072 -46.481746)
			(xy 97.329238 -46.481746) (xy 97.348615 -46.588073) (xy 97.368459 -46.741347) (xy 97.380387 -46.895438)
			(xy 97.384366 -47.04994) (xy 97.380387 -47.204442) (xy 97.368459 -47.358533) (xy 97.348615 -47.511807)
			(xy 97.320906 -47.663855) (xy 97.285407 -47.814276) (xy 97.242212 -47.96267) (xy 97.239575 -47.97025)
			(xy 155.567386 -47.97025) (xy 155.567386 -47.91575) (xy 155.575142 -47.861805) (xy 155.590495 -47.809513)
			(xy 155.613135 -47.759938) (xy 155.642598 -47.71409) (xy 155.678287 -47.672901) (xy 155.719474 -47.63721)
			(xy 155.765321 -47.607744) (xy 155.814895 -47.585102) (xy 155.867186 -47.569746) (xy 155.92113 -47.561987)
			(xy 155.94838 -47.5615) (xy 156.81198 -47.5615) (xy 156.839234 -47.561946) (xy 156.893189 -47.569701)
			(xy 156.94549 -47.585055) (xy 156.995074 -47.607697) (xy 157.04093 -47.637165) (xy 157.082126 -47.67286)
			(xy 157.117823 -47.714054) (xy 157.147293 -47.759909) (xy 157.169938 -47.809491) (xy 157.185295 -47.861792)
			(xy 157.193053 -47.915746) (xy 157.193053 -47.970249) (xy 158.785586 -47.970249) (xy 158.785586 -47.915751)
			(xy 158.793341 -47.861808) (xy 158.808694 -47.809518) (xy 158.831331 -47.759944) (xy 158.860793 -47.714097)
			(xy 158.89648 -47.672908) (xy 158.937664 -47.637217) (xy 158.983509 -47.607751) (xy 159.03308 -47.585108)
			(xy 159.085369 -47.569749) (xy 159.139311 -47.561988) (xy 159.16656 -47.5615) (xy 160.03016 -47.5615)
			(xy 160.057415 -47.561945) (xy 160.111372 -47.569697) (xy 160.163675 -47.58505) (xy 160.213262 -47.607691)
			(xy 160.259121 -47.637158) (xy 160.300319 -47.672853) (xy 160.336018 -47.714047) (xy 160.36549 -47.759903)
			(xy 160.388136 -47.809487) (xy 160.403494 -47.861789) (xy 160.411253 -47.915745) (xy 160.411253 -47.970255)
			(xy 160.403494 -48.024211) (xy 160.402353 -48.028098) (xy 181.659784 -48.028098) (xy 181.659784 -47.164498)
			(xy 181.66027 -47.137247) (xy 181.668026 -47.083299) (xy 181.683381 -47.031004) (xy 181.706023 -46.981427)
			(xy 181.735489 -46.935577) (xy 181.77118 -46.894386) (xy 181.812371 -46.858695) (xy 181.858221 -46.829229)
			(xy 181.907798 -46.806587) (xy 181.960093 -46.791232) (xy 182.014041 -46.783476) (xy 182.068543 -46.783476)
			(xy 182.122491 -46.791232) (xy 182.174786 -46.806587) (xy 182.224363 -46.829229) (xy 182.225669 -46.830068)
			(xy 356.445326 -46.830068) (xy 356.445326 -46.775532) (xy 356.453087 -46.721552) (xy 356.468451 -46.669225)
			(xy 356.491104 -46.619618) (xy 356.520587 -46.573739) (xy 356.556298 -46.532522) (xy 356.597512 -46.496807)
			(xy 356.643388 -46.467321) (xy 356.692994 -46.444663) (xy 356.745319 -46.429294) (xy 356.799298 -46.421529)
			(xy 356.826566 -46.42104) (xy 357.690166 -46.42104) (xy 357.717439 -46.421497) (xy 357.77143 -46.429255)
			(xy 357.823767 -46.444619) (xy 357.873384 -46.467275) (xy 357.919272 -46.496761) (xy 357.960497 -46.532479)
			(xy 357.996218 -46.5737) (xy 358.025709 -46.619586) (xy 358.048369 -46.669202) (xy 358.063737 -46.721537)
			(xy 358.0715 -46.775527) (xy 358.0715 -46.830069) (xy 358.762026 -46.830069) (xy 358.762026 -46.775531)
			(xy 358.769788 -46.721547) (xy 358.785153 -46.669218) (xy 358.807809 -46.619608) (xy 358.837295 -46.573728)
			(xy 358.87301 -46.53251) (xy 358.914228 -46.496795) (xy 358.960108 -46.467309) (xy 359.009718 -46.444653)
			(xy 359.062047 -46.429288) (xy 359.116031 -46.421526) (xy 359.1433 -46.42104) (xy 360.0069 -46.42104)
			(xy 360.03417 -46.421522) (xy 360.088153 -46.429284) (xy 360.140483 -46.44465) (xy 360.190094 -46.467306)
			(xy 360.235975 -46.496792) (xy 360.277193 -46.532507) (xy 360.312908 -46.573725) (xy 360.342394 -46.619606)
			(xy 360.36505 -46.669217) (xy 360.380416 -46.721547) (xy 360.388178 -46.77553) (xy 360.388178 -46.83007)
			(xy 360.388178 -46.830073) (xy 361.088604 -46.830073) (xy 361.088604 -46.775527) (xy 361.096367 -46.721537)
			(xy 361.111735 -46.669202) (xy 361.134395 -46.619586) (xy 361.163887 -46.573701) (xy 361.199608 -46.53248)
			(xy 361.240833 -46.496763) (xy 361.286721 -46.467276) (xy 361.336339 -46.444621) (xy 361.388676 -46.429258)
			(xy 361.442667 -46.421501) (xy 361.46994 -46.42104) (xy 362.33354 -46.42104) (xy 362.360808 -46.421525)
			(xy 362.414787 -46.429291) (xy 362.467112 -46.44466) (xy 362.516718 -46.467319) (xy 362.562594 -46.496806)
			(xy 362.603807 -46.532522) (xy 362.639518 -46.573738) (xy 362.669 -46.619618) (xy 362.691654 -46.669225)
			(xy 362.707017 -46.721552) (xy 362.714778 -46.775532) (xy 362.714778 -46.830068) (xy 362.707017 -46.884048)
			(xy 362.691654 -46.936375) (xy 362.672751 -46.977768) (xy 396.642323 -46.977768) (xy 396.642323 -46.891996)
			(xy 396.650237 -46.806588) (xy 396.665998 -46.722276) (xy 396.689471 -46.639777) (xy 396.720456 -46.559796)
			(xy 396.758688 -46.483015) (xy 396.803842 -46.41009) (xy 396.855532 -46.341642) (xy 396.913317 -46.278255)
			(xy 396.976704 -46.22047) (xy 397.045152 -46.16878) (xy 397.118077 -46.123626) (xy 397.194858 -46.085394)
			(xy 397.274839 -46.054409) (xy 397.357338 -46.030936) (xy 397.44165 -46.015175) (xy 397.527058 -46.007261)
			(xy 397.61283 -46.007261) (xy 397.698238 -46.015175) (xy 397.78255 -46.030936) (xy 397.865049 -46.054409)
			(xy 397.94503 -46.085394) (xy 398.021811 -46.123626) (xy 398.094736 -46.16878) (xy 398.163184 -46.22047)
			(xy 398.226571 -46.278255) (xy 398.284356 -46.341642) (xy 398.336046 -46.41009) (xy 398.3812 -46.483015)
			(xy 398.419432 -46.559796) (xy 398.450417 -46.639777) (xy 398.47389 -46.722276) (xy 398.489651 -46.806588)
			(xy 398.497565 -46.891996) (xy 398.49806 -46.934882) (xy 398.497565 -46.977768) (xy 398.489651 -47.063176)
			(xy 398.47389 -47.147488) (xy 398.450417 -47.229987) (xy 398.419432 -47.309968) (xy 398.3812 -47.386749)
			(xy 398.336046 -47.459674) (xy 398.284356 -47.528122) (xy 398.226571 -47.591509) (xy 398.163184 -47.649294)
			(xy 398.094736 -47.700984) (xy 398.021811 -47.746138) (xy 397.94503 -47.78437) (xy 397.865049 -47.815355)
			(xy 397.78255 -47.838828) (xy 397.698238 -47.854589) (xy 397.61283 -47.862503) (xy 397.527058 -47.862503)
			(xy 397.44165 -47.854589) (xy 397.357338 -47.838828) (xy 397.274839 -47.815355) (xy 397.194858 -47.78437)
			(xy 397.118077 -47.746138) (xy 397.045152 -47.700984) (xy 396.976704 -47.649294) (xy 396.913317 -47.591509)
			(xy 396.855532 -47.528122) (xy 396.803842 -47.459674) (xy 396.758688 -47.386749) (xy 396.720456 -47.309968)
			(xy 396.689471 -47.229987) (xy 396.665998 -47.147488) (xy 396.650237 -47.063176) (xy 396.642323 -46.977768)
			(xy 362.672751 -46.977768) (xy 362.669 -46.985982) (xy 362.639518 -47.031862) (xy 362.603807 -47.073078)
			(xy 362.562594 -47.108794) (xy 362.516718 -47.138281) (xy 362.467112 -47.16094) (xy 362.414787 -47.176309)
			(xy 362.360808 -47.184075) (xy 362.33354 -47.184564) (xy 361.46994 -47.184564) (xy 361.442667 -47.184099)
			(xy 361.388676 -47.176342) (xy 361.336339 -47.160979) (xy 361.286721 -47.138324) (xy 361.240833 -47.108837)
			(xy 361.199608 -47.07312) (xy 361.163887 -47.031899) (xy 361.134395 -46.986014) (xy 361.111735 -46.936398)
			(xy 361.096367 -46.884063) (xy 361.088604 -46.830073) (xy 360.388178 -46.830073) (xy 360.380416 -46.884053)
			(xy 360.36505 -46.936383) (xy 360.342394 -46.985994) (xy 360.312908 -47.031875) (xy 360.277193 -47.073093)
			(xy 360.235975 -47.108808) (xy 360.190094 -47.138294) (xy 360.140483 -47.16095) (xy 360.088153 -47.176316)
			(xy 360.03417 -47.184078) (xy 360.0069 -47.184564) (xy 359.1433 -47.184564) (xy 359.116031 -47.184074)
			(xy 359.062047 -47.176312) (xy 359.009718 -47.160947) (xy 358.960108 -47.138291) (xy 358.914228 -47.108805)
			(xy 358.87301 -47.07309) (xy 358.837295 -47.031872) (xy 358.807809 -46.985992) (xy 358.785153 -46.936382)
			(xy 358.769788 -46.884053) (xy 358.762026 -46.830069) (xy 358.0715 -46.830069) (xy 358.0715 -46.830073)
			(xy 358.063737 -46.884063) (xy 358.048369 -46.936398) (xy 358.025709 -46.986014) (xy 357.996218 -47.0319)
			(xy 357.960497 -47.073121) (xy 357.919272 -47.108839) (xy 357.873384 -47.138325) (xy 357.823767 -47.160981)
			(xy 357.77143 -47.176345) (xy 357.717439 -47.184103) (xy 357.690166 -47.184564) (xy 356.826566 -47.184564)
			(xy 356.799298 -47.184071) (xy 356.745319 -47.176306) (xy 356.692994 -47.160937) (xy 356.643388 -47.138279)
			(xy 356.597512 -47.108793) (xy 356.556298 -47.073078) (xy 356.520587 -47.031861) (xy 356.491104 -46.985982)
			(xy 356.468451 -46.936375) (xy 356.453087 -46.884048) (xy 356.445326 -46.830068) (xy 182.225669 -46.830068)
			(xy 182.270213 -46.858695) (xy 182.311404 -46.894386) (xy 182.347095 -46.935577) (xy 182.376561 -46.981427)
			(xy 182.399203 -47.031004) (xy 182.414558 -47.083299) (xy 182.422314 -47.137247) (xy 182.4228 -47.164498)
			(xy 182.4228 -48.028098) (xy 182.422314 -48.055349) (xy 182.414558 -48.109297) (xy 182.399203 -48.161592)
			(xy 182.376561 -48.211169) (xy 182.347095 -48.257019) (xy 182.311404 -48.29821) (xy 182.270213 -48.333901)
			(xy 182.224363 -48.363367) (xy 182.174786 -48.386009) (xy 182.122491 -48.401364) (xy 182.068543 -48.40912)
			(xy 182.014041 -48.40912) (xy 181.960093 -48.401364) (xy 181.907798 -48.386009) (xy 181.858221 -48.363367)
			(xy 181.812371 -48.333901) (xy 181.77118 -48.29821) (xy 181.735489 -48.257019) (xy 181.706023 -48.211169)
			(xy 181.683381 -48.161592) (xy 181.668026 -48.109297) (xy 181.66027 -48.055349) (xy 181.659784 -48.028098)
			(xy 160.402353 -48.028098) (xy 160.388136 -48.076513) (xy 160.36549 -48.126097) (xy 160.336018 -48.171953)
			(xy 160.300319 -48.213147) (xy 160.259121 -48.248842) (xy 160.213262 -48.278309) (xy 160.163675 -48.30095)
			(xy 160.111372 -48.316303) (xy 160.057415 -48.324055) (xy 160.03016 -48.324516) (xy 159.16656 -48.324516)
			(xy 159.139311 -48.324012) (xy 159.085369 -48.316251) (xy 159.03308 -48.300892) (xy 158.983509 -48.278249)
			(xy 158.937664 -48.248783) (xy 158.89648 -48.213092) (xy 158.860793 -48.171903) (xy 158.831331 -48.126056)
			(xy 158.808694 -48.076482) (xy 158.793341 -48.024192) (xy 158.785586 -47.970249) (xy 157.193053 -47.970249)
			(xy 157.193053 -47.970254) (xy 157.185295 -48.024208) (xy 157.169938 -48.076509) (xy 157.147293 -48.126091)
			(xy 157.117823 -48.171946) (xy 157.082126 -48.21314) (xy 157.04093 -48.248835) (xy 156.995074 -48.278303)
			(xy 156.94549 -48.300945) (xy 156.893189 -48.316299) (xy 156.839234 -48.324054) (xy 156.81198 -48.324516)
			(xy 155.94838 -48.324516) (xy 155.92113 -48.324013) (xy 155.867186 -48.316254) (xy 155.814895 -48.300898)
			(xy 155.765321 -48.278256) (xy 155.719474 -48.24879) (xy 155.678287 -48.213099) (xy 155.642598 -48.17191)
			(xy 155.613135 -48.126062) (xy 155.590495 -48.076487) (xy 155.575142 -48.024195) (xy 155.567386 -47.97025)
			(xy 97.239575 -47.97025) (xy 97.191435 -48.108643) (xy 97.133211 -48.251809) (xy 97.067693 -48.391788)
			(xy 96.995057 -48.528208) (xy 96.915495 -48.660709) (xy 96.829216 -48.788937) (xy 96.736452 -48.912555)
			(xy 96.637446 -49.031233) (xy 96.532463 -49.144657) (xy 96.421779 -49.252526) (xy 96.30569 -49.354554)
			(xy 96.184502 -49.450471) (xy 96.140518 -49.48174) (xy 178.630072 -49.48174) (xy 178.630072 -48.61814)
			(xy 178.630558 -48.590889) (xy 178.638314 -48.536941) (xy 178.653669 -48.484646) (xy 178.676311 -48.435069)
			(xy 178.705777 -48.389219) (xy 178.741468 -48.348028) (xy 178.782659 -48.312337) (xy 178.828509 -48.282871)
			(xy 178.878086 -48.260229) (xy 178.930381 -48.244874) (xy 178.984329 -48.237118) (xy 179.038831 -48.237118)
			(xy 179.092779 -48.244874) (xy 179.145074 -48.260229) (xy 179.194651 -48.282871) (xy 179.240501 -48.312337)
			(xy 179.281692 -48.348028) (xy 179.317383 -48.389219) (xy 179.346849 -48.435069) (xy 179.369491 -48.484646)
			(xy 179.384846 -48.536941) (xy 179.392602 -48.590889) (xy 179.393088 -48.61814) (xy 179.393088 -49.48174)
			(xy 179.392602 -49.508991) (xy 179.384846 -49.562939) (xy 179.369491 -49.615234) (xy 179.346849 -49.664811)
			(xy 179.317383 -49.710661) (xy 179.281692 -49.751852) (xy 179.240501 -49.787543) (xy 179.194651 -49.817009)
			(xy 179.145074 -49.839651) (xy 179.092779 -49.855006) (xy 179.038831 -49.862762) (xy 178.984329 -49.862762)
			(xy 178.930381 -49.855006) (xy 178.878086 -49.839651) (xy 178.828509 -49.817009) (xy 178.782659 -49.787543)
			(xy 178.741468 -49.751852) (xy 178.705777 -49.710661) (xy 178.676311 -49.664811) (xy 178.653669 -49.615234)
			(xy 178.638314 -49.562939) (xy 178.630558 -49.508991) (xy 178.630072 -49.48174) (xy 96.140518 -49.48174)
			(xy 96.058537 -49.540022) (xy 95.928129 -49.62297) (xy 95.793624 -49.699095) (xy 95.655379 -49.768194)
			(xy 95.513759 -49.830085) (xy 95.369142 -49.884604) (xy 95.221909 -49.931606) (xy 95.072452 -49.970966)
			(xy 94.921168 -50.00258) (xy 94.768456 -50.026364) (xy 94.614722 -50.042255) (xy 94.460374 -50.050211)
			(xy 94.383098 -50.0507) (xy 92.782898 -50.0507) (xy 92.705622 -50.050194) (xy 92.551275 -50.042238)
			(xy 92.397543 -50.026347) (xy 92.244832 -50.002563) (xy 92.093548 -49.970949) (xy 91.944092 -49.931589)
			(xy 91.796861 -49.884587) (xy 91.652244 -49.830069) (xy 91.510626 -49.768178) (xy 91.372381 -49.699079)
			(xy 91.237877 -49.622954) (xy 91.10747 -49.540007) (xy 90.981506 -49.450456) (xy 90.860319 -49.35454)
			(xy 90.74423 -49.252512) (xy 90.633548 -49.144644) (xy 90.528565 -49.031221) (xy 90.42956 -48.912543)
			(xy 90.336796 -48.788927) (xy 90.250519 -48.660699) (xy 90.170957 -48.528199) (xy 90.098321 -48.391779)
			(xy 90.032804 -48.251802) (xy 89.97458 -48.108637) (xy 89.923803 -47.962664) (xy 89.880608 -47.814271)
			(xy 89.84511 -47.663852) (xy 89.817402 -47.511804) (xy 89.797557 -47.358531) (xy 89.78563 -47.204441)
			(xy 89.78165 -47.04994) (xy 67.384154 -47.04994) (xy 67.384157 -47.050067) (xy 67.380172 -47.204564)
			(xy 67.368238 -47.35865) (xy 67.348389 -47.511918) (xy 67.320675 -47.663961) (xy 67.285172 -47.814376)
			(xy 67.241973 -47.962763) (xy 67.191193 -48.108731) (xy 67.132966 -48.25189) (xy 67.067447 -48.391863)
			(xy 66.994809 -48.528277) (xy 66.915245 -48.660771) (xy 66.828966 -48.788993) (xy 66.736201 -48.912605)
			(xy 66.637196 -49.031277) (xy 66.532213 -49.144695) (xy 66.421531 -49.252559) (xy 66.305444 -49.354582)
			(xy 66.184258 -49.450493) (xy 66.058295 -49.54004) (xy 65.927891 -49.622983) (xy 65.793389 -49.699104)
			(xy 65.655147 -49.768199) (xy 65.513531 -49.830087) (xy 65.368918 -49.884603) (xy 65.22169 -49.931602)
			(xy 65.072237 -49.970961) (xy 64.920957 -50.002573) (xy 64.76825 -50.026356) (xy 64.614521 -50.042247)
			(xy 64.460178 -50.050202) (xy 64.382904 -50.0507) (xy 62.78245 -50.0507) (xy 62.705176 -50.050188)
			(xy 62.550834 -50.04222) (xy 62.397107 -50.026316) (xy 62.244402 -50.002521) (xy 62.093124 -49.970896)
			(xy 61.943675 -49.931526) (xy 61.796451 -49.884514) (xy 61.651842 -49.829987) (xy 61.510232 -49.768087)
			(xy 61.371996 -49.69898) (xy 61.2375 -49.622848) (xy 61.107102 -49.539894) (xy 60.981148 -49.450337)
			(xy 60.85997 -49.354416) (xy 60.743891 -49.252383) (xy 60.633218 -49.14451) (xy 60.528245 -49.031083)
			(xy 60.429249 -48.912403) (xy 60.336495 -48.788784) (xy 60.250227 -48.660555) (xy 60.170674 -48.528054)
			(xy 60.098048 -48.391634) (xy 60.032541 -48.251656) (xy 59.974326 -48.108492) (xy 59.923558 -47.96252)
			(xy 59.880371 -47.814129) (xy 59.844881 -47.663712) (xy 59.81718 -47.511667) (xy 59.797344 -47.358397)
			(xy 59.785423 -47.20431) (xy 59.781451 -47.049813) (xy 0.509016 -47.049813) (xy 0.509016 -50.949098)
			(xy 181.659784 -50.949098) (xy 181.659784 -50.085498) (xy 181.66027 -50.058247) (xy 181.668026 -50.004299)
			(xy 181.683381 -49.952004) (xy 181.706023 -49.902427) (xy 181.735489 -49.856577) (xy 181.77118 -49.815386)
			(xy 181.812371 -49.779695) (xy 181.858221 -49.750229) (xy 181.907798 -49.727587) (xy 181.960093 -49.712232)
			(xy 182.014041 -49.704476) (xy 182.068543 -49.704476) (xy 182.122491 -49.712232) (xy 182.174786 -49.727587)
			(xy 182.224363 -49.750229) (xy 182.270213 -49.779695) (xy 182.311404 -49.815386) (xy 182.347095 -49.856577)
			(xy 182.376561 -49.902427) (xy 182.399203 -49.952004) (xy 182.414558 -50.004299) (xy 182.422314 -50.058247)
			(xy 182.4228 -50.085498) (xy 182.4228 -50.949098) (xy 182.422314 -50.976349) (xy 182.414558 -51.030297)
			(xy 182.399203 -51.082592) (xy 182.376561 -51.132169) (xy 182.347095 -51.178019) (xy 182.311404 -51.21921)
			(xy 182.270213 -51.254901) (xy 182.224363 -51.284367) (xy 182.174786 -51.307009) (xy 182.122491 -51.322364)
			(xy 182.068543 -51.33012) (xy 182.014041 -51.33012) (xy 181.960093 -51.322364) (xy 181.907798 -51.307009)
			(xy 181.858221 -51.284367) (xy 181.812371 -51.254901) (xy 181.77118 -51.21921) (xy 181.735489 -51.178019)
			(xy 181.706023 -51.132169) (xy 181.683381 -51.082592) (xy 181.668026 -51.030297) (xy 181.66027 -50.976349)
			(xy 181.659784 -50.949098) (xy 0.509016 -50.949098) (xy 0.509016 -52.481734) (xy 178.630072 -52.481734)
			(xy 178.630072 -51.618134) (xy 178.630558 -51.590883) (xy 178.638314 -51.536935) (xy 178.653669 -51.48464)
			(xy 178.676311 -51.435063) (xy 178.705777 -51.389213) (xy 178.741468 -51.348022) (xy 178.782659 -51.312331)
			(xy 178.828509 -51.282865) (xy 178.878086 -51.260223) (xy 178.930381 -51.244868) (xy 178.984329 -51.237112)
			(xy 179.038831 -51.237112) (xy 179.092779 -51.244868) (xy 179.145074 -51.260223) (xy 179.194651 -51.282865)
			(xy 179.240501 -51.312331) (xy 179.281692 -51.348022) (xy 179.317383 -51.389213) (xy 179.346849 -51.435063)
			(xy 179.369491 -51.48464) (xy 179.384846 -51.536935) (xy 179.392602 -51.590883) (xy 179.393088 -51.618134)
			(xy 179.393088 -51.999896) (xy 201.367397 -51.999896) (xy 201.371407 -51.837793) (xy 201.38343 -51.676088)
			(xy 201.403434 -51.515174) (xy 201.431372 -51.355447) (xy 201.467175 -51.197297) (xy 201.510755 -51.041111)
			(xy 201.562006 -50.887271) (xy 201.620802 -50.736154) (xy 201.687 -50.58813) (xy 201.760436 -50.44356)
			(xy 201.840933 -50.302799) (xy 201.928292 -50.166191) (xy 202.0223 -50.034071) (xy 202.122727 -49.906761)
			(xy 202.229327 -49.784573) (xy 202.341839 -49.667807) (xy 202.459987 -49.556748) (xy 202.583484 -49.451667)
			(xy 202.712026 -49.352823) (xy 202.845299 -49.260456) (xy 202.982977 -49.174793) (xy 203.124723 -49.096044)
			(xy 203.27019 -49.024401) (xy 203.419022 -48.960039) (xy 203.570854 -48.903117) (xy 203.725316 -48.853773)
			(xy 203.882029 -48.812128) (xy 204.04061 -48.778283) (xy 204.200671 -48.752323) (xy 204.361819 -48.73431)
			(xy 204.523661 -48.724289) (xy 204.685801 -48.722283) (xy 204.847842 -48.728299) (xy 205.009386 -48.74232)
			(xy 205.17004 -48.764313) (xy 205.32941 -48.794225) (xy 205.487105 -48.831981) (xy 205.64274 -48.877489)
			(xy 205.795934 -48.930639) (xy 205.946312 -48.9913) (xy 206.093507 -49.059323) (xy 206.237157 -49.134542)
			(xy 206.376912 -49.216773) (xy 206.512428 -49.305815) (xy 206.643376 -49.40145) (xy 206.769434 -49.503444)
			(xy 206.890294 -49.611547) (xy 207.00566 -49.725494) (xy 207.115249 -49.845008) (xy 207.218794 -49.969795)
			(xy 207.316041 -50.09955) (xy 207.406753 -50.233955) (xy 207.424818 -50.263806) (xy 239.457992 -50.263806)
			(xy 239.457992 -49.400206) (xy 239.458478 -49.372955) (xy 239.466234 -49.319007) (xy 239.481589 -49.266712)
			(xy 239.504231 -49.217135) (xy 239.533697 -49.171285) (xy 239.569388 -49.130094) (xy 239.610579 -49.094403)
			(xy 239.656429 -49.064937) (xy 239.706006 -49.042295) (xy 239.758301 -49.02694) (xy 239.812249 -49.019184)
			(xy 239.866751 -49.019184) (xy 239.920699 -49.02694) (xy 239.972994 -49.042295) (xy 240.022571 -49.064937)
			(xy 240.068421 -49.094403) (xy 240.109612 -49.130094) (xy 240.145303 -49.171285) (xy 240.174769 -49.217135)
			(xy 240.197411 -49.266712) (xy 240.212766 -49.319007) (xy 240.220522 -49.372955) (xy 240.221008 -49.400206)
			(xy 240.221008 -50.263806) (xy 240.220522 -50.291057) (xy 240.212766 -50.345005) (xy 240.197411 -50.3973)
			(xy 240.174769 -50.446877) (xy 240.145303 -50.492727) (xy 240.109612 -50.533918) (xy 240.068421 -50.569609)
			(xy 240.022571 -50.599075) (xy 239.972994 -50.621717) (xy 239.920699 -50.637072) (xy 239.866751 -50.644828)
			(xy 239.812249 -50.644828) (xy 239.758301 -50.637072) (xy 239.706006 -50.621717) (xy 239.656429 -50.599075)
			(xy 239.610579 -50.569609) (xy 239.569388 -50.533918) (xy 239.533697 -50.492727) (xy 239.504231 -50.446877)
			(xy 239.481589 -50.3973) (xy 239.466234 -50.345005) (xy 239.458478 -50.291057) (xy 239.457992 -50.263806)
			(xy 207.424818 -50.263806) (xy 207.490706 -50.372682) (xy 207.567696 -50.515391) (xy 207.637535 -50.661732)
			(xy 207.70005 -50.811349) (xy 207.755091 -50.963874) (xy 207.802521 -51.118934) (xy 207.842224 -51.27615)
			(xy 207.874105 -51.435138) (xy 207.898083 -51.595507) (xy 207.914102 -51.756866) (xy 207.922121 -51.91882)
			(xy 207.922622 -51.999896) (xy 207.922121 -52.080972) (xy 207.914102 -52.242926) (xy 207.898083 -52.404285)
			(xy 207.874105 -52.564654) (xy 207.842224 -52.723642) (xy 207.802521 -52.880858) (xy 207.794624 -52.906676)
			(xy 228.815392 -52.906676) (xy 228.815392 -52.043076) (xy 228.815878 -52.015825) (xy 228.823634 -51.961877)
			(xy 228.838989 -51.909582) (xy 228.861631 -51.860005) (xy 228.891097 -51.814155) (xy 228.926788 -51.772964)
			(xy 228.967979 -51.737273) (xy 229.013829 -51.707807) (xy 229.063406 -51.685165) (xy 229.115701 -51.66981)
			(xy 229.169649 -51.662054) (xy 229.224151 -51.662054) (xy 229.278099 -51.66981) (xy 229.330394 -51.685165)
			(xy 229.379971 -51.707807) (xy 229.425821 -51.737273) (xy 229.467012 -51.772964) (xy 229.502703 -51.814155)
			(xy 229.532169 -51.860005) (xy 229.554811 -51.909582) (xy 229.570166 -51.961877) (xy 229.577922 -52.015825)
			(xy 229.578408 -52.043076) (xy 229.578408 -52.90185) (xy 241.926872 -52.90185) (xy 241.926872 -52.03825)
			(xy 241.927358 -52.010999) (xy 241.935114 -51.957051) (xy 241.950469 -51.904756) (xy 241.973111 -51.855179)
			(xy 242.002577 -51.809329) (xy 242.038268 -51.768138) (xy 242.079459 -51.732447) (xy 242.125309 -51.702981)
			(xy 242.174886 -51.680339) (xy 242.227181 -51.664984) (xy 242.281129 -51.657228) (xy 242.335631 -51.657228)
			(xy 242.389579 -51.664984) (xy 242.441874 -51.680339) (xy 242.491451 -51.702981) (xy 242.537301 -51.732447)
			(xy 242.578492 -51.768138) (xy 242.614183 -51.809329) (xy 242.643649 -51.855179) (xy 242.666291 -51.904756)
			(xy 242.681646 -51.957051) (xy 242.687806 -51.999896) (xy 265.367269 -51.999896) (xy 265.371279 -51.837793)
			(xy 265.383302 -51.676088) (xy 265.403306 -51.515174) (xy 265.431244 -51.355447) (xy 265.467047 -51.197297)
			(xy 265.510627 -51.041111) (xy 265.561878 -50.887271) (xy 265.620674 -50.736154) (xy 265.686872 -50.58813)
			(xy 265.760308 -50.44356) (xy 265.840805 -50.302799) (xy 265.928164 -50.166191) (xy 266.022172 -50.034071)
			(xy 266.122599 -49.906761) (xy 266.229199 -49.784573) (xy 266.341711 -49.667807) (xy 266.459859 -49.556748)
			(xy 266.583356 -49.451667) (xy 266.711898 -49.352823) (xy 266.845171 -49.260456) (xy 266.982849 -49.174793)
			(xy 267.124595 -49.096044) (xy 267.270062 -49.024401) (xy 267.418894 -48.960039) (xy 267.570726 -48.903117)
			(xy 267.725188 -48.853773) (xy 267.881901 -48.812128) (xy 268.040482 -48.778283) (xy 268.200543 -48.752323)
			(xy 268.361691 -48.73431) (xy 268.523533 -48.724289) (xy 268.685673 -48.722283) (xy 268.847714 -48.728299)
			(xy 269.009258 -48.74232) (xy 269.169912 -48.764313) (xy 269.329282 -48.794225) (xy 269.486977 -48.831981)
			(xy 269.642612 -48.877489) (xy 269.795806 -48.930639) (xy 269.946184 -48.9913) (xy 270.093379 -49.059323)
			(xy 270.237029 -49.134542) (xy 270.376784 -49.216773) (xy 270.5123 -49.305815) (xy 270.643248 -49.40145)
			(xy 270.769306 -49.503444) (xy 270.890166 -49.611547) (xy 271.005532 -49.725494) (xy 271.115121 -49.845008)
			(xy 271.218666 -49.969795) (xy 271.315913 -50.09955) (xy 271.406625 -50.233955) (xy 271.40723 -50.234955)
			(xy 350.291827 -50.234955) (xy 350.291827 -50.180445) (xy 350.299585 -50.126489) (xy 350.314942 -50.074187)
			(xy 350.337587 -50.024602) (xy 350.367058 -49.978745) (xy 350.402755 -49.937549) (xy 350.443952 -49.901853)
			(xy 350.489809 -49.872383) (xy 350.539394 -49.849739) (xy 350.591697 -49.834383) (xy 350.645653 -49.826626)
			(xy 350.672908 -49.826164) (xy 351.536508 -49.826164) (xy 351.563757 -49.826707) (xy 351.6177 -49.834464)
			(xy 351.66999 -49.849818) (xy 351.719562 -49.872458) (xy 351.765408 -49.901922) (xy 351.806594 -49.937611)
			(xy 351.842282 -49.978798) (xy 351.871746 -50.024645) (xy 351.894385 -50.074218) (xy 351.909738 -50.126508)
			(xy 351.917494 -50.180451) (xy 351.917494 -50.234949) (xy 351.917493 -50.234956) (xy 352.489927 -50.234956)
			(xy 352.489927 -50.180444) (xy 352.497685 -50.126487) (xy 352.513044 -50.074183) (xy 352.535689 -50.024598)
			(xy 352.565162 -49.97874) (xy 352.600861 -49.937544) (xy 352.642059 -49.901848) (xy 352.687919 -49.872378)
			(xy 352.737506 -49.849735) (xy 352.78981 -49.83438) (xy 352.843768 -49.826625) (xy 352.871024 -49.826164)
			(xy 353.734624 -49.826164) (xy 353.761872 -49.826708) (xy 353.815813 -49.834467) (xy 353.868101 -49.849823)
			(xy 353.917672 -49.872463) (xy 353.963516 -49.901928) (xy 354.0047 -49.937617) (xy 354.040386 -49.978804)
			(xy 354.069848 -50.024649) (xy 354.092486 -50.074221) (xy 354.107839 -50.12651) (xy 354.115594 -50.180452)
			(xy 354.115594 -50.234948) (xy 354.115593 -50.234956) (xy 354.712427 -50.234956) (xy 354.712427 -50.180444)
			(xy 354.720185 -50.126487) (xy 354.735544 -50.074183) (xy 354.758189 -50.024598) (xy 354.787662 -49.97874)
			(xy 354.823361 -49.937544) (xy 354.864559 -49.901848) (xy 354.910419 -49.872378) (xy 354.960006 -49.849735)
			(xy 355.01231 -49.83438) (xy 355.066268 -49.826625) (xy 355.093524 -49.826164) (xy 355.957124 -49.826164)
			(xy 355.984372 -49.826708) (xy 356.038313 -49.834467) (xy 356.090601 -49.849823) (xy 356.140172 -49.872463)
			(xy 356.186016 -49.901928) (xy 356.2272 -49.937617) (xy 356.262886 -49.978804) (xy 356.292348 -50.024649)
			(xy 356.314986 -50.074221) (xy 356.330339 -50.12651) (xy 356.338094 -50.180452) (xy 356.338094 -50.234948)
			(xy 356.338093 -50.234957) (xy 356.942527 -50.234957) (xy 356.942527 -50.180443) (xy 356.950286 -50.126484)
			(xy 356.965645 -50.074179) (xy 356.988293 -50.024592) (xy 357.017767 -49.978734) (xy 357.053468 -49.937537)
			(xy 357.094669 -49.90184) (xy 357.140531 -49.872371) (xy 357.19012 -49.84973) (xy 357.242427 -49.834376)
			(xy 357.296387 -49.826624) (xy 357.323644 -49.826164) (xy 358.187244 -49.826164) (xy 358.214491 -49.826709)
			(xy 358.26843 -49.83447) (xy 358.320716 -49.849828) (xy 358.370284 -49.87247) (xy 358.416125 -49.901935)
			(xy 358.457307 -49.937624) (xy 358.492991 -49.97881) (xy 358.522451 -50.024655) (xy 358.545087 -50.074226)
			(xy 358.560439 -50.126513) (xy 358.568194 -50.180453) (xy 358.568194 -50.234947) (xy 358.560439 -50.288887)
			(xy 358.545087 -50.341174) (xy 358.522451 -50.390745) (xy 358.492991 -50.43659) (xy 358.457307 -50.477776)
			(xy 358.416125 -50.513465) (xy 358.370284 -50.54293) (xy 358.320716 -50.565572) (xy 358.26843 -50.58093)
			(xy 358.214491 -50.588691) (xy 358.187244 -50.58918) (xy 357.323644 -50.58918) (xy 357.296387 -50.588776)
			(xy 357.242427 -50.581024) (xy 357.19012 -50.56567) (xy 357.140531 -50.543029) (xy 357.094669 -50.51356)
			(xy 357.053468 -50.477863) (xy 357.017767 -50.436666) (xy 356.988293 -50.390808) (xy 356.965645 -50.341221)
			(xy 356.950286 -50.288916) (xy 356.942527 -50.234957) (xy 356.338093 -50.234957) (xy 356.330339 -50.28889)
			(xy 356.314986 -50.341179) (xy 356.292348 -50.390751) (xy 356.262886 -50.436596) (xy 356.2272 -50.477783)
			(xy 356.186016 -50.513472) (xy 356.140172 -50.542937) (xy 356.090601 -50.565577) (xy 356.038313 -50.580933)
			(xy 355.984372 -50.588692) (xy 355.957124 -50.58918) (xy 355.093524 -50.58918) (xy 355.066268 -50.588775)
			(xy 355.01231 -50.58102) (xy 354.960006 -50.565665) (xy 354.910419 -50.543022) (xy 354.864559 -50.513552)
			(xy 354.823361 -50.477856) (xy 354.787662 -50.43666) (xy 354.758189 -50.390802) (xy 354.735544 -50.341217)
			(xy 354.720185 -50.288913) (xy 354.712427 -50.234956) (xy 354.115593 -50.234956) (xy 354.107839 -50.28889)
			(xy 354.092486 -50.341179) (xy 354.069848 -50.390751) (xy 354.040386 -50.436596) (xy 354.0047 -50.477783)
			(xy 353.963516 -50.513472) (xy 353.917672 -50.542937) (xy 353.868101 -50.565577) (xy 353.815813 -50.580933)
			(xy 353.761872 -50.588692) (xy 353.734624 -50.58918) (xy 352.871024 -50.58918) (xy 352.843768 -50.588775)
			(xy 352.78981 -50.58102) (xy 352.737506 -50.565665) (xy 352.687919 -50.543022) (xy 352.642059 -50.513552)
			(xy 352.600861 -50.477856) (xy 352.565162 -50.43666) (xy 352.535689 -50.390802) (xy 352.513044 -50.341217)
			(xy 352.497685 -50.288913) (xy 352.489927 -50.234956) (xy 351.917493 -50.234956) (xy 351.909738 -50.288892)
			(xy 351.894385 -50.341182) (xy 351.871746 -50.390755) (xy 351.842282 -50.436602) (xy 351.806594 -50.477789)
			(xy 351.765408 -50.513477) (xy 351.719562 -50.542942) (xy 351.66999 -50.565582) (xy 351.6177 -50.580936)
			(xy 351.563757 -50.588693) (xy 351.536508 -50.58918) (xy 350.672908 -50.58918) (xy 350.645653 -50.588774)
			(xy 350.591697 -50.581017) (xy 350.539394 -50.565661) (xy 350.489809 -50.543017) (xy 350.443952 -50.513547)
			(xy 350.402755 -50.477851) (xy 350.367058 -50.436655) (xy 350.337587 -50.390798) (xy 350.314942 -50.341213)
			(xy 350.299585 -50.288911) (xy 350.291827 -50.234955) (xy 271.40723 -50.234955) (xy 271.490578 -50.372682)
			(xy 271.567568 -50.515391) (xy 271.637407 -50.661732) (xy 271.699922 -50.811349) (xy 271.754963 -50.963874)
			(xy 271.802393 -51.118934) (xy 271.842096 -51.27615) (xy 271.873977 -51.435138) (xy 271.897955 -51.595507)
			(xy 271.913974 -51.756866) (xy 271.921993 -51.91882) (xy 271.922494 -51.999896) (xy 271.921993 -52.080972)
			(xy 271.913974 -52.242926) (xy 271.897955 -52.404285) (xy 271.873977 -52.564654) (xy 271.842096 -52.723642)
			(xy 271.802393 -52.880858) (xy 271.754963 -53.035918) (xy 271.699922 -53.188443) (xy 271.637407 -53.33806)
			(xy 271.567568 -53.484401) (xy 271.490578 -53.62711) (xy 271.406625 -53.765837) (xy 271.315913 -53.900242)
			(xy 271.218666 -54.029997) (xy 271.115121 -54.154784) (xy 271.005532 -54.274298) (xy 270.890166 -54.388245)
			(xy 270.769306 -54.496348) (xy 270.643248 -54.598342) (xy 270.5123 -54.693977) (xy 270.376784 -54.783019)
			(xy 270.237029 -54.86525) (xy 270.093379 -54.940469) (xy 269.946184 -55.008492) (xy 269.795806 -55.069153)
			(xy 269.642612 -55.122303) (xy 269.486977 -55.167811) (xy 269.329282 -55.205567) (xy 269.169912 -55.235479)
			(xy 269.009258 -55.257472) (xy 268.847714 -55.271493) (xy 268.685673 -55.277509) (xy 268.523533 -55.275503)
			(xy 268.361691 -55.265482) (xy 268.200543 -55.247469) (xy 268.040482 -55.221509) (xy 267.881901 -55.187664)
			(xy 267.725188 -55.146019) (xy 267.570726 -55.096675) (xy 267.418894 -55.039753) (xy 267.270062 -54.975391)
			(xy 267.124595 -54.903748) (xy 266.982849 -54.824999) (xy 266.845171 -54.739336) (xy 266.711898 -54.646969)
			(xy 266.583356 -54.548125) (xy 266.459859 -54.443044) (xy 266.341711 -54.331985) (xy 266.229199 -54.215219)
			(xy 266.122599 -54.093031) (xy 266.022172 -53.965721) (xy 265.928164 -53.833601) (xy 265.840805 -53.696993)
			(xy 265.760308 -53.556232) (xy 265.686872 -53.411662) (xy 265.620674 -53.263638) (xy 265.561878 -53.112521)
			(xy 265.510627 -52.958681) (xy 265.467047 -52.802495) (xy 265.431244 -52.644345) (xy 265.403306 -52.484618)
			(xy 265.383302 -52.323704) (xy 265.371279 -52.161999) (xy 265.367269 -51.999896) (xy 242.687806 -51.999896)
			(xy 242.689402 -52.010999) (xy 242.689888 -52.03825) (xy 242.689888 -52.90185) (xy 242.689402 -52.929101)
			(xy 242.681646 -52.983049) (xy 242.666291 -53.035344) (xy 242.643649 -53.084921) (xy 242.614183 -53.130771)
			(xy 242.578492 -53.171962) (xy 242.537301 -53.207653) (xy 242.491451 -53.237119) (xy 242.441874 -53.259761)
			(xy 242.389579 -53.275116) (xy 242.335631 -53.282872) (xy 242.281129 -53.282872) (xy 242.227181 -53.275116)
			(xy 242.174886 -53.259761) (xy 242.125309 -53.237119) (xy 242.079459 -53.207653) (xy 242.038268 -53.171962)
			(xy 242.002577 -53.130771) (xy 241.973111 -53.084921) (xy 241.950469 -53.035344) (xy 241.935114 -52.983049)
			(xy 241.927358 -52.929101) (xy 241.926872 -52.90185) (xy 229.578408 -52.90185) (xy 229.578408 -52.906676)
			(xy 229.577922 -52.933927) (xy 229.570166 -52.987875) (xy 229.554811 -53.04017) (xy 229.532169 -53.089747)
			(xy 229.502703 -53.135597) (xy 229.467012 -53.176788) (xy 229.425821 -53.212479) (xy 229.379971 -53.241945)
			(xy 229.330394 -53.264587) (xy 229.278099 -53.279942) (xy 229.224151 -53.287698) (xy 229.169649 -53.287698)
			(xy 229.115701 -53.279942) (xy 229.063406 -53.264587) (xy 229.013829 -53.241945) (xy 228.967979 -53.212479)
			(xy 228.926788 -53.176788) (xy 228.891097 -53.135597) (xy 228.861631 -53.089747) (xy 228.838989 -53.04017)
			(xy 228.823634 -52.987875) (xy 228.815878 -52.933927) (xy 228.815392 -52.906676) (xy 207.794624 -52.906676)
			(xy 207.755091 -53.035918) (xy 207.70005 -53.188443) (xy 207.637535 -53.33806) (xy 207.567696 -53.484401)
			(xy 207.490706 -53.62711) (xy 207.406753 -53.765837) (xy 207.316041 -53.900242) (xy 207.218794 -54.029997)
			(xy 207.115249 -54.154784) (xy 207.00566 -54.274298) (xy 206.890294 -54.388245) (xy 206.769434 -54.496348)
			(xy 206.643376 -54.598342) (xy 206.512428 -54.693977) (xy 206.493338 -54.70652) (xy 230.115872 -54.70652)
			(xy 230.115872 -53.84292) (xy 230.116358 -53.815669) (xy 230.124114 -53.761721) (xy 230.139469 -53.709426)
			(xy 230.162111 -53.659849) (xy 230.191577 -53.613999) (xy 230.227268 -53.572808) (xy 230.268459 -53.537117)
			(xy 230.314309 -53.507651) (xy 230.363886 -53.485009) (xy 230.416181 -53.469654) (xy 230.470129 -53.461898)
			(xy 230.524631 -53.461898) (xy 230.578579 -53.469654) (xy 230.630874 -53.485009) (xy 230.680451 -53.507651)
			(xy 230.726301 -53.537117) (xy 230.767492 -53.572808) (xy 230.803183 -53.613999) (xy 230.832649 -53.659849)
			(xy 230.855291 -53.709426) (xy 230.870646 -53.761721) (xy 230.878402 -53.815669) (xy 230.878888 -53.84292)
			(xy 230.878888 -54.70652) (xy 230.878811 -54.710838) (xy 240.282476 -54.710838) (xy 240.282476 -53.847238)
			(xy 240.282962 -53.819987) (xy 240.290718 -53.766039) (xy 240.306073 -53.713744) (xy 240.328715 -53.664167)
			(xy 240.358181 -53.618317) (xy 240.393872 -53.577126) (xy 240.435063 -53.541435) (xy 240.480913 -53.511969)
			(xy 240.53049 -53.489327) (xy 240.582785 -53.473972) (xy 240.636733 -53.466216) (xy 240.691235 -53.466216)
			(xy 240.745183 -53.473972) (xy 240.797478 -53.489327) (xy 240.847055 -53.511969) (xy 240.892905 -53.541435)
			(xy 240.934096 -53.577126) (xy 240.969787 -53.618317) (xy 240.999253 -53.664167) (xy 241.021895 -53.713744)
			(xy 241.03725 -53.766039) (xy 241.045006 -53.819987) (xy 241.045492 -53.847238) (xy 241.045492 -54.710838)
			(xy 241.045006 -54.738089) (xy 241.03725 -54.792037) (xy 241.021895 -54.844332) (xy 240.999253 -54.893909)
			(xy 240.969787 -54.939759) (xy 240.934096 -54.98095) (xy 240.892905 -55.016641) (xy 240.847055 -55.046107)
			(xy 240.797478 -55.068749) (xy 240.745183 -55.084104) (xy 240.691235 -55.09186) (xy 240.636733 -55.09186)
			(xy 240.582785 -55.084104) (xy 240.53049 -55.068749) (xy 240.480913 -55.046107) (xy 240.435063 -55.016641)
			(xy 240.393872 -54.98095) (xy 240.358181 -54.939759) (xy 240.328715 -54.893909) (xy 240.306073 -54.844332)
			(xy 240.290718 -54.792037) (xy 240.282962 -54.738089) (xy 240.282476 -54.710838) (xy 230.878811 -54.710838)
			(xy 230.878402 -54.733771) (xy 230.870646 -54.787719) (xy 230.855291 -54.840014) (xy 230.832649 -54.889591)
			(xy 230.803183 -54.935441) (xy 230.767492 -54.976632) (xy 230.726301 -55.012323) (xy 230.680451 -55.041789)
			(xy 230.630874 -55.064431) (xy 230.578579 -55.079786) (xy 230.524631 -55.087542) (xy 230.470129 -55.087542)
			(xy 230.416181 -55.079786) (xy 230.363886 -55.064431) (xy 230.314309 -55.041789) (xy 230.268459 -55.012323)
			(xy 230.227268 -54.976632) (xy 230.191577 -54.935441) (xy 230.162111 -54.889591) (xy 230.139469 -54.840014)
			(xy 230.124114 -54.787719) (xy 230.116358 -54.733771) (xy 230.115872 -54.70652) (xy 206.493338 -54.70652)
			(xy 206.376912 -54.783019) (xy 206.237157 -54.86525) (xy 206.093507 -54.940469) (xy 205.946312 -55.008492)
			(xy 205.795934 -55.069153) (xy 205.64274 -55.122303) (xy 205.487105 -55.167811) (xy 205.32941 -55.205567)
			(xy 205.17004 -55.235479) (xy 205.009386 -55.257472) (xy 204.847842 -55.271493) (xy 204.685801 -55.277509)
			(xy 204.523661 -55.275503) (xy 204.361819 -55.265482) (xy 204.200671 -55.247469) (xy 204.04061 -55.221509)
			(xy 203.882029 -55.187664) (xy 203.725316 -55.146019) (xy 203.570854 -55.096675) (xy 203.419022 -55.039753)
			(xy 203.27019 -54.975391) (xy 203.124723 -54.903748) (xy 202.982977 -54.824999) (xy 202.845299 -54.739336)
			(xy 202.712026 -54.646969) (xy 202.583484 -54.548125) (xy 202.459987 -54.443044) (xy 202.341839 -54.331985)
			(xy 202.229327 -54.215219) (xy 202.122727 -54.093031) (xy 202.0223 -53.965721) (xy 201.928292 -53.833601)
			(xy 201.840933 -53.696993) (xy 201.760436 -53.556232) (xy 201.687 -53.411662) (xy 201.620802 -53.263638)
			(xy 201.562006 -53.112521) (xy 201.510755 -52.958681) (xy 201.467175 -52.802495) (xy 201.431372 -52.644345)
			(xy 201.403434 -52.484618) (xy 201.38343 -52.323704) (xy 201.371407 -52.161999) (xy 201.367397 -51.999896)
			(xy 179.393088 -51.999896) (xy 179.393088 -52.481734) (xy 179.392602 -52.508985) (xy 179.384846 -52.562933)
			(xy 179.369491 -52.615228) (xy 179.346849 -52.664805) (xy 179.317383 -52.710655) (xy 179.281692 -52.751846)
			(xy 179.240501 -52.787537) (xy 179.194651 -52.817003) (xy 179.145074 -52.839645) (xy 179.092779 -52.855)
			(xy 179.038831 -52.862756) (xy 178.984329 -52.862756) (xy 178.930381 -52.855) (xy 178.878086 -52.839645)
			(xy 178.828509 -52.817003) (xy 178.782659 -52.787537) (xy 178.741468 -52.751846) (xy 178.705777 -52.710655)
			(xy 178.676311 -52.664805) (xy 178.653669 -52.615228) (xy 178.638314 -52.562933) (xy 178.630558 -52.508985)
			(xy 178.630072 -52.481734) (xy 0.509016 -52.481734) (xy 0.509016 -53.954934) (xy 181.659784 -53.954934)
			(xy 181.659784 -53.091334) (xy 181.66027 -53.064083) (xy 181.668026 -53.010135) (xy 181.683381 -52.95784)
			(xy 181.706023 -52.908263) (xy 181.735489 -52.862413) (xy 181.77118 -52.821222) (xy 181.812371 -52.785531)
			(xy 181.858221 -52.756065) (xy 181.907798 -52.733423) (xy 181.960093 -52.718068) (xy 182.014041 -52.710312)
			(xy 182.068543 -52.710312) (xy 182.122491 -52.718068) (xy 182.174786 -52.733423) (xy 182.224363 -52.756065)
			(xy 182.270213 -52.785531) (xy 182.311404 -52.821222) (xy 182.347095 -52.862413) (xy 182.376561 -52.908263)
			(xy 182.399203 -52.95784) (xy 182.414558 -53.010135) (xy 182.422314 -53.064083) (xy 182.4228 -53.091334)
			(xy 182.4228 -53.954934) (xy 182.422314 -53.982185) (xy 182.414558 -54.036133) (xy 182.399203 -54.088428)
			(xy 182.376561 -54.138005) (xy 182.347095 -54.183855) (xy 182.311404 -54.225046) (xy 182.270213 -54.260737)
			(xy 182.224363 -54.290203) (xy 182.174786 -54.312845) (xy 182.122491 -54.3282) (xy 182.068543 -54.335956)
			(xy 182.014041 -54.335956) (xy 181.960093 -54.3282) (xy 181.907798 -54.312845) (xy 181.858221 -54.290203)
			(xy 181.812371 -54.260737) (xy 181.77118 -54.225046) (xy 181.735489 -54.183855) (xy 181.706023 -54.138005)
			(xy 181.683381 -54.088428) (xy 181.668026 -54.036133) (xy 181.66027 -53.982185) (xy 181.659784 -53.954934)
			(xy 0.509016 -53.954934) (xy 0.509016 -55.481728) (xy 178.630072 -55.481728) (xy 178.630072 -54.618128)
			(xy 178.630558 -54.590877) (xy 178.638314 -54.536929) (xy 178.653669 -54.484634) (xy 178.676311 -54.435057)
			(xy 178.705777 -54.389207) (xy 178.741468 -54.348016) (xy 178.782659 -54.312325) (xy 178.828509 -54.282859)
			(xy 178.878086 -54.260217) (xy 178.930381 -54.244862) (xy 178.984329 -54.237106) (xy 179.038831 -54.237106)
			(xy 179.092779 -54.244862) (xy 179.145074 -54.260217) (xy 179.194651 -54.282859) (xy 179.240501 -54.312325)
			(xy 179.281692 -54.348016) (xy 179.317383 -54.389207) (xy 179.346849 -54.435057) (xy 179.369491 -54.484634)
			(xy 179.384846 -54.536929) (xy 179.392602 -54.590877) (xy 179.393088 -54.618128) (xy 179.393088 -55.481728)
			(xy 179.392602 -55.508979) (xy 179.384846 -55.562927) (xy 179.369491 -55.615222) (xy 179.346849 -55.664799)
			(xy 179.317383 -55.710649) (xy 179.281692 -55.75184) (xy 179.240501 -55.787531) (xy 179.194651 -55.816997)
			(xy 179.145074 -55.839639) (xy 179.092779 -55.854994) (xy 179.038831 -55.86275) (xy 178.984329 -55.86275)
			(xy 178.930381 -55.854994) (xy 178.878086 -55.839639) (xy 178.828509 -55.816997) (xy 178.782659 -55.787531)
			(xy 178.741468 -55.75184) (xy 178.705777 -55.710649) (xy 178.676311 -55.664799) (xy 178.653669 -55.615222)
			(xy 178.638314 -55.562927) (xy 178.630558 -55.508979) (xy 178.630072 -55.481728) (xy 0.509016 -55.481728)
			(xy 0.509016 -57.094435) (xy 170.841915 -57.094435) (xy 170.841915 -57.005413) (xy 170.849895 -56.916749)
			(xy 170.865791 -56.829158) (xy 170.889474 -56.743343) (xy 170.920754 -56.659998) (xy 170.95938 -56.579792)
			(xy 171.005039 -56.503371) (xy 171.057365 -56.43135) (xy 171.115936 -56.36431) (xy 171.180281 -56.30279)
			(xy 171.249881 -56.247286) (xy 171.324177 -56.198244) (xy 171.402569 -56.156059) (xy 171.484428 -56.121071)
			(xy 171.569093 -56.093562) (xy 171.655883 -56.073752) (xy 171.744099 -56.061802) (xy 171.833032 -56.057809)
			(xy 171.921965 -56.061802) (xy 172.010181 -56.073752) (xy 172.096971 -56.093562) (xy 172.181636 -56.121071)
			(xy 172.263495 -56.156059) (xy 172.341887 -56.198244) (xy 172.416183 -56.247286) (xy 172.485783 -56.30279)
			(xy 172.550128 -56.36431) (xy 172.608699 -56.43135) (xy 172.661025 -56.503371) (xy 172.663117 -56.506872)
			(xy 228.815392 -56.506872) (xy 228.815392 -55.643272) (xy 228.815878 -55.616021) (xy 228.823634 -55.562073)
			(xy 228.838989 -55.509778) (xy 228.861631 -55.460201) (xy 228.891097 -55.414351) (xy 228.926788 -55.37316)
			(xy 228.967979 -55.337469) (xy 229.013829 -55.308003) (xy 229.063406 -55.285361) (xy 229.115701 -55.270006)
			(xy 229.169649 -55.26225) (xy 229.224151 -55.26225) (xy 229.278099 -55.270006) (xy 229.330394 -55.285361)
			(xy 229.379971 -55.308003) (xy 229.425821 -55.337469) (xy 229.467012 -55.37316) (xy 229.502703 -55.414351)
			(xy 229.532169 -55.460201) (xy 229.554811 -55.509778) (xy 229.570166 -55.562073) (xy 229.577922 -55.616021)
			(xy 229.578408 -55.643272) (xy 229.578408 -55.911852) (xy 357.10365 -55.911852) (xy 357.10365 -55.857348)
			(xy 357.111406 -55.803398) (xy 357.126762 -55.751101) (xy 357.149403 -55.701521) (xy 357.17887 -55.655668)
			(xy 357.214562 -55.614476) (xy 357.255752 -55.578782) (xy 357.301604 -55.549313) (xy 357.351182 -55.526669)
			(xy 357.403478 -55.511311) (xy 357.457428 -55.503551) (xy 357.48468 -55.503064) (xy 358.34828 -55.503064)
			(xy 358.375532 -55.503582) (xy 358.429481 -55.511336) (xy 358.481777 -55.526689) (xy 358.531356 -55.549329)
			(xy 358.577209 -55.578794) (xy 358.618401 -55.614485) (xy 358.654094 -55.655675) (xy 358.683562 -55.701526)
			(xy 358.706204 -55.751104) (xy 358.72156 -55.8034) (xy 358.729317 -55.857348) (xy 358.729317 -55.911852)
			(xy 358.729316 -55.911856) (xy 359.950927 -55.911856) (xy 359.950927 -55.857344) (xy 359.958685 -55.803388)
			(xy 359.974043 -55.751084) (xy 359.996689 -55.701499) (xy 360.026161 -55.655642) (xy 360.061859 -55.614445)
			(xy 360.103058 -55.578749) (xy 360.148917 -55.549279) (xy 360.198503 -55.526636) (xy 360.250807 -55.511281)
			(xy 360.304764 -55.503526) (xy 360.33202 -55.503064) (xy 361.19562 -55.503064) (xy 361.222868 -55.503608)
			(xy 361.27681 -55.511366) (xy 361.329098 -55.526722) (xy 361.378669 -55.549362) (xy 361.424514 -55.578827)
			(xy 361.465699 -55.614516) (xy 361.501385 -55.655702) (xy 361.530847 -55.701548) (xy 361.553485 -55.75112)
			(xy 361.568838 -55.80341) (xy 361.576594 -55.857352) (xy 361.576594 -55.911848) (xy 361.576593 -55.911857)
			(xy 363.514527 -55.911857) (xy 363.514527 -55.857343) (xy 363.522286 -55.803385) (xy 363.537645 -55.75108)
			(xy 363.560292 -55.701493) (xy 363.589766 -55.655635) (xy 363.625466 -55.614438) (xy 363.666667 -55.578742)
			(xy 363.712529 -55.549273) (xy 363.762117 -55.526631) (xy 363.814424 -55.511277) (xy 363.868383 -55.503524)
			(xy 363.89564 -55.503064) (xy 364.75924 -55.503064) (xy 364.786487 -55.503609) (xy 364.840427 -55.511369)
			(xy 364.892713 -55.526727) (xy 364.942281 -55.549369) (xy 364.988123 -55.578834) (xy 365.029306 -55.614523)
			(xy 365.06499 -55.655709) (xy 365.094451 -55.701554) (xy 365.117087 -55.751125) (xy 365.132439 -55.803412)
			(xy 365.140194 -55.857353) (xy 365.140194 -55.911847) (xy 365.132439 -55.965788) (xy 365.117087 -56.018075)
			(xy 365.094451 -56.067646) (xy 365.06499 -56.113491) (xy 365.029306 -56.154677) (xy 364.988123 -56.190366)
			(xy 364.942281 -56.219831) (xy 364.892713 -56.242473) (xy 364.840427 -56.257831) (xy 364.786487 -56.265591)
			(xy 364.75924 -56.26608) (xy 363.89564 -56.26608) (xy 363.868383 -56.265676) (xy 363.814424 -56.257923)
			(xy 363.762117 -56.242569) (xy 363.712529 -56.219927) (xy 363.666667 -56.190458) (xy 363.625466 -56.154762)
			(xy 363.589766 -56.113565) (xy 363.560292 -56.067707) (xy 363.537645 -56.01812) (xy 363.522286 -55.965815)
			(xy 363.514527 -55.911857) (xy 361.576593 -55.911857) (xy 361.568838 -55.96579) (xy 361.553485 -56.01808)
			(xy 361.530847 -56.067652) (xy 361.501385 -56.113498) (xy 361.465699 -56.154684) (xy 361.424514 -56.190373)
			(xy 361.378669 -56.219838) (xy 361.329098 -56.242478) (xy 361.27681 -56.257834) (xy 361.222868 -56.265592)
			(xy 361.19562 -56.26608) (xy 360.33202 -56.26608) (xy 360.304764 -56.265674) (xy 360.250807 -56.257919)
			(xy 360.198503 -56.242564) (xy 360.148917 -56.219921) (xy 360.103058 -56.190451) (xy 360.061859 -56.154755)
			(xy 360.026161 -56.113558) (xy 359.996689 -56.067701) (xy 359.974043 -56.018116) (xy 359.958685 -55.965812)
			(xy 359.950927 -55.911856) (xy 358.729316 -55.911856) (xy 358.72156 -55.9658) (xy 358.706204 -56.018096)
			(xy 358.683562 -56.067674) (xy 358.654094 -56.113525) (xy 358.618401 -56.154715) (xy 358.577209 -56.190406)
			(xy 358.531356 -56.219871) (xy 358.481777 -56.242511) (xy 358.429481 -56.257864) (xy 358.375532 -56.265618)
			(xy 358.34828 -56.26608) (xy 357.48468 -56.26608) (xy 357.457428 -56.265649) (xy 357.403478 -56.257889)
			(xy 357.351182 -56.242531) (xy 357.301604 -56.219887) (xy 357.255752 -56.190418) (xy 357.214562 -56.154724)
			(xy 357.17887 -56.113532) (xy 357.149403 -56.067679) (xy 357.126762 -56.018099) (xy 357.111406 -55.965802)
			(xy 357.10365 -55.911852) (xy 229.578408 -55.911852) (xy 229.578408 -56.506872) (xy 229.577922 -56.534123)
			(xy 229.570166 -56.588071) (xy 229.554811 -56.640366) (xy 229.532169 -56.689943) (xy 229.502703 -56.735793)
			(xy 229.467012 -56.776984) (xy 229.425821 -56.812675) (xy 229.379971 -56.842141) (xy 229.330394 -56.864783)
			(xy 229.278099 -56.880138) (xy 229.224151 -56.887894) (xy 229.169649 -56.887894) (xy 229.115701 -56.880138)
			(xy 229.063406 -56.864783) (xy 229.013829 -56.842141) (xy 228.967979 -56.812675) (xy 228.926788 -56.776984)
			(xy 228.891097 -56.735793) (xy 228.861631 -56.689943) (xy 228.838989 -56.640366) (xy 228.823634 -56.588071)
			(xy 228.815878 -56.534123) (xy 228.815392 -56.506872) (xy 172.663117 -56.506872) (xy 172.706684 -56.579792)
			(xy 172.74531 -56.659998) (xy 172.77659 -56.743343) (xy 172.800273 -56.829158) (xy 172.816169 -56.916749)
			(xy 172.824149 -57.005413) (xy 172.824648 -57.049924) (xy 172.824149 -57.094435) (xy 172.816169 -57.183099)
			(xy 172.800273 -57.27069) (xy 172.77659 -57.356505) (xy 172.74531 -57.43985) (xy 172.706684 -57.520056)
			(xy 172.661025 -57.596477) (xy 172.608699 -57.668498) (xy 172.550128 -57.735538) (xy 172.485783 -57.797058)
			(xy 172.416183 -57.852562) (xy 172.341887 -57.901604) (xy 172.263495 -57.943789) (xy 172.181636 -57.978777)
			(xy 172.096971 -58.006286) (xy 172.010181 -58.026096) (xy 171.921965 -58.038046) (xy 171.833032 -58.04204)
			(xy 171.744099 -58.038046) (xy 171.655883 -58.026096) (xy 171.569093 -58.006286) (xy 171.484428 -57.978777)
			(xy 171.402569 -57.943789) (xy 171.324177 -57.901604) (xy 171.249881 -57.852562) (xy 171.180281 -57.797058)
			(xy 171.115936 -57.735538) (xy 171.057365 -57.668498) (xy 171.005039 -57.596477) (xy 170.95938 -57.520056)
			(xy 170.920754 -57.43985) (xy 170.889474 -57.356505) (xy 170.865791 -57.27069) (xy 170.849895 -57.183099)
			(xy 170.841915 -57.094435) (xy 0.509016 -57.094435) (xy 0.509016 -58.306716) (xy 230.115872 -58.306716)
			(xy 230.115872 -57.443116) (xy 230.116358 -57.415865) (xy 230.124114 -57.361917) (xy 230.139469 -57.309622)
			(xy 230.162111 -57.260045) (xy 230.191577 -57.214195) (xy 230.227268 -57.173004) (xy 230.268459 -57.137313)
			(xy 230.314309 -57.107847) (xy 230.363886 -57.085205) (xy 230.416181 -57.06985) (xy 230.470129 -57.062094)
			(xy 230.524631 -57.062094) (xy 230.578579 -57.06985) (xy 230.630874 -57.085205) (xy 230.680451 -57.107847)
			(xy 230.726301 -57.137313) (xy 230.767492 -57.173004) (xy 230.803183 -57.214195) (xy 230.832649 -57.260045)
			(xy 230.855291 -57.309622) (xy 230.870646 -57.361917) (xy 230.878402 -57.415865) (xy 230.878888 -57.443116)
			(xy 230.878888 -58.30189) (xy 240.282476 -58.30189) (xy 240.282476 -57.43829) (xy 240.282962 -57.411039)
			(xy 240.290718 -57.357091) (xy 240.306073 -57.304796) (xy 240.328715 -57.255219) (xy 240.358181 -57.209369)
			(xy 240.393872 -57.168178) (xy 240.435063 -57.132487) (xy 240.480913 -57.103021) (xy 240.53049 -57.080379)
			(xy 240.582785 -57.065024) (xy 240.636733 -57.057268) (xy 240.691235 -57.057268) (xy 240.745183 -57.065024)
			(xy 240.797478 -57.080379) (xy 240.847055 -57.103021) (xy 240.892905 -57.132487) (xy 240.934096 -57.168178)
			(xy 240.969787 -57.209369) (xy 240.999253 -57.255219) (xy 241.021895 -57.304796) (xy 241.03725 -57.357091)
			(xy 241.045006 -57.411039) (xy 241.045492 -57.43829) (xy 241.045492 -58.30189) (xy 241.045006 -58.329141)
			(xy 241.03725 -58.383089) (xy 241.021895 -58.435384) (xy 240.999253 -58.484961) (xy 240.969787 -58.530811)
			(xy 240.941894 -58.563002) (xy 242.736116 -58.563002) (xy 242.736116 -57.699402) (xy 242.736602 -57.672151)
			(xy 242.744358 -57.618203) (xy 242.759713 -57.565908) (xy 242.782355 -57.516331) (xy 242.811821 -57.470481)
			(xy 242.847512 -57.42929) (xy 242.888703 -57.393599) (xy 242.934553 -57.364133) (xy 242.98413 -57.341491)
			(xy 243.036425 -57.326136) (xy 243.090373 -57.31838) (xy 243.144875 -57.31838) (xy 243.198823 -57.326136)
			(xy 243.251118 -57.341491) (xy 243.300695 -57.364133) (xy 243.346545 -57.393599) (xy 243.387736 -57.42929)
			(xy 243.423427 -57.470481) (xy 243.452893 -57.516331) (xy 243.475535 -57.565908) (xy 243.49089 -57.618203)
			(xy 243.498646 -57.672151) (xy 243.499132 -57.699402) (xy 243.499132 -58.563002) (xy 243.498646 -58.590253)
			(xy 243.49089 -58.644201) (xy 243.475535 -58.696496) (xy 243.452893 -58.746073) (xy 243.423427 -58.791923)
			(xy 243.387736 -58.833114) (xy 243.346545 -58.868805) (xy 243.300695 -58.898271) (xy 243.251118 -58.920913)
			(xy 243.198823 -58.936268) (xy 243.144875 -58.944024) (xy 243.090373 -58.944024) (xy 243.036425 -58.936268)
			(xy 242.98413 -58.920913) (xy 242.934553 -58.898271) (xy 242.888703 -58.868805) (xy 242.847512 -58.833114)
			(xy 242.811821 -58.791923) (xy 242.782355 -58.746073) (xy 242.759713 -58.696496) (xy 242.744358 -58.644201)
			(xy 242.736602 -58.590253) (xy 242.736116 -58.563002) (xy 240.941894 -58.563002) (xy 240.934096 -58.572002)
			(xy 240.892905 -58.607693) (xy 240.847055 -58.637159) (xy 240.797478 -58.659801) (xy 240.745183 -58.675156)
			(xy 240.691235 -58.682912) (xy 240.636733 -58.682912) (xy 240.582785 -58.675156) (xy 240.53049 -58.659801)
			(xy 240.480913 -58.637159) (xy 240.435063 -58.607693) (xy 240.393872 -58.572002) (xy 240.358181 -58.530811)
			(xy 240.328715 -58.484961) (xy 240.306073 -58.435384) (xy 240.290718 -58.383089) (xy 240.282962 -58.329141)
			(xy 240.282476 -58.30189) (xy 230.878888 -58.30189) (xy 230.878888 -58.306716) (xy 230.878402 -58.333967)
			(xy 230.870646 -58.387915) (xy 230.855291 -58.44021) (xy 230.832649 -58.489787) (xy 230.803183 -58.535637)
			(xy 230.767492 -58.576828) (xy 230.726301 -58.612519) (xy 230.680451 -58.641985) (xy 230.630874 -58.664627)
			(xy 230.578579 -58.679982) (xy 230.524631 -58.687738) (xy 230.470129 -58.687738) (xy 230.416181 -58.679982)
			(xy 230.363886 -58.664627) (xy 230.314309 -58.641985) (xy 230.268459 -58.612519) (xy 230.227268 -58.576828)
			(xy 230.191577 -58.535637) (xy 230.162111 -58.489787) (xy 230.139469 -58.44021) (xy 230.124114 -58.387915)
			(xy 230.116358 -58.333967) (xy 230.115872 -58.306716) (xy 0.509016 -58.306716) (xy 0.509016 -59.99988)
			(xy 16.983969 -59.99988) (xy 16.987993 -59.914112) (xy 17.000031 -59.829098) (xy 17.019978 -59.745584)
			(xy 17.047657 -59.664305) (xy 17.082825 -59.585976) (xy 17.125174 -59.511283) (xy 17.174331 -59.440885)
			(xy 17.229864 -59.375399) (xy 17.291286 -59.315401) (xy 17.358055 -59.261418) (xy 17.429587 -59.213925)
			(xy 17.505251 -59.173339) (xy 17.584384 -59.140016) (xy 17.666289 -59.11425) (xy 17.750247 -59.096267)
			(xy 17.835521 -59.086225) (xy 17.92136 -59.084212) (xy 18.00701 -59.090246) (xy 18.091718 -59.104274)
			(xy 18.174741 -59.126173) (xy 18.255349 -59.15575) (xy 18.332833 -59.192745) (xy 18.406512 -59.236833)
			(xy 18.475738 -59.287627) (xy 18.539905 -59.34468) (xy 18.598446 -59.407491) (xy 18.650849 -59.475508)
			(xy 18.696652 -59.548133) (xy 18.735453 -59.624728) (xy 18.766912 -59.70462) (xy 18.790751 -59.787107)
			(xy 18.806761 -59.871464) (xy 18.814801 -59.956949) (xy 18.815304 -59.99988) (xy 18.814801 -60.042811)
			(xy 18.806761 -60.128296) (xy 18.790751 -60.212653) (xy 18.766912 -60.29514) (xy 18.735453 -60.375032)
			(xy 18.73545 -60.375038) (xy 233.333297 -60.375038) (xy 233.337302 -60.28713) (xy 233.349285 -60.19995)
			(xy 233.369145 -60.114221) (xy 233.39672 -60.030653) (xy 233.431779 -59.949939) (xy 233.474032 -59.872747)
			(xy 233.52313 -59.799718) (xy 233.578666 -59.731456) (xy 233.640178 -59.668526) (xy 233.707159 -59.611452)
			(xy 233.779052 -59.560704) (xy 233.855261 -59.516704) (xy 233.935156 -59.479817) (xy 234.018075 -59.450348)
			(xy 234.10333 -59.428541) (xy 234.190214 -59.414577) (xy 234.278008 -59.408571) (xy 234.365985 -59.410575)
			(xy 234.453415 -59.42057) (xy 234.539574 -59.438474) (xy 234.623748 -59.464138) (xy 234.705239 -59.497351)
			(xy 234.783373 -59.537837) (xy 234.857501 -59.585259) (xy 234.927009 -59.639226) (xy 234.991323 -59.699291)
			(xy 235.049907 -59.764955) (xy 235.102278 -59.835674) (xy 235.148001 -59.910862) (xy 235.186698 -59.989897)
			(xy 235.218047 -60.072123) (xy 235.241789 -60.156859) (xy 235.257727 -60.243403) (xy 235.265729 -60.331038)
			(xy 235.26623 -60.375038) (xy 235.265729 -60.419038) (xy 235.257727 -60.506673) (xy 235.241789 -60.593217)
			(xy 235.218047 -60.677953) (xy 235.186698 -60.760179) (xy 235.148001 -60.839214) (xy 235.102278 -60.914402)
			(xy 235.049907 -60.985121) (xy 234.991323 -61.050785) (xy 234.927009 -61.11085) (xy 234.857501 -61.164817)
			(xy 234.783373 -61.212239) (xy 234.705239 -61.252725) (xy 234.623748 -61.285938) (xy 234.539574 -61.311602)
			(xy 234.453415 -61.329506) (xy 234.365985 -61.339501) (xy 234.278008 -61.341505) (xy 234.190214 -61.335499)
			(xy 234.10333 -61.321535) (xy 234.018075 -61.299728) (xy 233.935156 -61.270259) (xy 233.855261 -61.233372)
			(xy 233.779052 -61.189372) (xy 233.707159 -61.138624) (xy 233.640178 -61.08155) (xy 233.578666 -61.01862)
			(xy 233.52313 -60.950358) (xy 233.474032 -60.877329) (xy 233.431779 -60.800137) (xy 233.39672 -60.719423)
			(xy 233.369145 -60.635855) (xy 233.349285 -60.550126) (xy 233.337302 -60.462946) (xy 233.333297 -60.375038)
			(xy 18.73545 -60.375038) (xy 18.696652 -60.451627) (xy 18.650849 -60.524252) (xy 18.598446 -60.592269)
			(xy 18.539905 -60.65508) (xy 18.475738 -60.712133) (xy 18.406512 -60.762927) (xy 18.332833 -60.807015)
			(xy 18.255349 -60.84401) (xy 18.174741 -60.873587) (xy 18.091718 -60.895486) (xy 18.00701 -60.909514)
			(xy 17.92136 -60.915548) (xy 17.835521 -60.913535) (xy 17.750247 -60.903493) (xy 17.666289 -60.88551)
			(xy 17.584384 -60.859744) (xy 17.505251 -60.826421) (xy 17.429587 -60.785835) (xy 17.358055 -60.738342)
			(xy 17.291286 -60.684359) (xy 17.229864 -60.624361) (xy 17.174331 -60.558875) (xy 17.125174 -60.488477)
			(xy 17.082825 -60.413784) (xy 17.047657 -60.335455) (xy 17.019978 -60.254176) (xy 17.000031 -60.170662)
			(xy 16.987993 -60.085648) (xy 16.983969 -59.99988) (xy 0.509016 -59.99988) (xy 0.509016 -74.760836)
			(xy 39.554404 -74.760836) (xy 39.554404 -66.060828) (xy 39.554909 -65.955304) (xy 39.562993 -65.74441)
			(xy 39.579149 -65.533981) (xy 39.603352 -65.324324) (xy 39.635569 -65.115749) (xy 39.675751 -64.908561)
			(xy 39.723839 -64.703064) (xy 39.779763 -64.49956) (xy 39.84344 -64.298347) (xy 39.914778 -64.09972)
			(xy 39.993672 -63.903972) (xy 40.080005 -63.71139) (xy 40.173652 -63.522255) (xy 40.274474 -63.336846)
			(xy 40.382324 -63.155435) (xy 40.497043 -62.978288) (xy 40.618463 -62.805666) (xy 40.746406 -62.63782)
			(xy 40.880684 -62.474998) (xy 41.0211 -62.317439) (xy 41.167448 -62.165374) (xy 41.319513 -62.019026)
			(xy 41.477072 -61.87861) (xy 41.639894 -61.744332) (xy 41.80774 -61.616389) (xy 41.980362 -61.494969)
			(xy 42.157509 -61.38025) (xy 42.33892 -61.2724) (xy 42.524329 -61.171578) (xy 42.713464 -61.077931)
			(xy 42.906046 -60.991598) (xy 43.101794 -60.912704) (xy 43.300421 -60.841366) (xy 43.501634 -60.777689)
			(xy 43.705138 -60.721765) (xy 43.910635 -60.673677) (xy 44.117823 -60.633495) (xy 44.326398 -60.601278)
			(xy 44.536055 -60.577075) (xy 44.746484 -60.560919) (xy 44.957378 -60.552835) (xy 45.168426 -60.552835)
			(xy 45.37932 -60.560919) (xy 45.589749 -60.577075) (xy 45.799406 -60.601278) (xy 46.007981 -60.633495)
			(xy 46.215169 -60.673677) (xy 46.420666 -60.721765) (xy 46.62417 -60.777689) (xy 46.825383 -60.841366)
			(xy 47.02401 -60.912704) (xy 47.219758 -60.991598) (xy 47.41234 -61.077931) (xy 47.601475 -61.171578)
			(xy 47.786884 -61.2724) (xy 47.968295 -61.38025) (xy 48.145442 -61.494969) (xy 48.318064 -61.616389)
			(xy 48.48591 -61.744332) (xy 48.648732 -61.87861) (xy 48.806291 -62.019026) (xy 48.958356 -62.165374)
			(xy 49.104704 -62.317439) (xy 49.24512 -62.474998) (xy 49.379398 -62.63782) (xy 49.507341 -62.805666)
			(xy 49.628761 -62.978288) (xy 49.74348 -63.155435) (xy 49.85133 -63.336846) (xy 49.952152 -63.522255)
			(xy 50.045799 -63.71139) (xy 50.132132 -63.903972) (xy 50.211026 -64.09972) (xy 50.282364 -64.298347)
			(xy 50.346041 -64.49956) (xy 50.401965 -64.703064) (xy 50.450053 -64.908561) (xy 50.490235 -65.115749)
			(xy 50.522452 -65.324324) (xy 50.546655 -65.533981) (xy 50.562811 -65.74441) (xy 50.570895 -65.955304)
			(xy 50.5714 -66.060828) (xy 50.5714 -74.760836) (xy 50.571366 -74.767948) (xy 173.354492 -74.767948)
			(xy 173.354492 -66.06794) (xy 173.354997 -65.962416) (xy 173.363081 -65.751522) (xy 173.379237 -65.541093)
			(xy 173.40344 -65.331436) (xy 173.435657 -65.122861) (xy 173.475839 -64.915673) (xy 173.523927 -64.710176)
			(xy 173.579851 -64.506672) (xy 173.643528 -64.305459) (xy 173.714866 -64.106832) (xy 173.79376 -63.911084)
			(xy 173.880093 -63.718502) (xy 173.97374 -63.529367) (xy 174.074562 -63.343958) (xy 174.182412 -63.162547)
			(xy 174.297131 -62.9854) (xy 174.418551 -62.812778) (xy 174.546494 -62.644932) (xy 174.680772 -62.48211)
			(xy 174.821188 -62.324551) (xy 174.967536 -62.172486) (xy 175.119601 -62.026138) (xy 175.27716 -61.885722)
			(xy 175.439982 -61.751444) (xy 175.607828 -61.623501) (xy 175.78045 -61.502081) (xy 175.957597 -61.387362)
			(xy 176.139008 -61.279512) (xy 176.324417 -61.17869) (xy 176.513552 -61.085043) (xy 176.706134 -60.99871)
			(xy 176.901882 -60.919816) (xy 177.100509 -60.848478) (xy 177.301722 -60.784801) (xy 177.505226 -60.728877)
			(xy 177.710723 -60.680789) (xy 177.917911 -60.640607) (xy 178.126486 -60.60839) (xy 178.336143 -60.584187)
			(xy 178.546572 -60.568031) (xy 178.757466 -60.559947) (xy 178.968514 -60.559947) (xy 179.179408 -60.568031)
			(xy 179.389837 -60.584187) (xy 179.599494 -60.60839) (xy 179.808069 -60.640607) (xy 180.015257 -60.680789)
			(xy 180.220754 -60.728877) (xy 180.424258 -60.784801) (xy 180.625471 -60.848478) (xy 180.824098 -60.919816)
			(xy 181.019846 -60.99871) (xy 181.212428 -61.085043) (xy 181.401563 -61.17869) (xy 181.586972 -61.279512)
			(xy 181.768383 -61.387362) (xy 181.94553 -61.502081) (xy 182.118152 -61.623501) (xy 182.285998 -61.751444)
			(xy 182.44882 -61.885722) (xy 182.606379 -62.026138) (xy 182.758444 -62.172486) (xy 182.904792 -62.324551)
			(xy 183.045208 -62.48211) (xy 183.179486 -62.644932) (xy 183.307429 -62.812778) (xy 183.428849 -62.9854)
			(xy 183.543568 -63.162547) (xy 183.651418 -63.343958) (xy 183.75224 -63.529367) (xy 183.845887 -63.718502)
			(xy 183.93222 -63.911084) (xy 184.011114 -64.106832) (xy 184.082452 -64.305459) (xy 184.146129 -64.506672)
			(xy 184.202053 -64.710176) (xy 184.250141 -64.915673) (xy 184.290323 -65.122861) (xy 184.32254 -65.331436)
			(xy 184.346743 -65.541093) (xy 184.362899 -65.751522) (xy 184.370983 -65.962416) (xy 184.371488 -66.06794)
			(xy 184.371488 -74.760836) (xy 287.494472 -74.760836) (xy 287.494472 -66.060828) (xy 287.494977 -65.955304)
			(xy 287.503061 -65.74441) (xy 287.519217 -65.533981) (xy 287.54342 -65.324324) (xy 287.575637 -65.115749)
			(xy 287.615819 -64.908561) (xy 287.663907 -64.703064) (xy 287.719831 -64.49956) (xy 287.783508 -64.298347)
			(xy 287.854846 -64.09972) (xy 287.93374 -63.903972) (xy 288.020073 -63.71139) (xy 288.11372 -63.522255)
			(xy 288.214542 -63.336846) (xy 288.322392 -63.155435) (xy 288.437111 -62.978288) (xy 288.558531 -62.805666)
			(xy 288.686474 -62.63782) (xy 288.820752 -62.474998) (xy 288.961168 -62.317439) (xy 289.107516 -62.165374)
			(xy 289.259581 -62.019026) (xy 289.41714 -61.87861) (xy 289.579962 -61.744332) (xy 289.747808 -61.616389)
			(xy 289.92043 -61.494969) (xy 290.097577 -61.38025) (xy 290.278988 -61.2724) (xy 290.464397 -61.171578)
			(xy 290.653532 -61.077931) (xy 290.846114 -60.991598) (xy 291.041862 -60.912704) (xy 291.240489 -60.841366)
			(xy 291.441702 -60.777689) (xy 291.645206 -60.721765) (xy 291.850703 -60.673677) (xy 292.057891 -60.633495)
			(xy 292.266466 -60.601278) (xy 292.476123 -60.577075) (xy 292.686552 -60.560919) (xy 292.897446 -60.552835)
			(xy 293.108494 -60.552835) (xy 293.319388 -60.560919) (xy 293.529817 -60.577075) (xy 293.739474 -60.601278)
			(xy 293.948049 -60.633495) (xy 294.155237 -60.673677) (xy 294.360734 -60.721765) (xy 294.564238 -60.777689)
			(xy 294.765451 -60.841366) (xy 294.964078 -60.912704) (xy 295.159826 -60.991598) (xy 295.352408 -61.077931)
			(xy 295.541543 -61.171578) (xy 295.726952 -61.2724) (xy 295.908363 -61.38025) (xy 296.063868 -61.480954)
			(xy 351.822512 -61.480954) (xy 351.822512 -60.617354) (xy 351.822998 -60.590103) (xy 351.830754 -60.536155)
			(xy 351.846109 -60.48386) (xy 351.868751 -60.434283) (xy 351.898217 -60.388433) (xy 351.933908 -60.347242)
			(xy 351.975099 -60.311551) (xy 352.020949 -60.282085) (xy 352.070526 -60.259443) (xy 352.122821 -60.244088)
			(xy 352.176769 -60.236332) (xy 352.231271 -60.236332) (xy 352.285219 -60.244088) (xy 352.337514 -60.259443)
			(xy 352.387091 -60.282085) (xy 352.432941 -60.311551) (xy 352.474132 -60.347242) (xy 352.509823 -60.388433)
			(xy 352.539289 -60.434283) (xy 352.561931 -60.48386) (xy 352.577286 -60.536155) (xy 352.585042 -60.590103)
			(xy 352.585528 -60.617354) (xy 352.585528 -61.223271) (xy 355.46889 -61.223271) (xy 355.46889 -61.168729)
			(xy 355.476653 -61.114741) (xy 355.492019 -61.062408) (xy 355.514676 -61.012794) (xy 355.544164 -60.966909)
			(xy 355.579881 -60.925688) (xy 355.621101 -60.88997) (xy 355.666985 -60.860481) (xy 355.716598 -60.837822)
			(xy 355.768931 -60.822455) (xy 355.822919 -60.814691) (xy 355.85019 -60.814204) (xy 356.71379 -60.814204)
			(xy 356.741059 -60.814735) (xy 356.795042 -60.822495) (xy 356.847371 -60.837859) (xy 356.896981 -60.860514)
			(xy 356.942862 -60.889999) (xy 356.98408 -60.925713) (xy 357.019795 -60.96693) (xy 357.049281 -61.01281)
			(xy 357.071937 -61.062419) (xy 357.087303 -61.114748) (xy 357.095065 -61.168731) (xy 357.095065 -61.223269)
			(xy 357.087303 -61.277252) (xy 357.071937 -61.329581) (xy 357.049281 -61.37919) (xy 357.019795 -61.42507)
			(xy 356.98408 -61.466287) (xy 356.942862 -61.502001) (xy 356.896981 -61.531486) (xy 356.847371 -61.554141)
			(xy 356.795042 -61.569505) (xy 356.741059 -61.577265) (xy 356.71379 -61.577728) (xy 355.85019 -61.577728)
			(xy 355.822919 -61.577309) (xy 355.768931 -61.569545) (xy 355.716598 -61.554178) (xy 355.666985 -61.531519)
			(xy 355.621101 -61.50203) (xy 355.579881 -61.466312) (xy 355.544164 -61.425091) (xy 355.514676 -61.379206)
			(xy 355.492019 -61.329592) (xy 355.476653 -61.277259) (xy 355.46889 -61.223271) (xy 352.585528 -61.223271)
			(xy 352.585528 -61.480954) (xy 352.585042 -61.508205) (xy 352.577286 -61.562153) (xy 352.561931 -61.614448)
			(xy 352.539289 -61.664025) (xy 352.509823 -61.709875) (xy 352.474132 -61.751066) (xy 352.432941 -61.786757)
			(xy 352.387091 -61.816223) (xy 352.337514 -61.838865) (xy 352.285219 -61.85422) (xy 352.231271 -61.861976)
			(xy 352.176769 -61.861976) (xy 352.122821 -61.85422) (xy 352.070526 -61.838865) (xy 352.020949 -61.816223)
			(xy 351.975099 -61.786757) (xy 351.933908 -61.751066) (xy 351.898217 -61.709875) (xy 351.868751 -61.664025)
			(xy 351.846109 -61.614448) (xy 351.830754 -61.562153) (xy 351.822998 -61.508205) (xy 351.822512 -61.480954)
			(xy 296.063868 -61.480954) (xy 296.08551 -61.494969) (xy 296.258132 -61.616389) (xy 296.425978 -61.744332)
			(xy 296.5888 -61.87861) (xy 296.746359 -62.019026) (xy 296.898424 -62.165374) (xy 297.044772 -62.317439)
			(xy 297.185188 -62.474998) (xy 297.319466 -62.63782) (xy 297.447409 -62.805666) (xy 297.568829 -62.978288)
			(xy 297.683548 -63.155435) (xy 297.751584 -63.269876) (xy 350.300544 -63.269876) (xy 350.300544 -62.406276)
			(xy 350.30103 -62.379025) (xy 350.308786 -62.325077) (xy 350.324141 -62.272782) (xy 350.346783 -62.223205)
			(xy 350.376249 -62.177355) (xy 350.41194 -62.136164) (xy 350.453131 -62.100473) (xy 350.498981 -62.071007)
			(xy 350.548558 -62.048365) (xy 350.600853 -62.03301) (xy 350.654801 -62.025254) (xy 350.709303 -62.025254)
			(xy 350.763251 -62.03301) (xy 350.815546 -62.048365) (xy 350.865123 -62.071007) (xy 350.910973 -62.100473)
			(xy 350.952164 -62.136164) (xy 350.987855 -62.177355) (xy 351.017321 -62.223205) (xy 351.039963 -62.272782)
			(xy 351.055318 -62.325077) (xy 351.063074 -62.379025) (xy 351.06356 -62.406276) (xy 351.06356 -63.269876)
			(xy 351.063074 -63.297127) (xy 351.055318 -63.351075) (xy 351.039963 -63.40337) (xy 351.017321 -63.452947)
			(xy 350.987855 -63.498797) (xy 350.952164 -63.539988) (xy 350.910973 -63.575679) (xy 350.865123 -63.605145)
			(xy 350.815546 -63.627787) (xy 350.763251 -63.643142) (xy 350.709303 -63.650898) (xy 350.654801 -63.650898)
			(xy 350.600853 -63.643142) (xy 350.548558 -63.627787) (xy 350.498981 -63.605145) (xy 350.453131 -63.575679)
			(xy 350.41194 -63.539988) (xy 350.376249 -63.498797) (xy 350.346783 -63.452947) (xy 350.324141 -63.40337)
			(xy 350.308786 -63.351075) (xy 350.30103 -63.297127) (xy 350.300544 -63.269876) (xy 297.751584 -63.269876)
			(xy 297.791398 -63.336846) (xy 297.89222 -63.522255) (xy 297.985867 -63.71139) (xy 298.0722 -63.903972)
			(xy 298.151094 -64.09972) (xy 298.222432 -64.298347) (xy 298.286109 -64.49956) (xy 298.342033 -64.703064)
			(xy 298.390121 -64.908561) (xy 298.396302 -64.940434) (xy 325.410068 -64.940434) (xy 325.410068 -64.076834)
			(xy 325.410554 -64.049565) (xy 325.418316 -63.995581) (xy 325.433681 -63.943251) (xy 325.456338 -63.893641)
			(xy 325.485824 -63.84776) (xy 325.521539 -63.806543) (xy 325.562756 -63.770828) (xy 325.608637 -63.741342)
			(xy 325.658247 -63.718685) (xy 325.710577 -63.70332) (xy 325.764561 -63.695558) (xy 325.819099 -63.695558)
			(xy 325.873083 -63.70332) (xy 325.925413 -63.718685) (xy 325.975023 -63.741342) (xy 326.020904 -63.770828)
			(xy 326.062121 -63.806543) (xy 326.097836 -63.84776) (xy 326.127322 -63.893641) (xy 326.149979 -63.943251)
			(xy 326.165344 -63.995581) (xy 326.173106 -64.049565) (xy 326.173592 -64.076834) (xy 326.173592 -64.940434)
			(xy 326.173106 -64.967703) (xy 326.165344 -65.021687) (xy 326.149979 -65.074017) (xy 326.127322 -65.123627)
			(xy 326.097836 -65.169508) (xy 326.062121 -65.210725) (xy 326.020904 -65.24644) (xy 325.975023 -65.275926)
			(xy 325.925413 -65.298583) (xy 325.873083 -65.313948) (xy 325.819099 -65.32171) (xy 325.764561 -65.32171)
			(xy 325.710577 -65.313948) (xy 325.658247 -65.298583) (xy 325.608637 -65.275926) (xy 325.562756 -65.24644)
			(xy 325.521539 -65.210725) (xy 325.485824 -65.169508) (xy 325.456338 -65.123627) (xy 325.433681 -65.074017)
			(xy 325.418316 -65.021687) (xy 325.410554 -64.967703) (xy 325.410068 -64.940434) (xy 298.396302 -64.940434)
			(xy 298.430303 -65.115749) (xy 298.46252 -65.324324) (xy 298.463125 -65.329562) (xy 352.362008 -65.329562)
			(xy 352.362008 -64.465962) (xy 352.362494 -64.438711) (xy 352.37025 -64.384763) (xy 352.385605 -64.332468)
			(xy 352.408247 -64.282891) (xy 352.437713 -64.237041) (xy 352.473404 -64.19585) (xy 352.514595 -64.160159)
			(xy 352.560445 -64.130693) (xy 352.610022 -64.108051) (xy 352.662317 -64.092696) (xy 352.716265 -64.08494)
			(xy 352.770767 -64.08494) (xy 352.824715 -64.092696) (xy 352.87701 -64.108051) (xy 352.926587 -64.130693)
			(xy 352.972437 -64.160159) (xy 353.013628 -64.19585) (xy 353.049319 -64.237041) (xy 353.078785 -64.282891)
			(xy 353.101427 -64.332468) (xy 353.116782 -64.384763) (xy 353.124538 -64.438711) (xy 353.125024 -64.465962)
			(xy 353.125024 -65.329562) (xy 353.124538 -65.356813) (xy 353.116782 -65.410761) (xy 353.101427 -65.463056)
			(xy 353.078785 -65.512633) (xy 353.049319 -65.558483) (xy 353.013628 -65.599674) (xy 352.972437 -65.635365)
			(xy 352.926587 -65.664831) (xy 352.87701 -65.687473) (xy 352.824715 -65.702828) (xy 352.770767 -65.710584)
			(xy 352.716265 -65.710584) (xy 352.662317 -65.702828) (xy 352.610022 -65.687473) (xy 352.560445 -65.664831)
			(xy 352.514595 -65.635365) (xy 352.473404 -65.599674) (xy 352.437713 -65.558483) (xy 352.408247 -65.512633)
			(xy 352.385605 -65.463056) (xy 352.37025 -65.410761) (xy 352.362494 -65.356813) (xy 352.362008 -65.329562)
			(xy 298.463125 -65.329562) (xy 298.486723 -65.533981) (xy 298.502879 -65.74441) (xy 298.510963 -65.955304)
			(xy 298.511468 -66.060828) (xy 298.511468 -68.449952) (xy 314.840884 -68.449952) (xy 314.844867 -68.321934)
			(xy 314.856802 -68.194412) (xy 314.876641 -68.067878) (xy 314.904308 -67.942822) (xy 314.939697 -67.819729)
			(xy 314.98267 -67.699073) (xy 315.033061 -67.581323) (xy 315.090675 -67.466933) (xy 315.155289 -67.356346)
			(xy 315.226653 -67.24999) (xy 315.304491 -67.148277) (xy 315.388502 -67.051599) (xy 315.478361 -66.960332)
			(xy 315.57372 -66.874827) (xy 315.674211 -66.795417) (xy 315.779444 -66.722407) (xy 315.889013 -66.656081)
			(xy 316.002493 -66.596695) (xy 316.119445 -66.544479) (xy 316.239418 -66.499635) (xy 316.361946 -66.462337)
			(xy 316.486557 -66.432728) (xy 316.612766 -66.410923) (xy 316.740088 -66.397007) (xy 316.868028 -66.391033)
			(xy 316.996092 -66.393025) (xy 317.123785 -66.402975) (xy 317.250612 -66.420844) (xy 317.376083 -66.446563)
			(xy 317.499712 -66.480033) (xy 317.621021 -66.521124) (xy 317.739541 -66.569678) (xy 317.854813 -66.625506)
			(xy 317.966391 -66.688392) (xy 318.073844 -66.758094) (xy 318.176756 -66.834341) (xy 318.274728 -66.916838)
			(xy 318.323666 -66.963544) (xy 350.27108 -66.963544) (xy 350.27108 -66.099944) (xy 350.271566 -66.072693)
			(xy 350.279322 -66.018745) (xy 350.294677 -65.96645) (xy 350.317319 -65.916873) (xy 350.346785 -65.871023)
			(xy 350.382476 -65.829832) (xy 350.423667 -65.794141) (xy 350.469517 -65.764675) (xy 350.519094 -65.742033)
			(xy 350.571389 -65.726678) (xy 350.625337 -65.718922) (xy 350.679839 -65.718922) (xy 350.733787 -65.726678)
			(xy 350.786082 -65.742033) (xy 350.835659 -65.764675) (xy 350.881509 -65.794141) (xy 350.9227 -65.829832)
			(xy 350.958391 -65.871023) (xy 350.987857 -65.916873) (xy 351.010499 -65.96645) (xy 351.025854 -66.018745)
			(xy 351.03361 -66.072693) (xy 351.034096 -66.099944) (xy 351.034096 -66.963544) (xy 351.03361 -66.990795)
			(xy 351.025854 -67.044743) (xy 351.010499 -67.097038) (xy 351.005595 -67.107776) (xy 396.642323 -67.107776)
			(xy 396.642323 -67.022004) (xy 396.650237 -66.936596) (xy 396.665998 -66.852284) (xy 396.689471 -66.769785)
			(xy 396.720456 -66.689804) (xy 396.758688 -66.613023) (xy 396.803842 -66.540098) (xy 396.855532 -66.47165)
			(xy 396.913317 -66.408263) (xy 396.976704 -66.350478) (xy 397.045152 -66.298788) (xy 397.118077 -66.253634)
			(xy 397.194858 -66.215402) (xy 397.274839 -66.184417) (xy 397.357338 -66.160944) (xy 397.44165 -66.145183)
			(xy 397.527058 -66.137269) (xy 397.61283 -66.137269) (xy 397.698238 -66.145183) (xy 397.78255 -66.160944)
			(xy 397.865049 -66.184417) (xy 397.94503 -66.215402) (xy 398.021811 -66.253634) (xy 398.094736 -66.298788)
			(xy 398.163184 -66.350478) (xy 398.226571 -66.408263) (xy 398.284356 -66.47165) (xy 398.336046 -66.540098)
			(xy 398.3812 -66.613023) (xy 398.419432 -66.689804) (xy 398.450417 -66.769785) (xy 398.47389 -66.852284)
			(xy 398.489651 -66.936596) (xy 398.497565 -67.022004) (xy 398.49806 -67.06489) (xy 398.497565 -67.107776)
			(xy 398.489651 -67.193184) (xy 398.47389 -67.277496) (xy 398.450417 -67.359995) (xy 398.419432 -67.439976)
			(xy 398.3812 -67.516757) (xy 398.336046 -67.589682) (xy 398.284356 -67.65813) (xy 398.226571 -67.721517)
			(xy 398.163184 -67.779302) (xy 398.094736 -67.830992) (xy 398.021811 -67.876146) (xy 397.94503 -67.914378)
			(xy 397.865049 -67.945363) (xy 397.78255 -67.968836) (xy 397.698238 -67.984597) (xy 397.61283 -67.992511)
			(xy 397.527058 -67.992511) (xy 397.44165 -67.984597) (xy 397.357338 -67.968836) (xy 397.274839 -67.945363)
			(xy 397.194858 -67.914378) (xy 397.118077 -67.876146) (xy 397.045152 -67.830992) (xy 396.976704 -67.779302)
			(xy 396.913317 -67.721517) (xy 396.855532 -67.65813) (xy 396.803842 -67.589682) (xy 396.758688 -67.516757)
			(xy 396.720456 -67.439976) (xy 396.689471 -67.359995) (xy 396.665998 -67.277496) (xy 396.650237 -67.193184)
			(xy 396.642323 -67.107776) (xy 351.005595 -67.107776) (xy 350.987857 -67.146615) (xy 350.958391 -67.192465)
			(xy 350.9227 -67.233656) (xy 350.881509 -67.269347) (xy 350.835659 -67.298813) (xy 350.786082 -67.321455)
			(xy 350.733787 -67.33681) (xy 350.679839 -67.344566) (xy 350.625337 -67.344566) (xy 350.571389 -67.33681)
			(xy 350.519094 -67.321455) (xy 350.469517 -67.298813) (xy 350.423667 -67.269347) (xy 350.382476 -67.233656)
			(xy 350.346785 -67.192465) (xy 350.317319 -67.146615) (xy 350.294677 -67.097038) (xy 350.279322 -67.044743)
			(xy 350.271566 -66.990795) (xy 350.27108 -66.963544) (xy 318.323666 -66.963544) (xy 318.367382 -67.005267)
			(xy 318.454359 -67.099285) (xy 318.535323 -67.198528) (xy 318.60996 -67.302613) (xy 318.677982 -67.411137)
			(xy 318.739126 -67.52368) (xy 318.793154 -67.639806) (xy 318.839859 -67.759067) (xy 318.879059 -67.881)
			(xy 318.910602 -68.005135) (xy 318.934367 -68.130991) (xy 318.950261 -68.25808) (xy 318.958224 -68.385912)
			(xy 318.958722 -68.449952) (xy 318.958224 -68.513992) (xy 318.950261 -68.641824) (xy 318.934367 -68.768913)
			(xy 318.910602 -68.894769) (xy 318.879059 -69.018904) (xy 318.851129 -69.10578) (xy 351.73158 -69.10578)
			(xy 351.73158 -68.24218) (xy 351.732066 -68.214911) (xy 351.739828 -68.160927) (xy 351.755193 -68.108597)
			(xy 351.77785 -68.058987) (xy 351.807336 -68.013106) (xy 351.843051 -67.971889) (xy 351.884268 -67.936174)
			(xy 351.930149 -67.906688) (xy 351.979759 -67.884031) (xy 352.032089 -67.868666) (xy 352.086073 -67.860904)
			(xy 352.140611 -67.860904) (xy 352.194595 -67.868666) (xy 352.246925 -67.884031) (xy 352.296535 -67.906688)
			(xy 352.342416 -67.936174) (xy 352.383633 -67.971889) (xy 352.419348 -68.013106) (xy 352.448834 -68.058987)
			(xy 352.471491 -68.108597) (xy 352.486856 -68.160927) (xy 352.494618 -68.214911) (xy 352.495104 -68.24218)
			(xy 352.495104 -69.10578) (xy 352.494618 -69.133049) (xy 352.486856 -69.187033) (xy 352.471491 -69.239363)
			(xy 352.448834 -69.288973) (xy 352.419348 -69.334854) (xy 352.383633 -69.376071) (xy 352.342416 -69.411786)
			(xy 352.296535 -69.441272) (xy 352.246925 -69.463929) (xy 352.194595 -69.479294) (xy 352.140611 -69.487056)
			(xy 352.086073 -69.487056) (xy 352.032089 -69.479294) (xy 351.979759 -69.463929) (xy 351.930149 -69.441272)
			(xy 351.884268 -69.411786) (xy 351.843051 -69.376071) (xy 351.807336 -69.334854) (xy 351.77785 -69.288973)
			(xy 351.755193 -69.239363) (xy 351.739828 -69.187033) (xy 351.732066 -69.133049) (xy 351.73158 -69.10578)
			(xy 318.851129 -69.10578) (xy 318.839859 -69.140837) (xy 318.793154 -69.260098) (xy 318.739126 -69.376224)
			(xy 318.677982 -69.488767) (xy 318.60996 -69.597291) (xy 318.535323 -69.701376) (xy 318.454359 -69.800619)
			(xy 318.367382 -69.894637) (xy 318.274728 -69.983066) (xy 318.176756 -70.065563) (xy 318.073844 -70.14181)
			(xy 317.966391 -70.211512) (xy 317.854813 -70.274398) (xy 317.739541 -70.330226) (xy 317.621021 -70.37878)
			(xy 317.499712 -70.419871) (xy 317.376083 -70.453341) (xy 317.250612 -70.47906) (xy 317.123785 -70.496929)
			(xy 316.996092 -70.506879) (xy 316.868028 -70.508871) (xy 316.740088 -70.502897) (xy 316.612766 -70.488981)
			(xy 316.486557 -70.467176) (xy 316.361946 -70.437567) (xy 316.239418 -70.400269) (xy 316.119445 -70.355425)
			(xy 316.002493 -70.303209) (xy 315.889013 -70.243823) (xy 315.779444 -70.177497) (xy 315.674211 -70.104487)
			(xy 315.57372 -70.025077) (xy 315.478361 -69.939572) (xy 315.388502 -69.848305) (xy 315.304491 -69.751627)
			(xy 315.226653 -69.649914) (xy 315.155289 -69.543558) (xy 315.090675 -69.432971) (xy 315.033061 -69.318581)
			(xy 314.98267 -69.200831) (xy 314.939697 -69.080175) (xy 314.904308 -68.957082) (xy 314.876641 -68.832026)
			(xy 314.856802 -68.705492) (xy 314.844867 -68.57797) (xy 314.840884 -68.449952) (xy 298.511468 -68.449952)
			(xy 298.511468 -71.213074) (xy 341.168388 -71.213074) (xy 341.168388 -71.158526) (xy 341.176151 -71.104534)
			(xy 341.19152 -71.052197) (xy 341.214181 -71.00258) (xy 341.243673 -70.956692) (xy 341.279395 -70.91547)
			(xy 341.320621 -70.879751) (xy 341.366511 -70.850263) (xy 341.416131 -70.827607) (xy 341.46847 -70.812243)
			(xy 341.522462 -70.804485) (xy 341.549736 -70.804024) (xy 342.413336 -70.804024) (xy 342.440603 -70.804541)
			(xy 342.49458 -70.812306) (xy 342.546904 -70.827674) (xy 342.596508 -70.850332) (xy 342.642382 -70.879817)
			(xy 342.683594 -70.915531) (xy 342.719304 -70.956747) (xy 342.748786 -71.002624) (xy 342.771438 -71.05223)
			(xy 342.786801 -71.104555) (xy 342.794562 -71.158533) (xy 342.794562 -71.213067) (xy 342.786801 -71.267045)
			(xy 342.771438 -71.31937) (xy 342.748786 -71.368976) (xy 342.719304 -71.414853) (xy 342.683594 -71.456069)
			(xy 342.642382 -71.491783) (xy 342.596508 -71.521268) (xy 342.546904 -71.543926) (xy 342.49458 -71.559294)
			(xy 342.440603 -71.567059) (xy 342.413336 -71.567548) (xy 341.549736 -71.567548) (xy 341.522462 -71.567115)
			(xy 341.46847 -71.559357) (xy 341.416131 -71.543993) (xy 341.366511 -71.521337) (xy 341.320621 -71.491849)
			(xy 341.279395 -71.45613) (xy 341.243673 -71.414908) (xy 341.214181 -71.36902) (xy 341.19152 -71.319403)
			(xy 341.176151 -71.267066) (xy 341.168388 -71.213074) (xy 298.511468 -71.213074) (xy 298.511468 -71.844253)
			(xy 346.360454 -71.844253) (xy 346.360454 -71.789747) (xy 346.368211 -71.735796) (xy 346.383567 -71.683499)
			(xy 346.406209 -71.633919) (xy 346.435677 -71.588066) (xy 346.47137 -71.546873) (xy 346.512562 -71.511179)
			(xy 346.558415 -71.481711) (xy 346.607995 -71.459068) (xy 346.660293 -71.443712) (xy 346.714243 -71.435954)
			(xy 346.741496 -71.435468) (xy 347.605096 -71.435468) (xy 347.632347 -71.435979) (xy 347.686295 -71.443735)
			(xy 347.73859 -71.45909) (xy 347.788168 -71.481731) (xy 347.834019 -71.511197) (xy 347.875209 -71.546888)
			(xy 347.910901 -71.588078) (xy 347.940367 -71.633929) (xy 347.963009 -71.683506) (xy 347.978364 -71.735801)
			(xy 347.986121 -71.789749) (xy 347.986121 -71.844251) (xy 347.978364 -71.898199) (xy 347.963009 -71.950494)
			(xy 347.940367 -72.000071) (xy 347.910901 -72.045922) (xy 347.875209 -72.087112) (xy 347.834019 -72.122803)
			(xy 347.788168 -72.152269) (xy 347.73859 -72.17491) (xy 347.686295 -72.190265) (xy 347.632347 -72.198021)
			(xy 347.605096 -72.198484) (xy 346.741496 -72.198484) (xy 346.714243 -72.198046) (xy 346.660293 -72.190288)
			(xy 346.607995 -72.174932) (xy 346.558415 -72.152289) (xy 346.512562 -72.122821) (xy 346.47137 -72.087127)
			(xy 346.435677 -72.045934) (xy 346.406209 -72.000081) (xy 346.383567 -71.950501) (xy 346.368211 -71.898204)
			(xy 346.360454 -71.844253) (xy 298.511468 -71.844253) (xy 298.511468 -72.404055) (xy 332.037847 -72.404055)
			(xy 332.037847 -72.349545) (xy 332.045606 -72.295589) (xy 332.060964 -72.243286) (xy 332.083611 -72.193702)
			(xy 332.113083 -72.147846) (xy 332.148782 -72.106651) (xy 332.189981 -72.070957) (xy 332.235841 -72.041489)
			(xy 332.285427 -72.018849) (xy 332.337732 -72.003496) (xy 332.391689 -71.995744) (xy 332.418944 -71.995284)
			(xy 333.282544 -71.995284) (xy 333.309793 -71.995789) (xy 333.363734 -72.00355) (xy 333.416023 -72.018909)
			(xy 333.465593 -72.041552) (xy 333.511437 -72.071019) (xy 333.552622 -72.10671) (xy 333.588308 -72.147898)
			(xy 333.617769 -72.193745) (xy 333.640407 -72.243318) (xy 333.655759 -72.295609) (xy 333.660251 -72.326853)
			(xy 343.845854 -72.326853) (xy 343.845854 -72.272347) (xy 343.853611 -72.218396) (xy 343.868967 -72.166099)
			(xy 343.891609 -72.116519) (xy 343.921077 -72.070666) (xy 343.95677 -72.029473) (xy 343.997962 -71.993779)
			(xy 344.043815 -71.964311) (xy 344.093395 -71.941668) (xy 344.145693 -71.926312) (xy 344.199643 -71.918554)
			(xy 344.226896 -71.918068) (xy 345.090496 -71.918068) (xy 345.117747 -71.918579) (xy 345.171695 -71.926335)
			(xy 345.22399 -71.94169) (xy 345.273568 -71.964331) (xy 345.319419 -71.993797) (xy 345.360609 -72.029488)
			(xy 345.396301 -72.070678) (xy 345.425767 -72.116529) (xy 345.448409 -72.166106) (xy 345.463764 -72.218401)
			(xy 345.471521 -72.272349) (xy 345.471521 -72.326851) (xy 345.463764 -72.380799) (xy 345.448409 -72.433094)
			(xy 345.425767 -72.482671) (xy 345.396301 -72.528522) (xy 345.360609 -72.569712) (xy 345.319419 -72.605403)
			(xy 345.273568 -72.634869) (xy 345.22399 -72.65751) (xy 345.171695 -72.672865) (xy 345.117747 -72.680621)
			(xy 345.090496 -72.681084) (xy 344.226896 -72.681084) (xy 344.199643 -72.680646) (xy 344.145693 -72.672888)
			(xy 344.093395 -72.657532) (xy 344.043815 -72.634889) (xy 343.997962 -72.605421) (xy 343.95677 -72.569727)
			(xy 343.921077 -72.528534) (xy 343.891609 -72.482681) (xy 343.868967 -72.433101) (xy 343.853611 -72.380804)
			(xy 343.845854 -72.326853) (xy 333.660251 -72.326853) (xy 333.663514 -72.349551) (xy 333.663514 -72.404049)
			(xy 333.655759 -72.457991) (xy 333.640407 -72.510282) (xy 333.617769 -72.559855) (xy 333.588308 -72.605702)
			(xy 333.552622 -72.64689) (xy 333.511437 -72.682581) (xy 333.465593 -72.712048) (xy 333.416023 -72.734691)
			(xy 333.363734 -72.75005) (xy 333.309793 -72.757811) (xy 333.282544 -72.7583) (xy 332.418944 -72.7583)
			(xy 332.391689 -72.757856) (xy 332.337732 -72.750104) (xy 332.285427 -72.734751) (xy 332.235841 -72.712111)
			(xy 332.189981 -72.682643) (xy 332.148782 -72.646949) (xy 332.113083 -72.605754) (xy 332.083611 -72.559898)
			(xy 332.060964 -72.510314) (xy 332.045606 -72.458011) (xy 332.037847 -72.404055) (xy 298.511468 -72.404055)
			(xy 298.511468 -74.617072) (xy 327.277726 -74.617072) (xy 327.281813 -74.561227) (xy 327.293988 -74.506573)
			(xy 327.31399 -74.454274) (xy 327.341395 -74.405445) (xy 327.375617 -74.361126) (xy 327.415927 -74.322262)
			(xy 327.461466 -74.289681) (xy 327.511264 -74.264078) (xy 327.564259 -74.245999) (xy 327.619321 -74.235828)
			(xy 327.675278 -74.233783) (xy 327.730936 -74.239908) (xy 327.785109 -74.25407) (xy 327.836643 -74.27597)
			(xy 327.884439 -74.305139) (xy 327.927478 -74.340957) (xy 327.941626 -74.356747) (xy 330.744122 -74.356747)
			(xy 330.744122 -74.302253) (xy 330.751877 -74.248315) (xy 330.767229 -74.196029) (xy 330.789865 -74.146459)
			(xy 330.819325 -74.100616) (xy 330.855009 -74.059431) (xy 330.89619 -74.023744) (xy 330.942031 -73.99428)
			(xy 330.991599 -73.97164) (xy 331.043883 -73.956284) (xy 331.097821 -73.948524) (xy 331.125068 -73.948036)
			(xy 331.988668 -73.948036) (xy 332.015926 -73.948409) (xy 332.069886 -73.956163) (xy 332.122194 -73.971518)
			(xy 332.171784 -73.994161) (xy 332.217646 -74.023632) (xy 332.258848 -74.05933) (xy 332.294549 -74.100528)
			(xy 332.324023 -74.146388) (xy 332.346671 -74.195976) (xy 332.36203 -74.248283) (xy 332.369789 -74.302243)
			(xy 332.369789 -74.356757) (xy 332.36203 -74.410717) (xy 332.346671 -74.463024) (xy 332.324023 -74.512612)
			(xy 332.294549 -74.558472) (xy 332.26684 -74.590448) (xy 336.274202 -74.590448) (xy 336.274202 -74.535953)
			(xy 336.281957 -74.482012) (xy 336.297309 -74.429724) (xy 336.319945 -74.380153) (xy 336.349406 -74.334308)
			(xy 336.38509 -74.293121) (xy 336.426272 -74.257432) (xy 336.472114 -74.227966) (xy 336.521683 -74.205324)
			(xy 336.573969 -74.189966) (xy 336.627909 -74.182205) (xy 336.655156 -74.181716) (xy 337.518756 -74.181716)
			(xy 337.546013 -74.182128) (xy 337.599972 -74.18988) (xy 337.652278 -74.205233) (xy 337.701867 -74.227875)
			(xy 337.747729 -74.257344) (xy 337.788929 -74.29304) (xy 337.82463 -74.334236) (xy 337.854104 -74.380094)
			(xy 337.876751 -74.42968) (xy 337.89211 -74.481985) (xy 337.899869 -74.535943) (xy 337.899869 -74.55185)
			(xy 339.156294 -74.55185) (xy 339.156294 -74.49735) (xy 339.16405 -74.443405) (xy 339.179404 -74.391113)
			(xy 339.202044 -74.341539) (xy 339.231509 -74.29569) (xy 339.267198 -74.254502) (xy 339.308386 -74.218812)
			(xy 339.354233 -74.189347) (xy 339.403808 -74.166707) (xy 339.456099 -74.151352) (xy 339.510044 -74.143595)
			(xy 339.537294 -74.143108) (xy 340.400894 -74.143108) (xy 340.428148 -74.143538) (xy 340.482102 -74.151295)
			(xy 340.534403 -74.166651) (xy 340.583986 -74.189294) (xy 340.629842 -74.218763) (xy 340.671037 -74.254459)
			(xy 340.706733 -74.295653) (xy 340.736203 -74.341509) (xy 340.758847 -74.391091) (xy 340.774204 -74.443392)
			(xy 340.781961 -74.497346) (xy 340.781961 -74.551854) (xy 340.774204 -74.605808) (xy 340.758847 -74.658109)
			(xy 340.736203 -74.707691) (xy 340.706733 -74.753547) (xy 340.694254 -74.767948) (xy 421.29456 -74.767948)
			(xy 421.29456 -66.06794) (xy 421.295065 -65.962416) (xy 421.303149 -65.751522) (xy 421.319305 -65.541093)
			(xy 421.343508 -65.331436) (xy 421.375725 -65.122861) (xy 421.415907 -64.915673) (xy 421.463995 -64.710176)
			(xy 421.519919 -64.506672) (xy 421.583596 -64.305459) (xy 421.654934 -64.106832) (xy 421.733828 -63.911084)
			(xy 421.820161 -63.718502) (xy 421.913808 -63.529367) (xy 422.01463 -63.343958) (xy 422.12248 -63.162547)
			(xy 422.237199 -62.9854) (xy 422.358619 -62.812778) (xy 422.486562 -62.644932) (xy 422.62084 -62.48211)
			(xy 422.761256 -62.324551) (xy 422.907604 -62.172486) (xy 423.059669 -62.026138) (xy 423.217228 -61.885722)
			(xy 423.38005 -61.751444) (xy 423.547896 -61.623501) (xy 423.720518 -61.502081) (xy 423.897665 -61.387362)
			(xy 424.079076 -61.279512) (xy 424.264485 -61.17869) (xy 424.45362 -61.085043) (xy 424.646202 -60.99871)
			(xy 424.84195 -60.919816) (xy 425.040577 -60.848478) (xy 425.24179 -60.784801) (xy 425.445294 -60.728877)
			(xy 425.650791 -60.680789) (xy 425.857979 -60.640607) (xy 426.066554 -60.60839) (xy 426.276211 -60.584187)
			(xy 426.48664 -60.568031) (xy 426.697534 -60.559947) (xy 426.908582 -60.559947) (xy 427.119476 -60.568031)
			(xy 427.329905 -60.584187) (xy 427.539562 -60.60839) (xy 427.748137 -60.640607) (xy 427.955325 -60.680789)
			(xy 428.160822 -60.728877) (xy 428.364326 -60.784801) (xy 428.565539 -60.848478) (xy 428.764166 -60.919816)
			(xy 428.959914 -60.99871) (xy 429.152496 -61.085043) (xy 429.341631 -61.17869) (xy 429.52704 -61.279512)
			(xy 429.708451 -61.387362) (xy 429.885598 -61.502081) (xy 430.05822 -61.623501) (xy 430.226066 -61.751444)
			(xy 430.388888 -61.885722) (xy 430.546447 -62.026138) (xy 430.698512 -62.172486) (xy 430.84486 -62.324551)
			(xy 430.985276 -62.48211) (xy 431.119554 -62.644932) (xy 431.247497 -62.812778) (xy 431.368917 -62.9854)
			(xy 431.483636 -63.162547) (xy 431.591486 -63.343958) (xy 431.692308 -63.529367) (xy 431.785955 -63.718502)
			(xy 431.872288 -63.911084) (xy 431.951182 -64.106832) (xy 432.02252 -64.305459) (xy 432.086197 -64.506672)
			(xy 432.142121 -64.710176) (xy 432.190209 -64.915673) (xy 432.230391 -65.122861) (xy 432.262608 -65.331436)
			(xy 432.286811 -65.541093) (xy 432.302967 -65.751522) (xy 432.311051 -65.962416) (xy 432.311556 -66.06794)
			(xy 432.311556 -74.767948) (xy 432.311051 -74.873472) (xy 432.302967 -75.084366) (xy 432.286811 -75.294795)
			(xy 432.262608 -75.504452) (xy 432.230391 -75.713027) (xy 432.190209 -75.920215) (xy 432.142121 -76.125712)
			(xy 432.086197 -76.329216) (xy 432.02252 -76.530429) (xy 431.951182 -76.729056) (xy 431.872288 -76.924804)
			(xy 431.785955 -77.117386) (xy 431.692308 -77.306521) (xy 431.591486 -77.49193) (xy 431.483636 -77.673341)
			(xy 431.368917 -77.850488) (xy 431.247497 -78.02311) (xy 431.119554 -78.190956) (xy 430.985276 -78.353778)
			(xy 430.84486 -78.511337) (xy 430.698512 -78.663402) (xy 430.546447 -78.80975) (xy 430.388888 -78.950166)
			(xy 430.226066 -79.084444) (xy 430.05822 -79.212387) (xy 429.885598 -79.333807) (xy 429.708451 -79.448526)
			(xy 429.52704 -79.556376) (xy 429.341631 -79.657198) (xy 429.152496 -79.750845) (xy 428.959914 -79.837178)
			(xy 428.764166 -79.916072) (xy 428.565539 -79.98741) (xy 428.364326 -80.051087) (xy 428.160822 -80.107011)
			(xy 427.955325 -80.155099) (xy 427.748137 -80.195281) (xy 427.539562 -80.227498) (xy 427.329905 -80.251701)
			(xy 427.119476 -80.267857) (xy 426.908582 -80.275941) (xy 426.697534 -80.275941) (xy 426.48664 -80.267857)
			(xy 426.276211 -80.251701) (xy 426.066554 -80.227498) (xy 425.857979 -80.195281) (xy 425.650791 -80.155099)
			(xy 425.445294 -80.107011) (xy 425.24179 -80.051087) (xy 425.040577 -79.98741) (xy 424.84195 -79.916072)
			(xy 424.646202 -79.837178) (xy 424.45362 -79.750845) (xy 424.264485 -79.657198) (xy 424.079076 -79.556376)
			(xy 423.897665 -79.448526) (xy 423.720518 -79.333807) (xy 423.547896 -79.212387) (xy 423.38005 -79.084444)
			(xy 423.217228 -78.950166) (xy 423.059669 -78.80975) (xy 422.907604 -78.663402) (xy 422.761256 -78.511337)
			(xy 422.62084 -78.353778) (xy 422.486562 -78.190956) (xy 422.358619 -78.02311) (xy 422.237199 -77.850488)
			(xy 422.12248 -77.673341) (xy 422.01463 -77.49193) (xy 421.913808 -77.306521) (xy 421.820161 -77.117386)
			(xy 421.733828 -76.924804) (xy 421.654934 -76.729056) (xy 421.583596 -76.530429) (xy 421.519919 -76.329216)
			(xy 421.463995 -76.125712) (xy 421.415907 -75.920215) (xy 421.375725 -75.713027) (xy 421.343508 -75.504452)
			(xy 421.319305 -75.294795) (xy 421.303149 -75.084366) (xy 421.295065 -74.873472) (xy 421.29456 -74.767948)
			(xy 340.694254 -74.767948) (xy 340.671037 -74.794741) (xy 340.629842 -74.830437) (xy 340.583986 -74.859906)
			(xy 340.534403 -74.882549) (xy 340.482102 -74.897905) (xy 340.428148 -74.905662) (xy 340.400894 -74.906124)
			(xy 339.537294 -74.906124) (xy 339.510044 -74.905605) (xy 339.456099 -74.897848) (xy 339.403808 -74.882493)
			(xy 339.354233 -74.859853) (xy 339.308386 -74.830388) (xy 339.267198 -74.794698) (xy 339.231509 -74.75351)
			(xy 339.202044 -74.707661) (xy 339.179404 -74.658087) (xy 339.16405 -74.605795) (xy 339.156294 -74.55185)
			(xy 337.899869 -74.55185) (xy 337.899869 -74.590457) (xy 337.89211 -74.644415) (xy 337.876751 -74.69672)
			(xy 337.854104 -74.746306) (xy 337.82463 -74.792164) (xy 337.788929 -74.83336) (xy 337.747729 -74.869056)
			(xy 337.701867 -74.898525) (xy 337.652278 -74.921167) (xy 337.599972 -74.93652) (xy 337.546013 -74.944272)
			(xy 337.518756 -74.944732) (xy 336.655156 -74.944732) (xy 336.627909 -74.944195) (xy 336.573969 -74.936434)
			(xy 336.521683 -74.921076) (xy 336.472114 -74.898434) (xy 336.426272 -74.868968) (xy 336.38509 -74.833279)
			(xy 336.349406 -74.792092) (xy 336.319945 -74.746247) (xy 336.297309 -74.696676) (xy 336.281957 -74.644388)
			(xy 336.274202 -74.590448) (xy 332.26684 -74.590448) (xy 332.258848 -74.59967) (xy 332.217646 -74.635368)
			(xy 332.171784 -74.664839) (xy 332.122194 -74.687482) (xy 332.069886 -74.702837) (xy 332.015926 -74.710591)
			(xy 331.988668 -74.711052) (xy 331.125068 -74.711052) (xy 331.097821 -74.710476) (xy 331.043883 -74.702716)
			(xy 330.991599 -74.68736) (xy 330.942031 -74.66472) (xy 330.89619 -74.635256) (xy 330.855009 -74.599569)
			(xy 330.819325 -74.558384) (xy 330.789865 -74.512541) (xy 330.767229 -74.462971) (xy 330.751877 -74.410685)
			(xy 330.744122 -74.356747) (xy 327.941626 -74.356747) (xy 327.964844 -74.38266) (xy 327.99574 -74.429358)
			(xy 328.019507 -74.480058) (xy 328.035639 -74.533678) (xy 328.043791 -74.589075) (xy 328.044302 -74.617072)
			(xy 328.043791 -74.645069) (xy 328.035639 -74.700466) (xy 328.019507 -74.754086) (xy 327.99574 -74.804786)
			(xy 327.964844 -74.851484) (xy 327.927478 -74.893187) (xy 327.884439 -74.929005) (xy 327.836643 -74.958174)
			(xy 327.785109 -74.980074) (xy 327.730936 -74.994236) (xy 327.675278 -75.000361) (xy 327.619321 -74.998316)
			(xy 327.564259 -74.988145) (xy 327.511264 -74.970066) (xy 327.461466 -74.944463) (xy 327.415927 -74.911882)
			(xy 327.375617 -74.873018) (xy 327.341395 -74.828699) (xy 327.31399 -74.77987) (xy 327.293988 -74.727571)
			(xy 327.281813 -74.672917) (xy 327.277726 -74.617072) (xy 298.511468 -74.617072) (xy 298.511468 -74.760836)
			(xy 298.510963 -74.86636) (xy 298.502879 -75.077254) (xy 298.486723 -75.287683) (xy 298.46252 -75.49734)
			(xy 298.430303 -75.705915) (xy 298.390121 -75.913103) (xy 298.342033 -76.1186) (xy 298.333664 -76.149054)
			(xy 327.558346 -76.149054) (xy 327.558346 -76.094546) (xy 327.566103 -76.040594) (xy 327.581459 -75.988295)
			(xy 327.604102 -75.938714) (xy 327.633571 -75.892859) (xy 327.669266 -75.851666) (xy 327.710459 -75.815971)
			(xy 327.756314 -75.786502) (xy 327.805895 -75.763859) (xy 327.858194 -75.748503) (xy 327.912146 -75.740746)
			(xy 327.9394 -75.74026) (xy 328.803 -75.74026) (xy 328.830249 -75.74081) (xy 328.884192 -75.748566)
			(xy 328.936482 -75.76392) (xy 328.986055 -75.786559) (xy 329.031902 -75.816023) (xy 329.073089 -75.851711)
			(xy 329.108777 -75.892898) (xy 329.138241 -75.938745) (xy 329.16088 -75.988318) (xy 329.169581 -76.017949)
			(xy 334.874382 -76.017949) (xy 334.874382 -75.963451) (xy 334.882137 -75.909507) (xy 334.89749 -75.857216)
			(xy 334.920128 -75.807642) (xy 334.949591 -75.761793) (xy 334.985278 -75.720605) (xy 335.026463 -75.684914)
			(xy 335.072308 -75.655447) (xy 335.12188 -75.632803) (xy 335.17417 -75.617445) (xy 335.228113 -75.609684)
			(xy 335.255362 -75.609196) (xy 336.118962 -75.609196) (xy 336.146217 -75.609649) (xy 336.200173 -75.617401)
			(xy 336.252475 -75.632754) (xy 336.302061 -75.655395) (xy 336.347919 -75.684862) (xy 336.389117 -75.720556)
			(xy 336.424815 -75.76175) (xy 336.454287 -75.807606) (xy 336.476932 -75.857189) (xy 336.49229 -75.90949)
			(xy 336.500049 -75.963445) (xy 336.500049 -76.017955) (xy 336.49229 -76.07191) (xy 336.476932 -76.124211)
			(xy 336.454287 -76.173794) (xy 336.424815 -76.21965) (xy 336.389117 -76.260844) (xy 336.347919 -76.296538)
			(xy 336.302061 -76.326005) (xy 336.252475 -76.348646) (xy 336.200173 -76.363999) (xy 336.146217 -76.371751)
			(xy 336.118962 -76.372212) (xy 335.255362 -76.372212) (xy 335.228113 -76.371716) (xy 335.17417 -76.363955)
			(xy 335.12188 -76.348597) (xy 335.072308 -76.325953) (xy 335.026463 -76.296486) (xy 334.985278 -76.260795)
			(xy 334.949591 -76.219607) (xy 334.920128 -76.173758) (xy 334.89749 -76.124184) (xy 334.882137 -76.071893)
			(xy 334.874382 -76.017949) (xy 329.169581 -76.017949) (xy 329.176234 -76.040608) (xy 329.18399 -76.094551)
			(xy 329.18399 -76.149049) (xy 329.176234 -76.202992) (xy 329.16088 -76.255282) (xy 329.138241 -76.304855)
			(xy 329.108777 -76.350702) (xy 329.073089 -76.391889) (xy 329.031902 -76.427577) (xy 328.986055 -76.457041)
			(xy 328.936482 -76.47968) (xy 328.884192 -76.495034) (xy 328.830249 -76.50279) (xy 328.803 -76.503276)
			(xy 327.9394 -76.503276) (xy 327.912146 -76.502854) (xy 327.858194 -76.495097) (xy 327.805895 -76.479741)
			(xy 327.756314 -76.457098) (xy 327.710459 -76.427629) (xy 327.669266 -76.391934) (xy 327.633571 -76.350741)
			(xy 327.604102 -76.304886) (xy 327.581459 -76.255305) (xy 327.566103 -76.203006) (xy 327.558346 -76.149054)
			(xy 298.333664 -76.149054) (xy 298.286109 -76.322104) (xy 298.222432 -76.523317) (xy 298.151094 -76.721944)
			(xy 298.0722 -76.917692) (xy 297.985867 -77.110274) (xy 297.89222 -77.299409) (xy 297.791398 -77.484818)
			(xy 297.683548 -77.666229) (xy 297.568829 -77.843376) (xy 297.455321 -78.00475) (xy 330.84567 -78.00475)
			(xy 330.84567 -77.95025) (xy 330.853426 -77.896304) (xy 330.868779 -77.84401) (xy 330.891419 -77.794434)
			(xy 330.920883 -77.748584) (xy 330.956571 -77.707394) (xy 330.997759 -77.671702) (xy 331.043606 -77.642234)
			(xy 331.09318 -77.619591) (xy 331.145472 -77.604232) (xy 331.199418 -77.596472) (xy 331.226668 -77.595984)
			(xy 332.090268 -77.595984) (xy 332.117522 -77.596461) (xy 332.171475 -77.604214) (xy 332.223776 -77.619567)
			(xy 332.273359 -77.642207) (xy 332.319215 -77.671674) (xy 332.360411 -77.707367) (xy 332.396107 -77.748559)
			(xy 332.425577 -77.794413) (xy 332.448222 -77.843994) (xy 332.463579 -77.896294) (xy 332.471337 -77.950246)
			(xy 332.471337 -78.004754) (xy 332.463579 -78.058706) (xy 332.448222 -78.111006) (xy 332.425577 -78.160587)
			(xy 332.396107 -78.206441) (xy 332.360411 -78.247633) (xy 332.319215 -78.283326) (xy 332.273359 -78.312793)
			(xy 332.223776 -78.335433) (xy 332.171475 -78.350786) (xy 332.117522 -78.358539) (xy 332.090268 -78.359)
			(xy 331.226668 -78.359) (xy 331.199418 -78.358528) (xy 331.145472 -78.350768) (xy 331.09318 -78.335409)
			(xy 331.043606 -78.312766) (xy 330.997759 -78.283298) (xy 330.956571 -78.247606) (xy 330.920883 -78.206416)
			(xy 330.891419 -78.160566) (xy 330.868779 -78.11099) (xy 330.853426 -78.058696) (xy 330.84567 -78.00475)
			(xy 297.455321 -78.00475) (xy 297.447409 -78.015998) (xy 297.319466 -78.183844) (xy 297.185188 -78.346666)
			(xy 297.044772 -78.504225) (xy 296.898424 -78.65629) (xy 296.746359 -78.802638) (xy 296.5888 -78.943054)
			(xy 296.425978 -79.077332) (xy 296.258132 -79.205275) (xy 296.08551 -79.326695) (xy 295.908363 -79.441414)
			(xy 295.726952 -79.549264) (xy 295.541543 -79.650086) (xy 295.352408 -79.743733) (xy 295.159826 -79.830066)
			(xy 294.964078 -79.90896) (xy 294.765451 -79.980298) (xy 294.564238 -80.043975) (xy 294.360734 -80.099899)
			(xy 294.155237 -80.147987) (xy 293.948049 -80.188169) (xy 293.739474 -80.220386) (xy 293.529817 -80.244589)
			(xy 293.319388 -80.260745) (xy 293.108494 -80.268829) (xy 292.897446 -80.268829) (xy 292.686552 -80.260745)
			(xy 292.476123 -80.244589) (xy 292.266466 -80.220386) (xy 292.057891 -80.188169) (xy 291.850703 -80.147987)
			(xy 291.645206 -80.099899) (xy 291.441702 -80.043975) (xy 291.240489 -79.980298) (xy 291.041862 -79.90896)
			(xy 290.846114 -79.830066) (xy 290.653532 -79.743733) (xy 290.464397 -79.650086) (xy 290.278988 -79.549264)
			(xy 290.097577 -79.441414) (xy 289.92043 -79.326695) (xy 289.747808 -79.205275) (xy 289.579962 -79.077332)
			(xy 289.41714 -78.943054) (xy 289.259581 -78.802638) (xy 289.107516 -78.65629) (xy 288.961168 -78.504225)
			(xy 288.820752 -78.346666) (xy 288.686474 -78.183844) (xy 288.558531 -78.015998) (xy 288.437111 -77.843376)
			(xy 288.322392 -77.666229) (xy 288.214542 -77.484818) (xy 288.11372 -77.299409) (xy 288.020073 -77.110274)
			(xy 287.93374 -76.917692) (xy 287.854846 -76.721944) (xy 287.783508 -76.523317) (xy 287.719831 -76.322104)
			(xy 287.663907 -76.1186) (xy 287.615819 -75.913103) (xy 287.575637 -75.705915) (xy 287.54342 -75.49734)
			(xy 287.519217 -75.287683) (xy 287.503061 -75.077254) (xy 287.494977 -74.86636) (xy 287.494472 -74.760836)
			(xy 184.371488 -74.760836) (xy 184.371488 -74.767948) (xy 184.370983 -74.873472) (xy 184.362899 -75.084366)
			(xy 184.346743 -75.294795) (xy 184.32254 -75.504452) (xy 184.290323 -75.713027) (xy 184.250141 -75.920215)
			(xy 184.202053 -76.125712) (xy 184.146129 -76.329216) (xy 184.082452 -76.530429) (xy 184.011114 -76.729056)
			(xy 183.93222 -76.924804) (xy 183.845887 -77.117386) (xy 183.75224 -77.306521) (xy 183.651418 -77.49193)
			(xy 183.543568 -77.673341) (xy 183.428849 -77.850488) (xy 183.307429 -78.02311) (xy 183.179486 -78.190956)
			(xy 183.045208 -78.353778) (xy 182.904792 -78.511337) (xy 182.758444 -78.663402) (xy 182.606379 -78.80975)
			(xy 182.44882 -78.950166) (xy 182.285998 -79.084444) (xy 182.118152 -79.212387) (xy 181.94553 -79.333807)
			(xy 181.768383 -79.448526) (xy 181.586972 -79.556376) (xy 181.401563 -79.657198) (xy 181.212428 -79.750845)
			(xy 181.019846 -79.837178) (xy 180.824098 -79.916072) (xy 180.625471 -79.98741) (xy 180.424258 -80.051087)
			(xy 180.220754 -80.107011) (xy 180.015257 -80.155099) (xy 179.808069 -80.195281) (xy 179.599494 -80.227498)
			(xy 179.389837 -80.251701) (xy 179.179408 -80.267857) (xy 178.968514 -80.275941) (xy 178.757466 -80.275941)
			(xy 178.546572 -80.267857) (xy 178.336143 -80.251701) (xy 178.126486 -80.227498) (xy 177.917911 -80.195281)
			(xy 177.710723 -80.155099) (xy 177.505226 -80.107011) (xy 177.301722 -80.051087) (xy 177.100509 -79.98741)
			(xy 176.901882 -79.916072) (xy 176.706134 -79.837178) (xy 176.513552 -79.750845) (xy 176.324417 -79.657198)
			(xy 176.139008 -79.556376) (xy 175.957597 -79.448526) (xy 175.78045 -79.333807) (xy 175.607828 -79.212387)
			(xy 175.439982 -79.084444) (xy 175.27716 -78.950166) (xy 175.119601 -78.80975) (xy 174.967536 -78.663402)
			(xy 174.821188 -78.511337) (xy 174.680772 -78.353778) (xy 174.546494 -78.190956) (xy 174.418551 -78.02311)
			(xy 174.297131 -77.850488) (xy 174.182412 -77.673341) (xy 174.074562 -77.49193) (xy 173.97374 -77.306521)
			(xy 173.880093 -77.117386) (xy 173.79376 -76.924804) (xy 173.714866 -76.729056) (xy 173.643528 -76.530429)
			(xy 173.579851 -76.329216) (xy 173.523927 -76.125712) (xy 173.475839 -75.920215) (xy 173.435657 -75.713027)
			(xy 173.40344 -75.504452) (xy 173.379237 -75.294795) (xy 173.363081 -75.084366) (xy 173.354997 -74.873472)
			(xy 173.354492 -74.767948) (xy 50.571366 -74.767948) (xy 50.570895 -74.86636) (xy 50.562811 -75.077254)
			(xy 50.546655 -75.287683) (xy 50.522452 -75.49734) (xy 50.490235 -75.705915) (xy 50.450053 -75.913103)
			(xy 50.401965 -76.1186) (xy 50.346041 -76.322104) (xy 50.282364 -76.523317) (xy 50.211026 -76.721944)
			(xy 50.132132 -76.917692) (xy 50.045799 -77.110274) (xy 49.952152 -77.299409) (xy 49.85133 -77.484818)
			(xy 49.74348 -77.666229) (xy 49.628761 -77.843376) (xy 49.507341 -78.015998) (xy 49.379398 -78.183844)
			(xy 49.24512 -78.346666) (xy 49.104704 -78.504225) (xy 48.958356 -78.65629) (xy 48.806291 -78.802638)
			(xy 48.648732 -78.943054) (xy 48.48591 -79.077332) (xy 48.318064 -79.205275) (xy 48.145442 -79.326695)
			(xy 47.968295 -79.441414) (xy 47.786884 -79.549264) (xy 47.601475 -79.650086) (xy 47.41234 -79.743733)
			(xy 47.219758 -79.830066) (xy 47.02401 -79.90896) (xy 46.825383 -79.980298) (xy 46.62417 -80.043975)
			(xy 46.420666 -80.099899) (xy 46.215169 -80.147987) (xy 46.007981 -80.188169) (xy 45.799406 -80.220386)
			(xy 45.589749 -80.244589) (xy 45.37932 -80.260745) (xy 45.168426 -80.268829) (xy 44.957378 -80.268829)
			(xy 44.746484 -80.260745) (xy 44.536055 -80.244589) (xy 44.326398 -80.220386) (xy 44.117823 -80.188169)
			(xy 43.910635 -80.147987) (xy 43.705138 -80.099899) (xy 43.501634 -80.043975) (xy 43.300421 -79.980298)
			(xy 43.101794 -79.90896) (xy 42.906046 -79.830066) (xy 42.713464 -79.743733) (xy 42.524329 -79.650086)
			(xy 42.33892 -79.549264) (xy 42.157509 -79.441414) (xy 41.980362 -79.326695) (xy 41.80774 -79.205275)
			(xy 41.639894 -79.077332) (xy 41.477072 -78.943054) (xy 41.319513 -78.802638) (xy 41.167448 -78.65629)
			(xy 41.0211 -78.504225) (xy 40.880684 -78.346666) (xy 40.746406 -78.183844) (xy 40.618463 -78.015998)
			(xy 40.497043 -77.843376) (xy 40.382324 -77.666229) (xy 40.274474 -77.484818) (xy 40.173652 -77.299409)
			(xy 40.080005 -77.110274) (xy 39.993672 -76.917692) (xy 39.914778 -76.721944) (xy 39.84344 -76.523317)
			(xy 39.779763 -76.322104) (xy 39.723839 -76.1186) (xy 39.675751 -75.913103) (xy 39.635569 -75.705915)
			(xy 39.603352 -75.49734) (xy 39.579149 -75.287683) (xy 39.562993 -75.077254) (xy 39.554909 -74.86636)
			(xy 39.554404 -74.760836) (xy 0.509016 -74.760836) (xy 0.509016 -77.671676) (xy 0.509504 -77.724899)
			(xy 0.51712 -77.831071) (xy 0.532286 -77.93643) (xy 0.554925 -78.04044) (xy 0.584921 -78.142572)
			(xy 0.622123 -78.242305) (xy 0.666339 -78.339132) (xy 0.717347 -78.43256) (xy 0.774885 -78.522114)
			(xy 0.838661 -78.607338) (xy 0.908351 -78.687799) (xy 0.945642 -78.725776) (xy 1.77419 -79.554324)
			(xy 1.823602 -79.604436) (xy 1.917388 -79.709385) (xy 2.005143 -79.819428) (xy 2.08659 -79.934217)
			(xy 2.161473 -80.053392) (xy 2.229556 -80.176578) (xy 2.290626 -80.303388) (xy 2.344491 -80.433422)
			(xy 2.39098 -80.566271) (xy 2.429948 -80.701518) (xy 2.461272 -80.838737) (xy 2.484853 -80.977496)
			(xy 2.500618 -81.117359) (xy 2.508516 -81.257886) (xy 2.509012 -81.32826) (xy 2.509012 -81.69181)
			(xy 232.140667 -81.69181) (xy 232.145062 -81.517977) (xy 232.15749 -81.344533) (xy 232.177927 -81.171849)
			(xy 232.206328 -81.000295) (xy 232.242632 -80.830238) (xy 232.286762 -80.662042) (xy 232.338623 -80.496067)
			(xy 232.398104 -80.332668) (xy 232.465078 -80.172194) (xy 232.539402 -80.01499) (xy 232.620917 -79.86139)
			(xy 232.709448 -79.711725) (xy 232.804805 -79.566315) (xy 232.906785 -79.425469) (xy 233.01517 -79.289491)
			(xy 233.129727 -79.158671) (xy 233.250212 -79.033288) (xy 233.376366 -78.913612) (xy 233.50792 -78.799897)
			(xy 233.644592 -78.692389) (xy 233.715052 -78.641448) (xy 238.08436 -78.641448) (xy 238.15482 -78.692389)
			(xy 238.291492 -78.799897) (xy 238.423046 -78.913612) (xy 238.5492 -79.033288) (xy 238.669685 -79.158671)
			(xy 238.784242 -79.289491) (xy 238.892627 -79.425469) (xy 238.994607 -79.566315) (xy 239.089964 -79.711725)
			(xy 239.178495 -79.86139) (xy 239.26001 -80.01499) (xy 239.334334 -80.172194) (xy 239.401308 -80.332668)
			(xy 239.460789 -80.496067) (xy 239.51265 -80.662042) (xy 239.553507 -80.817765) (xy 333.938166 -80.817765)
			(xy 333.938166 -80.763235) (xy 333.945926 -80.70926) (xy 333.961289 -80.656938) (xy 333.98394 -80.607335)
			(xy 334.01342 -80.561461) (xy 334.049129 -80.520248) (xy 334.090338 -80.484537) (xy 334.136211 -80.455054)
			(xy 334.185812 -80.432398) (xy 334.238132 -80.417032) (xy 334.292107 -80.409268) (xy 334.319372 -80.40878)
			(xy 335.182972 -80.40878) (xy 335.210247 -80.409158) (xy 335.264243 -80.416917) (xy 335.316585 -80.432283)
			(xy 335.366207 -80.454941) (xy 335.412099 -80.484432) (xy 335.453327 -80.520153) (xy 335.489052 -80.561378)
			(xy 335.518545 -80.607268) (xy 335.541207 -80.656889) (xy 335.556577 -80.709229) (xy 335.56434 -80.763225)
			(xy 335.56434 -80.817775) (xy 335.556577 -80.871771) (xy 335.541207 -80.924111) (xy 335.518545 -80.973732)
			(xy 335.489052 -81.019622) (xy 335.453327 -81.060847) (xy 335.412099 -81.096568) (xy 335.366207 -81.126059)
			(xy 335.316585 -81.148717) (xy 335.264243 -81.164083) (xy 335.210247 -81.171842) (xy 335.182972 -81.172304)
			(xy 334.319372 -81.172304) (xy 334.292107 -81.171732) (xy 334.238132 -81.163968) (xy 334.185812 -81.148602)
			(xy 334.136211 -81.125946) (xy 334.090338 -81.096463) (xy 334.049129 -81.060752) (xy 334.01342 -81.019539)
			(xy 333.98394 -80.973665) (xy 333.961289 -80.924062) (xy 333.945926 -80.87174) (xy 333.938166 -80.817765)
			(xy 239.553507 -80.817765) (xy 239.55678 -80.830238) (xy 239.593084 -81.000295) (xy 239.621485 -81.171849)
			(xy 239.641922 -81.344533) (xy 239.65435 -81.517977) (xy 239.658745 -81.69181) (xy 239.655095 -81.865661)
			(xy 239.643409 -82.039157) (xy 239.640092 -82.06825) (xy 331.768962 -82.06825) (xy 331.768962 -82.01375)
			(xy 331.776717 -81.959803) (xy 331.792071 -81.90751) (xy 331.81471 -81.857933) (xy 331.844174 -81.812083)
			(xy 331.879862 -81.770892) (xy 331.921049 -81.735199) (xy 331.966896 -81.70573) (xy 332.01647 -81.683086)
			(xy 332.068762 -81.667726) (xy 332.122708 -81.659965) (xy 332.149958 -81.659476) (xy 333.013558 -81.659476)
			(xy 333.040812 -81.659968) (xy 333.094765 -81.66772) (xy 333.147066 -81.683072) (xy 333.196649 -81.705711)
			(xy 333.242505 -81.735177) (xy 333.283701 -81.770869) (xy 333.319398 -81.812061) (xy 333.348869 -81.857914)
			(xy 333.371513 -81.907495) (xy 333.386871 -81.959794) (xy 333.394629 -82.013746) (xy 333.394629 -82.068254)
			(xy 333.386871 -82.122206) (xy 333.371513 -82.174505) (xy 333.348869 -82.224086) (xy 333.319398 -82.269939)
			(xy 333.294774 -82.298353) (xy 336.189263 -82.298353) (xy 336.189263 -82.243847) (xy 336.197021 -82.189895)
			(xy 336.212377 -82.137597) (xy 336.235021 -82.088017) (xy 336.26449 -82.042163) (xy 336.300185 -82.000971)
			(xy 336.341379 -81.965278) (xy 336.387234 -81.935811) (xy 336.436816 -81.91317) (xy 336.489115 -81.897816)
			(xy 336.543067 -81.890062) (xy 336.57032 -81.8896) (xy 337.43392 -81.8896) (xy 337.461171 -81.890071)
			(xy 337.515118 -81.89783) (xy 337.567411 -81.913187) (xy 337.616987 -81.93583) (xy 337.662836 -81.965298)
			(xy 337.692804 -81.991267) (xy 339.478646 -81.991267) (xy 339.478646 -81.936733) (xy 339.486407 -81.882755)
			(xy 339.50177 -81.830431) (xy 339.524423 -81.780825) (xy 339.553905 -81.734948) (xy 339.589615 -81.693734)
			(xy 339.630827 -81.65802) (xy 339.676702 -81.628535) (xy 339.726306 -81.605879) (xy 339.77863 -81.590512)
			(xy 339.832607 -81.582748) (xy 339.859874 -81.58226) (xy 340.723474 -81.58226) (xy 340.750748 -81.582678)
			(xy 340.804741 -81.590437) (xy 340.857079 -81.605802) (xy 340.906699 -81.62846) (xy 340.952588 -81.657948)
			(xy 340.993814 -81.693668) (xy 341.029536 -81.734891) (xy 341.059028 -81.780778) (xy 341.081689 -81.830396)
			(xy 341.097057 -81.882734) (xy 341.10482 -81.936726) (xy 341.10482 -81.991274) (xy 341.097057 -82.045266)
			(xy 341.081689 -82.097604) (xy 341.059028 -82.147222) (xy 341.029536 -82.193109) (xy 340.993814 -82.234332)
			(xy 340.952588 -82.270052) (xy 340.906699 -82.29954) (xy 340.857079 -82.322198) (xy 340.804741 -82.337563)
			(xy 340.750748 -82.345322) (xy 340.723474 -82.345784) (xy 339.859874 -82.345784) (xy 339.832607 -82.345252)
			(xy 339.77863 -82.337488) (xy 339.726306 -82.322121) (xy 339.676702 -82.299465) (xy 339.630827 -82.26998)
			(xy 339.589615 -82.234266) (xy 339.553905 -82.193052) (xy 339.524423 -82.147175) (xy 339.50177 -82.097569)
			(xy 339.486407 -82.045245) (xy 339.478646 -81.991267) (xy 337.692804 -81.991267) (xy 337.704024 -82.00099)
			(xy 337.739714 -82.04218) (xy 337.76918 -82.088031) (xy 337.79182 -82.137608) (xy 337.807174 -82.189902)
			(xy 337.81493 -82.243849) (xy 337.81493 -82.298351) (xy 337.807174 -82.352298) (xy 337.79182 -82.404592)
			(xy 337.769179 -82.454169) (xy 337.739714 -82.50002) (xy 337.704024 -82.54121) (xy 337.662836 -82.576902)
			(xy 337.616987 -82.60637) (xy 337.567411 -82.629013) (xy 337.515118 -82.64437) (xy 337.461171 -82.652129)
			(xy 337.43392 -82.652616) (xy 336.57032 -82.652616) (xy 336.543067 -82.652138) (xy 336.489115 -82.644384)
			(xy 336.436816 -82.62903) (xy 336.387234 -82.606389) (xy 336.341379 -82.576922) (xy 336.300185 -82.541229)
			(xy 336.26449 -82.500037) (xy 336.235021 -82.454183) (xy 336.212377 -82.404603) (xy 336.197021 -82.352305)
			(xy 336.189263 -82.298353) (xy 333.294774 -82.298353) (xy 333.283701 -82.311131) (xy 333.242505 -82.346823)
			(xy 333.196649 -82.376289) (xy 333.147066 -82.398928) (xy 333.094765 -82.41428) (xy 333.040812 -82.422032)
			(xy 333.013558 -82.422492) (xy 332.149958 -82.422492) (xy 332.122708 -82.422035) (xy 332.068762 -82.414274)
			(xy 332.01647 -82.398914) (xy 331.966896 -82.37627) (xy 331.921049 -82.346801) (xy 331.879862 -82.311108)
			(xy 331.844174 -82.269917) (xy 331.81471 -82.224067) (xy 331.792071 -82.17449) (xy 331.776717 -82.122197)
			(xy 331.768962 -82.06825) (xy 239.640092 -82.06825) (xy 239.623713 -82.211927) (xy 239.596047 -82.383601)
			(xy 239.560472 -82.553811) (xy 239.517063 -82.722195) (xy 239.465913 -82.888391) (xy 239.407133 -83.052043)
			(xy 239.340846 -83.212802) (xy 239.267197 -83.370324) (xy 239.186341 -83.524271) (xy 239.148735 -83.588471)
			(xy 341.356398 -83.588471) (xy 341.356398 -83.533929) (xy 341.364161 -83.479942) (xy 341.379527 -83.427609)
			(xy 341.402184 -83.377996) (xy 341.431672 -83.332112) (xy 341.467389 -83.290892) (xy 341.508609 -83.255174)
			(xy 341.554492 -83.225686) (xy 341.604106 -83.203028) (xy 341.656438 -83.187661) (xy 341.710425 -83.179899)
			(xy 341.737696 -83.179412) (xy 342.601296 -83.179412) (xy 342.628565 -83.179927) (xy 342.682549 -83.187688)
			(xy 342.734879 -83.203053) (xy 342.784489 -83.225709) (xy 342.83037 -83.255194) (xy 342.871588 -83.290909)
			(xy 342.907303 -83.332127) (xy 342.936789 -83.378008) (xy 342.959445 -83.427618) (xy 342.974811 -83.479947)
			(xy 342.982573 -83.533931) (xy 342.982573 -83.588469) (xy 342.974811 -83.642453) (xy 342.959445 -83.694782)
			(xy 342.936789 -83.744392) (xy 342.907303 -83.790273) (xy 342.871588 -83.831491) (xy 342.83037 -83.867206)
			(xy 342.784489 -83.896691) (xy 342.734879 -83.919347) (xy 342.682549 -83.934712) (xy 342.628565 -83.942473)
			(xy 342.601296 -83.942936) (xy 341.737696 -83.942936) (xy 341.710425 -83.942501) (xy 341.656438 -83.934739)
			(xy 341.604106 -83.919372) (xy 341.554492 -83.896714) (xy 341.508609 -83.867226) (xy 341.467389 -83.831508)
			(xy 341.431672 -83.790288) (xy 341.402184 -83.744404) (xy 341.379527 -83.694791) (xy 341.364161 -83.642458)
			(xy 341.356398 -83.588471) (xy 239.148735 -83.588471) (xy 239.098452 -83.674314) (xy 239.003718 -83.820132)
			(xy 238.902342 -83.961413) (xy 238.794541 -84.097854) (xy 238.680545 -84.229164) (xy 238.560599 -84.355062)
			(xy 238.434958 -84.475277) (xy 238.393119 -84.511757) (xy 337.882119 -84.511757) (xy 337.882119 -84.457243)
			(xy 337.889878 -84.403284) (xy 337.905237 -84.350979) (xy 337.927883 -84.301392) (xy 337.957357 -84.255533)
			(xy 337.993057 -84.214336) (xy 338.034257 -84.178639) (xy 338.080119 -84.149169) (xy 338.129707 -84.126526)
			(xy 338.182014 -84.111171) (xy 338.235973 -84.103417) (xy 338.26323 -84.102956) (xy 339.12683 -84.102956)
			(xy 339.154077 -84.103516) (xy 339.208017 -84.111275) (xy 339.260303 -84.126632) (xy 339.309871 -84.149272)
			(xy 339.355714 -84.178737) (xy 339.396896 -84.214425) (xy 339.432581 -84.25561) (xy 339.462042 -84.301455)
			(xy 339.484679 -84.351025) (xy 339.500031 -84.403313) (xy 339.503159 -84.425069) (xy 344.644951 -84.425069)
			(xy 344.644951 -84.370531) (xy 344.652713 -84.316548) (xy 344.668079 -84.26422) (xy 344.690737 -84.214611)
			(xy 344.720223 -84.168731) (xy 344.75594 -84.127516) (xy 344.797159 -84.091803) (xy 344.843041 -84.06232)
			(xy 344.892652 -84.039668) (xy 344.944981 -84.024306) (xy 344.998965 -84.016549) (xy 345.026234 -84.016088)
			(xy 345.889834 -84.016088) (xy 345.917105 -84.016477) (xy 345.971092 -84.024243) (xy 346.023425 -84.039614)
			(xy 346.073037 -84.062275) (xy 346.11892 -84.091766) (xy 346.160139 -84.127485) (xy 346.195855 -84.168708)
			(xy 346.225341 -84.214593) (xy 346.247998 -84.264207) (xy 346.263364 -84.316541) (xy 346.271126 -84.370529)
			(xy 346.271126 -84.425071) (xy 346.263364 -84.479059) (xy 346.247998 -84.531393) (xy 346.225341 -84.581007)
			(xy 346.195855 -84.626892) (xy 346.160139 -84.668115) (xy 346.11892 -84.703834) (xy 346.073037 -84.733325)
			(xy 346.023425 -84.755986) (xy 345.971092 -84.771357) (xy 345.917105 -84.779123) (xy 345.889834 -84.779612)
			(xy 345.026234 -84.779612) (xy 344.998965 -84.779051) (xy 344.944981 -84.771294) (xy 344.892652 -84.755932)
			(xy 344.843041 -84.73328) (xy 344.797159 -84.703797) (xy 344.75594 -84.668084) (xy 344.720223 -84.626869)
			(xy 344.690737 -84.580989) (xy 344.668079 -84.53138) (xy 344.652713 -84.479052) (xy 344.644951 -84.425069)
			(xy 339.503159 -84.425069) (xy 339.507786 -84.457253) (xy 339.507786 -84.511747) (xy 339.500031 -84.565687)
			(xy 339.484679 -84.617975) (xy 339.462042 -84.667545) (xy 339.432581 -84.71339) (xy 339.396896 -84.754575)
			(xy 339.355714 -84.790263) (xy 339.309871 -84.819728) (xy 339.260303 -84.842368) (xy 339.208017 -84.857725)
			(xy 339.154077 -84.865484) (xy 339.12683 -84.865972) (xy 338.26323 -84.865972) (xy 338.235973 -84.865583)
			(xy 338.182014 -84.857829) (xy 338.129707 -84.842474) (xy 338.080119 -84.819831) (xy 338.034257 -84.790361)
			(xy 337.993057 -84.754664) (xy 337.957357 -84.713467) (xy 337.927883 -84.667608) (xy 337.905237 -84.618021)
			(xy 337.889878 -84.565716) (xy 337.882119 -84.511757) (xy 238.393119 -84.511757) (xy 238.303893 -84.589554)
			(xy 238.167683 -84.697647) (xy 238.02662 -84.799326) (xy 237.881005 -84.894371) (xy 237.73115 -84.982581)
			(xy 237.577377 -85.063767) (xy 237.420014 -85.137754) (xy 237.259397 -85.204384) (xy 237.095871 -85.263515)
			(xy 236.929785 -85.315021) (xy 236.761494 -85.35879) (xy 236.59136 -85.39473) (xy 236.419746 -85.422763)
			(xy 236.247019 -85.44283) (xy 236.073548 -85.454887) (xy 235.899706 -85.458909) (xy 235.725864 -85.454887)
			(xy 235.552393 -85.44283) (xy 235.379666 -85.422763) (xy 235.208052 -85.39473) (xy 235.037918 -85.35879)
			(xy 234.869627 -85.315021) (xy 234.703541 -85.263515) (xy 234.540015 -85.204384) (xy 234.379398 -85.137754)
			(xy 234.222035 -85.063767) (xy 234.068262 -84.982581) (xy 233.918407 -84.894371) (xy 233.772792 -84.799326)
			(xy 233.631729 -84.697647) (xy 233.495519 -84.589554) (xy 233.364454 -84.475277) (xy 233.238813 -84.355062)
			(xy 233.118867 -84.229164) (xy 233.004871 -84.097854) (xy 232.89707 -83.961413) (xy 232.795694 -83.820132)
			(xy 232.70096 -83.674314) (xy 232.613071 -83.524271) (xy 232.532215 -83.370324) (xy 232.458566 -83.212802)
			(xy 232.392279 -83.052043) (xy 232.333499 -82.888391) (xy 232.282349 -82.722195) (xy 232.23894 -82.553811)
			(xy 232.203365 -82.383601) (xy 232.175699 -82.211927) (xy 232.156003 -82.039157) (xy 232.144317 -81.865661)
			(xy 232.140667 -81.69181) (xy 2.509012 -81.69181) (xy 2.509012 -85.764678) (xy 10.421355 -85.764678)
			(xy 10.421355 -85.635538) (xy 10.429305 -85.506643) (xy 10.445175 -85.378483) (xy 10.468904 -85.251542)
			(xy 10.500403 -85.126303) (xy 10.539552 -85.00324) (xy 10.586203 -84.882821) (xy 10.640178 -84.765502)
			(xy 10.701273 -84.651728) (xy 10.769256 -84.541931) (xy 10.84387 -84.436528) (xy 10.924831 -84.335918)
			(xy 11.011831 -84.240483) (xy 11.104542 -84.150584) (xy 11.202612 -84.066563) (xy 11.305667 -83.988739)
			(xy 11.413318 -83.917407) (xy 11.525157 -83.852837) (xy 11.640758 -83.795275) (xy 11.759683 -83.744938)
			(xy 11.881482 -83.702018) (xy 12.005692 -83.666677) (xy 12.131841 -83.63905) (xy 12.259453 -83.619241)
			(xy 12.388042 -83.607325) (xy 12.51712 -83.603349) (xy 12.646198 -83.607325) (xy 12.774787 -83.619241)
			(xy 12.902399 -83.63905) (xy 13.028548 -83.666677) (xy 13.152758 -83.702018) (xy 13.274557 -83.744938)
			(xy 13.393482 -83.795275) (xy 13.509083 -83.852837) (xy 13.620922 -83.917407) (xy 13.728573 -83.988739)
			(xy 13.831628 -84.066563) (xy 13.929698 -84.150584) (xy 14.022409 -84.240483) (xy 14.109409 -84.335918)
			(xy 14.19037 -84.436528) (xy 14.264984 -84.541931) (xy 14.332967 -84.651728) (xy 14.394062 -84.765502)
			(xy 14.448037 -84.882821) (xy 14.494688 -85.00324) (xy 14.533837 -85.126303) (xy 14.565336 -85.251542)
			(xy 14.589065 -85.378483) (xy 14.604935 -85.506643) (xy 14.612885 -85.635538) (xy 14.613382 -85.700108)
			(xy 14.612885 -85.764678) (xy 14.608278 -85.839368) (xy 342.975946 -85.839368) (xy 342.975946 -85.784832)
			(xy 342.983708 -85.730852) (xy 342.999072 -85.678525) (xy 343.021727 -85.628918) (xy 343.051211 -85.58304)
			(xy 343.086924 -85.541824) (xy 343.12814 -85.506111) (xy 343.174018 -85.476627) (xy 343.223625 -85.453972)
			(xy 343.275952 -85.438608) (xy 343.329932 -85.430846) (xy 343.3572 -85.43036) (xy 344.2208 -85.43036)
			(xy 344.248071 -85.430802) (xy 344.302058 -85.438565) (xy 344.35439 -85.453931) (xy 344.404003 -85.476588)
			(xy 344.449887 -85.506076) (xy 344.491107 -85.541793) (xy 344.526824 -85.583013) (xy 344.556312 -85.628897)
			(xy 344.578969 -85.67851) (xy 344.594335 -85.730842) (xy 344.602098 -85.784829) (xy 344.602098 -85.839371)
			(xy 344.594335 -85.893358) (xy 344.578969 -85.94569) (xy 344.556312 -85.995303) (xy 344.526824 -86.041187)
			(xy 344.491107 -86.082407) (xy 344.449887 -86.118124) (xy 344.404003 -86.147612) (xy 344.35439 -86.170269)
			(xy 344.302058 -86.185635) (xy 344.248071 -86.193398) (xy 344.2208 -86.193884) (xy 343.3572 -86.193884)
			(xy 343.329932 -86.193354) (xy 343.275952 -86.185592) (xy 343.223625 -86.170228) (xy 343.174018 -86.147573)
			(xy 343.12814 -86.118089) (xy 343.086924 -86.082376) (xy 343.051211 -86.04116) (xy 343.021727 -85.995282)
			(xy 342.999072 -85.945675) (xy 342.983708 -85.893348) (xy 342.975946 -85.839368) (xy 14.608278 -85.839368)
			(xy 14.604935 -85.893573) (xy 14.589065 -86.021733) (xy 14.565336 -86.148674) (xy 14.533837 -86.273913)
			(xy 14.494688 -86.396976) (xy 14.448037 -86.517395) (xy 14.394062 -86.634714) (xy 14.332967 -86.748488)
			(xy 14.264984 -86.858285) (xy 14.19037 -86.963688) (xy 14.109409 -87.064298) (xy 14.022409 -87.159733)
			(xy 13.929698 -87.249632) (xy 13.831628 -87.333653) (xy 13.728573 -87.411477) (xy 13.620922 -87.482809)
			(xy 13.509083 -87.547379) (xy 13.393482 -87.604941) (xy 13.274557 -87.655278) (xy 13.152758 -87.698198)
			(xy 13.028548 -87.733539) (xy 12.902399 -87.761166) (xy 12.774787 -87.780975) (xy 12.646198 -87.792891)
			(xy 12.51712 -87.796868) (xy 12.388042 -87.792891) (xy 12.259453 -87.780975) (xy 12.131841 -87.761166)
			(xy 12.005692 -87.733539) (xy 11.881482 -87.698198) (xy 11.759683 -87.655278) (xy 11.640758 -87.604941)
			(xy 11.525157 -87.547379) (xy 11.413318 -87.482809) (xy 11.305667 -87.411477) (xy 11.202612 -87.333653)
			(xy 11.104542 -87.249632) (xy 11.011831 -87.159733) (xy 10.924831 -87.064298) (xy 10.84387 -86.963688)
			(xy 10.769256 -86.858285) (xy 10.701273 -86.748488) (xy 10.640178 -86.634714) (xy 10.586203 -86.517395)
			(xy 10.539552 -86.396976) (xy 10.500403 -86.273913) (xy 10.468904 -86.148674) (xy 10.445175 -86.021733)
			(xy 10.429305 -85.893573) (xy 10.421355 -85.764678) (xy 2.509012 -85.764678) (xy 2.509012 -98.341434)
			(xy 261.733792 -98.341434) (xy 261.733792 -97.477834) (xy 261.734278 -97.450583) (xy 261.742034 -97.396635)
			(xy 261.757389 -97.34434) (xy 261.780031 -97.294763) (xy 261.809497 -97.248913) (xy 261.845188 -97.207722)
			(xy 261.886379 -97.172031) (xy 261.932229 -97.142565) (xy 261.981806 -97.119923) (xy 262.034101 -97.104568)
			(xy 262.088049 -97.096812) (xy 262.142551 -97.096812) (xy 262.196499 -97.104568) (xy 262.248794 -97.119923)
			(xy 262.298371 -97.142565) (xy 262.344221 -97.172031) (xy 262.385412 -97.207722) (xy 262.421103 -97.248913)
			(xy 262.450569 -97.294763) (xy 262.473211 -97.34434) (xy 262.488566 -97.396635) (xy 262.496322 -97.450583)
			(xy 262.496808 -97.477834) (xy 262.496808 -98.341434) (xy 262.496322 -98.368685) (xy 262.488566 -98.422633)
			(xy 262.473211 -98.474928) (xy 262.450569 -98.524505) (xy 262.421103 -98.570355) (xy 262.385412 -98.611546)
			(xy 262.344221 -98.647237) (xy 262.298371 -98.676703) (xy 262.248794 -98.699345) (xy 262.196499 -98.7147)
			(xy 262.142551 -98.722456) (xy 262.088049 -98.722456) (xy 262.034101 -98.7147) (xy 261.981806 -98.699345)
			(xy 261.932229 -98.676703) (xy 261.886379 -98.647237) (xy 261.845188 -98.611546) (xy 261.809497 -98.570355)
			(xy 261.780031 -98.524505) (xy 261.757389 -98.474928) (xy 261.742034 -98.422633) (xy 261.734278 -98.368685)
			(xy 261.733792 -98.341434) (xy 2.509012 -98.341434) (xy 2.509012 -106.40187) (xy 11.713464 -106.40187)
			(xy 11.713464 -105.53827) (xy 11.71395 -105.511001) (xy 11.721712 -105.457017) (xy 11.737077 -105.404687)
			(xy 11.759734 -105.355077) (xy 11.78922 -105.309196) (xy 11.824935 -105.267979) (xy 11.866152 -105.232264)
			(xy 11.912033 -105.202778) (xy 11.961643 -105.180121) (xy 12.013973 -105.164756) (xy 12.067957 -105.156994)
			(xy 12.122495 -105.156994) (xy 12.176479 -105.164756) (xy 12.228809 -105.180121) (xy 12.278419 -105.202778)
			(xy 12.3243 -105.232264) (xy 12.365517 -105.267979) (xy 12.401232 -105.309196) (xy 12.430718 -105.355077)
			(xy 12.453375 -105.404687) (xy 12.46874 -105.457017) (xy 12.476502 -105.511001) (xy 12.476988 -105.53827)
			(xy 12.476988 -105.664) (xy 15.57274 -105.664) (xy 15.57274 -104.8004) (xy 15.573226 -104.773131)
			(xy 15.580988 -104.719147) (xy 15.596353 -104.666817) (xy 15.61901 -104.617207) (xy 15.648496 -104.571326)
			(xy 15.684211 -104.530109) (xy 15.725428 -104.494394) (xy 15.771309 -104.464908) (xy 15.820919 -104.442251)
			(xy 15.873249 -104.426886) (xy 15.927233 -104.419124) (xy 15.981771 -104.419124) (xy 16.035755 -104.426886)
			(xy 16.088085 -104.442251) (xy 16.137695 -104.464908) (xy 16.183576 -104.494394) (xy 16.224793 -104.530109)
			(xy 16.260508 -104.571326) (xy 16.289994 -104.617207) (xy 16.312651 -104.666817) (xy 16.328016 -104.719147)
			(xy 16.335778 -104.773131) (xy 16.336264 -104.8004) (xy 16.336264 -105.664) (xy 16.335778 -105.691269)
			(xy 16.328016 -105.745253) (xy 16.312651 -105.797583) (xy 16.289994 -105.847193) (xy 16.260508 -105.893074)
			(xy 16.224793 -105.934291) (xy 16.183576 -105.970006) (xy 16.137695 -105.999492) (xy 16.088085 -106.022149)
			(xy 16.035755 -106.037514) (xy 15.981771 -106.045276) (xy 15.927233 -106.045276) (xy 15.873249 -106.037514)
			(xy 15.820919 -106.022149) (xy 15.771309 -105.999492) (xy 15.725428 -105.970006) (xy 15.684211 -105.934291)
			(xy 15.648496 -105.893074) (xy 15.61901 -105.847193) (xy 15.596353 -105.797583) (xy 15.580988 -105.745253)
			(xy 15.573226 -105.691269) (xy 15.57274 -105.664) (xy 12.476988 -105.664) (xy 12.476988 -106.40187)
			(xy 12.476502 -106.429139) (xy 12.46874 -106.483123) (xy 12.453375 -106.535453) (xy 12.430718 -106.585063)
			(xy 12.401232 -106.630944) (xy 12.365517 -106.672161) (xy 12.3243 -106.707876) (xy 12.278419 -106.737362)
			(xy 12.228809 -106.760019) (xy 12.176479 -106.775384) (xy 12.122495 -106.783146) (xy 12.067957 -106.783146)
			(xy 12.013973 -106.775384) (xy 11.961643 -106.760019) (xy 11.912033 -106.737362) (xy 11.866152 -106.707876)
			(xy 11.824935 -106.672161) (xy 11.78922 -106.630944) (xy 11.759734 -106.585063) (xy 11.737077 -106.535453)
			(xy 11.721712 -106.483123) (xy 11.71395 -106.429139) (xy 11.713464 -106.40187) (xy 2.509012 -106.40187)
			(xy 2.509012 -108.943971) (xy 11.292822 -108.943971) (xy 11.292822 -108.889469) (xy 11.300578 -108.835522)
			(xy 11.315933 -108.783228) (xy 11.338574 -108.733651) (xy 11.36804 -108.687801) (xy 11.403731 -108.646611)
			(xy 11.444921 -108.61092) (xy 11.490771 -108.581454) (xy 11.540348 -108.558813) (xy 11.592642 -108.543458)
			(xy 11.646589 -108.535702) (xy 11.67384 -108.535216) (xy 12.53744 -108.535216) (xy 12.564692 -108.535694)
			(xy 12.61864 -108.54345) (xy 12.670935 -108.558806) (xy 12.720513 -108.581447) (xy 12.766364 -108.610914)
			(xy 12.807554 -108.646606) (xy 12.843246 -108.687796) (xy 12.872713 -108.733647) (xy 12.895354 -108.783225)
			(xy 12.91071 -108.83552) (xy 12.918466 -108.889468) (xy 12.918466 -108.943972) (xy 12.918466 -108.943973)
			(xy 15.156389 -108.943973) (xy 15.156389 -108.889467) (xy 15.164146 -108.835517) (xy 15.179502 -108.783219)
			(xy 15.202145 -108.733639) (xy 15.231613 -108.687786) (xy 15.267307 -108.646594) (xy 15.308499 -108.610901)
			(xy 15.354353 -108.581433) (xy 15.403933 -108.558791) (xy 15.45623 -108.543435) (xy 15.510181 -108.535679)
			(xy 15.537434 -108.535216) (xy 16.401034 -108.535216) (xy 16.428285 -108.535694) (xy 16.482233 -108.543451)
			(xy 16.534528 -108.558807) (xy 16.584105 -108.581448) (xy 16.629956 -108.610915) (xy 16.671146 -108.646607)
			(xy 16.706837 -108.687798) (xy 16.707863 -108.689394) (xy 238.647224 -108.689394) (xy 238.647224 -107.825794)
			(xy 238.64771 -107.798525) (xy 238.655472 -107.744541) (xy 238.670837 -107.692211) (xy 238.693494 -107.642601)
			(xy 238.72298 -107.59672) (xy 238.758695 -107.555503) (xy 238.799912 -107.519788) (xy 238.845793 -107.490302)
			(xy 238.895403 -107.467645) (xy 238.947733 -107.45228) (xy 239.001717 -107.444518) (xy 239.056255 -107.444518)
			(xy 239.110239 -107.45228) (xy 239.162569 -107.467645) (xy 239.212179 -107.490302) (xy 239.25806 -107.519788)
			(xy 239.299277 -107.555503) (xy 239.334992 -107.59672) (xy 239.364478 -107.642601) (xy 239.387135 -107.692211)
			(xy 239.4025 -107.744541) (xy 239.410262 -107.798525) (xy 239.410748 -107.825794) (xy 239.410748 -108.689394)
			(xy 239.410262 -108.716663) (xy 239.4025 -108.770647) (xy 239.387135 -108.822977) (xy 239.364478 -108.872587)
			(xy 239.334992 -108.918468) (xy 239.299277 -108.959685) (xy 239.25806 -108.9954) (xy 239.212179 -109.024886)
			(xy 239.162569 -109.047543) (xy 239.110239 -109.062908) (xy 239.056255 -109.07067) (xy 239.001717 -109.07067)
			(xy 238.947733 -109.062908) (xy 238.895403 -109.047543) (xy 238.845793 -109.024886) (xy 238.799912 -108.9954)
			(xy 238.758695 -108.959685) (xy 238.72298 -108.918468) (xy 238.693494 -108.872587) (xy 238.670837 -108.822977)
			(xy 238.655472 -108.770647) (xy 238.64771 -108.716663) (xy 238.647224 -108.689394) (xy 16.707863 -108.689394)
			(xy 16.736304 -108.733648) (xy 16.758945 -108.783226) (xy 16.7743 -108.835521) (xy 16.782056 -108.889469)
			(xy 16.782056 -108.943971) (xy 16.7743 -108.997919) (xy 16.758945 -109.050214) (xy 16.736304 -109.099792)
			(xy 16.706837 -109.145642) (xy 16.671146 -109.186833) (xy 16.629956 -109.222525) (xy 16.584105 -109.251992)
			(xy 16.534528 -109.274633) (xy 16.482233 -109.289989) (xy 16.428285 -109.297746) (xy 16.401034 -109.298232)
			(xy 15.537434 -109.298232) (xy 15.510181 -109.297761) (xy 15.45623 -109.290005) (xy 15.403933 -109.274649)
			(xy 15.354353 -109.252007) (xy 15.308499 -109.222539) (xy 15.267307 -109.186846) (xy 15.231613 -109.145654)
			(xy 15.202145 -109.099801) (xy 15.179502 -109.050221) (xy 15.164146 -108.997923) (xy 15.156389 -108.943973)
			(xy 12.918466 -108.943973) (xy 12.91071 -108.99792) (xy 12.895354 -109.050215) (xy 12.872713 -109.099793)
			(xy 12.843246 -109.145644) (xy 12.807554 -109.186834) (xy 12.766364 -109.222526) (xy 12.720513 -109.251993)
			(xy 12.670935 -109.274634) (xy 12.61864 -109.28999) (xy 12.564692 -109.297746) (xy 12.53744 -109.298232)
			(xy 11.67384 -109.298232) (xy 11.646589 -109.297738) (xy 11.592642 -109.289982) (xy 11.540348 -109.274627)
			(xy 11.490771 -109.251986) (xy 11.444921 -109.22252) (xy 11.403731 -109.186829) (xy 11.36804 -109.145639)
			(xy 11.338574 -109.099789) (xy 11.315933 -109.050212) (xy 11.300578 -108.997918) (xy 11.292822 -108.943971)
			(xy 2.509012 -108.943971) (xy 2.509012 -109.550266) (xy 250.428546 -109.550266) (xy 250.428546 -109.495734)
			(xy 250.436306 -109.441757) (xy 250.451669 -109.389434) (xy 250.474321 -109.339829) (xy 250.503801 -109.293953)
			(xy 250.53951 -109.252739) (xy 250.580721 -109.217025) (xy 250.626594 -109.18754) (xy 250.676196 -109.164883)
			(xy 250.728518 -109.149515) (xy 250.782494 -109.141749) (xy 250.80976 -109.14126) (xy 251.67336 -109.14126)
			(xy 251.700634 -109.141677) (xy 251.754629 -109.149435) (xy 251.806969 -109.164798) (xy 251.85659 -109.187455)
			(xy 251.902482 -109.216943) (xy 251.943709 -109.252663) (xy 251.979433 -109.293886) (xy 252.008926 -109.339775)
			(xy 252.031588 -109.389393) (xy 252.046957 -109.441732) (xy 252.05472 -109.495726) (xy 252.05472 -109.550274)
			(xy 252.046957 -109.604268) (xy 252.031588 -109.656607) (xy 252.008926 -109.706225) (xy 251.979433 -109.752114)
			(xy 251.943709 -109.793337) (xy 251.902482 -109.829057) (xy 251.85659 -109.858545) (xy 251.806969 -109.881202)
			(xy 251.754629 -109.896565) (xy 251.700634 -109.904323) (xy 251.67336 -109.904784) (xy 250.80976 -109.904784)
			(xy 250.782494 -109.904251) (xy 250.728518 -109.896485) (xy 250.676196 -109.881117) (xy 250.626594 -109.85846)
			(xy 250.580721 -109.828975) (xy 250.53951 -109.793262) (xy 250.503801 -109.752047) (xy 250.474321 -109.706171)
			(xy 250.451669 -109.656566) (xy 250.436306 -109.604243) (xy 250.428546 -109.550266) (xy 2.509012 -109.550266)
			(xy 2.509012 -111.158274) (xy 239.40262 -111.158274) (xy 239.40262 -110.294674) (xy 239.403106 -110.267423)
			(xy 239.410862 -110.213475) (xy 239.426217 -110.16118) (xy 239.448859 -110.111603) (xy 239.478325 -110.065753)
			(xy 239.514016 -110.024562) (xy 239.555207 -109.988871) (xy 239.601057 -109.959405) (xy 239.650634 -109.936763)
			(xy 239.702929 -109.921408) (xy 239.756877 -109.913652) (xy 239.811379 -109.913652) (xy 239.865327 -109.921408)
			(xy 239.917622 -109.936763) (xy 239.967199 -109.959405) (xy 240.000574 -109.980854) (xy 256.88563 -109.980854)
			(xy 256.88563 -109.926346) (xy 256.893387 -109.872392) (xy 256.908744 -109.820091) (xy 256.931388 -109.770508)
			(xy 256.960857 -109.724652) (xy 256.996552 -109.683457) (xy 257.037747 -109.647761) (xy 257.083602 -109.61829)
			(xy 257.133185 -109.595646) (xy 257.185486 -109.580288) (xy 257.23944 -109.57253) (xy 257.266694 -109.572044)
			(xy 258.130294 -109.572044) (xy 258.157544 -109.572603) (xy 258.211488 -109.580358) (xy 258.26378 -109.595712)
			(xy 258.313355 -109.618351) (xy 258.359203 -109.647815) (xy 258.400391 -109.683504) (xy 258.436081 -109.724692)
			(xy 258.465546 -109.77054) (xy 258.488186 -109.820114) (xy 258.503541 -109.872406) (xy 258.511297 -109.92635)
			(xy 258.511297 -109.98085) (xy 258.503541 -110.034794) (xy 258.488186 -110.087086) (xy 258.465546 -110.13666)
			(xy 258.436081 -110.182508) (xy 258.400391 -110.223696) (xy 258.359203 -110.259385) (xy 258.313355 -110.288849)
			(xy 258.26378 -110.311488) (xy 258.211488 -110.326842) (xy 258.157544 -110.334597) (xy 258.130294 -110.33506)
			(xy 257.266694 -110.33506) (xy 257.23944 -110.33467) (xy 257.185486 -110.326912) (xy 257.133185 -110.311554)
			(xy 257.083602 -110.28891) (xy 257.037747 -110.259439) (xy 256.996552 -110.223743) (xy 256.960857 -110.182548)
			(xy 256.931388 -110.136692) (xy 256.908744 -110.087109) (xy 256.893387 -110.034808) (xy 256.88563 -109.980854)
			(xy 240.000574 -109.980854) (xy 240.013049 -109.988871) (xy 240.05424 -110.024562) (xy 240.089931 -110.065753)
			(xy 240.119397 -110.111603) (xy 240.142039 -110.16118) (xy 240.157394 -110.213475) (xy 240.16515 -110.267423)
			(xy 240.165636 -110.294674) (xy 240.165636 -111.158274) (xy 240.16515 -111.185525) (xy 240.157394 -111.239473)
			(xy 240.142039 -111.291768) (xy 240.119397 -111.341345) (xy 240.089931 -111.387195) (xy 240.05424 -111.428386)
			(xy 240.013049 -111.464077) (xy 239.967199 -111.493543) (xy 239.917622 -111.516185) (xy 239.865327 -111.53154)
			(xy 239.811379 -111.539296) (xy 239.756877 -111.539296) (xy 239.702929 -111.53154) (xy 239.650634 -111.516185)
			(xy 239.601057 -111.493543) (xy 239.555207 -111.464077) (xy 239.514016 -111.428386) (xy 239.478325 -111.387195)
			(xy 239.448859 -111.341345) (xy 239.426217 -111.291768) (xy 239.410862 -111.239473) (xy 239.403106 -111.185525)
			(xy 239.40262 -111.158274) (xy 2.509012 -111.158274) (xy 2.509012 -114.734161) (xy 11.255226 -114.734161)
			(xy 11.255226 -114.679659) (xy 11.262982 -114.625711) (xy 11.278337 -114.573416) (xy 11.300979 -114.523839)
			(xy 11.330445 -114.477988) (xy 11.366136 -114.436798) (xy 11.407326 -114.401106) (xy 11.453177 -114.371639)
			(xy 11.502754 -114.348998) (xy 11.555049 -114.333643) (xy 11.608997 -114.325886) (xy 11.636248 -114.3254)
			(xy 12.499848 -114.3254) (xy 12.527101 -114.325867) (xy 12.581052 -114.333624) (xy 12.633349 -114.34898)
			(xy 12.68293 -114.371622) (xy 12.728783 -114.40109) (xy 12.769975 -114.436783) (xy 12.805669 -114.477976)
			(xy 12.835137 -114.523829) (xy 12.85778 -114.573409) (xy 12.873136 -114.625706) (xy 12.880893 -114.679657)
			(xy 12.880893 -114.734163) (xy 12.873136 -114.788114) (xy 12.85778 -114.840411) (xy 12.835137 -114.889991)
			(xy 12.805669 -114.935844) (xy 12.769975 -114.977037) (xy 12.728783 -115.01273) (xy 12.68293 -115.042198)
			(xy 12.633349 -115.06484) (xy 12.581052 -115.080196) (xy 12.527101 -115.087953) (xy 12.499848 -115.088416)
			(xy 11.636248 -115.088416) (xy 11.608997 -115.087934) (xy 11.555049 -115.080177) (xy 11.502754 -115.064822)
			(xy 11.453177 -115.042181) (xy 11.407326 -115.012714) (xy 11.366136 -114.977022) (xy 11.330445 -114.935832)
			(xy 11.300979 -114.889981) (xy 11.278337 -114.840404) (xy 11.262982 -114.788109) (xy 11.255226 -114.734161)
			(xy 2.509012 -114.734161) (xy 2.509012 -116.393573) (xy 230.652992 -116.393573) (xy 230.652992 -116.339027)
			(xy 230.660755 -116.285035) (xy 230.676123 -116.232698) (xy 230.698784 -116.183081) (xy 230.728276 -116.137195)
			(xy 230.763998 -116.095973) (xy 230.805224 -116.060254) (xy 230.851113 -116.030767) (xy 230.900732 -116.008111)
			(xy 230.95307 -115.992747) (xy 231.007063 -115.984989) (xy 231.034336 -115.984528) (xy 231.897936 -115.984528)
			(xy 231.925203 -115.985037) (xy 231.979181 -115.992802) (xy 232.031505 -116.008171) (xy 232.081109 -116.030828)
			(xy 232.126985 -116.060314) (xy 232.168197 -116.096029) (xy 232.203907 -116.137244) (xy 232.233389 -116.183122)
			(xy 232.256042 -116.232729) (xy 232.271405 -116.285054) (xy 232.277026 -116.324151) (xy 236.866903 -116.324151)
			(xy 236.866903 -116.269649) (xy 236.87466 -116.215701) (xy 236.890016 -116.163407) (xy 236.912659 -116.113831)
			(xy 236.942127 -116.067981) (xy 236.97782 -116.026793) (xy 237.019012 -115.991104) (xy 237.064864 -115.961641)
			(xy 237.114443 -115.939003) (xy 237.166739 -115.923652) (xy 237.220687 -115.915901) (xy 237.247938 -115.91544)
			(xy 238.111538 -115.91544) (xy 238.138791 -115.915832) (xy 238.192741 -115.923594) (xy 238.245038 -115.938955)
			(xy 238.294617 -115.961601) (xy 238.340468 -115.991072) (xy 238.381659 -116.026768) (xy 238.417351 -116.067962)
			(xy 238.446817 -116.113817) (xy 238.469459 -116.163398) (xy 238.484814 -116.215696) (xy 238.49257 -116.269647)
			(xy 238.49257 -116.324153) (xy 238.484814 -116.378104) (xy 238.469459 -116.430402) (xy 238.446817 -116.479983)
			(xy 238.417351 -116.525838) (xy 238.381659 -116.567032) (xy 238.340468 -116.602728) (xy 238.294617 -116.632199)
			(xy 238.245038 -116.654845) (xy 238.192741 -116.670206) (xy 238.138791 -116.677968) (xy 238.111538 -116.678456)
			(xy 237.247938 -116.678456) (xy 237.220687 -116.677899) (xy 237.166739 -116.670148) (xy 237.114443 -116.654797)
			(xy 237.064864 -116.632159) (xy 237.019012 -116.602696) (xy 236.97782 -116.567007) (xy 236.942127 -116.525819)
			(xy 236.912659 -116.479969) (xy 236.890016 -116.430393) (xy 236.87466 -116.378099) (xy 236.866903 -116.324151)
			(xy 232.277026 -116.324151) (xy 232.279166 -116.339033) (xy 232.279166 -116.393567) (xy 232.271405 -116.447546)
			(xy 232.256042 -116.499871) (xy 232.233389 -116.549478) (xy 232.203907 -116.595356) (xy 232.168197 -116.636571)
			(xy 232.126985 -116.672286) (xy 232.081109 -116.701772) (xy 232.031505 -116.724429) (xy 231.979181 -116.739798)
			(xy 231.925203 -116.747563) (xy 231.897936 -116.748052) (xy 231.034336 -116.748052) (xy 231.007063 -116.747611)
			(xy 230.95307 -116.739853) (xy 230.900732 -116.724489) (xy 230.851113 -116.701833) (xy 230.805224 -116.672346)
			(xy 230.763998 -116.636627) (xy 230.728276 -116.595405) (xy 230.698784 -116.549519) (xy 230.676123 -116.499902)
			(xy 230.660755 -116.447565) (xy 230.652992 -116.393573) (xy 2.509012 -116.393573) (xy 2.509012 -117.632251)
			(xy 233.564903 -117.632251) (xy 233.564903 -117.577749) (xy 233.57266 -117.523801) (xy 233.588016 -117.471507)
			(xy 233.610659 -117.421931) (xy 233.640127 -117.376081) (xy 233.67582 -117.334893) (xy 233.717012 -117.299204)
			(xy 233.762864 -117.269741) (xy 233.812443 -117.247103) (xy 233.864739 -117.231752) (xy 233.918687 -117.224001)
			(xy 233.945938 -117.22354) (xy 234.809538 -117.22354) (xy 234.836791 -117.223932) (xy 234.890741 -117.231694)
			(xy 234.943038 -117.247055) (xy 234.992617 -117.269701) (xy 235.038468 -117.299172) (xy 235.079659 -117.334868)
			(xy 235.115351 -117.376062) (xy 235.144817 -117.421917) (xy 235.167459 -117.471498) (xy 235.182814 -117.523796)
			(xy 235.19057 -117.577747) (xy 235.19057 -117.632251) (xy 238.898903 -117.632251) (xy 238.898903 -117.577749)
			(xy 238.90666 -117.523801) (xy 238.922016 -117.471507) (xy 238.944659 -117.421931) (xy 238.974127 -117.376081)
			(xy 239.00982 -117.334893) (xy 239.051012 -117.299204) (xy 239.096864 -117.269741) (xy 239.146443 -117.247103)
			(xy 239.198739 -117.231752) (xy 239.252687 -117.224001) (xy 239.279938 -117.22354) (xy 240.143538 -117.22354)
			(xy 240.170791 -117.223932) (xy 240.224741 -117.231694) (xy 240.277038 -117.247055) (xy 240.326617 -117.269701)
			(xy 240.372468 -117.299172) (xy 240.413659 -117.334868) (xy 240.449351 -117.376062) (xy 240.478817 -117.421917)
			(xy 240.501459 -117.471498) (xy 240.516814 -117.523796) (xy 240.52457 -117.577747) (xy 240.52457 -117.632253)
			(xy 240.516814 -117.686204) (xy 240.501459 -117.738502) (xy 240.478817 -117.788083) (xy 240.449351 -117.833938)
			(xy 240.413659 -117.875132) (xy 240.372468 -117.910828) (xy 240.326617 -117.940299) (xy 240.277038 -117.962945)
			(xy 240.224741 -117.978306) (xy 240.170791 -117.986068) (xy 240.143538 -117.986556) (xy 239.279938 -117.986556)
			(xy 239.252687 -117.985999) (xy 239.198739 -117.978248) (xy 239.146443 -117.962897) (xy 239.096864 -117.940259)
			(xy 239.051012 -117.910796) (xy 239.00982 -117.875107) (xy 238.974127 -117.833919) (xy 238.944659 -117.788069)
			(xy 238.922016 -117.738493) (xy 238.90666 -117.686199) (xy 238.898903 -117.632251) (xy 235.19057 -117.632251)
			(xy 235.19057 -117.632253) (xy 235.182814 -117.686204) (xy 235.167459 -117.738502) (xy 235.144817 -117.788083)
			(xy 235.115351 -117.833938) (xy 235.079659 -117.875132) (xy 235.038468 -117.910828) (xy 234.992617 -117.940299)
			(xy 234.943038 -117.962945) (xy 234.890741 -117.978306) (xy 234.836791 -117.986068) (xy 234.809538 -117.986556)
			(xy 233.945938 -117.986556) (xy 233.918687 -117.985999) (xy 233.864739 -117.978248) (xy 233.812443 -117.962897)
			(xy 233.762864 -117.940259) (xy 233.717012 -117.910796) (xy 233.67582 -117.875107) (xy 233.640127 -117.833919)
			(xy 233.610659 -117.788069) (xy 233.588016 -117.738493) (xy 233.57266 -117.686199) (xy 233.564903 -117.632251)
			(xy 2.509012 -117.632251) (xy 2.509012 -123.093988) (xy 227.217732 -123.093988) (xy 227.217732 -122.230388)
			(xy 227.218218 -122.203137) (xy 227.225974 -122.149189) (xy 227.241329 -122.096894) (xy 227.263971 -122.047317)
			(xy 227.293437 -122.001467) (xy 227.329128 -121.960276) (xy 227.370319 -121.924585) (xy 227.416169 -121.895119)
			(xy 227.465746 -121.872477) (xy 227.518041 -121.857122) (xy 227.571989 -121.849366) (xy 227.626491 -121.849366)
			(xy 227.680439 -121.857122) (xy 227.732734 -121.872477) (xy 227.782311 -121.895119) (xy 227.828161 -121.924585)
			(xy 227.869352 -121.960276) (xy 227.905043 -122.001467) (xy 227.934509 -122.047317) (xy 227.957151 -122.096894)
			(xy 227.972506 -122.149189) (xy 227.980262 -122.203137) (xy 227.980748 -122.230388) (xy 227.980748 -122.921014)
			(xy 245.563136 -122.921014) (xy 245.563136 -122.057414) (xy 245.563622 -122.030163) (xy 245.571378 -121.976215)
			(xy 245.586733 -121.92392) (xy 245.609375 -121.874343) (xy 245.638841 -121.828493) (xy 245.674532 -121.787302)
			(xy 245.715723 -121.751611) (xy 245.761573 -121.722145) (xy 245.81115 -121.699503) (xy 245.863445 -121.684148)
			(xy 245.917393 -121.676392) (xy 245.971895 -121.676392) (xy 246.025843 -121.684148) (xy 246.078138 -121.699503)
			(xy 246.127715 -121.722145) (xy 246.173565 -121.751611) (xy 246.214756 -121.787302) (xy 246.250447 -121.828493)
			(xy 246.279913 -121.874343) (xy 246.302555 -121.92392) (xy 246.31791 -121.976215) (xy 246.325666 -122.030163)
			(xy 246.326152 -122.057414) (xy 246.326152 -122.921014) (xy 246.325666 -122.948265) (xy 246.31791 -123.002213)
			(xy 246.302555 -123.054508) (xy 246.279913 -123.104085) (xy 246.250447 -123.149935) (xy 246.214756 -123.191126)
			(xy 246.173565 -123.226817) (xy 246.127715 -123.256283) (xy 246.078138 -123.278925) (xy 246.025843 -123.29428)
			(xy 245.971895 -123.302036) (xy 245.917393 -123.302036) (xy 245.863445 -123.29428) (xy 245.81115 -123.278925)
			(xy 245.761573 -123.256283) (xy 245.715723 -123.226817) (xy 245.674532 -123.191126) (xy 245.638841 -123.149935)
			(xy 245.609375 -123.104085) (xy 245.586733 -123.054508) (xy 245.571378 -123.002213) (xy 245.563622 -122.948265)
			(xy 245.563136 -122.921014) (xy 227.980748 -122.921014) (xy 227.980748 -123.093988) (xy 227.980262 -123.121239)
			(xy 227.972506 -123.175187) (xy 227.957151 -123.227482) (xy 227.934509 -123.277059) (xy 227.905043 -123.322909)
			(xy 227.869352 -123.3641) (xy 227.828161 -123.399791) (xy 227.782311 -123.429257) (xy 227.732734 -123.451899)
			(xy 227.680439 -123.467254) (xy 227.626491 -123.47501) (xy 227.571989 -123.47501) (xy 227.518041 -123.467254)
			(xy 227.465746 -123.451899) (xy 227.416169 -123.429257) (xy 227.370319 -123.399791) (xy 227.329128 -123.3641)
			(xy 227.293437 -123.322909) (xy 227.263971 -123.277059) (xy 227.241329 -123.227482) (xy 227.225974 -123.175187)
			(xy 227.218218 -123.121239) (xy 227.217732 -123.093988) (xy 2.509012 -123.093988) (xy 2.509012 -125.221746)
			(xy 225.535744 -125.221746) (xy 225.535744 -124.358146) (xy 225.53623 -124.330877) (xy 225.543992 -124.276893)
			(xy 225.559357 -124.224563) (xy 225.582014 -124.174953) (xy 225.6115 -124.129072) (xy 225.647215 -124.087855)
			(xy 225.688432 -124.05214) (xy 225.734313 -124.022654) (xy 225.783923 -123.999997) (xy 225.836253 -123.984632)
			(xy 225.890237 -123.97687) (xy 225.944775 -123.97687) (xy 225.998759 -123.984632) (xy 226.051089 -123.999997)
			(xy 226.100699 -124.022654) (xy 226.14658 -124.05214) (xy 226.187797 -124.087855) (xy 226.223512 -124.129072)
			(xy 226.252998 -124.174953) (xy 226.275655 -124.224563) (xy 226.29102 -124.276893) (xy 226.298782 -124.330877)
			(xy 226.299268 -124.358146) (xy 226.299268 -125.221746) (xy 226.298782 -125.249015) (xy 226.29102 -125.302999)
			(xy 226.275655 -125.355329) (xy 226.252998 -125.404939) (xy 226.223512 -125.45082) (xy 226.187797 -125.492037)
			(xy 226.14658 -125.527752) (xy 226.100699 -125.557238) (xy 226.051089 -125.579895) (xy 225.998759 -125.59526)
			(xy 225.944775 -125.603022) (xy 225.890237 -125.603022) (xy 225.836253 -125.59526) (xy 225.783923 -125.579895)
			(xy 225.734313 -125.557238) (xy 225.688432 -125.527752) (xy 225.647215 -125.492037) (xy 225.6115 -125.45082)
			(xy 225.582014 -125.404939) (xy 225.559357 -125.355329) (xy 225.543992 -125.302999) (xy 225.53623 -125.249015)
			(xy 225.535744 -125.221746) (xy 2.509012 -125.221746) (xy 2.509012 -127.325628) (xy 227.034852 -127.325628)
			(xy 227.034852 -126.462028) (xy 227.035338 -126.434777) (xy 227.043094 -126.380829) (xy 227.058449 -126.328534)
			(xy 227.081091 -126.278957) (xy 227.110557 -126.233107) (xy 227.146248 -126.191916) (xy 227.187439 -126.156225)
			(xy 227.233289 -126.126759) (xy 227.282866 -126.104117) (xy 227.335161 -126.088762) (xy 227.389109 -126.081006)
			(xy 227.443611 -126.081006) (xy 227.497559 -126.088762) (xy 227.549854 -126.104117) (xy 227.599431 -126.126759)
			(xy 227.645281 -126.156225) (xy 227.686472 -126.191916) (xy 227.722163 -126.233107) (xy 227.751629 -126.278957)
			(xy 227.774271 -126.328534) (xy 227.789626 -126.380829) (xy 227.797382 -126.434777) (xy 227.797868 -126.462028)
			(xy 227.797868 -127.140208) (xy 242.041172 -127.140208) (xy 242.041172 -126.276608) (xy 242.041658 -126.249357)
			(xy 242.049414 -126.195409) (xy 242.064769 -126.143114) (xy 242.087411 -126.093537) (xy 242.116877 -126.047687)
			(xy 242.152568 -126.006496) (xy 242.193759 -125.970805) (xy 242.239609 -125.941339) (xy 242.289186 -125.918697)
			(xy 242.341481 -125.903342) (xy 242.395429 -125.895586) (xy 242.449931 -125.895586) (xy 242.503879 -125.903342)
			(xy 242.556174 -125.918697) (xy 242.605751 -125.941339) (xy 242.651601 -125.970805) (xy 242.692792 -126.006496)
			(xy 242.728483 -126.047687) (xy 242.757949 -126.093537) (xy 242.780591 -126.143114) (xy 242.795946 -126.195409)
			(xy 242.803702 -126.249357) (xy 242.804188 -126.276608) (xy 242.804188 -127.140208) (xy 242.803702 -127.167459)
			(xy 242.795946 -127.221407) (xy 242.780591 -127.273702) (xy 242.757949 -127.323279) (xy 242.728483 -127.369129)
			(xy 242.692792 -127.41032) (xy 242.651601 -127.446011) (xy 242.605751 -127.475477) (xy 242.556174 -127.498119)
			(xy 242.503879 -127.513474) (xy 242.449931 -127.52123) (xy 242.395429 -127.52123) (xy 242.341481 -127.513474)
			(xy 242.289186 -127.498119) (xy 242.239609 -127.475477) (xy 242.193759 -127.446011) (xy 242.152568 -127.41032)
			(xy 242.116877 -127.369129) (xy 242.087411 -127.323279) (xy 242.064769 -127.273702) (xy 242.049414 -127.221407)
			(xy 242.041658 -127.167459) (xy 242.041172 -127.140208) (xy 227.797868 -127.140208) (xy 227.797868 -127.325628)
			(xy 227.797382 -127.352879) (xy 227.789626 -127.406827) (xy 227.774271 -127.459122) (xy 227.751629 -127.508699)
			(xy 227.722163 -127.554549) (xy 227.686472 -127.59574) (xy 227.645281 -127.631431) (xy 227.599431 -127.660897)
			(xy 227.549854 -127.683539) (xy 227.519478 -127.692458) (xy 458.401155 -127.692458) (xy 458.401155 -127.563318)
			(xy 458.409105 -127.434423) (xy 458.424975 -127.306263) (xy 458.448704 -127.179322) (xy 458.480203 -127.054083)
			(xy 458.519352 -126.93102) (xy 458.566003 -126.810601) (xy 458.619978 -126.693282) (xy 458.681073 -126.579508)
			(xy 458.749056 -126.469711) (xy 458.82367 -126.364308) (xy 458.904631 -126.263698) (xy 458.991631 -126.168263)
			(xy 459.084342 -126.078364) (xy 459.182412 -125.994343) (xy 459.285467 -125.916519) (xy 459.393118 -125.845187)
			(xy 459.504957 -125.780617) (xy 459.620558 -125.723055) (xy 459.739483 -125.672718) (xy 459.861282 -125.629798)
			(xy 459.985492 -125.594457) (xy 460.111641 -125.56683) (xy 460.239253 -125.547021) (xy 460.367842 -125.535105)
			(xy 460.49692 -125.531129) (xy 460.625998 -125.535105) (xy 460.754587 -125.547021) (xy 460.882199 -125.56683)
			(xy 461.008348 -125.594457) (xy 461.132558 -125.629798) (xy 461.254357 -125.672718) (xy 461.373282 -125.723055)
			(xy 461.488883 -125.780617) (xy 461.600722 -125.845187) (xy 461.708373 -125.916519) (xy 461.811428 -125.994343)
			(xy 461.909498 -126.078364) (xy 462.002209 -126.168263) (xy 462.089209 -126.263698) (xy 462.17017 -126.364308)
			(xy 462.244784 -126.469711) (xy 462.312767 -126.579508) (xy 462.373862 -126.693282) (xy 462.427837 -126.810601)
			(xy 462.474488 -126.93102) (xy 462.513637 -127.054083) (xy 462.545136 -127.179322) (xy 462.568865 -127.306263)
			(xy 462.584735 -127.434423) (xy 462.592685 -127.563318) (xy 462.593182 -127.627888) (xy 462.592685 -127.692458)
			(xy 462.584735 -127.821353) (xy 462.568865 -127.949513) (xy 462.545136 -128.076454) (xy 462.513637 -128.201693)
			(xy 462.474488 -128.324756) (xy 462.427837 -128.445175) (xy 462.373862 -128.562494) (xy 462.312767 -128.676268)
			(xy 462.244784 -128.786065) (xy 462.17017 -128.891468) (xy 462.089209 -128.992078) (xy 462.002209 -129.087513)
			(xy 461.909498 -129.177412) (xy 461.811428 -129.261433) (xy 461.708373 -129.339257) (xy 461.600722 -129.410589)
			(xy 461.488883 -129.475159) (xy 461.373282 -129.532721) (xy 461.254357 -129.583058) (xy 461.132558 -129.625978)
			(xy 461.008348 -129.661319) (xy 460.882199 -129.688946) (xy 460.754587 -129.708755) (xy 460.625998 -129.720671)
			(xy 460.49692 -129.724648) (xy 460.367842 -129.720671) (xy 460.239253 -129.708755) (xy 460.111641 -129.688946)
			(xy 459.985492 -129.661319) (xy 459.861282 -129.625978) (xy 459.739483 -129.583058) (xy 459.620558 -129.532721)
			(xy 459.504957 -129.475159) (xy 459.393118 -129.410589) (xy 459.285467 -129.339257) (xy 459.182412 -129.261433)
			(xy 459.084342 -129.177412) (xy 458.991631 -129.087513) (xy 458.904631 -128.992078) (xy 458.82367 -128.891468)
			(xy 458.749056 -128.786065) (xy 458.681073 -128.676268) (xy 458.619978 -128.562494) (xy 458.566003 -128.445175)
			(xy 458.519352 -128.324756) (xy 458.480203 -128.201693) (xy 458.448704 -128.076454) (xy 458.424975 -127.949513)
			(xy 458.409105 -127.821353) (xy 458.401155 -127.692458) (xy 227.519478 -127.692458) (xy 227.497559 -127.698894)
			(xy 227.443611 -127.70665) (xy 227.389109 -127.70665) (xy 227.335161 -127.698894) (xy 227.282866 -127.683539)
			(xy 227.233289 -127.660897) (xy 227.187439 -127.631431) (xy 227.146248 -127.59574) (xy 227.110557 -127.554549)
			(xy 227.081091 -127.508699) (xy 227.058449 -127.459122) (xy 227.043094 -127.406827) (xy 227.035338 -127.352879)
			(xy 227.034852 -127.325628) (xy 2.509012 -127.325628) (xy 2.509012 -129.073148) (xy 223.562672 -129.073148)
			(xy 223.562672 -128.209548) (xy 223.563115 -128.182788) (xy 223.570596 -128.129795) (xy 223.585403 -128.078365)
			(xy 223.607247 -128.029506) (xy 223.621092 -128.006602) (xy 223.636032 -127.983032) (xy 223.671662 -127.940084)
			(xy 223.713174 -127.902792) (xy 223.759681 -127.871951) (xy 223.810187 -127.848221) (xy 223.863614 -127.832109)
			(xy 223.918819 -127.823961) (xy 223.94672 -127.823468) (xy 223.973934 -127.823967) (xy 224.027808 -127.831715)
			(xy 224.080031 -127.84705) (xy 224.12954 -127.869661) (xy 224.175327 -127.899088) (xy 224.216462 -127.93473)
			(xy 224.252105 -127.975863) (xy 224.281533 -128.02165) (xy 224.304145 -128.071158) (xy 224.319483 -128.123381)
			(xy 224.327232 -128.177254) (xy 224.32772 -128.204468) (xy 224.32772 -128.204722) (xy 224.325942 -128.241552)
			(xy 224.325688 -128.243838) (xy 224.325688 -129.019808) (xy 240.086896 -129.019808) (xy 240.086896 -128.156208)
			(xy 240.087382 -128.128939) (xy 240.095144 -128.074955) (xy 240.110509 -128.022625) (xy 240.133166 -127.973015)
			(xy 240.162652 -127.927134) (xy 240.198367 -127.885917) (xy 240.239584 -127.850202) (xy 240.285465 -127.820716)
			(xy 240.335075 -127.798059) (xy 240.387405 -127.782694) (xy 240.441389 -127.774932) (xy 240.495927 -127.774932)
			(xy 240.549911 -127.782694) (xy 240.602241 -127.798059) (xy 240.651851 -127.820716) (xy 240.697732 -127.850202)
			(xy 240.738949 -127.885917) (xy 240.774664 -127.927134) (xy 240.80415 -127.973015) (xy 240.826807 -128.022625)
			(xy 240.842172 -128.074955) (xy 240.849934 -128.128939) (xy 240.85042 -128.156208) (xy 240.85042 -129.019808)
			(xy 240.849934 -129.047077) (xy 240.842172 -129.101061) (xy 240.826807 -129.153391) (xy 240.80415 -129.203001)
			(xy 240.774664 -129.248882) (xy 240.738949 -129.290099) (xy 240.697732 -129.325814) (xy 240.651851 -129.3553)
			(xy 240.602241 -129.377957) (xy 240.549911 -129.393322) (xy 240.495927 -129.401084) (xy 240.441389 -129.401084)
			(xy 240.387405 -129.393322) (xy 240.335075 -129.377957) (xy 240.285465 -129.3553) (xy 240.239584 -129.325814)
			(xy 240.198367 -129.290099) (xy 240.162652 -129.248882) (xy 240.133166 -129.203001) (xy 240.110509 -129.153391)
			(xy 240.095144 -129.101061) (xy 240.087382 -129.047077) (xy 240.086896 -129.019808) (xy 224.325688 -129.019808)
			(xy 224.325942 -129.022602) (xy 224.327226 -129.033861) (xy 224.328622 -129.056482) (xy 224.328736 -129.067814)
			(xy 224.328736 -129.068068) (xy 224.328226 -129.095352) (xy 224.320425 -129.14936) (xy 224.305035 -129.201713)
			(xy 224.282367 -129.251351) (xy 224.26803 -129.27457) (xy 224.253042 -129.297814) (xy 224.217376 -129.340083)
			(xy 224.175977 -129.376756) (xy 224.129714 -129.407061) (xy 224.079557 -129.430365) (xy 224.026559 -129.446176)
			(xy 223.971833 -129.454165) (xy 223.94418 -129.454656) (xy 223.91693 -129.454141) (xy 223.862986 -129.446383)
			(xy 223.810695 -129.431028) (xy 223.761121 -129.408388) (xy 223.715273 -129.378924) (xy 223.674084 -129.343236)
			(xy 223.638393 -129.30205) (xy 223.608926 -129.256204) (xy 223.586282 -129.206631) (xy 223.570923 -129.154341)
			(xy 223.563161 -129.100398) (xy 223.562672 -129.073148) (xy 2.509012 -129.073148) (xy 2.509012 -131.09702)
			(xy 228.682804 -131.09702) (xy 228.682804 -130.23342) (xy 228.68329 -130.206151) (xy 228.691052 -130.152167)
			(xy 228.706417 -130.099837) (xy 228.729074 -130.050227) (xy 228.75856 -130.004346) (xy 228.794275 -129.963129)
			(xy 228.835492 -129.927414) (xy 228.881373 -129.897928) (xy 228.930983 -129.875271) (xy 228.983313 -129.859906)
			(xy 229.037297 -129.852144) (xy 229.091835 -129.852144) (xy 229.145819 -129.859906) (xy 229.198149 -129.875271)
			(xy 229.247759 -129.897928) (xy 229.29364 -129.927414) (xy 229.334857 -129.963129) (xy 229.370572 -130.004346)
			(xy 229.400058 -130.050227) (xy 229.422715 -130.099837) (xy 229.43808 -130.152167) (xy 229.445842 -130.206151)
			(xy 229.446328 -130.23342) (xy 229.446328 -130.721608) (xy 242.041172 -130.721608) (xy 242.041172 -129.858008)
			(xy 242.041658 -129.830757) (xy 242.049414 -129.776809) (xy 242.064769 -129.724514) (xy 242.087411 -129.674937)
			(xy 242.116877 -129.629087) (xy 242.152568 -129.587896) (xy 242.193759 -129.552205) (xy 242.239609 -129.522739)
			(xy 242.289186 -129.500097) (xy 242.341481 -129.484742) (xy 242.395429 -129.476986) (xy 242.449931 -129.476986)
			(xy 242.503879 -129.484742) (xy 242.556174 -129.500097) (xy 242.605751 -129.522739) (xy 242.651601 -129.552205)
			(xy 242.692792 -129.587896) (xy 242.728483 -129.629087) (xy 242.757949 -129.674937) (xy 242.780591 -129.724514)
			(xy 242.795946 -129.776809) (xy 242.803702 -129.830757) (xy 242.804188 -129.858008) (xy 242.804188 -130.721608)
			(xy 242.803702 -130.748859) (xy 242.795946 -130.802807) (xy 242.780591 -130.855102) (xy 242.757949 -130.904679)
			(xy 242.728483 -130.950529) (xy 242.692792 -130.99172) (xy 242.651601 -131.027411) (xy 242.605751 -131.056877)
			(xy 242.556174 -131.079519) (xy 242.503879 -131.094874) (xy 242.449931 -131.10263) (xy 242.395429 -131.10263)
			(xy 242.341481 -131.094874) (xy 242.289186 -131.079519) (xy 242.239609 -131.056877) (xy 242.193759 -131.027411)
			(xy 242.152568 -130.99172) (xy 242.116877 -130.950529) (xy 242.087411 -130.904679) (xy 242.064769 -130.855102)
			(xy 242.049414 -130.802807) (xy 242.041658 -130.748859) (xy 242.041172 -130.721608) (xy 229.446328 -130.721608)
			(xy 229.446328 -131.09702) (xy 229.445842 -131.124289) (xy 229.43808 -131.178273) (xy 229.422715 -131.230603)
			(xy 229.400058 -131.280213) (xy 229.370572 -131.326094) (xy 229.334857 -131.367311) (xy 229.29364 -131.403026)
			(xy 229.247759 -131.432512) (xy 229.198149 -131.455169) (xy 229.145819 -131.470534) (xy 229.091835 -131.478296)
			(xy 229.037297 -131.478296) (xy 228.983313 -131.470534) (xy 228.930983 -131.455169) (xy 228.881373 -131.432512)
			(xy 228.835492 -131.403026) (xy 228.794275 -131.367311) (xy 228.75856 -131.326094) (xy 228.729074 -131.280213)
			(xy 228.706417 -131.230603) (xy 228.691052 -131.178273) (xy 228.68329 -131.124289) (xy 228.682804 -131.09702)
			(xy 2.509012 -131.09702) (xy 2.509012 -132.529347) (xy 231.621126 -132.529347) (xy 231.621126 -132.474853)
			(xy 231.628881 -132.420915) (xy 231.644233 -132.368628) (xy 231.666869 -132.319059) (xy 231.69633 -132.273216)
			(xy 231.732014 -132.232031) (xy 231.773196 -132.196344) (xy 231.819038 -132.166881) (xy 231.868606 -132.144241)
			(xy 231.920891 -132.128886) (xy 231.974829 -132.121128) (xy 232.002076 -132.12064) (xy 232.865676 -132.12064)
			(xy 232.892933 -132.121005) (xy 232.946894 -132.128761) (xy 232.999201 -132.144116) (xy 233.048791 -132.16676)
			(xy 233.094653 -132.196231) (xy 233.135853 -132.23193) (xy 233.171554 -132.273128) (xy 233.201028 -132.318988)
			(xy 233.223675 -132.368576) (xy 233.239034 -132.420883) (xy 233.246793 -132.474843) (xy 233.246793 -132.529357)
			(xy 233.239034 -132.583317) (xy 233.223675 -132.635624) (xy 233.201028 -132.685212) (xy 233.171554 -132.731072)
			(xy 233.135853 -132.77227) (xy 233.094653 -132.807968) (xy 233.048791 -132.83744) (xy 232.999201 -132.860084)
			(xy 232.946894 -132.875439) (xy 232.892933 -132.883195) (xy 232.865676 -132.883656) (xy 232.002076 -132.883656)
			(xy 231.974829 -132.883072) (xy 231.920891 -132.875314) (xy 231.868606 -132.859959) (xy 231.819038 -132.837319)
			(xy 231.773196 -132.807856) (xy 231.732014 -132.772169) (xy 231.69633 -132.730984) (xy 231.666869 -132.685141)
			(xy 231.644233 -132.635572) (xy 231.628881 -132.583285) (xy 231.621126 -132.529347) (xy 2.509012 -132.529347)
			(xy 2.509012 -135.31065) (xy 225.204003 -135.31065) (xy 225.204003 -135.25615) (xy 225.21176 -135.202204)
			(xy 225.227115 -135.149911) (xy 225.249756 -135.100336) (xy 225.279222 -135.054487) (xy 225.314914 -135.013299)
			(xy 225.356103 -134.97761) (xy 225.401953 -134.948146) (xy 225.45153 -134.925508) (xy 225.503823 -134.910156)
			(xy 225.55777 -134.902402) (xy 225.58502 -134.90194) (xy 226.44862 -134.90194) (xy 226.475874 -134.902331)
			(xy 226.529826 -134.910091) (xy 226.582125 -134.92545) (xy 226.631706 -134.948095) (xy 226.67756 -134.977566)
			(xy 226.718753 -135.013262) (xy 226.754446 -135.054456) (xy 226.755856 -135.05665) (xy 228.531403 -135.05665)
			(xy 228.531403 -135.00215) (xy 228.53916 -134.948204) (xy 228.554515 -134.895911) (xy 228.577156 -134.846336)
			(xy 228.606622 -134.800487) (xy 228.642314 -134.759299) (xy 228.683503 -134.72361) (xy 228.729353 -134.694146)
			(xy 228.77893 -134.671508) (xy 228.831223 -134.656156) (xy 228.88517 -134.648402) (xy 228.91242 -134.64794)
			(xy 229.77602 -134.64794) (xy 229.803274 -134.648331) (xy 229.857226 -134.656091) (xy 229.909525 -134.67145)
			(xy 229.959106 -134.694095) (xy 230.00496 -134.723566) (xy 230.046153 -134.759262) (xy 230.081846 -134.800456)
			(xy 230.111315 -134.846312) (xy 230.133957 -134.895894) (xy 230.149313 -134.948193) (xy 230.15707 -135.002146)
			(xy 230.15707 -135.056654) (xy 230.149313 -135.110607) (xy 230.145996 -135.121904) (xy 234.029504 -135.121904)
			(xy 234.029504 -134.258304) (xy 234.02999 -134.231035) (xy 234.037752 -134.177051) (xy 234.053117 -134.124721)
			(xy 234.075774 -134.075111) (xy 234.10526 -134.02923) (xy 234.140975 -133.988013) (xy 234.182192 -133.952298)
			(xy 234.228073 -133.922812) (xy 234.277683 -133.900155) (xy 234.330013 -133.88479) (xy 234.383997 -133.877028)
			(xy 234.438535 -133.877028) (xy 234.492519 -133.88479) (xy 234.544849 -133.900155) (xy 234.594459 -133.922812)
			(xy 234.64034 -133.952298) (xy 234.681557 -133.988013) (xy 234.717272 -134.02923) (xy 234.746758 -134.075111)
			(xy 234.769415 -134.124721) (xy 234.78478 -134.177051) (xy 234.792542 -134.231035) (xy 234.793028 -134.258304)
			(xy 234.793028 -134.768971) (xy 236.02439 -134.768971) (xy 236.02439 -134.714429) (xy 236.032152 -134.660443)
			(xy 236.047518 -134.608111) (xy 236.070174 -134.558498) (xy 236.09966 -134.512615) (xy 236.135376 -134.471394)
			(xy 236.176594 -134.435676) (xy 236.222475 -134.406186) (xy 236.272087 -134.383527) (xy 236.324418 -134.368158)
			(xy 236.378403 -134.360392) (xy 236.405674 -134.359904) (xy 237.178342 -134.359904) (xy 237.205607 -134.360461)
			(xy 237.259581 -134.368227) (xy 237.311901 -134.383595) (xy 237.361502 -134.406251) (xy 237.407373 -134.435736)
			(xy 237.448582 -134.471448) (xy 237.48429 -134.512661) (xy 237.513769 -134.558535) (xy 237.53642 -134.608138)
			(xy 237.551782 -134.66046) (xy 237.559542 -134.714435) (xy 237.559542 -134.768965) (xy 237.551782 -134.82294)
			(xy 237.53642 -134.875262) (xy 237.513769 -134.924865) (xy 237.48429 -134.970739) (xy 237.448582 -135.011952)
			(xy 237.407373 -135.047664) (xy 237.361502 -135.077149) (xy 237.311901 -135.099805) (xy 237.259581 -135.115173)
			(xy 237.205607 -135.122939) (xy 237.178342 -135.123428) (xy 236.405674 -135.123428) (xy 236.378403 -135.123008)
			(xy 236.324418 -135.115242) (xy 236.272087 -135.099873) (xy 236.222475 -135.077214) (xy 236.176594 -135.047724)
			(xy 236.135376 -135.012006) (xy 236.09966 -134.970785) (xy 236.070174 -134.924902) (xy 236.047518 -134.875289)
			(xy 236.032152 -134.822957) (xy 236.02439 -134.768971) (xy 234.793028 -134.768971) (xy 234.793028 -135.121904)
			(xy 234.792542 -135.149173) (xy 234.786383 -135.192008) (xy 238.645192 -135.192008) (xy 238.645192 -134.328408)
			(xy 238.645678 -134.301157) (xy 238.653434 -134.247209) (xy 238.668789 -134.194914) (xy 238.691431 -134.145337)
			(xy 238.720897 -134.099487) (xy 238.756588 -134.058296) (xy 238.797779 -134.022605) (xy 238.843629 -133.993139)
			(xy 238.893206 -133.970497) (xy 238.945501 -133.955142) (xy 238.999449 -133.947386) (xy 239.053951 -133.947386)
			(xy 239.107899 -133.955142) (xy 239.160194 -133.970497) (xy 239.209771 -133.993139) (xy 239.255621 -134.022605)
			(xy 239.271831 -134.036651) (xy 242.034062 -134.036651) (xy 242.034062 -133.982149) (xy 242.041817 -133.928203)
			(xy 242.057171 -133.875909) (xy 242.07981 -133.826333) (xy 242.109274 -133.780482) (xy 242.144963 -133.739291)
			(xy 242.18615 -133.703598) (xy 242.231997 -133.67413) (xy 242.281572 -133.651485) (xy 242.333864 -133.636126)
			(xy 242.387809 -133.628365) (xy 242.41506 -133.627876) (xy 243.27866 -133.627876) (xy 243.305914 -133.628369)
			(xy 243.359867 -133.636121) (xy 243.412167 -133.651473) (xy 243.46175 -133.674112) (xy 243.507606 -133.703577)
			(xy 243.548802 -133.73927) (xy 243.584499 -133.780462) (xy 243.613969 -133.826315) (xy 243.636613 -133.875895)
			(xy 243.651971 -133.928194) (xy 243.659729 -133.982146) (xy 243.659729 -134.036654) (xy 243.651971 -134.090606)
			(xy 243.636613 -134.142905) (xy 243.613969 -134.192485) (xy 243.584499 -134.238338) (xy 243.548802 -134.27953)
			(xy 243.507606 -134.315223) (xy 243.46175 -134.344688) (xy 243.412167 -134.367327) (xy 243.359867 -134.382679)
			(xy 243.305914 -134.390431) (xy 243.27866 -134.390892) (xy 242.41506 -134.390892) (xy 242.387809 -134.390435)
			(xy 242.333864 -134.382674) (xy 242.281572 -134.367315) (xy 242.231997 -134.34467) (xy 242.18615 -134.315202)
			(xy 242.144963 -134.279509) (xy 242.109274 -134.238318) (xy 242.07981 -134.192467) (xy 242.057171 -134.142891)
			(xy 242.041817 -134.090597) (xy 242.034062 -134.036651) (xy 239.271831 -134.036651) (xy 239.296812 -134.058296)
			(xy 239.332503 -134.099487) (xy 239.361969 -134.145337) (xy 239.384611 -134.194914) (xy 239.399966 -134.247209)
			(xy 239.407722 -134.301157) (xy 239.408208 -134.328408) (xy 239.408208 -135.192008) (xy 239.407722 -135.219259)
			(xy 239.399966 -135.273207) (xy 239.384611 -135.325502) (xy 239.361969 -135.375079) (xy 239.332503 -135.420929)
			(xy 239.296812 -135.46212) (xy 239.255621 -135.497811) (xy 239.250425 -135.50115) (xy 244.457203 -135.50115)
			(xy 244.457203 -135.44665) (xy 244.46496 -135.392704) (xy 244.480315 -135.340411) (xy 244.502956 -135.290836)
			(xy 244.532422 -135.244987) (xy 244.568114 -135.203799) (xy 244.609303 -135.16811) (xy 244.655153 -135.138646)
			(xy 244.70473 -135.116008) (xy 244.757023 -135.100656) (xy 244.81097 -135.092902) (xy 244.83822 -135.09244)
			(xy 245.70182 -135.09244) (xy 245.729074 -135.092831) (xy 245.783026 -135.100591) (xy 245.835325 -135.11595)
			(xy 245.884906 -135.138595) (xy 245.93076 -135.168066) (xy 245.971953 -135.203762) (xy 246.007646 -135.244956)
			(xy 246.037115 -135.290812) (xy 246.059757 -135.340394) (xy 246.075113 -135.392693) (xy 246.08287 -135.446646)
			(xy 246.08287 -135.501154) (xy 246.075113 -135.555107) (xy 246.059757 -135.607406) (xy 246.037115 -135.656988)
			(xy 246.007646 -135.702844) (xy 245.971953 -135.744038) (xy 245.93076 -135.779734) (xy 245.884906 -135.809205)
			(xy 245.835325 -135.83185) (xy 245.783026 -135.847209) (xy 245.729074 -135.854969) (xy 245.70182 -135.855456)
			(xy 244.83822 -135.855456) (xy 244.81097 -135.854898) (xy 244.757023 -135.847144) (xy 244.70473 -135.831792)
			(xy 244.655153 -135.809154) (xy 244.609303 -135.77969) (xy 244.568114 -135.744001) (xy 244.532422 -135.702813)
			(xy 244.502956 -135.656964) (xy 244.480315 -135.607389) (xy 244.46496 -135.555096) (xy 244.457203 -135.50115)
			(xy 239.250425 -135.50115) (xy 239.209771 -135.527277) (xy 239.160194 -135.549919) (xy 239.107899 -135.565274)
			(xy 239.053951 -135.57303) (xy 238.999449 -135.57303) (xy 238.945501 -135.565274) (xy 238.893206 -135.549919)
			(xy 238.843629 -135.527277) (xy 238.797779 -135.497811) (xy 238.756588 -135.46212) (xy 238.720897 -135.420929)
			(xy 238.691431 -135.375079) (xy 238.668789 -135.325502) (xy 238.653434 -135.273207) (xy 238.645678 -135.219259)
			(xy 238.645192 -135.192008) (xy 234.786383 -135.192008) (xy 234.78478 -135.203157) (xy 234.769415 -135.255487)
			(xy 234.746758 -135.305097) (xy 234.717272 -135.350978) (xy 234.681557 -135.392195) (xy 234.64034 -135.42791)
			(xy 234.594459 -135.457396) (xy 234.544849 -135.480053) (xy 234.492519 -135.495418) (xy 234.438535 -135.50318)
			(xy 234.383997 -135.50318) (xy 234.330013 -135.495418) (xy 234.277683 -135.480053) (xy 234.228073 -135.457396)
			(xy 234.182192 -135.42791) (xy 234.140975 -135.392195) (xy 234.10526 -135.350978) (xy 234.075774 -135.305097)
			(xy 234.053117 -135.255487) (xy 234.037752 -135.203157) (xy 234.02999 -135.149173) (xy 234.029504 -135.121904)
			(xy 230.145996 -135.121904) (xy 230.133957 -135.162906) (xy 230.111315 -135.212488) (xy 230.081846 -135.258344)
			(xy 230.046153 -135.299538) (xy 230.00496 -135.335234) (xy 229.959106 -135.364705) (xy 229.909525 -135.38735)
			(xy 229.857226 -135.402709) (xy 229.803274 -135.410469) (xy 229.77602 -135.410956) (xy 228.91242 -135.410956)
			(xy 228.88517 -135.410398) (xy 228.831223 -135.402644) (xy 228.77893 -135.387292) (xy 228.729353 -135.364654)
			(xy 228.683503 -135.33519) (xy 228.642314 -135.299501) (xy 228.606622 -135.258313) (xy 228.577156 -135.212464)
			(xy 228.554515 -135.162889) (xy 228.53916 -135.110596) (xy 228.531403 -135.05665) (xy 226.755856 -135.05665)
			(xy 226.783915 -135.100312) (xy 226.806557 -135.149894) (xy 226.821913 -135.202193) (xy 226.82967 -135.256146)
			(xy 226.82967 -135.310654) (xy 226.821913 -135.364607) (xy 226.806557 -135.416906) (xy 226.783915 -135.466488)
			(xy 226.754446 -135.512344) (xy 226.718753 -135.553538) (xy 226.67756 -135.589234) (xy 226.631706 -135.618705)
			(xy 226.582125 -135.64135) (xy 226.529826 -135.656709) (xy 226.475874 -135.664469) (xy 226.44862 -135.664956)
			(xy 225.58502 -135.664956) (xy 225.55777 -135.664398) (xy 225.503823 -135.656644) (xy 225.45153 -135.641292)
			(xy 225.401953 -135.618654) (xy 225.356103 -135.58919) (xy 225.314914 -135.553501) (xy 225.279222 -135.512313)
			(xy 225.249756 -135.466464) (xy 225.227115 -135.416889) (xy 225.21176 -135.364596) (xy 225.204003 -135.31065)
			(xy 2.509012 -135.31065) (xy 2.509012 -137.199664) (xy 337.46447 -137.199664) (xy 337.46447 -137.145136)
			(xy 337.47223 -137.091163) (xy 337.487591 -137.038843) (xy 337.510241 -136.989242) (xy 337.539719 -136.943369)
			(xy 337.575425 -136.902158) (xy 337.616632 -136.866447) (xy 337.662502 -136.836963) (xy 337.7121 -136.814307)
			(xy 337.764418 -136.79894) (xy 337.81839 -136.791173) (xy 337.845654 -136.790684) (xy 338.618322 -136.790684)
			(xy 338.645594 -136.79108) (xy 338.699581 -136.798845) (xy 338.751915 -136.814214) (xy 338.801528 -136.836874)
			(xy 338.847412 -136.866364) (xy 338.888632 -136.902084) (xy 338.924349 -136.943306) (xy 338.953836 -136.989191)
			(xy 338.976493 -137.038806) (xy 338.991859 -137.09114) (xy 338.999622 -137.145128) (xy 338.999622 -137.199672)
			(xy 338.991859 -137.25366) (xy 338.976493 -137.305994) (xy 338.953836 -137.355609) (xy 338.924349 -137.401494)
			(xy 338.888632 -137.442716) (xy 338.847412 -137.478436) (xy 338.801528 -137.507926) (xy 338.751915 -137.530586)
			(xy 338.699581 -137.545955) (xy 338.645594 -137.55372) (xy 338.618322 -137.554208) (xy 337.845654 -137.554208)
			(xy 337.81839 -137.553627) (xy 337.764418 -137.54586) (xy 337.7121 -137.530493) (xy 337.662502 -137.507837)
			(xy 337.616632 -137.478353) (xy 337.575425 -137.442642) (xy 337.539719 -137.401431) (xy 337.510241 -137.355558)
			(xy 337.487591 -137.305957) (xy 337.47223 -137.253637) (xy 337.46447 -137.199664) (xy 2.509012 -137.199664)
			(xy 2.509012 -137.622788) (xy 340.085172 -137.622788) (xy 340.085172 -136.759188) (xy 340.085658 -136.731937)
			(xy 340.093414 -136.677989) (xy 340.108769 -136.625694) (xy 340.131411 -136.576117) (xy 340.160877 -136.530267)
			(xy 340.196568 -136.489076) (xy 340.237759 -136.453385) (xy 340.283609 -136.423919) (xy 340.333186 -136.401277)
			(xy 340.385481 -136.385922) (xy 340.439429 -136.378166) (xy 340.493931 -136.378166) (xy 340.547879 -136.385922)
			(xy 340.600174 -136.401277) (xy 340.649751 -136.423919) (xy 340.695601 -136.453385) (xy 340.736792 -136.489076)
			(xy 340.772483 -136.530267) (xy 340.801949 -136.576117) (xy 340.824591 -136.625694) (xy 340.839946 -136.677989)
			(xy 340.847702 -136.731937) (xy 340.848188 -136.759188) (xy 340.848188 -137.622788) (xy 340.847702 -137.650039)
			(xy 340.839946 -137.703987) (xy 340.824591 -137.756282) (xy 340.801949 -137.805859) (xy 340.772483 -137.851709)
			(xy 340.736792 -137.8929) (xy 340.695601 -137.928591) (xy 340.649751 -137.958057) (xy 340.600174 -137.980699)
			(xy 340.547879 -137.996054) (xy 340.493931 -138.00381) (xy 340.439429 -138.00381) (xy 340.385481 -137.996054)
			(xy 340.333186 -137.980699) (xy 340.283609 -137.958057) (xy 340.237759 -137.928591) (xy 340.196568 -137.8929)
			(xy 340.160877 -137.851709) (xy 340.131411 -137.805859) (xy 340.108769 -137.756282) (xy 340.093414 -137.703987)
			(xy 340.085658 -137.650039) (xy 340.085172 -137.622788) (xy 2.509012 -137.622788) (xy 2.509012 -153.766012)
			(xy 24.445731 -153.766012) (xy 24.449724 -153.556271) (xy 24.4617 -153.346834) (xy 24.481641 -153.138005)
			(xy 24.509518 -152.930086) (xy 24.54529 -152.723379) (xy 24.588905 -152.518184) (xy 24.640301 -152.314799)
			(xy 24.699403 -152.113517) (xy 24.766125 -151.914631) (xy 24.84037 -151.71843) (xy 24.92203 -151.525198)
			(xy 25.010988 -151.335214) (xy 25.107115 -151.148755) (xy 25.21027 -150.966091) (xy 25.320305 -150.787486)
			(xy 25.437059 -150.6132) (xy 25.560364 -150.443485) (xy 25.690041 -150.278587) (xy 25.825902 -150.118746)
			(xy 25.967749 -149.964193) (xy 26.115378 -149.815153) (xy 26.268573 -149.67184) (xy 26.427114 -149.534464)
			(xy 26.590769 -149.403223) (xy 26.759303 -149.278308) (xy 26.932469 -149.1599) (xy 27.110019 -149.04817)
			(xy 27.291693 -148.94328) (xy 27.477228 -148.845383) (xy 27.666356 -148.754621) (xy 27.858803 -148.671124)
			(xy 28.054288 -148.595014) (xy 28.25253 -148.526402) (xy 28.45324 -148.465387) (xy 28.656127 -148.412058)
			(xy 28.860897 -148.366491) (xy 29.067254 -148.328752) (xy 29.274898 -148.298898) (xy 29.483528 -148.27697)
			(xy 29.692841 -148.263001) (xy 29.902535 -148.25701) (xy 30.112304 -148.259007) (xy 30.321846 -148.268989)
			(xy 30.530856 -148.286941) (xy 30.73903 -148.312837) (xy 30.946068 -148.346639) (xy 31.151669 -148.388299)
			(xy 31.355535 -148.437757) (xy 31.55737 -148.49494) (xy 31.756882 -148.559765) (xy 31.953781 -148.632139)
			(xy 32.147782 -148.711956) (xy 32.338604 -148.799102) (xy 32.52597 -148.893449) (xy 32.709608 -148.99486)
			(xy 32.889252 -149.10319) (xy 33.064642 -149.21828) (xy 33.235523 -149.339964) (xy 33.401647 -149.468065)
			(xy 33.562774 -149.602398) (xy 33.718671 -149.742767) (xy 33.86911 -149.88897) (xy 34.013874 -150.040794)
			(xy 34.152753 -150.19802) (xy 34.285546 -150.360419) (xy 34.41206 -150.527755) (xy 34.532112 -150.699787)
			(xy 34.645527 -150.876264) (xy 34.752141 -151.056932) (xy 34.8518 -151.241527) (xy 34.944359 -151.429782)
			(xy 35.029684 -151.621425) (xy 35.107651 -151.816177) (xy 35.178147 -152.013757) (xy 35.24107 -152.213876)
			(xy 35.296329 -152.416247) (xy 35.343843 -152.620574) (xy 35.383544 -152.826562) (xy 35.415374 -153.033913)
			(xy 35.439287 -153.242324) (xy 35.455248 -153.451495) (xy 35.463235 -153.661122) (xy 35.463734 -153.766012)
			(xy 35.463235 -153.870902) (xy 35.455248 -154.080529) (xy 35.44312 -154.239468) (xy 186.742832 -154.239468)
			(xy 186.742832 -153.375868) (xy 186.743318 -153.348617) (xy 186.751074 -153.294669) (xy 186.766429 -153.242374)
			(xy 186.789071 -153.192797) (xy 186.818537 -153.146947) (xy 186.854228 -153.105756) (xy 186.895419 -153.070065)
			(xy 186.941269 -153.040599) (xy 186.990846 -153.017957) (xy 187.043141 -153.002602) (xy 187.097089 -152.994846)
			(xy 187.151591 -152.994846) (xy 187.205539 -153.002602) (xy 187.257834 -153.017957) (xy 187.307411 -153.040599)
			(xy 187.353261 -153.070065) (xy 187.394452 -153.105756) (xy 187.430143 -153.146947) (xy 187.459609 -153.192797)
			(xy 187.482251 -153.242374) (xy 187.497606 -153.294669) (xy 187.505362 -153.348617) (xy 187.505848 -153.375868)
			(xy 187.505848 -153.774902) (xy 188.445657 -153.774902) (xy 188.44965 -153.565161) (xy 188.461626 -153.355724)
			(xy 188.481567 -153.146895) (xy 188.509444 -152.938976) (xy 188.545216 -152.732269) (xy 188.588831 -152.527074)
			(xy 188.640227 -152.323689) (xy 188.699329 -152.122407) (xy 188.766051 -151.923521) (xy 188.840296 -151.72732)
			(xy 188.921956 -151.534088) (xy 189.010914 -151.344104) (xy 189.107041 -151.157645) (xy 189.210196 -150.974981)
			(xy 189.320231 -150.796376) (xy 189.436985 -150.62209) (xy 189.56029 -150.452375) (xy 189.689967 -150.287477)
			(xy 189.825828 -150.127636) (xy 189.967675 -149.973083) (xy 190.115304 -149.824043) (xy 190.268499 -149.68073)
			(xy 190.42704 -149.543354) (xy 190.590695 -149.412113) (xy 190.759229 -149.287198) (xy 190.932395 -149.16879)
			(xy 191.109945 -149.05706) (xy 191.291619 -148.95217) (xy 191.477154 -148.854273) (xy 191.666282 -148.763511)
			(xy 191.858729 -148.680014) (xy 192.054214 -148.603904) (xy 192.252456 -148.535292) (xy 192.453166 -148.474277)
			(xy 192.656053 -148.420948) (xy 192.860823 -148.375381) (xy 193.06718 -148.337642) (xy 193.274824 -148.307788)
			(xy 193.483454 -148.28586) (xy 193.692767 -148.271891) (xy 193.902461 -148.2659) (xy 194.11223 -148.267897)
			(xy 194.321772 -148.277879) (xy 194.530782 -148.295831) (xy 194.738956 -148.321727) (xy 194.945994 -148.355529)
			(xy 195.151595 -148.397189) (xy 195.355461 -148.446647) (xy 195.557296 -148.50383) (xy 195.756808 -148.568655)
			(xy 195.953707 -148.641029) (xy 196.147708 -148.720846) (xy 196.33853 -148.807992) (xy 196.525896 -148.902339)
			(xy 196.709534 -149.00375) (xy 196.889178 -149.11208) (xy 197.064568 -149.22717) (xy 197.235449 -149.348854)
			(xy 197.401573 -149.476955) (xy 197.5627 -149.611288) (xy 197.718597 -149.751657) (xy 197.869036 -149.89786)
			(xy 198.0138 -150.049684) (xy 198.152679 -150.20691) (xy 198.285472 -150.369309) (xy 198.411986 -150.536645)
			(xy 198.532038 -150.708677) (xy 198.645453 -150.885154) (xy 198.752067 -151.065822) (xy 198.851726 -151.250417)
			(xy 198.944285 -151.438672) (xy 199.02961 -151.630315) (xy 199.107577 -151.825067) (xy 199.178073 -152.022647)
			(xy 199.240996 -152.222766) (xy 199.296255 -152.425137) (xy 199.343769 -152.629464) (xy 199.38347 -152.835452)
			(xy 199.4153 -153.042803) (xy 199.439213 -153.251214) (xy 199.455174 -153.460385) (xy 199.463161 -153.670012)
			(xy 199.463618 -153.766012) (xy 272.385799 -153.766012) (xy 272.389792 -153.556271) (xy 272.401768 -153.346834)
			(xy 272.421709 -153.138005) (xy 272.449586 -152.930086) (xy 272.485358 -152.723379) (xy 272.528973 -152.518184)
			(xy 272.580369 -152.314799) (xy 272.639471 -152.113517) (xy 272.706193 -151.914631) (xy 272.780438 -151.71843)
			(xy 272.862098 -151.525198) (xy 272.951056 -151.335214) (xy 273.047183 -151.148755) (xy 273.150338 -150.966091)
			(xy 273.260373 -150.787486) (xy 273.377127 -150.6132) (xy 273.500432 -150.443485) (xy 273.630109 -150.278587)
			(xy 273.76597 -150.118746) (xy 273.907817 -149.964193) (xy 274.055446 -149.815153) (xy 274.208641 -149.67184)
			(xy 274.367182 -149.534464) (xy 274.530837 -149.403223) (xy 274.699371 -149.278308) (xy 274.872537 -149.1599)
			(xy 275.050087 -149.04817) (xy 275.231761 -148.94328) (xy 275.417296 -148.845383) (xy 275.606424 -148.754621)
			(xy 275.798871 -148.671124) (xy 275.994356 -148.595014) (xy 276.192598 -148.526402) (xy 276.393308 -148.465387)
			(xy 276.596195 -148.412058) (xy 276.800965 -148.366491) (xy 277.007322 -148.328752) (xy 277.214966 -148.298898)
			(xy 277.423596 -148.27697) (xy 277.632909 -148.263001) (xy 277.842603 -148.25701) (xy 278.052372 -148.259007)
			(xy 278.261914 -148.268989) (xy 278.470924 -148.286941) (xy 278.679098 -148.312837) (xy 278.886136 -148.346639)
			(xy 279.091737 -148.388299) (xy 279.295603 -148.437757) (xy 279.497438 -148.49494) (xy 279.69695 -148.559765)
			(xy 279.893849 -148.632139) (xy 280.08785 -148.711956) (xy 280.278672 -148.799102) (xy 280.466038 -148.893449)
			(xy 280.649676 -148.99486) (xy 280.82932 -149.10319) (xy 281.00471 -149.21828) (xy 281.175591 -149.339964)
			(xy 281.341715 -149.468065) (xy 281.502842 -149.602398) (xy 281.658739 -149.742767) (xy 281.809178 -149.88897)
			(xy 281.953942 -150.040794) (xy 282.092821 -150.19802) (xy 282.225614 -150.360419) (xy 282.352128 -150.527755)
			(xy 282.47218 -150.699787) (xy 282.585595 -150.876264) (xy 282.692209 -151.056932) (xy 282.791868 -151.241527)
			(xy 282.884427 -151.429782) (xy 282.969752 -151.621425) (xy 283.047719 -151.816177) (xy 283.118215 -152.013757)
			(xy 283.181138 -152.213876) (xy 283.236397 -152.416247) (xy 283.283911 -152.620574) (xy 283.323612 -152.826562)
			(xy 283.355442 -153.033913) (xy 283.379355 -153.242324) (xy 283.395316 -153.451495) (xy 283.403303 -153.661122)
			(xy 283.403802 -153.766012) (xy 283.40376 -153.774902) (xy 436.385725 -153.774902) (xy 436.389718 -153.565161)
			(xy 436.401694 -153.355724) (xy 436.421635 -153.146895) (xy 436.449512 -152.938976) (xy 436.485284 -152.732269)
			(xy 436.528899 -152.527074) (xy 436.580295 -152.323689) (xy 436.639397 -152.122407) (xy 436.706119 -151.923521)
			(xy 436.780364 -151.72732) (xy 436.862024 -151.534088) (xy 436.950982 -151.344104) (xy 437.047109 -151.157645)
			(xy 437.150264 -150.974981) (xy 437.260299 -150.796376) (xy 437.377053 -150.62209) (xy 437.500358 -150.452375)
			(xy 437.630035 -150.287477) (xy 437.765896 -150.127636) (xy 437.907743 -149.973083) (xy 438.055372 -149.824043)
			(xy 438.208567 -149.68073) (xy 438.367108 -149.543354) (xy 438.530763 -149.412113) (xy 438.699297 -149.287198)
			(xy 438.872463 -149.16879) (xy 439.050013 -149.05706) (xy 439.231687 -148.95217) (xy 439.417222 -148.854273)
			(xy 439.60635 -148.763511) (xy 439.798797 -148.680014) (xy 439.994282 -148.603904) (xy 440.192524 -148.535292)
			(xy 440.393234 -148.474277) (xy 440.596121 -148.420948) (xy 440.800891 -148.375381) (xy 441.007248 -148.337642)
			(xy 441.214892 -148.307788) (xy 441.423522 -148.28586) (xy 441.632835 -148.271891) (xy 441.842529 -148.2659)
			(xy 442.052298 -148.267897) (xy 442.26184 -148.277879) (xy 442.47085 -148.295831) (xy 442.679024 -148.321727)
			(xy 442.886062 -148.355529) (xy 443.091663 -148.397189) (xy 443.295529 -148.446647) (xy 443.497364 -148.50383)
			(xy 443.696876 -148.568655) (xy 443.893775 -148.641029) (xy 444.087776 -148.720846) (xy 444.278598 -148.807992)
			(xy 444.465964 -148.902339) (xy 444.649602 -149.00375) (xy 444.829246 -149.11208) (xy 445.004636 -149.22717)
			(xy 445.175517 -149.348854) (xy 445.341641 -149.476955) (xy 445.502768 -149.611288) (xy 445.658665 -149.751657)
			(xy 445.809104 -149.89786) (xy 445.953868 -150.049684) (xy 446.092747 -150.20691) (xy 446.22554 -150.369309)
			(xy 446.352054 -150.536645) (xy 446.472106 -150.708677) (xy 446.585521 -150.885154) (xy 446.692135 -151.065822)
			(xy 446.791794 -151.250417) (xy 446.884353 -151.438672) (xy 446.969678 -151.630315) (xy 447.047645 -151.825067)
			(xy 447.118141 -152.022647) (xy 447.181064 -152.222766) (xy 447.236323 -152.425137) (xy 447.283837 -152.629464)
			(xy 447.323538 -152.835452) (xy 447.355368 -153.042803) (xy 447.379281 -153.251214) (xy 447.395242 -153.460385)
			(xy 447.403229 -153.670012) (xy 447.403728 -153.774902) (xy 447.403229 -153.879792) (xy 447.395242 -154.089419)
			(xy 447.379281 -154.29859) (xy 447.355368 -154.507001) (xy 447.323538 -154.714352) (xy 447.283837 -154.92034)
			(xy 447.236323 -155.124667) (xy 447.181064 -155.327038) (xy 447.118141 -155.527157) (xy 447.047645 -155.724737)
			(xy 446.969678 -155.919489) (xy 446.884353 -156.111132) (xy 446.791794 -156.299387) (xy 446.692135 -156.483982)
			(xy 446.585521 -156.66465) (xy 446.472106 -156.841127) (xy 446.352054 -157.013159) (xy 446.22554 -157.180495)
			(xy 446.092747 -157.342894) (xy 445.953868 -157.50012) (xy 445.809104 -157.651944) (xy 445.658665 -157.798147)
			(xy 445.502768 -157.938516) (xy 445.341641 -158.072849) (xy 445.175517 -158.20095) (xy 445.004636 -158.322634)
			(xy 444.829246 -158.437724) (xy 444.649602 -158.546054) (xy 444.465964 -158.647465) (xy 444.278598 -158.741812)
			(xy 444.087776 -158.828958) (xy 443.893775 -158.908775) (xy 443.696876 -158.981149) (xy 443.497364 -159.045974)
			(xy 443.295529 -159.103157) (xy 443.091663 -159.152615) (xy 442.886062 -159.194275) (xy 442.679024 -159.228077)
			(xy 442.47085 -159.253973) (xy 442.26184 -159.271925) (xy 442.052298 -159.281907) (xy 441.842529 -159.283904)
			(xy 441.632835 -159.277913) (xy 441.423522 -159.263944) (xy 441.214892 -159.242016) (xy 441.007248 -159.212162)
			(xy 440.800891 -159.174423) (xy 440.596121 -159.128856) (xy 440.393234 -159.075527) (xy 440.192524 -159.014512)
			(xy 439.994282 -158.9459) (xy 439.798797 -158.86979) (xy 439.60635 -158.786293) (xy 439.417222 -158.695531)
			(xy 439.231687 -158.597634) (xy 439.050013 -158.492744) (xy 438.872463 -158.381014) (xy 438.699297 -158.262606)
			(xy 438.530763 -158.137691) (xy 438.367108 -158.00645) (xy 438.208567 -157.869074) (xy 438.055372 -157.725761)
			(xy 437.907743 -157.576721) (xy 437.765896 -157.422168) (xy 437.630035 -157.262327) (xy 437.500358 -157.097429)
			(xy 437.377053 -156.927714) (xy 437.260299 -156.753428) (xy 437.150264 -156.574823) (xy 437.047109 -156.392159)
			(xy 436.950982 -156.2057) (xy 436.862024 -156.015716) (xy 436.780364 -155.822484) (xy 436.706119 -155.626283)
			(xy 436.639397 -155.427397) (xy 436.580295 -155.226115) (xy 436.528899 -155.02273) (xy 436.485284 -154.817535)
			(xy 436.449512 -154.610828) (xy 436.421635 -154.402909) (xy 436.401694 -154.19408) (xy 436.389718 -153.984643)
			(xy 436.385725 -153.774902) (xy 283.40376 -153.774902) (xy 283.403303 -153.870902) (xy 283.395316 -154.080529)
			(xy 283.379355 -154.2897) (xy 283.355442 -154.498111) (xy 283.323612 -154.705462) (xy 283.283911 -154.91145)
			(xy 283.236397 -155.115777) (xy 283.181138 -155.318148) (xy 283.118215 -155.518267) (xy 283.047719 -155.715847)
			(xy 282.969752 -155.910599) (xy 282.884427 -156.102242) (xy 282.791868 -156.290497) (xy 282.692209 -156.475092)
			(xy 282.585595 -156.65576) (xy 282.47218 -156.832237) (xy 282.352128 -157.004269) (xy 282.225614 -157.171605)
			(xy 282.092821 -157.334004) (xy 281.953942 -157.49123) (xy 281.809178 -157.643054) (xy 281.658739 -157.789257)
			(xy 281.502842 -157.929626) (xy 281.341715 -158.063959) (xy 281.175591 -158.19206) (xy 281.00471 -158.313744)
			(xy 280.82932 -158.428834) (xy 280.649676 -158.537164) (xy 280.466038 -158.638575) (xy 280.278672 -158.732922)
			(xy 280.08785 -158.820068) (xy 279.893849 -158.899885) (xy 279.69695 -158.972259) (xy 279.497438 -159.037084)
			(xy 279.295603 -159.094267) (xy 279.091737 -159.143725) (xy 278.886136 -159.185385) (xy 278.679098 -159.219187)
			(xy 278.470924 -159.245083) (xy 278.261914 -159.263035) (xy 278.052372 -159.273017) (xy 277.842603 -159.275014)
			(xy 277.632909 -159.269023) (xy 277.423596 -159.255054) (xy 277.214966 -159.233126) (xy 277.007322 -159.203272)
			(xy 276.800965 -159.165533) (xy 276.596195 -159.119966) (xy 276.393308 -159.066637) (xy 276.192598 -159.005622)
			(xy 275.994356 -158.93701) (xy 275.798871 -158.8609) (xy 275.606424 -158.777403) (xy 275.417296 -158.686641)
			(xy 275.231761 -158.588744) (xy 275.050087 -158.483854) (xy 274.872537 -158.372124) (xy 274.699371 -158.253716)
			(xy 274.530837 -158.128801) (xy 274.367182 -157.99756) (xy 274.208641 -157.860184) (xy 274.055446 -157.716871)
			(xy 273.907817 -157.567831) (xy 273.76597 -157.413278) (xy 273.630109 -157.253437) (xy 273.500432 -157.088539)
			(xy 273.377127 -156.918824) (xy 273.260373 -156.744538) (xy 273.150338 -156.565933) (xy 273.047183 -156.383269)
			(xy 272.951056 -156.19681) (xy 272.862098 -156.006826) (xy 272.780438 -155.813594) (xy 272.706193 -155.617393)
			(xy 272.639471 -155.418507) (xy 272.580369 -155.217225) (xy 272.528973 -155.01384) (xy 272.485358 -154.808645)
			(xy 272.449586 -154.601938) (xy 272.421709 -154.394019) (xy 272.401768 -154.18519) (xy 272.389792 -153.975753)
			(xy 272.385799 -153.766012) (xy 199.463618 -153.766012) (xy 199.46366 -153.774902) (xy 199.463161 -153.879792)
			(xy 199.455174 -154.089419) (xy 199.439213 -154.29859) (xy 199.4153 -154.507001) (xy 199.38347 -154.714352)
			(xy 199.343769 -154.92034) (xy 199.296255 -155.124667) (xy 199.240996 -155.327038) (xy 199.178073 -155.527157)
			(xy 199.107577 -155.724737) (xy 199.02961 -155.919489) (xy 198.944285 -156.111132) (xy 198.851726 -156.299387)
			(xy 198.752067 -156.483982) (xy 198.645453 -156.66465) (xy 198.532038 -156.841127) (xy 198.411986 -157.013159)
			(xy 198.285472 -157.180495) (xy 198.152679 -157.342894) (xy 198.0138 -157.50012) (xy 197.869036 -157.651944)
			(xy 197.718597 -157.798147) (xy 197.5627 -157.938516) (xy 197.401573 -158.072849) (xy 197.235449 -158.20095)
			(xy 197.064568 -158.322634) (xy 196.889178 -158.437724) (xy 196.709534 -158.546054) (xy 196.525896 -158.647465)
			(xy 196.33853 -158.741812) (xy 196.147708 -158.828958) (xy 195.953707 -158.908775) (xy 195.756808 -158.981149)
			(xy 195.557296 -159.045974) (xy 195.355461 -159.103157) (xy 195.151595 -159.152615) (xy 194.945994 -159.194275)
			(xy 194.738956 -159.228077) (xy 194.530782 -159.253973) (xy 194.321772 -159.271925) (xy 194.11223 -159.281907)
			(xy 193.902461 -159.283904) (xy 193.692767 -159.277913) (xy 193.483454 -159.263944) (xy 193.274824 -159.242016)
			(xy 193.06718 -159.212162) (xy 192.860823 -159.174423) (xy 192.656053 -159.128856) (xy 192.453166 -159.075527)
			(xy 192.252456 -159.014512) (xy 192.054214 -158.9459) (xy 191.858729 -158.86979) (xy 191.666282 -158.786293)
			(xy 191.477154 -158.695531) (xy 191.291619 -158.597634) (xy 191.109945 -158.492744) (xy 190.932395 -158.381014)
			(xy 190.759229 -158.262606) (xy 190.590695 -158.137691) (xy 190.42704 -158.00645) (xy 190.268499 -157.869074)
			(xy 190.115304 -157.725761) (xy 189.967675 -157.576721) (xy 189.825828 -157.422168) (xy 189.689967 -157.262327)
			(xy 189.56029 -157.097429) (xy 189.436985 -156.927714) (xy 189.320231 -156.753428) (xy 189.210196 -156.574823)
			(xy 189.107041 -156.392159) (xy 189.010914 -156.2057) (xy 188.921956 -156.015716) (xy 188.840296 -155.822484)
			(xy 188.766051 -155.626283) (xy 188.699329 -155.427397) (xy 188.640227 -155.226115) (xy 188.588831 -155.02273)
			(xy 188.545216 -154.817535) (xy 188.509444 -154.610828) (xy 188.481567 -154.402909) (xy 188.461626 -154.19408)
			(xy 188.44965 -153.984643) (xy 188.445657 -153.774902) (xy 187.505848 -153.774902) (xy 187.505848 -154.239468)
			(xy 187.505362 -154.266719) (xy 187.497606 -154.320667) (xy 187.482251 -154.372962) (xy 187.459609 -154.422539)
			(xy 187.430143 -154.468389) (xy 187.394452 -154.50958) (xy 187.353261 -154.545271) (xy 187.307411 -154.574737)
			(xy 187.257834 -154.597379) (xy 187.205539 -154.612734) (xy 187.151591 -154.62049) (xy 187.097089 -154.62049)
			(xy 187.043141 -154.612734) (xy 186.990846 -154.597379) (xy 186.941269 -154.574737) (xy 186.895419 -154.545271)
			(xy 186.854228 -154.50958) (xy 186.818537 -154.468389) (xy 186.789071 -154.422539) (xy 186.766429 -154.372962)
			(xy 186.751074 -154.320667) (xy 186.743318 -154.266719) (xy 186.742832 -154.239468) (xy 35.44312 -154.239468)
			(xy 35.439287 -154.2897) (xy 35.415374 -154.498111) (xy 35.383544 -154.705462) (xy 35.343843 -154.91145)
			(xy 35.296329 -155.115777) (xy 35.24107 -155.318148) (xy 35.178147 -155.518267) (xy 35.107651 -155.715847)
			(xy 35.029684 -155.910599) (xy 34.944359 -156.102242) (xy 34.8518 -156.290497) (xy 34.752141 -156.475092)
			(xy 34.645527 -156.65576) (xy 34.532112 -156.832237) (xy 34.41206 -157.004269) (xy 34.285546 -157.171605)
			(xy 34.152753 -157.334004) (xy 34.013874 -157.49123) (xy 33.86911 -157.643054) (xy 33.718671 -157.789257)
			(xy 33.562774 -157.929626) (xy 33.401647 -158.063959) (xy 33.235523 -158.19206) (xy 33.064642 -158.313744)
			(xy 32.889252 -158.428834) (xy 32.709608 -158.537164) (xy 32.52597 -158.638575) (xy 32.338604 -158.732922)
			(xy 32.147782 -158.820068) (xy 31.953781 -158.899885) (xy 31.756882 -158.972259) (xy 31.55737 -159.037084)
			(xy 31.355535 -159.094267) (xy 31.151669 -159.143725) (xy 30.946068 -159.185385) (xy 30.73903 -159.219187)
			(xy 30.530856 -159.245083) (xy 30.321846 -159.263035) (xy 30.112304 -159.273017) (xy 29.902535 -159.275014)
			(xy 29.692841 -159.269023) (xy 29.483528 -159.255054) (xy 29.274898 -159.233126) (xy 29.067254 -159.203272)
			(xy 28.860897 -159.165533) (xy 28.656127 -159.119966) (xy 28.45324 -159.066637) (xy 28.25253 -159.005622)
			(xy 28.054288 -158.93701) (xy 27.858803 -158.8609) (xy 27.666356 -158.777403) (xy 27.477228 -158.686641)
			(xy 27.291693 -158.588744) (xy 27.110019 -158.483854) (xy 26.932469 -158.372124) (xy 26.759303 -158.253716)
			(xy 26.590769 -158.128801) (xy 26.427114 -157.99756) (xy 26.268573 -157.860184) (xy 26.115378 -157.716871)
			(xy 25.967749 -157.567831) (xy 25.825902 -157.413278) (xy 25.690041 -157.253437) (xy 25.560364 -157.088539)
			(xy 25.437059 -156.918824) (xy 25.320305 -156.744538) (xy 25.21027 -156.565933) (xy 25.107115 -156.383269)
			(xy 25.010988 -156.19681) (xy 24.92203 -156.006826) (xy 24.84037 -155.813594) (xy 24.766125 -155.617393)
			(xy 24.699403 -155.418507) (xy 24.640301 -155.217225) (xy 24.588905 -155.01384) (xy 24.54529 -154.808645)
			(xy 24.509518 -154.601938) (xy 24.481641 -154.394019) (xy 24.4617 -154.18519) (xy 24.449724 -153.975753)
			(xy 24.445731 -153.766012) (xy 2.509012 -153.766012) (xy 2.509012 -160.911354) (xy 372.506163 -160.911354)
			(xy 372.506163 -160.856846) (xy 372.513921 -160.802893) (xy 372.529279 -160.750593) (xy 372.551924 -160.701011)
			(xy 372.581395 -160.655157) (xy 372.617092 -160.613964) (xy 372.658289 -160.578271) (xy 372.704146 -160.548805)
			(xy 372.75373 -160.526165) (xy 372.806032 -160.510813) (xy 372.859986 -160.503061) (xy 372.88724 -160.5026)
			(xy 373.75084 -160.5026) (xy 373.77809 -160.503073) (xy 373.832034 -160.510834) (xy 373.884326 -160.526193)
			(xy 373.933899 -160.548837) (xy 373.979745 -160.578305) (xy 374.020931 -160.613997) (xy 374.056619 -160.655187)
			(xy 374.086083 -160.701036) (xy 374.108721 -160.750612) (xy 374.124075 -160.802905) (xy 374.13183 -160.85685)
			(xy 374.13183 -160.91135) (xy 374.124075 -160.965295) (xy 374.108721 -161.017588) (xy 374.086083 -161.067164)
			(xy 374.056619 -161.113013) (xy 374.020931 -161.154203) (xy 373.979745 -161.189895) (xy 373.933899 -161.219363)
			(xy 373.884326 -161.242007) (xy 373.832034 -161.257366) (xy 373.77809 -161.265127) (xy 373.75084 -161.265616)
			(xy 372.88724 -161.265616) (xy 372.859986 -161.265139) (xy 372.806032 -161.257387) (xy 372.75373 -161.242035)
			(xy 372.704146 -161.219395) (xy 372.658289 -161.189929) (xy 372.617092 -161.154236) (xy 372.581395 -161.113043)
			(xy 372.551924 -161.067189) (xy 372.529279 -161.017607) (xy 372.513921 -160.965307) (xy 372.506163 -160.911354)
			(xy 2.509012 -160.911354) (xy 2.509012 -161.58445) (xy 296.753286 -161.58445) (xy 296.753286 -161.52995)
			(xy 296.761042 -161.476005) (xy 296.776395 -161.423713) (xy 296.799035 -161.374138) (xy 296.828498 -161.32829)
			(xy 296.864187 -161.287101) (xy 296.905374 -161.25141) (xy 296.951221 -161.221944) (xy 297.000795 -161.199302)
			(xy 297.053086 -161.183946) (xy 297.10703 -161.176187) (xy 297.13428 -161.1757) (xy 297.99788 -161.1757)
			(xy 298.025134 -161.176146) (xy 298.079089 -161.183901) (xy 298.13139 -161.199255) (xy 298.180974 -161.221897)
			(xy 298.22683 -161.251365) (xy 298.268026 -161.28706) (xy 298.303723 -161.328254) (xy 298.333193 -161.374109)
			(xy 298.355838 -161.423691) (xy 298.371195 -161.475992) (xy 298.378953 -161.529946) (xy 298.378953 -161.584454)
			(xy 298.371195 -161.638408) (xy 298.355838 -161.690709) (xy 298.333193 -161.740291) (xy 298.303723 -161.786146)
			(xy 298.268026 -161.82734) (xy 298.22683 -161.863035) (xy 298.180974 -161.892503) (xy 298.13139 -161.915145)
			(xy 298.079089 -161.930499) (xy 298.025134 -161.938254) (xy 297.99788 -161.938716) (xy 297.13428 -161.938716)
			(xy 297.10703 -161.938213) (xy 297.053086 -161.930454) (xy 297.000795 -161.915098) (xy 296.951221 -161.892456)
			(xy 296.905374 -161.86299) (xy 296.864187 -161.827299) (xy 296.828498 -161.78611) (xy 296.799035 -161.740262)
			(xy 296.776395 -161.690687) (xy 296.761042 -161.638395) (xy 296.753286 -161.58445) (xy 2.509012 -161.58445)
			(xy 2.509012 -162.128053) (xy 292.574946 -162.128053) (xy 292.574946 -162.073547) (xy 292.582702 -162.019597)
			(xy 292.598058 -161.967299) (xy 292.620699 -161.917719) (xy 292.650166 -161.871866) (xy 292.685859 -161.830673)
			(xy 292.72705 -161.794978) (xy 292.772902 -161.765509) (xy 292.822481 -161.742865) (xy 292.874777 -161.727507)
			(xy 292.928727 -161.719747) (xy 292.95598 -161.71926) (xy 293.81958 -161.71926) (xy 293.846832 -161.719786)
			(xy 293.90078 -161.72754) (xy 293.953076 -161.742893) (xy 294.002654 -161.765532) (xy 294.048506 -161.794997)
			(xy 294.089698 -161.830688) (xy 294.125391 -161.871878) (xy 294.154858 -161.917728) (xy 294.1775 -161.967305)
			(xy 294.192856 -162.0196) (xy 294.200613 -162.073549) (xy 294.200613 -162.128051) (xy 294.192856 -162.182)
			(xy 294.1775 -162.234295) (xy 294.154858 -162.283872) (xy 294.125391 -162.329722) (xy 294.089698 -162.370912)
			(xy 294.048506 -162.406603) (xy 294.002654 -162.436068) (xy 293.953076 -162.458707) (xy 293.90078 -162.47406)
			(xy 293.846832 -162.481814) (xy 293.81958 -162.482276) (xy 292.95598 -162.482276) (xy 292.928727 -162.481853)
			(xy 292.874777 -162.474093) (xy 292.822481 -162.458735) (xy 292.772902 -162.436091) (xy 292.72705 -162.406622)
			(xy 292.685859 -162.370927) (xy 292.650166 -162.329734) (xy 292.620699 -162.283881) (xy 292.598058 -162.234301)
			(xy 292.582702 -162.182003) (xy 292.574946 -162.128053) (xy 2.509012 -162.128053) (xy 2.509012 -163.123651)
			(xy 294.731403 -163.123651) (xy 294.731403 -163.069149) (xy 294.73916 -163.015201) (xy 294.754516 -162.962907)
			(xy 294.777159 -162.91333) (xy 294.806627 -162.867481) (xy 294.842321 -162.826292) (xy 294.883513 -162.790603)
			(xy 294.929365 -162.76114) (xy 294.978944 -162.738502) (xy 295.03124 -162.723152) (xy 295.085189 -162.7154)
			(xy 295.11244 -162.71494) (xy 295.97604 -162.71494) (xy 296.003293 -162.715333) (xy 296.057243 -162.723095)
			(xy 296.10954 -162.738455) (xy 296.159118 -162.761102) (xy 296.204969 -162.790573) (xy 296.24616 -162.826269)
			(xy 296.281851 -162.867463) (xy 296.311318 -162.913317) (xy 296.333959 -162.962898) (xy 296.349314 -163.015196)
			(xy 296.35707 -163.069147) (xy 296.35707 -163.110951) (xy 300.192403 -163.110951) (xy 300.192403 -163.056449)
			(xy 300.20016 -163.002501) (xy 300.215516 -162.950207) (xy 300.238159 -162.90063) (xy 300.267627 -162.854781)
			(xy 300.303321 -162.813592) (xy 300.344513 -162.777903) (xy 300.390365 -162.74844) (xy 300.439944 -162.725802)
			(xy 300.49224 -162.710452) (xy 300.546189 -162.7027) (xy 300.57344 -162.70224) (xy 301.43704 -162.70224)
			(xy 301.464293 -162.702633) (xy 301.518243 -162.710395) (xy 301.57054 -162.725755) (xy 301.620118 -162.748402)
			(xy 301.665969 -162.777873) (xy 301.70716 -162.813569) (xy 301.742851 -162.854763) (xy 301.772318 -162.900617)
			(xy 301.794959 -162.950198) (xy 301.810314 -163.002496) (xy 301.81807 -163.056447) (xy 301.81807 -163.110953)
			(xy 301.810314 -163.164904) (xy 301.794959 -163.217202) (xy 301.772318 -163.266783) (xy 301.742851 -163.312637)
			(xy 301.70716 -163.353831) (xy 301.665969 -163.389527) (xy 301.620118 -163.418998) (xy 301.57054 -163.441645)
			(xy 301.518243 -163.457005) (xy 301.464293 -163.464767) (xy 301.43704 -163.465256) (xy 300.57344 -163.465256)
			(xy 300.546189 -163.4647) (xy 300.49224 -163.456948) (xy 300.439944 -163.441598) (xy 300.390365 -163.41896)
			(xy 300.344513 -163.389497) (xy 300.303321 -163.353808) (xy 300.267627 -163.312619) (xy 300.238159 -163.26677)
			(xy 300.215516 -163.217193) (xy 300.20016 -163.164899) (xy 300.192403 -163.110951) (xy 296.35707 -163.110951)
			(xy 296.35707 -163.123653) (xy 296.349314 -163.177604) (xy 296.333959 -163.229902) (xy 296.311318 -163.279483)
			(xy 296.281851 -163.325337) (xy 296.24616 -163.366531) (xy 296.204969 -163.402227) (xy 296.159118 -163.431698)
			(xy 296.10954 -163.454345) (xy 296.057243 -163.469705) (xy 296.003293 -163.477467) (xy 295.97604 -163.477956)
			(xy 295.11244 -163.477956) (xy 295.085189 -163.4774) (xy 295.03124 -163.469648) (xy 294.978944 -163.454298)
			(xy 294.929365 -163.43166) (xy 294.883513 -163.402197) (xy 294.842321 -163.366508) (xy 294.806627 -163.325319)
			(xy 294.777159 -163.27947) (xy 294.754516 -163.229893) (xy 294.73916 -163.177599) (xy 294.731403 -163.123651)
			(xy 2.509012 -163.123651) (xy 2.509012 -167.565832) (xy 348.657164 -167.565832) (xy 348.657658 -167.532531)
			(xy 348.666337 -167.466499) (xy 348.683566 -167.402165) (xy 348.709048 -167.340632) (xy 348.742347 -167.282953)
			(xy 348.782893 -167.230117) (xy 348.829992 -167.183027) (xy 348.882836 -167.142492) (xy 348.911418 -167.125396)
			(xy 349.83547 -166.591742) (xy 349.864533 -166.575642) (xy 349.925937 -166.550271) (xy 349.990123 -166.533114)
			(xy 350.055996 -166.524463) (xy 350.089216 -166.523924) (xy 350.089724 -166.523924) (xy 350.120458 -166.524315)
			(xy 350.181477 -166.531727) (xy 350.241158 -166.54644) (xy 350.29863 -166.56824) (xy 350.353056 -166.596808)
			(xy 350.403641 -166.631729) (xy 350.449648 -166.672492) (xy 350.490406 -166.718503) (xy 350.525321 -166.769092)
			(xy 350.553883 -166.823521) (xy 350.57377 -166.875968) (xy 369.614196 -166.875968) (xy 369.614752 -166.84267)
			(xy 369.623426 -166.776641) (xy 369.640648 -166.71231) (xy 369.666122 -166.650779) (xy 369.699412 -166.593101)
			(xy 369.739949 -166.540263) (xy 369.787038 -166.493171) (xy 369.839873 -166.452631) (xy 369.86845 -166.435532)
			(xy 370.792502 -165.901878) (xy 370.82156 -165.885769) (xy 370.882966 -165.8604) (xy 370.947153 -165.843245)
			(xy 371.013028 -165.834597) (xy 371.046248 -165.83406) (xy 371.046756 -165.83406) (xy 371.077486 -165.834579)
			(xy 371.138498 -165.841982) (xy 371.198173 -165.856685) (xy 371.255641 -165.878475) (xy 371.310063 -165.907032)
			(xy 371.360647 -165.941941) (xy 371.406653 -165.982693) (xy 371.447412 -166.028694) (xy 371.482329 -166.079272)
			(xy 371.510894 -166.133689) (xy 371.532692 -166.191154) (xy 371.547404 -166.250827) (xy 371.554816 -166.311838)
			(xy 371.555264 -166.342568) (xy 371.554757 -166.375868) (xy 371.546077 -166.4419) (xy 371.52885 -166.506232)
			(xy 371.503369 -166.567765) (xy 371.470072 -166.625443) (xy 371.429528 -166.67828) (xy 371.382432 -166.72537)
			(xy 371.329591 -166.765907) (xy 371.30101 -166.783004) (xy 370.964111 -166.977568) (xy 373.398796 -166.977568)
			(xy 373.399226 -166.946836) (xy 373.406638 -166.885821) (xy 373.421351 -166.826144) (xy 373.443149 -166.768676)
			(xy 373.471715 -166.714254) (xy 373.506633 -166.663671) (xy 373.547392 -166.617667) (xy 373.5934 -166.57691)
			(xy 373.643984 -166.541996) (xy 373.698409 -166.513434) (xy 373.755879 -166.49164) (xy 373.815556 -166.476932)
			(xy 373.876572 -166.469524) (xy 373.907304 -166.46906) (xy 373.907812 -166.46906) (xy 373.941031 -166.469606)
			(xy 374.006903 -166.478264) (xy 374.071088 -166.495419) (xy 374.132496 -166.520778) (xy 374.161558 -166.536878)
			(xy 375.08561 -167.070532) (xy 375.114171 -167.087654) (xy 375.166997 -167.128201) (xy 375.214079 -167.175295)
			(xy 375.254613 -167.22813) (xy 375.287906 -167.285802) (xy 375.313388 -167.347326) (xy 375.330623 -167.411649)
			(xy 375.339318 -167.477672) (xy 375.339864 -167.510968) (xy 375.339432 -167.541701) (xy 375.332026 -167.60272)
			(xy 375.317319 -167.6624) (xy 375.295524 -167.719873) (xy 375.266961 -167.774299) (xy 375.232044 -167.824885)
			(xy 375.191284 -167.870893) (xy 375.145275 -167.911651) (xy 375.094689 -167.946567) (xy 375.040262 -167.975129)
			(xy 374.982789 -167.996923) (xy 374.923108 -168.011629) (xy 374.862089 -168.019033) (xy 374.831356 -168.019476)
			(xy 374.830848 -168.019476) (xy 374.797629 -168.018942) (xy 374.731757 -168.01028) (xy 374.667571 -167.993122)
			(xy 374.606164 -167.967759) (xy 374.577102 -167.951658) (xy 373.65305 -167.418004) (xy 373.624495 -167.400872)
			(xy 373.571672 -167.360325) (xy 373.524591 -167.313232) (xy 373.484057 -167.260398) (xy 373.450764 -167.202727)
			(xy 373.42528 -167.141205) (xy 373.408042 -167.076884) (xy 373.399344 -167.010863) (xy 373.398796 -166.977568)
			(xy 370.964111 -166.977568) (xy 370.376958 -167.316658) (xy 370.34791 -167.332786) (xy 370.2865 -167.35815)
			(xy 370.22231 -167.375299) (xy 370.156433 -167.383942) (xy 370.123212 -167.384476) (xy 370.122704 -167.384476)
			(xy 370.091971 -167.384059) (xy 370.030952 -167.37665) (xy 369.971272 -167.36194) (xy 369.9138 -167.340143)
			(xy 369.859375 -167.311577) (xy 369.808789 -167.276659) (xy 369.762782 -167.235898) (xy 369.722023 -167.189889)
			(xy 369.687108 -167.139301) (xy 369.658546 -167.084874) (xy 369.636752 -167.027401) (xy 369.622045 -166.96772)
			(xy 369.61464 -166.906701) (xy 369.614196 -166.875968) (xy 350.57377 -166.875968) (xy 350.575676 -166.880996)
			(xy 350.590383 -166.940678) (xy 350.597788 -167.001698) (xy 350.598232 -167.032432) (xy 350.597712 -167.065732)
			(xy 350.589036 -167.131763) (xy 350.571812 -167.196097) (xy 350.546334 -167.25763) (xy 350.513038 -167.315309)
			(xy 350.472496 -167.368145) (xy 350.4254 -167.415235) (xy 350.372559 -167.455772) (xy 350.343978 -167.472868)
			(xy 349.419926 -168.006522) (xy 349.390862 -168.02262) (xy 349.329459 -168.047992) (xy 349.265273 -168.06515)
			(xy 349.1994 -168.073802) (xy 349.16618 -168.07434) (xy 349.165672 -168.07434) (xy 349.134942 -168.07387)
			(xy 349.073929 -168.066459) (xy 349.014255 -168.051748) (xy 348.956789 -168.029953) (xy 348.902369 -168.001389)
			(xy 348.851788 -167.966475) (xy 348.805784 -167.925719) (xy 348.765027 -167.879715) (xy 348.730113 -167.829135)
			(xy 348.701549 -167.774715) (xy 348.679753 -167.717249) (xy 348.665041 -167.657575) (xy 348.65763 -167.596562)
			(xy 348.657164 -167.565832) (xy 2.509012 -167.565832) (xy 2.509012 -168.302432) (xy 352.441764 -168.302432)
			(xy 352.442268 -168.271702) (xy 352.449672 -168.210689) (xy 352.464377 -168.151013) (xy 352.486168 -168.093545)
			(xy 352.514727 -168.039122) (xy 352.549637 -167.988539) (xy 352.59039 -167.942533) (xy 352.636392 -167.901774)
			(xy 352.686971 -167.866858) (xy 352.74139 -167.838292) (xy 352.798856 -167.816495) (xy 352.85853 -167.801783)
			(xy 352.919542 -167.794371) (xy 352.950272 -167.793924) (xy 352.95078 -167.793924) (xy 352.983998 -167.794489)
			(xy 353.049869 -167.803142) (xy 353.114055 -167.820291) (xy 353.175463 -167.845645) (xy 353.204526 -167.861742)
			(xy 354.128578 -168.395396) (xy 354.157139 -168.412518) (xy 354.209962 -168.453067) (xy 354.257042 -168.500162)
			(xy 354.297574 -168.552998) (xy 354.330866 -168.61067) (xy 354.356349 -168.672193) (xy 354.373586 -168.736515)
			(xy 354.382284 -168.802536) (xy 354.382832 -168.835832) (xy 354.382374 -168.866563) (xy 354.374962 -168.927576)
			(xy 354.360251 -168.987251) (xy 354.338454 -169.044717) (xy 354.30989 -169.099138) (xy 354.274975 -169.149719)
			(xy 354.234218 -169.195723) (xy 354.188213 -169.23648) (xy 354.137631 -169.271394) (xy 354.08321 -169.299957)
			(xy 354.025743 -169.321753) (xy 353.966068 -169.336464) (xy 353.905055 -169.343875) (xy 353.874324 -169.34434)
			(xy 353.873816 -169.34434) (xy 353.840597 -169.343782) (xy 353.774726 -169.335127) (xy 353.710541 -169.317976)
			(xy 353.649132 -169.292621) (xy 353.62007 -169.276522) (xy 352.696018 -168.742868) (xy 352.667463 -168.725735)
			(xy 352.614637 -168.685191) (xy 352.567553 -168.638099) (xy 352.527018 -168.585266) (xy 352.493724 -168.527595)
			(xy 352.468241 -168.466072) (xy 352.451005 -168.40175) (xy 352.44231 -168.335728) (xy 352.441764 -168.302432)
			(xy 2.509012 -168.302432) (xy 2.509012 -170.613832) (xy 348.657164 -170.613832) (xy 348.657658 -170.580531)
			(xy 348.666337 -170.514499) (xy 348.683566 -170.450165) (xy 348.709048 -170.388632) (xy 348.742347 -170.330953)
			(xy 348.782893 -170.278117) (xy 348.829992 -170.231027) (xy 348.882836 -170.190492) (xy 348.911418 -170.173396)
			(xy 349.83547 -169.639742) (xy 349.864533 -169.623642) (xy 349.925937 -169.598271) (xy 349.990123 -169.581114)
			(xy 350.055996 -169.572463) (xy 350.089216 -169.571924) (xy 350.089724 -169.571924) (xy 350.120458 -169.572315)
			(xy 350.181477 -169.579727) (xy 350.241158 -169.59444) (xy 350.29863 -169.61624) (xy 350.353056 -169.644808)
			(xy 350.403641 -169.679729) (xy 350.449648 -169.720492) (xy 350.490406 -169.766503) (xy 350.525321 -169.817092)
			(xy 350.553883 -169.871521) (xy 350.57377 -169.923968) (xy 369.614196 -169.923968) (xy 369.614752 -169.89067)
			(xy 369.623426 -169.824641) (xy 369.640648 -169.76031) (xy 369.666122 -169.698779) (xy 369.699412 -169.641101)
			(xy 369.739949 -169.588263) (xy 369.787038 -169.541171) (xy 369.839873 -169.500631) (xy 369.86845 -169.483532)
			(xy 370.792502 -168.949878) (xy 370.82156 -168.933769) (xy 370.882966 -168.9084) (xy 370.947153 -168.891245)
			(xy 371.013028 -168.882597) (xy 371.046248 -168.88206) (xy 371.046756 -168.88206) (xy 371.077486 -168.882579)
			(xy 371.138498 -168.889982) (xy 371.198173 -168.904685) (xy 371.255641 -168.926475) (xy 371.310063 -168.955032)
			(xy 371.360647 -168.989941) (xy 371.406653 -169.030693) (xy 371.447412 -169.076694) (xy 371.482329 -169.127272)
			(xy 371.510894 -169.181689) (xy 371.532692 -169.239154) (xy 371.547404 -169.298827) (xy 371.554816 -169.359838)
			(xy 371.555264 -169.390568) (xy 371.554757 -169.423868) (xy 371.546077 -169.4899) (xy 371.52885 -169.554232)
			(xy 371.503369 -169.615765) (xy 371.470072 -169.673443) (xy 371.429528 -169.72628) (xy 371.382432 -169.77337)
			(xy 371.329591 -169.813907) (xy 371.30101 -169.831004) (xy 370.376958 -170.364658) (xy 370.34791 -170.380786)
			(xy 370.2865 -170.40615) (xy 370.22231 -170.423299) (xy 370.156433 -170.431942) (xy 370.123212 -170.432476)
			(xy 370.122704 -170.432476) (xy 370.091971 -170.432059) (xy 370.030952 -170.42465) (xy 369.971272 -170.40994)
			(xy 369.9138 -170.388143) (xy 369.859375 -170.359577) (xy 369.808789 -170.324659) (xy 369.762782 -170.283898)
			(xy 369.722023 -170.237889) (xy 369.687108 -170.187301) (xy 369.658546 -170.132874) (xy 369.636752 -170.075401)
			(xy 369.622045 -170.01572) (xy 369.61464 -169.954701) (xy 369.614196 -169.923968) (xy 350.57377 -169.923968)
			(xy 350.575676 -169.928996) (xy 350.590383 -169.988678) (xy 350.597788 -170.049698) (xy 350.598232 -170.080432)
			(xy 350.597712 -170.113732) (xy 350.589036 -170.179763) (xy 350.571812 -170.244097) (xy 350.546334 -170.30563)
			(xy 350.513038 -170.363309) (xy 350.472496 -170.416145) (xy 350.4254 -170.463235) (xy 350.372559 -170.503772)
			(xy 350.343978 -170.520868) (xy 350.10208 -170.660568) (xy 373.398796 -170.660568) (xy 373.399226 -170.629836)
			(xy 373.406638 -170.568821) (xy 373.421351 -170.509144) (xy 373.443149 -170.451676) (xy 373.471715 -170.397254)
			(xy 373.506633 -170.346671) (xy 373.547392 -170.300667) (xy 373.5934 -170.25991) (xy 373.643984 -170.224996)
			(xy 373.698409 -170.196434) (xy 373.755879 -170.17464) (xy 373.815556 -170.159932) (xy 373.876572 -170.152524)
			(xy 373.907304 -170.15206) (xy 373.907812 -170.15206) (xy 373.941031 -170.152606) (xy 374.006903 -170.161264)
			(xy 374.071088 -170.178419) (xy 374.132496 -170.203778) (xy 374.161558 -170.219878) (xy 375.08561 -170.753532)
			(xy 375.114171 -170.770654) (xy 375.166997 -170.811201) (xy 375.214079 -170.858295) (xy 375.254613 -170.91113)
			(xy 375.287906 -170.968802) (xy 375.313388 -171.030326) (xy 375.330623 -171.094649) (xy 375.339318 -171.160672)
			(xy 375.339864 -171.193968) (xy 375.339432 -171.224701) (xy 375.332026 -171.28572) (xy 375.317319 -171.3454)
			(xy 375.295524 -171.402873) (xy 375.266961 -171.457299) (xy 375.232044 -171.507885) (xy 375.191284 -171.553893)
			(xy 375.145275 -171.594651) (xy 375.094689 -171.629567) (xy 375.040262 -171.658129) (xy 374.982789 -171.679923)
			(xy 374.923108 -171.694629) (xy 374.862089 -171.702033) (xy 374.831356 -171.702476) (xy 374.830848 -171.702476)
			(xy 374.797629 -171.701942) (xy 374.731757 -171.69328) (xy 374.667571 -171.676122) (xy 374.606164 -171.650759)
			(xy 374.577102 -171.634658) (xy 373.65305 -171.101004) (xy 373.624495 -171.083872) (xy 373.571672 -171.043325)
			(xy 373.524591 -170.996232) (xy 373.484057 -170.943398) (xy 373.450764 -170.885727) (xy 373.42528 -170.824205)
			(xy 373.408042 -170.759884) (xy 373.399344 -170.693863) (xy 373.398796 -170.660568) (xy 350.10208 -170.660568)
			(xy 349.419926 -171.054522) (xy 349.390862 -171.07062) (xy 349.329459 -171.095992) (xy 349.265273 -171.11315)
			(xy 349.1994 -171.121802) (xy 349.16618 -171.12234) (xy 349.165672 -171.12234) (xy 349.134942 -171.12187)
			(xy 349.073929 -171.114459) (xy 349.014255 -171.099748) (xy 348.956789 -171.077953) (xy 348.902369 -171.049389)
			(xy 348.851788 -171.014475) (xy 348.805784 -170.973719) (xy 348.765027 -170.927715) (xy 348.730113 -170.877135)
			(xy 348.701549 -170.822715) (xy 348.679753 -170.765249) (xy 348.665041 -170.705575) (xy 348.65763 -170.644562)
			(xy 348.657164 -170.613832) (xy 2.509012 -170.613832) (xy 2.509012 -171.985432) (xy 352.441764 -171.985432)
			(xy 352.442268 -171.954702) (xy 352.449672 -171.893689) (xy 352.464377 -171.834013) (xy 352.486168 -171.776545)
			(xy 352.514727 -171.722122) (xy 352.549637 -171.671539) (xy 352.59039 -171.625533) (xy 352.636392 -171.584774)
			(xy 352.686971 -171.549858) (xy 352.74139 -171.521292) (xy 352.798856 -171.499495) (xy 352.85853 -171.484783)
			(xy 352.919542 -171.477371) (xy 352.950272 -171.476924) (xy 352.95078 -171.476924) (xy 352.983998 -171.477489)
			(xy 353.049869 -171.486142) (xy 353.114055 -171.503291) (xy 353.175463 -171.528645) (xy 353.204526 -171.544742)
			(xy 354.128578 -172.078396) (xy 354.157139 -172.095518) (xy 354.209962 -172.136067) (xy 354.257042 -172.183162)
			(xy 354.297574 -172.235998) (xy 354.330866 -172.29367) (xy 354.356349 -172.355193) (xy 354.373586 -172.419515)
			(xy 354.382284 -172.485536) (xy 354.382832 -172.518832) (xy 354.382374 -172.549563) (xy 354.374962 -172.610576)
			(xy 354.360251 -172.670251) (xy 354.338454 -172.727717) (xy 354.30989 -172.782138) (xy 354.274975 -172.832719)
			(xy 354.234218 -172.878723) (xy 354.188213 -172.91948) (xy 354.137631 -172.954394) (xy 354.104147 -172.971968)
			(xy 369.614196 -172.971968) (xy 369.614752 -172.93867) (xy 369.623426 -172.872641) (xy 369.640648 -172.80831)
			(xy 369.666122 -172.746779) (xy 369.699412 -172.689101) (xy 369.739949 -172.636263) (xy 369.787038 -172.589171)
			(xy 369.839873 -172.548631) (xy 369.86845 -172.531532) (xy 370.792502 -171.997878) (xy 370.82156 -171.981769)
			(xy 370.882966 -171.9564) (xy 370.947153 -171.939245) (xy 371.013028 -171.930597) (xy 371.046248 -171.93006)
			(xy 371.046756 -171.93006) (xy 371.077486 -171.930579) (xy 371.138498 -171.937982) (xy 371.198173 -171.952685)
			(xy 371.255641 -171.974475) (xy 371.310063 -172.003032) (xy 371.360647 -172.037941) (xy 371.406653 -172.078693)
			(xy 371.447412 -172.124694) (xy 371.482329 -172.175272) (xy 371.510894 -172.229689) (xy 371.532692 -172.287154)
			(xy 371.547404 -172.346827) (xy 371.554816 -172.407838) (xy 371.555264 -172.438568) (xy 371.554757 -172.471868)
			(xy 371.546077 -172.5379) (xy 371.52885 -172.602232) (xy 371.503369 -172.663765) (xy 371.470072 -172.721443)
			(xy 371.429528 -172.77428) (xy 371.382432 -172.82137) (xy 371.329591 -172.861907) (xy 371.30101 -172.879004)
			(xy 370.376958 -173.412658) (xy 370.34791 -173.428786) (xy 370.2865 -173.45415) (xy 370.22231 -173.471299)
			(xy 370.156433 -173.479942) (xy 370.123212 -173.480476) (xy 370.122704 -173.480476) (xy 370.091971 -173.480059)
			(xy 370.030952 -173.47265) (xy 369.971272 -173.45794) (xy 369.9138 -173.436143) (xy 369.859375 -173.407577)
			(xy 369.808789 -173.372659) (xy 369.762782 -173.331898) (xy 369.722023 -173.285889) (xy 369.687108 -173.235301)
			(xy 369.658546 -173.180874) (xy 369.636752 -173.123401) (xy 369.622045 -173.06372) (xy 369.61464 -173.002701)
			(xy 369.614196 -172.971968) (xy 354.104147 -172.971968) (xy 354.08321 -172.982957) (xy 354.025743 -173.004753)
			(xy 353.966068 -173.019464) (xy 353.905055 -173.026875) (xy 353.874324 -173.02734) (xy 353.873816 -173.02734)
			(xy 353.840597 -173.026782) (xy 353.774726 -173.018127) (xy 353.710541 -173.000976) (xy 353.649132 -172.975621)
			(xy 353.62007 -172.959522) (xy 352.696018 -172.425868) (xy 352.667463 -172.408735) (xy 352.614637 -172.368191)
			(xy 352.567553 -172.321099) (xy 352.527018 -172.268266) (xy 352.493724 -172.210595) (xy 352.468241 -172.149072)
			(xy 352.451005 -172.08475) (xy 352.44231 -172.018728) (xy 352.441764 -171.985432) (xy 2.509012 -171.985432)
			(xy 2.509012 -173.661832) (xy 348.657164 -173.661832) (xy 348.657658 -173.628531) (xy 348.666337 -173.562499)
			(xy 348.683566 -173.498165) (xy 348.709048 -173.436632) (xy 348.742347 -173.378953) (xy 348.782893 -173.326117)
			(xy 348.829992 -173.279027) (xy 348.882836 -173.238492) (xy 348.911418 -173.221396) (xy 349.83547 -172.687742)
			(xy 349.864533 -172.671642) (xy 349.925937 -172.646271) (xy 349.990123 -172.629114) (xy 350.055996 -172.620463)
			(xy 350.089216 -172.619924) (xy 350.089724 -172.619924) (xy 350.120458 -172.620315) (xy 350.181477 -172.627727)
			(xy 350.241158 -172.64244) (xy 350.29863 -172.66424) (xy 350.353056 -172.692808) (xy 350.403641 -172.727729)
			(xy 350.449648 -172.768492) (xy 350.490406 -172.814503) (xy 350.525321 -172.865092) (xy 350.553883 -172.919521)
			(xy 350.575676 -172.976996) (xy 350.590383 -173.036678) (xy 350.597788 -173.097698) (xy 350.598232 -173.128432)
			(xy 350.597712 -173.161732) (xy 350.589036 -173.227763) (xy 350.571812 -173.292097) (xy 350.546334 -173.35363)
			(xy 350.513038 -173.411309) (xy 350.472496 -173.464145) (xy 350.4254 -173.511235) (xy 350.372559 -173.551772)
			(xy 350.343978 -173.568868) (xy 349.419926 -174.102522) (xy 349.390862 -174.11862) (xy 349.329459 -174.143992)
			(xy 349.265273 -174.16115) (xy 349.1994 -174.169802) (xy 349.16618 -174.17034) (xy 349.165672 -174.17034)
			(xy 349.134942 -174.16987) (xy 349.073929 -174.162459) (xy 349.014255 -174.147748) (xy 348.956789 -174.125953)
			(xy 348.902369 -174.097389) (xy 348.851788 -174.062475) (xy 348.805784 -174.021719) (xy 348.765027 -173.975715)
			(xy 348.730113 -173.925135) (xy 348.701549 -173.870715) (xy 348.679753 -173.813249) (xy 348.665041 -173.753575)
			(xy 348.65763 -173.692562) (xy 348.657164 -173.661832) (xy 2.509012 -173.661832) (xy 2.509012 -174.343568)
			(xy 373.398796 -174.343568) (xy 373.399226 -174.312836) (xy 373.406638 -174.251821) (xy 373.421351 -174.192144)
			(xy 373.443149 -174.134676) (xy 373.471715 -174.080254) (xy 373.506633 -174.029671) (xy 373.547392 -173.983667)
			(xy 373.5934 -173.94291) (xy 373.643984 -173.907996) (xy 373.698409 -173.879434) (xy 373.755879 -173.85764)
			(xy 373.815556 -173.842932) (xy 373.876572 -173.835524) (xy 373.907304 -173.83506) (xy 373.907812 -173.83506)
			(xy 373.941031 -173.835606) (xy 374.006903 -173.844264) (xy 374.071088 -173.861419) (xy 374.132496 -173.886778)
			(xy 374.161558 -173.902878) (xy 375.08561 -174.436532) (xy 375.114171 -174.453654) (xy 375.166997 -174.494201)
			(xy 375.214079 -174.541295) (xy 375.254613 -174.59413) (xy 375.287906 -174.651802) (xy 375.313388 -174.713326)
			(xy 375.330623 -174.777649) (xy 375.339318 -174.843672) (xy 375.339864 -174.876968) (xy 375.339432 -174.907701)
			(xy 375.332026 -174.96872) (xy 375.317319 -175.0284) (xy 375.295524 -175.085873) (xy 375.266961 -175.140299)
			(xy 375.232044 -175.190885) (xy 375.191284 -175.236893) (xy 375.145275 -175.277651) (xy 375.094689 -175.312567)
			(xy 375.040262 -175.341129) (xy 374.982789 -175.362923) (xy 374.923108 -175.377629) (xy 374.862089 -175.385033)
			(xy 374.831356 -175.385476) (xy 374.830848 -175.385476) (xy 374.797629 -175.384942) (xy 374.731757 -175.37628)
			(xy 374.667571 -175.359122) (xy 374.606164 -175.333759) (xy 374.577102 -175.317658) (xy 373.65305 -174.784004)
			(xy 373.624495 -174.766872) (xy 373.571672 -174.726325) (xy 373.524591 -174.679232) (xy 373.484057 -174.626398)
			(xy 373.450764 -174.568727) (xy 373.42528 -174.507205) (xy 373.408042 -174.442884) (xy 373.399344 -174.376863)
			(xy 373.398796 -174.343568) (xy 2.509012 -174.343568) (xy 2.509012 -175.83404) (xy 23.37714 -175.83404)
			(xy 23.381229 -175.778158) (xy 23.393412 -175.723468) (xy 23.413428 -175.671134) (xy 23.440851 -175.622272)
			(xy 23.475096 -175.577924) (xy 23.515432 -175.539034) (xy 23.561002 -175.506432) (xy 23.610833 -175.480813)
			(xy 23.663863 -175.462721) (xy 23.718961 -175.452544) (xy 23.774955 -175.450498) (xy 23.83065 -175.456626)
			(xy 23.884859 -175.470798) (xy 23.936427 -175.492712) (xy 23.984255 -175.521901) (xy 24.027323 -175.557742)
			(xy 24.064713 -175.599472) (xy 24.095629 -175.646202) (xy 24.119412 -175.696935) (xy 24.135554 -175.750591)
			(xy 24.143713 -175.806025) (xy 24.144224 -175.83404) (xy 24.143713 -175.862055) (xy 24.135554 -175.917489)
			(xy 24.119412 -175.971145) (xy 24.095629 -176.021878) (xy 24.064713 -176.068608) (xy 24.027323 -176.110338)
			(xy 23.984255 -176.146179) (xy 23.936427 -176.175368) (xy 23.884859 -176.197282) (xy 23.83065 -176.211454)
			(xy 23.774955 -176.217582) (xy 23.718961 -176.215536) (xy 23.663863 -176.205359) (xy 23.610833 -176.187267)
			(xy 23.561002 -176.161648) (xy 23.515432 -176.129046) (xy 23.475096 -176.090156) (xy 23.440851 -176.045808)
			(xy 23.413428 -175.996946) (xy 23.393412 -175.944612) (xy 23.381229 -175.889922) (xy 23.37714 -175.83404)
			(xy 2.509012 -175.83404) (xy 2.509012 -176.709832) (xy 348.657164 -176.709832) (xy 348.657658 -176.676531)
			(xy 348.666337 -176.610499) (xy 348.683566 -176.546165) (xy 348.709048 -176.484632) (xy 348.742347 -176.426953)
			(xy 348.782893 -176.374117) (xy 348.829992 -176.327027) (xy 348.882836 -176.286492) (xy 348.911418 -176.269396)
			(xy 349.83547 -175.735742) (xy 349.864533 -175.719642) (xy 349.925937 -175.694271) (xy 349.990123 -175.677114)
			(xy 350.055996 -175.668463) (xy 350.089216 -175.667924) (xy 350.089724 -175.667924) (xy 350.120458 -175.668315)
			(xy 350.121421 -175.668432) (xy 352.441764 -175.668432) (xy 352.442268 -175.637702) (xy 352.449672 -175.576689)
			(xy 352.464377 -175.517013) (xy 352.486168 -175.459545) (xy 352.514727 -175.405122) (xy 352.549637 -175.354539)
			(xy 352.59039 -175.308533) (xy 352.636392 -175.267774) (xy 352.686971 -175.232858) (xy 352.74139 -175.204292)
			(xy 352.798856 -175.182495) (xy 352.85853 -175.167783) (xy 352.919542 -175.160371) (xy 352.950272 -175.159924)
			(xy 352.95078 -175.159924) (xy 352.983998 -175.160489) (xy 353.049869 -175.169142) (xy 353.114055 -175.186291)
			(xy 353.175463 -175.211645) (xy 353.204526 -175.227742) (xy 354.128578 -175.761396) (xy 354.157139 -175.778518)
			(xy 354.209962 -175.819067) (xy 354.257042 -175.866162) (xy 354.297574 -175.918998) (xy 354.330866 -175.97667)
			(xy 354.3488 -176.019968) (xy 369.614196 -176.019968) (xy 369.614752 -175.98667) (xy 369.623426 -175.920641)
			(xy 369.640648 -175.85631) (xy 369.666122 -175.794779) (xy 369.699412 -175.737101) (xy 369.739949 -175.684263)
			(xy 369.787038 -175.637171) (xy 369.839873 -175.596631) (xy 369.86845 -175.579532) (xy 370.792502 -175.045878)
			(xy 370.82156 -175.029769) (xy 370.882966 -175.0044) (xy 370.947153 -174.987245) (xy 371.013028 -174.978597)
			(xy 371.046248 -174.97806) (xy 371.046756 -174.97806) (xy 371.077486 -174.978579) (xy 371.138498 -174.985982)
			(xy 371.198173 -175.000685) (xy 371.255641 -175.022475) (xy 371.310063 -175.051032) (xy 371.360647 -175.085941)
			(xy 371.406653 -175.126693) (xy 371.447412 -175.172694) (xy 371.482329 -175.223272) (xy 371.510894 -175.277689)
			(xy 371.532692 -175.335154) (xy 371.547404 -175.394827) (xy 371.554816 -175.455838) (xy 371.555264 -175.486568)
			(xy 371.554757 -175.519868) (xy 371.546077 -175.5859) (xy 371.543089 -175.597058) (xy 434.095902 -175.597058)
			(xy 434.099991 -175.541176) (xy 434.112174 -175.486486) (xy 434.13219 -175.434152) (xy 434.159613 -175.38529)
			(xy 434.193858 -175.340942) (xy 434.234194 -175.302052) (xy 434.279764 -175.26945) (xy 434.329595 -175.243831)
			(xy 434.382625 -175.225739) (xy 434.437723 -175.215562) (xy 434.493717 -175.213516) (xy 434.549412 -175.219644)
			(xy 434.603621 -175.233816) (xy 434.655189 -175.25573) (xy 434.703017 -175.284919) (xy 434.746085 -175.32076)
			(xy 434.783475 -175.36249) (xy 434.814391 -175.40922) (xy 434.838174 -175.459953) (xy 434.854316 -175.513609)
			(xy 434.862475 -175.569043) (xy 434.862986 -175.597058) (xy 434.862475 -175.625073) (xy 434.854316 -175.680507)
			(xy 434.838174 -175.734163) (xy 434.814391 -175.784896) (xy 434.783475 -175.831626) (xy 434.746085 -175.873356)
			(xy 434.703017 -175.909197) (xy 434.655189 -175.938386) (xy 434.603621 -175.9603) (xy 434.549412 -175.974472)
			(xy 434.493717 -175.9806) (xy 434.437723 -175.978554) (xy 434.382625 -175.968377) (xy 434.329595 -175.950285)
			(xy 434.279764 -175.924666) (xy 434.234194 -175.892064) (xy 434.193858 -175.853174) (xy 434.159613 -175.808826)
			(xy 434.13219 -175.759964) (xy 434.112174 -175.70763) (xy 434.099991 -175.65294) (xy 434.095902 -175.597058)
			(xy 371.543089 -175.597058) (xy 371.52885 -175.650232) (xy 371.503369 -175.711765) (xy 371.470072 -175.769443)
			(xy 371.429528 -175.82228) (xy 371.382432 -175.86937) (xy 371.329591 -175.909907) (xy 371.30101 -175.927004)
			(xy 370.376958 -176.460658) (xy 370.34791 -176.476786) (xy 370.2865 -176.50215) (xy 370.22231 -176.519299)
			(xy 370.156433 -176.527942) (xy 370.123212 -176.528476) (xy 370.122704 -176.528476) (xy 370.091971 -176.528059)
			(xy 370.030952 -176.52065) (xy 369.971272 -176.50594) (xy 369.9138 -176.484143) (xy 369.859375 -176.455577)
			(xy 369.808789 -176.420659) (xy 369.762782 -176.379898) (xy 369.722023 -176.333889) (xy 369.687108 -176.283301)
			(xy 369.658546 -176.228874) (xy 369.636752 -176.171401) (xy 369.622045 -176.11172) (xy 369.61464 -176.050701)
			(xy 369.614196 -176.019968) (xy 354.3488 -176.019968) (xy 354.356349 -176.038193) (xy 354.373586 -176.102515)
			(xy 354.382284 -176.168536) (xy 354.382832 -176.201832) (xy 354.382374 -176.232563) (xy 354.374962 -176.293576)
			(xy 354.360251 -176.353251) (xy 354.338454 -176.410717) (xy 354.30989 -176.465138) (xy 354.274975 -176.515719)
			(xy 354.234218 -176.561723) (xy 354.188213 -176.60248) (xy 354.137631 -176.637394) (xy 354.08321 -176.665957)
			(xy 354.025743 -176.687753) (xy 353.966068 -176.702464) (xy 353.905055 -176.709875) (xy 353.874324 -176.71034)
			(xy 353.873816 -176.71034) (xy 353.840597 -176.709782) (xy 353.774726 -176.701127) (xy 353.710541 -176.683976)
			(xy 353.649132 -176.658621) (xy 353.62007 -176.642522) (xy 352.696018 -176.108868) (xy 352.667463 -176.091735)
			(xy 352.614637 -176.051191) (xy 352.567553 -176.004099) (xy 352.527018 -175.951266) (xy 352.493724 -175.893595)
			(xy 352.468241 -175.832072) (xy 352.451005 -175.76775) (xy 352.44231 -175.701728) (xy 352.441764 -175.668432)
			(xy 350.121421 -175.668432) (xy 350.181477 -175.675727) (xy 350.241158 -175.69044) (xy 350.29863 -175.71224)
			(xy 350.353056 -175.740808) (xy 350.403641 -175.775729) (xy 350.449648 -175.816492) (xy 350.490406 -175.862503)
			(xy 350.525321 -175.913092) (xy 350.553883 -175.967521) (xy 350.575676 -176.024996) (xy 350.590383 -176.084678)
			(xy 350.597788 -176.145698) (xy 350.598232 -176.176432) (xy 350.597712 -176.209732) (xy 350.589036 -176.275763)
			(xy 350.571812 -176.340097) (xy 350.546334 -176.40163) (xy 350.513038 -176.459309) (xy 350.472496 -176.512145)
			(xy 350.4254 -176.559235) (xy 350.372559 -176.599772) (xy 350.343978 -176.616868) (xy 349.419926 -177.150522)
			(xy 349.390862 -177.16662) (xy 349.329459 -177.191992) (xy 349.265273 -177.20915) (xy 349.1994 -177.217802)
			(xy 349.16618 -177.21834) (xy 349.165672 -177.21834) (xy 349.134942 -177.21787) (xy 349.073929 -177.210459)
			(xy 349.014255 -177.195748) (xy 348.956789 -177.173953) (xy 348.902369 -177.145389) (xy 348.851788 -177.110475)
			(xy 348.805784 -177.069719) (xy 348.765027 -177.023715) (xy 348.730113 -176.973135) (xy 348.701549 -176.918715)
			(xy 348.679753 -176.861249) (xy 348.665041 -176.801575) (xy 348.65763 -176.740562) (xy 348.657164 -176.709832)
			(xy 2.509012 -176.709832) (xy 2.509012 -179.757832) (xy 348.657164 -179.757832) (xy 348.657658 -179.724531)
			(xy 348.666337 -179.658499) (xy 348.683566 -179.594165) (xy 348.709048 -179.532632) (xy 348.742347 -179.474953)
			(xy 348.782893 -179.422117) (xy 348.829992 -179.375027) (xy 348.882836 -179.334492) (xy 348.911418 -179.317396)
			(xy 349.83547 -178.783742) (xy 349.864533 -178.767642) (xy 349.925937 -178.742271) (xy 349.990123 -178.725114)
			(xy 350.055996 -178.716463) (xy 350.089216 -178.715924) (xy 350.089724 -178.715924) (xy 350.120458 -178.716315)
			(xy 350.181477 -178.723727) (xy 350.241158 -178.73844) (xy 350.29863 -178.76024) (xy 350.353056 -178.788808)
			(xy 350.403641 -178.823729) (xy 350.449648 -178.864492) (xy 350.490406 -178.910503) (xy 350.525321 -178.961092)
			(xy 350.553883 -179.015521) (xy 350.575676 -179.072996) (xy 350.590383 -179.132678) (xy 350.597788 -179.193698)
			(xy 350.598232 -179.224432) (xy 350.597712 -179.257732) (xy 350.589036 -179.323763) (xy 350.581628 -179.351432)
			(xy 352.441764 -179.351432) (xy 352.442268 -179.320702) (xy 352.449672 -179.259689) (xy 352.464377 -179.200013)
			(xy 352.486168 -179.142545) (xy 352.514727 -179.088122) (xy 352.549637 -179.037539) (xy 352.59039 -178.991533)
			(xy 352.636392 -178.950774) (xy 352.686971 -178.915858) (xy 352.74139 -178.887292) (xy 352.798856 -178.865495)
			(xy 352.85853 -178.850783) (xy 352.919542 -178.843371) (xy 352.950272 -178.842924) (xy 352.95078 -178.842924)
			(xy 352.983998 -178.843489) (xy 353.049869 -178.852142) (xy 353.114055 -178.869291) (xy 353.175463 -178.894645)
			(xy 353.204526 -178.910742) (xy 353.476772 -179.067968) (xy 369.614196 -179.067968) (xy 369.614752 -179.03467)
			(xy 369.623426 -178.968641) (xy 369.640648 -178.90431) (xy 369.666122 -178.842779) (xy 369.699412 -178.785101)
			(xy 369.739949 -178.732263) (xy 369.787038 -178.685171) (xy 369.839873 -178.644631) (xy 369.86845 -178.627532)
			(xy 370.792502 -178.093878) (xy 370.82156 -178.077769) (xy 370.882966 -178.0524) (xy 370.947153 -178.035245)
			(xy 371.013028 -178.026597) (xy 371.046248 -178.02606) (xy 371.046756 -178.02606) (xy 371.076835 -178.026568)
			(xy 373.398796 -178.026568) (xy 373.399226 -177.995836) (xy 373.406638 -177.934821) (xy 373.421351 -177.875144)
			(xy 373.443149 -177.817676) (xy 373.471715 -177.763254) (xy 373.506633 -177.712671) (xy 373.547392 -177.666667)
			(xy 373.5934 -177.62591) (xy 373.643984 -177.590996) (xy 373.698409 -177.562434) (xy 373.755879 -177.54064)
			(xy 373.815556 -177.525932) (xy 373.876572 -177.518524) (xy 373.907304 -177.51806) (xy 373.907812 -177.51806)
			(xy 373.941031 -177.518606) (xy 374.006903 -177.527264) (xy 374.071088 -177.544419) (xy 374.132496 -177.569778)
			(xy 374.161558 -177.585878) (xy 375.08561 -178.119532) (xy 375.114171 -178.136654) (xy 375.166997 -178.177201)
			(xy 375.214079 -178.224295) (xy 375.254613 -178.27713) (xy 375.287906 -178.334802) (xy 375.313388 -178.396326)
			(xy 375.330623 -178.460649) (xy 375.339318 -178.526672) (xy 375.339864 -178.559968) (xy 375.339432 -178.590701)
			(xy 375.332026 -178.65172) (xy 375.317319 -178.7114) (xy 375.295524 -178.768873) (xy 375.266961 -178.823299)
			(xy 375.232044 -178.873885) (xy 375.191284 -178.919893) (xy 375.145275 -178.960651) (xy 375.094689 -178.995567)
			(xy 375.040262 -179.024129) (xy 374.982789 -179.045923) (xy 374.923108 -179.060629) (xy 374.862089 -179.068033)
			(xy 374.831356 -179.068476) (xy 374.830848 -179.068476) (xy 374.797629 -179.067942) (xy 374.731757 -179.05928)
			(xy 374.667571 -179.042122) (xy 374.606164 -179.016759) (xy 374.577102 -179.000658) (xy 373.65305 -178.467004)
			(xy 373.624495 -178.449872) (xy 373.571672 -178.409325) (xy 373.524591 -178.362232) (xy 373.484057 -178.309398)
			(xy 373.450764 -178.251727) (xy 373.42528 -178.190205) (xy 373.408042 -178.125884) (xy 373.399344 -178.059863)
			(xy 373.398796 -178.026568) (xy 371.076835 -178.026568) (xy 371.077486 -178.026579) (xy 371.138498 -178.033982)
			(xy 371.198173 -178.048685) (xy 371.255641 -178.070475) (xy 371.310063 -178.099032) (xy 371.360647 -178.133941)
			(xy 371.406653 -178.174693) (xy 371.447412 -178.220694) (xy 371.482329 -178.271272) (xy 371.510894 -178.325689)
			(xy 371.532692 -178.383154) (xy 371.547404 -178.442827) (xy 371.554816 -178.503838) (xy 371.555264 -178.534568)
			(xy 371.554757 -178.567868) (xy 371.546077 -178.6339) (xy 371.52885 -178.698232) (xy 371.503369 -178.759765)
			(xy 371.470072 -178.817443) (xy 371.429528 -178.87028) (xy 371.382432 -178.91737) (xy 371.329591 -178.957907)
			(xy 371.30101 -178.975004) (xy 370.376958 -179.508658) (xy 370.34791 -179.524786) (xy 370.2865 -179.55015)
			(xy 370.22231 -179.567299) (xy 370.156433 -179.575942) (xy 370.123212 -179.576476) (xy 370.122704 -179.576476)
			(xy 370.091971 -179.576059) (xy 370.030952 -179.56865) (xy 369.971272 -179.55394) (xy 369.9138 -179.532143)
			(xy 369.859375 -179.503577) (xy 369.808789 -179.468659) (xy 369.762782 -179.427898) (xy 369.722023 -179.381889)
			(xy 369.687108 -179.331301) (xy 369.658546 -179.276874) (xy 369.636752 -179.219401) (xy 369.622045 -179.15972)
			(xy 369.61464 -179.098701) (xy 369.614196 -179.067968) (xy 353.476772 -179.067968) (xy 354.128578 -179.444396)
			(xy 354.157139 -179.461518) (xy 354.209962 -179.502067) (xy 354.257042 -179.549162) (xy 354.297574 -179.601998)
			(xy 354.330866 -179.65967) (xy 354.356349 -179.721193) (xy 354.373586 -179.785515) (xy 354.382284 -179.851536)
			(xy 354.382832 -179.884832) (xy 354.382374 -179.915563) (xy 354.374962 -179.976576) (xy 354.360251 -180.036251)
			(xy 354.338454 -180.093717) (xy 354.30989 -180.148138) (xy 354.274975 -180.198719) (xy 354.234218 -180.244723)
			(xy 354.188213 -180.28548) (xy 354.137631 -180.320394) (xy 354.08321 -180.348957) (xy 354.025743 -180.370753)
			(xy 353.966068 -180.385464) (xy 353.905055 -180.392875) (xy 353.874324 -180.39334) (xy 353.873816 -180.39334)
			(xy 353.840597 -180.392782) (xy 353.774726 -180.384127) (xy 353.710541 -180.366976) (xy 353.649132 -180.341621)
			(xy 353.62007 -180.325522) (xy 352.696018 -179.791868) (xy 352.667463 -179.774735) (xy 352.614637 -179.734191)
			(xy 352.567553 -179.687099) (xy 352.527018 -179.634266) (xy 352.493724 -179.576595) (xy 352.468241 -179.515072)
			(xy 352.451005 -179.45075) (xy 352.44231 -179.384728) (xy 352.441764 -179.351432) (xy 350.581628 -179.351432)
			(xy 350.571812 -179.388097) (xy 350.546334 -179.44963) (xy 350.513038 -179.507309) (xy 350.472496 -179.560145)
			(xy 350.4254 -179.607235) (xy 350.372559 -179.647772) (xy 350.343978 -179.664868) (xy 349.419926 -180.198522)
			(xy 349.390862 -180.21462) (xy 349.329459 -180.239992) (xy 349.265273 -180.25715) (xy 349.1994 -180.265802)
			(xy 349.16618 -180.26634) (xy 349.165672 -180.26634) (xy 349.134942 -180.26587) (xy 349.073929 -180.258459)
			(xy 349.014255 -180.243748) (xy 348.956789 -180.221953) (xy 348.902369 -180.193389) (xy 348.851788 -180.158475)
			(xy 348.805784 -180.117719) (xy 348.765027 -180.071715) (xy 348.730113 -180.021135) (xy 348.701549 -179.966715)
			(xy 348.679753 -179.909249) (xy 348.665041 -179.849575) (xy 348.65763 -179.788562) (xy 348.657164 -179.757832)
			(xy 2.509012 -179.757832) (xy 2.509012 -182.805832) (xy 348.657164 -182.805832) (xy 348.657658 -182.772531)
			(xy 348.666337 -182.706499) (xy 348.683566 -182.642165) (xy 348.709048 -182.580632) (xy 348.742347 -182.522953)
			(xy 348.782893 -182.470117) (xy 348.829992 -182.423027) (xy 348.882836 -182.382492) (xy 348.911418 -182.365396)
			(xy 349.83547 -181.831742) (xy 349.864533 -181.815642) (xy 349.925937 -181.790271) (xy 349.990123 -181.773114)
			(xy 350.055996 -181.764463) (xy 350.089216 -181.763924) (xy 350.089724 -181.763924) (xy 350.120458 -181.764315)
			(xy 350.181477 -181.771727) (xy 350.241158 -181.78644) (xy 350.29863 -181.80824) (xy 350.353056 -181.836808)
			(xy 350.403641 -181.871729) (xy 350.449648 -181.912492) (xy 350.490406 -181.958503) (xy 350.525321 -182.009092)
			(xy 350.553883 -182.063521) (xy 350.57377 -182.115968) (xy 369.614196 -182.115968) (xy 369.614752 -182.08267)
			(xy 369.623426 -182.016641) (xy 369.640648 -181.95231) (xy 369.666122 -181.890779) (xy 369.699412 -181.833101)
			(xy 369.739949 -181.780263) (xy 369.787038 -181.733171) (xy 369.839873 -181.692631) (xy 369.86845 -181.675532)
			(xy 370.792502 -181.141878) (xy 370.82156 -181.125769) (xy 370.882966 -181.1004) (xy 370.947153 -181.083245)
			(xy 371.013028 -181.074597) (xy 371.046248 -181.07406) (xy 371.046756 -181.07406) (xy 371.077486 -181.074579)
			(xy 371.138498 -181.081982) (xy 371.198173 -181.096685) (xy 371.255641 -181.118475) (xy 371.310063 -181.147032)
			(xy 371.360647 -181.181941) (xy 371.406653 -181.222693) (xy 371.447412 -181.268694) (xy 371.482329 -181.319272)
			(xy 371.510894 -181.373689) (xy 371.532692 -181.431154) (xy 371.547404 -181.490827) (xy 371.554816 -181.551838)
			(xy 371.555264 -181.582568) (xy 371.554757 -181.615868) (xy 371.546077 -181.6819) (xy 371.538668 -181.709568)
			(xy 373.398796 -181.709568) (xy 373.399226 -181.678836) (xy 373.406638 -181.617821) (xy 373.421351 -181.558144)
			(xy 373.443149 -181.500676) (xy 373.471715 -181.446254) (xy 373.506633 -181.395671) (xy 373.547392 -181.349667)
			(xy 373.5934 -181.30891) (xy 373.643984 -181.273996) (xy 373.698409 -181.245434) (xy 373.755879 -181.22364)
			(xy 373.815556 -181.208932) (xy 373.876572 -181.201524) (xy 373.907304 -181.20106) (xy 373.907812 -181.20106)
			(xy 373.941031 -181.201606) (xy 374.006903 -181.210264) (xy 374.071088 -181.227419) (xy 374.132496 -181.252778)
			(xy 374.161558 -181.268878) (xy 375.08561 -181.802532) (xy 375.114171 -181.819654) (xy 375.166997 -181.860201)
			(xy 375.214079 -181.907295) (xy 375.254613 -181.96013) (xy 375.287906 -182.017802) (xy 375.313388 -182.079326)
			(xy 375.330623 -182.143649) (xy 375.339318 -182.209672) (xy 375.339864 -182.242968) (xy 375.339432 -182.273701)
			(xy 375.332026 -182.33472) (xy 375.317319 -182.3944) (xy 375.295524 -182.451873) (xy 375.266961 -182.506299)
			(xy 375.232044 -182.556885) (xy 375.191284 -182.602893) (xy 375.145275 -182.643651) (xy 375.094689 -182.678567)
			(xy 375.040262 -182.707129) (xy 374.982789 -182.728923) (xy 374.923108 -182.743629) (xy 374.862089 -182.751033)
			(xy 374.831356 -182.751476) (xy 374.830848 -182.751476) (xy 374.797629 -182.750942) (xy 374.731757 -182.74228)
			(xy 374.667571 -182.725122) (xy 374.606164 -182.699759) (xy 374.577102 -182.683658) (xy 373.65305 -182.150004)
			(xy 373.624495 -182.132872) (xy 373.571672 -182.092325) (xy 373.524591 -182.045232) (xy 373.484057 -181.992398)
			(xy 373.450764 -181.934727) (xy 373.42528 -181.873205) (xy 373.408042 -181.808884) (xy 373.399344 -181.742863)
			(xy 373.398796 -181.709568) (xy 371.538668 -181.709568) (xy 371.52885 -181.746232) (xy 371.503369 -181.807765)
			(xy 371.470072 -181.865443) (xy 371.429528 -181.91828) (xy 371.382432 -181.96537) (xy 371.329591 -182.005907)
			(xy 371.30101 -182.023004) (xy 370.376958 -182.556658) (xy 370.34791 -182.572786) (xy 370.2865 -182.59815)
			(xy 370.22231 -182.615299) (xy 370.156433 -182.623942) (xy 370.123212 -182.624476) (xy 370.122704 -182.624476)
			(xy 370.091971 -182.624059) (xy 370.030952 -182.61665) (xy 369.971272 -182.60194) (xy 369.9138 -182.580143)
			(xy 369.859375 -182.551577) (xy 369.808789 -182.516659) (xy 369.762782 -182.475898) (xy 369.722023 -182.429889)
			(xy 369.687108 -182.379301) (xy 369.658546 -182.324874) (xy 369.636752 -182.267401) (xy 369.622045 -182.20772)
			(xy 369.61464 -182.146701) (xy 369.614196 -182.115968) (xy 350.57377 -182.115968) (xy 350.575676 -182.120996)
			(xy 350.590383 -182.180678) (xy 350.597788 -182.241698) (xy 350.598232 -182.272432) (xy 350.597712 -182.305732)
			(xy 350.589036 -182.371763) (xy 350.571812 -182.436097) (xy 350.546334 -182.49763) (xy 350.513038 -182.555309)
			(xy 350.472496 -182.608145) (xy 350.4254 -182.655235) (xy 350.372559 -182.695772) (xy 350.343978 -182.712868)
			(xy 349.775297 -183.04129) (xy 352.441764 -183.04129) (xy 352.442192 -183.010552) (xy 352.449601 -182.949525)
			(xy 352.46431 -182.889835) (xy 352.486105 -182.832352) (xy 352.514667 -182.777914) (xy 352.549581 -182.727315)
			(xy 352.590338 -182.681292) (xy 352.636344 -182.640516) (xy 352.686928 -182.60558) (xy 352.741353 -182.576994)
			(xy 352.798826 -182.555175) (xy 352.85851 -182.540441) (xy 352.919534 -182.533005) (xy 352.950272 -182.532528)
			(xy 352.95078 -182.532528) (xy 352.984007 -182.533118) (xy 353.049889 -182.541823) (xy 353.114077 -182.559036)
			(xy 353.175475 -182.584464) (xy 353.204526 -182.6006) (xy 354.128578 -183.134254) (xy 354.157165 -183.151335)
			(xy 354.209988 -183.19189) (xy 354.257067 -183.238991) (xy 354.297597 -183.291832) (xy 354.330886 -183.34951)
			(xy 354.356365 -183.411039) (xy 354.373597 -183.475367) (xy 354.382288 -183.541392) (xy 354.382832 -183.57469)
			(xy 354.382389 -183.605428) (xy 354.374982 -183.666455) (xy 354.360275 -183.726145) (xy 354.338483 -183.783627)
			(xy 354.309922 -183.838065) (xy 354.275009 -183.888665) (xy 354.234254 -183.934688) (xy 354.188249 -183.975465)
			(xy 354.137666 -184.010401) (xy 354.083241 -184.038987) (xy 354.025768 -184.060806) (xy 353.966085 -184.07554)
			(xy 353.905061 -184.082975) (xy 353.874324 -184.083452) (xy 353.873816 -184.083452) (xy 353.840589 -184.082867)
			(xy 353.774706 -184.07416) (xy 353.710519 -184.056946) (xy 353.649121 -184.031517) (xy 353.62007 -184.01538)
			(xy 352.696018 -183.481726) (xy 352.667489 -183.464552) (xy 352.614663 -183.424014) (xy 352.567578 -183.376928)
			(xy 352.527041 -183.324101) (xy 352.493744 -183.266436) (xy 352.468257 -183.204918) (xy 352.451015 -183.140601)
			(xy 352.442314 -183.074584) (xy 352.441764 -183.04129) (xy 349.775297 -183.04129) (xy 349.419926 -183.246522)
			(xy 349.390862 -183.26262) (xy 349.329459 -183.287992) (xy 349.265273 -183.30515) (xy 349.1994 -183.313802)
			(xy 349.16618 -183.31434) (xy 349.165672 -183.31434) (xy 349.134942 -183.31387) (xy 349.073929 -183.306459)
			(xy 349.014255 -183.291748) (xy 348.956789 -183.269953) (xy 348.902369 -183.241389) (xy 348.851788 -183.206475)
			(xy 348.805784 -183.165719) (xy 348.765027 -183.119715) (xy 348.730113 -183.069135) (xy 348.701549 -183.014715)
			(xy 348.679753 -182.957249) (xy 348.665041 -182.897575) (xy 348.65763 -182.836562) (xy 348.657164 -182.805832)
			(xy 2.509012 -182.805832) (xy 2.509012 -185.011568) (xy 372.585996 -185.011568) (xy 372.586426 -184.980836)
			(xy 372.593838 -184.919821) (xy 372.608551 -184.860144) (xy 372.630349 -184.802676) (xy 372.658915 -184.748254)
			(xy 372.693833 -184.697671) (xy 372.734592 -184.651667) (xy 372.7806 -184.61091) (xy 372.831184 -184.575996)
			(xy 372.885609 -184.547434) (xy 372.943079 -184.52564) (xy 373.002756 -184.510932) (xy 373.063772 -184.503524)
			(xy 373.094504 -184.50306) (xy 373.095012 -184.50306) (xy 373.128231 -184.503606) (xy 373.194103 -184.512264)
			(xy 373.258288 -184.529419) (xy 373.319696 -184.554778) (xy 373.348758 -184.570878) (xy 374.27281 -185.104532)
			(xy 374.301371 -185.121654) (xy 374.354197 -185.162201) (xy 374.401279 -185.209295) (xy 374.441813 -185.26213)
			(xy 374.475106 -185.319802) (xy 374.500588 -185.381326) (xy 374.517823 -185.445649) (xy 374.526518 -185.511672)
			(xy 374.527064 -185.544968) (xy 374.526632 -185.575701) (xy 374.519226 -185.63672) (xy 374.504519 -185.6964)
			(xy 374.482724 -185.753873) (xy 374.454161 -185.808299) (xy 374.419244 -185.858885) (xy 374.378484 -185.904893)
			(xy 374.332475 -185.945651) (xy 374.281889 -185.980567) (xy 374.227462 -186.009129) (xy 374.169989 -186.030923)
			(xy 374.110308 -186.045629) (xy 374.049289 -186.053033) (xy 374.018556 -186.053476) (xy 374.018048 -186.053476)
			(xy 373.984829 -186.052942) (xy 373.918957 -186.04428) (xy 373.854771 -186.027122) (xy 373.793364 -186.001759)
			(xy 373.764302 -185.985658) (xy 372.84025 -185.452004) (xy 372.811695 -185.434872) (xy 372.758872 -185.394325)
			(xy 372.711791 -185.347232) (xy 372.671257 -185.294398) (xy 372.637964 -185.236727) (xy 372.61248 -185.175205)
			(xy 372.595242 -185.110884) (xy 372.586544 -185.044863) (xy 372.585996 -185.011568) (xy 2.509012 -185.011568)
			(xy 2.509012 -186.714892) (xy 351.367344 -186.714892) (xy 351.367848 -186.684163) (xy 351.375257 -186.623152)
			(xy 351.389965 -186.563479) (xy 351.411758 -186.506014) (xy 351.440318 -186.451595) (xy 351.475229 -186.401014)
			(xy 351.515982 -186.355011) (xy 351.561983 -186.314254) (xy 351.612561 -186.279339) (xy 351.666978 -186.250774)
			(xy 351.724441 -186.228977) (xy 351.784113 -186.214264) (xy 351.845123 -186.206851) (xy 351.875852 -186.206384)
			(xy 351.87636 -186.206384) (xy 351.90958 -186.206906) (xy 351.975453 -186.215571) (xy 352.039638 -186.232732)
			(xy 352.101045 -186.258098) (xy 352.130106 -186.274202) (xy 353.054158 -186.807856) (xy 353.082741 -186.824943)
			(xy 353.135565 -186.865496) (xy 353.182645 -186.912596) (xy 353.223176 -186.965436) (xy 353.256466 -187.023114)
			(xy 353.281945 -187.084642) (xy 353.299177 -187.148969) (xy 353.307868 -187.214995) (xy 353.308412 -187.248292)
			(xy 353.307955 -187.279024) (xy 353.300547 -187.340039) (xy 353.285839 -187.399717) (xy 353.264044 -187.457187)
			(xy 353.235482 -187.51161) (xy 353.200567 -187.562194) (xy 353.15981 -187.608201) (xy 353.113804 -187.648959)
			(xy 353.063221 -187.683875) (xy 353.008798 -187.712439) (xy 352.951329 -187.734235) (xy 352.891651 -187.748945)
			(xy 352.830636 -187.756354) (xy 352.799904 -187.7568) (xy 352.799396 -187.7568) (xy 352.766177 -187.756256)
			(xy 352.700305 -187.747598) (xy 352.636119 -187.730443) (xy 352.574711 -187.705083) (xy 352.54565 -187.688982)
			(xy 351.621598 -187.155328) (xy 351.593065 -187.13816) (xy 351.54024 -187.09762) (xy 351.493156 -187.050533)
			(xy 351.45262 -186.997705) (xy 351.419323 -186.940039) (xy 351.393837 -186.878521) (xy 351.376595 -186.814204)
			(xy 351.367894 -186.748186) (xy 351.367344 -186.714892) (xy 2.509012 -186.714892) (xy 2.509012 -206.024988)
			(xy 86.700624 -206.024988) (xy 86.704605 -205.891968) (xy 86.716534 -205.759423) (xy 86.736369 -205.62783)
			(xy 86.764038 -205.497658) (xy 86.799442 -205.369373) (xy 86.842455 -205.243436) (xy 86.892922 -205.120297)
			(xy 86.950663 -205.000396) (xy 87.015472 -204.884163) (xy 87.087116 -204.772013) (xy 87.165338 -204.664349)
			(xy 87.249859 -204.561556) (xy 87.340377 -204.464001) (xy 87.436566 -204.372035) (xy 87.538084 -204.285985)
			(xy 87.644565 -204.206161) (xy 87.75563 -204.132848) (xy 87.870881 -204.066308) (xy 87.989905 -204.006779)
			(xy 88.112276 -203.954475) (xy 88.237555 -203.909583) (xy 88.365296 -203.872264) (xy 88.495039 -203.842651)
			(xy 88.626321 -203.82085) (xy 88.758672 -203.80694) (xy 88.891618 -203.800969) (xy 89.024683 -203.80296)
			(xy 89.157391 -203.812905) (xy 89.289267 -203.830769) (xy 89.419838 -203.856487) (xy 89.548638 -203.889968)
			(xy 89.675204 -203.931092) (xy 89.799085 -203.979712) (xy 89.919836 -204.035653) (xy 90.037026 -204.098715)
			(xy 90.150235 -204.168673) (xy 90.259057 -204.245277) (xy 90.363103 -204.328251) (xy 90.462001 -204.417299)
			(xy 90.555396 -204.512102) (xy 90.642954 -204.61232) (xy 90.724363 -204.717596) (xy 90.799329 -204.827552)
			(xy 90.867586 -204.941794) (xy 90.928888 -205.059914) (xy 90.983017 -205.181489) (xy 91.029778 -205.306083)
			(xy 91.069004 -205.433251) (xy 91.100554 -205.562537) (xy 91.124317 -205.693478) (xy 91.140206 -205.825606)
			(xy 91.148164 -205.958448) (xy 91.148662 -206.024988) (xy 132.710692 -206.024988) (xy 132.714673 -205.891968)
			(xy 132.726602 -205.759423) (xy 132.746437 -205.62783) (xy 132.774106 -205.497658) (xy 132.80951 -205.369373)
			(xy 132.852523 -205.243436) (xy 132.90299 -205.120297) (xy 132.960731 -205.000396) (xy 133.02554 -204.884163)
			(xy 133.097184 -204.772013) (xy 133.175406 -204.664349) (xy 133.259927 -204.561556) (xy 133.350445 -204.464001)
			(xy 133.446634 -204.372035) (xy 133.548152 -204.285985) (xy 133.654633 -204.206161) (xy 133.765698 -204.132848)
			(xy 133.880949 -204.066308) (xy 133.999973 -204.006779) (xy 134.122344 -203.954475) (xy 134.247623 -203.909583)
			(xy 134.375364 -203.872264) (xy 134.505107 -203.842651) (xy 134.636389 -203.82085) (xy 134.76874 -203.80694)
			(xy 134.901686 -203.800969) (xy 135.034751 -203.80296) (xy 135.167459 -203.812905) (xy 135.299335 -203.830769)
			(xy 135.429906 -203.856487) (xy 135.558706 -203.889968) (xy 135.685272 -203.931092) (xy 135.809153 -203.979712)
			(xy 135.929904 -204.035653) (xy 136.047094 -204.098715) (xy 136.160303 -204.168673) (xy 136.269125 -204.245277)
			(xy 136.373171 -204.328251) (xy 136.472069 -204.417299) (xy 136.565464 -204.512102) (xy 136.653022 -204.61232)
			(xy 136.734431 -204.717596) (xy 136.809397 -204.827552) (xy 136.877654 -204.941794) (xy 136.938956 -205.059914)
			(xy 136.993085 -205.181489) (xy 137.039846 -205.306083) (xy 137.079072 -205.433251) (xy 137.110622 -205.562537)
			(xy 137.134385 -205.693478) (xy 137.150274 -205.825606) (xy 137.158232 -205.958448) (xy 137.15873 -206.024988)
			(xy 334.640692 -206.024988) (xy 334.644673 -205.891968) (xy 334.656602 -205.759423) (xy 334.676437 -205.62783)
			(xy 334.704106 -205.497658) (xy 334.73951 -205.369373) (xy 334.782523 -205.243436) (xy 334.83299 -205.120297)
			(xy 334.890731 -205.000396) (xy 334.95554 -204.884163) (xy 335.027184 -204.772013) (xy 335.105406 -204.664349)
			(xy 335.189927 -204.561556) (xy 335.280445 -204.464001) (xy 335.376634 -204.372035) (xy 335.478152 -204.285985)
			(xy 335.584633 -204.206161) (xy 335.695698 -204.132848) (xy 335.810949 -204.066308) (xy 335.929973 -204.006779)
			(xy 336.052344 -203.954475) (xy 336.177623 -203.909583) (xy 336.305364 -203.872264) (xy 336.435107 -203.842651)
			(xy 336.566389 -203.82085) (xy 336.69874 -203.80694) (xy 336.831686 -203.800969) (xy 336.964751 -203.80296)
			(xy 337.097459 -203.812905) (xy 337.229335 -203.830769) (xy 337.359906 -203.856487) (xy 337.488706 -203.889968)
			(xy 337.615272 -203.931092) (xy 337.739153 -203.979712) (xy 337.859904 -204.035653) (xy 337.977094 -204.098715)
			(xy 338.090303 -204.168673) (xy 338.199125 -204.245277) (xy 338.303171 -204.328251) (xy 338.402069 -204.417299)
			(xy 338.495464 -204.512102) (xy 338.583022 -204.61232) (xy 338.664431 -204.717596) (xy 338.739397 -204.827552)
			(xy 338.807654 -204.941794) (xy 338.868956 -205.059914) (xy 338.923085 -205.181489) (xy 338.969846 -205.306083)
			(xy 339.009072 -205.433251) (xy 339.040622 -205.562537) (xy 339.064385 -205.693478) (xy 339.080274 -205.825606)
			(xy 339.088232 -205.958448) (xy 339.08873 -206.024988) (xy 380.650506 -206.024988) (xy 380.654487 -205.891968)
			(xy 380.666416 -205.759423) (xy 380.686251 -205.62783) (xy 380.71392 -205.497658) (xy 380.749324 -205.369373)
			(xy 380.792337 -205.243436) (xy 380.842804 -205.120297) (xy 380.900545 -205.000396) (xy 380.965354 -204.884163)
			(xy 381.036998 -204.772013) (xy 381.11522 -204.664349) (xy 381.199741 -204.561556) (xy 381.290259 -204.464001)
			(xy 381.386448 -204.372035) (xy 381.487966 -204.285985) (xy 381.594447 -204.206161) (xy 381.705512 -204.132848)
			(xy 381.820763 -204.066308) (xy 381.939787 -204.006779) (xy 382.062158 -203.954475) (xy 382.187437 -203.909583)
			(xy 382.315178 -203.872264) (xy 382.444921 -203.842651) (xy 382.576203 -203.82085) (xy 382.708554 -203.80694)
			(xy 382.8415 -203.800969) (xy 382.974565 -203.80296) (xy 383.107273 -203.812905) (xy 383.239149 -203.830769)
			(xy 383.36972 -203.856487) (xy 383.49852 -203.889968) (xy 383.625086 -203.931092) (xy 383.748967 -203.979712)
			(xy 383.869718 -204.035653) (xy 383.986908 -204.098715) (xy 384.100117 -204.168673) (xy 384.208939 -204.245277)
			(xy 384.312985 -204.328251) (xy 384.411883 -204.417299) (xy 384.505278 -204.512102) (xy 384.592836 -204.61232)
			(xy 384.674245 -204.717596) (xy 384.749211 -204.827552) (xy 384.817468 -204.941794) (xy 384.87877 -205.059914)
			(xy 384.932899 -205.181489) (xy 384.97966 -205.306083) (xy 385.018886 -205.433251) (xy 385.050436 -205.562537)
			(xy 385.074199 -205.693478) (xy 385.090088 -205.825606) (xy 385.098046 -205.958448) (xy 385.098544 -206.024988)
			(xy 385.098046 -206.091528) (xy 385.090088 -206.22437) (xy 385.074199 -206.356498) (xy 385.050436 -206.487439)
			(xy 385.018886 -206.616725) (xy 384.97966 -206.743893) (xy 384.932899 -206.868487) (xy 384.87877 -206.990062)
			(xy 384.817468 -207.108182) (xy 384.749211 -207.222424) (xy 384.674245 -207.33238) (xy 384.592836 -207.437656)
			(xy 384.505278 -207.537874) (xy 384.411883 -207.632677) (xy 384.312985 -207.721725) (xy 384.208939 -207.804699)
			(xy 384.100117 -207.881303) (xy 383.986908 -207.951261) (xy 383.869718 -208.014323) (xy 383.748967 -208.070264)
			(xy 383.625086 -208.118884) (xy 383.49852 -208.160008) (xy 383.36972 -208.193489) (xy 383.239149 -208.219207)
			(xy 383.107273 -208.237071) (xy 382.974565 -208.247016) (xy 382.8415 -208.249007) (xy 382.708554 -208.243036)
			(xy 382.576203 -208.229126) (xy 382.444921 -208.207325) (xy 382.315178 -208.177712) (xy 382.187437 -208.140393)
			(xy 382.062158 -208.095501) (xy 381.939787 -208.043197) (xy 381.820763 -207.983668) (xy 381.705512 -207.917128)
			(xy 381.594447 -207.843815) (xy 381.487966 -207.763991) (xy 381.386448 -207.677941) (xy 381.290259 -207.585975)
			(xy 381.199741 -207.48842) (xy 381.11522 -207.385627) (xy 381.036998 -207.277963) (xy 380.965354 -207.165813)
			(xy 380.900545 -207.04958) (xy 380.842804 -206.929679) (xy 380.792337 -206.80654) (xy 380.749324 -206.680603)
			(xy 380.71392 -206.552318) (xy 380.686251 -206.422146) (xy 380.666416 -206.290553) (xy 380.654487 -206.158008)
			(xy 380.650506 -206.024988) (xy 339.08873 -206.024988) (xy 339.088232 -206.091528) (xy 339.080274 -206.22437)
			(xy 339.064385 -206.356498) (xy 339.040622 -206.487439) (xy 339.009072 -206.616725) (xy 338.969846 -206.743893)
			(xy 338.923085 -206.868487) (xy 338.868956 -206.990062) (xy 338.807654 -207.108182) (xy 338.739397 -207.222424)
			(xy 338.664431 -207.33238) (xy 338.583022 -207.437656) (xy 338.495464 -207.537874) (xy 338.402069 -207.632677)
			(xy 338.303171 -207.721725) (xy 338.199125 -207.804699) (xy 338.090303 -207.881303) (xy 337.977094 -207.951261)
			(xy 337.859904 -208.014323) (xy 337.739153 -208.070264) (xy 337.615272 -208.118884) (xy 337.488706 -208.160008)
			(xy 337.359906 -208.193489) (xy 337.229335 -208.219207) (xy 337.097459 -208.237071) (xy 336.964751 -208.247016)
			(xy 336.831686 -208.249007) (xy 336.69874 -208.243036) (xy 336.566389 -208.229126) (xy 336.435107 -208.207325)
			(xy 336.305364 -208.177712) (xy 336.177623 -208.140393) (xy 336.052344 -208.095501) (xy 335.929973 -208.043197)
			(xy 335.810949 -207.983668) (xy 335.695698 -207.917128) (xy 335.584633 -207.843815) (xy 335.478152 -207.763991)
			(xy 335.376634 -207.677941) (xy 335.280445 -207.585975) (xy 335.189927 -207.48842) (xy 335.105406 -207.385627)
			(xy 335.027184 -207.277963) (xy 334.95554 -207.165813) (xy 334.890731 -207.04958) (xy 334.83299 -206.929679)
			(xy 334.782523 -206.80654) (xy 334.73951 -206.680603) (xy 334.704106 -206.552318) (xy 334.676437 -206.422146)
			(xy 334.656602 -206.290553) (xy 334.644673 -206.158008) (xy 334.640692 -206.024988) (xy 137.15873 -206.024988)
			(xy 137.158232 -206.091528) (xy 137.150274 -206.22437) (xy 137.134385 -206.356498) (xy 137.110622 -206.487439)
			(xy 137.079072 -206.616725) (xy 137.039846 -206.743893) (xy 136.993085 -206.868487) (xy 136.938956 -206.990062)
			(xy 136.877654 -207.108182) (xy 136.809397 -207.222424) (xy 136.734431 -207.33238) (xy 136.653022 -207.437656)
			(xy 136.565464 -207.537874) (xy 136.472069 -207.632677) (xy 136.373171 -207.721725) (xy 136.269125 -207.804699)
			(xy 136.160303 -207.881303) (xy 136.047094 -207.951261) (xy 135.929904 -208.014323) (xy 135.809153 -208.070264)
			(xy 135.685272 -208.118884) (xy 135.558706 -208.160008) (xy 135.429906 -208.193489) (xy 135.299335 -208.219207)
			(xy 135.167459 -208.237071) (xy 135.034751 -208.247016) (xy 134.901686 -208.249007) (xy 134.76874 -208.243036)
			(xy 134.636389 -208.229126) (xy 134.505107 -208.207325) (xy 134.375364 -208.177712) (xy 134.247623 -208.140393)
			(xy 134.122344 -208.095501) (xy 133.999973 -208.043197) (xy 133.880949 -207.983668) (xy 133.765698 -207.917128)
			(xy 133.654633 -207.843815) (xy 133.548152 -207.763991) (xy 133.446634 -207.677941) (xy 133.350445 -207.585975)
			(xy 133.259927 -207.48842) (xy 133.175406 -207.385627) (xy 133.097184 -207.277963) (xy 133.02554 -207.165813)
			(xy 132.960731 -207.04958) (xy 132.90299 -206.929679) (xy 132.852523 -206.80654) (xy 132.80951 -206.680603)
			(xy 132.774106 -206.552318) (xy 132.746437 -206.422146) (xy 132.726602 -206.290553) (xy 132.714673 -206.158008)
			(xy 132.710692 -206.024988) (xy 91.148662 -206.024988) (xy 91.148164 -206.091528) (xy 91.140206 -206.22437)
			(xy 91.124317 -206.356498) (xy 91.100554 -206.487439) (xy 91.069004 -206.616725) (xy 91.029778 -206.743893)
			(xy 90.983017 -206.868487) (xy 90.928888 -206.990062) (xy 90.867586 -207.108182) (xy 90.799329 -207.222424)
			(xy 90.724363 -207.33238) (xy 90.642954 -207.437656) (xy 90.555396 -207.537874) (xy 90.462001 -207.632677)
			(xy 90.363103 -207.721725) (xy 90.259057 -207.804699) (xy 90.150235 -207.881303) (xy 90.037026 -207.951261)
			(xy 89.919836 -208.014323) (xy 89.799085 -208.070264) (xy 89.675204 -208.118884) (xy 89.548638 -208.160008)
			(xy 89.419838 -208.193489) (xy 89.289267 -208.219207) (xy 89.157391 -208.237071) (xy 89.024683 -208.247016)
			(xy 88.891618 -208.249007) (xy 88.758672 -208.243036) (xy 88.626321 -208.229126) (xy 88.495039 -208.207325)
			(xy 88.365296 -208.177712) (xy 88.237555 -208.140393) (xy 88.112276 -208.095501) (xy 87.989905 -208.043197)
			(xy 87.870881 -207.983668) (xy 87.75563 -207.917128) (xy 87.644565 -207.843815) (xy 87.538084 -207.763991)
			(xy 87.436566 -207.677941) (xy 87.340377 -207.585975) (xy 87.249859 -207.48842) (xy 87.165338 -207.385627)
			(xy 87.087116 -207.277963) (xy 87.015472 -207.165813) (xy 86.950663 -207.04958) (xy 86.892922 -206.929679)
			(xy 86.842455 -206.80654) (xy 86.799442 -206.680603) (xy 86.764038 -206.552318) (xy 86.736369 -206.422146)
			(xy 86.716534 -206.290553) (xy 86.704605 -206.158008) (xy 86.700624 -206.024988) (xy 2.509012 -206.024988)
			(xy 2.509012 -213.732618) (xy 90.165428 -213.732618) (xy 90.165936 -213.706731) (xy 90.174035 -213.655593)
			(xy 90.190034 -213.606353) (xy 90.21354 -213.560221) (xy 90.243972 -213.518334) (xy 90.280582 -213.481724)
			(xy 90.322469 -213.451292) (xy 90.368601 -213.427786) (xy 90.417841 -213.411787) (xy 90.468979 -213.403688)
			(xy 90.520753 -213.403688) (xy 90.571891 -213.411787) (xy 90.621131 -213.427786) (xy 90.667263 -213.451292)
			(xy 90.70915 -213.481724) (xy 90.74576 -213.518334) (xy 90.776192 -213.560221) (xy 90.799698 -213.606353)
			(xy 90.815697 -213.655593) (xy 90.823796 -213.706731) (xy 90.824304 -213.732618) (xy 92.045028 -213.732618)
			(xy 92.045536 -213.706731) (xy 92.053635 -213.655593) (xy 92.069634 -213.606353) (xy 92.09314 -213.560221)
			(xy 92.123572 -213.518334) (xy 92.160182 -213.481724) (xy 92.202069 -213.451292) (xy 92.248201 -213.427786)
			(xy 92.297441 -213.411787) (xy 92.348579 -213.403688) (xy 92.400353 -213.403688) (xy 92.451491 -213.411787)
			(xy 92.500731 -213.427786) (xy 92.546863 -213.451292) (xy 92.58875 -213.481724) (xy 92.62536 -213.518334)
			(xy 92.655792 -213.560221) (xy 92.679298 -213.606353) (xy 92.695297 -213.655593) (xy 92.703396 -213.706731)
			(xy 92.703904 -213.732618) (xy 93.924628 -213.732618) (xy 93.925136 -213.706731) (xy 93.933235 -213.655593)
			(xy 93.949234 -213.606353) (xy 93.97274 -213.560221) (xy 94.003172 -213.518334) (xy 94.039782 -213.481724)
			(xy 94.081669 -213.451292) (xy 94.127801 -213.427786) (xy 94.177041 -213.411787) (xy 94.228179 -213.403688)
			(xy 94.279953 -213.403688) (xy 94.331091 -213.411787) (xy 94.380331 -213.427786) (xy 94.426463 -213.451292)
			(xy 94.46835 -213.481724) (xy 94.50496 -213.518334) (xy 94.535392 -213.560221) (xy 94.558898 -213.606353)
			(xy 94.574897 -213.655593) (xy 94.582996 -213.706731) (xy 94.583504 -213.732618) (xy 95.804228 -213.732618)
			(xy 95.804736 -213.706731) (xy 95.812835 -213.655593) (xy 95.828834 -213.606353) (xy 95.85234 -213.560221)
			(xy 95.882772 -213.518334) (xy 95.919382 -213.481724) (xy 95.961269 -213.451292) (xy 96.007401 -213.427786)
			(xy 96.056641 -213.411787) (xy 96.107779 -213.403688) (xy 96.159553 -213.403688) (xy 96.210691 -213.411787)
			(xy 96.259931 -213.427786) (xy 96.306063 -213.451292) (xy 96.34795 -213.481724) (xy 96.38456 -213.518334)
			(xy 96.414992 -213.560221) (xy 96.438498 -213.606353) (xy 96.454497 -213.655593) (xy 96.462596 -213.706731)
			(xy 96.463104 -213.732618) (xy 97.683828 -213.732618) (xy 97.684336 -213.706731) (xy 97.692435 -213.655593)
			(xy 97.708434 -213.606353) (xy 97.73194 -213.560221) (xy 97.762372 -213.518334) (xy 97.798982 -213.481724)
			(xy 97.840869 -213.451292) (xy 97.887001 -213.427786) (xy 97.936241 -213.411787) (xy 97.987379 -213.403688)
			(xy 98.039153 -213.403688) (xy 98.090291 -213.411787) (xy 98.139531 -213.427786) (xy 98.185663 -213.451292)
			(xy 98.22755 -213.481724) (xy 98.26416 -213.518334) (xy 98.294592 -213.560221) (xy 98.318098 -213.606353)
			(xy 98.334097 -213.655593) (xy 98.342196 -213.706731) (xy 98.342704 -213.732618) (xy 99.563428 -213.732618)
			(xy 99.563936 -213.706731) (xy 99.572035 -213.655593) (xy 99.588034 -213.606353) (xy 99.61154 -213.560221)
			(xy 99.641972 -213.518334) (xy 99.678582 -213.481724) (xy 99.720469 -213.451292) (xy 99.766601 -213.427786)
			(xy 99.815841 -213.411787) (xy 99.866979 -213.403688) (xy 99.918753 -213.403688) (xy 99.969891 -213.411787)
			(xy 100.019131 -213.427786) (xy 100.065263 -213.451292) (xy 100.10715 -213.481724) (xy 100.14376 -213.518334)
			(xy 100.174192 -213.560221) (xy 100.197698 -213.606353) (xy 100.213697 -213.655593) (xy 100.221796 -213.706731)
			(xy 100.222304 -213.732618) (xy 101.443028 -213.732618) (xy 101.443536 -213.706731) (xy 101.451635 -213.655593)
			(xy 101.467634 -213.606353) (xy 101.49114 -213.560221) (xy 101.521572 -213.518334) (xy 101.558182 -213.481724)
			(xy 101.600069 -213.451292) (xy 101.646201 -213.427786) (xy 101.695441 -213.411787) (xy 101.746579 -213.403688)
			(xy 101.798353 -213.403688) (xy 101.849491 -213.411787) (xy 101.898731 -213.427786) (xy 101.944863 -213.451292)
			(xy 101.98675 -213.481724) (xy 102.02336 -213.518334) (xy 102.053792 -213.560221) (xy 102.077298 -213.606353)
			(xy 102.093297 -213.655593) (xy 102.101396 -213.706731) (xy 102.101904 -213.732618) (xy 103.322628 -213.732618)
			(xy 103.323136 -213.706731) (xy 103.331235 -213.655593) (xy 103.347234 -213.606353) (xy 103.37074 -213.560221)
			(xy 103.401172 -213.518334) (xy 103.437782 -213.481724) (xy 103.479669 -213.451292) (xy 103.525801 -213.427786)
			(xy 103.575041 -213.411787) (xy 103.626179 -213.403688) (xy 103.677953 -213.403688) (xy 103.729091 -213.411787)
			(xy 103.778331 -213.427786) (xy 103.824463 -213.451292) (xy 103.86635 -213.481724) (xy 103.90296 -213.518334)
			(xy 103.933392 -213.560221) (xy 103.956898 -213.606353) (xy 103.972897 -213.655593) (xy 103.980996 -213.706731)
			(xy 103.981504 -213.732618) (xy 105.202228 -213.732618) (xy 105.202736 -213.706731) (xy 105.210835 -213.655593)
			(xy 105.226834 -213.606353) (xy 105.25034 -213.560221) (xy 105.280772 -213.518334) (xy 105.317382 -213.481724)
			(xy 105.359269 -213.451292) (xy 105.405401 -213.427786) (xy 105.454641 -213.411787) (xy 105.505779 -213.403688)
			(xy 105.557553 -213.403688) (xy 105.608691 -213.411787) (xy 105.657931 -213.427786) (xy 105.704063 -213.451292)
			(xy 105.74595 -213.481724) (xy 105.78256 -213.518334) (xy 105.812992 -213.560221) (xy 105.836498 -213.606353)
			(xy 105.852497 -213.655593) (xy 105.860596 -213.706731) (xy 105.861104 -213.732618) (xy 107.081828 -213.732618)
			(xy 107.082336 -213.706731) (xy 107.090435 -213.655593) (xy 107.106434 -213.606353) (xy 107.12994 -213.560221)
			(xy 107.160372 -213.518334) (xy 107.196982 -213.481724) (xy 107.238869 -213.451292) (xy 107.285001 -213.427786)
			(xy 107.334241 -213.411787) (xy 107.385379 -213.403688) (xy 107.437153 -213.403688) (xy 107.488291 -213.411787)
			(xy 107.537531 -213.427786) (xy 107.583663 -213.451292) (xy 107.62555 -213.481724) (xy 107.66216 -213.518334)
			(xy 107.692592 -213.560221) (xy 107.716098 -213.606353) (xy 107.732097 -213.655593) (xy 107.740196 -213.706731)
			(xy 107.740704 -213.732618) (xy 114.600228 -213.732618) (xy 114.600736 -213.706731) (xy 114.608835 -213.655593)
			(xy 114.624834 -213.606353) (xy 114.64834 -213.560221) (xy 114.678772 -213.518334) (xy 114.715382 -213.481724)
			(xy 114.757269 -213.451292) (xy 114.803401 -213.427786) (xy 114.852641 -213.411787) (xy 114.903779 -213.403688)
			(xy 114.955553 -213.403688) (xy 115.006691 -213.411787) (xy 115.055931 -213.427786) (xy 115.102063 -213.451292)
			(xy 115.14395 -213.481724) (xy 115.18056 -213.518334) (xy 115.210992 -213.560221) (xy 115.234498 -213.606353)
			(xy 115.250497 -213.655593) (xy 115.258596 -213.706731) (xy 115.259104 -213.732618) (xy 116.479828 -213.732618)
			(xy 116.480336 -213.706731) (xy 116.488435 -213.655593) (xy 116.504434 -213.606353) (xy 116.52794 -213.560221)
			(xy 116.558372 -213.518334) (xy 116.594982 -213.481724) (xy 116.636869 -213.451292) (xy 116.683001 -213.427786)
			(xy 116.732241 -213.411787) (xy 116.783379 -213.403688) (xy 116.835153 -213.403688) (xy 116.886291 -213.411787)
			(xy 116.935531 -213.427786) (xy 116.981663 -213.451292) (xy 117.02355 -213.481724) (xy 117.06016 -213.518334)
			(xy 117.090592 -213.560221) (xy 117.114098 -213.606353) (xy 117.130097 -213.655593) (xy 117.138196 -213.706731)
			(xy 117.138704 -213.732618) (xy 118.359428 -213.732618) (xy 118.359936 -213.706731) (xy 118.368035 -213.655593)
			(xy 118.384034 -213.606353) (xy 118.40754 -213.560221) (xy 118.437972 -213.518334) (xy 118.474582 -213.481724)
			(xy 118.516469 -213.451292) (xy 118.562601 -213.427786) (xy 118.611841 -213.411787) (xy 118.662979 -213.403688)
			(xy 118.714753 -213.403688) (xy 118.765891 -213.411787) (xy 118.815131 -213.427786) (xy 118.861263 -213.451292)
			(xy 118.90315 -213.481724) (xy 118.93976 -213.518334) (xy 118.970192 -213.560221) (xy 118.993698 -213.606353)
			(xy 119.009697 -213.655593) (xy 119.017796 -213.706731) (xy 119.018304 -213.732618) (xy 120.239028 -213.732618)
			(xy 120.239536 -213.706731) (xy 120.247635 -213.655593) (xy 120.263634 -213.606353) (xy 120.28714 -213.560221)
			(xy 120.317572 -213.518334) (xy 120.354182 -213.481724) (xy 120.396069 -213.451292) (xy 120.442201 -213.427786)
			(xy 120.491441 -213.411787) (xy 120.542579 -213.403688) (xy 120.594353 -213.403688) (xy 120.645491 -213.411787)
			(xy 120.694731 -213.427786) (xy 120.740863 -213.451292) (xy 120.78275 -213.481724) (xy 120.81936 -213.518334)
			(xy 120.849792 -213.560221) (xy 120.873298 -213.606353) (xy 120.889297 -213.655593) (xy 120.897396 -213.706731)
			(xy 120.897904 -213.732618) (xy 122.118628 -213.732618) (xy 122.119136 -213.706731) (xy 122.127235 -213.655593)
			(xy 122.143234 -213.606353) (xy 122.16674 -213.560221) (xy 122.197172 -213.518334) (xy 122.233782 -213.481724)
			(xy 122.275669 -213.451292) (xy 122.321801 -213.427786) (xy 122.371041 -213.411787) (xy 122.422179 -213.403688)
			(xy 122.473953 -213.403688) (xy 122.525091 -213.411787) (xy 122.574331 -213.427786) (xy 122.620463 -213.451292)
			(xy 122.66235 -213.481724) (xy 122.69896 -213.518334) (xy 122.729392 -213.560221) (xy 122.752898 -213.606353)
			(xy 122.768897 -213.655593) (xy 122.776996 -213.706731) (xy 122.777504 -213.732618) (xy 123.99772 -213.732618)
			(xy 123.998228 -213.706711) (xy 124.006334 -213.655534) (xy 124.022346 -213.606255) (xy 124.045869 -213.560088)
			(xy 124.076325 -213.518169) (xy 124.112963 -213.481531) (xy 124.154882 -213.451075) (xy 124.201049 -213.427552)
			(xy 124.250328 -213.41154) (xy 124.301505 -213.403434) (xy 124.353319 -213.403434) (xy 124.404496 -213.41154)
			(xy 124.453775 -213.427552) (xy 124.499942 -213.451075) (xy 124.541861 -213.481531) (xy 124.578499 -213.518169)
			(xy 124.608955 -213.560088) (xy 124.632478 -213.606255) (xy 124.64849 -213.655534) (xy 124.656596 -213.706711)
			(xy 124.657104 -213.732618) (xy 125.87732 -213.732618) (xy 125.877828 -213.706711) (xy 125.885934 -213.655534)
			(xy 125.901946 -213.606255) (xy 125.925469 -213.560088) (xy 125.955925 -213.518169) (xy 125.992563 -213.481531)
			(xy 126.034482 -213.451075) (xy 126.080649 -213.427552) (xy 126.129928 -213.41154) (xy 126.181105 -213.403434)
			(xy 126.232919 -213.403434) (xy 126.284096 -213.41154) (xy 126.333375 -213.427552) (xy 126.379542 -213.451075)
			(xy 126.421461 -213.481531) (xy 126.458099 -213.518169) (xy 126.488555 -213.560088) (xy 126.512078 -213.606255)
			(xy 126.52809 -213.655534) (xy 126.536196 -213.706711) (xy 126.536704 -213.732618) (xy 127.757428 -213.732618)
			(xy 127.757936 -213.706731) (xy 127.766035 -213.655593) (xy 127.782034 -213.606353) (xy 127.80554 -213.560221)
			(xy 127.835972 -213.518334) (xy 127.872582 -213.481724) (xy 127.914469 -213.451292) (xy 127.960601 -213.427786)
			(xy 128.009841 -213.411787) (xy 128.060979 -213.403688) (xy 128.112753 -213.403688) (xy 128.163891 -213.411787)
			(xy 128.213131 -213.427786) (xy 128.259263 -213.451292) (xy 128.30115 -213.481724) (xy 128.33776 -213.518334)
			(xy 128.368192 -213.560221) (xy 128.391698 -213.606353) (xy 128.407697 -213.655593) (xy 128.415796 -213.706731)
			(xy 128.416304 -213.732618) (xy 129.637028 -213.732618) (xy 129.637536 -213.706731) (xy 129.645635 -213.655593)
			(xy 129.661634 -213.606353) (xy 129.68514 -213.560221) (xy 129.715572 -213.518334) (xy 129.752182 -213.481724)
			(xy 129.794069 -213.451292) (xy 129.840201 -213.427786) (xy 129.889441 -213.411787) (xy 129.940579 -213.403688)
			(xy 129.992353 -213.403688) (xy 130.043491 -213.411787) (xy 130.092731 -213.427786) (xy 130.138863 -213.451292)
			(xy 130.18075 -213.481724) (xy 130.21736 -213.518334) (xy 130.247792 -213.560221) (xy 130.271298 -213.606353)
			(xy 130.287297 -213.655593) (xy 130.295396 -213.706731) (xy 130.295904 -213.732618) (xy 131.516628 -213.732618)
			(xy 131.517136 -213.706731) (xy 131.525235 -213.655593) (xy 131.541234 -213.606353) (xy 131.56474 -213.560221)
			(xy 131.595172 -213.518334) (xy 131.631782 -213.481724) (xy 131.673669 -213.451292) (xy 131.719801 -213.427786)
			(xy 131.769041 -213.411787) (xy 131.820179 -213.403688) (xy 131.871953 -213.403688) (xy 131.923091 -213.411787)
			(xy 131.972331 -213.427786) (xy 132.018463 -213.451292) (xy 132.06035 -213.481724) (xy 132.09696 -213.518334)
			(xy 132.127392 -213.560221) (xy 132.150898 -213.606353) (xy 132.166897 -213.655593) (xy 132.174996 -213.706731)
			(xy 132.175504 -213.732618) (xy 338.105496 -213.732618) (xy 338.106004 -213.706731) (xy 338.114103 -213.655593)
			(xy 338.130102 -213.606353) (xy 338.153608 -213.560221) (xy 338.18404 -213.518334) (xy 338.22065 -213.481724)
			(xy 338.262537 -213.451292) (xy 338.308669 -213.427786) (xy 338.357909 -213.411787) (xy 338.409047 -213.403688)
			(xy 338.460821 -213.403688) (xy 338.511959 -213.411787) (xy 338.561199 -213.427786) (xy 338.607331 -213.451292)
			(xy 338.649218 -213.481724) (xy 338.685828 -213.518334) (xy 338.71626 -213.560221) (xy 338.739766 -213.606353)
			(xy 338.755765 -213.655593) (xy 338.763864 -213.706731) (xy 338.764372 -213.732618) (xy 339.985096 -213.732618)
			(xy 339.985604 -213.706731) (xy 339.993703 -213.655593) (xy 340.009702 -213.606353) (xy 340.033208 -213.560221)
			(xy 340.06364 -213.518334) (xy 340.10025 -213.481724) (xy 340.142137 -213.451292) (xy 340.188269 -213.427786)
			(xy 340.237509 -213.411787) (xy 340.288647 -213.403688) (xy 340.340421 -213.403688) (xy 340.391559 -213.411787)
			(xy 340.440799 -213.427786) (xy 340.486931 -213.451292) (xy 340.528818 -213.481724) (xy 340.565428 -213.518334)
			(xy 340.59586 -213.560221) (xy 340.619366 -213.606353) (xy 340.635365 -213.655593) (xy 340.643464 -213.706731)
			(xy 340.643972 -213.732618) (xy 341.864696 -213.732618) (xy 341.865204 -213.706731) (xy 341.873303 -213.655593)
			(xy 341.889302 -213.606353) (xy 341.912808 -213.560221) (xy 341.94324 -213.518334) (xy 341.97985 -213.481724)
			(xy 342.021737 -213.451292) (xy 342.067869 -213.427786) (xy 342.117109 -213.411787) (xy 342.168247 -213.403688)
			(xy 342.220021 -213.403688) (xy 342.271159 -213.411787) (xy 342.320399 -213.427786) (xy 342.366531 -213.451292)
			(xy 342.408418 -213.481724) (xy 342.445028 -213.518334) (xy 342.47546 -213.560221) (xy 342.498966 -213.606353)
			(xy 342.514965 -213.655593) (xy 342.523064 -213.706731) (xy 342.523572 -213.732618) (xy 343.744296 -213.732618)
			(xy 343.744804 -213.706731) (xy 343.752903 -213.655593) (xy 343.768902 -213.606353) (xy 343.792408 -213.560221)
			(xy 343.82284 -213.518334) (xy 343.85945 -213.481724) (xy 343.901337 -213.451292) (xy 343.947469 -213.427786)
			(xy 343.996709 -213.411787) (xy 344.047847 -213.403688) (xy 344.099621 -213.403688) (xy 344.150759 -213.411787)
			(xy 344.199999 -213.427786) (xy 344.246131 -213.451292) (xy 344.288018 -213.481724) (xy 344.324628 -213.518334)
			(xy 344.35506 -213.560221) (xy 344.378566 -213.606353) (xy 344.394565 -213.655593) (xy 344.402664 -213.706731)
			(xy 344.403172 -213.732618) (xy 345.623896 -213.732618) (xy 345.624404 -213.706731) (xy 345.632503 -213.655593)
			(xy 345.648502 -213.606353) (xy 345.672008 -213.560221) (xy 345.70244 -213.518334) (xy 345.73905 -213.481724)
			(xy 345.780937 -213.451292) (xy 345.827069 -213.427786) (xy 345.876309 -213.411787) (xy 345.927447 -213.403688)
			(xy 345.979221 -213.403688) (xy 346.030359 -213.411787) (xy 346.079599 -213.427786) (xy 346.125731 -213.451292)
			(xy 346.167618 -213.481724) (xy 346.204228 -213.518334) (xy 346.23466 -213.560221) (xy 346.258166 -213.606353)
			(xy 346.274165 -213.655593) (xy 346.282264 -213.706731) (xy 346.282772 -213.732618) (xy 347.503496 -213.732618)
			(xy 347.504004 -213.706731) (xy 347.512103 -213.655593) (xy 347.528102 -213.606353) (xy 347.551608 -213.560221)
			(xy 347.58204 -213.518334) (xy 347.61865 -213.481724) (xy 347.660537 -213.451292) (xy 347.706669 -213.427786)
			(xy 347.755909 -213.411787) (xy 347.807047 -213.403688) (xy 347.858821 -213.403688) (xy 347.909959 -213.411787)
			(xy 347.959199 -213.427786) (xy 348.005331 -213.451292) (xy 348.047218 -213.481724) (xy 348.083828 -213.518334)
			(xy 348.11426 -213.560221) (xy 348.137766 -213.606353) (xy 348.153765 -213.655593) (xy 348.161864 -213.706731)
			(xy 348.162372 -213.732618) (xy 349.383096 -213.732618) (xy 349.383604 -213.706731) (xy 349.391703 -213.655593)
			(xy 349.407702 -213.606353) (xy 349.431208 -213.560221) (xy 349.46164 -213.518334) (xy 349.49825 -213.481724)
			(xy 349.540137 -213.451292) (xy 349.586269 -213.427786) (xy 349.635509 -213.411787) (xy 349.686647 -213.403688)
			(xy 349.738421 -213.403688) (xy 349.789559 -213.411787) (xy 349.838799 -213.427786) (xy 349.884931 -213.451292)
			(xy 349.926818 -213.481724) (xy 349.963428 -213.518334) (xy 349.99386 -213.560221) (xy 350.017366 -213.606353)
			(xy 350.033365 -213.655593) (xy 350.041464 -213.706731) (xy 350.041972 -213.732618) (xy 351.262696 -213.732618)
			(xy 351.263204 -213.706731) (xy 351.271303 -213.655593) (xy 351.287302 -213.606353) (xy 351.310808 -213.560221)
			(xy 351.34124 -213.518334) (xy 351.37785 -213.481724) (xy 351.419737 -213.451292) (xy 351.465869 -213.427786)
			(xy 351.515109 -213.411787) (xy 351.566247 -213.403688) (xy 351.618021 -213.403688) (xy 351.669159 -213.411787)
			(xy 351.718399 -213.427786) (xy 351.764531 -213.451292) (xy 351.806418 -213.481724) (xy 351.843028 -213.518334)
			(xy 351.87346 -213.560221) (xy 351.896966 -213.606353) (xy 351.912965 -213.655593) (xy 351.921064 -213.706731)
			(xy 351.921572 -213.732618) (xy 353.142296 -213.732618) (xy 353.142804 -213.706731) (xy 353.150903 -213.655593)
			(xy 353.166902 -213.606353) (xy 353.190408 -213.560221) (xy 353.22084 -213.518334) (xy 353.25745 -213.481724)
			(xy 353.299337 -213.451292) (xy 353.345469 -213.427786) (xy 353.394709 -213.411787) (xy 353.445847 -213.403688)
			(xy 353.497621 -213.403688) (xy 353.548759 -213.411787) (xy 353.597999 -213.427786) (xy 353.644131 -213.451292)
			(xy 353.686018 -213.481724) (xy 353.722628 -213.518334) (xy 353.75306 -213.560221) (xy 353.776566 -213.606353)
			(xy 353.792565 -213.655593) (xy 353.800664 -213.706731) (xy 353.801172 -213.732618) (xy 355.021896 -213.732618)
			(xy 355.022404 -213.706731) (xy 355.030503 -213.655593) (xy 355.046502 -213.606353) (xy 355.070008 -213.560221)
			(xy 355.10044 -213.518334) (xy 355.13705 -213.481724) (xy 355.178937 -213.451292) (xy 355.225069 -213.427786)
			(xy 355.274309 -213.411787) (xy 355.325447 -213.403688) (xy 355.377221 -213.403688) (xy 355.428359 -213.411787)
			(xy 355.477599 -213.427786) (xy 355.523731 -213.451292) (xy 355.565618 -213.481724) (xy 355.602228 -213.518334)
			(xy 355.63266 -213.560221) (xy 355.656166 -213.606353) (xy 355.672165 -213.655593) (xy 355.680264 -213.706731)
			(xy 355.680772 -213.732618) (xy 355.680423 -213.755595) (xy 355.674102 -213.801111) (xy 355.661516 -213.845306)
			(xy 355.652578 -213.866476) (xy 355.642672 -213.888828) (xy 355.856286 -214.293958) (xy 355.880416 -214.29853)
			(xy 355.90533 -214.303664) (xy 355.95334 -214.320459) (xy 355.998199 -214.344434) (xy 356.038841 -214.375017)
			(xy 356.074299 -214.411484) (xy 356.103732 -214.452967) (xy 356.12644 -214.49848) (xy 356.141883 -214.546942)
			(xy 356.149695 -214.597202) (xy 356.150164 -214.622634) (xy 356.149656 -214.648521) (xy 356.141557 -214.699659)
			(xy 356.125558 -214.748899) (xy 356.102052 -214.795031) (xy 356.07162 -214.836918) (xy 356.03501 -214.873528)
			(xy 355.993123 -214.90396) (xy 355.946991 -214.927466) (xy 355.897751 -214.943465) (xy 355.846613 -214.951564)
			(xy 355.794839 -214.951564) (xy 355.743701 -214.943465) (xy 355.694461 -214.927466) (xy 355.648329 -214.90396)
			(xy 355.606442 -214.873528) (xy 355.569832 -214.836918) (xy 355.5394 -214.795031) (xy 355.515894 -214.748899)
			(xy 355.499895 -214.699659) (xy 355.491796 -214.648521) (xy 355.491288 -214.622634) (xy 355.491658 -214.599658)
			(xy 355.49797 -214.554143) (xy 355.510548 -214.509947) (xy 355.519482 -214.488776) (xy 355.529388 -214.466424)
			(xy 355.315774 -214.061294) (xy 355.291644 -214.056722) (xy 355.266713 -214.051663) (xy 355.218699 -214.034858)
			(xy 355.173839 -214.010874) (xy 355.133197 -213.980281) (xy 355.097739 -213.943805) (xy 355.068309 -213.902313)
			(xy 355.045605 -213.856791) (xy 355.030167 -213.80832) (xy 355.022362 -213.758053) (xy 355.021896 -213.732618)
			(xy 353.801172 -213.732618) (xy 353.800823 -213.755595) (xy 353.794502 -213.801111) (xy 353.781916 -213.845306)
			(xy 353.772978 -213.866476) (xy 353.763072 -213.888828) (xy 353.976686 -214.293958) (xy 354.000816 -214.29853)
			(xy 354.02573 -214.303664) (xy 354.07374 -214.320459) (xy 354.118599 -214.344434) (xy 354.159241 -214.375017)
			(xy 354.194699 -214.411484) (xy 354.224132 -214.452967) (xy 354.24684 -214.49848) (xy 354.262283 -214.546942)
			(xy 354.270095 -214.597202) (xy 354.270564 -214.622634) (xy 354.270056 -214.648521) (xy 354.261957 -214.699659)
			(xy 354.245958 -214.748899) (xy 354.222452 -214.795031) (xy 354.19202 -214.836918) (xy 354.15541 -214.873528)
			(xy 354.113523 -214.90396) (xy 354.067391 -214.927466) (xy 354.018151 -214.943465) (xy 353.967013 -214.951564)
			(xy 353.915239 -214.951564) (xy 353.864101 -214.943465) (xy 353.814861 -214.927466) (xy 353.768729 -214.90396)
			(xy 353.726842 -214.873528) (xy 353.690232 -214.836918) (xy 353.6598 -214.795031) (xy 353.636294 -214.748899)
			(xy 353.620295 -214.699659) (xy 353.612196 -214.648521) (xy 353.611688 -214.622634) (xy 353.612058 -214.599658)
			(xy 353.61837 -214.554143) (xy 353.630948 -214.509947) (xy 353.639882 -214.488776) (xy 353.649788 -214.466424)
			(xy 353.436174 -214.061294) (xy 353.412044 -214.056722) (xy 353.387113 -214.051663) (xy 353.339099 -214.034858)
			(xy 353.294239 -214.010874) (xy 353.253597 -213.980281) (xy 353.218139 -213.943805) (xy 353.188709 -213.902313)
			(xy 353.166005 -213.856791) (xy 353.150567 -213.80832) (xy 353.142762 -213.758053) (xy 353.142296 -213.732618)
			(xy 351.921572 -213.732618) (xy 351.921223 -213.755595) (xy 351.914902 -213.801111) (xy 351.902316 -213.845306)
			(xy 351.893378 -213.866476) (xy 351.883472 -213.888828) (xy 352.097086 -214.293958) (xy 352.121216 -214.29853)
			(xy 352.14613 -214.303664) (xy 352.19414 -214.320459) (xy 352.238999 -214.344434) (xy 352.279641 -214.375017)
			(xy 352.315099 -214.411484) (xy 352.344532 -214.452967) (xy 352.36724 -214.49848) (xy 352.382683 -214.546942)
			(xy 352.390495 -214.597202) (xy 352.390964 -214.622634) (xy 352.390456 -214.648521) (xy 352.382357 -214.699659)
			(xy 352.366358 -214.748899) (xy 352.342852 -214.795031) (xy 352.31242 -214.836918) (xy 352.27581 -214.873528)
			(xy 352.233923 -214.90396) (xy 352.187791 -214.927466) (xy 352.138551 -214.943465) (xy 352.087413 -214.951564)
			(xy 352.035639 -214.951564) (xy 351.984501 -214.943465) (xy 351.935261 -214.927466) (xy 351.889129 -214.90396)
			(xy 351.847242 -214.873528) (xy 351.810632 -214.836918) (xy 351.7802 -214.795031) (xy 351.756694 -214.748899)
			(xy 351.740695 -214.699659) (xy 351.732596 -214.648521) (xy 351.732088 -214.622634) (xy 351.732458 -214.599658)
			(xy 351.73877 -214.554143) (xy 351.751348 -214.509947) (xy 351.760282 -214.488776) (xy 351.770188 -214.466424)
			(xy 351.556574 -214.061294) (xy 351.532444 -214.056722) (xy 351.507513 -214.051663) (xy 351.459499 -214.034858)
			(xy 351.414639 -214.010874) (xy 351.373997 -213.980281) (xy 351.338539 -213.943805) (xy 351.309109 -213.902313)
			(xy 351.286405 -213.856791) (xy 351.270967 -213.80832) (xy 351.263162 -213.758053) (xy 351.262696 -213.732618)
			(xy 350.041972 -213.732618) (xy 350.041623 -213.755595) (xy 350.035302 -213.801111) (xy 350.022716 -213.845306)
			(xy 350.013778 -213.866476) (xy 350.003872 -213.888828) (xy 350.217486 -214.293958) (xy 350.241616 -214.29853)
			(xy 350.26653 -214.303664) (xy 350.31454 -214.320459) (xy 350.359399 -214.344434) (xy 350.400041 -214.375017)
			(xy 350.435499 -214.411484) (xy 350.464932 -214.452967) (xy 350.48764 -214.49848) (xy 350.503083 -214.546942)
			(xy 350.510895 -214.597202) (xy 350.511364 -214.622634) (xy 350.510856 -214.648521) (xy 350.502757 -214.699659)
			(xy 350.486758 -214.748899) (xy 350.463252 -214.795031) (xy 350.43282 -214.836918) (xy 350.39621 -214.873528)
			(xy 350.354323 -214.90396) (xy 350.308191 -214.927466) (xy 350.258951 -214.943465) (xy 350.207813 -214.951564)
			(xy 350.156039 -214.951564) (xy 350.104901 -214.943465) (xy 350.055661 -214.927466) (xy 350.009529 -214.90396)
			(xy 349.967642 -214.873528) (xy 349.931032 -214.836918) (xy 349.9006 -214.795031) (xy 349.877094 -214.748899)
			(xy 349.861095 -214.699659) (xy 349.852996 -214.648521) (xy 349.852488 -214.622634) (xy 349.852858 -214.599658)
			(xy 349.85917 -214.554143) (xy 349.871748 -214.509947) (xy 349.880682 -214.488776) (xy 349.890588 -214.466424)
			(xy 349.676974 -214.061294) (xy 349.652844 -214.056722) (xy 349.627913 -214.051663) (xy 349.579899 -214.034858)
			(xy 349.535039 -214.010874) (xy 349.494397 -213.980281) (xy 349.458939 -213.943805) (xy 349.429509 -213.902313)
			(xy 349.406805 -213.856791) (xy 349.391367 -213.80832) (xy 349.383562 -213.758053) (xy 349.383096 -213.732618)
			(xy 348.162372 -213.732618) (xy 348.162023 -213.755595) (xy 348.155702 -213.801111) (xy 348.143116 -213.845306)
			(xy 348.134178 -213.866476) (xy 348.124272 -213.888828) (xy 348.337886 -214.293958) (xy 348.362016 -214.29853)
			(xy 348.38693 -214.303664) (xy 348.43494 -214.320459) (xy 348.479799 -214.344434) (xy 348.520441 -214.375017)
			(xy 348.555899 -214.411484) (xy 348.585332 -214.452967) (xy 348.60804 -214.49848) (xy 348.623483 -214.546942)
			(xy 348.631295 -214.597202) (xy 348.631764 -214.622634) (xy 348.631256 -214.648521) (xy 348.623157 -214.699659)
			(xy 348.607158 -214.748899) (xy 348.583652 -214.795031) (xy 348.55322 -214.836918) (xy 348.51661 -214.873528)
			(xy 348.474723 -214.90396) (xy 348.428591 -214.927466) (xy 348.379351 -214.943465) (xy 348.328213 -214.951564)
			(xy 348.276439 -214.951564) (xy 348.225301 -214.943465) (xy 348.176061 -214.927466) (xy 348.129929 -214.90396)
			(xy 348.088042 -214.873528) (xy 348.051432 -214.836918) (xy 348.021 -214.795031) (xy 347.997494 -214.748899)
			(xy 347.981495 -214.699659) (xy 347.973396 -214.648521) (xy 347.972888 -214.622634) (xy 347.973258 -214.599658)
			(xy 347.97957 -214.554143) (xy 347.992148 -214.509947) (xy 348.001082 -214.488776) (xy 348.010988 -214.466424)
			(xy 347.797374 -214.061294) (xy 347.773244 -214.056722) (xy 347.748313 -214.051663) (xy 347.700299 -214.034858)
			(xy 347.655439 -214.010874) (xy 347.614797 -213.980281) (xy 347.579339 -213.943805) (xy 347.549909 -213.902313)
			(xy 347.527205 -213.856791) (xy 347.511767 -213.80832) (xy 347.503962 -213.758053) (xy 347.503496 -213.732618)
			(xy 346.282772 -213.732618) (xy 346.282423 -213.755595) (xy 346.276102 -213.801111) (xy 346.263516 -213.845306)
			(xy 346.254578 -213.866476) (xy 346.244672 -213.888828) (xy 346.458286 -214.293958) (xy 346.482416 -214.29853)
			(xy 346.50733 -214.303664) (xy 346.55534 -214.320459) (xy 346.600199 -214.344434) (xy 346.640841 -214.375017)
			(xy 346.676299 -214.411484) (xy 346.705732 -214.452967) (xy 346.72844 -214.49848) (xy 346.743883 -214.546942)
			(xy 346.751695 -214.597202) (xy 346.752164 -214.622634) (xy 346.751656 -214.648521) (xy 346.743557 -214.699659)
			(xy 346.727558 -214.748899) (xy 346.704052 -214.795031) (xy 346.67362 -214.836918) (xy 346.63701 -214.873528)
			(xy 346.595123 -214.90396) (xy 346.548991 -214.927466) (xy 346.499751 -214.943465) (xy 346.448613 -214.951564)
			(xy 346.396839 -214.951564) (xy 346.345701 -214.943465) (xy 346.296461 -214.927466) (xy 346.250329 -214.90396)
			(xy 346.208442 -214.873528) (xy 346.171832 -214.836918) (xy 346.1414 -214.795031) (xy 346.117894 -214.748899)
			(xy 346.101895 -214.699659) (xy 346.093796 -214.648521) (xy 346.093288 -214.622634) (xy 346.093658 -214.599658)
			(xy 346.09997 -214.554143) (xy 346.112548 -214.509947) (xy 346.121482 -214.488776) (xy 346.131388 -214.466424)
			(xy 345.917774 -214.061294) (xy 345.893644 -214.056722) (xy 345.868713 -214.051663) (xy 345.820699 -214.034858)
			(xy 345.775839 -214.010874) (xy 345.735197 -213.980281) (xy 345.699739 -213.943805) (xy 345.670309 -213.902313)
			(xy 345.647605 -213.856791) (xy 345.632167 -213.80832) (xy 345.624362 -213.758053) (xy 345.623896 -213.732618)
			(xy 344.403172 -213.732618) (xy 344.402823 -213.755595) (xy 344.396502 -213.801111) (xy 344.383916 -213.845306)
			(xy 344.374978 -213.866476) (xy 344.365072 -213.888828) (xy 344.578686 -214.293958) (xy 344.602816 -214.29853)
			(xy 344.62773 -214.303664) (xy 344.67574 -214.320459) (xy 344.720599 -214.344434) (xy 344.761241 -214.375017)
			(xy 344.796699 -214.411484) (xy 344.826132 -214.452967) (xy 344.84884 -214.49848) (xy 344.864283 -214.546942)
			(xy 344.872095 -214.597202) (xy 344.872564 -214.622634) (xy 344.872056 -214.648521) (xy 344.863957 -214.699659)
			(xy 344.847958 -214.748899) (xy 344.824452 -214.795031) (xy 344.79402 -214.836918) (xy 344.75741 -214.873528)
			(xy 344.715523 -214.90396) (xy 344.669391 -214.927466) (xy 344.620151 -214.943465) (xy 344.569013 -214.951564)
			(xy 344.517239 -214.951564) (xy 344.466101 -214.943465) (xy 344.416861 -214.927466) (xy 344.370729 -214.90396)
			(xy 344.328842 -214.873528) (xy 344.292232 -214.836918) (xy 344.2618 -214.795031) (xy 344.238294 -214.748899)
			(xy 344.222295 -214.699659) (xy 344.214196 -214.648521) (xy 344.213688 -214.622634) (xy 344.214058 -214.599658)
			(xy 344.22037 -214.554143) (xy 344.232948 -214.509947) (xy 344.241882 -214.488776) (xy 344.251788 -214.466424)
			(xy 344.038174 -214.061294) (xy 344.014044 -214.056722) (xy 343.989113 -214.051663) (xy 343.941099 -214.034858)
			(xy 343.896239 -214.010874) (xy 343.855597 -213.980281) (xy 343.820139 -213.943805) (xy 343.790709 -213.902313)
			(xy 343.768005 -213.856791) (xy 343.752567 -213.80832) (xy 343.744762 -213.758053) (xy 343.744296 -213.732618)
			(xy 342.523572 -213.732618) (xy 342.523223 -213.755595) (xy 342.516902 -213.801111) (xy 342.504316 -213.845306)
			(xy 342.495378 -213.866476) (xy 342.485472 -213.888828) (xy 342.699086 -214.293958) (xy 342.723216 -214.29853)
			(xy 342.74813 -214.303664) (xy 342.79614 -214.320459) (xy 342.840999 -214.344434) (xy 342.881641 -214.375017)
			(xy 342.917099 -214.411484) (xy 342.946532 -214.452967) (xy 342.96924 -214.49848) (xy 342.984683 -214.546942)
			(xy 342.992495 -214.597202) (xy 342.992964 -214.622634) (xy 342.992456 -214.648521) (xy 342.984357 -214.699659)
			(xy 342.968358 -214.748899) (xy 342.944852 -214.795031) (xy 342.91442 -214.836918) (xy 342.87781 -214.873528)
			(xy 342.835923 -214.90396) (xy 342.789791 -214.927466) (xy 342.740551 -214.943465) (xy 342.689413 -214.951564)
			(xy 342.637639 -214.951564) (xy 342.586501 -214.943465) (xy 342.537261 -214.927466) (xy 342.491129 -214.90396)
			(xy 342.449242 -214.873528) (xy 342.412632 -214.836918) (xy 342.3822 -214.795031) (xy 342.358694 -214.748899)
			(xy 342.342695 -214.699659) (xy 342.334596 -214.648521) (xy 342.334088 -214.622634) (xy 342.334458 -214.599658)
			(xy 342.34077 -214.554143) (xy 342.353348 -214.509947) (xy 342.362282 -214.488776) (xy 342.372188 -214.466424)
			(xy 342.158574 -214.061294) (xy 342.134444 -214.056722) (xy 342.109513 -214.051663) (xy 342.061499 -214.034858)
			(xy 342.016639 -214.010874) (xy 341.975997 -213.980281) (xy 341.940539 -213.943805) (xy 341.911109 -213.902313)
			(xy 341.888405 -213.856791) (xy 341.872967 -213.80832) (xy 341.865162 -213.758053) (xy 341.864696 -213.732618)
			(xy 340.643972 -213.732618) (xy 340.643623 -213.755595) (xy 340.637302 -213.801111) (xy 340.624716 -213.845306)
			(xy 340.615778 -213.866476) (xy 340.605872 -213.888828) (xy 340.819486 -214.293958) (xy 340.843616 -214.29853)
			(xy 340.86853 -214.303664) (xy 340.91654 -214.320459) (xy 340.961399 -214.344434) (xy 341.002041 -214.375017)
			(xy 341.037499 -214.411484) (xy 341.066932 -214.452967) (xy 341.08964 -214.49848) (xy 341.105083 -214.546942)
			(xy 341.112895 -214.597202) (xy 341.113364 -214.622634) (xy 341.112856 -214.648521) (xy 341.104757 -214.699659)
			(xy 341.088758 -214.748899) (xy 341.065252 -214.795031) (xy 341.03482 -214.836918) (xy 340.99821 -214.873528)
			(xy 340.956323 -214.90396) (xy 340.910191 -214.927466) (xy 340.860951 -214.943465) (xy 340.809813 -214.951564)
			(xy 340.758039 -214.951564) (xy 340.706901 -214.943465) (xy 340.657661 -214.927466) (xy 340.611529 -214.90396)
			(xy 340.569642 -214.873528) (xy 340.533032 -214.836918) (xy 340.5026 -214.795031) (xy 340.479094 -214.748899)
			(xy 340.463095 -214.699659) (xy 340.454996 -214.648521) (xy 340.454488 -214.622634) (xy 340.454858 -214.599658)
			(xy 340.46117 -214.554143) (xy 340.473748 -214.509947) (xy 340.482682 -214.488776) (xy 340.492588 -214.466424)
			(xy 340.278974 -214.061294) (xy 340.254844 -214.056722) (xy 340.229913 -214.051663) (xy 340.181899 -214.034858)
			(xy 340.137039 -214.010874) (xy 340.096397 -213.980281) (xy 340.060939 -213.943805) (xy 340.031509 -213.902313)
			(xy 340.008805 -213.856791) (xy 339.993367 -213.80832) (xy 339.985562 -213.758053) (xy 339.985096 -213.732618)
			(xy 338.764372 -213.732618) (xy 338.764023 -213.755595) (xy 338.757702 -213.801111) (xy 338.745116 -213.845306)
			(xy 338.736178 -213.866476) (xy 338.726272 -213.888828) (xy 338.939886 -214.293958) (xy 338.964016 -214.29853)
			(xy 338.98893 -214.303664) (xy 339.03694 -214.320459) (xy 339.081799 -214.344434) (xy 339.122441 -214.375017)
			(xy 339.157899 -214.411484) (xy 339.187332 -214.452967) (xy 339.21004 -214.49848) (xy 339.225483 -214.546942)
			(xy 339.233295 -214.597202) (xy 339.233764 -214.622634) (xy 339.233256 -214.648521) (xy 339.225157 -214.699659)
			(xy 339.209158 -214.748899) (xy 339.185652 -214.795031) (xy 339.15522 -214.836918) (xy 339.11861 -214.873528)
			(xy 339.076723 -214.90396) (xy 339.030591 -214.927466) (xy 338.981351 -214.943465) (xy 338.930213 -214.951564)
			(xy 338.878439 -214.951564) (xy 338.827301 -214.943465) (xy 338.778061 -214.927466) (xy 338.731929 -214.90396)
			(xy 338.690042 -214.873528) (xy 338.653432 -214.836918) (xy 338.623 -214.795031) (xy 338.599494 -214.748899)
			(xy 338.583495 -214.699659) (xy 338.575396 -214.648521) (xy 338.574888 -214.622634) (xy 338.575258 -214.599658)
			(xy 338.58157 -214.554143) (xy 338.594148 -214.509947) (xy 338.603082 -214.488776) (xy 338.612988 -214.466424)
			(xy 338.399374 -214.061294) (xy 338.375244 -214.056722) (xy 338.350313 -214.051663) (xy 338.302299 -214.034858)
			(xy 338.257439 -214.010874) (xy 338.216797 -213.980281) (xy 338.181339 -213.943805) (xy 338.151909 -213.902313)
			(xy 338.129205 -213.856791) (xy 338.113767 -213.80832) (xy 338.105962 -213.758053) (xy 338.105496 -213.732618)
			(xy 132.175504 -213.732618) (xy 132.175153 -213.755595) (xy 132.168832 -213.80111) (xy 132.156248 -213.845306)
			(xy 132.14731 -213.866476) (xy 132.137404 -213.888828) (xy 132.351018 -214.293958) (xy 132.375148 -214.29853)
			(xy 132.400067 -214.303641) (xy 132.448077 -214.320441) (xy 132.492936 -214.344419) (xy 132.533576 -214.375006)
			(xy 132.569034 -214.411476) (xy 132.598466 -214.452961) (xy 132.621173 -214.498476) (xy 132.636615 -214.54694)
			(xy 132.644427 -214.597201) (xy 132.644896 -214.622634) (xy 132.644388 -214.648521) (xy 132.636289 -214.699659)
			(xy 132.62029 -214.748899) (xy 132.596784 -214.795031) (xy 132.566352 -214.836918) (xy 132.529742 -214.873528)
			(xy 132.487855 -214.90396) (xy 132.441723 -214.927466) (xy 132.392483 -214.943465) (xy 132.341345 -214.951564)
			(xy 132.289571 -214.951564) (xy 132.238433 -214.943465) (xy 132.189193 -214.927466) (xy 132.143061 -214.90396)
			(xy 132.101174 -214.873528) (xy 132.064564 -214.836918) (xy 132.034132 -214.795031) (xy 132.010626 -214.748899)
			(xy 131.994627 -214.699659) (xy 131.986528 -214.648521) (xy 131.98602 -214.622634) (xy 131.986387 -214.599658)
			(xy 131.9927 -214.554143) (xy 132.005279 -214.509947) (xy 132.014214 -214.488776) (xy 132.02412 -214.466424)
			(xy 131.810506 -214.061294) (xy 131.786376 -214.056722) (xy 131.76145 -214.051639) (xy 131.713436 -214.034839)
			(xy 131.668575 -214.010859) (xy 131.627932 -213.980269) (xy 131.592474 -213.943796) (xy 131.563043 -213.902307)
			(xy 131.540338 -213.856787) (xy 131.5249 -213.808318) (xy 131.517094 -213.758052) (xy 131.516628 -213.732618)
			(xy 130.295904 -213.732618) (xy 130.295553 -213.755595) (xy 130.289232 -213.80111) (xy 130.276648 -213.845306)
			(xy 130.26771 -213.866476) (xy 130.257804 -213.888828) (xy 130.471418 -214.293958) (xy 130.495548 -214.29853)
			(xy 130.520467 -214.303641) (xy 130.568477 -214.320441) (xy 130.613336 -214.344419) (xy 130.653976 -214.375006)
			(xy 130.689434 -214.411476) (xy 130.718866 -214.452961) (xy 130.741573 -214.498476) (xy 130.757015 -214.54694)
			(xy 130.764827 -214.597201) (xy 130.765296 -214.622634) (xy 130.764788 -214.648521) (xy 130.756689 -214.699659)
			(xy 130.74069 -214.748899) (xy 130.717184 -214.795031) (xy 130.686752 -214.836918) (xy 130.650142 -214.873528)
			(xy 130.608255 -214.90396) (xy 130.562123 -214.927466) (xy 130.512883 -214.943465) (xy 130.461745 -214.951564)
			(xy 130.409971 -214.951564) (xy 130.358833 -214.943465) (xy 130.309593 -214.927466) (xy 130.263461 -214.90396)
			(xy 130.221574 -214.873528) (xy 130.184964 -214.836918) (xy 130.154532 -214.795031) (xy 130.131026 -214.748899)
			(xy 130.115027 -214.699659) (xy 130.106928 -214.648521) (xy 130.10642 -214.622634) (xy 130.106787 -214.599658)
			(xy 130.1131 -214.554143) (xy 130.125679 -214.509947) (xy 130.134614 -214.488776) (xy 130.14452 -214.466424)
			(xy 129.930906 -214.061294) (xy 129.906776 -214.056722) (xy 129.88185 -214.051639) (xy 129.833836 -214.034839)
			(xy 129.788975 -214.010859) (xy 129.748332 -213.980269) (xy 129.712874 -213.943796) (xy 129.683443 -213.902307)
			(xy 129.660738 -213.856787) (xy 129.6453 -213.808318) (xy 129.637494 -213.758052) (xy 129.637028 -213.732618)
			(xy 128.416304 -213.732618) (xy 128.415953 -213.755595) (xy 128.409632 -213.80111) (xy 128.397048 -213.845306)
			(xy 128.38811 -213.866476) (xy 128.378204 -213.888828) (xy 128.591818 -214.293958) (xy 128.615948 -214.29853)
			(xy 128.640867 -214.303641) (xy 128.688877 -214.320441) (xy 128.733736 -214.344419) (xy 128.774376 -214.375006)
			(xy 128.809834 -214.411476) (xy 128.839266 -214.452961) (xy 128.861973 -214.498476) (xy 128.877415 -214.54694)
			(xy 128.885227 -214.597201) (xy 128.885696 -214.622634) (xy 128.885188 -214.648521) (xy 128.877089 -214.699659)
			(xy 128.86109 -214.748899) (xy 128.837584 -214.795031) (xy 128.807152 -214.836918) (xy 128.770542 -214.873528)
			(xy 128.728655 -214.90396) (xy 128.682523 -214.927466) (xy 128.633283 -214.943465) (xy 128.582145 -214.951564)
			(xy 128.530371 -214.951564) (xy 128.479233 -214.943465) (xy 128.429993 -214.927466) (xy 128.383861 -214.90396)
			(xy 128.341974 -214.873528) (xy 128.305364 -214.836918) (xy 128.274932 -214.795031) (xy 128.251426 -214.748899)
			(xy 128.235427 -214.699659) (xy 128.227328 -214.648521) (xy 128.22682 -214.622634) (xy 128.227187 -214.599658)
			(xy 128.2335 -214.554143) (xy 128.246079 -214.509947) (xy 128.255014 -214.488776) (xy 128.26492 -214.466424)
			(xy 128.051306 -214.061294) (xy 128.027176 -214.056722) (xy 128.00225 -214.051639) (xy 127.954236 -214.034839)
			(xy 127.909375 -214.010859) (xy 127.868732 -213.980269) (xy 127.833274 -213.943796) (xy 127.803843 -213.902307)
			(xy 127.781138 -213.856787) (xy 127.7657 -213.808318) (xy 127.757894 -213.758052) (xy 127.757428 -213.732618)
			(xy 126.536704 -213.732618) (xy 126.536283 -213.755559) (xy 126.529855 -213.80099) (xy 126.517209 -213.845096)
			(xy 126.508256 -213.866222) (xy 126.49835 -213.888574) (xy 126.712218 -214.293958) (xy 126.736348 -214.29853)
			(xy 126.761267 -214.303641) (xy 126.809277 -214.320441) (xy 126.854136 -214.344419) (xy 126.894776 -214.375006)
			(xy 126.930234 -214.411476) (xy 126.959666 -214.452961) (xy 126.982373 -214.498476) (xy 126.997815 -214.54694)
			(xy 127.005627 -214.597201) (xy 127.006096 -214.622634) (xy 127.005588 -214.648521) (xy 126.997489 -214.699659)
			(xy 126.98149 -214.748899) (xy 126.957984 -214.795031) (xy 126.927552 -214.836918) (xy 126.890942 -214.873528)
			(xy 126.849055 -214.90396) (xy 126.802923 -214.927466) (xy 126.753683 -214.943465) (xy 126.702545 -214.951564)
			(xy 126.650771 -214.951564) (xy 126.599633 -214.943465) (xy 126.550393 -214.927466) (xy 126.504261 -214.90396)
			(xy 126.462374 -214.873528) (xy 126.425764 -214.836918) (xy 126.395332 -214.795031) (xy 126.371826 -214.748899)
			(xy 126.355827 -214.699659) (xy 126.347728 -214.648521) (xy 126.34722 -214.622634) (xy 126.347587 -214.599658)
			(xy 126.3539 -214.554143) (xy 126.366479 -214.509947) (xy 126.375414 -214.488776) (xy 126.38532 -214.466424)
			(xy 126.171706 -214.061294) (xy 126.147576 -214.056722) (xy 126.12262 -214.051672) (xy 126.074538 -214.034924)
			(xy 126.029605 -214.010979) (xy 125.98889 -213.980407) (xy 125.953363 -213.943936) (xy 125.92387 -213.902434)
			(xy 125.901111 -213.856888) (xy 125.88563 -213.808384) (xy 125.877795 -213.758075) (xy 125.87732 -213.732618)
			(xy 124.657104 -213.732618) (xy 124.656681 -213.756953) (xy 124.649527 -213.805095) (xy 124.635379 -213.851663)
			(xy 124.625354 -213.873842) (xy 124.614432 -213.896448) (xy 124.820172 -214.292942) (xy 124.845826 -214.296752)
			(xy 124.87151 -214.301109) (xy 124.921167 -214.316849) (xy 124.967731 -214.340204) (xy 125.010041 -214.370592)
			(xy 125.047044 -214.407258) (xy 125.077819 -214.449288) (xy 125.101599 -214.495635) (xy 125.117793 -214.545146)
			(xy 125.125998 -214.596588) (xy 125.126496 -214.622634) (xy 125.125988 -214.648521) (xy 125.117889 -214.699659)
			(xy 125.10189 -214.748899) (xy 125.078384 -214.795031) (xy 125.047952 -214.836918) (xy 125.011342 -214.873528)
			(xy 124.969455 -214.90396) (xy 124.923323 -214.927466) (xy 124.874083 -214.943465) (xy 124.822945 -214.951564)
			(xy 124.771171 -214.951564) (xy 124.720033 -214.943465) (xy 124.670793 -214.927466) (xy 124.624661 -214.90396)
			(xy 124.582774 -214.873528) (xy 124.546164 -214.836918) (xy 124.515732 -214.795031) (xy 124.492226 -214.748899)
			(xy 124.476227 -214.699659) (xy 124.468128 -214.648521) (xy 124.46762 -214.622634) (xy 124.468099 -214.597068)
			(xy 124.476002 -214.546552) (xy 124.491623 -214.497866) (xy 124.502672 -214.474806) (xy 124.514102 -214.451438)
			(xy 124.31268 -214.062818) (xy 124.28601 -214.059516) (xy 124.259814 -214.055663) (xy 124.20902 -214.04073)
			(xy 124.161267 -214.017866) (xy 124.117785 -213.987661) (xy 124.079693 -213.950891) (xy 124.047971 -213.908503)
			(xy 124.023436 -213.861587) (xy 124.006718 -213.811352) (xy 123.998249 -213.75909) (xy 123.99772 -213.732618)
			(xy 122.777504 -213.732618) (xy 122.777153 -213.755595) (xy 122.770832 -213.80111) (xy 122.758248 -213.845306)
			(xy 122.74931 -213.866476) (xy 122.739404 -213.888828) (xy 122.953018 -214.293958) (xy 122.977148 -214.29853)
			(xy 123.002067 -214.303641) (xy 123.050077 -214.320441) (xy 123.094936 -214.344419) (xy 123.135576 -214.375006)
			(xy 123.171034 -214.411476) (xy 123.200466 -214.452961) (xy 123.223173 -214.498476) (xy 123.238615 -214.54694)
			(xy 123.246427 -214.597201) (xy 123.246896 -214.622634) (xy 123.246388 -214.648521) (xy 123.238289 -214.699659)
			(xy 123.22229 -214.748899) (xy 123.198784 -214.795031) (xy 123.168352 -214.836918) (xy 123.131742 -214.873528)
			(xy 123.089855 -214.90396) (xy 123.043723 -214.927466) (xy 122.994483 -214.943465) (xy 122.943345 -214.951564)
			(xy 122.891571 -214.951564) (xy 122.840433 -214.943465) (xy 122.791193 -214.927466) (xy 122.745061 -214.90396)
			(xy 122.703174 -214.873528) (xy 122.666564 -214.836918) (xy 122.636132 -214.795031) (xy 122.612626 -214.748899)
			(xy 122.596627 -214.699659) (xy 122.588528 -214.648521) (xy 122.58802 -214.622634) (xy 122.588387 -214.599658)
			(xy 122.5947 -214.554143) (xy 122.607279 -214.509947) (xy 122.616214 -214.488776) (xy 122.62612 -214.466424)
			(xy 122.412506 -214.061294) (xy 122.388376 -214.056722) (xy 122.36345 -214.051639) (xy 122.315436 -214.034839)
			(xy 122.270575 -214.010859) (xy 122.229932 -213.980269) (xy 122.194474 -213.943796) (xy 122.165043 -213.902307)
			(xy 122.142338 -213.856787) (xy 122.1269 -213.808318) (xy 122.119094 -213.758052) (xy 122.118628 -213.732618)
			(xy 120.897904 -213.732618) (xy 120.897553 -213.755595) (xy 120.891232 -213.80111) (xy 120.878648 -213.845306)
			(xy 120.86971 -213.866476) (xy 120.859804 -213.888828) (xy 121.073418 -214.293958) (xy 121.097548 -214.29853)
			(xy 121.122467 -214.303641) (xy 121.170477 -214.320441) (xy 121.215336 -214.344419) (xy 121.255976 -214.375006)
			(xy 121.291434 -214.411476) (xy 121.320866 -214.452961) (xy 121.343573 -214.498476) (xy 121.359015 -214.54694)
			(xy 121.366827 -214.597201) (xy 121.367296 -214.622634) (xy 121.366788 -214.648521) (xy 121.358689 -214.699659)
			(xy 121.34269 -214.748899) (xy 121.319184 -214.795031) (xy 121.288752 -214.836918) (xy 121.252142 -214.873528)
			(xy 121.210255 -214.90396) (xy 121.164123 -214.927466) (xy 121.114883 -214.943465) (xy 121.063745 -214.951564)
			(xy 121.011971 -214.951564) (xy 120.960833 -214.943465) (xy 120.911593 -214.927466) (xy 120.865461 -214.90396)
			(xy 120.823574 -214.873528) (xy 120.786964 -214.836918) (xy 120.756532 -214.795031) (xy 120.733026 -214.748899)
			(xy 120.717027 -214.699659) (xy 120.708928 -214.648521) (xy 120.70842 -214.622634) (xy 120.708787 -214.599658)
			(xy 120.7151 -214.554143) (xy 120.727679 -214.509947) (xy 120.736614 -214.488776) (xy 120.74652 -214.466424)
			(xy 120.532906 -214.061294) (xy 120.508776 -214.056722) (xy 120.48385 -214.051639) (xy 120.435836 -214.034839)
			(xy 120.390975 -214.010859) (xy 120.350332 -213.980269) (xy 120.314874 -213.943796) (xy 120.285443 -213.902307)
			(xy 120.262738 -213.856787) (xy 120.2473 -213.808318) (xy 120.239494 -213.758052) (xy 120.239028 -213.732618)
			(xy 119.018304 -213.732618) (xy 119.017953 -213.755595) (xy 119.011632 -213.80111) (xy 118.999048 -213.845306)
			(xy 118.99011 -213.866476) (xy 118.980204 -213.888828) (xy 119.193818 -214.293958) (xy 119.217948 -214.29853)
			(xy 119.242867 -214.303641) (xy 119.290877 -214.320441) (xy 119.335736 -214.344419) (xy 119.376376 -214.375006)
			(xy 119.411834 -214.411476) (xy 119.441266 -214.452961) (xy 119.463973 -214.498476) (xy 119.479415 -214.54694)
			(xy 119.487227 -214.597201) (xy 119.487696 -214.622634) (xy 119.487188 -214.648521) (xy 119.479089 -214.699659)
			(xy 119.46309 -214.748899) (xy 119.439584 -214.795031) (xy 119.409152 -214.836918) (xy 119.372542 -214.873528)
			(xy 119.330655 -214.90396) (xy 119.284523 -214.927466) (xy 119.235283 -214.943465) (xy 119.184145 -214.951564)
			(xy 119.132371 -214.951564) (xy 119.081233 -214.943465) (xy 119.031993 -214.927466) (xy 118.985861 -214.90396)
			(xy 118.943974 -214.873528) (xy 118.907364 -214.836918) (xy 118.876932 -214.795031) (xy 118.853426 -214.748899)
			(xy 118.837427 -214.699659) (xy 118.829328 -214.648521) (xy 118.82882 -214.622634) (xy 118.829187 -214.599658)
			(xy 118.8355 -214.554143) (xy 118.848079 -214.509947) (xy 118.857014 -214.488776) (xy 118.86692 -214.466424)
			(xy 118.653306 -214.061294) (xy 118.629176 -214.056722) (xy 118.60425 -214.051639) (xy 118.556236 -214.034839)
			(xy 118.511375 -214.010859) (xy 118.470732 -213.980269) (xy 118.435274 -213.943796) (xy 118.405843 -213.902307)
			(xy 118.383138 -213.856787) (xy 118.3677 -213.808318) (xy 118.359894 -213.758052) (xy 118.359428 -213.732618)
			(xy 117.138704 -213.732618) (xy 117.138353 -213.755595) (xy 117.132032 -213.80111) (xy 117.119448 -213.845306)
			(xy 117.11051 -213.866476) (xy 117.100604 -213.888828) (xy 117.314218 -214.293958) (xy 117.338348 -214.29853)
			(xy 117.363267 -214.303641) (xy 117.411277 -214.320441) (xy 117.456136 -214.344419) (xy 117.496776 -214.375006)
			(xy 117.532234 -214.411476) (xy 117.561666 -214.452961) (xy 117.584373 -214.498476) (xy 117.599815 -214.54694)
			(xy 117.607627 -214.597201) (xy 117.608096 -214.622634) (xy 117.607588 -214.648521) (xy 117.599489 -214.699659)
			(xy 117.58349 -214.748899) (xy 117.559984 -214.795031) (xy 117.529552 -214.836918) (xy 117.492942 -214.873528)
			(xy 117.451055 -214.90396) (xy 117.404923 -214.927466) (xy 117.355683 -214.943465) (xy 117.304545 -214.951564)
			(xy 117.252771 -214.951564) (xy 117.201633 -214.943465) (xy 117.152393 -214.927466) (xy 117.106261 -214.90396)
			(xy 117.064374 -214.873528) (xy 117.027764 -214.836918) (xy 116.997332 -214.795031) (xy 116.973826 -214.748899)
			(xy 116.957827 -214.699659) (xy 116.949728 -214.648521) (xy 116.94922 -214.622634) (xy 116.949587 -214.599658)
			(xy 116.9559 -214.554143) (xy 116.968479 -214.509947) (xy 116.977414 -214.488776) (xy 116.98732 -214.466424)
			(xy 116.773706 -214.061294) (xy 116.749576 -214.056722) (xy 116.72465 -214.051639) (xy 116.676636 -214.034839)
			(xy 116.631775 -214.010859) (xy 116.591132 -213.980269) (xy 116.555674 -213.943796) (xy 116.526243 -213.902307)
			(xy 116.503538 -213.856787) (xy 116.4881 -213.808318) (xy 116.480294 -213.758052) (xy 116.479828 -213.732618)
			(xy 115.259104 -213.732618) (xy 115.258753 -213.755595) (xy 115.252432 -213.80111) (xy 115.239848 -213.845306)
			(xy 115.23091 -213.866476) (xy 115.221004 -213.888828) (xy 115.434618 -214.293958) (xy 115.458748 -214.29853)
			(xy 115.483667 -214.303641) (xy 115.531677 -214.320441) (xy 115.576536 -214.344419) (xy 115.617176 -214.375006)
			(xy 115.652634 -214.411476) (xy 115.682066 -214.452961) (xy 115.704773 -214.498476) (xy 115.720215 -214.54694)
			(xy 115.728027 -214.597201) (xy 115.728496 -214.622634) (xy 115.727988 -214.648521) (xy 115.719889 -214.699659)
			(xy 115.70389 -214.748899) (xy 115.680384 -214.795031) (xy 115.649952 -214.836918) (xy 115.613342 -214.873528)
			(xy 115.571455 -214.90396) (xy 115.525323 -214.927466) (xy 115.476083 -214.943465) (xy 115.424945 -214.951564)
			(xy 115.373171 -214.951564) (xy 115.322033 -214.943465) (xy 115.272793 -214.927466) (xy 115.226661 -214.90396)
			(xy 115.184774 -214.873528) (xy 115.148164 -214.836918) (xy 115.117732 -214.795031) (xy 115.094226 -214.748899)
			(xy 115.078227 -214.699659) (xy 115.070128 -214.648521) (xy 115.06962 -214.622634) (xy 115.069987 -214.599658)
			(xy 115.0763 -214.554143) (xy 115.088879 -214.509947) (xy 115.097814 -214.488776) (xy 115.10772 -214.466424)
			(xy 114.894106 -214.061294) (xy 114.869976 -214.056722) (xy 114.84505 -214.051639) (xy 114.797036 -214.034839)
			(xy 114.752175 -214.010859) (xy 114.711532 -213.980269) (xy 114.676074 -213.943796) (xy 114.646643 -213.902307)
			(xy 114.623938 -213.856787) (xy 114.6085 -213.808318) (xy 114.600694 -213.758052) (xy 114.600228 -213.732618)
			(xy 107.740704 -213.732618) (xy 107.740353 -213.755595) (xy 107.734032 -213.80111) (xy 107.721448 -213.845306)
			(xy 107.71251 -213.866476) (xy 107.702604 -213.888828) (xy 107.916218 -214.293958) (xy 107.940348 -214.29853)
			(xy 107.965267 -214.303641) (xy 108.013277 -214.320441) (xy 108.058136 -214.344419) (xy 108.098776 -214.375006)
			(xy 108.134234 -214.411476) (xy 108.163666 -214.452961) (xy 108.186373 -214.498476) (xy 108.201815 -214.54694)
			(xy 108.209627 -214.597201) (xy 108.210096 -214.622634) (xy 108.209588 -214.648521) (xy 108.201489 -214.699659)
			(xy 108.18549 -214.748899) (xy 108.161984 -214.795031) (xy 108.131552 -214.836918) (xy 108.094942 -214.873528)
			(xy 108.053055 -214.90396) (xy 108.006923 -214.927466) (xy 107.957683 -214.943465) (xy 107.906545 -214.951564)
			(xy 107.854771 -214.951564) (xy 107.803633 -214.943465) (xy 107.754393 -214.927466) (xy 107.708261 -214.90396)
			(xy 107.666374 -214.873528) (xy 107.629764 -214.836918) (xy 107.599332 -214.795031) (xy 107.575826 -214.748899)
			(xy 107.559827 -214.699659) (xy 107.551728 -214.648521) (xy 107.55122 -214.622634) (xy 107.551587 -214.599658)
			(xy 107.5579 -214.554143) (xy 107.570479 -214.509947) (xy 107.579414 -214.488776) (xy 107.58932 -214.466424)
			(xy 107.375706 -214.061294) (xy 107.351576 -214.056722) (xy 107.32665 -214.051639) (xy 107.278636 -214.034839)
			(xy 107.233775 -214.010859) (xy 107.193132 -213.980269) (xy 107.157674 -213.943796) (xy 107.128243 -213.902307)
			(xy 107.105538 -213.856787) (xy 107.0901 -213.808318) (xy 107.082294 -213.758052) (xy 107.081828 -213.732618)
			(xy 105.861104 -213.732618) (xy 105.860753 -213.755595) (xy 105.854432 -213.80111) (xy 105.841848 -213.845306)
			(xy 105.83291 -213.866476) (xy 105.823004 -213.888828) (xy 106.036618 -214.293958) (xy 106.060748 -214.29853)
			(xy 106.085667 -214.303641) (xy 106.133677 -214.320441) (xy 106.178536 -214.344419) (xy 106.219176 -214.375006)
			(xy 106.254634 -214.411476) (xy 106.284066 -214.452961) (xy 106.306773 -214.498476) (xy 106.322215 -214.54694)
			(xy 106.330027 -214.597201) (xy 106.330496 -214.622634) (xy 106.329988 -214.648521) (xy 106.321889 -214.699659)
			(xy 106.30589 -214.748899) (xy 106.282384 -214.795031) (xy 106.251952 -214.836918) (xy 106.215342 -214.873528)
			(xy 106.173455 -214.90396) (xy 106.127323 -214.927466) (xy 106.078083 -214.943465) (xy 106.026945 -214.951564)
			(xy 105.975171 -214.951564) (xy 105.924033 -214.943465) (xy 105.874793 -214.927466) (xy 105.828661 -214.90396)
			(xy 105.786774 -214.873528) (xy 105.750164 -214.836918) (xy 105.719732 -214.795031) (xy 105.696226 -214.748899)
			(xy 105.680227 -214.699659) (xy 105.672128 -214.648521) (xy 105.67162 -214.622634) (xy 105.671987 -214.599658)
			(xy 105.6783 -214.554143) (xy 105.690879 -214.509947) (xy 105.699814 -214.488776) (xy 105.70972 -214.466424)
			(xy 105.496106 -214.061294) (xy 105.471976 -214.056722) (xy 105.44705 -214.051639) (xy 105.399036 -214.034839)
			(xy 105.354175 -214.010859) (xy 105.313532 -213.980269) (xy 105.278074 -213.943796) (xy 105.248643 -213.902307)
			(xy 105.225938 -213.856787) (xy 105.2105 -213.808318) (xy 105.202694 -213.758052) (xy 105.202228 -213.732618)
			(xy 103.981504 -213.732618) (xy 103.981153 -213.755595) (xy 103.974832 -213.80111) (xy 103.962248 -213.845306)
			(xy 103.95331 -213.866476) (xy 103.943404 -213.888828) (xy 104.157018 -214.293958) (xy 104.181148 -214.29853)
			(xy 104.206067 -214.303641) (xy 104.254077 -214.320441) (xy 104.298936 -214.344419) (xy 104.339576 -214.375006)
			(xy 104.375034 -214.411476) (xy 104.404466 -214.452961) (xy 104.427173 -214.498476) (xy 104.442615 -214.54694)
			(xy 104.450427 -214.597201) (xy 104.450896 -214.622634) (xy 104.450388 -214.648521) (xy 104.442289 -214.699659)
			(xy 104.42629 -214.748899) (xy 104.402784 -214.795031) (xy 104.372352 -214.836918) (xy 104.335742 -214.873528)
			(xy 104.293855 -214.90396) (xy 104.247723 -214.927466) (xy 104.198483 -214.943465) (xy 104.147345 -214.951564)
			(xy 104.095571 -214.951564) (xy 104.044433 -214.943465) (xy 103.995193 -214.927466) (xy 103.949061 -214.90396)
			(xy 103.907174 -214.873528) (xy 103.870564 -214.836918) (xy 103.840132 -214.795031) (xy 103.816626 -214.748899)
			(xy 103.800627 -214.699659) (xy 103.792528 -214.648521) (xy 103.79202 -214.622634) (xy 103.792387 -214.599658)
			(xy 103.7987 -214.554143) (xy 103.811279 -214.509947) (xy 103.820214 -214.488776) (xy 103.83012 -214.466424)
			(xy 103.616506 -214.061294) (xy 103.592376 -214.056722) (xy 103.56745 -214.051639) (xy 103.519436 -214.034839)
			(xy 103.474575 -214.010859) (xy 103.433932 -213.980269) (xy 103.398474 -213.943796) (xy 103.369043 -213.902307)
			(xy 103.346338 -213.856787) (xy 103.3309 -213.808318) (xy 103.323094 -213.758052) (xy 103.322628 -213.732618)
			(xy 102.101904 -213.732618) (xy 102.101553 -213.755595) (xy 102.095232 -213.80111) (xy 102.082648 -213.845306)
			(xy 102.07371 -213.866476) (xy 102.063804 -213.888828) (xy 102.277418 -214.293958) (xy 102.301548 -214.29853)
			(xy 102.326467 -214.303641) (xy 102.374477 -214.320441) (xy 102.419336 -214.344419) (xy 102.459976 -214.375006)
			(xy 102.495434 -214.411476) (xy 102.524866 -214.452961) (xy 102.547573 -214.498476) (xy 102.563015 -214.54694)
			(xy 102.570827 -214.597201) (xy 102.571296 -214.622634) (xy 102.570788 -214.648521) (xy 102.562689 -214.699659)
			(xy 102.54669 -214.748899) (xy 102.523184 -214.795031) (xy 102.492752 -214.836918) (xy 102.456142 -214.873528)
			(xy 102.414255 -214.90396) (xy 102.368123 -214.927466) (xy 102.318883 -214.943465) (xy 102.267745 -214.951564)
			(xy 102.215971 -214.951564) (xy 102.164833 -214.943465) (xy 102.115593 -214.927466) (xy 102.069461 -214.90396)
			(xy 102.027574 -214.873528) (xy 101.990964 -214.836918) (xy 101.960532 -214.795031) (xy 101.937026 -214.748899)
			(xy 101.921027 -214.699659) (xy 101.912928 -214.648521) (xy 101.91242 -214.622634) (xy 101.912787 -214.599658)
			(xy 101.9191 -214.554143) (xy 101.931679 -214.509947) (xy 101.940614 -214.488776) (xy 101.95052 -214.466424)
			(xy 101.736906 -214.061294) (xy 101.712776 -214.056722) (xy 101.68785 -214.051639) (xy 101.639836 -214.034839)
			(xy 101.594975 -214.010859) (xy 101.554332 -213.980269) (xy 101.518874 -213.943796) (xy 101.489443 -213.902307)
			(xy 101.466738 -213.856787) (xy 101.4513 -213.808318) (xy 101.443494 -213.758052) (xy 101.443028 -213.732618)
			(xy 100.222304 -213.732618) (xy 100.221953 -213.755595) (xy 100.215632 -213.80111) (xy 100.203048 -213.845306)
			(xy 100.19411 -213.866476) (xy 100.184204 -213.888828) (xy 100.397818 -214.293958) (xy 100.421948 -214.29853)
			(xy 100.446867 -214.303641) (xy 100.494877 -214.320441) (xy 100.539736 -214.344419) (xy 100.580376 -214.375006)
			(xy 100.615834 -214.411476) (xy 100.645266 -214.452961) (xy 100.667973 -214.498476) (xy 100.683415 -214.54694)
			(xy 100.691227 -214.597201) (xy 100.691696 -214.622634) (xy 100.691188 -214.648521) (xy 100.683089 -214.699659)
			(xy 100.66709 -214.748899) (xy 100.643584 -214.795031) (xy 100.613152 -214.836918) (xy 100.576542 -214.873528)
			(xy 100.534655 -214.90396) (xy 100.488523 -214.927466) (xy 100.439283 -214.943465) (xy 100.388145 -214.951564)
			(xy 100.336371 -214.951564) (xy 100.285233 -214.943465) (xy 100.235993 -214.927466) (xy 100.189861 -214.90396)
			(xy 100.147974 -214.873528) (xy 100.111364 -214.836918) (xy 100.080932 -214.795031) (xy 100.057426 -214.748899)
			(xy 100.041427 -214.699659) (xy 100.033328 -214.648521) (xy 100.03282 -214.622634) (xy 100.033187 -214.599658)
			(xy 100.0395 -214.554143) (xy 100.052079 -214.509947) (xy 100.061014 -214.488776) (xy 100.07092 -214.466424)
			(xy 99.857306 -214.061294) (xy 99.833176 -214.056722) (xy 99.80825 -214.051639) (xy 99.760236 -214.034839)
			(xy 99.715375 -214.010859) (xy 99.674732 -213.980269) (xy 99.639274 -213.943796) (xy 99.609843 -213.902307)
			(xy 99.587138 -213.856787) (xy 99.5717 -213.808318) (xy 99.563894 -213.758052) (xy 99.563428 -213.732618)
			(xy 98.342704 -213.732618) (xy 98.342353 -213.755595) (xy 98.336032 -213.80111) (xy 98.323448 -213.845306)
			(xy 98.31451 -213.866476) (xy 98.304604 -213.888828) (xy 98.518218 -214.293958) (xy 98.542348 -214.29853)
			(xy 98.567267 -214.303641) (xy 98.615277 -214.320441) (xy 98.660136 -214.344419) (xy 98.700776 -214.375006)
			(xy 98.736234 -214.411476) (xy 98.765666 -214.452961) (xy 98.788373 -214.498476) (xy 98.803815 -214.54694)
			(xy 98.811627 -214.597201) (xy 98.812096 -214.622634) (xy 98.811588 -214.648521) (xy 98.803489 -214.699659)
			(xy 98.78749 -214.748899) (xy 98.763984 -214.795031) (xy 98.733552 -214.836918) (xy 98.696942 -214.873528)
			(xy 98.655055 -214.90396) (xy 98.608923 -214.927466) (xy 98.559683 -214.943465) (xy 98.508545 -214.951564)
			(xy 98.456771 -214.951564) (xy 98.405633 -214.943465) (xy 98.356393 -214.927466) (xy 98.310261 -214.90396)
			(xy 98.268374 -214.873528) (xy 98.231764 -214.836918) (xy 98.201332 -214.795031) (xy 98.177826 -214.748899)
			(xy 98.161827 -214.699659) (xy 98.153728 -214.648521) (xy 98.15322 -214.622634) (xy 98.153587 -214.599658)
			(xy 98.1599 -214.554143) (xy 98.172479 -214.509947) (xy 98.181414 -214.488776) (xy 98.19132 -214.466424)
			(xy 97.977706 -214.061294) (xy 97.953576 -214.056722) (xy 97.92865 -214.051639) (xy 97.880636 -214.034839)
			(xy 97.835775 -214.010859) (xy 97.795132 -213.980269) (xy 97.759674 -213.943796) (xy 97.730243 -213.902307)
			(xy 97.707538 -213.856787) (xy 97.6921 -213.808318) (xy 97.684294 -213.758052) (xy 97.683828 -213.732618)
			(xy 96.463104 -213.732618) (xy 96.462753 -213.755595) (xy 96.456432 -213.80111) (xy 96.443848 -213.845306)
			(xy 96.43491 -213.866476) (xy 96.425004 -213.888828) (xy 96.638618 -214.293958) (xy 96.662748 -214.29853)
			(xy 96.687667 -214.303641) (xy 96.735677 -214.320441) (xy 96.780536 -214.344419) (xy 96.821176 -214.375006)
			(xy 96.856634 -214.411476) (xy 96.886066 -214.452961) (xy 96.908773 -214.498476) (xy 96.924215 -214.54694)
			(xy 96.932027 -214.597201) (xy 96.932496 -214.622634) (xy 96.931988 -214.648521) (xy 96.923889 -214.699659)
			(xy 96.90789 -214.748899) (xy 96.884384 -214.795031) (xy 96.853952 -214.836918) (xy 96.817342 -214.873528)
			(xy 96.775455 -214.90396) (xy 96.729323 -214.927466) (xy 96.680083 -214.943465) (xy 96.628945 -214.951564)
			(xy 96.577171 -214.951564) (xy 96.526033 -214.943465) (xy 96.476793 -214.927466) (xy 96.430661 -214.90396)
			(xy 96.388774 -214.873528) (xy 96.352164 -214.836918) (xy 96.321732 -214.795031) (xy 96.298226 -214.748899)
			(xy 96.282227 -214.699659) (xy 96.274128 -214.648521) (xy 96.27362 -214.622634) (xy 96.273987 -214.599658)
			(xy 96.2803 -214.554143) (xy 96.292879 -214.509947) (xy 96.301814 -214.488776) (xy 96.31172 -214.466424)
			(xy 96.098106 -214.061294) (xy 96.073976 -214.056722) (xy 96.04905 -214.051639) (xy 96.001036 -214.034839)
			(xy 95.956175 -214.010859) (xy 95.915532 -213.980269) (xy 95.880074 -213.943796) (xy 95.850643 -213.902307)
			(xy 95.827938 -213.856787) (xy 95.8125 -213.808318) (xy 95.804694 -213.758052) (xy 95.804228 -213.732618)
			(xy 94.583504 -213.732618) (xy 94.583153 -213.755595) (xy 94.576832 -213.80111) (xy 94.564248 -213.845306)
			(xy 94.55531 -213.866476) (xy 94.545404 -213.888828) (xy 94.759018 -214.293958) (xy 94.783148 -214.29853)
			(xy 94.808067 -214.303641) (xy 94.856077 -214.320441) (xy 94.900936 -214.344419) (xy 94.941576 -214.375006)
			(xy 94.977034 -214.411476) (xy 95.006466 -214.452961) (xy 95.029173 -214.498476) (xy 95.044615 -214.54694)
			(xy 95.052427 -214.597201) (xy 95.052896 -214.622634) (xy 95.052388 -214.648521) (xy 95.044289 -214.699659)
			(xy 95.02829 -214.748899) (xy 95.004784 -214.795031) (xy 94.974352 -214.836918) (xy 94.937742 -214.873528)
			(xy 94.895855 -214.90396) (xy 94.849723 -214.927466) (xy 94.800483 -214.943465) (xy 94.749345 -214.951564)
			(xy 94.697571 -214.951564) (xy 94.646433 -214.943465) (xy 94.597193 -214.927466) (xy 94.551061 -214.90396)
			(xy 94.509174 -214.873528) (xy 94.472564 -214.836918) (xy 94.442132 -214.795031) (xy 94.418626 -214.748899)
			(xy 94.402627 -214.699659) (xy 94.394528 -214.648521) (xy 94.39402 -214.622634) (xy 94.394387 -214.599658)
			(xy 94.4007 -214.554143) (xy 94.413279 -214.509947) (xy 94.422214 -214.488776) (xy 94.43212 -214.466424)
			(xy 94.218506 -214.061294) (xy 94.194376 -214.056722) (xy 94.16945 -214.051639) (xy 94.121436 -214.034839)
			(xy 94.076575 -214.010859) (xy 94.035932 -213.980269) (xy 94.000474 -213.943796) (xy 93.971043 -213.902307)
			(xy 93.948338 -213.856787) (xy 93.9329 -213.808318) (xy 93.925094 -213.758052) (xy 93.924628 -213.732618)
			(xy 92.703904 -213.732618) (xy 92.703553 -213.755595) (xy 92.697232 -213.80111) (xy 92.684648 -213.845306)
			(xy 92.67571 -213.866476) (xy 92.665804 -213.888828) (xy 92.879418 -214.293958) (xy 92.903548 -214.29853)
			(xy 92.928467 -214.303641) (xy 92.976477 -214.320441) (xy 93.021336 -214.344419) (xy 93.061976 -214.375006)
			(xy 93.097434 -214.411476) (xy 93.126866 -214.452961) (xy 93.149573 -214.498476) (xy 93.165015 -214.54694)
			(xy 93.172827 -214.597201) (xy 93.173296 -214.622634) (xy 93.172788 -214.648521) (xy 93.164689 -214.699659)
			(xy 93.14869 -214.748899) (xy 93.125184 -214.795031) (xy 93.094752 -214.836918) (xy 93.058142 -214.873528)
			(xy 93.016255 -214.90396) (xy 92.970123 -214.927466) (xy 92.920883 -214.943465) (xy 92.869745 -214.951564)
			(xy 92.817971 -214.951564) (xy 92.766833 -214.943465) (xy 92.717593 -214.927466) (xy 92.671461 -214.90396)
			(xy 92.629574 -214.873528) (xy 92.592964 -214.836918) (xy 92.562532 -214.795031) (xy 92.539026 -214.748899)
			(xy 92.523027 -214.699659) (xy 92.514928 -214.648521) (xy 92.51442 -214.622634) (xy 92.514787 -214.599658)
			(xy 92.5211 -214.554143) (xy 92.533679 -214.509947) (xy 92.542614 -214.488776) (xy 92.55252 -214.466424)
			(xy 92.338906 -214.061294) (xy 92.314776 -214.056722) (xy 92.28985 -214.051639) (xy 92.241836 -214.034839)
			(xy 92.196975 -214.010859) (xy 92.156332 -213.980269) (xy 92.120874 -213.943796) (xy 92.091443 -213.902307)
			(xy 92.068738 -213.856787) (xy 92.0533 -213.808318) (xy 92.045494 -213.758052) (xy 92.045028 -213.732618)
			(xy 90.824304 -213.732618) (xy 90.823953 -213.755595) (xy 90.817632 -213.80111) (xy 90.805048 -213.845306)
			(xy 90.79611 -213.866476) (xy 90.786204 -213.888828) (xy 90.999818 -214.293958) (xy 91.023948 -214.29853)
			(xy 91.048867 -214.303641) (xy 91.096877 -214.320441) (xy 91.141736 -214.344419) (xy 91.182376 -214.375006)
			(xy 91.217834 -214.411476) (xy 91.247266 -214.452961) (xy 91.269973 -214.498476) (xy 91.285415 -214.54694)
			(xy 91.293227 -214.597201) (xy 91.293696 -214.622634) (xy 91.293188 -214.648521) (xy 91.285089 -214.699659)
			(xy 91.26909 -214.748899) (xy 91.245584 -214.795031) (xy 91.215152 -214.836918) (xy 91.178542 -214.873528)
			(xy 91.136655 -214.90396) (xy 91.090523 -214.927466) (xy 91.041283 -214.943465) (xy 90.990145 -214.951564)
			(xy 90.938371 -214.951564) (xy 90.887233 -214.943465) (xy 90.837993 -214.927466) (xy 90.791861 -214.90396)
			(xy 90.749974 -214.873528) (xy 90.713364 -214.836918) (xy 90.682932 -214.795031) (xy 90.659426 -214.748899)
			(xy 90.643427 -214.699659) (xy 90.635328 -214.648521) (xy 90.63482 -214.622634) (xy 90.635187 -214.599658)
			(xy 90.6415 -214.554143) (xy 90.654079 -214.509947) (xy 90.663014 -214.488776) (xy 90.67292 -214.466424)
			(xy 90.459306 -214.061294) (xy 90.435176 -214.056722) (xy 90.41025 -214.051639) (xy 90.362236 -214.034839)
			(xy 90.317375 -214.010859) (xy 90.276732 -213.980269) (xy 90.241274 -213.943796) (xy 90.211843 -213.902307)
			(xy 90.189138 -213.856787) (xy 90.1737 -213.808318) (xy 90.165894 -213.758052) (xy 90.165428 -213.732618)
			(xy 2.509012 -213.732618) (xy 2.509012 -215.436704) (xy 88.28532 -215.436704) (xy 88.285828 -215.410797)
			(xy 88.293934 -215.35962) (xy 88.309946 -215.310341) (xy 88.333469 -215.264174) (xy 88.363925 -215.222255)
			(xy 88.400563 -215.185617) (xy 88.442482 -215.155161) (xy 88.488649 -215.131638) (xy 88.537928 -215.115626)
			(xy 88.589105 -215.10752) (xy 88.640919 -215.10752) (xy 88.692096 -215.115626) (xy 88.741375 -215.131638)
			(xy 88.787542 -215.155161) (xy 88.829461 -215.185617) (xy 88.866099 -215.222255) (xy 88.896555 -215.264174)
			(xy 88.920078 -215.310341) (xy 88.93609 -215.35962) (xy 88.944196 -215.410797) (xy 88.944704 -215.436704)
			(xy 89.22512 -215.436704) (xy 89.225629 -215.41136) (xy 89.2334 -215.36127) (xy 89.248746 -215.31296)
			(xy 89.271303 -215.267567) (xy 89.300542 -215.226161) (xy 89.335773 -215.189717) (xy 89.376165 -215.159094)
			(xy 89.420769 -215.135013) (xy 89.468532 -215.118041) (xy 89.493344 -215.112854) (xy 89.516204 -215.108536)
			(xy 89.721182 -214.753444) (xy 89.713308 -214.7316) (xy 89.704729 -214.705181) (xy 89.695532 -214.650406)
			(xy 89.69502 -214.622634) (xy 89.695528 -214.596747) (xy 89.703627 -214.545609) (xy 89.719626 -214.496369)
			(xy 89.743132 -214.450237) (xy 89.773564 -214.40835) (xy 89.810174 -214.37174) (xy 89.852061 -214.341308)
			(xy 89.898193 -214.317802) (xy 89.947433 -214.301803) (xy 89.998571 -214.293704) (xy 90.050345 -214.293704)
			(xy 90.101483 -214.301803) (xy 90.150723 -214.317802) (xy 90.196855 -214.341308) (xy 90.238742 -214.37174)
			(xy 90.275352 -214.40835) (xy 90.305784 -214.450237) (xy 90.32929 -214.496369) (xy 90.345289 -214.545609)
			(xy 90.353388 -214.596747) (xy 90.353896 -214.622634) (xy 90.353447 -214.64797) (xy 90.34569 -214.698044)
			(xy 90.330363 -214.746341) (xy 90.307827 -214.791726) (xy 90.278612 -214.833128) (xy 90.243408 -214.869572)
			(xy 90.203042 -214.900202) (xy 90.158465 -214.924296) (xy 90.110727 -214.941286) (xy 90.085926 -214.946484)
			(xy 90.063066 -214.950802) (xy 89.858088 -215.305894) (xy 89.865962 -215.327738) (xy 89.87461 -215.354146)
			(xy 89.883929 -215.408922) (xy 89.884504 -215.436704) (xy 91.10472 -215.436704) (xy 91.105229 -215.41136)
			(xy 91.113 -215.36127) (xy 91.128346 -215.31296) (xy 91.150903 -215.267567) (xy 91.180142 -215.226161)
			(xy 91.215373 -215.189717) (xy 91.255765 -215.159094) (xy 91.300369 -215.135013) (xy 91.348132 -215.118041)
			(xy 91.372944 -215.112854) (xy 91.395804 -215.108536) (xy 91.600782 -214.753444) (xy 91.592908 -214.7316)
			(xy 91.584329 -214.705181) (xy 91.575132 -214.650406) (xy 91.57462 -214.622634) (xy 91.575128 -214.596747)
			(xy 91.583227 -214.545609) (xy 91.599226 -214.496369) (xy 91.622732 -214.450237) (xy 91.653164 -214.40835)
			(xy 91.689774 -214.37174) (xy 91.731661 -214.341308) (xy 91.777793 -214.317802) (xy 91.827033 -214.301803)
			(xy 91.878171 -214.293704) (xy 91.929945 -214.293704) (xy 91.981083 -214.301803) (xy 92.030323 -214.317802)
			(xy 92.076455 -214.341308) (xy 92.118342 -214.37174) (xy 92.154952 -214.40835) (xy 92.185384 -214.450237)
			(xy 92.20889 -214.496369) (xy 92.224889 -214.545609) (xy 92.232988 -214.596747) (xy 92.233496 -214.622634)
			(xy 92.233047 -214.64797) (xy 92.22529 -214.698044) (xy 92.209963 -214.746341) (xy 92.187427 -214.791726)
			(xy 92.158212 -214.833128) (xy 92.123008 -214.869572) (xy 92.082642 -214.900202) (xy 92.038065 -214.924296)
			(xy 91.990327 -214.941286) (xy 91.965526 -214.946484) (xy 91.942666 -214.950802) (xy 91.737688 -215.305894)
			(xy 91.745562 -215.327738) (xy 91.75421 -215.354146) (xy 91.763529 -215.408922) (xy 91.764104 -215.436704)
			(xy 92.98432 -215.436704) (xy 92.984829 -215.41136) (xy 92.9926 -215.36127) (xy 93.007946 -215.31296)
			(xy 93.030503 -215.267567) (xy 93.059742 -215.226161) (xy 93.094973 -215.189717) (xy 93.135365 -215.159094)
			(xy 93.179969 -215.135013) (xy 93.227732 -215.118041) (xy 93.252544 -215.112854) (xy 93.275404 -215.108536)
			(xy 93.480382 -214.753444) (xy 93.472508 -214.7316) (xy 93.463929 -214.705181) (xy 93.454732 -214.650406)
			(xy 93.45422 -214.622634) (xy 93.454728 -214.596747) (xy 93.462827 -214.545609) (xy 93.478826 -214.496369)
			(xy 93.502332 -214.450237) (xy 93.532764 -214.40835) (xy 93.569374 -214.37174) (xy 93.611261 -214.341308)
			(xy 93.657393 -214.317802) (xy 93.706633 -214.301803) (xy 93.757771 -214.293704) (xy 93.809545 -214.293704)
			(xy 93.860683 -214.301803) (xy 93.909923 -214.317802) (xy 93.956055 -214.341308) (xy 93.997942 -214.37174)
			(xy 94.034552 -214.40835) (xy 94.064984 -214.450237) (xy 94.08849 -214.496369) (xy 94.104489 -214.545609)
			(xy 94.112588 -214.596747) (xy 94.113096 -214.622634) (xy 94.112647 -214.64797) (xy 94.10489 -214.698044)
			(xy 94.089563 -214.746341) (xy 94.067027 -214.791726) (xy 94.037812 -214.833128) (xy 94.002608 -214.869572)
			(xy 93.962242 -214.900202) (xy 93.917665 -214.924296) (xy 93.869927 -214.941286) (xy 93.845126 -214.946484)
			(xy 93.822266 -214.950802) (xy 93.617288 -215.305894) (xy 93.625162 -215.327738) (xy 93.63381 -215.354146)
			(xy 93.643129 -215.408922) (xy 93.643704 -215.436704) (xy 94.86392 -215.436704) (xy 94.864429 -215.41136)
			(xy 94.8722 -215.36127) (xy 94.887546 -215.31296) (xy 94.910103 -215.267567) (xy 94.939342 -215.226161)
			(xy 94.974573 -215.189717) (xy 95.014965 -215.159094) (xy 95.059569 -215.135013) (xy 95.107332 -215.118041)
			(xy 95.132144 -215.112854) (xy 95.155004 -215.108536) (xy 95.359982 -214.753444) (xy 95.352108 -214.7316)
			(xy 95.343529 -214.705181) (xy 95.334332 -214.650406) (xy 95.33382 -214.622634) (xy 95.334328 -214.596747)
			(xy 95.342427 -214.545609) (xy 95.358426 -214.496369) (xy 95.381932 -214.450237) (xy 95.412364 -214.40835)
			(xy 95.448974 -214.37174) (xy 95.490861 -214.341308) (xy 95.536993 -214.317802) (xy 95.586233 -214.301803)
			(xy 95.637371 -214.293704) (xy 95.689145 -214.293704) (xy 95.740283 -214.301803) (xy 95.789523 -214.317802)
			(xy 95.835655 -214.341308) (xy 95.877542 -214.37174) (xy 95.914152 -214.40835) (xy 95.944584 -214.450237)
			(xy 95.96809 -214.496369) (xy 95.984089 -214.545609) (xy 95.992188 -214.596747) (xy 95.992696 -214.622634)
			(xy 95.992247 -214.64797) (xy 95.98449 -214.698044) (xy 95.969163 -214.746341) (xy 95.946627 -214.791726)
			(xy 95.917412 -214.833128) (xy 95.882208 -214.869572) (xy 95.841842 -214.900202) (xy 95.797265 -214.924296)
			(xy 95.749527 -214.941286) (xy 95.724726 -214.946484) (xy 95.701866 -214.950802) (xy 95.496888 -215.305894)
			(xy 95.504762 -215.327738) (xy 95.51341 -215.354146) (xy 95.522729 -215.408922) (xy 95.523304 -215.436704)
			(xy 96.74352 -215.436704) (xy 96.744029 -215.41136) (xy 96.7518 -215.36127) (xy 96.767146 -215.31296)
			(xy 96.789703 -215.267567) (xy 96.818942 -215.226161) (xy 96.854173 -215.189717) (xy 96.894565 -215.159094)
			(xy 96.939169 -215.135013) (xy 96.986932 -215.118041) (xy 97.011744 -215.112854) (xy 97.034604 -215.108536)
			(xy 97.239582 -214.753444) (xy 97.231708 -214.7316) (xy 97.223129 -214.705181) (xy 97.213932 -214.650406)
			(xy 97.21342 -214.622634) (xy 97.213928 -214.596747) (xy 97.222027 -214.545609) (xy 97.238026 -214.496369)
			(xy 97.261532 -214.450237) (xy 97.291964 -214.40835) (xy 97.328574 -214.37174) (xy 97.370461 -214.341308)
			(xy 97.416593 -214.317802) (xy 97.465833 -214.301803) (xy 97.516971 -214.293704) (xy 97.568745 -214.293704)
			(xy 97.619883 -214.301803) (xy 97.669123 -214.317802) (xy 97.715255 -214.341308) (xy 97.757142 -214.37174)
			(xy 97.793752 -214.40835) (xy 97.824184 -214.450237) (xy 97.84769 -214.496369) (xy 97.863689 -214.545609)
			(xy 97.871788 -214.596747) (xy 97.872296 -214.622634) (xy 97.871847 -214.64797) (xy 97.86409 -214.698044)
			(xy 97.848763 -214.746341) (xy 97.826227 -214.791726) (xy 97.797012 -214.833128) (xy 97.761808 -214.869572)
			(xy 97.721442 -214.900202) (xy 97.676865 -214.924296) (xy 97.629127 -214.941286) (xy 97.604326 -214.946484)
			(xy 97.581466 -214.950802) (xy 97.376488 -215.305894) (xy 97.384362 -215.327738) (xy 97.39301 -215.354146)
			(xy 97.402329 -215.408922) (xy 97.402904 -215.436704) (xy 98.62312 -215.436704) (xy 98.623629 -215.41136)
			(xy 98.6314 -215.36127) (xy 98.646746 -215.31296) (xy 98.669303 -215.267567) (xy 98.698542 -215.226161)
			(xy 98.733773 -215.189717) (xy 98.774165 -215.159094) (xy 98.818769 -215.135013) (xy 98.866532 -215.118041)
			(xy 98.891344 -215.112854) (xy 98.914204 -215.108536) (xy 99.119182 -214.753444) (xy 99.111308 -214.7316)
			(xy 99.102729 -214.705181) (xy 99.093532 -214.650406) (xy 99.09302 -214.622634) (xy 99.093528 -214.596747)
			(xy 99.101627 -214.545609) (xy 99.117626 -214.496369) (xy 99.141132 -214.450237) (xy 99.171564 -214.40835)
			(xy 99.208174 -214.37174) (xy 99.250061 -214.341308) (xy 99.296193 -214.317802) (xy 99.345433 -214.301803)
			(xy 99.396571 -214.293704) (xy 99.448345 -214.293704) (xy 99.499483 -214.301803) (xy 99.548723 -214.317802)
			(xy 99.594855 -214.341308) (xy 99.636742 -214.37174) (xy 99.673352 -214.40835) (xy 99.703784 -214.450237)
			(xy 99.72729 -214.496369) (xy 99.743289 -214.545609) (xy 99.751388 -214.596747) (xy 99.751896 -214.622634)
			(xy 99.751447 -214.64797) (xy 99.74369 -214.698044) (xy 99.728363 -214.746341) (xy 99.705827 -214.791726)
			(xy 99.676612 -214.833128) (xy 99.641408 -214.869572) (xy 99.601042 -214.900202) (xy 99.556465 -214.924296)
			(xy 99.508727 -214.941286) (xy 99.483926 -214.946484) (xy 99.461066 -214.950802) (xy 99.256088 -215.305894)
			(xy 99.263962 -215.327738) (xy 99.27261 -215.354146) (xy 99.281929 -215.408922) (xy 99.282504 -215.436704)
			(xy 100.50272 -215.436704) (xy 100.503229 -215.41136) (xy 100.511 -215.36127) (xy 100.526346 -215.31296)
			(xy 100.548903 -215.267567) (xy 100.578142 -215.226161) (xy 100.613373 -215.189717) (xy 100.653765 -215.159094)
			(xy 100.698369 -215.135013) (xy 100.746132 -215.118041) (xy 100.770944 -215.112854) (xy 100.793804 -215.108536)
			(xy 100.998782 -214.753444) (xy 100.990908 -214.7316) (xy 100.982329 -214.705181) (xy 100.973132 -214.650406)
			(xy 100.97262 -214.622634) (xy 100.973128 -214.596747) (xy 100.981227 -214.545609) (xy 100.997226 -214.496369)
			(xy 101.020732 -214.450237) (xy 101.051164 -214.40835) (xy 101.087774 -214.37174) (xy 101.129661 -214.341308)
			(xy 101.175793 -214.317802) (xy 101.225033 -214.301803) (xy 101.276171 -214.293704) (xy 101.327945 -214.293704)
			(xy 101.379083 -214.301803) (xy 101.428323 -214.317802) (xy 101.474455 -214.341308) (xy 101.516342 -214.37174)
			(xy 101.552952 -214.40835) (xy 101.583384 -214.450237) (xy 101.60689 -214.496369) (xy 101.622889 -214.545609)
			(xy 101.630988 -214.596747) (xy 101.631496 -214.622634) (xy 101.631047 -214.64797) (xy 101.62329 -214.698044)
			(xy 101.607963 -214.746341) (xy 101.585427 -214.791726) (xy 101.556212 -214.833128) (xy 101.521008 -214.869572)
			(xy 101.480642 -214.900202) (xy 101.436065 -214.924296) (xy 101.388327 -214.941286) (xy 101.363526 -214.946484)
			(xy 101.340666 -214.950802) (xy 101.135688 -215.305894) (xy 101.143562 -215.327738) (xy 101.15221 -215.354146)
			(xy 101.161529 -215.408922) (xy 101.162104 -215.436704) (xy 102.38232 -215.436704) (xy 102.382829 -215.41136)
			(xy 102.3906 -215.36127) (xy 102.405946 -215.31296) (xy 102.428503 -215.267567) (xy 102.457742 -215.226161)
			(xy 102.492973 -215.189717) (xy 102.533365 -215.159094) (xy 102.577969 -215.135013) (xy 102.625732 -215.118041)
			(xy 102.650544 -215.112854) (xy 102.673404 -215.108536) (xy 102.878382 -214.753444) (xy 102.870508 -214.7316)
			(xy 102.861929 -214.705181) (xy 102.852732 -214.650406) (xy 102.85222 -214.622634) (xy 102.852728 -214.596747)
			(xy 102.860827 -214.545609) (xy 102.876826 -214.496369) (xy 102.900332 -214.450237) (xy 102.930764 -214.40835)
			(xy 102.967374 -214.37174) (xy 103.009261 -214.341308) (xy 103.055393 -214.317802) (xy 103.104633 -214.301803)
			(xy 103.155771 -214.293704) (xy 103.207545 -214.293704) (xy 103.258683 -214.301803) (xy 103.307923 -214.317802)
			(xy 103.354055 -214.341308) (xy 103.395942 -214.37174) (xy 103.432552 -214.40835) (xy 103.462984 -214.450237)
			(xy 103.48649 -214.496369) (xy 103.502489 -214.545609) (xy 103.510588 -214.596747) (xy 103.511096 -214.622634)
			(xy 103.510647 -214.64797) (xy 103.50289 -214.698044) (xy 103.487563 -214.746341) (xy 103.465027 -214.791726)
			(xy 103.435812 -214.833128) (xy 103.400608 -214.869572) (xy 103.360242 -214.900202) (xy 103.315665 -214.924296)
			(xy 103.267927 -214.941286) (xy 103.243126 -214.946484) (xy 103.220266 -214.950802) (xy 103.015288 -215.305894)
			(xy 103.023162 -215.327738) (xy 103.03181 -215.354146) (xy 103.041129 -215.408922) (xy 103.041704 -215.436704)
			(xy 104.26192 -215.436704) (xy 104.262429 -215.41136) (xy 104.2702 -215.36127) (xy 104.285546 -215.31296)
			(xy 104.308103 -215.267567) (xy 104.337342 -215.226161) (xy 104.372573 -215.189717) (xy 104.412965 -215.159094)
			(xy 104.457569 -215.135013) (xy 104.505332 -215.118041) (xy 104.530144 -215.112854) (xy 104.553004 -215.108536)
			(xy 104.757982 -214.753444) (xy 104.750108 -214.7316) (xy 104.741529 -214.705181) (xy 104.732332 -214.650406)
			(xy 104.73182 -214.622634) (xy 104.732328 -214.596747) (xy 104.740427 -214.545609) (xy 104.756426 -214.496369)
			(xy 104.779932 -214.450237) (xy 104.810364 -214.40835) (xy 104.846974 -214.37174) (xy 104.888861 -214.341308)
			(xy 104.934993 -214.317802) (xy 104.984233 -214.301803) (xy 105.035371 -214.293704) (xy 105.087145 -214.293704)
			(xy 105.138283 -214.301803) (xy 105.187523 -214.317802) (xy 105.233655 -214.341308) (xy 105.275542 -214.37174)
			(xy 105.312152 -214.40835) (xy 105.342584 -214.450237) (xy 105.36609 -214.496369) (xy 105.382089 -214.545609)
			(xy 105.390188 -214.596747) (xy 105.390696 -214.622634) (xy 105.390247 -214.64797) (xy 105.38249 -214.698044)
			(xy 105.367163 -214.746341) (xy 105.344627 -214.791726) (xy 105.315412 -214.833128) (xy 105.280208 -214.869572)
			(xy 105.239842 -214.900202) (xy 105.195265 -214.924296) (xy 105.147527 -214.941286) (xy 105.122726 -214.946484)
			(xy 105.099866 -214.950802) (xy 104.894888 -215.305894) (xy 104.902762 -215.327738) (xy 104.91141 -215.354146)
			(xy 104.920729 -215.408922) (xy 104.921304 -215.436704) (xy 106.14152 -215.436704) (xy 106.142029 -215.41136)
			(xy 106.1498 -215.36127) (xy 106.165146 -215.31296) (xy 106.187703 -215.267567) (xy 106.216942 -215.226161)
			(xy 106.252173 -215.189717) (xy 106.292565 -215.159094) (xy 106.337169 -215.135013) (xy 106.384932 -215.118041)
			(xy 106.409744 -215.112854) (xy 106.432604 -215.108536) (xy 106.637582 -214.753444) (xy 106.629708 -214.7316)
			(xy 106.621129 -214.705181) (xy 106.611932 -214.650406) (xy 106.61142 -214.622634) (xy 106.611928 -214.596747)
			(xy 106.620027 -214.545609) (xy 106.636026 -214.496369) (xy 106.659532 -214.450237) (xy 106.689964 -214.40835)
			(xy 106.726574 -214.37174) (xy 106.768461 -214.341308) (xy 106.814593 -214.317802) (xy 106.863833 -214.301803)
			(xy 106.914971 -214.293704) (xy 106.966745 -214.293704) (xy 107.017883 -214.301803) (xy 107.067123 -214.317802)
			(xy 107.113255 -214.341308) (xy 107.155142 -214.37174) (xy 107.191752 -214.40835) (xy 107.222184 -214.450237)
			(xy 107.24569 -214.496369) (xy 107.261689 -214.545609) (xy 107.269788 -214.596747) (xy 107.270296 -214.622634)
			(xy 107.269847 -214.64797) (xy 107.26209 -214.698044) (xy 107.246763 -214.746341) (xy 107.224227 -214.791726)
			(xy 107.195012 -214.833128) (xy 107.159808 -214.869572) (xy 107.119442 -214.900202) (xy 107.074865 -214.924296)
			(xy 107.027127 -214.941286) (xy 107.002326 -214.946484) (xy 106.979466 -214.950802) (xy 106.774488 -215.305894)
			(xy 106.782362 -215.327738) (xy 106.79101 -215.354146) (xy 106.800329 -215.408922) (xy 106.800904 -215.436704)
			(xy 108.02112 -215.436704) (xy 108.021629 -215.41136) (xy 108.0294 -215.36127) (xy 108.044746 -215.31296)
			(xy 108.067303 -215.267567) (xy 108.096542 -215.226161) (xy 108.131773 -215.189717) (xy 108.172165 -215.159094)
			(xy 108.216769 -215.135013) (xy 108.264532 -215.118041) (xy 108.289344 -215.112854) (xy 108.312204 -215.108536)
			(xy 108.517182 -214.753444) (xy 108.509308 -214.7316) (xy 108.500729 -214.705181) (xy 108.491532 -214.650406)
			(xy 108.49102 -214.622634) (xy 108.491528 -214.596747) (xy 108.499627 -214.545609) (xy 108.515626 -214.496369)
			(xy 108.539132 -214.450237) (xy 108.569564 -214.40835) (xy 108.606174 -214.37174) (xy 108.648061 -214.341308)
			(xy 108.694193 -214.317802) (xy 108.743433 -214.301803) (xy 108.794571 -214.293704) (xy 108.846345 -214.293704)
			(xy 108.897483 -214.301803) (xy 108.946723 -214.317802) (xy 108.992855 -214.341308) (xy 109.034742 -214.37174)
			(xy 109.071352 -214.40835) (xy 109.101784 -214.450237) (xy 109.12529 -214.496369) (xy 109.141289 -214.545609)
			(xy 109.14142 -214.546434) (xy 110.371128 -214.546434) (xy 110.371636 -214.520547) (xy 110.379735 -214.469409)
			(xy 110.395734 -214.420169) (xy 110.41924 -214.374037) (xy 110.449672 -214.33215) (xy 110.486282 -214.29554)
			(xy 110.528169 -214.265108) (xy 110.574301 -214.241602) (xy 110.623541 -214.225603) (xy 110.674679 -214.217504)
			(xy 110.726453 -214.217504) (xy 110.777591 -214.225603) (xy 110.826831 -214.241602) (xy 110.872963 -214.265108)
			(xy 110.91485 -214.29554) (xy 110.95146 -214.33215) (xy 110.981892 -214.374037) (xy 111.005398 -214.420169)
			(xy 111.021397 -214.469409) (xy 111.029496 -214.520547) (xy 111.030004 -214.546434) (xy 111.030004 -214.546942)
			(xy 111.029596 -214.56979) (xy 111.029246 -214.572283) (xy 112.250803 -214.572283) (xy 112.250803 -214.520517)
			(xy 112.258901 -214.469389) (xy 112.274896 -214.420157) (xy 112.298395 -214.374033) (xy 112.32882 -214.332153)
			(xy 112.365421 -214.295547) (xy 112.407297 -214.265117) (xy 112.453418 -214.241612) (xy 112.502648 -214.22561)
			(xy 112.553775 -214.217507) (xy 112.579658 -214.216996) (xy 112.605169 -214.217509) (xy 112.655581 -214.225363)
			(xy 112.704182 -214.24089) (xy 112.749811 -214.263719) (xy 112.791377 -214.293306) (xy 112.827889 -214.328944)
			(xy 112.843564 -214.349076) (xy 113.255552 -214.349076) (xy 113.271247 -214.328958) (xy 113.307753 -214.293314)
			(xy 113.349314 -214.263719) (xy 113.394938 -214.24088) (xy 113.443536 -214.225342) (xy 113.493947 -214.217476)
			(xy 113.519458 -214.216996) (xy 113.545352 -214.217406) (xy 113.596504 -214.225502) (xy 113.645759 -214.2415)
			(xy 113.691905 -214.265008) (xy 113.733805 -214.295445) (xy 113.770428 -214.332063) (xy 113.80087 -214.373959)
			(xy 113.824384 -214.420102) (xy 113.840388 -214.469355) (xy 113.848491 -214.520506) (xy 113.848491 -214.572294)
			(xy 113.840388 -214.623445) (xy 113.824384 -214.672698) (xy 113.80087 -214.718841) (xy 113.770428 -214.760737)
			(xy 113.733805 -214.797355) (xy 113.691905 -214.827792) (xy 113.645759 -214.8513) (xy 113.596504 -214.867298)
			(xy 113.545352 -214.875394) (xy 113.519458 -214.875872) (xy 113.493944 -214.875433) (xy 113.443527 -214.867566)
			(xy 113.394925 -214.852025) (xy 113.349296 -214.829181) (xy 113.307732 -214.799581) (xy 113.271224 -214.763931)
			(xy 113.255552 -214.743792) (xy 112.843564 -214.743792) (xy 112.827909 -214.763943) (xy 112.791396 -214.799586)
			(xy 112.749827 -214.829178) (xy 112.704195 -214.852012) (xy 112.655589 -214.867542) (xy 112.605171 -214.875398)
			(xy 112.579658 -214.875872) (xy 112.553775 -214.875293) (xy 112.502648 -214.86719) (xy 112.453418 -214.851188)
			(xy 112.407297 -214.827683) (xy 112.365421 -214.797253) (xy 112.32882 -214.760647) (xy 112.298395 -214.718767)
			(xy 112.274896 -214.672643) (xy 112.258901 -214.623411) (xy 112.250803 -214.572283) (xy 111.029246 -214.572283)
			(xy 111.023246 -214.615045) (xy 111.010702 -214.658987) (xy 111.00181 -214.680038) (xy 110.991904 -214.702644)
			(xy 111.205772 -215.108028) (xy 111.229902 -215.1126) (xy 111.254835 -215.117694) (xy 111.302873 -215.134477)
			(xy 111.347761 -215.158443) (xy 111.388433 -215.189024) (xy 111.423922 -215.225492) (xy 111.453384 -215.266981)
			(xy 111.47612 -215.312505) (xy 111.491589 -215.360982) (xy 111.499424 -215.411261) (xy 111.499904 -215.436704)
			(xy 113.65992 -215.436704) (xy 113.660429 -215.41136) (xy 113.6682 -215.36127) (xy 113.683546 -215.31296)
			(xy 113.706103 -215.267567) (xy 113.735342 -215.226161) (xy 113.770573 -215.189717) (xy 113.810965 -215.159094)
			(xy 113.855569 -215.135013) (xy 113.903332 -215.118041) (xy 113.928144 -215.112854) (xy 113.951004 -215.108536)
			(xy 114.156236 -214.753444) (xy 114.148362 -214.731346) (xy 114.139733 -214.704999) (xy 114.130411 -214.650352)
			(xy 114.12982 -214.622634) (xy 114.130328 -214.596727) (xy 114.138434 -214.54555) (xy 114.154446 -214.496271)
			(xy 114.177969 -214.450104) (xy 114.208425 -214.408185) (xy 114.245063 -214.371547) (xy 114.286982 -214.341091)
			(xy 114.333149 -214.317568) (xy 114.382428 -214.301556) (xy 114.433605 -214.29345) (xy 114.485419 -214.29345)
			(xy 114.536596 -214.301556) (xy 114.585875 -214.317568) (xy 114.632042 -214.341091) (xy 114.673961 -214.371547)
			(xy 114.710599 -214.408185) (xy 114.741055 -214.450104) (xy 114.764578 -214.496271) (xy 114.78059 -214.54555)
			(xy 114.788696 -214.596727) (xy 114.789204 -214.622634) (xy 114.78871 -214.647978) (xy 114.780934 -214.698068)
			(xy 114.765584 -214.746377) (xy 114.743024 -214.791769) (xy 114.713783 -214.833174) (xy 114.678552 -214.869617)
			(xy 114.638158 -214.90024) (xy 114.593555 -214.924322) (xy 114.545792 -214.941296) (xy 114.52098 -214.946484)
			(xy 114.49812 -214.950802) (xy 114.292888 -215.305894) (xy 114.300762 -215.327992) (xy 114.309397 -215.354337)
			(xy 114.318716 -215.408986) (xy 114.319304 -215.436704) (xy 115.53952 -215.436704) (xy 115.540029 -215.41136)
			(xy 115.5478 -215.36127) (xy 115.563146 -215.31296) (xy 115.585703 -215.267567) (xy 115.614942 -215.226161)
			(xy 115.650173 -215.189717) (xy 115.690565 -215.159094) (xy 115.735169 -215.135013) (xy 115.782932 -215.118041)
			(xy 115.807744 -215.112854) (xy 115.830604 -215.108536) (xy 116.035582 -214.753444) (xy 116.027708 -214.7316)
			(xy 116.019129 -214.705181) (xy 116.009932 -214.650406) (xy 116.00942 -214.622634) (xy 116.009928 -214.596747)
			(xy 116.018027 -214.545609) (xy 116.034026 -214.496369) (xy 116.057532 -214.450237) (xy 116.087964 -214.40835)
			(xy 116.124574 -214.37174) (xy 116.166461 -214.341308) (xy 116.212593 -214.317802) (xy 116.261833 -214.301803)
			(xy 116.312971 -214.293704) (xy 116.364745 -214.293704) (xy 116.415883 -214.301803) (xy 116.465123 -214.317802)
			(xy 116.511255 -214.341308) (xy 116.553142 -214.37174) (xy 116.589752 -214.40835) (xy 116.620184 -214.450237)
			(xy 116.64369 -214.496369) (xy 116.659689 -214.545609) (xy 116.667788 -214.596747) (xy 116.668296 -214.622634)
			(xy 116.667847 -214.64797) (xy 116.66009 -214.698044) (xy 116.644763 -214.746341) (xy 116.622227 -214.791726)
			(xy 116.593012 -214.833128) (xy 116.557808 -214.869572) (xy 116.517442 -214.900202) (xy 116.472865 -214.924296)
			(xy 116.425127 -214.941286) (xy 116.400326 -214.946484) (xy 116.377466 -214.950802) (xy 116.172488 -215.305894)
			(xy 116.180362 -215.327738) (xy 116.18901 -215.354146) (xy 116.198329 -215.408922) (xy 116.198904 -215.436704)
			(xy 117.41912 -215.436704) (xy 117.419629 -215.41136) (xy 117.4274 -215.36127) (xy 117.442746 -215.31296)
			(xy 117.465303 -215.267567) (xy 117.494542 -215.226161) (xy 117.529773 -215.189717) (xy 117.570165 -215.159094)
			(xy 117.614769 -215.135013) (xy 117.662532 -215.118041) (xy 117.687344 -215.112854) (xy 117.710204 -215.108536)
			(xy 117.915182 -214.753444) (xy 117.907308 -214.7316) (xy 117.898729 -214.705181) (xy 117.889532 -214.650406)
			(xy 117.88902 -214.622634) (xy 117.889528 -214.596747) (xy 117.897627 -214.545609) (xy 117.913626 -214.496369)
			(xy 117.937132 -214.450237) (xy 117.967564 -214.40835) (xy 118.004174 -214.37174) (xy 118.046061 -214.341308)
			(xy 118.092193 -214.317802) (xy 118.141433 -214.301803) (xy 118.192571 -214.293704) (xy 118.244345 -214.293704)
			(xy 118.295483 -214.301803) (xy 118.344723 -214.317802) (xy 118.390855 -214.341308) (xy 118.432742 -214.37174)
			(xy 118.469352 -214.40835) (xy 118.499784 -214.450237) (xy 118.52329 -214.496369) (xy 118.539289 -214.545609)
			(xy 118.547388 -214.596747) (xy 118.547896 -214.622634) (xy 118.547447 -214.64797) (xy 118.53969 -214.698044)
			(xy 118.524363 -214.746341) (xy 118.501827 -214.791726) (xy 118.472612 -214.833128) (xy 118.437408 -214.869572)
			(xy 118.397042 -214.900202) (xy 118.352465 -214.924296) (xy 118.304727 -214.941286) (xy 118.279926 -214.946484)
			(xy 118.257066 -214.950802) (xy 118.052088 -215.305894) (xy 118.059962 -215.327738) (xy 118.06861 -215.354146)
			(xy 118.077929 -215.408922) (xy 118.078504 -215.436704) (xy 119.29872 -215.436704) (xy 119.299229 -215.41136)
			(xy 119.307 -215.36127) (xy 119.322346 -215.31296) (xy 119.344903 -215.267567) (xy 119.374142 -215.226161)
			(xy 119.409373 -215.189717) (xy 119.449765 -215.159094) (xy 119.494369 -215.135013) (xy 119.542132 -215.118041)
			(xy 119.566944 -215.112854) (xy 119.589804 -215.108536) (xy 119.794782 -214.753444) (xy 119.786908 -214.7316)
			(xy 119.778329 -214.705181) (xy 119.769132 -214.650406) (xy 119.76862 -214.622634) (xy 119.769128 -214.596747)
			(xy 119.777227 -214.545609) (xy 119.793226 -214.496369) (xy 119.816732 -214.450237) (xy 119.847164 -214.40835)
			(xy 119.883774 -214.37174) (xy 119.925661 -214.341308) (xy 119.971793 -214.317802) (xy 120.021033 -214.301803)
			(xy 120.072171 -214.293704) (xy 120.123945 -214.293704) (xy 120.175083 -214.301803) (xy 120.224323 -214.317802)
			(xy 120.270455 -214.341308) (xy 120.312342 -214.37174) (xy 120.348952 -214.40835) (xy 120.379384 -214.450237)
			(xy 120.40289 -214.496369) (xy 120.418889 -214.545609) (xy 120.426988 -214.596747) (xy 120.427496 -214.622634)
			(xy 120.427047 -214.64797) (xy 120.41929 -214.698044) (xy 120.403963 -214.746341) (xy 120.381427 -214.791726)
			(xy 120.352212 -214.833128) (xy 120.317008 -214.869572) (xy 120.276642 -214.900202) (xy 120.232065 -214.924296)
			(xy 120.184327 -214.941286) (xy 120.159526 -214.946484) (xy 120.136666 -214.950802) (xy 119.931688 -215.305894)
			(xy 119.939562 -215.327738) (xy 119.94821 -215.354146) (xy 119.957529 -215.408922) (xy 119.958104 -215.436704)
			(xy 121.17832 -215.436704) (xy 121.178829 -215.41136) (xy 121.1866 -215.36127) (xy 121.201946 -215.31296)
			(xy 121.224503 -215.267567) (xy 121.253742 -215.226161) (xy 121.288973 -215.189717) (xy 121.329365 -215.159094)
			(xy 121.373969 -215.135013) (xy 121.421732 -215.118041) (xy 121.446544 -215.112854) (xy 121.469404 -215.108536)
			(xy 121.674382 -214.753444) (xy 121.666508 -214.7316) (xy 121.657929 -214.705181) (xy 121.648732 -214.650406)
			(xy 121.64822 -214.622634) (xy 121.648728 -214.596747) (xy 121.656827 -214.545609) (xy 121.672826 -214.496369)
			(xy 121.696332 -214.450237) (xy 121.726764 -214.40835) (xy 121.763374 -214.37174) (xy 121.805261 -214.341308)
			(xy 121.851393 -214.317802) (xy 121.900633 -214.301803) (xy 121.951771 -214.293704) (xy 122.003545 -214.293704)
			(xy 122.054683 -214.301803) (xy 122.103923 -214.317802) (xy 122.150055 -214.341308) (xy 122.191942 -214.37174)
			(xy 122.228552 -214.40835) (xy 122.258984 -214.450237) (xy 122.28249 -214.496369) (xy 122.298489 -214.545609)
			(xy 122.306588 -214.596747) (xy 122.307096 -214.622634) (xy 122.306647 -214.64797) (xy 122.29889 -214.698044)
			(xy 122.283563 -214.746341) (xy 122.261027 -214.791726) (xy 122.231812 -214.833128) (xy 122.196608 -214.869572)
			(xy 122.156242 -214.900202) (xy 122.111665 -214.924296) (xy 122.063927 -214.941286) (xy 122.039126 -214.946484)
			(xy 122.016266 -214.950802) (xy 121.811288 -215.305894) (xy 121.819162 -215.327738) (xy 121.82781 -215.354146)
			(xy 121.837129 -215.408922) (xy 121.837704 -215.436704) (xy 123.05792 -215.436704) (xy 123.058429 -215.41136)
			(xy 123.0662 -215.36127) (xy 123.081546 -215.31296) (xy 123.104103 -215.267567) (xy 123.133342 -215.226161)
			(xy 123.168573 -215.189717) (xy 123.208965 -215.159094) (xy 123.253569 -215.135013) (xy 123.301332 -215.118041)
			(xy 123.326144 -215.112854) (xy 123.349004 -215.108536) (xy 123.553982 -214.753444) (xy 123.546108 -214.7316)
			(xy 123.537529 -214.705181) (xy 123.528332 -214.650406) (xy 123.52782 -214.622634) (xy 123.528328 -214.596747)
			(xy 123.536427 -214.545609) (xy 123.552426 -214.496369) (xy 123.575932 -214.450237) (xy 123.606364 -214.40835)
			(xy 123.642974 -214.37174) (xy 123.684861 -214.341308) (xy 123.730993 -214.317802) (xy 123.780233 -214.301803)
			(xy 123.831371 -214.293704) (xy 123.883145 -214.293704) (xy 123.934283 -214.301803) (xy 123.983523 -214.317802)
			(xy 124.029655 -214.341308) (xy 124.071542 -214.37174) (xy 124.108152 -214.40835) (xy 124.138584 -214.450237)
			(xy 124.16209 -214.496369) (xy 124.178089 -214.545609) (xy 124.186188 -214.596747) (xy 124.186696 -214.622634)
			(xy 124.186247 -214.64797) (xy 124.17849 -214.698044) (xy 124.163163 -214.746341) (xy 124.140627 -214.791726)
			(xy 124.111412 -214.833128) (xy 124.076208 -214.869572) (xy 124.035842 -214.900202) (xy 123.991265 -214.924296)
			(xy 123.943527 -214.941286) (xy 123.918726 -214.946484) (xy 123.895866 -214.950802) (xy 123.690888 -215.305894)
			(xy 123.698762 -215.327738) (xy 123.70741 -215.354146) (xy 123.716729 -215.408922) (xy 123.717304 -215.436704)
			(xy 124.93752 -215.436704) (xy 124.938029 -215.41136) (xy 124.9458 -215.36127) (xy 124.961146 -215.31296)
			(xy 124.983703 -215.267567) (xy 125.012942 -215.226161) (xy 125.048173 -215.189717) (xy 125.088565 -215.159094)
			(xy 125.133169 -215.135013) (xy 125.180932 -215.118041) (xy 125.205744 -215.112854) (xy 125.228604 -215.108536)
			(xy 125.433582 -214.753444) (xy 125.425708 -214.7316) (xy 125.417129 -214.705181) (xy 125.407932 -214.650406)
			(xy 125.40742 -214.622634) (xy 125.407928 -214.596747) (xy 125.416027 -214.545609) (xy 125.432026 -214.496369)
			(xy 125.455532 -214.450237) (xy 125.485964 -214.40835) (xy 125.522574 -214.37174) (xy 125.564461 -214.341308)
			(xy 125.610593 -214.317802) (xy 125.659833 -214.301803) (xy 125.710971 -214.293704) (xy 125.762745 -214.293704)
			(xy 125.813883 -214.301803) (xy 125.863123 -214.317802) (xy 125.909255 -214.341308) (xy 125.951142 -214.37174)
			(xy 125.987752 -214.40835) (xy 126.018184 -214.450237) (xy 126.04169 -214.496369) (xy 126.057689 -214.545609)
			(xy 126.065788 -214.596747) (xy 126.066296 -214.622634) (xy 126.065847 -214.64797) (xy 126.05809 -214.698044)
			(xy 126.042763 -214.746341) (xy 126.020227 -214.791726) (xy 125.991012 -214.833128) (xy 125.955808 -214.869572)
			(xy 125.915442 -214.900202) (xy 125.870865 -214.924296) (xy 125.823127 -214.941286) (xy 125.798326 -214.946484)
			(xy 125.775466 -214.950802) (xy 125.570488 -215.305894) (xy 125.578362 -215.327738) (xy 125.58701 -215.354146)
			(xy 125.596329 -215.408922) (xy 125.596904 -215.436704) (xy 126.81712 -215.436704) (xy 126.817629 -215.41136)
			(xy 126.8254 -215.36127) (xy 126.840746 -215.31296) (xy 126.863303 -215.267567) (xy 126.892542 -215.226161)
			(xy 126.927773 -215.189717) (xy 126.968165 -215.159094) (xy 127.012769 -215.135013) (xy 127.060532 -215.118041)
			(xy 127.085344 -215.112854) (xy 127.108204 -215.108536) (xy 127.313182 -214.753444) (xy 127.305308 -214.7316)
			(xy 127.296729 -214.705181) (xy 127.287532 -214.650406) (xy 127.28702 -214.622634) (xy 127.287528 -214.596747)
			(xy 127.295627 -214.545609) (xy 127.311626 -214.496369) (xy 127.335132 -214.450237) (xy 127.365564 -214.40835)
			(xy 127.402174 -214.37174) (xy 127.444061 -214.341308) (xy 127.490193 -214.317802) (xy 127.539433 -214.301803)
			(xy 127.590571 -214.293704) (xy 127.642345 -214.293704) (xy 127.693483 -214.301803) (xy 127.742723 -214.317802)
			(xy 127.788855 -214.341308) (xy 127.830742 -214.37174) (xy 127.867352 -214.40835) (xy 127.897784 -214.450237)
			(xy 127.92129 -214.496369) (xy 127.937289 -214.545609) (xy 127.945388 -214.596747) (xy 127.945896 -214.622634)
			(xy 127.945447 -214.64797) (xy 127.93769 -214.698044) (xy 127.922363 -214.746341) (xy 127.899827 -214.791726)
			(xy 127.870612 -214.833128) (xy 127.835408 -214.869572) (xy 127.795042 -214.900202) (xy 127.750465 -214.924296)
			(xy 127.702727 -214.941286) (xy 127.677926 -214.946484) (xy 127.655066 -214.950802) (xy 127.450088 -215.305894)
			(xy 127.457962 -215.327738) (xy 127.46661 -215.354146) (xy 127.475929 -215.408922) (xy 127.476504 -215.436704)
			(xy 128.69672 -215.436704) (xy 128.697229 -215.41136) (xy 128.705 -215.36127) (xy 128.720346 -215.31296)
			(xy 128.742903 -215.267567) (xy 128.772142 -215.226161) (xy 128.807373 -215.189717) (xy 128.847765 -215.159094)
			(xy 128.892369 -215.135013) (xy 128.940132 -215.118041) (xy 128.964944 -215.112854) (xy 128.987804 -215.108536)
			(xy 129.192782 -214.753444) (xy 129.184908 -214.7316) (xy 129.176329 -214.705181) (xy 129.167132 -214.650406)
			(xy 129.16662 -214.622634) (xy 129.167128 -214.596747) (xy 129.175227 -214.545609) (xy 129.191226 -214.496369)
			(xy 129.214732 -214.450237) (xy 129.245164 -214.40835) (xy 129.281774 -214.37174) (xy 129.323661 -214.341308)
			(xy 129.369793 -214.317802) (xy 129.419033 -214.301803) (xy 129.470171 -214.293704) (xy 129.521945 -214.293704)
			(xy 129.573083 -214.301803) (xy 129.622323 -214.317802) (xy 129.668455 -214.341308) (xy 129.710342 -214.37174)
			(xy 129.746952 -214.40835) (xy 129.777384 -214.450237) (xy 129.80089 -214.496369) (xy 129.816889 -214.545609)
			(xy 129.824988 -214.596747) (xy 129.825496 -214.622634) (xy 129.825047 -214.64797) (xy 129.81729 -214.698044)
			(xy 129.801963 -214.746341) (xy 129.779427 -214.791726) (xy 129.750212 -214.833128) (xy 129.715008 -214.869572)
			(xy 129.674642 -214.900202) (xy 129.630065 -214.924296) (xy 129.582327 -214.941286) (xy 129.557526 -214.946484)
			(xy 129.534666 -214.950802) (xy 129.329688 -215.305894) (xy 129.337562 -215.327738) (xy 129.34621 -215.354146)
			(xy 129.355529 -215.408922) (xy 129.356104 -215.436704) (xy 130.57632 -215.436704) (xy 130.576829 -215.41136)
			(xy 130.5846 -215.36127) (xy 130.599946 -215.31296) (xy 130.622503 -215.267567) (xy 130.651742 -215.226161)
			(xy 130.686973 -215.189717) (xy 130.727365 -215.159094) (xy 130.771969 -215.135013) (xy 130.819732 -215.118041)
			(xy 130.844544 -215.112854) (xy 130.867404 -215.108536) (xy 131.072382 -214.753444) (xy 131.064508 -214.7316)
			(xy 131.055929 -214.705181) (xy 131.046732 -214.650406) (xy 131.04622 -214.622634) (xy 131.046728 -214.596747)
			(xy 131.054827 -214.545609) (xy 131.070826 -214.496369) (xy 131.094332 -214.450237) (xy 131.124764 -214.40835)
			(xy 131.161374 -214.37174) (xy 131.203261 -214.341308) (xy 131.249393 -214.317802) (xy 131.298633 -214.301803)
			(xy 131.349771 -214.293704) (xy 131.401545 -214.293704) (xy 131.452683 -214.301803) (xy 131.501923 -214.317802)
			(xy 131.548055 -214.341308) (xy 131.589942 -214.37174) (xy 131.626552 -214.40835) (xy 131.656984 -214.450237)
			(xy 131.68049 -214.496369) (xy 131.696489 -214.545609) (xy 131.704588 -214.596747) (xy 131.705096 -214.622634)
			(xy 131.704647 -214.64797) (xy 131.69689 -214.698044) (xy 131.681563 -214.746341) (xy 131.659027 -214.791726)
			(xy 131.629812 -214.833128) (xy 131.594608 -214.869572) (xy 131.554242 -214.900202) (xy 131.509665 -214.924296)
			(xy 131.461927 -214.941286) (xy 131.437126 -214.946484) (xy 131.414266 -214.950802) (xy 131.209288 -215.305894)
			(xy 131.217162 -215.327738) (xy 131.22581 -215.354146) (xy 131.235129 -215.408922) (xy 131.235704 -215.436704)
			(xy 132.45592 -215.436704) (xy 132.456429 -215.41136) (xy 132.4642 -215.36127) (xy 132.479546 -215.31296)
			(xy 132.502103 -215.267567) (xy 132.531342 -215.226161) (xy 132.566573 -215.189717) (xy 132.606965 -215.159094)
			(xy 132.651569 -215.135013) (xy 132.699332 -215.118041) (xy 132.724144 -215.112854) (xy 132.747004 -215.108536)
			(xy 132.951982 -214.753444) (xy 132.944108 -214.7316) (xy 132.935529 -214.705181) (xy 132.926332 -214.650406)
			(xy 132.92582 -214.622634) (xy 132.926328 -214.596747) (xy 132.934427 -214.545609) (xy 132.950426 -214.496369)
			(xy 132.973932 -214.450237) (xy 133.004364 -214.40835) (xy 133.040974 -214.37174) (xy 133.082861 -214.341308)
			(xy 133.128993 -214.317802) (xy 133.178233 -214.301803) (xy 133.229371 -214.293704) (xy 133.281145 -214.293704)
			(xy 133.332283 -214.301803) (xy 133.381523 -214.317802) (xy 133.427655 -214.341308) (xy 133.469542 -214.37174)
			(xy 133.506152 -214.40835) (xy 133.536584 -214.450237) (xy 133.56009 -214.496369) (xy 133.576089 -214.545609)
			(xy 133.57622 -214.546434) (xy 134.80542 -214.546434) (xy 134.805928 -214.520527) (xy 134.814034 -214.46935)
			(xy 134.830046 -214.420071) (xy 134.853569 -214.373904) (xy 134.884025 -214.331985) (xy 134.920663 -214.295347)
			(xy 134.962582 -214.264891) (xy 135.008749 -214.241368) (xy 135.058028 -214.225356) (xy 135.109205 -214.21725)
			(xy 135.161019 -214.21725) (xy 135.212196 -214.225356) (xy 135.261475 -214.241368) (xy 135.307642 -214.264891)
			(xy 135.349561 -214.295347) (xy 135.386199 -214.331985) (xy 135.416655 -214.373904) (xy 135.440178 -214.420071)
			(xy 135.45619 -214.46935) (xy 135.464296 -214.520527) (xy 135.464804 -214.546434) (xy 135.464102 -214.577275)
			(xy 135.452589 -214.637875) (xy 135.441944 -214.66683) (xy 135.433308 -214.688674) (xy 135.656066 -215.110314)
			(xy 135.678672 -215.115394) (xy 135.702597 -215.121362) (xy 135.748484 -215.139404) (xy 135.791171 -215.164081)
			(xy 135.829706 -215.194841) (xy 135.863229 -215.230999) (xy 135.890992 -215.271747) (xy 135.912374 -215.316176)
			(xy 135.9269 -215.363294) (xy 135.934244 -215.412051) (xy 135.934704 -215.436704) (xy 336.225388 -215.436704)
			(xy 336.225896 -215.410797) (xy 336.234002 -215.35962) (xy 336.250014 -215.310341) (xy 336.273537 -215.264174)
			(xy 336.303993 -215.222255) (xy 336.340631 -215.185617) (xy 336.38255 -215.155161) (xy 336.428717 -215.131638)
			(xy 336.477996 -215.115626) (xy 336.529173 -215.10752) (xy 336.580987 -215.10752) (xy 336.632164 -215.115626)
			(xy 336.681443 -215.131638) (xy 336.72761 -215.155161) (xy 336.769529 -215.185617) (xy 336.806167 -215.222255)
			(xy 336.836623 -215.264174) (xy 336.860146 -215.310341) (xy 336.876158 -215.35962) (xy 336.884264 -215.410797)
			(xy 336.884772 -215.436704) (xy 337.165188 -215.436704) (xy 337.165723 -215.411361) (xy 337.173493 -215.361274)
			(xy 337.188837 -215.312966) (xy 337.211392 -215.267575) (xy 337.240627 -215.226169) (xy 337.275854 -215.189725)
			(xy 337.316243 -215.159101) (xy 337.360842 -215.135018) (xy 337.408601 -215.118043) (xy 337.433412 -215.112854)
			(xy 337.456272 -215.108536) (xy 337.66125 -214.753444) (xy 337.653376 -214.7316) (xy 337.644799 -214.705181)
			(xy 337.6356 -214.650406) (xy 337.635088 -214.622634) (xy 337.635596 -214.596747) (xy 337.643695 -214.545609)
			(xy 337.659694 -214.496369) (xy 337.6832 -214.450237) (xy 337.713632 -214.40835) (xy 337.750242 -214.37174)
			(xy 337.792129 -214.341308) (xy 337.838261 -214.317802) (xy 337.887501 -214.301803) (xy 337.938639 -214.293704)
			(xy 337.990413 -214.293704) (xy 338.041551 -214.301803) (xy 338.090791 -214.317802) (xy 338.136923 -214.341308)
			(xy 338.17881 -214.37174) (xy 338.21542 -214.40835) (xy 338.245852 -214.450237) (xy 338.269358 -214.496369)
			(xy 338.285357 -214.545609) (xy 338.293456 -214.596747) (xy 338.293964 -214.622634) (xy 338.293541 -214.647971)
			(xy 338.285783 -214.698047) (xy 338.270454 -214.746347) (xy 338.247915 -214.791733) (xy 338.218698 -214.833136)
			(xy 338.18349 -214.869581) (xy 338.14312 -214.90021) (xy 338.098539 -214.924301) (xy 338.050797 -214.941288)
			(xy 338.025994 -214.946484) (xy 338.003134 -214.950802) (xy 337.798156 -215.305894) (xy 337.80603 -215.327738)
			(xy 337.814677 -215.354146) (xy 337.823997 -215.408922) (xy 337.824572 -215.436704) (xy 339.044788 -215.436704)
			(xy 339.045323 -215.411361) (xy 339.053093 -215.361274) (xy 339.068437 -215.312966) (xy 339.090992 -215.267575)
			(xy 339.120227 -215.226169) (xy 339.155454 -215.189725) (xy 339.195843 -215.159101) (xy 339.240442 -215.135018)
			(xy 339.288201 -215.118043) (xy 339.313012 -215.112854) (xy 339.335872 -215.108536) (xy 339.54085 -214.753444)
			(xy 339.532976 -214.7316) (xy 339.524399 -214.705181) (xy 339.5152 -214.650406) (xy 339.514688 -214.622634)
			(xy 339.515196 -214.596747) (xy 339.523295 -214.545609) (xy 339.539294 -214.496369) (xy 339.5628 -214.450237)
			(xy 339.593232 -214.40835) (xy 339.629842 -214.37174) (xy 339.671729 -214.341308) (xy 339.717861 -214.317802)
			(xy 339.767101 -214.301803) (xy 339.818239 -214.293704) (xy 339.870013 -214.293704) (xy 339.921151 -214.301803)
			(xy 339.970391 -214.317802) (xy 340.016523 -214.341308) (xy 340.05841 -214.37174) (xy 340.09502 -214.40835)
			(xy 340.125452 -214.450237) (xy 340.148958 -214.496369) (xy 340.164957 -214.545609) (xy 340.173056 -214.596747)
			(xy 340.173564 -214.622634) (xy 340.173141 -214.647971) (xy 340.165383 -214.698047) (xy 340.150054 -214.746347)
			(xy 340.127515 -214.791733) (xy 340.098298 -214.833136) (xy 340.06309 -214.869581) (xy 340.02272 -214.90021)
			(xy 339.978139 -214.924301) (xy 339.930397 -214.941288) (xy 339.905594 -214.946484) (xy 339.882734 -214.950802)
			(xy 339.677756 -215.305894) (xy 339.68563 -215.327738) (xy 339.694277 -215.354146) (xy 339.703597 -215.408922)
			(xy 339.704172 -215.436704) (xy 340.924388 -215.436704) (xy 340.924923 -215.411361) (xy 340.932693 -215.361274)
			(xy 340.948037 -215.312966) (xy 340.970592 -215.267575) (xy 340.999827 -215.226169) (xy 341.035054 -215.189725)
			(xy 341.075443 -215.159101) (xy 341.120042 -215.135018) (xy 341.167801 -215.118043) (xy 341.192612 -215.112854)
			(xy 341.215472 -215.108536) (xy 341.42045 -214.753444) (xy 341.412576 -214.7316) (xy 341.403999 -214.705181)
			(xy 341.3948 -214.650406) (xy 341.394288 -214.622634) (xy 341.394796 -214.596747) (xy 341.402895 -214.545609)
			(xy 341.418894 -214.496369) (xy 341.4424 -214.450237) (xy 341.472832 -214.40835) (xy 341.509442 -214.37174)
			(xy 341.551329 -214.341308) (xy 341.597461 -214.317802) (xy 341.646701 -214.301803) (xy 341.697839 -214.293704)
			(xy 341.749613 -214.293704) (xy 341.800751 -214.301803) (xy 341.849991 -214.317802) (xy 341.896123 -214.341308)
			(xy 341.93801 -214.37174) (xy 341.97462 -214.40835) (xy 342.005052 -214.450237) (xy 342.028558 -214.496369)
			(xy 342.044557 -214.545609) (xy 342.052656 -214.596747) (xy 342.053164 -214.622634) (xy 342.052741 -214.647971)
			(xy 342.044983 -214.698047) (xy 342.029654 -214.746347) (xy 342.007115 -214.791733) (xy 341.977898 -214.833136)
			(xy 341.94269 -214.869581) (xy 341.90232 -214.90021) (xy 341.857739 -214.924301) (xy 341.809997 -214.941288)
			(xy 341.785194 -214.946484) (xy 341.762334 -214.950802) (xy 341.557356 -215.305894) (xy 341.56523 -215.327738)
			(xy 341.573877 -215.354146) (xy 341.583197 -215.408922) (xy 341.583772 -215.436704) (xy 342.803988 -215.436704)
			(xy 342.804523 -215.411361) (xy 342.812293 -215.361274) (xy 342.827637 -215.312966) (xy 342.850192 -215.267575)
			(xy 342.879427 -215.226169) (xy 342.914654 -215.189725) (xy 342.955043 -215.159101) (xy 342.999642 -215.135018)
			(xy 343.047401 -215.118043) (xy 343.072212 -215.112854) (xy 343.095072 -215.108536) (xy 343.30005 -214.753444)
			(xy 343.292176 -214.7316) (xy 343.283599 -214.705181) (xy 343.2744 -214.650406) (xy 343.273888 -214.622634)
			(xy 343.274396 -214.596747) (xy 343.282495 -214.545609) (xy 343.298494 -214.496369) (xy 343.322 -214.450237)
			(xy 343.352432 -214.40835) (xy 343.389042 -214.37174) (xy 343.430929 -214.341308) (xy 343.477061 -214.317802)
			(xy 343.526301 -214.301803) (xy 343.577439 -214.293704) (xy 343.629213 -214.293704) (xy 343.680351 -214.301803)
			(xy 343.729591 -214.317802) (xy 343.775723 -214.341308) (xy 343.81761 -214.37174) (xy 343.85422 -214.40835)
			(xy 343.884652 -214.450237) (xy 343.908158 -214.496369) (xy 343.924157 -214.545609) (xy 343.932256 -214.596747)
			(xy 343.932764 -214.622634) (xy 343.932341 -214.647971) (xy 343.924583 -214.698047) (xy 343.909254 -214.746347)
			(xy 343.886715 -214.791733) (xy 343.857498 -214.833136) (xy 343.82229 -214.869581) (xy 343.78192 -214.90021)
			(xy 343.737339 -214.924301) (xy 343.689597 -214.941288) (xy 343.664794 -214.946484) (xy 343.641934 -214.950802)
			(xy 343.436956 -215.305894) (xy 343.44483 -215.327738) (xy 343.453477 -215.354146) (xy 343.462797 -215.408922)
			(xy 343.463372 -215.436704) (xy 344.683588 -215.436704) (xy 344.684123 -215.411361) (xy 344.691893 -215.361274)
			(xy 344.707237 -215.312966) (xy 344.729792 -215.267575) (xy 344.759027 -215.226169) (xy 344.794254 -215.189725)
			(xy 344.834643 -215.159101) (xy 344.879242 -215.135018) (xy 344.927001 -215.118043) (xy 344.951812 -215.112854)
			(xy 344.974672 -215.108536) (xy 345.17965 -214.753444) (xy 345.171776 -214.7316) (xy 345.163199 -214.705181)
			(xy 345.154 -214.650406) (xy 345.153488 -214.622634) (xy 345.153996 -214.596747) (xy 345.162095 -214.545609)
			(xy 345.178094 -214.496369) (xy 345.2016 -214.450237) (xy 345.232032 -214.40835) (xy 345.268642 -214.37174)
			(xy 345.310529 -214.341308) (xy 345.356661 -214.317802) (xy 345.405901 -214.301803) (xy 345.457039 -214.293704)
			(xy 345.508813 -214.293704) (xy 345.559951 -214.301803) (xy 345.609191 -214.317802) (xy 345.655323 -214.341308)
			(xy 345.69721 -214.37174) (xy 345.73382 -214.40835) (xy 345.764252 -214.450237) (xy 345.787758 -214.496369)
			(xy 345.803757 -214.545609) (xy 345.811856 -214.596747) (xy 345.812364 -214.622634) (xy 345.811941 -214.647971)
			(xy 345.804183 -214.698047) (xy 345.788854 -214.746347) (xy 345.766315 -214.791733) (xy 345.737098 -214.833136)
			(xy 345.70189 -214.869581) (xy 345.66152 -214.90021) (xy 345.616939 -214.924301) (xy 345.569197 -214.941288)
			(xy 345.544394 -214.946484) (xy 345.521534 -214.950802) (xy 345.316556 -215.305894) (xy 345.32443 -215.327738)
			(xy 345.333077 -215.354146) (xy 345.342397 -215.408922) (xy 345.342972 -215.436704) (xy 346.563188 -215.436704)
			(xy 346.563723 -215.411361) (xy 346.571493 -215.361274) (xy 346.586837 -215.312966) (xy 346.609392 -215.267575)
			(xy 346.638627 -215.226169) (xy 346.673854 -215.189725) (xy 346.714243 -215.159101) (xy 346.758842 -215.135018)
			(xy 346.806601 -215.118043) (xy 346.831412 -215.112854) (xy 346.854272 -215.108536) (xy 347.05925 -214.753444)
			(xy 347.051376 -214.7316) (xy 347.042799 -214.705181) (xy 347.0336 -214.650406) (xy 347.033088 -214.622634)
			(xy 347.033596 -214.596747) (xy 347.041695 -214.545609) (xy 347.057694 -214.496369) (xy 347.0812 -214.450237)
			(xy 347.111632 -214.40835) (xy 347.148242 -214.37174) (xy 347.190129 -214.341308) (xy 347.236261 -214.317802)
			(xy 347.285501 -214.301803) (xy 347.336639 -214.293704) (xy 347.388413 -214.293704) (xy 347.439551 -214.301803)
			(xy 347.488791 -214.317802) (xy 347.534923 -214.341308) (xy 347.57681 -214.37174) (xy 347.61342 -214.40835)
			(xy 347.643852 -214.450237) (xy 347.667358 -214.496369) (xy 347.683357 -214.545609) (xy 347.691456 -214.596747)
			(xy 347.691964 -214.622634) (xy 347.691541 -214.647971) (xy 347.683783 -214.698047) (xy 347.668454 -214.746347)
			(xy 347.645915 -214.791733) (xy 347.616698 -214.833136) (xy 347.58149 -214.869581) (xy 347.54112 -214.90021)
			(xy 347.496539 -214.924301) (xy 347.448797 -214.941288) (xy 347.423994 -214.946484) (xy 347.401134 -214.950802)
			(xy 347.196156 -215.305894) (xy 347.20403 -215.327738) (xy 347.212677 -215.354146) (xy 347.221997 -215.408922)
			(xy 347.222572 -215.436704) (xy 348.442788 -215.436704) (xy 348.443323 -215.411361) (xy 348.451093 -215.361274)
			(xy 348.466437 -215.312966) (xy 348.488992 -215.267575) (xy 348.518227 -215.226169) (xy 348.553454 -215.189725)
			(xy 348.593843 -215.159101) (xy 348.638442 -215.135018) (xy 348.686201 -215.118043) (xy 348.711012 -215.112854)
			(xy 348.733872 -215.108536) (xy 348.93885 -214.753444) (xy 348.930976 -214.7316) (xy 348.922399 -214.705181)
			(xy 348.9132 -214.650406) (xy 348.912688 -214.622634) (xy 348.913196 -214.596747) (xy 348.921295 -214.545609)
			(xy 348.937294 -214.496369) (xy 348.9608 -214.450237) (xy 348.991232 -214.40835) (xy 349.027842 -214.37174)
			(xy 349.069729 -214.341308) (xy 349.115861 -214.317802) (xy 349.165101 -214.301803) (xy 349.216239 -214.293704)
			(xy 349.268013 -214.293704) (xy 349.319151 -214.301803) (xy 349.368391 -214.317802) (xy 349.414523 -214.341308)
			(xy 349.45641 -214.37174) (xy 349.49302 -214.40835) (xy 349.523452 -214.450237) (xy 349.546958 -214.496369)
			(xy 349.562957 -214.545609) (xy 349.571056 -214.596747) (xy 349.571564 -214.622634) (xy 349.571141 -214.647971)
			(xy 349.563383 -214.698047) (xy 349.548054 -214.746347) (xy 349.525515 -214.791733) (xy 349.496298 -214.833136)
			(xy 349.46109 -214.869581) (xy 349.42072 -214.90021) (xy 349.376139 -214.924301) (xy 349.328397 -214.941288)
			(xy 349.303594 -214.946484) (xy 349.280734 -214.950802) (xy 349.075756 -215.305894) (xy 349.08363 -215.327738)
			(xy 349.092277 -215.354146) (xy 349.101597 -215.408922) (xy 349.102172 -215.436704) (xy 350.322388 -215.436704)
			(xy 350.322923 -215.411361) (xy 350.330693 -215.361274) (xy 350.346037 -215.312966) (xy 350.368592 -215.267575)
			(xy 350.397827 -215.226169) (xy 350.433054 -215.189725) (xy 350.473443 -215.159101) (xy 350.518042 -215.135018)
			(xy 350.565801 -215.118043) (xy 350.590612 -215.112854) (xy 350.613472 -215.108536) (xy 350.81845 -214.753444)
			(xy 350.810576 -214.7316) (xy 350.801999 -214.705181) (xy 350.7928 -214.650406) (xy 350.792288 -214.622634)
			(xy 350.792796 -214.596747) (xy 350.800895 -214.545609) (xy 350.816894 -214.496369) (xy 350.8404 -214.450237)
			(xy 350.870832 -214.40835) (xy 350.907442 -214.37174) (xy 350.949329 -214.341308) (xy 350.995461 -214.317802)
			(xy 351.044701 -214.301803) (xy 351.095839 -214.293704) (xy 351.147613 -214.293704) (xy 351.198751 -214.301803)
			(xy 351.247991 -214.317802) (xy 351.294123 -214.341308) (xy 351.33601 -214.37174) (xy 351.37262 -214.40835)
			(xy 351.403052 -214.450237) (xy 351.426558 -214.496369) (xy 351.442557 -214.545609) (xy 351.450656 -214.596747)
			(xy 351.451164 -214.622634) (xy 351.450741 -214.647971) (xy 351.442983 -214.698047) (xy 351.427654 -214.746347)
			(xy 351.405115 -214.791733) (xy 351.375898 -214.833136) (xy 351.34069 -214.869581) (xy 351.30032 -214.90021)
			(xy 351.255739 -214.924301) (xy 351.207997 -214.941288) (xy 351.183194 -214.946484) (xy 351.160334 -214.950802)
			(xy 350.955356 -215.305894) (xy 350.96323 -215.327738) (xy 350.971877 -215.354146) (xy 350.981197 -215.408922)
			(xy 350.981772 -215.436704) (xy 352.201988 -215.436704) (xy 352.202523 -215.411361) (xy 352.210293 -215.361274)
			(xy 352.225637 -215.312966) (xy 352.248192 -215.267575) (xy 352.277427 -215.226169) (xy 352.312654 -215.189725)
			(xy 352.353043 -215.159101) (xy 352.397642 -215.135018) (xy 352.445401 -215.118043) (xy 352.470212 -215.112854)
			(xy 352.493072 -215.108536) (xy 352.69805 -214.753444) (xy 352.690176 -214.7316) (xy 352.681599 -214.705181)
			(xy 352.6724 -214.650406) (xy 352.671888 -214.622634) (xy 352.672396 -214.596747) (xy 352.680495 -214.545609)
			(xy 352.696494 -214.496369) (xy 352.72 -214.450237) (xy 352.750432 -214.40835) (xy 352.787042 -214.37174)
			(xy 352.828929 -214.341308) (xy 352.875061 -214.317802) (xy 352.924301 -214.301803) (xy 352.975439 -214.293704)
			(xy 353.027213 -214.293704) (xy 353.078351 -214.301803) (xy 353.127591 -214.317802) (xy 353.173723 -214.341308)
			(xy 353.21561 -214.37174) (xy 353.25222 -214.40835) (xy 353.282652 -214.450237) (xy 353.306158 -214.496369)
			(xy 353.322157 -214.545609) (xy 353.330256 -214.596747) (xy 353.330764 -214.622634) (xy 353.330341 -214.647971)
			(xy 353.322583 -214.698047) (xy 353.307254 -214.746347) (xy 353.284715 -214.791733) (xy 353.255498 -214.833136)
			(xy 353.22029 -214.869581) (xy 353.17992 -214.90021) (xy 353.135339 -214.924301) (xy 353.087597 -214.941288)
			(xy 353.062794 -214.946484) (xy 353.039934 -214.950802) (xy 352.834956 -215.305894) (xy 352.84283 -215.327738)
			(xy 352.851477 -215.354146) (xy 352.860797 -215.408922) (xy 352.861372 -215.436704) (xy 354.081588 -215.436704)
			(xy 354.082123 -215.411361) (xy 354.089893 -215.361274) (xy 354.105237 -215.312966) (xy 354.127792 -215.267575)
			(xy 354.157027 -215.226169) (xy 354.192254 -215.189725) (xy 354.232643 -215.159101) (xy 354.277242 -215.135018)
			(xy 354.325001 -215.118043) (xy 354.349812 -215.112854) (xy 354.372672 -215.108536) (xy 354.57765 -214.753444)
			(xy 354.569776 -214.7316) (xy 354.561199 -214.705181) (xy 354.552 -214.650406) (xy 354.551488 -214.622634)
			(xy 354.551996 -214.596747) (xy 354.560095 -214.545609) (xy 354.576094 -214.496369) (xy 354.5996 -214.450237)
			(xy 354.630032 -214.40835) (xy 354.666642 -214.37174) (xy 354.708529 -214.341308) (xy 354.754661 -214.317802)
			(xy 354.803901 -214.301803) (xy 354.855039 -214.293704) (xy 354.906813 -214.293704) (xy 354.957951 -214.301803)
			(xy 355.007191 -214.317802) (xy 355.053323 -214.341308) (xy 355.09521 -214.37174) (xy 355.13182 -214.40835)
			(xy 355.162252 -214.450237) (xy 355.185758 -214.496369) (xy 355.201757 -214.545609) (xy 355.209856 -214.596747)
			(xy 355.210364 -214.622634) (xy 355.209941 -214.647971) (xy 355.202183 -214.698047) (xy 355.186854 -214.746347)
			(xy 355.164315 -214.791733) (xy 355.135098 -214.833136) (xy 355.09989 -214.869581) (xy 355.05952 -214.90021)
			(xy 355.014939 -214.924301) (xy 354.967197 -214.941288) (xy 354.942394 -214.946484) (xy 354.919534 -214.950802)
			(xy 354.714556 -215.305894) (xy 354.72243 -215.327738) (xy 354.731077 -215.354146) (xy 354.740397 -215.408922)
			(xy 354.740972 -215.436704) (xy 355.961188 -215.436704) (xy 355.961723 -215.411361) (xy 355.969493 -215.361274)
			(xy 355.984837 -215.312966) (xy 356.007392 -215.267575) (xy 356.036627 -215.226169) (xy 356.071854 -215.189725)
			(xy 356.112243 -215.159101) (xy 356.156842 -215.135018) (xy 356.204601 -215.118043) (xy 356.229412 -215.112854)
			(xy 356.252272 -215.108536) (xy 356.45725 -214.753444) (xy 356.449376 -214.7316) (xy 356.440799 -214.705181)
			(xy 356.4316 -214.650406) (xy 356.431088 -214.622634) (xy 356.431596 -214.596747) (xy 356.439695 -214.545609)
			(xy 356.455694 -214.496369) (xy 356.4792 -214.450237) (xy 356.509632 -214.40835) (xy 356.546242 -214.37174)
			(xy 356.588129 -214.341308) (xy 356.634261 -214.317802) (xy 356.683501 -214.301803) (xy 356.734639 -214.293704)
			(xy 356.786413 -214.293704) (xy 356.837551 -214.301803) (xy 356.886791 -214.317802) (xy 356.932923 -214.341308)
			(xy 356.97481 -214.37174) (xy 357.01142 -214.40835) (xy 357.041852 -214.450237) (xy 357.065358 -214.496369)
			(xy 357.081357 -214.545609) (xy 357.089456 -214.596747) (xy 357.089964 -214.622634) (xy 358.310688 -214.622634)
			(xy 358.311196 -214.596747) (xy 358.319295 -214.545609) (xy 358.335294 -214.496369) (xy 358.3588 -214.450237)
			(xy 358.389232 -214.40835) (xy 358.425842 -214.37174) (xy 358.467729 -214.341308) (xy 358.513861 -214.317802)
			(xy 358.563101 -214.301803) (xy 358.614239 -214.293704) (xy 358.666013 -214.293704) (xy 358.717151 -214.301803)
			(xy 358.766391 -214.317802) (xy 358.812523 -214.341308) (xy 358.85441 -214.37174) (xy 358.89102 -214.40835)
			(xy 358.921452 -214.450237) (xy 358.944958 -214.496369) (xy 358.960957 -214.545609) (xy 358.969056 -214.596747)
			(xy 358.969564 -214.622634) (xy 358.969564 -214.623142) (xy 358.968984 -214.650659) (xy 358.959791 -214.70492)
			(xy 358.951276 -214.731092) (xy 358.943656 -214.75319) (xy 359.148888 -215.108536) (xy 359.171748 -215.112854)
			(xy 359.196559 -215.118062) (xy 359.244336 -215.135013) (xy 359.288953 -215.15908) (xy 359.329358 -215.189696)
			(xy 359.364599 -215.226137) (xy 359.393844 -215.267545) (xy 359.416403 -215.312943) (xy 359.431745 -215.36126)
			(xy 359.439507 -215.411357) (xy 359.439972 -215.436704) (xy 359.439464 -215.462611) (xy 359.431358 -215.513788)
			(xy 359.415346 -215.563067) (xy 359.391823 -215.609234) (xy 359.361367 -215.651153) (xy 359.324729 -215.687791)
			(xy 359.28281 -215.718247) (xy 359.236643 -215.74177) (xy 359.187364 -215.757782) (xy 359.136187 -215.765888)
			(xy 359.084373 -215.765888) (xy 359.033196 -215.757782) (xy 358.983917 -215.74177) (xy 358.93775 -215.718247)
			(xy 358.895831 -215.687791) (xy 358.859193 -215.651153) (xy 358.828737 -215.609234) (xy 358.805214 -215.563067)
			(xy 358.789202 -215.513788) (xy 358.781096 -215.462611) (xy 358.780588 -215.436704) (xy 358.781184 -215.408987)
			(xy 358.790506 -215.35434) (xy 358.79913 -215.327992) (xy 358.80675 -215.306148) (xy 358.601772 -214.950802)
			(xy 358.578912 -214.946484) (xy 358.554096 -214.941291) (xy 358.506315 -214.924344) (xy 358.461694 -214.900279)
			(xy 358.421285 -214.869663) (xy 358.386043 -214.833219) (xy 358.356798 -214.791807) (xy 358.33424 -214.746405)
			(xy 358.318903 -214.698083) (xy 358.311148 -214.647983) (xy 358.310688 -214.622634) (xy 357.089964 -214.622634)
			(xy 357.089541 -214.647971) (xy 357.081783 -214.698047) (xy 357.066454 -214.746347) (xy 357.043915 -214.791733)
			(xy 357.014698 -214.833136) (xy 356.97949 -214.869581) (xy 356.93912 -214.90021) (xy 356.894539 -214.924301)
			(xy 356.846797 -214.941288) (xy 356.821994 -214.946484) (xy 356.799134 -214.950802) (xy 356.594156 -215.305894)
			(xy 356.60203 -215.327738) (xy 356.610677 -215.354146) (xy 356.619997 -215.408922) (xy 356.620572 -215.436704)
			(xy 356.620064 -215.462606) (xy 356.90152 -215.462606) (xy 356.90152 -215.410794) (xy 356.909625 -215.35962)
			(xy 356.925635 -215.310344) (xy 356.949157 -215.264178) (xy 356.97961 -215.222261) (xy 357.016246 -215.185623)
			(xy 357.058161 -215.155167) (xy 357.104325 -215.131643) (xy 357.1536 -215.11563) (xy 357.204774 -215.107522)
			(xy 357.23068 -215.107012) (xy 357.256191 -215.107502) (xy 357.306606 -215.11536) (xy 357.355207 -215.130891)
			(xy 357.400836 -215.153725) (xy 357.442402 -215.183316) (xy 357.478912 -215.218958) (xy 357.494586 -215.239092)
			(xy 357.906574 -215.239092) (xy 357.92226 -215.218967) (xy 357.958768 -215.183323) (xy 358.000331 -215.153729)
			(xy 358.045956 -215.130891) (xy 358.094556 -215.115355) (xy 358.144969 -215.107491) (xy 358.17048 -215.107012)
			(xy 358.196391 -215.107484) (xy 358.247575 -215.115588) (xy 358.296861 -215.131599) (xy 358.343035 -215.155124)
			(xy 358.38496 -215.185582) (xy 358.421605 -215.222224) (xy 358.452066 -215.264148) (xy 358.475593 -215.310321)
			(xy 358.491607 -215.359606) (xy 358.499714 -215.410789) (xy 358.499714 -215.462611) (xy 358.491607 -215.513794)
			(xy 358.475593 -215.563079) (xy 358.452066 -215.609252) (xy 358.421605 -215.651176) (xy 358.38496 -215.687818)
			(xy 358.343035 -215.718276) (xy 358.296861 -215.741801) (xy 358.247575 -215.757812) (xy 358.196391 -215.765916)
			(xy 358.17048 -215.766396) (xy 358.144968 -215.765932) (xy 358.094552 -215.758068) (xy 358.04595 -215.742532)
			(xy 358.000322 -215.719693) (xy 357.958757 -215.690098) (xy 357.922247 -215.654452) (xy 357.906574 -215.634316)
			(xy 357.494586 -215.634316) (xy 357.478925 -215.654461) (xy 357.442412 -215.690104) (xy 357.400844 -215.719696)
			(xy 357.355213 -215.74253) (xy 357.306609 -215.758062) (xy 357.256193 -215.76592) (xy 357.23068 -215.766396)
			(xy 357.204774 -215.765878) (xy 357.1536 -215.75777) (xy 357.104325 -215.741757) (xy 357.058161 -215.718233)
			(xy 357.016246 -215.687777) (xy 356.97961 -215.651139) (xy 356.949157 -215.609222) (xy 356.925635 -215.563056)
			(xy 356.909625 -215.51378) (xy 356.90152 -215.462606) (xy 356.620064 -215.462606) (xy 356.620064 -215.462611)
			(xy 356.611958 -215.513788) (xy 356.595946 -215.563067) (xy 356.572423 -215.609234) (xy 356.541967 -215.651153)
			(xy 356.505329 -215.687791) (xy 356.46341 -215.718247) (xy 356.417243 -215.74177) (xy 356.367964 -215.757782)
			(xy 356.316787 -215.765888) (xy 356.264973 -215.765888) (xy 356.213796 -215.757782) (xy 356.164517 -215.74177)
			(xy 356.11835 -215.718247) (xy 356.076431 -215.687791) (xy 356.039793 -215.651153) (xy 356.009337 -215.609234)
			(xy 355.985814 -215.563067) (xy 355.969802 -215.513788) (xy 355.961696 -215.462611) (xy 355.961188 -215.436704)
			(xy 354.740972 -215.436704) (xy 354.740464 -215.462611) (xy 354.732358 -215.513788) (xy 354.716346 -215.563067)
			(xy 354.692823 -215.609234) (xy 354.662367 -215.651153) (xy 354.625729 -215.687791) (xy 354.58381 -215.718247)
			(xy 354.537643 -215.74177) (xy 354.488364 -215.757782) (xy 354.437187 -215.765888) (xy 354.385373 -215.765888)
			(xy 354.334196 -215.757782) (xy 354.284917 -215.74177) (xy 354.23875 -215.718247) (xy 354.196831 -215.687791)
			(xy 354.160193 -215.651153) (xy 354.129737 -215.609234) (xy 354.106214 -215.563067) (xy 354.090202 -215.513788)
			(xy 354.082096 -215.462611) (xy 354.081588 -215.436704) (xy 352.861372 -215.436704) (xy 352.860864 -215.462611)
			(xy 352.852758 -215.513788) (xy 352.836746 -215.563067) (xy 352.813223 -215.609234) (xy 352.782767 -215.651153)
			(xy 352.746129 -215.687791) (xy 352.70421 -215.718247) (xy 352.658043 -215.74177) (xy 352.608764 -215.757782)
			(xy 352.557587 -215.765888) (xy 352.505773 -215.765888) (xy 352.454596 -215.757782) (xy 352.405317 -215.74177)
			(xy 352.35915 -215.718247) (xy 352.317231 -215.687791) (xy 352.280593 -215.651153) (xy 352.250137 -215.609234)
			(xy 352.226614 -215.563067) (xy 352.210602 -215.513788) (xy 352.202496 -215.462611) (xy 352.201988 -215.436704)
			(xy 350.981772 -215.436704) (xy 350.981264 -215.462611) (xy 350.973158 -215.513788) (xy 350.957146 -215.563067)
			(xy 350.933623 -215.609234) (xy 350.903167 -215.651153) (xy 350.866529 -215.687791) (xy 350.82461 -215.718247)
			(xy 350.778443 -215.74177) (xy 350.729164 -215.757782) (xy 350.677987 -215.765888) (xy 350.626173 -215.765888)
			(xy 350.574996 -215.757782) (xy 350.525717 -215.74177) (xy 350.47955 -215.718247) (xy 350.437631 -215.687791)
			(xy 350.400993 -215.651153) (xy 350.370537 -215.609234) (xy 350.347014 -215.563067) (xy 350.331002 -215.513788)
			(xy 350.322896 -215.462611) (xy 350.322388 -215.436704) (xy 349.102172 -215.436704) (xy 349.101664 -215.462611)
			(xy 349.093558 -215.513788) (xy 349.077546 -215.563067) (xy 349.054023 -215.609234) (xy 349.023567 -215.651153)
			(xy 348.986929 -215.687791) (xy 348.94501 -215.718247) (xy 348.898843 -215.74177) (xy 348.849564 -215.757782)
			(xy 348.798387 -215.765888) (xy 348.746573 -215.765888) (xy 348.695396 -215.757782) (xy 348.646117 -215.74177)
			(xy 348.59995 -215.718247) (xy 348.558031 -215.687791) (xy 348.521393 -215.651153) (xy 348.490937 -215.609234)
			(xy 348.467414 -215.563067) (xy 348.451402 -215.513788) (xy 348.443296 -215.462611) (xy 348.442788 -215.436704)
			(xy 347.222572 -215.436704) (xy 347.222064 -215.462611) (xy 347.213958 -215.513788) (xy 347.197946 -215.563067)
			(xy 347.174423 -215.609234) (xy 347.143967 -215.651153) (xy 347.107329 -215.687791) (xy 347.06541 -215.718247)
			(xy 347.019243 -215.74177) (xy 346.969964 -215.757782) (xy 346.918787 -215.765888) (xy 346.866973 -215.765888)
			(xy 346.815796 -215.757782) (xy 346.766517 -215.74177) (xy 346.72035 -215.718247) (xy 346.678431 -215.687791)
			(xy 346.641793 -215.651153) (xy 346.611337 -215.609234) (xy 346.587814 -215.563067) (xy 346.571802 -215.513788)
			(xy 346.563696 -215.462611) (xy 346.563188 -215.436704) (xy 345.342972 -215.436704) (xy 345.342464 -215.462611)
			(xy 345.334358 -215.513788) (xy 345.318346 -215.563067) (xy 345.294823 -215.609234) (xy 345.264367 -215.651153)
			(xy 345.227729 -215.687791) (xy 345.18581 -215.718247) (xy 345.139643 -215.74177) (xy 345.090364 -215.757782)
			(xy 345.039187 -215.765888) (xy 344.987373 -215.765888) (xy 344.936196 -215.757782) (xy 344.886917 -215.74177)
			(xy 344.84075 -215.718247) (xy 344.798831 -215.687791) (xy 344.762193 -215.651153) (xy 344.731737 -215.609234)
			(xy 344.708214 -215.563067) (xy 344.692202 -215.513788) (xy 344.684096 -215.462611) (xy 344.683588 -215.436704)
			(xy 343.463372 -215.436704) (xy 343.462864 -215.462611) (xy 343.454758 -215.513788) (xy 343.438746 -215.563067)
			(xy 343.415223 -215.609234) (xy 343.384767 -215.651153) (xy 343.348129 -215.687791) (xy 343.30621 -215.718247)
			(xy 343.260043 -215.74177) (xy 343.210764 -215.757782) (xy 343.159587 -215.765888) (xy 343.107773 -215.765888)
			(xy 343.056596 -215.757782) (xy 343.007317 -215.74177) (xy 342.96115 -215.718247) (xy 342.919231 -215.687791)
			(xy 342.882593 -215.651153) (xy 342.852137 -215.609234) (xy 342.828614 -215.563067) (xy 342.812602 -215.513788)
			(xy 342.804496 -215.462611) (xy 342.803988 -215.436704) (xy 341.583772 -215.436704) (xy 341.583264 -215.462611)
			(xy 341.575158 -215.513788) (xy 341.559146 -215.563067) (xy 341.535623 -215.609234) (xy 341.505167 -215.651153)
			(xy 341.468529 -215.687791) (xy 341.42661 -215.718247) (xy 341.380443 -215.74177) (xy 341.331164 -215.757782)
			(xy 341.279987 -215.765888) (xy 341.228173 -215.765888) (xy 341.176996 -215.757782) (xy 341.127717 -215.74177)
			(xy 341.08155 -215.718247) (xy 341.039631 -215.687791) (xy 341.002993 -215.651153) (xy 340.972537 -215.609234)
			(xy 340.949014 -215.563067) (xy 340.933002 -215.513788) (xy 340.924896 -215.462611) (xy 340.924388 -215.436704)
			(xy 339.704172 -215.436704) (xy 339.703664 -215.462611) (xy 339.695558 -215.513788) (xy 339.679546 -215.563067)
			(xy 339.656023 -215.609234) (xy 339.625567 -215.651153) (xy 339.588929 -215.687791) (xy 339.54701 -215.718247)
			(xy 339.500843 -215.74177) (xy 339.451564 -215.757782) (xy 339.400387 -215.765888) (xy 339.348573 -215.765888)
			(xy 339.297396 -215.757782) (xy 339.248117 -215.74177) (xy 339.20195 -215.718247) (xy 339.160031 -215.687791)
			(xy 339.123393 -215.651153) (xy 339.092937 -215.609234) (xy 339.069414 -215.563067) (xy 339.053402 -215.513788)
			(xy 339.045296 -215.462611) (xy 339.044788 -215.436704) (xy 337.824572 -215.436704) (xy 337.824064 -215.462611)
			(xy 337.815958 -215.513788) (xy 337.799946 -215.563067) (xy 337.776423 -215.609234) (xy 337.745967 -215.651153)
			(xy 337.709329 -215.687791) (xy 337.66741 -215.718247) (xy 337.621243 -215.74177) (xy 337.571964 -215.757782)
			(xy 337.520787 -215.765888) (xy 337.468973 -215.765888) (xy 337.417796 -215.757782) (xy 337.368517 -215.74177)
			(xy 337.32235 -215.718247) (xy 337.280431 -215.687791) (xy 337.243793 -215.651153) (xy 337.213337 -215.609234)
			(xy 337.189814 -215.563067) (xy 337.173802 -215.513788) (xy 337.165696 -215.462611) (xy 337.165188 -215.436704)
			(xy 336.884772 -215.436704) (xy 336.884181 -215.464421) (xy 336.874856 -215.519068) (xy 336.86623 -215.545416)
			(xy 336.858356 -215.567514) (xy 337.063334 -215.922352) (xy 337.086194 -215.92667) (xy 337.110997 -215.931858)
			(xy 337.158737 -215.948846) (xy 337.203315 -215.972939) (xy 337.243681 -216.00357) (xy 337.278884 -216.040017)
			(xy 337.308096 -216.081421) (xy 337.330629 -216.126808) (xy 337.345951 -216.175108) (xy 337.353702 -216.225184)
			(xy 337.354164 -216.25052) (xy 337.353656 -216.276407) (xy 337.345557 -216.327545) (xy 337.329558 -216.376785)
			(xy 337.306052 -216.422917) (xy 337.27562 -216.464804) (xy 337.23901 -216.501414) (xy 337.197123 -216.531846)
			(xy 337.150991 -216.555352) (xy 337.101751 -216.571351) (xy 337.050613 -216.57945) (xy 336.998839 -216.57945)
			(xy 336.947701 -216.571351) (xy 336.898461 -216.555352) (xy 336.852329 -216.531846) (xy 336.810442 -216.501414)
			(xy 336.773832 -216.464804) (xy 336.7434 -216.422917) (xy 336.719894 -216.376785) (xy 336.703895 -216.327545)
			(xy 336.695796 -216.276407) (xy 336.695288 -216.25052) (xy 336.695823 -216.222812) (xy 336.705015 -216.168165)
			(xy 336.713576 -216.141808) (xy 336.72145 -216.11971) (xy 336.516472 -215.764872) (xy 336.493612 -215.760554)
			(xy 336.46879 -215.755389) (xy 336.421007 -215.73844) (xy 336.376384 -215.714372) (xy 336.335974 -215.683753)
			(xy 336.300731 -215.647305) (xy 336.271487 -215.60589) (xy 336.248932 -215.560483) (xy 336.233597 -215.512158)
			(xy 336.225846 -215.462054) (xy 336.225388 -215.436704) (xy 135.934704 -215.436704) (xy 135.934196 -215.462611)
			(xy 135.92609 -215.513788) (xy 135.910078 -215.563067) (xy 135.886555 -215.609234) (xy 135.856099 -215.651153)
			(xy 135.819461 -215.687791) (xy 135.777542 -215.718247) (xy 135.731375 -215.74177) (xy 135.682096 -215.757782)
			(xy 135.630919 -215.765888) (xy 135.579105 -215.765888) (xy 135.527928 -215.757782) (xy 135.478649 -215.74177)
			(xy 135.432482 -215.718247) (xy 135.390563 -215.687791) (xy 135.353925 -215.651153) (xy 135.323469 -215.609234)
			(xy 135.299946 -215.563067) (xy 135.283934 -215.513788) (xy 135.275828 -215.462611) (xy 135.27532 -215.436704)
			(xy 135.27603 -215.405863) (xy 135.287538 -215.345263) (xy 135.29818 -215.316308) (xy 135.306816 -215.294464)
			(xy 135.084058 -214.872824) (xy 135.061452 -214.867744) (xy 135.037516 -214.861817) (xy 134.991624 -214.843773)
			(xy 134.948934 -214.819093) (xy 134.910397 -214.788329) (xy 134.876873 -214.752166) (xy 134.849112 -214.711412)
			(xy 134.827733 -214.666976) (xy 134.813212 -214.619852) (xy 134.805875 -214.57109) (xy 134.80542 -214.546434)
			(xy 133.57622 -214.546434) (xy 133.584188 -214.596747) (xy 133.584696 -214.622634) (xy 133.584247 -214.64797)
			(xy 133.57649 -214.698044) (xy 133.561163 -214.746341) (xy 133.538627 -214.791726) (xy 133.509412 -214.833128)
			(xy 133.474208 -214.869572) (xy 133.433842 -214.900202) (xy 133.389265 -214.924296) (xy 133.341527 -214.941286)
			(xy 133.316726 -214.946484) (xy 133.293866 -214.950802) (xy 133.088888 -215.305894) (xy 133.096762 -215.327738)
			(xy 133.10541 -215.354146) (xy 133.114729 -215.408922) (xy 133.115304 -215.436704) (xy 133.114796 -215.46261)
			(xy 133.396194 -215.46261) (xy 133.396194 -215.41079) (xy 133.4043 -215.359609) (xy 133.420313 -215.310326)
			(xy 133.44384 -215.264155) (xy 133.474299 -215.222232) (xy 133.510941 -215.185591) (xy 133.552865 -215.155133)
			(xy 133.599037 -215.131609) (xy 133.648321 -215.115597) (xy 133.699502 -215.107493) (xy 133.725412 -215.107012)
			(xy 133.750924 -215.107479) (xy 133.80134 -215.115342) (xy 133.849942 -215.130878) (xy 133.89557 -215.153716)
			(xy 133.937135 -215.183311) (xy 133.973645 -215.218956) (xy 133.989318 -215.239092) (xy 134.401306 -215.239092)
			(xy 134.416974 -215.218952) (xy 134.453485 -215.183309) (xy 134.495052 -215.153716) (xy 134.540681 -215.130881)
			(xy 134.589284 -215.115348) (xy 134.6397 -215.107489) (xy 134.665212 -215.107012) (xy 134.691119 -215.107513)
			(xy 134.742295 -215.11562) (xy 134.791573 -215.131633) (xy 134.837739 -215.155158) (xy 134.879656 -215.185614)
			(xy 134.916294 -215.222253) (xy 134.946749 -215.264172) (xy 134.970271 -215.310339) (xy 134.986282 -215.359617)
			(xy 134.994388 -215.410793) (xy 134.994388 -215.462607) (xy 134.986282 -215.513783) (xy 134.970271 -215.563061)
			(xy 134.946749 -215.609228) (xy 134.916294 -215.651147) (xy 134.879656 -215.687786) (xy 134.837739 -215.718242)
			(xy 134.791573 -215.741767) (xy 134.742295 -215.75778) (xy 134.691119 -215.765887) (xy 134.665212 -215.766396)
			(xy 134.6397 -215.765908) (xy 134.589286 -215.758049) (xy 134.540685 -215.742517) (xy 134.495056 -215.719683)
			(xy 134.453491 -215.690092) (xy 134.41698 -215.65445) (xy 134.401306 -215.634316) (xy 133.989318 -215.634316)
			(xy 133.973638 -215.654446) (xy 133.937129 -215.69009) (xy 133.895565 -215.719683) (xy 133.849938 -215.74252)
			(xy 133.801337 -215.758055) (xy 133.750924 -215.765918) (xy 133.725412 -215.766396) (xy 133.699502 -215.765907)
			(xy 133.648321 -215.757803) (xy 133.599037 -215.741791) (xy 133.552865 -215.718267) (xy 133.510941 -215.687809)
			(xy 133.474299 -215.651168) (xy 133.44384 -215.609245) (xy 133.420313 -215.563074) (xy 133.4043 -215.513791)
			(xy 133.396194 -215.46261) (xy 133.114796 -215.46261) (xy 133.114796 -215.462611) (xy 133.10669 -215.513788)
			(xy 133.090678 -215.563067) (xy 133.067155 -215.609234) (xy 133.036699 -215.651153) (xy 133.000061 -215.687791)
			(xy 132.958142 -215.718247) (xy 132.911975 -215.74177) (xy 132.862696 -215.757782) (xy 132.811519 -215.765888)
			(xy 132.759705 -215.765888) (xy 132.708528 -215.757782) (xy 132.659249 -215.74177) (xy 132.613082 -215.718247)
			(xy 132.571163 -215.687791) (xy 132.534525 -215.651153) (xy 132.504069 -215.609234) (xy 132.480546 -215.563067)
			(xy 132.464534 -215.513788) (xy 132.456428 -215.462611) (xy 132.45592 -215.436704) (xy 131.235704 -215.436704)
			(xy 131.235196 -215.462611) (xy 131.22709 -215.513788) (xy 131.211078 -215.563067) (xy 131.187555 -215.609234)
			(xy 131.157099 -215.651153) (xy 131.120461 -215.687791) (xy 131.078542 -215.718247) (xy 131.032375 -215.74177)
			(xy 130.983096 -215.757782) (xy 130.931919 -215.765888) (xy 130.880105 -215.765888) (xy 130.828928 -215.757782)
			(xy 130.779649 -215.74177) (xy 130.733482 -215.718247) (xy 130.691563 -215.687791) (xy 130.654925 -215.651153)
			(xy 130.624469 -215.609234) (xy 130.600946 -215.563067) (xy 130.584934 -215.513788) (xy 130.576828 -215.462611)
			(xy 130.57632 -215.436704) (xy 129.356104 -215.436704) (xy 129.355596 -215.462611) (xy 129.34749 -215.513788)
			(xy 129.331478 -215.563067) (xy 129.307955 -215.609234) (xy 129.277499 -215.651153) (xy 129.240861 -215.687791)
			(xy 129.198942 -215.718247) (xy 129.152775 -215.74177) (xy 129.103496 -215.757782) (xy 129.052319 -215.765888)
			(xy 129.000505 -215.765888) (xy 128.949328 -215.757782) (xy 128.900049 -215.74177) (xy 128.853882 -215.718247)
			(xy 128.811963 -215.687791) (xy 128.775325 -215.651153) (xy 128.744869 -215.609234) (xy 128.721346 -215.563067)
			(xy 128.705334 -215.513788) (xy 128.697228 -215.462611) (xy 128.69672 -215.436704) (xy 127.476504 -215.436704)
			(xy 127.475996 -215.462611) (xy 127.46789 -215.513788) (xy 127.451878 -215.563067) (xy 127.428355 -215.609234)
			(xy 127.397899 -215.651153) (xy 127.361261 -215.687791) (xy 127.319342 -215.718247) (xy 127.273175 -215.74177)
			(xy 127.223896 -215.757782) (xy 127.172719 -215.765888) (xy 127.120905 -215.765888) (xy 127.069728 -215.757782)
			(xy 127.020449 -215.74177) (xy 126.974282 -215.718247) (xy 126.932363 -215.687791) (xy 126.895725 -215.651153)
			(xy 126.865269 -215.609234) (xy 126.841746 -215.563067) (xy 126.825734 -215.513788) (xy 126.817628 -215.462611)
			(xy 126.81712 -215.436704) (xy 125.596904 -215.436704) (xy 125.596396 -215.462611) (xy 125.58829 -215.513788)
			(xy 125.572278 -215.563067) (xy 125.548755 -215.609234) (xy 125.518299 -215.651153) (xy 125.481661 -215.687791)
			(xy 125.439742 -215.718247) (xy 125.393575 -215.74177) (xy 125.344296 -215.757782) (xy 125.293119 -215.765888)
			(xy 125.241305 -215.765888) (xy 125.190128 -215.757782) (xy 125.140849 -215.74177) (xy 125.094682 -215.718247)
			(xy 125.052763 -215.687791) (xy 125.016125 -215.651153) (xy 124.985669 -215.609234) (xy 124.962146 -215.563067)
			(xy 124.946134 -215.513788) (xy 124.938028 -215.462611) (xy 124.93752 -215.436704) (xy 123.717304 -215.436704)
			(xy 123.716796 -215.462611) (xy 123.70869 -215.513788) (xy 123.692678 -215.563067) (xy 123.669155 -215.609234)
			(xy 123.638699 -215.651153) (xy 123.602061 -215.687791) (xy 123.560142 -215.718247) (xy 123.513975 -215.74177)
			(xy 123.464696 -215.757782) (xy 123.413519 -215.765888) (xy 123.361705 -215.765888) (xy 123.310528 -215.757782)
			(xy 123.261249 -215.74177) (xy 123.215082 -215.718247) (xy 123.173163 -215.687791) (xy 123.136525 -215.651153)
			(xy 123.106069 -215.609234) (xy 123.082546 -215.563067) (xy 123.066534 -215.513788) (xy 123.058428 -215.462611)
			(xy 123.05792 -215.436704) (xy 121.837704 -215.436704) (xy 121.837196 -215.462611) (xy 121.82909 -215.513788)
			(xy 121.813078 -215.563067) (xy 121.789555 -215.609234) (xy 121.759099 -215.651153) (xy 121.722461 -215.687791)
			(xy 121.680542 -215.718247) (xy 121.634375 -215.74177) (xy 121.585096 -215.757782) (xy 121.533919 -215.765888)
			(xy 121.482105 -215.765888) (xy 121.430928 -215.757782) (xy 121.381649 -215.74177) (xy 121.335482 -215.718247)
			(xy 121.293563 -215.687791) (xy 121.256925 -215.651153) (xy 121.226469 -215.609234) (xy 121.202946 -215.563067)
			(xy 121.186934 -215.513788) (xy 121.178828 -215.462611) (xy 121.17832 -215.436704) (xy 119.958104 -215.436704)
			(xy 119.957596 -215.462611) (xy 119.94949 -215.513788) (xy 119.933478 -215.563067) (xy 119.909955 -215.609234)
			(xy 119.879499 -215.651153) (xy 119.842861 -215.687791) (xy 119.800942 -215.718247) (xy 119.754775 -215.74177)
			(xy 119.705496 -215.757782) (xy 119.654319 -215.765888) (xy 119.602505 -215.765888) (xy 119.551328 -215.757782)
			(xy 119.502049 -215.74177) (xy 119.455882 -215.718247) (xy 119.413963 -215.687791) (xy 119.377325 -215.651153)
			(xy 119.346869 -215.609234) (xy 119.323346 -215.563067) (xy 119.307334 -215.513788) (xy 119.299228 -215.462611)
			(xy 119.29872 -215.436704) (xy 118.078504 -215.436704) (xy 118.077996 -215.462611) (xy 118.06989 -215.513788)
			(xy 118.053878 -215.563067) (xy 118.030355 -215.609234) (xy 117.999899 -215.651153) (xy 117.963261 -215.687791)
			(xy 117.921342 -215.718247) (xy 117.875175 -215.74177) (xy 117.825896 -215.757782) (xy 117.774719 -215.765888)
			(xy 117.722905 -215.765888) (xy 117.671728 -215.757782) (xy 117.622449 -215.74177) (xy 117.576282 -215.718247)
			(xy 117.534363 -215.687791) (xy 117.497725 -215.651153) (xy 117.467269 -215.609234) (xy 117.443746 -215.563067)
			(xy 117.427734 -215.513788) (xy 117.419628 -215.462611) (xy 117.41912 -215.436704) (xy 116.198904 -215.436704)
			(xy 116.198396 -215.462611) (xy 116.19029 -215.513788) (xy 116.174278 -215.563067) (xy 116.150755 -215.609234)
			(xy 116.120299 -215.651153) (xy 116.083661 -215.687791) (xy 116.041742 -215.718247) (xy 115.995575 -215.74177)
			(xy 115.946296 -215.757782) (xy 115.895119 -215.765888) (xy 115.843305 -215.765888) (xy 115.792128 -215.757782)
			(xy 115.742849 -215.74177) (xy 115.696682 -215.718247) (xy 115.654763 -215.687791) (xy 115.618125 -215.651153)
			(xy 115.587669 -215.609234) (xy 115.564146 -215.563067) (xy 115.548134 -215.513788) (xy 115.540028 -215.462611)
			(xy 115.53952 -215.436704) (xy 114.319304 -215.436704) (xy 114.318796 -215.462611) (xy 114.31069 -215.513788)
			(xy 114.294678 -215.563067) (xy 114.271155 -215.609234) (xy 114.240699 -215.651153) (xy 114.204061 -215.687791)
			(xy 114.162142 -215.718247) (xy 114.115975 -215.74177) (xy 114.066696 -215.757782) (xy 114.015519 -215.765888)
			(xy 113.963705 -215.765888) (xy 113.912528 -215.757782) (xy 113.863249 -215.74177) (xy 113.817082 -215.718247)
			(xy 113.775163 -215.687791) (xy 113.738525 -215.651153) (xy 113.708069 -215.609234) (xy 113.684546 -215.563067)
			(xy 113.668534 -215.513788) (xy 113.660428 -215.462611) (xy 113.65992 -215.436704) (xy 111.499904 -215.436704)
			(xy 111.499396 -215.462611) (xy 111.49129 -215.513788) (xy 111.475278 -215.563067) (xy 111.451755 -215.609234)
			(xy 111.421299 -215.651153) (xy 111.384661 -215.687791) (xy 111.342742 -215.718247) (xy 111.296575 -215.74177)
			(xy 111.247296 -215.757782) (xy 111.196119 -215.765888) (xy 111.144305 -215.765888) (xy 111.093128 -215.757782)
			(xy 111.043849 -215.74177) (xy 110.997682 -215.718247) (xy 110.955763 -215.687791) (xy 110.919125 -215.651153)
			(xy 110.888669 -215.609234) (xy 110.865146 -215.563067) (xy 110.849134 -215.513788) (xy 110.841028 -215.462611)
			(xy 110.84052 -215.436704) (xy 110.840955 -215.413764) (xy 110.847378 -215.368334) (xy 110.860018 -215.324227)
			(xy 110.868968 -215.3031) (xy 110.878874 -215.280494) (xy 110.665006 -214.87511) (xy 110.640876 -214.870538)
			(xy 110.615954 -214.86544) (xy 110.567941 -214.848641) (xy 110.523081 -214.824663) (xy 110.482438 -214.794075)
			(xy 110.44698 -214.757604) (xy 110.417549 -214.716116) (xy 110.394843 -214.670598) (xy 110.379403 -214.622131)
			(xy 110.371595 -214.571867) (xy 110.371128 -214.546434) (xy 109.14142 -214.546434) (xy 109.149388 -214.596747)
			(xy 109.149896 -214.622634) (xy 109.149447 -214.64797) (xy 109.14169 -214.698044) (xy 109.126363 -214.746341)
			(xy 109.103827 -214.791726) (xy 109.074612 -214.833128) (xy 109.039408 -214.869572) (xy 108.999042 -214.900202)
			(xy 108.954465 -214.924296) (xy 108.906727 -214.941286) (xy 108.881926 -214.946484) (xy 108.859066 -214.950802)
			(xy 108.654088 -215.305894) (xy 108.661962 -215.327738) (xy 108.67061 -215.354146) (xy 108.679929 -215.408922)
			(xy 108.680504 -215.436704) (xy 108.679996 -215.46261) (xy 108.961394 -215.46261) (xy 108.961394 -215.41079)
			(xy 108.9695 -215.359609) (xy 108.985513 -215.310326) (xy 109.00904 -215.264155) (xy 109.039499 -215.222232)
			(xy 109.076141 -215.185591) (xy 109.118065 -215.155133) (xy 109.164237 -215.131609) (xy 109.213521 -215.115597)
			(xy 109.264702 -215.107493) (xy 109.290612 -215.107012) (xy 109.316124 -215.107479) (xy 109.36654 -215.115342)
			(xy 109.415142 -215.130878) (xy 109.46077 -215.153716) (xy 109.502335 -215.183311) (xy 109.538845 -215.218956)
			(xy 109.554518 -215.239092) (xy 109.966506 -215.239092) (xy 109.982174 -215.218952) (xy 110.018685 -215.183309)
			(xy 110.060252 -215.153716) (xy 110.105881 -215.130881) (xy 110.154484 -215.115348) (xy 110.2049 -215.107489)
			(xy 110.230412 -215.107012) (xy 110.256319 -215.107513) (xy 110.307495 -215.11562) (xy 110.356773 -215.131633)
			(xy 110.402939 -215.155158) (xy 110.444856 -215.185614) (xy 110.481494 -215.222253) (xy 110.511949 -215.264172)
			(xy 110.535471 -215.310339) (xy 110.551482 -215.359617) (xy 110.559588 -215.410793) (xy 110.559588 -215.462607)
			(xy 110.551482 -215.513783) (xy 110.535471 -215.563061) (xy 110.511949 -215.609228) (xy 110.481494 -215.651147)
			(xy 110.444856 -215.687786) (xy 110.402939 -215.718242) (xy 110.356773 -215.741767) (xy 110.307495 -215.75778)
			(xy 110.256319 -215.765887) (xy 110.230412 -215.766396) (xy 110.2049 -215.765908) (xy 110.154486 -215.758049)
			(xy 110.105885 -215.742517) (xy 110.060256 -215.719683) (xy 110.018691 -215.690092) (xy 109.98218 -215.65445)
			(xy 109.966506 -215.634316) (xy 109.554518 -215.634316) (xy 109.538838 -215.654446) (xy 109.502329 -215.69009)
			(xy 109.460765 -215.719683) (xy 109.415138 -215.74252) (xy 109.366537 -215.758055) (xy 109.316124 -215.765918)
			(xy 109.290612 -215.766396) (xy 109.264702 -215.765907) (xy 109.213521 -215.757803) (xy 109.164237 -215.741791)
			(xy 109.118065 -215.718267) (xy 109.076141 -215.687809) (xy 109.039499 -215.651168) (xy 109.00904 -215.609245)
			(xy 108.985513 -215.563074) (xy 108.9695 -215.513791) (xy 108.961394 -215.46261) (xy 108.679996 -215.46261)
			(xy 108.679996 -215.462611) (xy 108.67189 -215.513788) (xy 108.655878 -215.563067) (xy 108.632355 -215.609234)
			(xy 108.601899 -215.651153) (xy 108.565261 -215.687791) (xy 108.523342 -215.718247) (xy 108.477175 -215.74177)
			(xy 108.427896 -215.757782) (xy 108.376719 -215.765888) (xy 108.324905 -215.765888) (xy 108.273728 -215.757782)
			(xy 108.224449 -215.74177) (xy 108.178282 -215.718247) (xy 108.136363 -215.687791) (xy 108.099725 -215.651153)
			(xy 108.069269 -215.609234) (xy 108.045746 -215.563067) (xy 108.029734 -215.513788) (xy 108.021628 -215.462611)
			(xy 108.02112 -215.436704) (xy 106.800904 -215.436704) (xy 106.800396 -215.462611) (xy 106.79229 -215.513788)
			(xy 106.776278 -215.563067) (xy 106.752755 -215.609234) (xy 106.722299 -215.651153) (xy 106.685661 -215.687791)
			(xy 106.643742 -215.718247) (xy 106.597575 -215.74177) (xy 106.548296 -215.757782) (xy 106.497119 -215.765888)
			(xy 106.445305 -215.765888) (xy 106.394128 -215.757782) (xy 106.344849 -215.74177) (xy 106.298682 -215.718247)
			(xy 106.256763 -215.687791) (xy 106.220125 -215.651153) (xy 106.189669 -215.609234) (xy 106.166146 -215.563067)
			(xy 106.150134 -215.513788) (xy 106.142028 -215.462611) (xy 106.14152 -215.436704) (xy 104.921304 -215.436704)
			(xy 104.920796 -215.462611) (xy 104.91269 -215.513788) (xy 104.896678 -215.563067) (xy 104.873155 -215.609234)
			(xy 104.842699 -215.651153) (xy 104.806061 -215.687791) (xy 104.764142 -215.718247) (xy 104.717975 -215.74177)
			(xy 104.668696 -215.757782) (xy 104.617519 -215.765888) (xy 104.565705 -215.765888) (xy 104.514528 -215.757782)
			(xy 104.465249 -215.74177) (xy 104.419082 -215.718247) (xy 104.377163 -215.687791) (xy 104.340525 -215.651153)
			(xy 104.310069 -215.609234) (xy 104.286546 -215.563067) (xy 104.270534 -215.513788) (xy 104.262428 -215.462611)
			(xy 104.26192 -215.436704) (xy 103.041704 -215.436704) (xy 103.041196 -215.462611) (xy 103.03309 -215.513788)
			(xy 103.017078 -215.563067) (xy 102.993555 -215.609234) (xy 102.963099 -215.651153) (xy 102.926461 -215.687791)
			(xy 102.884542 -215.718247) (xy 102.838375 -215.74177) (xy 102.789096 -215.757782) (xy 102.737919 -215.765888)
			(xy 102.686105 -215.765888) (xy 102.634928 -215.757782) (xy 102.585649 -215.74177) (xy 102.539482 -215.718247)
			(xy 102.497563 -215.687791) (xy 102.460925 -215.651153) (xy 102.430469 -215.609234) (xy 102.406946 -215.563067)
			(xy 102.390934 -215.513788) (xy 102.382828 -215.462611) (xy 102.38232 -215.436704) (xy 101.162104 -215.436704)
			(xy 101.161596 -215.462611) (xy 101.15349 -215.513788) (xy 101.137478 -215.563067) (xy 101.113955 -215.609234)
			(xy 101.083499 -215.651153) (xy 101.046861 -215.687791) (xy 101.004942 -215.718247) (xy 100.958775 -215.74177)
			(xy 100.909496 -215.757782) (xy 100.858319 -215.765888) (xy 100.806505 -215.765888) (xy 100.755328 -215.757782)
			(xy 100.706049 -215.74177) (xy 100.659882 -215.718247) (xy 100.617963 -215.687791) (xy 100.581325 -215.651153)
			(xy 100.550869 -215.609234) (xy 100.527346 -215.563067) (xy 100.511334 -215.513788) (xy 100.503228 -215.462611)
			(xy 100.50272 -215.436704) (xy 99.282504 -215.436704) (xy 99.281996 -215.462611) (xy 99.27389 -215.513788)
			(xy 99.257878 -215.563067) (xy 99.234355 -215.609234) (xy 99.203899 -215.651153) (xy 99.167261 -215.687791)
			(xy 99.125342 -215.718247) (xy 99.079175 -215.74177) (xy 99.029896 -215.757782) (xy 98.978719 -215.765888)
			(xy 98.926905 -215.765888) (xy 98.875728 -215.757782) (xy 98.826449 -215.74177) (xy 98.780282 -215.718247)
			(xy 98.738363 -215.687791) (xy 98.701725 -215.651153) (xy 98.671269 -215.609234) (xy 98.647746 -215.563067)
			(xy 98.631734 -215.513788) (xy 98.623628 -215.462611) (xy 98.62312 -215.436704) (xy 97.402904 -215.436704)
			(xy 97.402396 -215.462611) (xy 97.39429 -215.513788) (xy 97.378278 -215.563067) (xy 97.354755 -215.609234)
			(xy 97.324299 -215.651153) (xy 97.287661 -215.687791) (xy 97.245742 -215.718247) (xy 97.199575 -215.74177)
			(xy 97.150296 -215.757782) (xy 97.099119 -215.765888) (xy 97.047305 -215.765888) (xy 96.996128 -215.757782)
			(xy 96.946849 -215.74177) (xy 96.900682 -215.718247) (xy 96.858763 -215.687791) (xy 96.822125 -215.651153)
			(xy 96.791669 -215.609234) (xy 96.768146 -215.563067) (xy 96.752134 -215.513788) (xy 96.744028 -215.462611)
			(xy 96.74352 -215.436704) (xy 95.523304 -215.436704) (xy 95.522796 -215.462611) (xy 95.51469 -215.513788)
			(xy 95.498678 -215.563067) (xy 95.475155 -215.609234) (xy 95.444699 -215.651153) (xy 95.408061 -215.687791)
			(xy 95.366142 -215.718247) (xy 95.319975 -215.74177) (xy 95.270696 -215.757782) (xy 95.219519 -215.765888)
			(xy 95.167705 -215.765888) (xy 95.116528 -215.757782) (xy 95.067249 -215.74177) (xy 95.021082 -215.718247)
			(xy 94.979163 -215.687791) (xy 94.942525 -215.651153) (xy 94.912069 -215.609234) (xy 94.888546 -215.563067)
			(xy 94.872534 -215.513788) (xy 94.864428 -215.462611) (xy 94.86392 -215.436704) (xy 93.643704 -215.436704)
			(xy 93.643196 -215.462611) (xy 93.63509 -215.513788) (xy 93.619078 -215.563067) (xy 93.595555 -215.609234)
			(xy 93.565099 -215.651153) (xy 93.528461 -215.687791) (xy 93.486542 -215.718247) (xy 93.440375 -215.74177)
			(xy 93.391096 -215.757782) (xy 93.339919 -215.765888) (xy 93.288105 -215.765888) (xy 93.236928 -215.757782)
			(xy 93.187649 -215.74177) (xy 93.141482 -215.718247) (xy 93.099563 -215.687791) (xy 93.062925 -215.651153)
			(xy 93.032469 -215.609234) (xy 93.008946 -215.563067) (xy 92.992934 -215.513788) (xy 92.984828 -215.462611)
			(xy 92.98432 -215.436704) (xy 91.764104 -215.436704) (xy 91.763596 -215.462611) (xy 91.75549 -215.513788)
			(xy 91.739478 -215.563067) (xy 91.715955 -215.609234) (xy 91.685499 -215.651153) (xy 91.648861 -215.687791)
			(xy 91.606942 -215.718247) (xy 91.560775 -215.74177) (xy 91.511496 -215.757782) (xy 91.460319 -215.765888)
			(xy 91.408505 -215.765888) (xy 91.357328 -215.757782) (xy 91.308049 -215.74177) (xy 91.261882 -215.718247)
			(xy 91.219963 -215.687791) (xy 91.183325 -215.651153) (xy 91.152869 -215.609234) (xy 91.129346 -215.563067)
			(xy 91.113334 -215.513788) (xy 91.105228 -215.462611) (xy 91.10472 -215.436704) (xy 89.884504 -215.436704)
			(xy 89.883996 -215.462611) (xy 89.87589 -215.513788) (xy 89.859878 -215.563067) (xy 89.836355 -215.609234)
			(xy 89.805899 -215.651153) (xy 89.769261 -215.687791) (xy 89.727342 -215.718247) (xy 89.681175 -215.74177)
			(xy 89.631896 -215.757782) (xy 89.580719 -215.765888) (xy 89.528905 -215.765888) (xy 89.477728 -215.757782)
			(xy 89.428449 -215.74177) (xy 89.382282 -215.718247) (xy 89.340363 -215.687791) (xy 89.303725 -215.651153)
			(xy 89.273269 -215.609234) (xy 89.249746 -215.563067) (xy 89.233734 -215.513788) (xy 89.225628 -215.462611)
			(xy 89.22512 -215.436704) (xy 88.944704 -215.436704) (xy 88.944111 -215.464421) (xy 88.934787 -215.519068)
			(xy 88.926162 -215.545416) (xy 88.918288 -215.567514) (xy 89.123266 -215.922352) (xy 89.146126 -215.92667)
			(xy 89.170934 -215.931835) (xy 89.218674 -215.948828) (xy 89.263251 -215.972925) (xy 89.303616 -216.003559)
			(xy 89.338819 -216.040009) (xy 89.36803 -216.081415) (xy 89.390562 -216.126804) (xy 89.405883 -216.175106)
			(xy 89.413634 -216.225183) (xy 89.414096 -216.25052) (xy 89.413588 -216.276407) (xy 89.405489 -216.327545)
			(xy 89.38949 -216.376785) (xy 89.365984 -216.422917) (xy 89.335552 -216.464804) (xy 89.298942 -216.501414)
			(xy 89.257055 -216.531846) (xy 89.210923 -216.555352) (xy 89.161683 -216.571351) (xy 89.110545 -216.57945)
			(xy 89.058771 -216.57945) (xy 89.007633 -216.571351) (xy 88.958393 -216.555352) (xy 88.912261 -216.531846)
			(xy 88.870374 -216.501414) (xy 88.833764 -216.464804) (xy 88.803332 -216.422917) (xy 88.779826 -216.376785)
			(xy 88.763827 -216.327545) (xy 88.755728 -216.276407) (xy 88.75522 -216.25052) (xy 88.755754 -216.222812)
			(xy 88.764946 -216.168165) (xy 88.773508 -216.141808) (xy 88.781382 -216.11971) (xy 88.576404 -215.764872)
			(xy 88.553544 -215.760554) (xy 88.528711 -215.755439) (xy 88.480928 -215.73848) (xy 88.436306 -215.714403)
			(xy 88.395898 -215.683776) (xy 88.360658 -215.647323) (xy 88.331415 -215.605902) (xy 88.308862 -215.560492)
			(xy 88.293529 -215.512163) (xy 88.285778 -215.462056) (xy 88.28532 -215.436704) (xy 2.509012 -215.436704)
			(xy 2.509012 -217.878406) (xy 88.755728 -217.878406) (xy 88.756236 -217.852519) (xy 88.764335 -217.801381)
			(xy 88.780334 -217.752141) (xy 88.80384 -217.706009) (xy 88.834272 -217.664122) (xy 88.870882 -217.627512)
			(xy 88.912769 -217.59708) (xy 88.958901 -217.573574) (xy 89.008141 -217.557575) (xy 89.059279 -217.549476)
			(xy 89.111053 -217.549476) (xy 89.162191 -217.557575) (xy 89.211431 -217.573574) (xy 89.257563 -217.59708)
			(xy 89.29945 -217.627512) (xy 89.33606 -217.664122) (xy 89.366492 -217.706009) (xy 89.389998 -217.752141)
			(xy 89.405997 -217.801381) (xy 89.414096 -217.852519) (xy 89.414604 -217.878406) (xy 89.695528 -217.878406)
			(xy 89.695994 -217.853071) (xy 89.703746 -217.802996) (xy 89.719069 -217.754698) (xy 89.741602 -217.709313)
			(xy 89.770814 -217.66791) (xy 89.806017 -217.631464) (xy 89.846382 -217.600835) (xy 89.890959 -217.576742)
			(xy 89.938697 -217.559754) (xy 89.963498 -217.554556) (xy 89.986358 -217.550238) (xy 90.191336 -217.195146)
			(xy 90.183462 -217.173302) (xy 90.174824 -217.146891) (xy 90.165499 -217.092117) (xy 90.16492 -217.064336)
			(xy 90.165428 -217.038429) (xy 90.173534 -216.987252) (xy 90.189546 -216.937973) (xy 90.213069 -216.891806)
			(xy 90.243525 -216.849887) (xy 90.280163 -216.813249) (xy 90.322082 -216.782793) (xy 90.368249 -216.75927)
			(xy 90.417528 -216.743258) (xy 90.468705 -216.735152) (xy 90.520519 -216.735152) (xy 90.571696 -216.743258)
			(xy 90.620975 -216.75927) (xy 90.667142 -216.782793) (xy 90.709061 -216.813249) (xy 90.745699 -216.849887)
			(xy 90.776155 -216.891806) (xy 90.799678 -216.937973) (xy 90.81569 -216.987252) (xy 90.823796 -217.038429)
			(xy 90.824304 -217.064336) (xy 90.823812 -217.08968) (xy 90.816035 -217.13977) (xy 90.800686 -217.188079)
			(xy 90.778125 -217.233471) (xy 90.748884 -217.274876) (xy 90.713652 -217.311319) (xy 90.673259 -217.341943)
			(xy 90.628655 -217.366024) (xy 90.580892 -217.382998) (xy 90.55608 -217.388186) (xy 90.53322 -217.392504)
			(xy 90.328242 -217.747596) (xy 90.336116 -217.76944) (xy 90.344706 -217.795856) (xy 90.353895 -217.850633)
			(xy 90.354404 -217.878406) (xy 90.635328 -217.878406) (xy 90.635836 -217.852519) (xy 90.643935 -217.801381)
			(xy 90.659934 -217.752141) (xy 90.68344 -217.706009) (xy 90.713872 -217.664122) (xy 90.750482 -217.627512)
			(xy 90.792369 -217.59708) (xy 90.838501 -217.573574) (xy 90.887741 -217.557575) (xy 90.938879 -217.549476)
			(xy 90.990653 -217.549476) (xy 91.041791 -217.557575) (xy 91.091031 -217.573574) (xy 91.137163 -217.59708)
			(xy 91.17905 -217.627512) (xy 91.21566 -217.664122) (xy 91.246092 -217.706009) (xy 91.269598 -217.752141)
			(xy 91.285597 -217.801381) (xy 91.293696 -217.852519) (xy 91.294204 -217.878406) (xy 91.575128 -217.878406)
			(xy 91.575594 -217.853071) (xy 91.583346 -217.802996) (xy 91.598669 -217.754698) (xy 91.621202 -217.709313)
			(xy 91.650414 -217.66791) (xy 91.685617 -217.631464) (xy 91.725982 -217.600835) (xy 91.770559 -217.576742)
			(xy 91.818297 -217.559754) (xy 91.843098 -217.554556) (xy 91.865958 -217.550238) (xy 92.070936 -217.195146)
			(xy 92.063062 -217.173302) (xy 92.054424 -217.146891) (xy 92.045099 -217.092117) (xy 92.04452 -217.064336)
			(xy 92.045028 -217.038429) (xy 92.053134 -216.987252) (xy 92.069146 -216.937973) (xy 92.092669 -216.891806)
			(xy 92.123125 -216.849887) (xy 92.159763 -216.813249) (xy 92.201682 -216.782793) (xy 92.247849 -216.75927)
			(xy 92.297128 -216.743258) (xy 92.348305 -216.735152) (xy 92.400119 -216.735152) (xy 92.451296 -216.743258)
			(xy 92.500575 -216.75927) (xy 92.546742 -216.782793) (xy 92.588661 -216.813249) (xy 92.625299 -216.849887)
			(xy 92.655755 -216.891806) (xy 92.679278 -216.937973) (xy 92.69529 -216.987252) (xy 92.703396 -217.038429)
			(xy 92.703904 -217.064336) (xy 92.703412 -217.08968) (xy 92.695635 -217.13977) (xy 92.680286 -217.188079)
			(xy 92.657725 -217.233471) (xy 92.628484 -217.274876) (xy 92.593252 -217.311319) (xy 92.552859 -217.341943)
			(xy 92.508255 -217.366024) (xy 92.460492 -217.382998) (xy 92.43568 -217.388186) (xy 92.41282 -217.392504)
			(xy 92.207842 -217.747596) (xy 92.215716 -217.76944) (xy 92.224306 -217.795856) (xy 92.233495 -217.850633)
			(xy 92.234004 -217.878406) (xy 92.514928 -217.878406) (xy 92.515436 -217.852519) (xy 92.523535 -217.801381)
			(xy 92.539534 -217.752141) (xy 92.56304 -217.706009) (xy 92.593472 -217.664122) (xy 92.630082 -217.627512)
			(xy 92.671969 -217.59708) (xy 92.718101 -217.573574) (xy 92.767341 -217.557575) (xy 92.818479 -217.549476)
			(xy 92.870253 -217.549476) (xy 92.921391 -217.557575) (xy 92.970631 -217.573574) (xy 93.016763 -217.59708)
			(xy 93.05865 -217.627512) (xy 93.09526 -217.664122) (xy 93.125692 -217.706009) (xy 93.149198 -217.752141)
			(xy 93.165197 -217.801381) (xy 93.173296 -217.852519) (xy 93.173804 -217.878406) (xy 93.454728 -217.878406)
			(xy 93.455194 -217.853071) (xy 93.462946 -217.802996) (xy 93.478269 -217.754698) (xy 93.500802 -217.709313)
			(xy 93.530014 -217.66791) (xy 93.565217 -217.631464) (xy 93.605582 -217.600835) (xy 93.650159 -217.576742)
			(xy 93.697897 -217.559754) (xy 93.722698 -217.554556) (xy 93.745558 -217.550238) (xy 93.950536 -217.195146)
			(xy 93.942662 -217.173302) (xy 93.934024 -217.146891) (xy 93.924699 -217.092117) (xy 93.92412 -217.064336)
			(xy 93.924628 -217.038429) (xy 93.932734 -216.987252) (xy 93.948746 -216.937973) (xy 93.972269 -216.891806)
			(xy 94.002725 -216.849887) (xy 94.039363 -216.813249) (xy 94.081282 -216.782793) (xy 94.127449 -216.75927)
			(xy 94.176728 -216.743258) (xy 94.227905 -216.735152) (xy 94.279719 -216.735152) (xy 94.330896 -216.743258)
			(xy 94.380175 -216.75927) (xy 94.426342 -216.782793) (xy 94.468261 -216.813249) (xy 94.504899 -216.849887)
			(xy 94.535355 -216.891806) (xy 94.558878 -216.937973) (xy 94.57489 -216.987252) (xy 94.582996 -217.038429)
			(xy 94.583504 -217.064336) (xy 94.583012 -217.08968) (xy 94.575235 -217.13977) (xy 94.559886 -217.188079)
			(xy 94.537325 -217.233471) (xy 94.508084 -217.274876) (xy 94.472852 -217.311319) (xy 94.432459 -217.341943)
			(xy 94.387855 -217.366024) (xy 94.340092 -217.382998) (xy 94.31528 -217.388186) (xy 94.29242 -217.392504)
			(xy 94.087442 -217.747596) (xy 94.095316 -217.76944) (xy 94.103906 -217.795856) (xy 94.113095 -217.850633)
			(xy 94.113604 -217.878406) (xy 94.394528 -217.878406) (xy 94.395036 -217.852519) (xy 94.403135 -217.801381)
			(xy 94.419134 -217.752141) (xy 94.44264 -217.706009) (xy 94.473072 -217.664122) (xy 94.509682 -217.627512)
			(xy 94.551569 -217.59708) (xy 94.597701 -217.573574) (xy 94.646941 -217.557575) (xy 94.698079 -217.549476)
			(xy 94.749853 -217.549476) (xy 94.800991 -217.557575) (xy 94.850231 -217.573574) (xy 94.896363 -217.59708)
			(xy 94.93825 -217.627512) (xy 94.97486 -217.664122) (xy 95.005292 -217.706009) (xy 95.028798 -217.752141)
			(xy 95.044797 -217.801381) (xy 95.052896 -217.852519) (xy 95.053404 -217.878406) (xy 95.334328 -217.878406)
			(xy 95.334794 -217.853071) (xy 95.342546 -217.802996) (xy 95.357869 -217.754698) (xy 95.380402 -217.709313)
			(xy 95.409614 -217.66791) (xy 95.444817 -217.631464) (xy 95.485182 -217.600835) (xy 95.529759 -217.576742)
			(xy 95.577497 -217.559754) (xy 95.602298 -217.554556) (xy 95.625158 -217.550238) (xy 95.830136 -217.195146)
			(xy 95.822262 -217.173302) (xy 95.813624 -217.146891) (xy 95.804299 -217.092117) (xy 95.80372 -217.064336)
			(xy 95.804228 -217.038429) (xy 95.812334 -216.987252) (xy 95.828346 -216.937973) (xy 95.851869 -216.891806)
			(xy 95.882325 -216.849887) (xy 95.918963 -216.813249) (xy 95.960882 -216.782793) (xy 96.007049 -216.75927)
			(xy 96.056328 -216.743258) (xy 96.107505 -216.735152) (xy 96.159319 -216.735152) (xy 96.210496 -216.743258)
			(xy 96.259775 -216.75927) (xy 96.305942 -216.782793) (xy 96.347861 -216.813249) (xy 96.384499 -216.849887)
			(xy 96.414955 -216.891806) (xy 96.438478 -216.937973) (xy 96.45449 -216.987252) (xy 96.462596 -217.038429)
			(xy 96.463104 -217.064336) (xy 96.462612 -217.08968) (xy 96.454835 -217.13977) (xy 96.439486 -217.188079)
			(xy 96.416925 -217.233471) (xy 96.387684 -217.274876) (xy 96.352452 -217.311319) (xy 96.312059 -217.341943)
			(xy 96.267455 -217.366024) (xy 96.219692 -217.382998) (xy 96.19488 -217.388186) (xy 96.17202 -217.392504)
			(xy 95.967042 -217.747596) (xy 95.974916 -217.76944) (xy 95.983506 -217.795856) (xy 95.992695 -217.850633)
			(xy 95.993204 -217.878406) (xy 96.274128 -217.878406) (xy 96.274636 -217.852519) (xy 96.282735 -217.801381)
			(xy 96.298734 -217.752141) (xy 96.32224 -217.706009) (xy 96.352672 -217.664122) (xy 96.389282 -217.627512)
			(xy 96.431169 -217.59708) (xy 96.477301 -217.573574) (xy 96.526541 -217.557575) (xy 96.577679 -217.549476)
			(xy 96.629453 -217.549476) (xy 96.680591 -217.557575) (xy 96.729831 -217.573574) (xy 96.775963 -217.59708)
			(xy 96.81785 -217.627512) (xy 96.85446 -217.664122) (xy 96.884892 -217.706009) (xy 96.908398 -217.752141)
			(xy 96.924397 -217.801381) (xy 96.932496 -217.852519) (xy 96.933004 -217.878406) (xy 97.213928 -217.878406)
			(xy 97.214394 -217.853071) (xy 97.222146 -217.802996) (xy 97.237469 -217.754698) (xy 97.260002 -217.709313)
			(xy 97.289214 -217.66791) (xy 97.324417 -217.631464) (xy 97.364782 -217.600835) (xy 97.409359 -217.576742)
			(xy 97.457097 -217.559754) (xy 97.481898 -217.554556) (xy 97.504758 -217.550238) (xy 97.709736 -217.195146)
			(xy 97.701862 -217.173302) (xy 97.693224 -217.146891) (xy 97.683899 -217.092117) (xy 97.68332 -217.064336)
			(xy 97.683828 -217.038429) (xy 97.691934 -216.987252) (xy 97.707946 -216.937973) (xy 97.731469 -216.891806)
			(xy 97.761925 -216.849887) (xy 97.798563 -216.813249) (xy 97.840482 -216.782793) (xy 97.886649 -216.75927)
			(xy 97.935928 -216.743258) (xy 97.987105 -216.735152) (xy 98.038919 -216.735152) (xy 98.090096 -216.743258)
			(xy 98.139375 -216.75927) (xy 98.185542 -216.782793) (xy 98.227461 -216.813249) (xy 98.264099 -216.849887)
			(xy 98.294555 -216.891806) (xy 98.318078 -216.937973) (xy 98.33409 -216.987252) (xy 98.342196 -217.038429)
			(xy 98.342704 -217.064336) (xy 98.342212 -217.08968) (xy 98.334435 -217.13977) (xy 98.319086 -217.188079)
			(xy 98.296525 -217.233471) (xy 98.267284 -217.274876) (xy 98.232052 -217.311319) (xy 98.191659 -217.341943)
			(xy 98.147055 -217.366024) (xy 98.099292 -217.382998) (xy 98.07448 -217.388186) (xy 98.05162 -217.392504)
			(xy 97.846642 -217.747596) (xy 97.854516 -217.76944) (xy 97.863106 -217.795856) (xy 97.872295 -217.850633)
			(xy 97.872804 -217.878406) (xy 98.153728 -217.878406) (xy 98.154236 -217.852519) (xy 98.162335 -217.801381)
			(xy 98.178334 -217.752141) (xy 98.20184 -217.706009) (xy 98.232272 -217.664122) (xy 98.268882 -217.627512)
			(xy 98.310769 -217.59708) (xy 98.356901 -217.573574) (xy 98.406141 -217.557575) (xy 98.457279 -217.549476)
			(xy 98.509053 -217.549476) (xy 98.560191 -217.557575) (xy 98.609431 -217.573574) (xy 98.655563 -217.59708)
			(xy 98.69745 -217.627512) (xy 98.73406 -217.664122) (xy 98.764492 -217.706009) (xy 98.787998 -217.752141)
			(xy 98.803997 -217.801381) (xy 98.812096 -217.852519) (xy 98.812604 -217.878406) (xy 99.093528 -217.878406)
			(xy 99.093994 -217.853071) (xy 99.101746 -217.802996) (xy 99.117069 -217.754698) (xy 99.139602 -217.709313)
			(xy 99.168814 -217.66791) (xy 99.204017 -217.631464) (xy 99.244382 -217.600835) (xy 99.288959 -217.576742)
			(xy 99.336697 -217.559754) (xy 99.361498 -217.554556) (xy 99.384358 -217.550238) (xy 99.589336 -217.195146)
			(xy 99.581462 -217.173302) (xy 99.572824 -217.146891) (xy 99.563499 -217.092117) (xy 99.56292 -217.064336)
			(xy 99.563428 -217.038429) (xy 99.571534 -216.987252) (xy 99.587546 -216.937973) (xy 99.611069 -216.891806)
			(xy 99.641525 -216.849887) (xy 99.678163 -216.813249) (xy 99.720082 -216.782793) (xy 99.766249 -216.75927)
			(xy 99.815528 -216.743258) (xy 99.866705 -216.735152) (xy 99.918519 -216.735152) (xy 99.969696 -216.743258)
			(xy 100.018975 -216.75927) (xy 100.065142 -216.782793) (xy 100.107061 -216.813249) (xy 100.143699 -216.849887)
			(xy 100.174155 -216.891806) (xy 100.197678 -216.937973) (xy 100.21369 -216.987252) (xy 100.221796 -217.038429)
			(xy 100.222304 -217.064336) (xy 100.221812 -217.08968) (xy 100.214035 -217.13977) (xy 100.198686 -217.188079)
			(xy 100.176125 -217.233471) (xy 100.146884 -217.274876) (xy 100.111652 -217.311319) (xy 100.071259 -217.341943)
			(xy 100.026655 -217.366024) (xy 99.978892 -217.382998) (xy 99.95408 -217.388186) (xy 99.93122 -217.392504)
			(xy 99.726242 -217.747596) (xy 99.734116 -217.76944) (xy 99.742706 -217.795856) (xy 99.751895 -217.850633)
			(xy 99.752404 -217.878406) (xy 100.033328 -217.878406) (xy 100.033836 -217.852519) (xy 100.041935 -217.801381)
			(xy 100.057934 -217.752141) (xy 100.08144 -217.706009) (xy 100.111872 -217.664122) (xy 100.148482 -217.627512)
			(xy 100.190369 -217.59708) (xy 100.236501 -217.573574) (xy 100.285741 -217.557575) (xy 100.336879 -217.549476)
			(xy 100.388653 -217.549476) (xy 100.439791 -217.557575) (xy 100.489031 -217.573574) (xy 100.535163 -217.59708)
			(xy 100.57705 -217.627512) (xy 100.61366 -217.664122) (xy 100.644092 -217.706009) (xy 100.667598 -217.752141)
			(xy 100.683597 -217.801381) (xy 100.691696 -217.852519) (xy 100.692204 -217.878406) (xy 100.973128 -217.878406)
			(xy 100.973594 -217.853071) (xy 100.981346 -217.802996) (xy 100.996669 -217.754698) (xy 101.019202 -217.709313)
			(xy 101.048414 -217.66791) (xy 101.083617 -217.631464) (xy 101.123982 -217.600835) (xy 101.168559 -217.576742)
			(xy 101.216297 -217.559754) (xy 101.241098 -217.554556) (xy 101.263958 -217.550238) (xy 101.468936 -217.195146)
			(xy 101.461062 -217.173302) (xy 101.452424 -217.146891) (xy 101.443099 -217.092117) (xy 101.44252 -217.064336)
			(xy 101.443028 -217.038429) (xy 101.451134 -216.987252) (xy 101.467146 -216.937973) (xy 101.490669 -216.891806)
			(xy 101.521125 -216.849887) (xy 101.557763 -216.813249) (xy 101.599682 -216.782793) (xy 101.645849 -216.75927)
			(xy 101.695128 -216.743258) (xy 101.746305 -216.735152) (xy 101.798119 -216.735152) (xy 101.849296 -216.743258)
			(xy 101.898575 -216.75927) (xy 101.944742 -216.782793) (xy 101.986661 -216.813249) (xy 102.023299 -216.849887)
			(xy 102.053755 -216.891806) (xy 102.077278 -216.937973) (xy 102.09329 -216.987252) (xy 102.101396 -217.038429)
			(xy 102.101904 -217.064336) (xy 102.101412 -217.08968) (xy 102.093635 -217.13977) (xy 102.078286 -217.188079)
			(xy 102.055725 -217.233471) (xy 102.026484 -217.274876) (xy 101.991252 -217.311319) (xy 101.950859 -217.341943)
			(xy 101.906255 -217.366024) (xy 101.858492 -217.382998) (xy 101.83368 -217.388186) (xy 101.81082 -217.392504)
			(xy 101.605842 -217.747596) (xy 101.613716 -217.76944) (xy 101.622306 -217.795856) (xy 101.631495 -217.850633)
			(xy 101.632004 -217.878406) (xy 101.912928 -217.878406) (xy 101.913436 -217.852519) (xy 101.921535 -217.801381)
			(xy 101.937534 -217.752141) (xy 101.96104 -217.706009) (xy 101.991472 -217.664122) (xy 102.028082 -217.627512)
			(xy 102.069969 -217.59708) (xy 102.116101 -217.573574) (xy 102.165341 -217.557575) (xy 102.216479 -217.549476)
			(xy 102.268253 -217.549476) (xy 102.319391 -217.557575) (xy 102.368631 -217.573574) (xy 102.414763 -217.59708)
			(xy 102.45665 -217.627512) (xy 102.49326 -217.664122) (xy 102.523692 -217.706009) (xy 102.547198 -217.752141)
			(xy 102.563197 -217.801381) (xy 102.571296 -217.852519) (xy 102.571804 -217.878406) (xy 102.852728 -217.878406)
			(xy 102.853194 -217.853071) (xy 102.860946 -217.802996) (xy 102.876269 -217.754698) (xy 102.898802 -217.709313)
			(xy 102.928014 -217.66791) (xy 102.963217 -217.631464) (xy 103.003582 -217.600835) (xy 103.048159 -217.576742)
			(xy 103.095897 -217.559754) (xy 103.120698 -217.554556) (xy 103.143558 -217.550238) (xy 103.348536 -217.195146)
			(xy 103.340662 -217.173302) (xy 103.332024 -217.146891) (xy 103.322699 -217.092117) (xy 103.32212 -217.064336)
			(xy 103.322628 -217.038429) (xy 103.330734 -216.987252) (xy 103.346746 -216.937973) (xy 103.370269 -216.891806)
			(xy 103.400725 -216.849887) (xy 103.437363 -216.813249) (xy 103.479282 -216.782793) (xy 103.525449 -216.75927)
			(xy 103.574728 -216.743258) (xy 103.625905 -216.735152) (xy 103.677719 -216.735152) (xy 103.728896 -216.743258)
			(xy 103.778175 -216.75927) (xy 103.824342 -216.782793) (xy 103.866261 -216.813249) (xy 103.902899 -216.849887)
			(xy 103.933355 -216.891806) (xy 103.956878 -216.937973) (xy 103.97289 -216.987252) (xy 103.980996 -217.038429)
			(xy 103.981504 -217.064336) (xy 103.981012 -217.08968) (xy 103.973235 -217.13977) (xy 103.957886 -217.188079)
			(xy 103.935325 -217.233471) (xy 103.906084 -217.274876) (xy 103.870852 -217.311319) (xy 103.830459 -217.341943)
			(xy 103.785855 -217.366024) (xy 103.738092 -217.382998) (xy 103.71328 -217.388186) (xy 103.69042 -217.392504)
			(xy 103.485442 -217.747596) (xy 103.493316 -217.76944) (xy 103.501906 -217.795856) (xy 103.511095 -217.850633)
			(xy 103.511604 -217.878406) (xy 103.792528 -217.878406) (xy 103.793036 -217.852519) (xy 103.801135 -217.801381)
			(xy 103.817134 -217.752141) (xy 103.84064 -217.706009) (xy 103.871072 -217.664122) (xy 103.907682 -217.627512)
			(xy 103.949569 -217.59708) (xy 103.995701 -217.573574) (xy 104.044941 -217.557575) (xy 104.096079 -217.549476)
			(xy 104.147853 -217.549476) (xy 104.198991 -217.557575) (xy 104.248231 -217.573574) (xy 104.294363 -217.59708)
			(xy 104.33625 -217.627512) (xy 104.37286 -217.664122) (xy 104.403292 -217.706009) (xy 104.426798 -217.752141)
			(xy 104.442797 -217.801381) (xy 104.450896 -217.852519) (xy 104.451404 -217.878406) (xy 104.732328 -217.878406)
			(xy 104.732794 -217.853071) (xy 104.740546 -217.802996) (xy 104.755869 -217.754698) (xy 104.778402 -217.709313)
			(xy 104.807614 -217.66791) (xy 104.842817 -217.631464) (xy 104.883182 -217.600835) (xy 104.927759 -217.576742)
			(xy 104.975497 -217.559754) (xy 105.000298 -217.554556) (xy 105.023158 -217.550238) (xy 105.228136 -217.195146)
			(xy 105.220262 -217.173302) (xy 105.211624 -217.146891) (xy 105.202299 -217.092117) (xy 105.20172 -217.064336)
			(xy 105.202228 -217.038429) (xy 105.210334 -216.987252) (xy 105.226346 -216.937973) (xy 105.249869 -216.891806)
			(xy 105.280325 -216.849887) (xy 105.316963 -216.813249) (xy 105.358882 -216.782793) (xy 105.405049 -216.75927)
			(xy 105.454328 -216.743258) (xy 105.505505 -216.735152) (xy 105.557319 -216.735152) (xy 105.608496 -216.743258)
			(xy 105.657775 -216.75927) (xy 105.703942 -216.782793) (xy 105.745861 -216.813249) (xy 105.782499 -216.849887)
			(xy 105.812955 -216.891806) (xy 105.836478 -216.937973) (xy 105.85249 -216.987252) (xy 105.860596 -217.038429)
			(xy 105.861104 -217.064336) (xy 105.860612 -217.08968) (xy 105.852835 -217.13977) (xy 105.837486 -217.188079)
			(xy 105.814925 -217.233471) (xy 105.785684 -217.274876) (xy 105.750452 -217.311319) (xy 105.710059 -217.341943)
			(xy 105.665455 -217.366024) (xy 105.617692 -217.382998) (xy 105.59288 -217.388186) (xy 105.57002 -217.392504)
			(xy 105.365042 -217.747596) (xy 105.372916 -217.76944) (xy 105.381506 -217.795856) (xy 105.390695 -217.850633)
			(xy 105.391204 -217.878406) (xy 105.672128 -217.878406) (xy 105.672636 -217.852519) (xy 105.680735 -217.801381)
			(xy 105.696734 -217.752141) (xy 105.72024 -217.706009) (xy 105.750672 -217.664122) (xy 105.787282 -217.627512)
			(xy 105.829169 -217.59708) (xy 105.875301 -217.573574) (xy 105.924541 -217.557575) (xy 105.975679 -217.549476)
			(xy 106.027453 -217.549476) (xy 106.078591 -217.557575) (xy 106.127831 -217.573574) (xy 106.173963 -217.59708)
			(xy 106.21585 -217.627512) (xy 106.25246 -217.664122) (xy 106.282892 -217.706009) (xy 106.306398 -217.752141)
			(xy 106.322397 -217.801381) (xy 106.330496 -217.852519) (xy 106.331004 -217.878406) (xy 106.611928 -217.878406)
			(xy 106.612394 -217.853071) (xy 106.620146 -217.802996) (xy 106.635469 -217.754698) (xy 106.658002 -217.709313)
			(xy 106.687214 -217.66791) (xy 106.722417 -217.631464) (xy 106.762782 -217.600835) (xy 106.807359 -217.576742)
			(xy 106.855097 -217.559754) (xy 106.879898 -217.554556) (xy 106.902758 -217.550238) (xy 107.107736 -217.195146)
			(xy 107.099862 -217.173302) (xy 107.091224 -217.146891) (xy 107.081899 -217.092117) (xy 107.08132 -217.064336)
			(xy 107.081828 -217.038429) (xy 107.089934 -216.987252) (xy 107.105946 -216.937973) (xy 107.129469 -216.891806)
			(xy 107.159925 -216.849887) (xy 107.196563 -216.813249) (xy 107.238482 -216.782793) (xy 107.284649 -216.75927)
			(xy 107.333928 -216.743258) (xy 107.385105 -216.735152) (xy 107.436919 -216.735152) (xy 107.488096 -216.743258)
			(xy 107.537375 -216.75927) (xy 107.583542 -216.782793) (xy 107.625461 -216.813249) (xy 107.662099 -216.849887)
			(xy 107.692555 -216.891806) (xy 107.716078 -216.937973) (xy 107.73209 -216.987252) (xy 107.740196 -217.038429)
			(xy 107.740704 -217.064336) (xy 107.740212 -217.08968) (xy 107.732435 -217.13977) (xy 107.717086 -217.188079)
			(xy 107.694525 -217.233471) (xy 107.665284 -217.274876) (xy 107.630052 -217.311319) (xy 107.589659 -217.341943)
			(xy 107.545055 -217.366024) (xy 107.497292 -217.382998) (xy 107.47248 -217.388186) (xy 107.44962 -217.392504)
			(xy 107.244642 -217.747596) (xy 107.252516 -217.76944) (xy 107.261106 -217.795856) (xy 107.270295 -217.850633)
			(xy 107.270804 -217.878406) (xy 107.551728 -217.878406) (xy 107.552236 -217.852519) (xy 107.560335 -217.801381)
			(xy 107.576334 -217.752141) (xy 107.59984 -217.706009) (xy 107.630272 -217.664122) (xy 107.666882 -217.627512)
			(xy 107.708769 -217.59708) (xy 107.754901 -217.573574) (xy 107.804141 -217.557575) (xy 107.855279 -217.549476)
			(xy 107.907053 -217.549476) (xy 107.958191 -217.557575) (xy 108.007431 -217.573574) (xy 108.053563 -217.59708)
			(xy 108.09545 -217.627512) (xy 108.13206 -217.664122) (xy 108.162492 -217.706009) (xy 108.185998 -217.752141)
			(xy 108.201997 -217.801381) (xy 108.210096 -217.852519) (xy 108.210604 -217.878406) (xy 108.491528 -217.878406)
			(xy 108.491994 -217.853071) (xy 108.499746 -217.802996) (xy 108.515069 -217.754698) (xy 108.537602 -217.709313)
			(xy 108.566814 -217.66791) (xy 108.602017 -217.631464) (xy 108.642382 -217.600835) (xy 108.686959 -217.576742)
			(xy 108.734697 -217.559754) (xy 108.759498 -217.554556) (xy 108.782358 -217.550238) (xy 108.987336 -217.195146)
			(xy 108.979462 -217.173302) (xy 108.970824 -217.146891) (xy 108.961499 -217.092117) (xy 108.96092 -217.064336)
			(xy 108.961428 -217.038429) (xy 108.969534 -216.987252) (xy 108.985546 -216.937973) (xy 109.009069 -216.891806)
			(xy 109.039525 -216.849887) (xy 109.076163 -216.813249) (xy 109.118082 -216.782793) (xy 109.164249 -216.75927)
			(xy 109.213528 -216.743258) (xy 109.264705 -216.735152) (xy 109.316519 -216.735152) (xy 109.367696 -216.743258)
			(xy 109.416975 -216.75927) (xy 109.463142 -216.782793) (xy 109.505061 -216.813249) (xy 109.541699 -216.849887)
			(xy 109.572155 -216.891806) (xy 109.595678 -216.937973) (xy 109.61169 -216.987252) (xy 109.619796 -217.038429)
			(xy 109.620304 -217.064336) (xy 109.619812 -217.08968) (xy 109.612035 -217.13977) (xy 109.596686 -217.188079)
			(xy 109.574125 -217.233471) (xy 109.544884 -217.274876) (xy 109.509652 -217.311319) (xy 109.469259 -217.341943)
			(xy 109.424655 -217.366024) (xy 109.376892 -217.382998) (xy 109.35208 -217.388186) (xy 109.32922 -217.392504)
			(xy 109.124242 -217.747596) (xy 109.132116 -217.76944) (xy 109.140706 -217.795856) (xy 109.149895 -217.850633)
			(xy 109.150404 -217.878406) (xy 109.431328 -217.878406) (xy 109.431836 -217.852519) (xy 109.439935 -217.801381)
			(xy 109.455934 -217.752141) (xy 109.47944 -217.706009) (xy 109.509872 -217.664122) (xy 109.546482 -217.627512)
			(xy 109.588369 -217.59708) (xy 109.634501 -217.573574) (xy 109.683741 -217.557575) (xy 109.734879 -217.549476)
			(xy 109.786653 -217.549476) (xy 109.837791 -217.557575) (xy 109.887031 -217.573574) (xy 109.933163 -217.59708)
			(xy 109.97505 -217.627512) (xy 110.01166 -217.664122) (xy 110.042092 -217.706009) (xy 110.065598 -217.752141)
			(xy 110.081597 -217.801381) (xy 110.089696 -217.852519) (xy 110.090204 -217.878406) (xy 110.371128 -217.878406)
			(xy 110.371594 -217.853071) (xy 110.379346 -217.802996) (xy 110.394669 -217.754698) (xy 110.417202 -217.709313)
			(xy 110.446414 -217.66791) (xy 110.481617 -217.631464) (xy 110.521982 -217.600835) (xy 110.566559 -217.576742)
			(xy 110.614297 -217.559754) (xy 110.639098 -217.554556) (xy 110.661958 -217.550238) (xy 110.866936 -217.194892)
			(xy 110.859316 -217.173048) (xy 110.850741 -217.146694) (xy 110.841552 -217.092045) (xy 110.841028 -217.064336)
			(xy 110.841536 -217.038449) (xy 110.849635 -216.987311) (xy 110.865634 -216.938071) (xy 110.88914 -216.891939)
			(xy 110.919572 -216.850052) (xy 110.956182 -216.813442) (xy 110.998069 -216.78301) (xy 111.044201 -216.759504)
			(xy 111.093441 -216.743505) (xy 111.144579 -216.735406) (xy 111.196353 -216.735406) (xy 111.247491 -216.743505)
			(xy 111.296731 -216.759504) (xy 111.342863 -216.78301) (xy 111.38475 -216.813442) (xy 111.42136 -216.850052)
			(xy 111.451792 -216.891939) (xy 111.475298 -216.938071) (xy 111.491297 -216.987311) (xy 111.499396 -217.038449)
			(xy 111.499904 -217.064336) (xy 112.72012 -217.064336) (xy 112.720628 -217.038429) (xy 112.728734 -216.987252)
			(xy 112.744746 -216.937973) (xy 112.768269 -216.891806) (xy 112.798725 -216.849887) (xy 112.835363 -216.813249)
			(xy 112.877282 -216.782793) (xy 112.923449 -216.75927) (xy 112.972728 -216.743258) (xy 113.023905 -216.735152)
			(xy 113.075719 -216.735152) (xy 113.126896 -216.743258) (xy 113.176175 -216.75927) (xy 113.222342 -216.782793)
			(xy 113.264261 -216.813249) (xy 113.300899 -216.849887) (xy 113.331355 -216.891806) (xy 113.354878 -216.937973)
			(xy 113.37089 -216.987252) (xy 113.378996 -217.038429) (xy 113.379504 -217.064336) (xy 114.59972 -217.064336)
			(xy 114.600228 -217.038429) (xy 114.608334 -216.987252) (xy 114.624346 -216.937973) (xy 114.647869 -216.891806)
			(xy 114.678325 -216.849887) (xy 114.714963 -216.813249) (xy 114.756882 -216.782793) (xy 114.803049 -216.75927)
			(xy 114.852328 -216.743258) (xy 114.903505 -216.735152) (xy 114.955319 -216.735152) (xy 115.006496 -216.743258)
			(xy 115.055775 -216.75927) (xy 115.101942 -216.782793) (xy 115.143861 -216.813249) (xy 115.180499 -216.849887)
			(xy 115.210955 -216.891806) (xy 115.234478 -216.937973) (xy 115.25049 -216.987252) (xy 115.258596 -217.038429)
			(xy 115.259104 -217.064336) (xy 116.47932 -217.064336) (xy 116.479828 -217.038429) (xy 116.487934 -216.987252)
			(xy 116.503946 -216.937973) (xy 116.527469 -216.891806) (xy 116.557925 -216.849887) (xy 116.594563 -216.813249)
			(xy 116.636482 -216.782793) (xy 116.682649 -216.75927) (xy 116.731928 -216.743258) (xy 116.783105 -216.735152)
			(xy 116.834919 -216.735152) (xy 116.886096 -216.743258) (xy 116.935375 -216.75927) (xy 116.981542 -216.782793)
			(xy 117.023461 -216.813249) (xy 117.060099 -216.849887) (xy 117.090555 -216.891806) (xy 117.114078 -216.937973)
			(xy 117.13009 -216.987252) (xy 117.138196 -217.038429) (xy 117.138704 -217.064336) (xy 118.35892 -217.064336)
			(xy 118.359428 -217.038429) (xy 118.367534 -216.987252) (xy 118.383546 -216.937973) (xy 118.407069 -216.891806)
			(xy 118.437525 -216.849887) (xy 118.474163 -216.813249) (xy 118.516082 -216.782793) (xy 118.562249 -216.75927)
			(xy 118.611528 -216.743258) (xy 118.662705 -216.735152) (xy 118.714519 -216.735152) (xy 118.765696 -216.743258)
			(xy 118.814975 -216.75927) (xy 118.861142 -216.782793) (xy 118.903061 -216.813249) (xy 118.939699 -216.849887)
			(xy 118.970155 -216.891806) (xy 118.993678 -216.937973) (xy 119.00969 -216.987252) (xy 119.017796 -217.038429)
			(xy 119.018304 -217.064336) (xy 120.23852 -217.064336) (xy 120.239028 -217.038429) (xy 120.247134 -216.987252)
			(xy 120.263146 -216.937973) (xy 120.286669 -216.891806) (xy 120.317125 -216.849887) (xy 120.353763 -216.813249)
			(xy 120.395682 -216.782793) (xy 120.441849 -216.75927) (xy 120.491128 -216.743258) (xy 120.542305 -216.735152)
			(xy 120.594119 -216.735152) (xy 120.645296 -216.743258) (xy 120.694575 -216.75927) (xy 120.740742 -216.782793)
			(xy 120.782661 -216.813249) (xy 120.819299 -216.849887) (xy 120.849755 -216.891806) (xy 120.873278 -216.937973)
			(xy 120.88929 -216.987252) (xy 120.897396 -217.038429) (xy 120.897904 -217.064336) (xy 122.11812 -217.064336)
			(xy 122.118628 -217.038429) (xy 122.126734 -216.987252) (xy 122.142746 -216.937973) (xy 122.166269 -216.891806)
			(xy 122.196725 -216.849887) (xy 122.233363 -216.813249) (xy 122.275282 -216.782793) (xy 122.321449 -216.75927)
			(xy 122.370728 -216.743258) (xy 122.421905 -216.735152) (xy 122.473719 -216.735152) (xy 122.524896 -216.743258)
			(xy 122.574175 -216.75927) (xy 122.620342 -216.782793) (xy 122.662261 -216.813249) (xy 122.698899 -216.849887)
			(xy 122.729355 -216.891806) (xy 122.752878 -216.937973) (xy 122.76889 -216.987252) (xy 122.776996 -217.038429)
			(xy 122.777504 -217.064336) (xy 123.99772 -217.064336) (xy 123.998228 -217.038429) (xy 124.006334 -216.987252)
			(xy 124.022346 -216.937973) (xy 124.045869 -216.891806) (xy 124.076325 -216.849887) (xy 124.112963 -216.813249)
			(xy 124.154882 -216.782793) (xy 124.201049 -216.75927) (xy 124.250328 -216.743258) (xy 124.301505 -216.735152)
			(xy 124.353319 -216.735152) (xy 124.404496 -216.743258) (xy 124.453775 -216.75927) (xy 124.499942 -216.782793)
			(xy 124.541861 -216.813249) (xy 124.578499 -216.849887) (xy 124.608955 -216.891806) (xy 124.632478 -216.937973)
			(xy 124.64849 -216.987252) (xy 124.656596 -217.038429) (xy 124.657104 -217.064336) (xy 125.87732 -217.064336)
			(xy 125.877828 -217.038429) (xy 125.885934 -216.987252) (xy 125.901946 -216.937973) (xy 125.925469 -216.891806)
			(xy 125.955925 -216.849887) (xy 125.992563 -216.813249) (xy 126.034482 -216.782793) (xy 126.080649 -216.75927)
			(xy 126.129928 -216.743258) (xy 126.181105 -216.735152) (xy 126.232919 -216.735152) (xy 126.284096 -216.743258)
			(xy 126.333375 -216.75927) (xy 126.379542 -216.782793) (xy 126.421461 -216.813249) (xy 126.458099 -216.849887)
			(xy 126.488555 -216.891806) (xy 126.512078 -216.937973) (xy 126.52809 -216.987252) (xy 126.536196 -217.038429)
			(xy 126.536704 -217.064336) (xy 127.75692 -217.064336) (xy 127.757428 -217.038429) (xy 127.765534 -216.987252)
			(xy 127.781546 -216.937973) (xy 127.805069 -216.891806) (xy 127.835525 -216.849887) (xy 127.872163 -216.813249)
			(xy 127.914082 -216.782793) (xy 127.960249 -216.75927) (xy 128.009528 -216.743258) (xy 128.060705 -216.735152)
			(xy 128.112519 -216.735152) (xy 128.163696 -216.743258) (xy 128.212975 -216.75927) (xy 128.259142 -216.782793)
			(xy 128.301061 -216.813249) (xy 128.337699 -216.849887) (xy 128.368155 -216.891806) (xy 128.391678 -216.937973)
			(xy 128.40769 -216.987252) (xy 128.415796 -217.038429) (xy 128.416304 -217.064336) (xy 129.63652 -217.064336)
			(xy 129.637028 -217.038429) (xy 129.645134 -216.987252) (xy 129.661146 -216.937973) (xy 129.684669 -216.891806)
			(xy 129.715125 -216.849887) (xy 129.751763 -216.813249) (xy 129.793682 -216.782793) (xy 129.839849 -216.75927)
			(xy 129.889128 -216.743258) (xy 129.940305 -216.735152) (xy 129.992119 -216.735152) (xy 130.043296 -216.743258)
			(xy 130.092575 -216.75927) (xy 130.138742 -216.782793) (xy 130.180661 -216.813249) (xy 130.217299 -216.849887)
			(xy 130.247755 -216.891806) (xy 130.271278 -216.937973) (xy 130.28729 -216.987252) (xy 130.295396 -217.038429)
			(xy 130.295904 -217.064336) (xy 131.51612 -217.064336) (xy 131.516628 -217.038429) (xy 131.524734 -216.987252)
			(xy 131.540746 -216.937973) (xy 131.564269 -216.891806) (xy 131.594725 -216.849887) (xy 131.631363 -216.813249)
			(xy 131.673282 -216.782793) (xy 131.719449 -216.75927) (xy 131.768728 -216.743258) (xy 131.819905 -216.735152)
			(xy 131.871719 -216.735152) (xy 131.922896 -216.743258) (xy 131.972175 -216.75927) (xy 132.018342 -216.782793)
			(xy 132.060261 -216.813249) (xy 132.096899 -216.849887) (xy 132.127355 -216.891806) (xy 132.150878 -216.937973)
			(xy 132.16689 -216.987252) (xy 132.174996 -217.038429) (xy 132.175504 -217.064336) (xy 133.39572 -217.064336)
			(xy 133.396228 -217.038429) (xy 133.404334 -216.987252) (xy 133.420346 -216.937973) (xy 133.443869 -216.891806)
			(xy 133.474325 -216.849887) (xy 133.510963 -216.813249) (xy 133.552882 -216.782793) (xy 133.599049 -216.75927)
			(xy 133.648328 -216.743258) (xy 133.699505 -216.735152) (xy 133.751319 -216.735152) (xy 133.802496 -216.743258)
			(xy 133.851775 -216.75927) (xy 133.897942 -216.782793) (xy 133.939861 -216.813249) (xy 133.976499 -216.849887)
			(xy 134.006955 -216.891806) (xy 134.030478 -216.937973) (xy 134.04649 -216.987252) (xy 134.054596 -217.038429)
			(xy 134.055104 -217.064336) (xy 134.054489 -217.091989) (xy 134.045169 -217.146507) (xy 134.036562 -217.172794)
			(xy 134.028942 -217.194892) (xy 134.234174 -217.550238) (xy 134.257034 -217.554556) (xy 134.281841 -217.559728)
			(xy 134.329579 -217.576721) (xy 134.374156 -217.600818) (xy 134.41452 -217.631451) (xy 134.449723 -217.6679)
			(xy 134.478934 -217.709305) (xy 134.501466 -217.754693) (xy 134.516789 -217.802993) (xy 134.524541 -217.85307)
			(xy 134.525004 -217.878406) (xy 336.695796 -217.878406) (xy 336.696304 -217.852519) (xy 336.704403 -217.801381)
			(xy 336.720402 -217.752141) (xy 336.743908 -217.706009) (xy 336.77434 -217.664122) (xy 336.81095 -217.627512)
			(xy 336.852837 -217.59708) (xy 336.898969 -217.573574) (xy 336.948209 -217.557575) (xy 336.999347 -217.549476)
			(xy 337.051121 -217.549476) (xy 337.102259 -217.557575) (xy 337.151499 -217.573574) (xy 337.197631 -217.59708)
			(xy 337.239518 -217.627512) (xy 337.276128 -217.664122) (xy 337.30656 -217.706009) (xy 337.330066 -217.752141)
			(xy 337.346065 -217.801381) (xy 337.354164 -217.852519) (xy 337.354672 -217.878406) (xy 337.635596 -217.878406)
			(xy 337.636088 -217.853072) (xy 337.643839 -217.803) (xy 337.65916 -217.754704) (xy 337.681691 -217.70932)
			(xy 337.710899 -217.667918) (xy 337.746099 -217.631473) (xy 337.78646 -217.600842) (xy 337.831033 -217.576747)
			(xy 337.878767 -217.559756) (xy 337.903566 -217.554556) (xy 337.926426 -217.550238) (xy 338.131404 -217.195146)
			(xy 338.12353 -217.173302) (xy 338.114891 -217.146892) (xy 338.105567 -217.092117) (xy 338.104988 -217.064336)
			(xy 338.105496 -217.038429) (xy 338.113602 -216.987252) (xy 338.129614 -216.937973) (xy 338.153137 -216.891806)
			(xy 338.183593 -216.849887) (xy 338.220231 -216.813249) (xy 338.26215 -216.782793) (xy 338.308317 -216.75927)
			(xy 338.357596 -216.743258) (xy 338.408773 -216.735152) (xy 338.460587 -216.735152) (xy 338.511764 -216.743258)
			(xy 338.561043 -216.75927) (xy 338.60721 -216.782793) (xy 338.649129 -216.813249) (xy 338.685767 -216.849887)
			(xy 338.716223 -216.891806) (xy 338.739746 -216.937973) (xy 338.755758 -216.987252) (xy 338.763864 -217.038429)
			(xy 338.764372 -217.064336) (xy 338.763906 -217.089682) (xy 338.756128 -217.139773) (xy 338.740777 -217.188085)
			(xy 338.718213 -217.233478) (xy 338.688969 -217.274884) (xy 338.653734 -217.311328) (xy 338.613336 -217.34195)
			(xy 338.568729 -217.36603) (xy 338.520962 -217.383) (xy 338.496148 -217.388186) (xy 338.473288 -217.392504)
			(xy 338.26831 -217.747596) (xy 338.276184 -217.76944) (xy 338.284773 -217.795856) (xy 338.293963 -217.850633)
			(xy 338.294472 -217.878406) (xy 338.575396 -217.878406) (xy 338.575904 -217.852519) (xy 338.584003 -217.801381)
			(xy 338.600002 -217.752141) (xy 338.623508 -217.706009) (xy 338.65394 -217.664122) (xy 338.69055 -217.627512)
			(xy 338.732437 -217.59708) (xy 338.778569 -217.573574) (xy 338.827809 -217.557575) (xy 338.878947 -217.549476)
			(xy 338.930721 -217.549476) (xy 338.981859 -217.557575) (xy 339.031099 -217.573574) (xy 339.077231 -217.59708)
			(xy 339.119118 -217.627512) (xy 339.155728 -217.664122) (xy 339.18616 -217.706009) (xy 339.209666 -217.752141)
			(xy 339.225665 -217.801381) (xy 339.233764 -217.852519) (xy 339.234272 -217.878406) (xy 339.515196 -217.878406)
			(xy 339.515688 -217.853072) (xy 339.523439 -217.803) (xy 339.53876 -217.754704) (xy 339.561291 -217.70932)
			(xy 339.590499 -217.667918) (xy 339.625699 -217.631473) (xy 339.66606 -217.600842) (xy 339.710633 -217.576747)
			(xy 339.758367 -217.559756) (xy 339.783166 -217.554556) (xy 339.806026 -217.550238) (xy 340.011004 -217.195146)
			(xy 340.00313 -217.173302) (xy 339.994491 -217.146892) (xy 339.985167 -217.092117) (xy 339.984588 -217.064336)
			(xy 339.985096 -217.038429) (xy 339.993202 -216.987252) (xy 340.009214 -216.937973) (xy 340.032737 -216.891806)
			(xy 340.063193 -216.849887) (xy 340.099831 -216.813249) (xy 340.14175 -216.782793) (xy 340.187917 -216.75927)
			(xy 340.237196 -216.743258) (xy 340.288373 -216.735152) (xy 340.340187 -216.735152) (xy 340.391364 -216.743258)
			(xy 340.440643 -216.75927) (xy 340.48681 -216.782793) (xy 340.528729 -216.813249) (xy 340.565367 -216.849887)
			(xy 340.595823 -216.891806) (xy 340.619346 -216.937973) (xy 340.635358 -216.987252) (xy 340.643464 -217.038429)
			(xy 340.643972 -217.064336) (xy 340.643506 -217.089682) (xy 340.635728 -217.139773) (xy 340.620377 -217.188085)
			(xy 340.597813 -217.233478) (xy 340.568569 -217.274884) (xy 340.533334 -217.311328) (xy 340.492936 -217.34195)
			(xy 340.448329 -217.36603) (xy 340.400562 -217.383) (xy 340.375748 -217.388186) (xy 340.352888 -217.392504)
			(xy 340.14791 -217.747596) (xy 340.155784 -217.76944) (xy 340.164373 -217.795856) (xy 340.173563 -217.850633)
			(xy 340.174072 -217.878406) (xy 340.454996 -217.878406) (xy 340.455504 -217.852519) (xy 340.463603 -217.801381)
			(xy 340.479602 -217.752141) (xy 340.503108 -217.706009) (xy 340.53354 -217.664122) (xy 340.57015 -217.627512)
			(xy 340.612037 -217.59708) (xy 340.658169 -217.573574) (xy 340.707409 -217.557575) (xy 340.758547 -217.549476)
			(xy 340.810321 -217.549476) (xy 340.861459 -217.557575) (xy 340.910699 -217.573574) (xy 340.956831 -217.59708)
			(xy 340.998718 -217.627512) (xy 341.035328 -217.664122) (xy 341.06576 -217.706009) (xy 341.089266 -217.752141)
			(xy 341.105265 -217.801381) (xy 341.113364 -217.852519) (xy 341.113872 -217.878406) (xy 341.394796 -217.878406)
			(xy 341.395288 -217.853072) (xy 341.403039 -217.803) (xy 341.41836 -217.754704) (xy 341.440891 -217.70932)
			(xy 341.470099 -217.667918) (xy 341.505299 -217.631473) (xy 341.54566 -217.600842) (xy 341.590233 -217.576747)
			(xy 341.637967 -217.559756) (xy 341.662766 -217.554556) (xy 341.685626 -217.550238) (xy 341.890604 -217.195146)
			(xy 341.88273 -217.173302) (xy 341.874091 -217.146892) (xy 341.864767 -217.092117) (xy 341.864188 -217.064336)
			(xy 341.864696 -217.038429) (xy 341.872802 -216.987252) (xy 341.888814 -216.937973) (xy 341.912337 -216.891806)
			(xy 341.942793 -216.849887) (xy 341.979431 -216.813249) (xy 342.02135 -216.782793) (xy 342.067517 -216.75927)
			(xy 342.116796 -216.743258) (xy 342.167973 -216.735152) (xy 342.219787 -216.735152) (xy 342.270964 -216.743258)
			(xy 342.320243 -216.75927) (xy 342.36641 -216.782793) (xy 342.408329 -216.813249) (xy 342.444967 -216.849887)
			(xy 342.475423 -216.891806) (xy 342.498946 -216.937973) (xy 342.514958 -216.987252) (xy 342.523064 -217.038429)
			(xy 342.523572 -217.064336) (xy 342.523106 -217.089682) (xy 342.515328 -217.139773) (xy 342.499977 -217.188085)
			(xy 342.477413 -217.233478) (xy 342.448169 -217.274884) (xy 342.412934 -217.311328) (xy 342.372536 -217.34195)
			(xy 342.327929 -217.36603) (xy 342.280162 -217.383) (xy 342.255348 -217.388186) (xy 342.232488 -217.392504)
			(xy 342.02751 -217.747596) (xy 342.035384 -217.76944) (xy 342.043973 -217.795856) (xy 342.053163 -217.850633)
			(xy 342.053672 -217.878406) (xy 342.334596 -217.878406) (xy 342.335104 -217.852519) (xy 342.343203 -217.801381)
			(xy 342.359202 -217.752141) (xy 342.382708 -217.706009) (xy 342.41314 -217.664122) (xy 342.44975 -217.627512)
			(xy 342.491637 -217.59708) (xy 342.537769 -217.573574) (xy 342.587009 -217.557575) (xy 342.638147 -217.549476)
			(xy 342.689921 -217.549476) (xy 342.741059 -217.557575) (xy 342.790299 -217.573574) (xy 342.836431 -217.59708)
			(xy 342.878318 -217.627512) (xy 342.914928 -217.664122) (xy 342.94536 -217.706009) (xy 342.968866 -217.752141)
			(xy 342.984865 -217.801381) (xy 342.992964 -217.852519) (xy 342.993472 -217.878406) (xy 343.274396 -217.878406)
			(xy 343.274888 -217.853072) (xy 343.282639 -217.803) (xy 343.29796 -217.754704) (xy 343.320491 -217.70932)
			(xy 343.349699 -217.667918) (xy 343.384899 -217.631473) (xy 343.42526 -217.600842) (xy 343.469833 -217.576747)
			(xy 343.517567 -217.559756) (xy 343.542366 -217.554556) (xy 343.565226 -217.550238) (xy 343.770204 -217.195146)
			(xy 343.76233 -217.173302) (xy 343.753691 -217.146892) (xy 343.744367 -217.092117) (xy 343.743788 -217.064336)
			(xy 343.744296 -217.038429) (xy 343.752402 -216.987252) (xy 343.768414 -216.937973) (xy 343.791937 -216.891806)
			(xy 343.822393 -216.849887) (xy 343.859031 -216.813249) (xy 343.90095 -216.782793) (xy 343.947117 -216.75927)
			(xy 343.996396 -216.743258) (xy 344.047573 -216.735152) (xy 344.099387 -216.735152) (xy 344.150564 -216.743258)
			(xy 344.199843 -216.75927) (xy 344.24601 -216.782793) (xy 344.287929 -216.813249) (xy 344.324567 -216.849887)
			(xy 344.355023 -216.891806) (xy 344.378546 -216.937973) (xy 344.394558 -216.987252) (xy 344.402664 -217.038429)
			(xy 344.403172 -217.064336) (xy 344.402706 -217.089682) (xy 344.394928 -217.139773) (xy 344.379577 -217.188085)
			(xy 344.357013 -217.233478) (xy 344.327769 -217.274884) (xy 344.292534 -217.311328) (xy 344.252136 -217.34195)
			(xy 344.207529 -217.36603) (xy 344.159762 -217.383) (xy 344.134948 -217.388186) (xy 344.112088 -217.392504)
			(xy 343.90711 -217.747596) (xy 343.914984 -217.76944) (xy 343.923573 -217.795856) (xy 343.932763 -217.850633)
			(xy 343.933272 -217.878406) (xy 344.214196 -217.878406) (xy 344.214704 -217.852519) (xy 344.222803 -217.801381)
			(xy 344.238802 -217.752141) (xy 344.262308 -217.706009) (xy 344.29274 -217.664122) (xy 344.32935 -217.627512)
			(xy 344.371237 -217.59708) (xy 344.417369 -217.573574) (xy 344.466609 -217.557575) (xy 344.517747 -217.549476)
			(xy 344.569521 -217.549476) (xy 344.620659 -217.557575) (xy 344.669899 -217.573574) (xy 344.716031 -217.59708)
			(xy 344.757918 -217.627512) (xy 344.794528 -217.664122) (xy 344.82496 -217.706009) (xy 344.848466 -217.752141)
			(xy 344.864465 -217.801381) (xy 344.872564 -217.852519) (xy 344.873072 -217.878406) (xy 345.153996 -217.878406)
			(xy 345.154488 -217.853072) (xy 345.162239 -217.803) (xy 345.17756 -217.754704) (xy 345.200091 -217.70932)
			(xy 345.229299 -217.667918) (xy 345.264499 -217.631473) (xy 345.30486 -217.600842) (xy 345.349433 -217.576747)
			(xy 345.397167 -217.559756) (xy 345.421966 -217.554556) (xy 345.444826 -217.550238) (xy 345.649804 -217.195146)
			(xy 345.64193 -217.173302) (xy 345.633291 -217.146892) (xy 345.623967 -217.092117) (xy 345.623388 -217.064336)
			(xy 345.623896 -217.038429) (xy 345.632002 -216.987252) (xy 345.648014 -216.937973) (xy 345.671537 -216.891806)
			(xy 345.701993 -216.849887) (xy 345.738631 -216.813249) (xy 345.78055 -216.782793) (xy 345.826717 -216.75927)
			(xy 345.875996 -216.743258) (xy 345.927173 -216.735152) (xy 345.978987 -216.735152) (xy 346.030164 -216.743258)
			(xy 346.079443 -216.75927) (xy 346.12561 -216.782793) (xy 346.167529 -216.813249) (xy 346.204167 -216.849887)
			(xy 346.234623 -216.891806) (xy 346.258146 -216.937973) (xy 346.274158 -216.987252) (xy 346.282264 -217.038429)
			(xy 346.282772 -217.064336) (xy 346.282306 -217.089682) (xy 346.274528 -217.139773) (xy 346.259177 -217.188085)
			(xy 346.236613 -217.233478) (xy 346.207369 -217.274884) (xy 346.172134 -217.311328) (xy 346.131736 -217.34195)
			(xy 346.087129 -217.36603) (xy 346.039362 -217.383) (xy 346.014548 -217.388186) (xy 345.991688 -217.392504)
			(xy 345.78671 -217.747596) (xy 345.794584 -217.76944) (xy 345.803173 -217.795856) (xy 345.812363 -217.850633)
			(xy 345.812872 -217.878406) (xy 346.093796 -217.878406) (xy 346.094304 -217.852519) (xy 346.102403 -217.801381)
			(xy 346.118402 -217.752141) (xy 346.141908 -217.706009) (xy 346.17234 -217.664122) (xy 346.20895 -217.627512)
			(xy 346.250837 -217.59708) (xy 346.296969 -217.573574) (xy 346.346209 -217.557575) (xy 346.397347 -217.549476)
			(xy 346.449121 -217.549476) (xy 346.500259 -217.557575) (xy 346.549499 -217.573574) (xy 346.595631 -217.59708)
			(xy 346.637518 -217.627512) (xy 346.674128 -217.664122) (xy 346.70456 -217.706009) (xy 346.728066 -217.752141)
			(xy 346.744065 -217.801381) (xy 346.752164 -217.852519) (xy 346.752672 -217.878406) (xy 347.033596 -217.878406)
			(xy 347.034088 -217.853072) (xy 347.041839 -217.803) (xy 347.05716 -217.754704) (xy 347.079691 -217.70932)
			(xy 347.108899 -217.667918) (xy 347.144099 -217.631473) (xy 347.18446 -217.600842) (xy 347.229033 -217.576747)
			(xy 347.276767 -217.559756) (xy 347.301566 -217.554556) (xy 347.324426 -217.550238) (xy 347.529404 -217.195146)
			(xy 347.52153 -217.173302) (xy 347.512891 -217.146892) (xy 347.503567 -217.092117) (xy 347.502988 -217.064336)
			(xy 347.503496 -217.038429) (xy 347.511602 -216.987252) (xy 347.527614 -216.937973) (xy 347.551137 -216.891806)
			(xy 347.581593 -216.849887) (xy 347.618231 -216.813249) (xy 347.66015 -216.782793) (xy 347.706317 -216.75927)
			(xy 347.755596 -216.743258) (xy 347.806773 -216.735152) (xy 347.858587 -216.735152) (xy 347.909764 -216.743258)
			(xy 347.959043 -216.75927) (xy 348.00521 -216.782793) (xy 348.047129 -216.813249) (xy 348.083767 -216.849887)
			(xy 348.114223 -216.891806) (xy 348.137746 -216.937973) (xy 348.153758 -216.987252) (xy 348.161864 -217.038429)
			(xy 348.162372 -217.064336) (xy 348.161906 -217.089682) (xy 348.154128 -217.139773) (xy 348.138777 -217.188085)
			(xy 348.116213 -217.233478) (xy 348.086969 -217.274884) (xy 348.051734 -217.311328) (xy 348.011336 -217.34195)
			(xy 347.966729 -217.36603) (xy 347.918962 -217.383) (xy 347.894148 -217.388186) (xy 347.871288 -217.392504)
			(xy 347.66631 -217.747596) (xy 347.674184 -217.76944) (xy 347.682773 -217.795856) (xy 347.691963 -217.850633)
			(xy 347.692472 -217.878406) (xy 347.973396 -217.878406) (xy 347.973904 -217.852519) (xy 347.982003 -217.801381)
			(xy 347.998002 -217.752141) (xy 348.021508 -217.706009) (xy 348.05194 -217.664122) (xy 348.08855 -217.627512)
			(xy 348.130437 -217.59708) (xy 348.176569 -217.573574) (xy 348.225809 -217.557575) (xy 348.276947 -217.549476)
			(xy 348.328721 -217.549476) (xy 348.379859 -217.557575) (xy 348.429099 -217.573574) (xy 348.475231 -217.59708)
			(xy 348.517118 -217.627512) (xy 348.553728 -217.664122) (xy 348.58416 -217.706009) (xy 348.607666 -217.752141)
			(xy 348.623665 -217.801381) (xy 348.631764 -217.852519) (xy 348.632272 -217.878406) (xy 348.913196 -217.878406)
			(xy 348.913688 -217.853072) (xy 348.921439 -217.803) (xy 348.93676 -217.754704) (xy 348.959291 -217.70932)
			(xy 348.988499 -217.667918) (xy 349.023699 -217.631473) (xy 349.06406 -217.600842) (xy 349.108633 -217.576747)
			(xy 349.156367 -217.559756) (xy 349.181166 -217.554556) (xy 349.204026 -217.550238) (xy 349.409004 -217.195146)
			(xy 349.40113 -217.173302) (xy 349.392491 -217.146892) (xy 349.383167 -217.092117) (xy 349.382588 -217.064336)
			(xy 349.383096 -217.038429) (xy 349.391202 -216.987252) (xy 349.407214 -216.937973) (xy 349.430737 -216.891806)
			(xy 349.461193 -216.849887) (xy 349.497831 -216.813249) (xy 349.53975 -216.782793) (xy 349.585917 -216.75927)
			(xy 349.635196 -216.743258) (xy 349.686373 -216.735152) (xy 349.738187 -216.735152) (xy 349.789364 -216.743258)
			(xy 349.838643 -216.75927) (xy 349.88481 -216.782793) (xy 349.926729 -216.813249) (xy 349.963367 -216.849887)
			(xy 349.993823 -216.891806) (xy 350.017346 -216.937973) (xy 350.033358 -216.987252) (xy 350.041464 -217.038429)
			(xy 350.041972 -217.064336) (xy 350.041506 -217.089682) (xy 350.033728 -217.139773) (xy 350.018377 -217.188085)
			(xy 349.995813 -217.233478) (xy 349.966569 -217.274884) (xy 349.931334 -217.311328) (xy 349.890936 -217.34195)
			(xy 349.846329 -217.36603) (xy 349.798562 -217.383) (xy 349.773748 -217.388186) (xy 349.750888 -217.392504)
			(xy 349.54591 -217.747596) (xy 349.553784 -217.76944) (xy 349.562373 -217.795856) (xy 349.571563 -217.850633)
			(xy 349.572072 -217.878406) (xy 349.852996 -217.878406) (xy 349.853504 -217.852519) (xy 349.861603 -217.801381)
			(xy 349.877602 -217.752141) (xy 349.901108 -217.706009) (xy 349.93154 -217.664122) (xy 349.96815 -217.627512)
			(xy 350.010037 -217.59708) (xy 350.056169 -217.573574) (xy 350.105409 -217.557575) (xy 350.156547 -217.549476)
			(xy 350.208321 -217.549476) (xy 350.259459 -217.557575) (xy 350.308699 -217.573574) (xy 350.354831 -217.59708)
			(xy 350.396718 -217.627512) (xy 350.433328 -217.664122) (xy 350.46376 -217.706009) (xy 350.487266 -217.752141)
			(xy 350.503265 -217.801381) (xy 350.511364 -217.852519) (xy 350.511872 -217.878406) (xy 350.792796 -217.878406)
			(xy 350.793288 -217.853072) (xy 350.801039 -217.803) (xy 350.81636 -217.754704) (xy 350.838891 -217.70932)
			(xy 350.868099 -217.667918) (xy 350.903299 -217.631473) (xy 350.94366 -217.600842) (xy 350.988233 -217.576747)
			(xy 351.035967 -217.559756) (xy 351.060766 -217.554556) (xy 351.083626 -217.550238) (xy 351.288604 -217.195146)
			(xy 351.28073 -217.173302) (xy 351.272091 -217.146892) (xy 351.262767 -217.092117) (xy 351.262188 -217.064336)
			(xy 351.262696 -217.038429) (xy 351.270802 -216.987252) (xy 351.286814 -216.937973) (xy 351.310337 -216.891806)
			(xy 351.340793 -216.849887) (xy 351.377431 -216.813249) (xy 351.41935 -216.782793) (xy 351.465517 -216.75927)
			(xy 351.514796 -216.743258) (xy 351.565973 -216.735152) (xy 351.617787 -216.735152) (xy 351.668964 -216.743258)
			(xy 351.718243 -216.75927) (xy 351.76441 -216.782793) (xy 351.806329 -216.813249) (xy 351.842967 -216.849887)
			(xy 351.873423 -216.891806) (xy 351.896946 -216.937973) (xy 351.912958 -216.987252) (xy 351.921064 -217.038429)
			(xy 351.921572 -217.064336) (xy 351.921106 -217.089682) (xy 351.913328 -217.139773) (xy 351.897977 -217.188085)
			(xy 351.875413 -217.233478) (xy 351.846169 -217.274884) (xy 351.810934 -217.311328) (xy 351.770536 -217.34195)
			(xy 351.725929 -217.36603) (xy 351.678162 -217.383) (xy 351.653348 -217.388186) (xy 351.630488 -217.392504)
			(xy 351.42551 -217.747596) (xy 351.433384 -217.76944) (xy 351.441973 -217.795856) (xy 351.451163 -217.850633)
			(xy 351.451672 -217.878406) (xy 351.732596 -217.878406) (xy 351.733104 -217.852519) (xy 351.741203 -217.801381)
			(xy 351.757202 -217.752141) (xy 351.780708 -217.706009) (xy 351.81114 -217.664122) (xy 351.84775 -217.627512)
			(xy 351.889637 -217.59708) (xy 351.935769 -217.573574) (xy 351.985009 -217.557575) (xy 352.036147 -217.549476)
			(xy 352.087921 -217.549476) (xy 352.139059 -217.557575) (xy 352.188299 -217.573574) (xy 352.234431 -217.59708)
			(xy 352.276318 -217.627512) (xy 352.312928 -217.664122) (xy 352.34336 -217.706009) (xy 352.366866 -217.752141)
			(xy 352.382865 -217.801381) (xy 352.390964 -217.852519) (xy 352.391472 -217.878406) (xy 352.672396 -217.878406)
			(xy 352.672888 -217.853072) (xy 352.680639 -217.803) (xy 352.69596 -217.754704) (xy 352.718491 -217.70932)
			(xy 352.747699 -217.667918) (xy 352.782899 -217.631473) (xy 352.82326 -217.600842) (xy 352.867833 -217.576747)
			(xy 352.915567 -217.559756) (xy 352.940366 -217.554556) (xy 352.963226 -217.550238) (xy 353.168204 -217.195146)
			(xy 353.16033 -217.173302) (xy 353.151691 -217.146892) (xy 353.142367 -217.092117) (xy 353.141788 -217.064336)
			(xy 353.142296 -217.038429) (xy 353.150402 -216.987252) (xy 353.166414 -216.937973) (xy 353.189937 -216.891806)
			(xy 353.220393 -216.849887) (xy 353.257031 -216.813249) (xy 353.29895 -216.782793) (xy 353.345117 -216.75927)
			(xy 353.394396 -216.743258) (xy 353.445573 -216.735152) (xy 353.497387 -216.735152) (xy 353.548564 -216.743258)
			(xy 353.597843 -216.75927) (xy 353.64401 -216.782793) (xy 353.685929 -216.813249) (xy 353.722567 -216.849887)
			(xy 353.753023 -216.891806) (xy 353.776546 -216.937973) (xy 353.792558 -216.987252) (xy 353.800664 -217.038429)
			(xy 353.801172 -217.064336) (xy 353.800706 -217.089682) (xy 353.792928 -217.139773) (xy 353.777577 -217.188085)
			(xy 353.755013 -217.233478) (xy 353.725769 -217.274884) (xy 353.690534 -217.311328) (xy 353.650136 -217.34195)
			(xy 353.605529 -217.36603) (xy 353.557762 -217.383) (xy 353.532948 -217.388186) (xy 353.510088 -217.392504)
			(xy 353.30511 -217.747596) (xy 353.312984 -217.76944) (xy 353.321573 -217.795856) (xy 353.330763 -217.850633)
			(xy 353.331272 -217.878406) (xy 353.612196 -217.878406) (xy 353.612704 -217.852519) (xy 353.620803 -217.801381)
			(xy 353.636802 -217.752141) (xy 353.660308 -217.706009) (xy 353.69074 -217.664122) (xy 353.72735 -217.627512)
			(xy 353.769237 -217.59708) (xy 353.815369 -217.573574) (xy 353.864609 -217.557575) (xy 353.915747 -217.549476)
			(xy 353.967521 -217.549476) (xy 354.018659 -217.557575) (xy 354.067899 -217.573574) (xy 354.114031 -217.59708)
			(xy 354.155918 -217.627512) (xy 354.192528 -217.664122) (xy 354.22296 -217.706009) (xy 354.246466 -217.752141)
			(xy 354.262465 -217.801381) (xy 354.270564 -217.852519) (xy 354.271072 -217.878406) (xy 354.551996 -217.878406)
			(xy 354.552488 -217.853072) (xy 354.560239 -217.803) (xy 354.57556 -217.754704) (xy 354.598091 -217.70932)
			(xy 354.627299 -217.667918) (xy 354.662499 -217.631473) (xy 354.70286 -217.600842) (xy 354.747433 -217.576747)
			(xy 354.795167 -217.559756) (xy 354.819966 -217.554556) (xy 354.842826 -217.550238) (xy 355.047804 -217.195146)
			(xy 355.03993 -217.173302) (xy 355.031291 -217.146892) (xy 355.021967 -217.092117) (xy 355.021388 -217.064336)
			(xy 355.021896 -217.038429) (xy 355.030002 -216.987252) (xy 355.046014 -216.937973) (xy 355.069537 -216.891806)
			(xy 355.099993 -216.849887) (xy 355.136631 -216.813249) (xy 355.17855 -216.782793) (xy 355.224717 -216.75927)
			(xy 355.273996 -216.743258) (xy 355.325173 -216.735152) (xy 355.376987 -216.735152) (xy 355.428164 -216.743258)
			(xy 355.477443 -216.75927) (xy 355.52361 -216.782793) (xy 355.565529 -216.813249) (xy 355.602167 -216.849887)
			(xy 355.632623 -216.891806) (xy 355.656146 -216.937973) (xy 355.672158 -216.987252) (xy 355.680264 -217.038429)
			(xy 355.680772 -217.064336) (xy 355.680306 -217.089682) (xy 355.672528 -217.139773) (xy 355.657177 -217.188085)
			(xy 355.634613 -217.233478) (xy 355.605369 -217.274884) (xy 355.570134 -217.311328) (xy 355.529736 -217.34195)
			(xy 355.485129 -217.36603) (xy 355.437362 -217.383) (xy 355.412548 -217.388186) (xy 355.389688 -217.392504)
			(xy 355.18471 -217.747596) (xy 355.192584 -217.76944) (xy 355.201173 -217.795856) (xy 355.210363 -217.850633)
			(xy 355.210872 -217.878406) (xy 355.491796 -217.878406) (xy 355.492304 -217.852519) (xy 355.500403 -217.801381)
			(xy 355.516402 -217.752141) (xy 355.539908 -217.706009) (xy 355.57034 -217.664122) (xy 355.60695 -217.627512)
			(xy 355.648837 -217.59708) (xy 355.694969 -217.573574) (xy 355.744209 -217.557575) (xy 355.795347 -217.549476)
			(xy 355.847121 -217.549476) (xy 355.898259 -217.557575) (xy 355.947499 -217.573574) (xy 355.993631 -217.59708)
			(xy 356.035518 -217.627512) (xy 356.072128 -217.664122) (xy 356.10256 -217.706009) (xy 356.126066 -217.752141)
			(xy 356.142065 -217.801381) (xy 356.150164 -217.852519) (xy 356.150672 -217.878406) (xy 356.431596 -217.878406)
			(xy 356.432088 -217.853072) (xy 356.439839 -217.803) (xy 356.45516 -217.754704) (xy 356.477691 -217.70932)
			(xy 356.506899 -217.667918) (xy 356.542099 -217.631473) (xy 356.58246 -217.600842) (xy 356.627033 -217.576747)
			(xy 356.674767 -217.559756) (xy 356.699566 -217.554556) (xy 356.722426 -217.550238) (xy 356.927404 -217.195146)
			(xy 356.91953 -217.173302) (xy 356.910891 -217.146892) (xy 356.901567 -217.092117) (xy 356.900988 -217.064336)
			(xy 356.901496 -217.038429) (xy 356.909602 -216.987252) (xy 356.925614 -216.937973) (xy 356.949137 -216.891806)
			(xy 356.979593 -216.849887) (xy 357.016231 -216.813249) (xy 357.05815 -216.782793) (xy 357.104317 -216.75927)
			(xy 357.153596 -216.743258) (xy 357.204773 -216.735152) (xy 357.256587 -216.735152) (xy 357.307764 -216.743258)
			(xy 357.357043 -216.75927) (xy 357.40321 -216.782793) (xy 357.445129 -216.813249) (xy 357.481767 -216.849887)
			(xy 357.512223 -216.891806) (xy 357.535746 -216.937973) (xy 357.551758 -216.987252) (xy 357.559864 -217.038429)
			(xy 357.560372 -217.064336) (xy 357.559906 -217.089682) (xy 357.552128 -217.139773) (xy 357.536777 -217.188085)
			(xy 357.514213 -217.233478) (xy 357.484969 -217.274884) (xy 357.449734 -217.311328) (xy 357.409336 -217.34195)
			(xy 357.364729 -217.36603) (xy 357.316962 -217.383) (xy 357.292148 -217.388186) (xy 357.269288 -217.392504)
			(xy 357.06431 -217.747596) (xy 357.072184 -217.76944) (xy 357.080773 -217.795856) (xy 357.089963 -217.850633)
			(xy 357.090472 -217.878406) (xy 357.371396 -217.878406) (xy 357.371904 -217.852519) (xy 357.380003 -217.801381)
			(xy 357.396002 -217.752141) (xy 357.419508 -217.706009) (xy 357.44994 -217.664122) (xy 357.48655 -217.627512)
			(xy 357.528437 -217.59708) (xy 357.574569 -217.573574) (xy 357.623809 -217.557575) (xy 357.674947 -217.549476)
			(xy 357.726721 -217.549476) (xy 357.777859 -217.557575) (xy 357.827099 -217.573574) (xy 357.873231 -217.59708)
			(xy 357.915118 -217.627512) (xy 357.951728 -217.664122) (xy 357.98216 -217.706009) (xy 358.005666 -217.752141)
			(xy 358.021665 -217.801381) (xy 358.029764 -217.852519) (xy 358.030272 -217.878406) (xy 358.311196 -217.878406)
			(xy 358.311688 -217.853072) (xy 358.319439 -217.803) (xy 358.33476 -217.754704) (xy 358.357291 -217.70932)
			(xy 358.386499 -217.667918) (xy 358.421699 -217.631473) (xy 358.46206 -217.600842) (xy 358.506633 -217.576747)
			(xy 358.554367 -217.559756) (xy 358.579166 -217.554556) (xy 358.602026 -217.550238) (xy 358.807004 -217.194892)
			(xy 358.799384 -217.173048) (xy 358.790811 -217.146694) (xy 358.78162 -217.092045) (xy 358.781096 -217.064336)
			(xy 358.781604 -217.038449) (xy 358.789703 -216.987311) (xy 358.805702 -216.938071) (xy 358.829208 -216.891939)
			(xy 358.85964 -216.850052) (xy 358.89625 -216.813442) (xy 358.938137 -216.78301) (xy 358.984269 -216.759504)
			(xy 359.033509 -216.743505) (xy 359.084647 -216.735406) (xy 359.136421 -216.735406) (xy 359.187559 -216.743505)
			(xy 359.236799 -216.759504) (xy 359.282931 -216.78301) (xy 359.324818 -216.813442) (xy 359.361428 -216.850052)
			(xy 359.39186 -216.891939) (xy 359.415366 -216.938071) (xy 359.431365 -216.987311) (xy 359.439464 -217.038449)
			(xy 359.439972 -217.064336) (xy 360.660188 -217.064336) (xy 360.660696 -217.038429) (xy 360.668802 -216.987252)
			(xy 360.684814 -216.937973) (xy 360.708337 -216.891806) (xy 360.738793 -216.849887) (xy 360.775431 -216.813249)
			(xy 360.81735 -216.782793) (xy 360.863517 -216.75927) (xy 360.912796 -216.743258) (xy 360.963973 -216.735152)
			(xy 361.015787 -216.735152) (xy 361.066964 -216.743258) (xy 361.116243 -216.75927) (xy 361.16241 -216.782793)
			(xy 361.204329 -216.813249) (xy 361.240967 -216.849887) (xy 361.271423 -216.891806) (xy 361.294946 -216.937973)
			(xy 361.310958 -216.987252) (xy 361.319064 -217.038429) (xy 361.319572 -217.064336) (xy 362.539788 -217.064336)
			(xy 362.540296 -217.038429) (xy 362.548402 -216.987252) (xy 362.564414 -216.937973) (xy 362.587937 -216.891806)
			(xy 362.618393 -216.849887) (xy 362.655031 -216.813249) (xy 362.69695 -216.782793) (xy 362.743117 -216.75927)
			(xy 362.792396 -216.743258) (xy 362.843573 -216.735152) (xy 362.895387 -216.735152) (xy 362.946564 -216.743258)
			(xy 362.995843 -216.75927) (xy 363.04201 -216.782793) (xy 363.083929 -216.813249) (xy 363.120567 -216.849887)
			(xy 363.151023 -216.891806) (xy 363.174546 -216.937973) (xy 363.190558 -216.987252) (xy 363.198664 -217.038429)
			(xy 363.199172 -217.064336) (xy 364.419388 -217.064336) (xy 364.419896 -217.038429) (xy 364.428002 -216.987252)
			(xy 364.444014 -216.937973) (xy 364.467537 -216.891806) (xy 364.497993 -216.849887) (xy 364.534631 -216.813249)
			(xy 364.57655 -216.782793) (xy 364.622717 -216.75927) (xy 364.671996 -216.743258) (xy 364.723173 -216.735152)
			(xy 364.774987 -216.735152) (xy 364.826164 -216.743258) (xy 364.875443 -216.75927) (xy 364.92161 -216.782793)
			(xy 364.963529 -216.813249) (xy 365.000167 -216.849887) (xy 365.030623 -216.891806) (xy 365.054146 -216.937973)
			(xy 365.070158 -216.987252) (xy 365.078264 -217.038429) (xy 365.078772 -217.064336) (xy 366.298988 -217.064336)
			(xy 366.299496 -217.038429) (xy 366.307602 -216.987252) (xy 366.323614 -216.937973) (xy 366.347137 -216.891806)
			(xy 366.377593 -216.849887) (xy 366.414231 -216.813249) (xy 366.45615 -216.782793) (xy 366.502317 -216.75927)
			(xy 366.551596 -216.743258) (xy 366.602773 -216.735152) (xy 366.654587 -216.735152) (xy 366.705764 -216.743258)
			(xy 366.755043 -216.75927) (xy 366.80121 -216.782793) (xy 366.843129 -216.813249) (xy 366.879767 -216.849887)
			(xy 366.910223 -216.891806) (xy 366.933746 -216.937973) (xy 366.949758 -216.987252) (xy 366.957864 -217.038429)
			(xy 366.958372 -217.064336) (xy 368.178588 -217.064336) (xy 368.179096 -217.038429) (xy 368.187202 -216.987252)
			(xy 368.203214 -216.937973) (xy 368.226737 -216.891806) (xy 368.257193 -216.849887) (xy 368.293831 -216.813249)
			(xy 368.33575 -216.782793) (xy 368.381917 -216.75927) (xy 368.431196 -216.743258) (xy 368.482373 -216.735152)
			(xy 368.534187 -216.735152) (xy 368.585364 -216.743258) (xy 368.634643 -216.75927) (xy 368.68081 -216.782793)
			(xy 368.722729 -216.813249) (xy 368.759367 -216.849887) (xy 368.789823 -216.891806) (xy 368.813346 -216.937973)
			(xy 368.829358 -216.987252) (xy 368.837464 -217.038429) (xy 368.837972 -217.064336) (xy 370.058188 -217.064336)
			(xy 370.058696 -217.038429) (xy 370.066802 -216.987252) (xy 370.082814 -216.937973) (xy 370.106337 -216.891806)
			(xy 370.136793 -216.849887) (xy 370.173431 -216.813249) (xy 370.21535 -216.782793) (xy 370.261517 -216.75927)
			(xy 370.310796 -216.743258) (xy 370.361973 -216.735152) (xy 370.413787 -216.735152) (xy 370.464964 -216.743258)
			(xy 370.514243 -216.75927) (xy 370.56041 -216.782793) (xy 370.602329 -216.813249) (xy 370.638967 -216.849887)
			(xy 370.669423 -216.891806) (xy 370.692946 -216.937973) (xy 370.708958 -216.987252) (xy 370.717064 -217.038429)
			(xy 370.717572 -217.064336) (xy 371.937788 -217.064336) (xy 371.938296 -217.038429) (xy 371.946402 -216.987252)
			(xy 371.962414 -216.937973) (xy 371.985937 -216.891806) (xy 372.016393 -216.849887) (xy 372.053031 -216.813249)
			(xy 372.09495 -216.782793) (xy 372.141117 -216.75927) (xy 372.190396 -216.743258) (xy 372.241573 -216.735152)
			(xy 372.293387 -216.735152) (xy 372.344564 -216.743258) (xy 372.393843 -216.75927) (xy 372.44001 -216.782793)
			(xy 372.481929 -216.813249) (xy 372.518567 -216.849887) (xy 372.549023 -216.891806) (xy 372.572546 -216.937973)
			(xy 372.588558 -216.987252) (xy 372.596664 -217.038429) (xy 372.597172 -217.064336) (xy 373.817388 -217.064336)
			(xy 373.817896 -217.038429) (xy 373.826002 -216.987252) (xy 373.842014 -216.937973) (xy 373.865537 -216.891806)
			(xy 373.895993 -216.849887) (xy 373.932631 -216.813249) (xy 373.97455 -216.782793) (xy 374.020717 -216.75927)
			(xy 374.069996 -216.743258) (xy 374.121173 -216.735152) (xy 374.172987 -216.735152) (xy 374.224164 -216.743258)
			(xy 374.273443 -216.75927) (xy 374.31961 -216.782793) (xy 374.361529 -216.813249) (xy 374.398167 -216.849887)
			(xy 374.428623 -216.891806) (xy 374.452146 -216.937973) (xy 374.468158 -216.987252) (xy 374.476264 -217.038429)
			(xy 374.476772 -217.064336) (xy 375.696988 -217.064336) (xy 375.697496 -217.038429) (xy 375.705602 -216.987252)
			(xy 375.721614 -216.937973) (xy 375.745137 -216.891806) (xy 375.775593 -216.849887) (xy 375.812231 -216.813249)
			(xy 375.85415 -216.782793) (xy 375.900317 -216.75927) (xy 375.949596 -216.743258) (xy 376.000773 -216.735152)
			(xy 376.052587 -216.735152) (xy 376.103764 -216.743258) (xy 376.153043 -216.75927) (xy 376.19921 -216.782793)
			(xy 376.241129 -216.813249) (xy 376.277767 -216.849887) (xy 376.308223 -216.891806) (xy 376.331746 -216.937973)
			(xy 376.347758 -216.987252) (xy 376.355864 -217.038429) (xy 376.356372 -217.064336) (xy 377.576588 -217.064336)
			(xy 377.577096 -217.038429) (xy 377.585202 -216.987252) (xy 377.601214 -216.937973) (xy 377.624737 -216.891806)
			(xy 377.655193 -216.849887) (xy 377.691831 -216.813249) (xy 377.73375 -216.782793) (xy 377.779917 -216.75927)
			(xy 377.829196 -216.743258) (xy 377.880373 -216.735152) (xy 377.932187 -216.735152) (xy 377.983364 -216.743258)
			(xy 378.032643 -216.75927) (xy 378.07881 -216.782793) (xy 378.120729 -216.813249) (xy 378.157367 -216.849887)
			(xy 378.187823 -216.891806) (xy 378.211346 -216.937973) (xy 378.227358 -216.987252) (xy 378.235464 -217.038429)
			(xy 378.235972 -217.064336) (xy 379.456188 -217.064336) (xy 379.456696 -217.038429) (xy 379.464802 -216.987252)
			(xy 379.480814 -216.937973) (xy 379.504337 -216.891806) (xy 379.534793 -216.849887) (xy 379.571431 -216.813249)
			(xy 379.61335 -216.782793) (xy 379.659517 -216.75927) (xy 379.708796 -216.743258) (xy 379.759973 -216.735152)
			(xy 379.811787 -216.735152) (xy 379.862964 -216.743258) (xy 379.912243 -216.75927) (xy 379.95841 -216.782793)
			(xy 380.000329 -216.813249) (xy 380.036967 -216.849887) (xy 380.067423 -216.891806) (xy 380.090946 -216.937973)
			(xy 380.106958 -216.987252) (xy 380.115064 -217.038429) (xy 380.115572 -217.064336) (xy 381.335788 -217.064336)
			(xy 381.336296 -217.038429) (xy 381.344402 -216.987252) (xy 381.360414 -216.937973) (xy 381.383937 -216.891806)
			(xy 381.414393 -216.849887) (xy 381.451031 -216.813249) (xy 381.49295 -216.782793) (xy 381.539117 -216.75927)
			(xy 381.588396 -216.743258) (xy 381.639573 -216.735152) (xy 381.691387 -216.735152) (xy 381.742564 -216.743258)
			(xy 381.791843 -216.75927) (xy 381.83801 -216.782793) (xy 381.879929 -216.813249) (xy 381.916567 -216.849887)
			(xy 381.947023 -216.891806) (xy 381.970546 -216.937973) (xy 381.986558 -216.987252) (xy 381.994664 -217.038429)
			(xy 381.995172 -217.064336) (xy 381.994559 -217.091989) (xy 381.985238 -217.146507) (xy 381.97663 -217.172794)
			(xy 381.96901 -217.194892) (xy 382.174242 -217.550238) (xy 382.197102 -217.554556) (xy 382.221903 -217.559751)
			(xy 382.269642 -217.57674) (xy 382.314219 -217.600833) (xy 382.354584 -217.631463) (xy 382.389788 -217.667908)
			(xy 382.419 -217.709312) (xy 382.441533 -217.754697) (xy 382.456856 -217.802996) (xy 382.464608 -217.85307)
			(xy 382.465072 -217.878406) (xy 382.464564 -217.904293) (xy 382.456465 -217.955431) (xy 382.440466 -218.004671)
			(xy 382.41696 -218.050803) (xy 382.386528 -218.09269) (xy 382.349918 -218.1293) (xy 382.308031 -218.159732)
			(xy 382.261899 -218.183238) (xy 382.212659 -218.199237) (xy 382.161521 -218.207336) (xy 382.109747 -218.207336)
			(xy 382.058609 -218.199237) (xy 382.009369 -218.183238) (xy 381.963237 -218.159732) (xy 381.92135 -218.1293)
			(xy 381.88474 -218.09269) (xy 381.854308 -218.050803) (xy 381.830802 -218.004671) (xy 381.814803 -217.955431)
			(xy 381.806704 -217.904293) (xy 381.806196 -217.878406) (xy 381.806727 -217.850698) (xy 381.815921 -217.796051)
			(xy 381.824484 -217.769694) (xy 381.832358 -217.747596) (xy 381.62738 -217.392504) (xy 381.60452 -217.388186)
			(xy 381.579675 -217.38302) (xy 381.531826 -217.366126) (xy 381.487133 -217.342096) (xy 381.446653 -217.311499)
			(xy 381.411341 -217.275058) (xy 381.382033 -217.233634) (xy 381.359422 -217.188207) (xy 381.344043 -217.13985)
			(xy 381.336258 -217.089708) (xy 381.335788 -217.064336) (xy 380.115572 -217.064336) (xy 380.114959 -217.091989)
			(xy 380.105638 -217.146507) (xy 380.09703 -217.172794) (xy 380.08941 -217.194892) (xy 380.294642 -217.550238)
			(xy 380.317502 -217.554556) (xy 380.342303 -217.559751) (xy 380.390042 -217.57674) (xy 380.434619 -217.600833)
			(xy 380.474984 -217.631463) (xy 380.510188 -217.667908) (xy 380.5394 -217.709312) (xy 380.561933 -217.754697)
			(xy 380.577256 -217.802996) (xy 380.585008 -217.85307) (xy 380.585472 -217.878406) (xy 380.584964 -217.904293)
			(xy 380.576865 -217.955431) (xy 380.560866 -218.004671) (xy 380.53736 -218.050803) (xy 380.506928 -218.09269)
			(xy 380.470318 -218.1293) (xy 380.428431 -218.159732) (xy 380.382299 -218.183238) (xy 380.333059 -218.199237)
			(xy 380.281921 -218.207336) (xy 380.230147 -218.207336) (xy 380.179009 -218.199237) (xy 380.129769 -218.183238)
			(xy 380.083637 -218.159732) (xy 380.04175 -218.1293) (xy 380.00514 -218.09269) (xy 379.974708 -218.050803)
			(xy 379.951202 -218.004671) (xy 379.935203 -217.955431) (xy 379.927104 -217.904293) (xy 379.926596 -217.878406)
			(xy 379.927127 -217.850698) (xy 379.936321 -217.796051) (xy 379.944884 -217.769694) (xy 379.952758 -217.747596)
			(xy 379.74778 -217.392504) (xy 379.72492 -217.388186) (xy 379.700075 -217.38302) (xy 379.652226 -217.366126)
			(xy 379.607533 -217.342096) (xy 379.567053 -217.311499) (xy 379.531741 -217.275058) (xy 379.502433 -217.233634)
			(xy 379.479822 -217.188207) (xy 379.464443 -217.13985) (xy 379.456658 -217.089708) (xy 379.456188 -217.064336)
			(xy 378.235972 -217.064336) (xy 378.235359 -217.091989) (xy 378.226038 -217.146507) (xy 378.21743 -217.172794)
			(xy 378.20981 -217.194892) (xy 378.415042 -217.550238) (xy 378.437902 -217.554556) (xy 378.462703 -217.559751)
			(xy 378.510442 -217.57674) (xy 378.555019 -217.600833) (xy 378.595384 -217.631463) (xy 378.630588 -217.667908)
			(xy 378.6598 -217.709312) (xy 378.682333 -217.754697) (xy 378.697656 -217.802996) (xy 378.705408 -217.85307)
			(xy 378.705872 -217.878406) (xy 378.705364 -217.904293) (xy 378.697265 -217.955431) (xy 378.681266 -218.004671)
			(xy 378.65776 -218.050803) (xy 378.627328 -218.09269) (xy 378.590718 -218.1293) (xy 378.548831 -218.159732)
			(xy 378.502699 -218.183238) (xy 378.453459 -218.199237) (xy 378.402321 -218.207336) (xy 378.350547 -218.207336)
			(xy 378.299409 -218.199237) (xy 378.250169 -218.183238) (xy 378.204037 -218.159732) (xy 378.16215 -218.1293)
			(xy 378.12554 -218.09269) (xy 378.095108 -218.050803) (xy 378.071602 -218.004671) (xy 378.055603 -217.955431)
			(xy 378.047504 -217.904293) (xy 378.046996 -217.878406) (xy 378.047527 -217.850698) (xy 378.056721 -217.796051)
			(xy 378.065284 -217.769694) (xy 378.073158 -217.747596) (xy 377.86818 -217.392504) (xy 377.84532 -217.388186)
			(xy 377.820475 -217.38302) (xy 377.772626 -217.366126) (xy 377.727933 -217.342096) (xy 377.687453 -217.311499)
			(xy 377.652141 -217.275058) (xy 377.622833 -217.233634) (xy 377.600222 -217.188207) (xy 377.584843 -217.13985)
			(xy 377.577058 -217.089708) (xy 377.576588 -217.064336) (xy 376.356372 -217.064336) (xy 376.355759 -217.091989)
			(xy 376.346438 -217.146507) (xy 376.33783 -217.172794) (xy 376.33021 -217.194892) (xy 376.535442 -217.550238)
			(xy 376.558302 -217.554556) (xy 376.583103 -217.559751) (xy 376.630842 -217.57674) (xy 376.675419 -217.600833)
			(xy 376.715784 -217.631463) (xy 376.750988 -217.667908) (xy 376.7802 -217.709312) (xy 376.802733 -217.754697)
			(xy 376.818056 -217.802996) (xy 376.825808 -217.85307) (xy 376.826272 -217.878406) (xy 376.825764 -217.904293)
			(xy 376.817665 -217.955431) (xy 376.801666 -218.004671) (xy 376.77816 -218.050803) (xy 376.747728 -218.09269)
			(xy 376.711118 -218.1293) (xy 376.669231 -218.159732) (xy 376.623099 -218.183238) (xy 376.573859 -218.199237)
			(xy 376.522721 -218.207336) (xy 376.470947 -218.207336) (xy 376.419809 -218.199237) (xy 376.370569 -218.183238)
			(xy 376.324437 -218.159732) (xy 376.28255 -218.1293) (xy 376.24594 -218.09269) (xy 376.215508 -218.050803)
			(xy 376.192002 -218.004671) (xy 376.176003 -217.955431) (xy 376.167904 -217.904293) (xy 376.167396 -217.878406)
			(xy 376.167927 -217.850698) (xy 376.177121 -217.796051) (xy 376.185684 -217.769694) (xy 376.193558 -217.747596)
			(xy 375.98858 -217.392504) (xy 375.96572 -217.388186) (xy 375.940875 -217.38302) (xy 375.893026 -217.366126)
			(xy 375.848333 -217.342096) (xy 375.807853 -217.311499) (xy 375.772541 -217.275058) (xy 375.743233 -217.233634)
			(xy 375.720622 -217.188207) (xy 375.705243 -217.13985) (xy 375.697458 -217.089708) (xy 375.696988 -217.064336)
			(xy 374.476772 -217.064336) (xy 374.476159 -217.091989) (xy 374.466838 -217.146507) (xy 374.45823 -217.172794)
			(xy 374.45061 -217.194892) (xy 374.655842 -217.550238) (xy 374.678702 -217.554556) (xy 374.703503 -217.559751)
			(xy 374.751242 -217.57674) (xy 374.795819 -217.600833) (xy 374.836184 -217.631463) (xy 374.871388 -217.667908)
			(xy 374.9006 -217.709312) (xy 374.923133 -217.754697) (xy 374.938456 -217.802996) (xy 374.946208 -217.85307)
			(xy 374.946672 -217.878406) (xy 374.946164 -217.904293) (xy 374.938065 -217.955431) (xy 374.922066 -218.004671)
			(xy 374.89856 -218.050803) (xy 374.868128 -218.09269) (xy 374.831518 -218.1293) (xy 374.789631 -218.159732)
			(xy 374.743499 -218.183238) (xy 374.694259 -218.199237) (xy 374.643121 -218.207336) (xy 374.591347 -218.207336)
			(xy 374.540209 -218.199237) (xy 374.490969 -218.183238) (xy 374.444837 -218.159732) (xy 374.40295 -218.1293)
			(xy 374.36634 -218.09269) (xy 374.335908 -218.050803) (xy 374.312402 -218.004671) (xy 374.296403 -217.955431)
			(xy 374.288304 -217.904293) (xy 374.287796 -217.878406) (xy 374.288327 -217.850698) (xy 374.297521 -217.796051)
			(xy 374.306084 -217.769694) (xy 374.313958 -217.747596) (xy 374.10898 -217.392504) (xy 374.08612 -217.388186)
			(xy 374.061275 -217.38302) (xy 374.013426 -217.366126) (xy 373.968733 -217.342096) (xy 373.928253 -217.311499)
			(xy 373.892941 -217.275058) (xy 373.863633 -217.233634) (xy 373.841022 -217.188207) (xy 373.825643 -217.13985)
			(xy 373.817858 -217.089708) (xy 373.817388 -217.064336) (xy 372.597172 -217.064336) (xy 372.596559 -217.091989)
			(xy 372.587238 -217.146507) (xy 372.57863 -217.172794) (xy 372.57101 -217.194892) (xy 372.776242 -217.550238)
			(xy 372.799102 -217.554556) (xy 372.823903 -217.559751) (xy 372.871642 -217.57674) (xy 372.916219 -217.600833)
			(xy 372.956584 -217.631463) (xy 372.991788 -217.667908) (xy 373.021 -217.709312) (xy 373.043533 -217.754697)
			(xy 373.058856 -217.802996) (xy 373.066608 -217.85307) (xy 373.067072 -217.878406) (xy 373.066564 -217.904293)
			(xy 373.058465 -217.955431) (xy 373.042466 -218.004671) (xy 373.01896 -218.050803) (xy 372.988528 -218.09269)
			(xy 372.951918 -218.1293) (xy 372.910031 -218.159732) (xy 372.863899 -218.183238) (xy 372.814659 -218.199237)
			(xy 372.763521 -218.207336) (xy 372.711747 -218.207336) (xy 372.660609 -218.199237) (xy 372.611369 -218.183238)
			(xy 372.565237 -218.159732) (xy 372.52335 -218.1293) (xy 372.48674 -218.09269) (xy 372.456308 -218.050803)
			(xy 372.432802 -218.004671) (xy 372.416803 -217.955431) (xy 372.408704 -217.904293) (xy 372.408196 -217.878406)
			(xy 372.408727 -217.850698) (xy 372.417921 -217.796051) (xy 372.426484 -217.769694) (xy 372.434358 -217.747596)
			(xy 372.22938 -217.392504) (xy 372.20652 -217.388186) (xy 372.181675 -217.38302) (xy 372.133826 -217.366126)
			(xy 372.089133 -217.342096) (xy 372.048653 -217.311499) (xy 372.013341 -217.275058) (xy 371.984033 -217.233634)
			(xy 371.961422 -217.188207) (xy 371.946043 -217.13985) (xy 371.938258 -217.089708) (xy 371.937788 -217.064336)
			(xy 370.717572 -217.064336) (xy 370.716959 -217.091989) (xy 370.707638 -217.146507) (xy 370.69903 -217.172794)
			(xy 370.69141 -217.194892) (xy 370.896642 -217.550238) (xy 370.919502 -217.554556) (xy 370.944303 -217.559751)
			(xy 370.992042 -217.57674) (xy 371.036619 -217.600833) (xy 371.076984 -217.631463) (xy 371.112188 -217.667908)
			(xy 371.1414 -217.709312) (xy 371.163933 -217.754697) (xy 371.179256 -217.802996) (xy 371.187008 -217.85307)
			(xy 371.187472 -217.878406) (xy 371.186964 -217.904293) (xy 371.178865 -217.955431) (xy 371.162866 -218.004671)
			(xy 371.13936 -218.050803) (xy 371.108928 -218.09269) (xy 371.072318 -218.1293) (xy 371.030431 -218.159732)
			(xy 370.984299 -218.183238) (xy 370.935059 -218.199237) (xy 370.883921 -218.207336) (xy 370.832147 -218.207336)
			(xy 370.781009 -218.199237) (xy 370.731769 -218.183238) (xy 370.685637 -218.159732) (xy 370.64375 -218.1293)
			(xy 370.60714 -218.09269) (xy 370.576708 -218.050803) (xy 370.553202 -218.004671) (xy 370.537203 -217.955431)
			(xy 370.529104 -217.904293) (xy 370.528596 -217.878406) (xy 370.529127 -217.850698) (xy 370.538321 -217.796051)
			(xy 370.546884 -217.769694) (xy 370.554758 -217.747596) (xy 370.34978 -217.392504) (xy 370.32692 -217.388186)
			(xy 370.302075 -217.38302) (xy 370.254226 -217.366126) (xy 370.209533 -217.342096) (xy 370.169053 -217.311499)
			(xy 370.133741 -217.275058) (xy 370.104433 -217.233634) (xy 370.081822 -217.188207) (xy 370.066443 -217.13985)
			(xy 370.058658 -217.089708) (xy 370.058188 -217.064336) (xy 368.837972 -217.064336) (xy 368.837359 -217.091989)
			(xy 368.828038 -217.146507) (xy 368.81943 -217.172794) (xy 368.81181 -217.194892) (xy 369.017042 -217.550238)
			(xy 369.039902 -217.554556) (xy 369.064703 -217.559751) (xy 369.112442 -217.57674) (xy 369.157019 -217.600833)
			(xy 369.197384 -217.631463) (xy 369.232588 -217.667908) (xy 369.2618 -217.709312) (xy 369.284333 -217.754697)
			(xy 369.299656 -217.802996) (xy 369.307408 -217.85307) (xy 369.307872 -217.878406) (xy 369.307364 -217.904293)
			(xy 369.299265 -217.955431) (xy 369.283266 -218.004671) (xy 369.25976 -218.050803) (xy 369.229328 -218.09269)
			(xy 369.192718 -218.1293) (xy 369.150831 -218.159732) (xy 369.104699 -218.183238) (xy 369.055459 -218.199237)
			(xy 369.004321 -218.207336) (xy 368.952547 -218.207336) (xy 368.901409 -218.199237) (xy 368.852169 -218.183238)
			(xy 368.806037 -218.159732) (xy 368.76415 -218.1293) (xy 368.72754 -218.09269) (xy 368.697108 -218.050803)
			(xy 368.673602 -218.004671) (xy 368.657603 -217.955431) (xy 368.649504 -217.904293) (xy 368.648996 -217.878406)
			(xy 368.649527 -217.850698) (xy 368.658721 -217.796051) (xy 368.667284 -217.769694) (xy 368.675158 -217.747596)
			(xy 368.47018 -217.392504) (xy 368.44732 -217.388186) (xy 368.422475 -217.38302) (xy 368.374626 -217.366126)
			(xy 368.329933 -217.342096) (xy 368.289453 -217.311499) (xy 368.254141 -217.275058) (xy 368.224833 -217.233634)
			(xy 368.202222 -217.188207) (xy 368.186843 -217.13985) (xy 368.179058 -217.089708) (xy 368.178588 -217.064336)
			(xy 366.958372 -217.064336) (xy 366.957759 -217.091989) (xy 366.948438 -217.146507) (xy 366.93983 -217.172794)
			(xy 366.93221 -217.194892) (xy 367.137442 -217.550238) (xy 367.160302 -217.554556) (xy 367.185103 -217.559751)
			(xy 367.232842 -217.57674) (xy 367.277419 -217.600833) (xy 367.317784 -217.631463) (xy 367.352988 -217.667908)
			(xy 367.3822 -217.709312) (xy 367.404733 -217.754697) (xy 367.420056 -217.802996) (xy 367.427808 -217.85307)
			(xy 367.428272 -217.878406) (xy 367.427764 -217.904293) (xy 367.419665 -217.955431) (xy 367.403666 -218.004671)
			(xy 367.38016 -218.050803) (xy 367.349728 -218.09269) (xy 367.313118 -218.1293) (xy 367.271231 -218.159732)
			(xy 367.225099 -218.183238) (xy 367.175859 -218.199237) (xy 367.124721 -218.207336) (xy 367.072947 -218.207336)
			(xy 367.021809 -218.199237) (xy 366.972569 -218.183238) (xy 366.926437 -218.159732) (xy 366.88455 -218.1293)
			(xy 366.84794 -218.09269) (xy 366.817508 -218.050803) (xy 366.794002 -218.004671) (xy 366.778003 -217.955431)
			(xy 366.769904 -217.904293) (xy 366.769396 -217.878406) (xy 366.769927 -217.850698) (xy 366.779121 -217.796051)
			(xy 366.787684 -217.769694) (xy 366.795558 -217.747596) (xy 366.59058 -217.392504) (xy 366.56772 -217.388186)
			(xy 366.542875 -217.38302) (xy 366.495026 -217.366126) (xy 366.450333 -217.342096) (xy 366.409853 -217.311499)
			(xy 366.374541 -217.275058) (xy 366.345233 -217.233634) (xy 366.322622 -217.188207) (xy 366.307243 -217.13985)
			(xy 366.299458 -217.089708) (xy 366.298988 -217.064336) (xy 365.078772 -217.064336) (xy 365.078159 -217.091989)
			(xy 365.068838 -217.146507) (xy 365.06023 -217.172794) (xy 365.05261 -217.194892) (xy 365.257842 -217.550238)
			(xy 365.280702 -217.554556) (xy 365.305503 -217.559751) (xy 365.353242 -217.57674) (xy 365.397819 -217.600833)
			(xy 365.438184 -217.631463) (xy 365.473388 -217.667908) (xy 365.5026 -217.709312) (xy 365.525133 -217.754697)
			(xy 365.540456 -217.802996) (xy 365.548208 -217.85307) (xy 365.548672 -217.878406) (xy 365.548164 -217.904293)
			(xy 365.540065 -217.955431) (xy 365.524066 -218.004671) (xy 365.50056 -218.050803) (xy 365.470128 -218.09269)
			(xy 365.433518 -218.1293) (xy 365.391631 -218.159732) (xy 365.345499 -218.183238) (xy 365.296259 -218.199237)
			(xy 365.245121 -218.207336) (xy 365.193347 -218.207336) (xy 365.142209 -218.199237) (xy 365.092969 -218.183238)
			(xy 365.046837 -218.159732) (xy 365.00495 -218.1293) (xy 364.96834 -218.09269) (xy 364.937908 -218.050803)
			(xy 364.914402 -218.004671) (xy 364.898403 -217.955431) (xy 364.890304 -217.904293) (xy 364.889796 -217.878406)
			(xy 364.890327 -217.850698) (xy 364.899521 -217.796051) (xy 364.908084 -217.769694) (xy 364.915958 -217.747596)
			(xy 364.71098 -217.392504) (xy 364.68812 -217.388186) (xy 364.663275 -217.38302) (xy 364.615426 -217.366126)
			(xy 364.570733 -217.342096) (xy 364.530253 -217.311499) (xy 364.494941 -217.275058) (xy 364.465633 -217.233634)
			(xy 364.443022 -217.188207) (xy 364.427643 -217.13985) (xy 364.419858 -217.089708) (xy 364.419388 -217.064336)
			(xy 363.199172 -217.064336) (xy 363.198559 -217.091989) (xy 363.189238 -217.146507) (xy 363.18063 -217.172794)
			(xy 363.17301 -217.194892) (xy 363.378242 -217.550238) (xy 363.401102 -217.554556) (xy 363.425903 -217.559751)
			(xy 363.473642 -217.57674) (xy 363.518219 -217.600833) (xy 363.558584 -217.631463) (xy 363.593788 -217.667908)
			(xy 363.623 -217.709312) (xy 363.645533 -217.754697) (xy 363.660856 -217.802996) (xy 363.668608 -217.85307)
			(xy 363.669072 -217.878406) (xy 363.668564 -217.904293) (xy 363.660465 -217.955431) (xy 363.644466 -218.004671)
			(xy 363.62096 -218.050803) (xy 363.590528 -218.09269) (xy 363.553918 -218.1293) (xy 363.512031 -218.159732)
			(xy 363.465899 -218.183238) (xy 363.416659 -218.199237) (xy 363.365521 -218.207336) (xy 363.313747 -218.207336)
			(xy 363.262609 -218.199237) (xy 363.213369 -218.183238) (xy 363.167237 -218.159732) (xy 363.12535 -218.1293)
			(xy 363.08874 -218.09269) (xy 363.058308 -218.050803) (xy 363.034802 -218.004671) (xy 363.018803 -217.955431)
			(xy 363.010704 -217.904293) (xy 363.010196 -217.878406) (xy 363.010727 -217.850698) (xy 363.019921 -217.796051)
			(xy 363.028484 -217.769694) (xy 363.036358 -217.747596) (xy 362.83138 -217.392504) (xy 362.80852 -217.388186)
			(xy 362.783675 -217.38302) (xy 362.735826 -217.366126) (xy 362.691133 -217.342096) (xy 362.650653 -217.311499)
			(xy 362.615341 -217.275058) (xy 362.586033 -217.233634) (xy 362.563422 -217.188207) (xy 362.548043 -217.13985)
			(xy 362.540258 -217.089708) (xy 362.539788 -217.064336) (xy 361.319572 -217.064336) (xy 361.318959 -217.091989)
			(xy 361.309638 -217.146507) (xy 361.30103 -217.172794) (xy 361.29341 -217.194892) (xy 361.498642 -217.550238)
			(xy 361.521502 -217.554556) (xy 361.546303 -217.559751) (xy 361.594042 -217.57674) (xy 361.638619 -217.600833)
			(xy 361.678984 -217.631463) (xy 361.714188 -217.667908) (xy 361.7434 -217.709312) (xy 361.765933 -217.754697)
			(xy 361.781256 -217.802996) (xy 361.789008 -217.85307) (xy 361.789472 -217.878406) (xy 361.788964 -217.904293)
			(xy 361.780865 -217.955431) (xy 361.764866 -218.004671) (xy 361.74136 -218.050803) (xy 361.710928 -218.09269)
			(xy 361.674318 -218.1293) (xy 361.632431 -218.159732) (xy 361.586299 -218.183238) (xy 361.537059 -218.199237)
			(xy 361.485921 -218.207336) (xy 361.434147 -218.207336) (xy 361.383009 -218.199237) (xy 361.333769 -218.183238)
			(xy 361.287637 -218.159732) (xy 361.24575 -218.1293) (xy 361.20914 -218.09269) (xy 361.178708 -218.050803)
			(xy 361.155202 -218.004671) (xy 361.139203 -217.955431) (xy 361.131104 -217.904293) (xy 361.130596 -217.878406)
			(xy 361.131127 -217.850698) (xy 361.140321 -217.796051) (xy 361.148884 -217.769694) (xy 361.156758 -217.747596)
			(xy 360.95178 -217.392504) (xy 360.92892 -217.388186) (xy 360.904075 -217.38302) (xy 360.856226 -217.366126)
			(xy 360.811533 -217.342096) (xy 360.771053 -217.311499) (xy 360.735741 -217.275058) (xy 360.706433 -217.233634)
			(xy 360.683822 -217.188207) (xy 360.668443 -217.13985) (xy 360.660658 -217.089708) (xy 360.660188 -217.064336)
			(xy 359.439972 -217.064336) (xy 359.439506 -217.089682) (xy 359.431728 -217.139773) (xy 359.416377 -217.188085)
			(xy 359.393813 -217.233478) (xy 359.364569 -217.274884) (xy 359.329334 -217.311328) (xy 359.288936 -217.34195)
			(xy 359.244329 -217.36603) (xy 359.196562 -217.383) (xy 359.171748 -217.388186) (xy 359.148888 -217.392504)
			(xy 358.94391 -217.747596) (xy 358.951784 -217.76944) (xy 358.960373 -217.795856) (xy 358.969563 -217.850633)
			(xy 358.970072 -217.878406) (xy 358.969564 -217.904293) (xy 358.961465 -217.955431) (xy 358.945466 -218.004671)
			(xy 358.92196 -218.050803) (xy 358.891528 -218.09269) (xy 358.854918 -218.1293) (xy 358.813031 -218.159732)
			(xy 358.766899 -218.183238) (xy 358.717659 -218.199237) (xy 358.666521 -218.207336) (xy 358.614747 -218.207336)
			(xy 358.563609 -218.199237) (xy 358.514369 -218.183238) (xy 358.468237 -218.159732) (xy 358.42635 -218.1293)
			(xy 358.38974 -218.09269) (xy 358.359308 -218.050803) (xy 358.335802 -218.004671) (xy 358.319803 -217.955431)
			(xy 358.311704 -217.904293) (xy 358.311196 -217.878406) (xy 358.030272 -217.878406) (xy 358.029741 -217.906114)
			(xy 358.020546 -217.960761) (xy 358.011984 -217.987118) (xy 358.004364 -218.008962) (xy 358.209342 -218.364054)
			(xy 358.232202 -218.368372) (xy 358.257007 -218.373552) (xy 358.304747 -218.390542) (xy 358.349324 -218.414636)
			(xy 358.38969 -218.445268) (xy 358.424894 -218.481716) (xy 358.454106 -218.523121) (xy 358.476638 -218.568508)
			(xy 358.491959 -218.616809) (xy 358.49971 -218.666886) (xy 358.500172 -218.692222) (xy 359.720388 -218.692222)
			(xy 359.720939 -218.66688) (xy 359.728707 -218.616793) (xy 359.744048 -218.568485) (xy 359.766601 -218.523094)
			(xy 359.795834 -218.481689) (xy 359.831059 -218.445245) (xy 359.871446 -218.41462) (xy 359.916044 -218.390537)
			(xy 359.963802 -218.373561) (xy 359.988612 -218.368372) (xy 360.011472 -218.364054) (xy 360.216704 -218.008708)
			(xy 360.20883 -217.98661) (xy 360.200361 -217.960367) (xy 360.191292 -217.905977) (xy 360.190796 -217.878406)
			(xy 360.191304 -217.852519) (xy 360.199403 -217.801381) (xy 360.215402 -217.752141) (xy 360.238908 -217.706009)
			(xy 360.26934 -217.664122) (xy 360.30595 -217.627512) (xy 360.347837 -217.59708) (xy 360.393969 -217.573574)
			(xy 360.443209 -217.557575) (xy 360.494347 -217.549476) (xy 360.546121 -217.549476) (xy 360.597259 -217.557575)
			(xy 360.646499 -217.573574) (xy 360.692631 -217.59708) (xy 360.734518 -217.627512) (xy 360.771128 -217.664122)
			(xy 360.80156 -217.706009) (xy 360.825066 -217.752141) (xy 360.841065 -217.801381) (xy 360.849164 -217.852519)
			(xy 360.849672 -217.878406) (xy 360.849225 -217.903782) (xy 360.841455 -217.953934) (xy 360.826085 -218.002302)
			(xy 360.803477 -218.047739) (xy 360.774167 -218.089171) (xy 360.73885 -218.125617) (xy 360.69836 -218.156215)
			(xy 360.653656 -218.18024) (xy 360.605796 -218.197124) (xy 360.58094 -218.202256) (xy 360.55808 -218.206574)
			(xy 360.353356 -218.561412) (xy 360.36123 -218.583256) (xy 360.369881 -218.609663) (xy 360.379198 -218.66444)
			(xy 360.379772 -218.692222) (xy 361.600496 -218.692222) (xy 361.601002 -218.666888) (xy 361.608751 -218.616817)
			(xy 361.62407 -218.568521) (xy 361.646599 -218.523138) (xy 361.675805 -218.481736) (xy 361.711003 -218.44529)
			(xy 361.751363 -218.414659) (xy 361.795934 -218.390564) (xy 361.843667 -218.373572) (xy 361.868466 -218.368372)
			(xy 361.891326 -218.364054) (xy 362.096304 -218.008962) (xy 362.088684 -217.986864) (xy 362.080159 -217.960694)
			(xy 362.070969 -217.906431) (xy 362.070396 -217.878914) (xy 362.070396 -217.878406) (xy 362.070904 -217.852519)
			(xy 362.079003 -217.801381) (xy 362.095002 -217.752141) (xy 362.118508 -217.706009) (xy 362.14894 -217.664122)
			(xy 362.18555 -217.627512) (xy 362.227437 -217.59708) (xy 362.273569 -217.573574) (xy 362.322809 -217.557575)
			(xy 362.373947 -217.549476) (xy 362.425721 -217.549476) (xy 362.476859 -217.557575) (xy 362.526099 -217.573574)
			(xy 362.572231 -217.59708) (xy 362.614118 -217.627512) (xy 362.650728 -217.664122) (xy 362.68116 -217.706009)
			(xy 362.704666 -217.752141) (xy 362.720665 -217.801381) (xy 362.728764 -217.852519) (xy 362.729272 -217.878406)
			(xy 362.728863 -217.903772) (xy 362.721112 -217.953909) (xy 362.705764 -218.002264) (xy 362.683182 -218.047694)
			(xy 362.6539 -218.089122) (xy 362.61861 -218.12557) (xy 362.578149 -218.156175) (xy 362.533472 -218.180212)
			(xy 362.485638 -218.197113) (xy 362.460794 -218.202256) (xy 362.437934 -218.206574) (xy 362.23321 -218.561412)
			(xy 362.241084 -218.583256) (xy 362.249677 -218.609671) (xy 362.258865 -218.664449) (xy 362.259372 -218.692222)
			(xy 363.479588 -218.692222) (xy 363.480139 -218.66688) (xy 363.487907 -218.616793) (xy 363.503248 -218.568485)
			(xy 363.525801 -218.523094) (xy 363.555034 -218.481689) (xy 363.590259 -218.445245) (xy 363.630646 -218.41462)
			(xy 363.675244 -218.390537) (xy 363.723002 -218.373561) (xy 363.747812 -218.368372) (xy 363.770672 -218.364054)
			(xy 363.975904 -218.008708) (xy 363.96803 -217.98661) (xy 363.959561 -217.960367) (xy 363.950492 -217.905977)
			(xy 363.949996 -217.878406) (xy 363.950504 -217.852519) (xy 363.958603 -217.801381) (xy 363.974602 -217.752141)
			(xy 363.998108 -217.706009) (xy 364.02854 -217.664122) (xy 364.06515 -217.627512) (xy 364.107037 -217.59708)
			(xy 364.153169 -217.573574) (xy 364.202409 -217.557575) (xy 364.253547 -217.549476) (xy 364.305321 -217.549476)
			(xy 364.356459 -217.557575) (xy 364.405699 -217.573574) (xy 364.451831 -217.59708) (xy 364.493718 -217.627512)
			(xy 364.530328 -217.664122) (xy 364.56076 -217.706009) (xy 364.584266 -217.752141) (xy 364.600265 -217.801381)
			(xy 364.608364 -217.852519) (xy 364.608872 -217.878406) (xy 364.608425 -217.903782) (xy 364.600655 -217.953934)
			(xy 364.585285 -218.002302) (xy 364.562677 -218.047739) (xy 364.533367 -218.089171) (xy 364.49805 -218.125617)
			(xy 364.45756 -218.156215) (xy 364.412856 -218.18024) (xy 364.364996 -218.197124) (xy 364.34014 -218.202256)
			(xy 364.31728 -218.206574) (xy 364.112556 -218.561412) (xy 364.12043 -218.583256) (xy 364.129081 -218.609663)
			(xy 364.138398 -218.66444) (xy 364.138972 -218.692222) (xy 365.359188 -218.692222) (xy 365.359739 -218.66688)
			(xy 365.367507 -218.616793) (xy 365.382848 -218.568485) (xy 365.405401 -218.523094) (xy 365.434634 -218.481689)
			(xy 365.469859 -218.445245) (xy 365.510246 -218.41462) (xy 365.554844 -218.390537) (xy 365.602602 -218.373561)
			(xy 365.627412 -218.368372) (xy 365.650272 -218.364054) (xy 365.855504 -218.008708) (xy 365.84763 -217.98661)
			(xy 365.839161 -217.960367) (xy 365.830092 -217.905977) (xy 365.829596 -217.878406) (xy 365.830104 -217.852519)
			(xy 365.838203 -217.801381) (xy 365.854202 -217.752141) (xy 365.877708 -217.706009) (xy 365.90814 -217.664122)
			(xy 365.94475 -217.627512) (xy 365.986637 -217.59708) (xy 366.032769 -217.573574) (xy 366.082009 -217.557575)
			(xy 366.133147 -217.549476) (xy 366.184921 -217.549476) (xy 366.236059 -217.557575) (xy 366.285299 -217.573574)
			(xy 366.331431 -217.59708) (xy 366.373318 -217.627512) (xy 366.409928 -217.664122) (xy 366.44036 -217.706009)
			(xy 366.463866 -217.752141) (xy 366.479865 -217.801381) (xy 366.487964 -217.852519) (xy 366.488472 -217.878406)
			(xy 366.488025 -217.903782) (xy 366.480255 -217.953934) (xy 366.464885 -218.002302) (xy 366.442277 -218.047739)
			(xy 366.412967 -218.089171) (xy 366.37765 -218.125617) (xy 366.33716 -218.156215) (xy 366.292456 -218.18024)
			(xy 366.244596 -218.197124) (xy 366.21974 -218.202256) (xy 366.19688 -218.206574) (xy 365.992156 -218.561412)
			(xy 366.00003 -218.583256) (xy 366.008681 -218.609663) (xy 366.017998 -218.66444) (xy 366.018572 -218.692222)
			(xy 367.238788 -218.692222) (xy 367.239339 -218.66688) (xy 367.247107 -218.616793) (xy 367.262448 -218.568485)
			(xy 367.285001 -218.523094) (xy 367.314234 -218.481689) (xy 367.349459 -218.445245) (xy 367.389846 -218.41462)
			(xy 367.434444 -218.390537) (xy 367.482202 -218.373561) (xy 367.507012 -218.368372) (xy 367.529872 -218.364054)
			(xy 367.735104 -218.008708) (xy 367.72723 -217.98661) (xy 367.718761 -217.960367) (xy 367.709692 -217.905977)
			(xy 367.709196 -217.878406) (xy 367.709704 -217.852519) (xy 367.717803 -217.801381) (xy 367.733802 -217.752141)
			(xy 367.757308 -217.706009) (xy 367.78774 -217.664122) (xy 367.82435 -217.627512) (xy 367.866237 -217.59708)
			(xy 367.912369 -217.573574) (xy 367.961609 -217.557575) (xy 368.012747 -217.549476) (xy 368.064521 -217.549476)
			(xy 368.115659 -217.557575) (xy 368.164899 -217.573574) (xy 368.211031 -217.59708) (xy 368.252918 -217.627512)
			(xy 368.289528 -217.664122) (xy 368.31996 -217.706009) (xy 368.343466 -217.752141) (xy 368.359465 -217.801381)
			(xy 368.367564 -217.852519) (xy 368.368072 -217.878406) (xy 368.367625 -217.903782) (xy 368.359855 -217.953934)
			(xy 368.344485 -218.002302) (xy 368.321877 -218.047739) (xy 368.292567 -218.089171) (xy 368.25725 -218.125617)
			(xy 368.21676 -218.156215) (xy 368.172056 -218.18024) (xy 368.124196 -218.197124) (xy 368.09934 -218.202256)
			(xy 368.07648 -218.206574) (xy 367.871756 -218.561412) (xy 367.87963 -218.583256) (xy 367.888281 -218.609663)
			(xy 367.897598 -218.66444) (xy 367.898172 -218.692222) (xy 369.118388 -218.692222) (xy 369.118939 -218.66688)
			(xy 369.126707 -218.616793) (xy 369.142048 -218.568485) (xy 369.164601 -218.523094) (xy 369.193834 -218.481689)
			(xy 369.229059 -218.445245) (xy 369.269446 -218.41462) (xy 369.314044 -218.390537) (xy 369.361802 -218.373561)
			(xy 369.386612 -218.368372) (xy 369.409472 -218.364054) (xy 369.614704 -218.008708) (xy 369.60683 -217.98661)
			(xy 369.598361 -217.960367) (xy 369.589292 -217.905977) (xy 369.588796 -217.878406) (xy 369.589304 -217.852519)
			(xy 369.597403 -217.801381) (xy 369.613402 -217.752141) (xy 369.636908 -217.706009) (xy 369.66734 -217.664122)
			(xy 369.70395 -217.627512) (xy 369.745837 -217.59708) (xy 369.791969 -217.573574) (xy 369.841209 -217.557575)
			(xy 369.892347 -217.549476) (xy 369.944121 -217.549476) (xy 369.995259 -217.557575) (xy 370.044499 -217.573574)
			(xy 370.090631 -217.59708) (xy 370.132518 -217.627512) (xy 370.169128 -217.664122) (xy 370.19956 -217.706009)
			(xy 370.223066 -217.752141) (xy 370.239065 -217.801381) (xy 370.247164 -217.852519) (xy 370.247672 -217.878406)
			(xy 370.247225 -217.903782) (xy 370.239455 -217.953934) (xy 370.224085 -218.002302) (xy 370.201477 -218.047739)
			(xy 370.172167 -218.089171) (xy 370.13685 -218.125617) (xy 370.09636 -218.156215) (xy 370.051656 -218.18024)
			(xy 370.003796 -218.197124) (xy 369.97894 -218.202256) (xy 369.95608 -218.206574) (xy 369.751356 -218.561412)
			(xy 369.75923 -218.583256) (xy 369.767881 -218.609663) (xy 369.777198 -218.66444) (xy 369.777772 -218.692222)
			(xy 370.997988 -218.692222) (xy 370.998539 -218.66688) (xy 371.006307 -218.616793) (xy 371.021648 -218.568485)
			(xy 371.044201 -218.523094) (xy 371.073434 -218.481689) (xy 371.108659 -218.445245) (xy 371.149046 -218.41462)
			(xy 371.193644 -218.390537) (xy 371.241402 -218.373561) (xy 371.266212 -218.368372) (xy 371.289072 -218.364054)
			(xy 371.494304 -218.008708) (xy 371.48643 -217.98661) (xy 371.477961 -217.960367) (xy 371.468892 -217.905977)
			(xy 371.468396 -217.878406) (xy 371.468904 -217.852519) (xy 371.477003 -217.801381) (xy 371.493002 -217.752141)
			(xy 371.516508 -217.706009) (xy 371.54694 -217.664122) (xy 371.58355 -217.627512) (xy 371.625437 -217.59708)
			(xy 371.671569 -217.573574) (xy 371.720809 -217.557575) (xy 371.771947 -217.549476) (xy 371.823721 -217.549476)
			(xy 371.874859 -217.557575) (xy 371.924099 -217.573574) (xy 371.970231 -217.59708) (xy 372.012118 -217.627512)
			(xy 372.048728 -217.664122) (xy 372.07916 -217.706009) (xy 372.102666 -217.752141) (xy 372.118665 -217.801381)
			(xy 372.126764 -217.852519) (xy 372.127272 -217.878406) (xy 372.126825 -217.903782) (xy 372.119055 -217.953934)
			(xy 372.103685 -218.002302) (xy 372.081077 -218.047739) (xy 372.051767 -218.089171) (xy 372.01645 -218.125617)
			(xy 371.97596 -218.156215) (xy 371.931256 -218.18024) (xy 371.883396 -218.197124) (xy 371.85854 -218.202256)
			(xy 371.83568 -218.206574) (xy 371.630956 -218.561412) (xy 371.63883 -218.583256) (xy 371.647481 -218.609663)
			(xy 371.656798 -218.66444) (xy 371.657372 -218.692222) (xy 372.877588 -218.692222) (xy 372.878139 -218.66688)
			(xy 372.885907 -218.616793) (xy 372.901248 -218.568485) (xy 372.923801 -218.523094) (xy 372.953034 -218.481689)
			(xy 372.988259 -218.445245) (xy 373.028646 -218.41462) (xy 373.073244 -218.390537) (xy 373.121002 -218.373561)
			(xy 373.145812 -218.368372) (xy 373.168672 -218.364054) (xy 373.373904 -218.008708) (xy 373.36603 -217.98661)
			(xy 373.357561 -217.960367) (xy 373.348492 -217.905977) (xy 373.347996 -217.878406) (xy 373.348504 -217.852519)
			(xy 373.356603 -217.801381) (xy 373.372602 -217.752141) (xy 373.396108 -217.706009) (xy 373.42654 -217.664122)
			(xy 373.46315 -217.627512) (xy 373.505037 -217.59708) (xy 373.551169 -217.573574) (xy 373.600409 -217.557575)
			(xy 373.651547 -217.549476) (xy 373.703321 -217.549476) (xy 373.754459 -217.557575) (xy 373.803699 -217.573574)
			(xy 373.849831 -217.59708) (xy 373.891718 -217.627512) (xy 373.928328 -217.664122) (xy 373.95876 -217.706009)
			(xy 373.982266 -217.752141) (xy 373.998265 -217.801381) (xy 374.006364 -217.852519) (xy 374.006872 -217.878406)
			(xy 374.006425 -217.903782) (xy 373.998655 -217.953934) (xy 373.983285 -218.002302) (xy 373.960677 -218.047739)
			(xy 373.931367 -218.089171) (xy 373.89605 -218.125617) (xy 373.85556 -218.156215) (xy 373.810856 -218.18024)
			(xy 373.762996 -218.197124) (xy 373.73814 -218.202256) (xy 373.71528 -218.206574) (xy 373.510556 -218.561412)
			(xy 373.51843 -218.583256) (xy 373.527081 -218.609663) (xy 373.536398 -218.66444) (xy 373.536972 -218.692222)
			(xy 374.757188 -218.692222) (xy 374.757739 -218.66688) (xy 374.765507 -218.616793) (xy 374.780848 -218.568485)
			(xy 374.803401 -218.523094) (xy 374.832634 -218.481689) (xy 374.867859 -218.445245) (xy 374.908246 -218.41462)
			(xy 374.952844 -218.390537) (xy 375.000602 -218.373561) (xy 375.025412 -218.368372) (xy 375.048272 -218.364054)
			(xy 375.253504 -218.008708) (xy 375.24563 -217.98661) (xy 375.237161 -217.960367) (xy 375.228092 -217.905977)
			(xy 375.227596 -217.878406) (xy 375.228104 -217.852519) (xy 375.236203 -217.801381) (xy 375.252202 -217.752141)
			(xy 375.275708 -217.706009) (xy 375.30614 -217.664122) (xy 375.34275 -217.627512) (xy 375.384637 -217.59708)
			(xy 375.430769 -217.573574) (xy 375.480009 -217.557575) (xy 375.531147 -217.549476) (xy 375.582921 -217.549476)
			(xy 375.634059 -217.557575) (xy 375.683299 -217.573574) (xy 375.729431 -217.59708) (xy 375.771318 -217.627512)
			(xy 375.807928 -217.664122) (xy 375.83836 -217.706009) (xy 375.861866 -217.752141) (xy 375.877865 -217.801381)
			(xy 375.885964 -217.852519) (xy 375.886472 -217.878406) (xy 375.886025 -217.903782) (xy 375.878255 -217.953934)
			(xy 375.862885 -218.002302) (xy 375.840277 -218.047739) (xy 375.810967 -218.089171) (xy 375.77565 -218.125617)
			(xy 375.73516 -218.156215) (xy 375.690456 -218.18024) (xy 375.642596 -218.197124) (xy 375.61774 -218.202256)
			(xy 375.59488 -218.206574) (xy 375.390156 -218.561412) (xy 375.39803 -218.583256) (xy 375.406681 -218.609663)
			(xy 375.415998 -218.66444) (xy 375.416572 -218.692222) (xy 376.636788 -218.692222) (xy 376.637339 -218.66688)
			(xy 376.645107 -218.616793) (xy 376.660448 -218.568485) (xy 376.683001 -218.523094) (xy 376.712234 -218.481689)
			(xy 376.747459 -218.445245) (xy 376.787846 -218.41462) (xy 376.832444 -218.390537) (xy 376.880202 -218.373561)
			(xy 376.905012 -218.368372) (xy 376.927872 -218.364054) (xy 377.133104 -218.008708) (xy 377.12523 -217.98661)
			(xy 377.116761 -217.960367) (xy 377.107692 -217.905977) (xy 377.107196 -217.878406) (xy 377.107704 -217.852519)
			(xy 377.115803 -217.801381) (xy 377.131802 -217.752141) (xy 377.155308 -217.706009) (xy 377.18574 -217.664122)
			(xy 377.22235 -217.627512) (xy 377.264237 -217.59708) (xy 377.310369 -217.573574) (xy 377.359609 -217.557575)
			(xy 377.410747 -217.549476) (xy 377.462521 -217.549476) (xy 377.513659 -217.557575) (xy 377.562899 -217.573574)
			(xy 377.609031 -217.59708) (xy 377.650918 -217.627512) (xy 377.687528 -217.664122) (xy 377.71796 -217.706009)
			(xy 377.741466 -217.752141) (xy 377.757465 -217.801381) (xy 377.765564 -217.852519) (xy 377.766072 -217.878406)
			(xy 377.765625 -217.903782) (xy 377.757855 -217.953934) (xy 377.742485 -218.002302) (xy 377.719877 -218.047739)
			(xy 377.690567 -218.089171) (xy 377.65525 -218.125617) (xy 377.61476 -218.156215) (xy 377.570056 -218.18024)
			(xy 377.522196 -218.197124) (xy 377.49734 -218.202256) (xy 377.47448 -218.206574) (xy 377.269756 -218.561412)
			(xy 377.27763 -218.583256) (xy 377.286281 -218.609663) (xy 377.295598 -218.66444) (xy 377.296172 -218.692222)
			(xy 378.516388 -218.692222) (xy 378.516939 -218.66688) (xy 378.524707 -218.616793) (xy 378.540048 -218.568485)
			(xy 378.562601 -218.523094) (xy 378.591834 -218.481689) (xy 378.627059 -218.445245) (xy 378.667446 -218.41462)
			(xy 378.712044 -218.390537) (xy 378.759802 -218.373561) (xy 378.784612 -218.368372) (xy 378.807472 -218.364054)
			(xy 379.012704 -218.008708) (xy 379.00483 -217.98661) (xy 378.996361 -217.960367) (xy 378.987292 -217.905977)
			(xy 378.986796 -217.878406) (xy 378.987304 -217.852519) (xy 378.995403 -217.801381) (xy 379.011402 -217.752141)
			(xy 379.034908 -217.706009) (xy 379.06534 -217.664122) (xy 379.10195 -217.627512) (xy 379.143837 -217.59708)
			(xy 379.189969 -217.573574) (xy 379.239209 -217.557575) (xy 379.290347 -217.549476) (xy 379.342121 -217.549476)
			(xy 379.393259 -217.557575) (xy 379.442499 -217.573574) (xy 379.488631 -217.59708) (xy 379.530518 -217.627512)
			(xy 379.567128 -217.664122) (xy 379.59756 -217.706009) (xy 379.621066 -217.752141) (xy 379.637065 -217.801381)
			(xy 379.645164 -217.852519) (xy 379.645672 -217.878406) (xy 379.645225 -217.903782) (xy 379.637455 -217.953934)
			(xy 379.622085 -218.002302) (xy 379.599477 -218.047739) (xy 379.570167 -218.089171) (xy 379.53485 -218.125617)
			(xy 379.49436 -218.156215) (xy 379.449656 -218.18024) (xy 379.401796 -218.197124) (xy 379.37694 -218.202256)
			(xy 379.35408 -218.206574) (xy 379.149356 -218.561412) (xy 379.15723 -218.583256) (xy 379.165881 -218.609663)
			(xy 379.175198 -218.66444) (xy 379.175772 -218.692222) (xy 380.395988 -218.692222) (xy 380.396539 -218.66688)
			(xy 380.404307 -218.616793) (xy 380.419648 -218.568485) (xy 380.442201 -218.523094) (xy 380.471434 -218.481689)
			(xy 380.506659 -218.445245) (xy 380.547046 -218.41462) (xy 380.591644 -218.390537) (xy 380.639402 -218.373561)
			(xy 380.664212 -218.368372) (xy 380.687072 -218.364054) (xy 380.892304 -218.008708) (xy 380.88443 -217.98661)
			(xy 380.875961 -217.960367) (xy 380.866892 -217.905977) (xy 380.866396 -217.878406) (xy 380.866904 -217.852519)
			(xy 380.875003 -217.801381) (xy 380.891002 -217.752141) (xy 380.914508 -217.706009) (xy 380.94494 -217.664122)
			(xy 380.98155 -217.627512) (xy 381.023437 -217.59708) (xy 381.069569 -217.573574) (xy 381.118809 -217.557575)
			(xy 381.169947 -217.549476) (xy 381.221721 -217.549476) (xy 381.272859 -217.557575) (xy 381.322099 -217.573574)
			(xy 381.368231 -217.59708) (xy 381.410118 -217.627512) (xy 381.446728 -217.664122) (xy 381.47716 -217.706009)
			(xy 381.500666 -217.752141) (xy 381.516665 -217.801381) (xy 381.524764 -217.852519) (xy 381.525272 -217.878406)
			(xy 381.524825 -217.903782) (xy 381.517055 -217.953934) (xy 381.501685 -218.002302) (xy 381.479077 -218.047739)
			(xy 381.449767 -218.089171) (xy 381.41445 -218.125617) (xy 381.37396 -218.156215) (xy 381.329256 -218.18024)
			(xy 381.281396 -218.197124) (xy 381.25654 -218.202256) (xy 381.23368 -218.206574) (xy 381.028956 -218.561412)
			(xy 381.03683 -218.583256) (xy 381.045481 -218.609663) (xy 381.054798 -218.66444) (xy 381.055372 -218.692222)
			(xy 381.054864 -218.718129) (xy 381.046758 -218.769306) (xy 381.030746 -218.818585) (xy 381.007223 -218.864752)
			(xy 380.976767 -218.906671) (xy 380.940129 -218.943309) (xy 380.89821 -218.973765) (xy 380.852043 -218.997288)
			(xy 380.802764 -219.0133) (xy 380.751587 -219.021406) (xy 380.699773 -219.021406) (xy 380.648596 -219.0133)
			(xy 380.599317 -218.997288) (xy 380.55315 -218.973765) (xy 380.511231 -218.943309) (xy 380.474593 -218.906671)
			(xy 380.444137 -218.864752) (xy 380.420614 -218.818585) (xy 380.404602 -218.769306) (xy 380.396496 -218.718129)
			(xy 380.395988 -218.692222) (xy 379.175772 -218.692222) (xy 379.175264 -218.718129) (xy 379.167158 -218.769306)
			(xy 379.151146 -218.818585) (xy 379.127623 -218.864752) (xy 379.097167 -218.906671) (xy 379.060529 -218.943309)
			(xy 379.01861 -218.973765) (xy 378.972443 -218.997288) (xy 378.923164 -219.0133) (xy 378.871987 -219.021406)
			(xy 378.820173 -219.021406) (xy 378.768996 -219.0133) (xy 378.719717 -218.997288) (xy 378.67355 -218.973765)
			(xy 378.631631 -218.943309) (xy 378.594993 -218.906671) (xy 378.564537 -218.864752) (xy 378.541014 -218.818585)
			(xy 378.525002 -218.769306) (xy 378.516896 -218.718129) (xy 378.516388 -218.692222) (xy 377.296172 -218.692222)
			(xy 377.295664 -218.718129) (xy 377.287558 -218.769306) (xy 377.271546 -218.818585) (xy 377.248023 -218.864752)
			(xy 377.217567 -218.906671) (xy 377.180929 -218.943309) (xy 377.13901 -218.973765) (xy 377.092843 -218.997288)
			(xy 377.043564 -219.0133) (xy 376.992387 -219.021406) (xy 376.940573 -219.021406) (xy 376.889396 -219.0133)
			(xy 376.840117 -218.997288) (xy 376.79395 -218.973765) (xy 376.752031 -218.943309) (xy 376.715393 -218.906671)
			(xy 376.684937 -218.864752) (xy 376.661414 -218.818585) (xy 376.645402 -218.769306) (xy 376.637296 -218.718129)
			(xy 376.636788 -218.692222) (xy 375.416572 -218.692222) (xy 375.416064 -218.718129) (xy 375.407958 -218.769306)
			(xy 375.391946 -218.818585) (xy 375.368423 -218.864752) (xy 375.337967 -218.906671) (xy 375.301329 -218.943309)
			(xy 375.25941 -218.973765) (xy 375.213243 -218.997288) (xy 375.163964 -219.0133) (xy 375.112787 -219.021406)
			(xy 375.060973 -219.021406) (xy 375.009796 -219.0133) (xy 374.960517 -218.997288) (xy 374.91435 -218.973765)
			(xy 374.872431 -218.943309) (xy 374.835793 -218.906671) (xy 374.805337 -218.864752) (xy 374.781814 -218.818585)
			(xy 374.765802 -218.769306) (xy 374.757696 -218.718129) (xy 374.757188 -218.692222) (xy 373.536972 -218.692222)
			(xy 373.536464 -218.718129) (xy 373.528358 -218.769306) (xy 373.512346 -218.818585) (xy 373.488823 -218.864752)
			(xy 373.458367 -218.906671) (xy 373.421729 -218.943309) (xy 373.37981 -218.973765) (xy 373.333643 -218.997288)
			(xy 373.284364 -219.0133) (xy 373.233187 -219.021406) (xy 373.181373 -219.021406) (xy 373.130196 -219.0133)
			(xy 373.080917 -218.997288) (xy 373.03475 -218.973765) (xy 372.992831 -218.943309) (xy 372.956193 -218.906671)
			(xy 372.925737 -218.864752) (xy 372.902214 -218.818585) (xy 372.886202 -218.769306) (xy 372.878096 -218.718129)
			(xy 372.877588 -218.692222) (xy 371.657372 -218.692222) (xy 371.656864 -218.718129) (xy 371.648758 -218.769306)
			(xy 371.632746 -218.818585) (xy 371.609223 -218.864752) (xy 371.578767 -218.906671) (xy 371.542129 -218.943309)
			(xy 371.50021 -218.973765) (xy 371.454043 -218.997288) (xy 371.404764 -219.0133) (xy 371.353587 -219.021406)
			(xy 371.301773 -219.021406) (xy 371.250596 -219.0133) (xy 371.201317 -218.997288) (xy 371.15515 -218.973765)
			(xy 371.113231 -218.943309) (xy 371.076593 -218.906671) (xy 371.046137 -218.864752) (xy 371.022614 -218.818585)
			(xy 371.006602 -218.769306) (xy 370.998496 -218.718129) (xy 370.997988 -218.692222) (xy 369.777772 -218.692222)
			(xy 369.777264 -218.718129) (xy 369.769158 -218.769306) (xy 369.753146 -218.818585) (xy 369.729623 -218.864752)
			(xy 369.699167 -218.906671) (xy 369.662529 -218.943309) (xy 369.62061 -218.973765) (xy 369.574443 -218.997288)
			(xy 369.525164 -219.0133) (xy 369.473987 -219.021406) (xy 369.422173 -219.021406) (xy 369.370996 -219.0133)
			(xy 369.321717 -218.997288) (xy 369.27555 -218.973765) (xy 369.233631 -218.943309) (xy 369.196993 -218.906671)
			(xy 369.166537 -218.864752) (xy 369.143014 -218.818585) (xy 369.127002 -218.769306) (xy 369.118896 -218.718129)
			(xy 369.118388 -218.692222) (xy 367.898172 -218.692222) (xy 367.897664 -218.718129) (xy 367.889558 -218.769306)
			(xy 367.873546 -218.818585) (xy 367.850023 -218.864752) (xy 367.819567 -218.906671) (xy 367.782929 -218.943309)
			(xy 367.74101 -218.973765) (xy 367.694843 -218.997288) (xy 367.645564 -219.0133) (xy 367.594387 -219.021406)
			(xy 367.542573 -219.021406) (xy 367.491396 -219.0133) (xy 367.442117 -218.997288) (xy 367.39595 -218.973765)
			(xy 367.354031 -218.943309) (xy 367.317393 -218.906671) (xy 367.286937 -218.864752) (xy 367.263414 -218.818585)
			(xy 367.247402 -218.769306) (xy 367.239296 -218.718129) (xy 367.238788 -218.692222) (xy 366.018572 -218.692222)
			(xy 366.018064 -218.718129) (xy 366.009958 -218.769306) (xy 365.993946 -218.818585) (xy 365.970423 -218.864752)
			(xy 365.939967 -218.906671) (xy 365.903329 -218.943309) (xy 365.86141 -218.973765) (xy 365.815243 -218.997288)
			(xy 365.765964 -219.0133) (xy 365.714787 -219.021406) (xy 365.662973 -219.021406) (xy 365.611796 -219.0133)
			(xy 365.562517 -218.997288) (xy 365.51635 -218.973765) (xy 365.474431 -218.943309) (xy 365.437793 -218.906671)
			(xy 365.407337 -218.864752) (xy 365.383814 -218.818585) (xy 365.367802 -218.769306) (xy 365.359696 -218.718129)
			(xy 365.359188 -218.692222) (xy 364.138972 -218.692222) (xy 364.138464 -218.718129) (xy 364.130358 -218.769306)
			(xy 364.114346 -218.818585) (xy 364.090823 -218.864752) (xy 364.060367 -218.906671) (xy 364.023729 -218.943309)
			(xy 363.98181 -218.973765) (xy 363.935643 -218.997288) (xy 363.886364 -219.0133) (xy 363.835187 -219.021406)
			(xy 363.783373 -219.021406) (xy 363.732196 -219.0133) (xy 363.682917 -218.997288) (xy 363.63675 -218.973765)
			(xy 363.594831 -218.943309) (xy 363.558193 -218.906671) (xy 363.527737 -218.864752) (xy 363.504214 -218.818585)
			(xy 363.488202 -218.769306) (xy 363.480096 -218.718129) (xy 363.479588 -218.692222) (xy 362.259372 -218.692222)
			(xy 362.258864 -218.718109) (xy 362.250765 -218.769247) (xy 362.234766 -218.818487) (xy 362.21126 -218.864619)
			(xy 362.180828 -218.906506) (xy 362.144218 -218.943116) (xy 362.102331 -218.973548) (xy 362.056199 -218.997054)
			(xy 362.006959 -219.013053) (xy 361.955821 -219.021152) (xy 361.904047 -219.021152) (xy 361.852909 -219.013053)
			(xy 361.803669 -218.997054) (xy 361.757537 -218.973548) (xy 361.71565 -218.943116) (xy 361.67904 -218.906506)
			(xy 361.648608 -218.864619) (xy 361.625102 -218.818487) (xy 361.609103 -218.769247) (xy 361.601004 -218.718109)
			(xy 361.600496 -218.692222) (xy 360.379772 -218.692222) (xy 360.379264 -218.718129) (xy 360.371158 -218.769306)
			(xy 360.355146 -218.818585) (xy 360.331623 -218.864752) (xy 360.301167 -218.906671) (xy 360.264529 -218.943309)
			(xy 360.22261 -218.973765) (xy 360.176443 -218.997288) (xy 360.127164 -219.0133) (xy 360.075987 -219.021406)
			(xy 360.024173 -219.021406) (xy 359.972996 -219.0133) (xy 359.923717 -218.997288) (xy 359.87755 -218.973765)
			(xy 359.835631 -218.943309) (xy 359.798993 -218.906671) (xy 359.768537 -218.864752) (xy 359.745014 -218.818585)
			(xy 359.729002 -218.769306) (xy 359.720896 -218.718129) (xy 359.720388 -218.692222) (xy 358.500172 -218.692222)
			(xy 358.499664 -218.718109) (xy 358.491565 -218.769247) (xy 358.475566 -218.818487) (xy 358.45206 -218.864619)
			(xy 358.421628 -218.906506) (xy 358.385018 -218.943116) (xy 358.343131 -218.973548) (xy 358.296999 -218.997054)
			(xy 358.247759 -219.013053) (xy 358.196621 -219.021152) (xy 358.144847 -219.021152) (xy 358.093709 -219.013053)
			(xy 358.044469 -218.997054) (xy 357.998337 -218.973548) (xy 357.95645 -218.943116) (xy 357.91984 -218.906506)
			(xy 357.889408 -218.864619) (xy 357.865902 -218.818487) (xy 357.849903 -218.769247) (xy 357.841804 -218.718109)
			(xy 357.841296 -218.692222) (xy 357.841831 -218.664514) (xy 357.851023 -218.609867) (xy 357.859584 -218.58351)
			(xy 357.867458 -218.561412) (xy 357.66248 -218.206574) (xy 357.63962 -218.202256) (xy 357.614783 -218.197156)
			(xy 357.567001 -218.180194) (xy 357.52238 -218.156114) (xy 357.481972 -218.125486) (xy 357.446732 -218.08903)
			(xy 357.417491 -218.047608) (xy 357.394937 -218.002196) (xy 357.379605 -217.953866) (xy 357.371854 -217.903758)
			(xy 357.371396 -217.878406) (xy 357.090472 -217.878406) (xy 357.089964 -217.904293) (xy 357.081865 -217.955431)
			(xy 357.065866 -218.004671) (xy 357.04236 -218.050803) (xy 357.011928 -218.09269) (xy 356.975318 -218.1293)
			(xy 356.933431 -218.159732) (xy 356.887299 -218.183238) (xy 356.838059 -218.199237) (xy 356.786921 -218.207336)
			(xy 356.735147 -218.207336) (xy 356.684009 -218.199237) (xy 356.634769 -218.183238) (xy 356.588637 -218.159732)
			(xy 356.54675 -218.1293) (xy 356.51014 -218.09269) (xy 356.479708 -218.050803) (xy 356.456202 -218.004671)
			(xy 356.440203 -217.955431) (xy 356.432104 -217.904293) (xy 356.431596 -217.878406) (xy 356.150672 -217.878406)
			(xy 356.150141 -217.906114) (xy 356.140946 -217.960761) (xy 356.132384 -217.987118) (xy 356.12451 -218.009216)
			(xy 356.329488 -218.364054) (xy 356.352348 -218.368372) (xy 356.377163 -218.373563) (xy 356.424941 -218.390515)
			(xy 356.469559 -218.414584) (xy 356.509965 -218.445202) (xy 356.545206 -218.481645) (xy 356.57445 -218.523056)
			(xy 356.597009 -218.568456) (xy 356.612349 -218.616776) (xy 356.620108 -218.666874) (xy 356.620572 -218.692222)
			(xy 356.620064 -218.718129) (xy 356.611958 -218.769306) (xy 356.595946 -218.818585) (xy 356.572423 -218.864752)
			(xy 356.541967 -218.906671) (xy 356.505329 -218.943309) (xy 356.46341 -218.973765) (xy 356.417243 -218.997288)
			(xy 356.367964 -219.0133) (xy 356.316787 -219.021406) (xy 356.264973 -219.021406) (xy 356.213796 -219.0133)
			(xy 356.164517 -218.997288) (xy 356.11835 -218.973765) (xy 356.076431 -218.943309) (xy 356.039793 -218.906671)
			(xy 356.009337 -218.864752) (xy 355.985814 -218.818585) (xy 355.969802 -218.769306) (xy 355.961696 -218.718129)
			(xy 355.961188 -218.692222) (xy 355.961788 -218.664505) (xy 355.971107 -218.609859) (xy 355.97973 -218.58351)
			(xy 355.987604 -218.561412) (xy 355.782626 -218.206574) (xy 355.759766 -218.202256) (xy 355.734962 -218.197073)
			(xy 355.687224 -218.180081) (xy 355.642649 -218.155985) (xy 355.602284 -218.125353) (xy 355.567082 -218.088906)
			(xy 355.53787 -218.047502) (xy 355.515337 -218.002116) (xy 355.500013 -217.953817) (xy 355.49226 -217.903742)
			(xy 355.491796 -217.878406) (xy 355.210872 -217.878406) (xy 355.210364 -217.904293) (xy 355.202265 -217.955431)
			(xy 355.186266 -218.004671) (xy 355.16276 -218.050803) (xy 355.132328 -218.09269) (xy 355.095718 -218.1293)
			(xy 355.053831 -218.159732) (xy 355.007699 -218.183238) (xy 354.958459 -218.199237) (xy 354.907321 -218.207336)
			(xy 354.855547 -218.207336) (xy 354.804409 -218.199237) (xy 354.755169 -218.183238) (xy 354.709037 -218.159732)
			(xy 354.66715 -218.1293) (xy 354.63054 -218.09269) (xy 354.600108 -218.050803) (xy 354.576602 -218.004671)
			(xy 354.560603 -217.955431) (xy 354.552504 -217.904293) (xy 354.551996 -217.878406) (xy 354.271072 -217.878406)
			(xy 354.270541 -217.906114) (xy 354.261346 -217.960761) (xy 354.252784 -217.987118) (xy 354.24491 -218.009216)
			(xy 354.449888 -218.364054) (xy 354.472748 -218.368372) (xy 354.497563 -218.373563) (xy 354.545341 -218.390515)
			(xy 354.589959 -218.414584) (xy 354.630365 -218.445202) (xy 354.665606 -218.481645) (xy 354.69485 -218.523056)
			(xy 354.717409 -218.568456) (xy 354.732749 -218.616776) (xy 354.740508 -218.666874) (xy 354.740972 -218.692222)
			(xy 354.740464 -218.718129) (xy 354.732358 -218.769306) (xy 354.716346 -218.818585) (xy 354.692823 -218.864752)
			(xy 354.662367 -218.906671) (xy 354.625729 -218.943309) (xy 354.58381 -218.973765) (xy 354.537643 -218.997288)
			(xy 354.488364 -219.0133) (xy 354.437187 -219.021406) (xy 354.385373 -219.021406) (xy 354.334196 -219.0133)
			(xy 354.284917 -218.997288) (xy 354.23875 -218.973765) (xy 354.196831 -218.943309) (xy 354.160193 -218.906671)
			(xy 354.129737 -218.864752) (xy 354.106214 -218.818585) (xy 354.090202 -218.769306) (xy 354.082096 -218.718129)
			(xy 354.081588 -218.692222) (xy 354.082188 -218.664505) (xy 354.091507 -218.609859) (xy 354.10013 -218.58351)
			(xy 354.108004 -218.561412) (xy 353.903026 -218.206574) (xy 353.880166 -218.202256) (xy 353.855362 -218.197073)
			(xy 353.807624 -218.180081) (xy 353.763049 -218.155985) (xy 353.722684 -218.125353) (xy 353.687482 -218.088906)
			(xy 353.65827 -218.047502) (xy 353.635737 -218.002116) (xy 353.620413 -217.953817) (xy 353.61266 -217.903742)
			(xy 353.612196 -217.878406) (xy 353.331272 -217.878406) (xy 353.330764 -217.904293) (xy 353.322665 -217.955431)
			(xy 353.306666 -218.004671) (xy 353.28316 -218.050803) (xy 353.252728 -218.09269) (xy 353.216118 -218.1293)
			(xy 353.174231 -218.159732) (xy 353.128099 -218.183238) (xy 353.078859 -218.199237) (xy 353.027721 -218.207336)
			(xy 352.975947 -218.207336) (xy 352.924809 -218.199237) (xy 352.875569 -218.183238) (xy 352.829437 -218.159732)
			(xy 352.78755 -218.1293) (xy 352.75094 -218.09269) (xy 352.720508 -218.050803) (xy 352.697002 -218.004671)
			(xy 352.681003 -217.955431) (xy 352.672904 -217.904293) (xy 352.672396 -217.878406) (xy 352.391472 -217.878406)
			(xy 352.390941 -217.906114) (xy 352.381746 -217.960761) (xy 352.373184 -217.987118) (xy 352.36531 -218.009216)
			(xy 352.570288 -218.364054) (xy 352.593148 -218.368372) (xy 352.617963 -218.373563) (xy 352.665741 -218.390515)
			(xy 352.710359 -218.414584) (xy 352.750765 -218.445202) (xy 352.786006 -218.481645) (xy 352.81525 -218.523056)
			(xy 352.837809 -218.568456) (xy 352.853149 -218.616776) (xy 352.860908 -218.666874) (xy 352.861372 -218.692222)
			(xy 352.860864 -218.718129) (xy 352.852758 -218.769306) (xy 352.836746 -218.818585) (xy 352.813223 -218.864752)
			(xy 352.782767 -218.906671) (xy 352.746129 -218.943309) (xy 352.70421 -218.973765) (xy 352.658043 -218.997288)
			(xy 352.608764 -219.0133) (xy 352.557587 -219.021406) (xy 352.505773 -219.021406) (xy 352.454596 -219.0133)
			(xy 352.405317 -218.997288) (xy 352.35915 -218.973765) (xy 352.317231 -218.943309) (xy 352.280593 -218.906671)
			(xy 352.250137 -218.864752) (xy 352.226614 -218.818585) (xy 352.210602 -218.769306) (xy 352.202496 -218.718129)
			(xy 352.201988 -218.692222) (xy 352.202588 -218.664505) (xy 352.211907 -218.609859) (xy 352.22053 -218.58351)
			(xy 352.228404 -218.561412) (xy 352.023426 -218.206574) (xy 352.000566 -218.202256) (xy 351.975762 -218.197073)
			(xy 351.928024 -218.180081) (xy 351.883449 -218.155985) (xy 351.843084 -218.125353) (xy 351.807882 -218.088906)
			(xy 351.77867 -218.047502) (xy 351.756137 -218.002116) (xy 351.740813 -217.953817) (xy 351.73306 -217.903742)
			(xy 351.732596 -217.878406) (xy 351.451672 -217.878406) (xy 351.451164 -217.904293) (xy 351.443065 -217.955431)
			(xy 351.427066 -218.004671) (xy 351.40356 -218.050803) (xy 351.373128 -218.09269) (xy 351.336518 -218.1293)
			(xy 351.294631 -218.159732) (xy 351.248499 -218.183238) (xy 351.199259 -218.199237) (xy 351.148121 -218.207336)
			(xy 351.096347 -218.207336) (xy 351.045209 -218.199237) (xy 350.995969 -218.183238) (xy 350.949837 -218.159732)
			(xy 350.90795 -218.1293) (xy 350.87134 -218.09269) (xy 350.840908 -218.050803) (xy 350.817402 -218.004671)
			(xy 350.801403 -217.955431) (xy 350.793304 -217.904293) (xy 350.792796 -217.878406) (xy 350.511872 -217.878406)
			(xy 350.511341 -217.906114) (xy 350.502146 -217.960761) (xy 350.493584 -217.987118) (xy 350.48571 -218.009216)
			(xy 350.690688 -218.364054) (xy 350.713548 -218.368372) (xy 350.738363 -218.373563) (xy 350.786141 -218.390515)
			(xy 350.830759 -218.414584) (xy 350.871165 -218.445202) (xy 350.906406 -218.481645) (xy 350.93565 -218.523056)
			(xy 350.958209 -218.568456) (xy 350.973549 -218.616776) (xy 350.981308 -218.666874) (xy 350.981772 -218.692222)
			(xy 350.981264 -218.718129) (xy 350.973158 -218.769306) (xy 350.957146 -218.818585) (xy 350.933623 -218.864752)
			(xy 350.903167 -218.906671) (xy 350.866529 -218.943309) (xy 350.82461 -218.973765) (xy 350.778443 -218.997288)
			(xy 350.729164 -219.0133) (xy 350.677987 -219.021406) (xy 350.626173 -219.021406) (xy 350.574996 -219.0133)
			(xy 350.525717 -218.997288) (xy 350.47955 -218.973765) (xy 350.437631 -218.943309) (xy 350.400993 -218.906671)
			(xy 350.370537 -218.864752) (xy 350.347014 -218.818585) (xy 350.331002 -218.769306) (xy 350.322896 -218.718129)
			(xy 350.322388 -218.692222) (xy 350.322988 -218.664505) (xy 350.332307 -218.609859) (xy 350.34093 -218.58351)
			(xy 350.348804 -218.561412) (xy 350.143826 -218.206574) (xy 350.120966 -218.202256) (xy 350.096162 -218.197073)
			(xy 350.048424 -218.180081) (xy 350.003849 -218.155985) (xy 349.963484 -218.125353) (xy 349.928282 -218.088906)
			(xy 349.89907 -218.047502) (xy 349.876537 -218.002116) (xy 349.861213 -217.953817) (xy 349.85346 -217.903742)
			(xy 349.852996 -217.878406) (xy 349.572072 -217.878406) (xy 349.571564 -217.904293) (xy 349.563465 -217.955431)
			(xy 349.547466 -218.004671) (xy 349.52396 -218.050803) (xy 349.493528 -218.09269) (xy 349.456918 -218.1293)
			(xy 349.415031 -218.159732) (xy 349.368899 -218.183238) (xy 349.319659 -218.199237) (xy 349.268521 -218.207336)
			(xy 349.216747 -218.207336) (xy 349.165609 -218.199237) (xy 349.116369 -218.183238) (xy 349.070237 -218.159732)
			(xy 349.02835 -218.1293) (xy 348.99174 -218.09269) (xy 348.961308 -218.050803) (xy 348.937802 -218.004671)
			(xy 348.921803 -217.955431) (xy 348.913704 -217.904293) (xy 348.913196 -217.878406) (xy 348.632272 -217.878406)
			(xy 348.631741 -217.906114) (xy 348.622546 -217.960761) (xy 348.613984 -217.987118) (xy 348.60611 -218.009216)
			(xy 348.811088 -218.364054) (xy 348.833948 -218.368372) (xy 348.858763 -218.373563) (xy 348.906541 -218.390515)
			(xy 348.951159 -218.414584) (xy 348.991565 -218.445202) (xy 349.026806 -218.481645) (xy 349.05605 -218.523056)
			(xy 349.078609 -218.568456) (xy 349.093949 -218.616776) (xy 349.101708 -218.666874) (xy 349.102172 -218.692222)
			(xy 349.101664 -218.718129) (xy 349.093558 -218.769306) (xy 349.077546 -218.818585) (xy 349.054023 -218.864752)
			(xy 349.023567 -218.906671) (xy 348.986929 -218.943309) (xy 348.94501 -218.973765) (xy 348.898843 -218.997288)
			(xy 348.849564 -219.0133) (xy 348.798387 -219.021406) (xy 348.746573 -219.021406) (xy 348.695396 -219.0133)
			(xy 348.646117 -218.997288) (xy 348.59995 -218.973765) (xy 348.558031 -218.943309) (xy 348.521393 -218.906671)
			(xy 348.490937 -218.864752) (xy 348.467414 -218.818585) (xy 348.451402 -218.769306) (xy 348.443296 -218.718129)
			(xy 348.442788 -218.692222) (xy 348.443388 -218.664505) (xy 348.452707 -218.609859) (xy 348.46133 -218.58351)
			(xy 348.469204 -218.561412) (xy 348.264226 -218.206574) (xy 348.241366 -218.202256) (xy 348.216562 -218.197073)
			(xy 348.168824 -218.180081) (xy 348.124249 -218.155985) (xy 348.083884 -218.125353) (xy 348.048682 -218.088906)
			(xy 348.01947 -218.047502) (xy 347.996937 -218.002116) (xy 347.981613 -217.953817) (xy 347.97386 -217.903742)
			(xy 347.973396 -217.878406) (xy 347.692472 -217.878406) (xy 347.691964 -217.904293) (xy 347.683865 -217.955431)
			(xy 347.667866 -218.004671) (xy 347.64436 -218.050803) (xy 347.613928 -218.09269) (xy 347.577318 -218.1293)
			(xy 347.535431 -218.159732) (xy 347.489299 -218.183238) (xy 347.440059 -218.199237) (xy 347.388921 -218.207336)
			(xy 347.337147 -218.207336) (xy 347.286009 -218.199237) (xy 347.236769 -218.183238) (xy 347.190637 -218.159732)
			(xy 347.14875 -218.1293) (xy 347.11214 -218.09269) (xy 347.081708 -218.050803) (xy 347.058202 -218.004671)
			(xy 347.042203 -217.955431) (xy 347.034104 -217.904293) (xy 347.033596 -217.878406) (xy 346.752672 -217.878406)
			(xy 346.752141 -217.906114) (xy 346.742946 -217.960761) (xy 346.734384 -217.987118) (xy 346.72651 -218.009216)
			(xy 346.931488 -218.364054) (xy 346.954348 -218.368372) (xy 346.979163 -218.373563) (xy 347.026941 -218.390515)
			(xy 347.071559 -218.414584) (xy 347.111965 -218.445202) (xy 347.147206 -218.481645) (xy 347.17645 -218.523056)
			(xy 347.199009 -218.568456) (xy 347.214349 -218.616776) (xy 347.222108 -218.666874) (xy 347.222572 -218.692222)
			(xy 347.222064 -218.718129) (xy 347.213958 -218.769306) (xy 347.197946 -218.818585) (xy 347.174423 -218.864752)
			(xy 347.143967 -218.906671) (xy 347.107329 -218.943309) (xy 347.06541 -218.973765) (xy 347.019243 -218.997288)
			(xy 346.969964 -219.0133) (xy 346.918787 -219.021406) (xy 346.866973 -219.021406) (xy 346.815796 -219.0133)
			(xy 346.766517 -218.997288) (xy 346.72035 -218.973765) (xy 346.678431 -218.943309) (xy 346.641793 -218.906671)
			(xy 346.611337 -218.864752) (xy 346.587814 -218.818585) (xy 346.571802 -218.769306) (xy 346.563696 -218.718129)
			(xy 346.563188 -218.692222) (xy 346.563788 -218.664505) (xy 346.573107 -218.609859) (xy 346.58173 -218.58351)
			(xy 346.589604 -218.561412) (xy 346.384626 -218.206574) (xy 346.361766 -218.202256) (xy 346.336962 -218.197073)
			(xy 346.289224 -218.180081) (xy 346.244649 -218.155985) (xy 346.204284 -218.125353) (xy 346.169082 -218.088906)
			(xy 346.13987 -218.047502) (xy 346.117337 -218.002116) (xy 346.102013 -217.953817) (xy 346.09426 -217.903742)
			(xy 346.093796 -217.878406) (xy 345.812872 -217.878406) (xy 345.812364 -217.904293) (xy 345.804265 -217.955431)
			(xy 345.788266 -218.004671) (xy 345.76476 -218.050803) (xy 345.734328 -218.09269) (xy 345.697718 -218.1293)
			(xy 345.655831 -218.159732) (xy 345.609699 -218.183238) (xy 345.560459 -218.199237) (xy 345.509321 -218.207336)
			(xy 345.457547 -218.207336) (xy 345.406409 -218.199237) (xy 345.357169 -218.183238) (xy 345.311037 -218.159732)
			(xy 345.26915 -218.1293) (xy 345.23254 -218.09269) (xy 345.202108 -218.050803) (xy 345.178602 -218.004671)
			(xy 345.162603 -217.955431) (xy 345.154504 -217.904293) (xy 345.153996 -217.878406) (xy 344.873072 -217.878406)
			(xy 344.872541 -217.906114) (xy 344.863346 -217.960761) (xy 344.854784 -217.987118) (xy 344.84691 -218.009216)
			(xy 345.051888 -218.364054) (xy 345.074748 -218.368372) (xy 345.099563 -218.373563) (xy 345.147341 -218.390515)
			(xy 345.191959 -218.414584) (xy 345.232365 -218.445202) (xy 345.267606 -218.481645) (xy 345.29685 -218.523056)
			(xy 345.319409 -218.568456) (xy 345.334749 -218.616776) (xy 345.342508 -218.666874) (xy 345.342972 -218.692222)
			(xy 345.342464 -218.718129) (xy 345.334358 -218.769306) (xy 345.318346 -218.818585) (xy 345.294823 -218.864752)
			(xy 345.264367 -218.906671) (xy 345.227729 -218.943309) (xy 345.18581 -218.973765) (xy 345.139643 -218.997288)
			(xy 345.090364 -219.0133) (xy 345.039187 -219.021406) (xy 344.987373 -219.021406) (xy 344.936196 -219.0133)
			(xy 344.886917 -218.997288) (xy 344.84075 -218.973765) (xy 344.798831 -218.943309) (xy 344.762193 -218.906671)
			(xy 344.731737 -218.864752) (xy 344.708214 -218.818585) (xy 344.692202 -218.769306) (xy 344.684096 -218.718129)
			(xy 344.683588 -218.692222) (xy 344.684188 -218.664505) (xy 344.693507 -218.609859) (xy 344.70213 -218.58351)
			(xy 344.710004 -218.561412) (xy 344.505026 -218.206574) (xy 344.482166 -218.202256) (xy 344.457362 -218.197073)
			(xy 344.409624 -218.180081) (xy 344.365049 -218.155985) (xy 344.324684 -218.125353) (xy 344.289482 -218.088906)
			(xy 344.26027 -218.047502) (xy 344.237737 -218.002116) (xy 344.222413 -217.953817) (xy 344.21466 -217.903742)
			(xy 344.214196 -217.878406) (xy 343.933272 -217.878406) (xy 343.932764 -217.904293) (xy 343.924665 -217.955431)
			(xy 343.908666 -218.004671) (xy 343.88516 -218.050803) (xy 343.854728 -218.09269) (xy 343.818118 -218.1293)
			(xy 343.776231 -218.159732) (xy 343.730099 -218.183238) (xy 343.680859 -218.199237) (xy 343.629721 -218.207336)
			(xy 343.577947 -218.207336) (xy 343.526809 -218.199237) (xy 343.477569 -218.183238) (xy 343.431437 -218.159732)
			(xy 343.38955 -218.1293) (xy 343.35294 -218.09269) (xy 343.322508 -218.050803) (xy 343.299002 -218.004671)
			(xy 343.283003 -217.955431) (xy 343.274904 -217.904293) (xy 343.274396 -217.878406) (xy 342.993472 -217.878406)
			(xy 342.992941 -217.906114) (xy 342.983746 -217.960761) (xy 342.975184 -217.987118) (xy 342.96731 -218.009216)
			(xy 343.172288 -218.364054) (xy 343.195148 -218.368372) (xy 343.219963 -218.373563) (xy 343.267741 -218.390515)
			(xy 343.312359 -218.414584) (xy 343.352765 -218.445202) (xy 343.388006 -218.481645) (xy 343.41725 -218.523056)
			(xy 343.439809 -218.568456) (xy 343.455149 -218.616776) (xy 343.462908 -218.666874) (xy 343.463372 -218.692222)
			(xy 343.462864 -218.718129) (xy 343.454758 -218.769306) (xy 343.438746 -218.818585) (xy 343.415223 -218.864752)
			(xy 343.384767 -218.906671) (xy 343.348129 -218.943309) (xy 343.30621 -218.973765) (xy 343.260043 -218.997288)
			(xy 343.210764 -219.0133) (xy 343.159587 -219.021406) (xy 343.107773 -219.021406) (xy 343.056596 -219.0133)
			(xy 343.007317 -218.997288) (xy 342.96115 -218.973765) (xy 342.919231 -218.943309) (xy 342.882593 -218.906671)
			(xy 342.852137 -218.864752) (xy 342.828614 -218.818585) (xy 342.812602 -218.769306) (xy 342.804496 -218.718129)
			(xy 342.803988 -218.692222) (xy 342.804588 -218.664505) (xy 342.813907 -218.609859) (xy 342.82253 -218.58351)
			(xy 342.830404 -218.561412) (xy 342.625426 -218.206574) (xy 342.602566 -218.202256) (xy 342.577762 -218.197073)
			(xy 342.530024 -218.180081) (xy 342.485449 -218.155985) (xy 342.445084 -218.125353) (xy 342.409882 -218.088906)
			(xy 342.38067 -218.047502) (xy 342.358137 -218.002116) (xy 342.342813 -217.953817) (xy 342.33506 -217.903742)
			(xy 342.334596 -217.878406) (xy 342.053672 -217.878406) (xy 342.053164 -217.904293) (xy 342.045065 -217.955431)
			(xy 342.029066 -218.004671) (xy 342.00556 -218.050803) (xy 341.975128 -218.09269) (xy 341.938518 -218.1293)
			(xy 341.896631 -218.159732) (xy 341.850499 -218.183238) (xy 341.801259 -218.199237) (xy 341.750121 -218.207336)
			(xy 341.698347 -218.207336) (xy 341.647209 -218.199237) (xy 341.597969 -218.183238) (xy 341.551837 -218.159732)
			(xy 341.50995 -218.1293) (xy 341.47334 -218.09269) (xy 341.442908 -218.050803) (xy 341.419402 -218.004671)
			(xy 341.403403 -217.955431) (xy 341.395304 -217.904293) (xy 341.394796 -217.878406) (xy 341.113872 -217.878406)
			(xy 341.113341 -217.906114) (xy 341.104146 -217.960761) (xy 341.095584 -217.987118) (xy 341.08771 -218.009216)
			(xy 341.292688 -218.364054) (xy 341.315548 -218.368372) (xy 341.340363 -218.373563) (xy 341.388141 -218.390515)
			(xy 341.432759 -218.414584) (xy 341.473165 -218.445202) (xy 341.508406 -218.481645) (xy 341.53765 -218.523056)
			(xy 341.560209 -218.568456) (xy 341.575549 -218.616776) (xy 341.583308 -218.666874) (xy 341.583772 -218.692222)
			(xy 341.583264 -218.718129) (xy 341.575158 -218.769306) (xy 341.559146 -218.818585) (xy 341.535623 -218.864752)
			(xy 341.505167 -218.906671) (xy 341.468529 -218.943309) (xy 341.42661 -218.973765) (xy 341.380443 -218.997288)
			(xy 341.331164 -219.0133) (xy 341.279987 -219.021406) (xy 341.228173 -219.021406) (xy 341.176996 -219.0133)
			(xy 341.127717 -218.997288) (xy 341.08155 -218.973765) (xy 341.039631 -218.943309) (xy 341.002993 -218.906671)
			(xy 340.972537 -218.864752) (xy 340.949014 -218.818585) (xy 340.933002 -218.769306) (xy 340.924896 -218.718129)
			(xy 340.924388 -218.692222) (xy 340.924988 -218.664505) (xy 340.934307 -218.609859) (xy 340.94293 -218.58351)
			(xy 340.950804 -218.561412) (xy 340.745826 -218.206574) (xy 340.722966 -218.202256) (xy 340.698162 -218.197073)
			(xy 340.650424 -218.180081) (xy 340.605849 -218.155985) (xy 340.565484 -218.125353) (xy 340.530282 -218.088906)
			(xy 340.50107 -218.047502) (xy 340.478537 -218.002116) (xy 340.463213 -217.953817) (xy 340.45546 -217.903742)
			(xy 340.454996 -217.878406) (xy 340.174072 -217.878406) (xy 340.173564 -217.904293) (xy 340.165465 -217.955431)
			(xy 340.149466 -218.004671) (xy 340.12596 -218.050803) (xy 340.095528 -218.09269) (xy 340.058918 -218.1293)
			(xy 340.017031 -218.159732) (xy 339.970899 -218.183238) (xy 339.921659 -218.199237) (xy 339.870521 -218.207336)
			(xy 339.818747 -218.207336) (xy 339.767609 -218.199237) (xy 339.718369 -218.183238) (xy 339.672237 -218.159732)
			(xy 339.63035 -218.1293) (xy 339.59374 -218.09269) (xy 339.563308 -218.050803) (xy 339.539802 -218.004671)
			(xy 339.523803 -217.955431) (xy 339.515704 -217.904293) (xy 339.515196 -217.878406) (xy 339.234272 -217.878406)
			(xy 339.233741 -217.906114) (xy 339.224546 -217.960761) (xy 339.215984 -217.987118) (xy 339.20811 -218.009216)
			(xy 339.413088 -218.364054) (xy 339.435948 -218.368372) (xy 339.460763 -218.373563) (xy 339.508541 -218.390515)
			(xy 339.553159 -218.414584) (xy 339.593565 -218.445202) (xy 339.628806 -218.481645) (xy 339.65805 -218.523056)
			(xy 339.680609 -218.568456) (xy 339.695949 -218.616776) (xy 339.703708 -218.666874) (xy 339.704172 -218.692222)
			(xy 339.703664 -218.718129) (xy 339.695558 -218.769306) (xy 339.679546 -218.818585) (xy 339.656023 -218.864752)
			(xy 339.625567 -218.906671) (xy 339.588929 -218.943309) (xy 339.54701 -218.973765) (xy 339.500843 -218.997288)
			(xy 339.451564 -219.0133) (xy 339.400387 -219.021406) (xy 339.348573 -219.021406) (xy 339.297396 -219.0133)
			(xy 339.248117 -218.997288) (xy 339.20195 -218.973765) (xy 339.160031 -218.943309) (xy 339.123393 -218.906671)
			(xy 339.092937 -218.864752) (xy 339.069414 -218.818585) (xy 339.053402 -218.769306) (xy 339.045296 -218.718129)
			(xy 339.044788 -218.692222) (xy 339.045388 -218.664505) (xy 339.054707 -218.609859) (xy 339.06333 -218.58351)
			(xy 339.071204 -218.561412) (xy 338.866226 -218.206574) (xy 338.843366 -218.202256) (xy 338.818562 -218.197073)
			(xy 338.770824 -218.180081) (xy 338.726249 -218.155985) (xy 338.685884 -218.125353) (xy 338.650682 -218.088906)
			(xy 338.62147 -218.047502) (xy 338.598937 -218.002116) (xy 338.583613 -217.953817) (xy 338.57586 -217.903742)
			(xy 338.575396 -217.878406) (xy 338.294472 -217.878406) (xy 338.293964 -217.904293) (xy 338.285865 -217.955431)
			(xy 338.269866 -218.004671) (xy 338.24636 -218.050803) (xy 338.215928 -218.09269) (xy 338.179318 -218.1293)
			(xy 338.137431 -218.159732) (xy 338.091299 -218.183238) (xy 338.042059 -218.199237) (xy 337.990921 -218.207336)
			(xy 337.939147 -218.207336) (xy 337.888009 -218.199237) (xy 337.838769 -218.183238) (xy 337.792637 -218.159732)
			(xy 337.75075 -218.1293) (xy 337.71414 -218.09269) (xy 337.683708 -218.050803) (xy 337.660202 -218.004671)
			(xy 337.644203 -217.955431) (xy 337.636104 -217.904293) (xy 337.635596 -217.878406) (xy 337.354672 -217.878406)
			(xy 337.354141 -217.906114) (xy 337.344946 -217.960761) (xy 337.336384 -217.987118) (xy 337.32851 -218.009216)
			(xy 337.533488 -218.364054) (xy 337.556348 -218.368372) (xy 337.581163 -218.373563) (xy 337.628941 -218.390515)
			(xy 337.673559 -218.414584) (xy 337.713965 -218.445202) (xy 337.749206 -218.481645) (xy 337.77845 -218.523056)
			(xy 337.801009 -218.568456) (xy 337.816349 -218.616776) (xy 337.824108 -218.666874) (xy 337.824572 -218.692222)
			(xy 337.824064 -218.718129) (xy 337.815958 -218.769306) (xy 337.799946 -218.818585) (xy 337.776423 -218.864752)
			(xy 337.745967 -218.906671) (xy 337.709329 -218.943309) (xy 337.66741 -218.973765) (xy 337.621243 -218.997288)
			(xy 337.571964 -219.0133) (xy 337.520787 -219.021406) (xy 337.468973 -219.021406) (xy 337.417796 -219.0133)
			(xy 337.368517 -218.997288) (xy 337.32235 -218.973765) (xy 337.280431 -218.943309) (xy 337.243793 -218.906671)
			(xy 337.213337 -218.864752) (xy 337.189814 -218.818585) (xy 337.173802 -218.769306) (xy 337.165696 -218.718129)
			(xy 337.165188 -218.692222) (xy 337.165788 -218.664505) (xy 337.175107 -218.609859) (xy 337.18373 -218.58351)
			(xy 337.191604 -218.561412) (xy 336.986626 -218.206574) (xy 336.963766 -218.202256) (xy 336.938962 -218.197073)
			(xy 336.891224 -218.180081) (xy 336.846649 -218.155985) (xy 336.806284 -218.125353) (xy 336.771082 -218.088906)
			(xy 336.74187 -218.047502) (xy 336.719337 -218.002116) (xy 336.704013 -217.953817) (xy 336.69626 -217.903742)
			(xy 336.695796 -217.878406) (xy 134.525004 -217.878406) (xy 134.524496 -217.904293) (xy 134.516397 -217.955431)
			(xy 134.500398 -218.004671) (xy 134.476892 -218.050803) (xy 134.44646 -218.09269) (xy 134.40985 -218.1293)
			(xy 134.367963 -218.159732) (xy 134.321831 -218.183238) (xy 134.272591 -218.199237) (xy 134.221453 -218.207336)
			(xy 134.169679 -218.207336) (xy 134.118541 -218.199237) (xy 134.069301 -218.183238) (xy 134.023169 -218.159732)
			(xy 133.981282 -218.1293) (xy 133.944672 -218.09269) (xy 133.91424 -218.050803) (xy 133.890734 -218.004671)
			(xy 133.874735 -217.955431) (xy 133.866636 -217.904293) (xy 133.866128 -217.878406) (xy 133.866662 -217.850698)
			(xy 133.875855 -217.796051) (xy 133.884416 -217.769694) (xy 133.89229 -217.747596) (xy 133.687312 -217.392504)
			(xy 133.664452 -217.388186) (xy 133.639596 -217.383069) (xy 133.591748 -217.366166) (xy 133.547056 -217.342128)
			(xy 133.506577 -217.311523) (xy 133.471267 -217.275076) (xy 133.441961 -217.233647) (xy 133.419352 -217.188215)
			(xy 133.403974 -217.139855) (xy 133.39619 -217.089709) (xy 133.39572 -217.064336) (xy 132.175504 -217.064336)
			(xy 132.174889 -217.091989) (xy 132.165569 -217.146507) (xy 132.156962 -217.172794) (xy 132.149342 -217.194892)
			(xy 132.354574 -217.550238) (xy 132.377434 -217.554556) (xy 132.402241 -217.559728) (xy 132.449979 -217.576721)
			(xy 132.494556 -217.600818) (xy 132.53492 -217.631451) (xy 132.570123 -217.6679) (xy 132.599334 -217.709305)
			(xy 132.621866 -217.754693) (xy 132.637189 -217.802993) (xy 132.644941 -217.85307) (xy 132.645404 -217.878406)
			(xy 132.644896 -217.904293) (xy 132.636797 -217.955431) (xy 132.620798 -218.004671) (xy 132.597292 -218.050803)
			(xy 132.56686 -218.09269) (xy 132.53025 -218.1293) (xy 132.488363 -218.159732) (xy 132.442231 -218.183238)
			(xy 132.392991 -218.199237) (xy 132.341853 -218.207336) (xy 132.290079 -218.207336) (xy 132.238941 -218.199237)
			(xy 132.189701 -218.183238) (xy 132.143569 -218.159732) (xy 132.101682 -218.1293) (xy 132.065072 -218.09269)
			(xy 132.03464 -218.050803) (xy 132.011134 -218.004671) (xy 131.995135 -217.955431) (xy 131.987036 -217.904293)
			(xy 131.986528 -217.878406) (xy 131.987062 -217.850698) (xy 131.996255 -217.796051) (xy 132.004816 -217.769694)
			(xy 132.01269 -217.747596) (xy 131.807712 -217.392504) (xy 131.784852 -217.388186) (xy 131.759996 -217.383069)
			(xy 131.712148 -217.366166) (xy 131.667456 -217.342128) (xy 131.626977 -217.311523) (xy 131.591667 -217.275076)
			(xy 131.562361 -217.233647) (xy 131.539752 -217.188215) (xy 131.524374 -217.139855) (xy 131.51659 -217.089709)
			(xy 131.51612 -217.064336) (xy 130.295904 -217.064336) (xy 130.295289 -217.091989) (xy 130.285969 -217.146507)
			(xy 130.277362 -217.172794) (xy 130.269742 -217.194892) (xy 130.474974 -217.550238) (xy 130.497834 -217.554556)
			(xy 130.522641 -217.559728) (xy 130.570379 -217.576721) (xy 130.614956 -217.600818) (xy 130.65532 -217.631451)
			(xy 130.690523 -217.6679) (xy 130.719734 -217.709305) (xy 130.742266 -217.754693) (xy 130.757589 -217.802993)
			(xy 130.765341 -217.85307) (xy 130.765804 -217.878406) (xy 130.765296 -217.904293) (xy 130.757197 -217.955431)
			(xy 130.741198 -218.004671) (xy 130.717692 -218.050803) (xy 130.68726 -218.09269) (xy 130.65065 -218.1293)
			(xy 130.608763 -218.159732) (xy 130.562631 -218.183238) (xy 130.513391 -218.199237) (xy 130.462253 -218.207336)
			(xy 130.410479 -218.207336) (xy 130.359341 -218.199237) (xy 130.310101 -218.183238) (xy 130.263969 -218.159732)
			(xy 130.222082 -218.1293) (xy 130.185472 -218.09269) (xy 130.15504 -218.050803) (xy 130.131534 -218.004671)
			(xy 130.115535 -217.955431) (xy 130.107436 -217.904293) (xy 130.106928 -217.878406) (xy 130.107462 -217.850698)
			(xy 130.116655 -217.796051) (xy 130.125216 -217.769694) (xy 130.13309 -217.747596) (xy 129.928112 -217.392504)
			(xy 129.905252 -217.388186) (xy 129.880396 -217.383069) (xy 129.832548 -217.366166) (xy 129.787856 -217.342128)
			(xy 129.747377 -217.311523) (xy 129.712067 -217.275076) (xy 129.682761 -217.233647) (xy 129.660152 -217.188215)
			(xy 129.644774 -217.139855) (xy 129.63699 -217.089709) (xy 129.63652 -217.064336) (xy 128.416304 -217.064336)
			(xy 128.415689 -217.091989) (xy 128.406369 -217.146507) (xy 128.397762 -217.172794) (xy 128.390142 -217.194892)
			(xy 128.595374 -217.550238) (xy 128.618234 -217.554556) (xy 128.643041 -217.559728) (xy 128.690779 -217.576721)
			(xy 128.735356 -217.600818) (xy 128.77572 -217.631451) (xy 128.810923 -217.6679) (xy 128.840134 -217.709305)
			(xy 128.862666 -217.754693) (xy 128.877989 -217.802993) (xy 128.885741 -217.85307) (xy 128.886204 -217.878406)
			(xy 128.885696 -217.904293) (xy 128.877597 -217.955431) (xy 128.861598 -218.004671) (xy 128.838092 -218.050803)
			(xy 128.80766 -218.09269) (xy 128.77105 -218.1293) (xy 128.729163 -218.159732) (xy 128.683031 -218.183238)
			(xy 128.633791 -218.199237) (xy 128.582653 -218.207336) (xy 128.530879 -218.207336) (xy 128.479741 -218.199237)
			(xy 128.430501 -218.183238) (xy 128.384369 -218.159732) (xy 128.342482 -218.1293) (xy 128.305872 -218.09269)
			(xy 128.27544 -218.050803) (xy 128.251934 -218.004671) (xy 128.235935 -217.955431) (xy 128.227836 -217.904293)
			(xy 128.227328 -217.878406) (xy 128.227862 -217.850698) (xy 128.237055 -217.796051) (xy 128.245616 -217.769694)
			(xy 128.25349 -217.747596) (xy 128.048512 -217.392504) (xy 128.025652 -217.388186) (xy 128.000796 -217.383069)
			(xy 127.952948 -217.366166) (xy 127.908256 -217.342128) (xy 127.867777 -217.311523) (xy 127.832467 -217.275076)
			(xy 127.803161 -217.233647) (xy 127.780552 -217.188215) (xy 127.765174 -217.139855) (xy 127.75739 -217.089709)
			(xy 127.75692 -217.064336) (xy 126.536704 -217.064336) (xy 126.536089 -217.091989) (xy 126.526769 -217.146507)
			(xy 126.518162 -217.172794) (xy 126.510542 -217.194892) (xy 126.715774 -217.550238) (xy 126.738634 -217.554556)
			(xy 126.763441 -217.559728) (xy 126.811179 -217.576721) (xy 126.855756 -217.600818) (xy 126.89612 -217.631451)
			(xy 126.931323 -217.6679) (xy 126.960534 -217.709305) (xy 126.983066 -217.754693) (xy 126.998389 -217.802993)
			(xy 127.006141 -217.85307) (xy 127.006604 -217.878406) (xy 127.006096 -217.904293) (xy 126.997997 -217.955431)
			(xy 126.981998 -218.004671) (xy 126.958492 -218.050803) (xy 126.92806 -218.09269) (xy 126.89145 -218.1293)
			(xy 126.849563 -218.159732) (xy 126.803431 -218.183238) (xy 126.754191 -218.199237) (xy 126.703053 -218.207336)
			(xy 126.651279 -218.207336) (xy 126.600141 -218.199237) (xy 126.550901 -218.183238) (xy 126.504769 -218.159732)
			(xy 126.462882 -218.1293) (xy 126.426272 -218.09269) (xy 126.39584 -218.050803) (xy 126.372334 -218.004671)
			(xy 126.356335 -217.955431) (xy 126.348236 -217.904293) (xy 126.347728 -217.878406) (xy 126.348262 -217.850698)
			(xy 126.357455 -217.796051) (xy 126.366016 -217.769694) (xy 126.37389 -217.747596) (xy 126.168912 -217.392504)
			(xy 126.146052 -217.388186) (xy 126.121196 -217.383069) (xy 126.073348 -217.366166) (xy 126.028656 -217.342128)
			(xy 125.988177 -217.311523) (xy 125.952867 -217.275076) (xy 125.923561 -217.233647) (xy 125.900952 -217.188215)
			(xy 125.885574 -217.139855) (xy 125.87779 -217.089709) (xy 125.87732 -217.064336) (xy 124.657104 -217.064336)
			(xy 124.656489 -217.091989) (xy 124.647169 -217.146507) (xy 124.638562 -217.172794) (xy 124.630942 -217.194892)
			(xy 124.836174 -217.550238) (xy 124.859034 -217.554556) (xy 124.883841 -217.559728) (xy 124.931579 -217.576721)
			(xy 124.976156 -217.600818) (xy 125.01652 -217.631451) (xy 125.051723 -217.6679) (xy 125.080934 -217.709305)
			(xy 125.103466 -217.754693) (xy 125.118789 -217.802993) (xy 125.126541 -217.85307) (xy 125.127004 -217.878406)
			(xy 125.126496 -217.904293) (xy 125.118397 -217.955431) (xy 125.102398 -218.004671) (xy 125.078892 -218.050803)
			(xy 125.04846 -218.09269) (xy 125.01185 -218.1293) (xy 124.969963 -218.159732) (xy 124.923831 -218.183238)
			(xy 124.874591 -218.199237) (xy 124.823453 -218.207336) (xy 124.771679 -218.207336) (xy 124.720541 -218.199237)
			(xy 124.671301 -218.183238) (xy 124.625169 -218.159732) (xy 124.583282 -218.1293) (xy 124.546672 -218.09269)
			(xy 124.51624 -218.050803) (xy 124.492734 -218.004671) (xy 124.476735 -217.955431) (xy 124.468636 -217.904293)
			(xy 124.468128 -217.878406) (xy 124.468662 -217.850698) (xy 124.477855 -217.796051) (xy 124.486416 -217.769694)
			(xy 124.49429 -217.747596) (xy 124.289312 -217.392504) (xy 124.266452 -217.388186) (xy 124.241596 -217.383069)
			(xy 124.193748 -217.366166) (xy 124.149056 -217.342128) (xy 124.108577 -217.311523) (xy 124.073267 -217.275076)
			(xy 124.043961 -217.233647) (xy 124.021352 -217.188215) (xy 124.005974 -217.139855) (xy 123.99819 -217.089709)
			(xy 123.99772 -217.064336) (xy 122.777504 -217.064336) (xy 122.776889 -217.091989) (xy 122.767569 -217.146507)
			(xy 122.758962 -217.172794) (xy 122.751342 -217.194892) (xy 122.956574 -217.550238) (xy 122.979434 -217.554556)
			(xy 123.004241 -217.559728) (xy 123.051979 -217.576721) (xy 123.096556 -217.600818) (xy 123.13692 -217.631451)
			(xy 123.172123 -217.6679) (xy 123.201334 -217.709305) (xy 123.223866 -217.754693) (xy 123.239189 -217.802993)
			(xy 123.246941 -217.85307) (xy 123.247404 -217.878406) (xy 123.246896 -217.904293) (xy 123.238797 -217.955431)
			(xy 123.222798 -218.004671) (xy 123.199292 -218.050803) (xy 123.16886 -218.09269) (xy 123.13225 -218.1293)
			(xy 123.090363 -218.159732) (xy 123.044231 -218.183238) (xy 122.994991 -218.199237) (xy 122.943853 -218.207336)
			(xy 122.892079 -218.207336) (xy 122.840941 -218.199237) (xy 122.791701 -218.183238) (xy 122.745569 -218.159732)
			(xy 122.703682 -218.1293) (xy 122.667072 -218.09269) (xy 122.63664 -218.050803) (xy 122.613134 -218.004671)
			(xy 122.597135 -217.955431) (xy 122.589036 -217.904293) (xy 122.588528 -217.878406) (xy 122.589062 -217.850698)
			(xy 122.598255 -217.796051) (xy 122.606816 -217.769694) (xy 122.61469 -217.747596) (xy 122.409712 -217.392504)
			(xy 122.386852 -217.388186) (xy 122.361996 -217.383069) (xy 122.314148 -217.366166) (xy 122.269456 -217.342128)
			(xy 122.228977 -217.311523) (xy 122.193667 -217.275076) (xy 122.164361 -217.233647) (xy 122.141752 -217.188215)
			(xy 122.126374 -217.139855) (xy 122.11859 -217.089709) (xy 122.11812 -217.064336) (xy 120.897904 -217.064336)
			(xy 120.897289 -217.091989) (xy 120.887969 -217.146507) (xy 120.879362 -217.172794) (xy 120.871742 -217.194892)
			(xy 121.076974 -217.550238) (xy 121.099834 -217.554556) (xy 121.124641 -217.559728) (xy 121.172379 -217.576721)
			(xy 121.216956 -217.600818) (xy 121.25732 -217.631451) (xy 121.292523 -217.6679) (xy 121.321734 -217.709305)
			(xy 121.344266 -217.754693) (xy 121.359589 -217.802993) (xy 121.367341 -217.85307) (xy 121.367804 -217.878406)
			(xy 121.367296 -217.904293) (xy 121.359197 -217.955431) (xy 121.343198 -218.004671) (xy 121.319692 -218.050803)
			(xy 121.28926 -218.09269) (xy 121.25265 -218.1293) (xy 121.210763 -218.159732) (xy 121.164631 -218.183238)
			(xy 121.115391 -218.199237) (xy 121.064253 -218.207336) (xy 121.012479 -218.207336) (xy 120.961341 -218.199237)
			(xy 120.912101 -218.183238) (xy 120.865969 -218.159732) (xy 120.824082 -218.1293) (xy 120.787472 -218.09269)
			(xy 120.75704 -218.050803) (xy 120.733534 -218.004671) (xy 120.717535 -217.955431) (xy 120.709436 -217.904293)
			(xy 120.708928 -217.878406) (xy 120.709462 -217.850698) (xy 120.718655 -217.796051) (xy 120.727216 -217.769694)
			(xy 120.73509 -217.747596) (xy 120.530112 -217.392504) (xy 120.507252 -217.388186) (xy 120.482396 -217.383069)
			(xy 120.434548 -217.366166) (xy 120.389856 -217.342128) (xy 120.349377 -217.311523) (xy 120.314067 -217.275076)
			(xy 120.284761 -217.233647) (xy 120.262152 -217.188215) (xy 120.246774 -217.139855) (xy 120.23899 -217.089709)
			(xy 120.23852 -217.064336) (xy 119.018304 -217.064336) (xy 119.017689 -217.091989) (xy 119.008369 -217.146507)
			(xy 118.999762 -217.172794) (xy 118.992142 -217.194892) (xy 119.197374 -217.550238) (xy 119.220234 -217.554556)
			(xy 119.245041 -217.559728) (xy 119.292779 -217.576721) (xy 119.337356 -217.600818) (xy 119.37772 -217.631451)
			(xy 119.412923 -217.6679) (xy 119.442134 -217.709305) (xy 119.464666 -217.754693) (xy 119.479989 -217.802993)
			(xy 119.487741 -217.85307) (xy 119.488204 -217.878406) (xy 119.487696 -217.904293) (xy 119.479597 -217.955431)
			(xy 119.463598 -218.004671) (xy 119.440092 -218.050803) (xy 119.40966 -218.09269) (xy 119.37305 -218.1293)
			(xy 119.331163 -218.159732) (xy 119.285031 -218.183238) (xy 119.235791 -218.199237) (xy 119.184653 -218.207336)
			(xy 119.132879 -218.207336) (xy 119.081741 -218.199237) (xy 119.032501 -218.183238) (xy 118.986369 -218.159732)
			(xy 118.944482 -218.1293) (xy 118.907872 -218.09269) (xy 118.87744 -218.050803) (xy 118.853934 -218.004671)
			(xy 118.837935 -217.955431) (xy 118.829836 -217.904293) (xy 118.829328 -217.878406) (xy 118.829862 -217.850698)
			(xy 118.839055 -217.796051) (xy 118.847616 -217.769694) (xy 118.85549 -217.747596) (xy 118.650512 -217.392504)
			(xy 118.627652 -217.388186) (xy 118.602796 -217.383069) (xy 118.554948 -217.366166) (xy 118.510256 -217.342128)
			(xy 118.469777 -217.311523) (xy 118.434467 -217.275076) (xy 118.405161 -217.233647) (xy 118.382552 -217.188215)
			(xy 118.367174 -217.139855) (xy 118.35939 -217.089709) (xy 118.35892 -217.064336) (xy 117.138704 -217.064336)
			(xy 117.138089 -217.091989) (xy 117.128769 -217.146507) (xy 117.120162 -217.172794) (xy 117.112542 -217.194892)
			(xy 117.317774 -217.550238) (xy 117.340634 -217.554556) (xy 117.365441 -217.559728) (xy 117.413179 -217.576721)
			(xy 117.457756 -217.600818) (xy 117.49812 -217.631451) (xy 117.533323 -217.6679) (xy 117.562534 -217.709305)
			(xy 117.585066 -217.754693) (xy 117.600389 -217.802993) (xy 117.608141 -217.85307) (xy 117.608604 -217.878406)
			(xy 117.608096 -217.904293) (xy 117.599997 -217.955431) (xy 117.583998 -218.004671) (xy 117.560492 -218.050803)
			(xy 117.53006 -218.09269) (xy 117.49345 -218.1293) (xy 117.451563 -218.159732) (xy 117.405431 -218.183238)
			(xy 117.356191 -218.199237) (xy 117.305053 -218.207336) (xy 117.253279 -218.207336) (xy 117.202141 -218.199237)
			(xy 117.152901 -218.183238) (xy 117.106769 -218.159732) (xy 117.064882 -218.1293) (xy 117.028272 -218.09269)
			(xy 116.99784 -218.050803) (xy 116.974334 -218.004671) (xy 116.958335 -217.955431) (xy 116.950236 -217.904293)
			(xy 116.949728 -217.878406) (xy 116.950262 -217.850698) (xy 116.959455 -217.796051) (xy 116.968016 -217.769694)
			(xy 116.97589 -217.747596) (xy 116.770912 -217.392504) (xy 116.748052 -217.388186) (xy 116.723196 -217.383069)
			(xy 116.675348 -217.366166) (xy 116.630656 -217.342128) (xy 116.590177 -217.311523) (xy 116.554867 -217.275076)
			(xy 116.525561 -217.233647) (xy 116.502952 -217.188215) (xy 116.487574 -217.139855) (xy 116.47979 -217.089709)
			(xy 116.47932 -217.064336) (xy 115.259104 -217.064336) (xy 115.258489 -217.091989) (xy 115.249169 -217.146507)
			(xy 115.240562 -217.172794) (xy 115.232942 -217.194892) (xy 115.438174 -217.550238) (xy 115.461034 -217.554556)
			(xy 115.485841 -217.559728) (xy 115.533579 -217.576721) (xy 115.578156 -217.600818) (xy 115.61852 -217.631451)
			(xy 115.653723 -217.6679) (xy 115.682934 -217.709305) (xy 115.705466 -217.754693) (xy 115.720789 -217.802993)
			(xy 115.728541 -217.85307) (xy 115.729004 -217.878406) (xy 115.728496 -217.904293) (xy 115.720397 -217.955431)
			(xy 115.704398 -218.004671) (xy 115.680892 -218.050803) (xy 115.65046 -218.09269) (xy 115.61385 -218.1293)
			(xy 115.571963 -218.159732) (xy 115.525831 -218.183238) (xy 115.476591 -218.199237) (xy 115.425453 -218.207336)
			(xy 115.373679 -218.207336) (xy 115.322541 -218.199237) (xy 115.273301 -218.183238) (xy 115.227169 -218.159732)
			(xy 115.185282 -218.1293) (xy 115.148672 -218.09269) (xy 115.11824 -218.050803) (xy 115.094734 -218.004671)
			(xy 115.078735 -217.955431) (xy 115.070636 -217.904293) (xy 115.070128 -217.878406) (xy 115.070662 -217.850698)
			(xy 115.079855 -217.796051) (xy 115.088416 -217.769694) (xy 115.09629 -217.747596) (xy 114.891312 -217.392504)
			(xy 114.868452 -217.388186) (xy 114.843596 -217.383069) (xy 114.795748 -217.366166) (xy 114.751056 -217.342128)
			(xy 114.710577 -217.311523) (xy 114.675267 -217.275076) (xy 114.645961 -217.233647) (xy 114.623352 -217.188215)
			(xy 114.607974 -217.139855) (xy 114.60019 -217.089709) (xy 114.59972 -217.064336) (xy 113.379504 -217.064336)
			(xy 113.378889 -217.091989) (xy 113.369569 -217.146507) (xy 113.360962 -217.172794) (xy 113.353342 -217.194892)
			(xy 113.558574 -217.550238) (xy 113.581434 -217.554556) (xy 113.606241 -217.559728) (xy 113.653979 -217.576721)
			(xy 113.698556 -217.600818) (xy 113.73892 -217.631451) (xy 113.774123 -217.6679) (xy 113.803334 -217.709305)
			(xy 113.825866 -217.754693) (xy 113.841189 -217.802993) (xy 113.848941 -217.85307) (xy 113.849404 -217.878406)
			(xy 113.848896 -217.904293) (xy 113.840797 -217.955431) (xy 113.824798 -218.004671) (xy 113.801292 -218.050803)
			(xy 113.77086 -218.09269) (xy 113.73425 -218.1293) (xy 113.692363 -218.159732) (xy 113.646231 -218.183238)
			(xy 113.596991 -218.199237) (xy 113.545853 -218.207336) (xy 113.494079 -218.207336) (xy 113.442941 -218.199237)
			(xy 113.393701 -218.183238) (xy 113.347569 -218.159732) (xy 113.305682 -218.1293) (xy 113.269072 -218.09269)
			(xy 113.23864 -218.050803) (xy 113.215134 -218.004671) (xy 113.199135 -217.955431) (xy 113.191036 -217.904293)
			(xy 113.190528 -217.878406) (xy 113.191062 -217.850698) (xy 113.200255 -217.796051) (xy 113.208816 -217.769694)
			(xy 113.21669 -217.747596) (xy 113.011712 -217.392504) (xy 112.988852 -217.388186) (xy 112.963996 -217.383069)
			(xy 112.916148 -217.366166) (xy 112.871456 -217.342128) (xy 112.830977 -217.311523) (xy 112.795667 -217.275076)
			(xy 112.766361 -217.233647) (xy 112.743752 -217.188215) (xy 112.728374 -217.139855) (xy 112.72059 -217.089709)
			(xy 112.72012 -217.064336) (xy 111.499904 -217.064336) (xy 111.499412 -217.08968) (xy 111.491635 -217.13977)
			(xy 111.476286 -217.188079) (xy 111.453725 -217.233471) (xy 111.424484 -217.274876) (xy 111.389252 -217.311319)
			(xy 111.348859 -217.341943) (xy 111.304255 -217.366024) (xy 111.256492 -217.382998) (xy 111.23168 -217.388186)
			(xy 111.20882 -217.392504) (xy 111.003842 -217.747596) (xy 111.011716 -217.76944) (xy 111.020306 -217.795856)
			(xy 111.029495 -217.850633) (xy 111.030004 -217.878406) (xy 111.029496 -217.904293) (xy 111.021397 -217.955431)
			(xy 111.005398 -218.004671) (xy 110.981892 -218.050803) (xy 110.95146 -218.09269) (xy 110.91485 -218.1293)
			(xy 110.872963 -218.159732) (xy 110.826831 -218.183238) (xy 110.777591 -218.199237) (xy 110.726453 -218.207336)
			(xy 110.674679 -218.207336) (xy 110.623541 -218.199237) (xy 110.574301 -218.183238) (xy 110.528169 -218.159732)
			(xy 110.486282 -218.1293) (xy 110.449672 -218.09269) (xy 110.41924 -218.050803) (xy 110.395734 -218.004671)
			(xy 110.379735 -217.955431) (xy 110.371636 -217.904293) (xy 110.371128 -217.878406) (xy 110.090204 -217.878406)
			(xy 110.089676 -217.906114) (xy 110.08048 -217.960761) (xy 110.071916 -217.987118) (xy 110.064296 -218.008962)
			(xy 110.269274 -218.364054) (xy 110.292134 -218.368372) (xy 110.316944 -218.373529) (xy 110.364684 -218.390523)
			(xy 110.409261 -218.414621) (xy 110.449626 -218.445257) (xy 110.484829 -218.481707) (xy 110.51404 -218.523115)
			(xy 110.536571 -218.568504) (xy 110.551892 -218.616807) (xy 110.559642 -218.666885) (xy 110.560104 -218.692222)
			(xy 111.78032 -218.692222) (xy 111.780845 -218.666878) (xy 111.788614 -218.616789) (xy 111.803957 -218.56848)
			(xy 111.826512 -218.523087) (xy 111.855749 -218.481681) (xy 111.890978 -218.445236) (xy 111.931369 -218.414613)
			(xy 111.97597 -218.390531) (xy 112.023732 -218.373559) (xy 112.048544 -218.368372) (xy 112.071404 -218.364054)
			(xy 112.276636 -218.008708) (xy 112.268762 -217.98661) (xy 112.260294 -217.960366) (xy 112.251224 -217.905977)
			(xy 112.250728 -217.878406) (xy 112.251236 -217.852519) (xy 112.259335 -217.801381) (xy 112.275334 -217.752141)
			(xy 112.29884 -217.706009) (xy 112.329272 -217.664122) (xy 112.365882 -217.627512) (xy 112.407769 -217.59708)
			(xy 112.453901 -217.573574) (xy 112.503141 -217.557575) (xy 112.554279 -217.549476) (xy 112.606053 -217.549476)
			(xy 112.657191 -217.557575) (xy 112.706431 -217.573574) (xy 112.752563 -217.59708) (xy 112.79445 -217.627512)
			(xy 112.83106 -217.664122) (xy 112.861492 -217.706009) (xy 112.884998 -217.752141) (xy 112.900997 -217.801381)
			(xy 112.909096 -217.852519) (xy 112.909604 -217.878406) (xy 112.909131 -217.90378) (xy 112.901362 -217.953931)
			(xy 112.885993 -218.002296) (xy 112.863388 -218.047732) (xy 112.834082 -218.089163) (xy 112.798768 -218.125609)
			(xy 112.758282 -218.156208) (xy 112.713582 -218.180235) (xy 112.665726 -218.197122) (xy 112.640872 -218.202256)
			(xy 112.618012 -218.206574) (xy 112.413288 -218.561412) (xy 112.421162 -218.583256) (xy 112.429814 -218.609662)
			(xy 112.43913 -218.66444) (xy 112.439704 -218.692222) (xy 113.660428 -218.692222) (xy 113.660908 -218.666887)
			(xy 113.668658 -218.616813) (xy 113.683979 -218.568515) (xy 113.70651 -218.52313) (xy 113.73572 -218.481727)
			(xy 113.770922 -218.445282) (xy 113.811285 -218.414651) (xy 113.855861 -218.390558) (xy 113.903598 -218.37357)
			(xy 113.928398 -218.368372) (xy 113.951258 -218.364054) (xy 114.156236 -218.008962) (xy 114.148616 -217.986864)
			(xy 114.140092 -217.960694) (xy 114.130901 -217.906431) (xy 114.130328 -217.878914) (xy 114.130328 -217.878406)
			(xy 114.130836 -217.852519) (xy 114.138935 -217.801381) (xy 114.154934 -217.752141) (xy 114.17844 -217.706009)
			(xy 114.208872 -217.664122) (xy 114.245482 -217.627512) (xy 114.287369 -217.59708) (xy 114.333501 -217.573574)
			(xy 114.382741 -217.557575) (xy 114.433879 -217.549476) (xy 114.485653 -217.549476) (xy 114.536791 -217.557575)
			(xy 114.586031 -217.573574) (xy 114.632163 -217.59708) (xy 114.67405 -217.627512) (xy 114.71066 -217.664122)
			(xy 114.741092 -217.706009) (xy 114.764598 -217.752141) (xy 114.780597 -217.801381) (xy 114.788696 -217.852519)
			(xy 114.789204 -217.878406) (xy 114.788769 -217.903771) (xy 114.781019 -217.953906) (xy 114.765673 -218.002259)
			(xy 114.743093 -218.047686) (xy 114.713814 -218.089114) (xy 114.678529 -218.125562) (xy 114.638071 -218.156167)
			(xy 114.593399 -218.180207) (xy 114.545568 -218.197111) (xy 114.520726 -218.202256) (xy 114.497866 -218.206574)
			(xy 114.293142 -218.561412) (xy 114.301016 -218.583256) (xy 114.309609 -218.609671) (xy 114.318797 -218.664449)
			(xy 114.319304 -218.692222) (xy 115.53952 -218.692222) (xy 115.540045 -218.666878) (xy 115.547814 -218.616789)
			(xy 115.563157 -218.56848) (xy 115.585712 -218.523087) (xy 115.614949 -218.481681) (xy 115.650178 -218.445236)
			(xy 115.690569 -218.414613) (xy 115.73517 -218.390531) (xy 115.782932 -218.373559) (xy 115.807744 -218.368372)
			(xy 115.830604 -218.364054) (xy 116.035836 -218.008708) (xy 116.027962 -217.98661) (xy 116.019494 -217.960366)
			(xy 116.010424 -217.905977) (xy 116.009928 -217.878406) (xy 116.010436 -217.852519) (xy 116.018535 -217.801381)
			(xy 116.034534 -217.752141) (xy 116.05804 -217.706009) (xy 116.088472 -217.664122) (xy 116.125082 -217.627512)
			(xy 116.166969 -217.59708) (xy 116.213101 -217.573574) (xy 116.262341 -217.557575) (xy 116.313479 -217.549476)
			(xy 116.365253 -217.549476) (xy 116.416391 -217.557575) (xy 116.465631 -217.573574) (xy 116.511763 -217.59708)
			(xy 116.55365 -217.627512) (xy 116.59026 -217.664122) (xy 116.620692 -217.706009) (xy 116.644198 -217.752141)
			(xy 116.660197 -217.801381) (xy 116.668296 -217.852519) (xy 116.668804 -217.878406) (xy 116.668331 -217.90378)
			(xy 116.660562 -217.953931) (xy 116.645193 -218.002296) (xy 116.622588 -218.047732) (xy 116.593282 -218.089163)
			(xy 116.557968 -218.125609) (xy 116.517482 -218.156208) (xy 116.472782 -218.180235) (xy 116.424926 -218.197122)
			(xy 116.400072 -218.202256) (xy 116.377212 -218.206574) (xy 116.172488 -218.561412) (xy 116.180362 -218.583256)
			(xy 116.189014 -218.609662) (xy 116.19833 -218.66444) (xy 116.198904 -218.692222) (xy 117.41912 -218.692222)
			(xy 117.419645 -218.666878) (xy 117.427414 -218.616789) (xy 117.442757 -218.56848) (xy 117.465312 -218.523087)
			(xy 117.494549 -218.481681) (xy 117.529778 -218.445236) (xy 117.570169 -218.414613) (xy 117.61477 -218.390531)
			(xy 117.662532 -218.373559) (xy 117.687344 -218.368372) (xy 117.710204 -218.364054) (xy 117.915436 -218.008708)
			(xy 117.907562 -217.98661) (xy 117.899094 -217.960366) (xy 117.890024 -217.905977) (xy 117.889528 -217.878406)
			(xy 117.890036 -217.852519) (xy 117.898135 -217.801381) (xy 117.914134 -217.752141) (xy 117.93764 -217.706009)
			(xy 117.968072 -217.664122) (xy 118.004682 -217.627512) (xy 118.046569 -217.59708) (xy 118.092701 -217.573574)
			(xy 118.141941 -217.557575) (xy 118.193079 -217.549476) (xy 118.244853 -217.549476) (xy 118.295991 -217.557575)
			(xy 118.345231 -217.573574) (xy 118.391363 -217.59708) (xy 118.43325 -217.627512) (xy 118.46986 -217.664122)
			(xy 118.500292 -217.706009) (xy 118.523798 -217.752141) (xy 118.539797 -217.801381) (xy 118.547896 -217.852519)
			(xy 118.548404 -217.878406) (xy 118.547931 -217.90378) (xy 118.540162 -217.953931) (xy 118.524793 -218.002296)
			(xy 118.502188 -218.047732) (xy 118.472882 -218.089163) (xy 118.437568 -218.125609) (xy 118.397082 -218.156208)
			(xy 118.352382 -218.180235) (xy 118.304526 -218.197122) (xy 118.279672 -218.202256) (xy 118.256812 -218.206574)
			(xy 118.052088 -218.561412) (xy 118.059962 -218.583256) (xy 118.068614 -218.609662) (xy 118.07793 -218.66444)
			(xy 118.078504 -218.692222) (xy 119.29872 -218.692222) (xy 119.299245 -218.666878) (xy 119.307014 -218.616789)
			(xy 119.322357 -218.56848) (xy 119.344912 -218.523087) (xy 119.374149 -218.481681) (xy 119.409378 -218.445236)
			(xy 119.449769 -218.414613) (xy 119.49437 -218.390531) (xy 119.542132 -218.373559) (xy 119.566944 -218.368372)
			(xy 119.589804 -218.364054) (xy 119.795036 -218.008708) (xy 119.787162 -217.98661) (xy 119.778694 -217.960366)
			(xy 119.769624 -217.905977) (xy 119.769128 -217.878406) (xy 119.769636 -217.852519) (xy 119.777735 -217.801381)
			(xy 119.793734 -217.752141) (xy 119.81724 -217.706009) (xy 119.847672 -217.664122) (xy 119.884282 -217.627512)
			(xy 119.926169 -217.59708) (xy 119.972301 -217.573574) (xy 120.021541 -217.557575) (xy 120.072679 -217.549476)
			(xy 120.124453 -217.549476) (xy 120.175591 -217.557575) (xy 120.224831 -217.573574) (xy 120.270963 -217.59708)
			(xy 120.31285 -217.627512) (xy 120.34946 -217.664122) (xy 120.379892 -217.706009) (xy 120.403398 -217.752141)
			(xy 120.419397 -217.801381) (xy 120.427496 -217.852519) (xy 120.428004 -217.878406) (xy 120.427531 -217.90378)
			(xy 120.419762 -217.953931) (xy 120.404393 -218.002296) (xy 120.381788 -218.047732) (xy 120.352482 -218.089163)
			(xy 120.317168 -218.125609) (xy 120.276682 -218.156208) (xy 120.231982 -218.180235) (xy 120.184126 -218.197122)
			(xy 120.159272 -218.202256) (xy 120.136412 -218.206574) (xy 119.931688 -218.561412) (xy 119.939562 -218.583256)
			(xy 119.948214 -218.609662) (xy 119.95753 -218.66444) (xy 119.958104 -218.692222) (xy 121.17832 -218.692222)
			(xy 121.178845 -218.666878) (xy 121.186614 -218.616789) (xy 121.201957 -218.56848) (xy 121.224512 -218.523087)
			(xy 121.253749 -218.481681) (xy 121.288978 -218.445236) (xy 121.329369 -218.414613) (xy 121.37397 -218.390531)
			(xy 121.421732 -218.373559) (xy 121.446544 -218.368372) (xy 121.469404 -218.364054) (xy 121.674636 -218.008708)
			(xy 121.666762 -217.98661) (xy 121.658294 -217.960366) (xy 121.649224 -217.905977) (xy 121.648728 -217.878406)
			(xy 121.649236 -217.852519) (xy 121.657335 -217.801381) (xy 121.673334 -217.752141) (xy 121.69684 -217.706009)
			(xy 121.727272 -217.664122) (xy 121.763882 -217.627512) (xy 121.805769 -217.59708) (xy 121.851901 -217.573574)
			(xy 121.901141 -217.557575) (xy 121.952279 -217.549476) (xy 122.004053 -217.549476) (xy 122.055191 -217.557575)
			(xy 122.104431 -217.573574) (xy 122.150563 -217.59708) (xy 122.19245 -217.627512) (xy 122.22906 -217.664122)
			(xy 122.259492 -217.706009) (xy 122.282998 -217.752141) (xy 122.298997 -217.801381) (xy 122.307096 -217.852519)
			(xy 122.307604 -217.878406) (xy 122.307131 -217.90378) (xy 122.299362 -217.953931) (xy 122.283993 -218.002296)
			(xy 122.261388 -218.047732) (xy 122.232082 -218.089163) (xy 122.196768 -218.125609) (xy 122.156282 -218.156208)
			(xy 122.111582 -218.180235) (xy 122.063726 -218.197122) (xy 122.038872 -218.202256) (xy 122.016012 -218.206574)
			(xy 121.811288 -218.561412) (xy 121.819162 -218.583256) (xy 121.827814 -218.609662) (xy 121.83713 -218.66444)
			(xy 121.837704 -218.692222) (xy 123.05792 -218.692222) (xy 123.058445 -218.666878) (xy 123.066214 -218.616789)
			(xy 123.081557 -218.56848) (xy 123.104112 -218.523087) (xy 123.133349 -218.481681) (xy 123.168578 -218.445236)
			(xy 123.208969 -218.414613) (xy 123.25357 -218.390531) (xy 123.301332 -218.373559) (xy 123.326144 -218.368372)
			(xy 123.349004 -218.364054) (xy 123.554236 -218.008708) (xy 123.546362 -217.98661) (xy 123.537894 -217.960366)
			(xy 123.528824 -217.905977) (xy 123.528328 -217.878406) (xy 123.528836 -217.852519) (xy 123.536935 -217.801381)
			(xy 123.552934 -217.752141) (xy 123.57644 -217.706009) (xy 123.606872 -217.664122) (xy 123.643482 -217.627512)
			(xy 123.685369 -217.59708) (xy 123.731501 -217.573574) (xy 123.780741 -217.557575) (xy 123.831879 -217.549476)
			(xy 123.883653 -217.549476) (xy 123.934791 -217.557575) (xy 123.984031 -217.573574) (xy 124.030163 -217.59708)
			(xy 124.07205 -217.627512) (xy 124.10866 -217.664122) (xy 124.139092 -217.706009) (xy 124.162598 -217.752141)
			(xy 124.178597 -217.801381) (xy 124.186696 -217.852519) (xy 124.187204 -217.878406) (xy 124.186731 -217.90378)
			(xy 124.178962 -217.953931) (xy 124.163593 -218.002296) (xy 124.140988 -218.047732) (xy 124.111682 -218.089163)
			(xy 124.076368 -218.125609) (xy 124.035882 -218.156208) (xy 123.991182 -218.180235) (xy 123.943326 -218.197122)
			(xy 123.918472 -218.202256) (xy 123.895612 -218.206574) (xy 123.690888 -218.561412) (xy 123.698762 -218.583256)
			(xy 123.707414 -218.609662) (xy 123.71673 -218.66444) (xy 123.717304 -218.692222) (xy 124.93752 -218.692222)
			(xy 124.938045 -218.666878) (xy 124.945814 -218.616789) (xy 124.961157 -218.56848) (xy 124.983712 -218.523087)
			(xy 125.012949 -218.481681) (xy 125.048178 -218.445236) (xy 125.088569 -218.414613) (xy 125.13317 -218.390531)
			(xy 125.180932 -218.373559) (xy 125.205744 -218.368372) (xy 125.228604 -218.364054) (xy 125.433836 -218.008708)
			(xy 125.425962 -217.98661) (xy 125.417494 -217.960366) (xy 125.408424 -217.905977) (xy 125.407928 -217.878406)
			(xy 125.408436 -217.852519) (xy 125.416535 -217.801381) (xy 125.432534 -217.752141) (xy 125.45604 -217.706009)
			(xy 125.486472 -217.664122) (xy 125.523082 -217.627512) (xy 125.564969 -217.59708) (xy 125.611101 -217.573574)
			(xy 125.660341 -217.557575) (xy 125.711479 -217.549476) (xy 125.763253 -217.549476) (xy 125.814391 -217.557575)
			(xy 125.863631 -217.573574) (xy 125.909763 -217.59708) (xy 125.95165 -217.627512) (xy 125.98826 -217.664122)
			(xy 126.018692 -217.706009) (xy 126.042198 -217.752141) (xy 126.058197 -217.801381) (xy 126.066296 -217.852519)
			(xy 126.066804 -217.878406) (xy 126.066331 -217.90378) (xy 126.058562 -217.953931) (xy 126.043193 -218.002296)
			(xy 126.020588 -218.047732) (xy 125.991282 -218.089163) (xy 125.955968 -218.125609) (xy 125.915482 -218.156208)
			(xy 125.870782 -218.180235) (xy 125.822926 -218.197122) (xy 125.798072 -218.202256) (xy 125.775212 -218.206574)
			(xy 125.570488 -218.561412) (xy 125.578362 -218.583256) (xy 125.587014 -218.609662) (xy 125.59633 -218.66444)
			(xy 125.596904 -218.692222) (xy 126.81712 -218.692222) (xy 126.817645 -218.666878) (xy 126.825414 -218.616789)
			(xy 126.840757 -218.56848) (xy 126.863312 -218.523087) (xy 126.892549 -218.481681) (xy 126.927778 -218.445236)
			(xy 126.968169 -218.414613) (xy 127.01277 -218.390531) (xy 127.060532 -218.373559) (xy 127.085344 -218.368372)
			(xy 127.108204 -218.364054) (xy 127.313436 -218.008708) (xy 127.305562 -217.98661) (xy 127.297094 -217.960366)
			(xy 127.288024 -217.905977) (xy 127.287528 -217.878406) (xy 127.288036 -217.852519) (xy 127.296135 -217.801381)
			(xy 127.312134 -217.752141) (xy 127.33564 -217.706009) (xy 127.366072 -217.664122) (xy 127.402682 -217.627512)
			(xy 127.444569 -217.59708) (xy 127.490701 -217.573574) (xy 127.539941 -217.557575) (xy 127.591079 -217.549476)
			(xy 127.642853 -217.549476) (xy 127.693991 -217.557575) (xy 127.743231 -217.573574) (xy 127.789363 -217.59708)
			(xy 127.83125 -217.627512) (xy 127.86786 -217.664122) (xy 127.898292 -217.706009) (xy 127.921798 -217.752141)
			(xy 127.937797 -217.801381) (xy 127.945896 -217.852519) (xy 127.946404 -217.878406) (xy 127.945931 -217.90378)
			(xy 127.938162 -217.953931) (xy 127.922793 -218.002296) (xy 127.900188 -218.047732) (xy 127.870882 -218.089163)
			(xy 127.835568 -218.125609) (xy 127.795082 -218.156208) (xy 127.750382 -218.180235) (xy 127.702526 -218.197122)
			(xy 127.677672 -218.202256) (xy 127.654812 -218.206574) (xy 127.450088 -218.561412) (xy 127.457962 -218.583256)
			(xy 127.466614 -218.609662) (xy 127.47593 -218.66444) (xy 127.476504 -218.692222) (xy 128.69672 -218.692222)
			(xy 128.697245 -218.666878) (xy 128.705014 -218.616789) (xy 128.720357 -218.56848) (xy 128.742912 -218.523087)
			(xy 128.772149 -218.481681) (xy 128.807378 -218.445236) (xy 128.847769 -218.414613) (xy 128.89237 -218.390531)
			(xy 128.940132 -218.373559) (xy 128.964944 -218.368372) (xy 128.987804 -218.364054) (xy 129.193036 -218.008708)
			(xy 129.185162 -217.98661) (xy 129.176694 -217.960366) (xy 129.167624 -217.905977) (xy 129.167128 -217.878406)
			(xy 129.167636 -217.852519) (xy 129.175735 -217.801381) (xy 129.191734 -217.752141) (xy 129.21524 -217.706009)
			(xy 129.245672 -217.664122) (xy 129.282282 -217.627512) (xy 129.324169 -217.59708) (xy 129.370301 -217.573574)
			(xy 129.419541 -217.557575) (xy 129.470679 -217.549476) (xy 129.522453 -217.549476) (xy 129.573591 -217.557575)
			(xy 129.622831 -217.573574) (xy 129.668963 -217.59708) (xy 129.71085 -217.627512) (xy 129.74746 -217.664122)
			(xy 129.777892 -217.706009) (xy 129.801398 -217.752141) (xy 129.817397 -217.801381) (xy 129.825496 -217.852519)
			(xy 129.826004 -217.878406) (xy 129.825531 -217.90378) (xy 129.817762 -217.953931) (xy 129.802393 -218.002296)
			(xy 129.779788 -218.047732) (xy 129.750482 -218.089163) (xy 129.715168 -218.125609) (xy 129.674682 -218.156208)
			(xy 129.629982 -218.180235) (xy 129.582126 -218.197122) (xy 129.557272 -218.202256) (xy 129.534412 -218.206574)
			(xy 129.329688 -218.561412) (xy 129.337562 -218.583256) (xy 129.346214 -218.609662) (xy 129.35553 -218.66444)
			(xy 129.356104 -218.692222) (xy 130.57632 -218.692222) (xy 130.576845 -218.666878) (xy 130.584614 -218.616789)
			(xy 130.599957 -218.56848) (xy 130.622512 -218.523087) (xy 130.651749 -218.481681) (xy 130.686978 -218.445236)
			(xy 130.727369 -218.414613) (xy 130.77197 -218.390531) (xy 130.819732 -218.373559) (xy 130.844544 -218.368372)
			(xy 130.867404 -218.364054) (xy 131.072636 -218.008708) (xy 131.064762 -217.98661) (xy 131.056294 -217.960366)
			(xy 131.047224 -217.905977) (xy 131.046728 -217.878406) (xy 131.047236 -217.852519) (xy 131.055335 -217.801381)
			(xy 131.071334 -217.752141) (xy 131.09484 -217.706009) (xy 131.125272 -217.664122) (xy 131.161882 -217.627512)
			(xy 131.203769 -217.59708) (xy 131.249901 -217.573574) (xy 131.299141 -217.557575) (xy 131.350279 -217.549476)
			(xy 131.402053 -217.549476) (xy 131.453191 -217.557575) (xy 131.502431 -217.573574) (xy 131.548563 -217.59708)
			(xy 131.59045 -217.627512) (xy 131.62706 -217.664122) (xy 131.657492 -217.706009) (xy 131.680998 -217.752141)
			(xy 131.696997 -217.801381) (xy 131.705096 -217.852519) (xy 131.705604 -217.878406) (xy 131.705131 -217.90378)
			(xy 131.697362 -217.953931) (xy 131.681993 -218.002296) (xy 131.659388 -218.047732) (xy 131.630082 -218.089163)
			(xy 131.594768 -218.125609) (xy 131.554282 -218.156208) (xy 131.509582 -218.180235) (xy 131.461726 -218.197122)
			(xy 131.436872 -218.202256) (xy 131.414012 -218.206574) (xy 131.209288 -218.561412) (xy 131.217162 -218.583256)
			(xy 131.225814 -218.609662) (xy 131.23513 -218.66444) (xy 131.235704 -218.692222) (xy 132.45592 -218.692222)
			(xy 132.456445 -218.666878) (xy 132.464214 -218.616789) (xy 132.479557 -218.56848) (xy 132.502112 -218.523087)
			(xy 132.531349 -218.481681) (xy 132.566578 -218.445236) (xy 132.606969 -218.414613) (xy 132.65157 -218.390531)
			(xy 132.699332 -218.373559) (xy 132.724144 -218.368372) (xy 132.747004 -218.364054) (xy 132.952236 -218.008708)
			(xy 132.944362 -217.98661) (xy 132.935894 -217.960366) (xy 132.926824 -217.905977) (xy 132.926328 -217.878406)
			(xy 132.926836 -217.852519) (xy 132.934935 -217.801381) (xy 132.950934 -217.752141) (xy 132.97444 -217.706009)
			(xy 133.004872 -217.664122) (xy 133.041482 -217.627512) (xy 133.083369 -217.59708) (xy 133.129501 -217.573574)
			(xy 133.178741 -217.557575) (xy 133.229879 -217.549476) (xy 133.281653 -217.549476) (xy 133.332791 -217.557575)
			(xy 133.382031 -217.573574) (xy 133.428163 -217.59708) (xy 133.47005 -217.627512) (xy 133.50666 -217.664122)
			(xy 133.537092 -217.706009) (xy 133.560598 -217.752141) (xy 133.576597 -217.801381) (xy 133.584696 -217.852519)
			(xy 133.585204 -217.878406) (xy 133.584731 -217.90378) (xy 133.576962 -217.953931) (xy 133.561593 -218.002296)
			(xy 133.538988 -218.047732) (xy 133.509682 -218.089163) (xy 133.474368 -218.125609) (xy 133.433882 -218.156208)
			(xy 133.389182 -218.180235) (xy 133.341326 -218.197122) (xy 133.316472 -218.202256) (xy 133.293612 -218.206574)
			(xy 133.088888 -218.561412) (xy 133.096762 -218.583256) (xy 133.105414 -218.609662) (xy 133.11473 -218.66444)
			(xy 133.115304 -218.692222) (xy 133.114796 -218.718129) (xy 133.10669 -218.769306) (xy 133.090678 -218.818585)
			(xy 133.067155 -218.864752) (xy 133.036699 -218.906671) (xy 133.000061 -218.943309) (xy 132.958142 -218.973765)
			(xy 132.911975 -218.997288) (xy 132.862696 -219.0133) (xy 132.811519 -219.021406) (xy 132.759705 -219.021406)
			(xy 132.708528 -219.0133) (xy 132.659249 -218.997288) (xy 132.613082 -218.973765) (xy 132.571163 -218.943309)
			(xy 132.534525 -218.906671) (xy 132.504069 -218.864752) (xy 132.480546 -218.818585) (xy 132.464534 -218.769306)
			(xy 132.456428 -218.718129) (xy 132.45592 -218.692222) (xy 131.235704 -218.692222) (xy 131.235196 -218.718129)
			(xy 131.22709 -218.769306) (xy 131.211078 -218.818585) (xy 131.187555 -218.864752) (xy 131.157099 -218.906671)
			(xy 131.120461 -218.943309) (xy 131.078542 -218.973765) (xy 131.032375 -218.997288) (xy 130.983096 -219.0133)
			(xy 130.931919 -219.021406) (xy 130.880105 -219.021406) (xy 130.828928 -219.0133) (xy 130.779649 -218.997288)
			(xy 130.733482 -218.973765) (xy 130.691563 -218.943309) (xy 130.654925 -218.906671) (xy 130.624469 -218.864752)
			(xy 130.600946 -218.818585) (xy 130.584934 -218.769306) (xy 130.576828 -218.718129) (xy 130.57632 -218.692222)
			(xy 129.356104 -218.692222) (xy 129.355596 -218.718129) (xy 129.34749 -218.769306) (xy 129.331478 -218.818585)
			(xy 129.307955 -218.864752) (xy 129.277499 -218.906671) (xy 129.240861 -218.943309) (xy 129.198942 -218.973765)
			(xy 129.152775 -218.997288) (xy 129.103496 -219.0133) (xy 129.052319 -219.021406) (xy 129.000505 -219.021406)
			(xy 128.949328 -219.0133) (xy 128.900049 -218.997288) (xy 128.853882 -218.973765) (xy 128.811963 -218.943309)
			(xy 128.775325 -218.906671) (xy 128.744869 -218.864752) (xy 128.721346 -218.818585) (xy 128.705334 -218.769306)
			(xy 128.697228 -218.718129) (xy 128.69672 -218.692222) (xy 127.476504 -218.692222) (xy 127.475996 -218.718129)
			(xy 127.46789 -218.769306) (xy 127.451878 -218.818585) (xy 127.428355 -218.864752) (xy 127.397899 -218.906671)
			(xy 127.361261 -218.943309) (xy 127.319342 -218.973765) (xy 127.273175 -218.997288) (xy 127.223896 -219.0133)
			(xy 127.172719 -219.021406) (xy 127.120905 -219.021406) (xy 127.069728 -219.0133) (xy 127.020449 -218.997288)
			(xy 126.974282 -218.973765) (xy 126.932363 -218.943309) (xy 126.895725 -218.906671) (xy 126.865269 -218.864752)
			(xy 126.841746 -218.818585) (xy 126.825734 -218.769306) (xy 126.817628 -218.718129) (xy 126.81712 -218.692222)
			(xy 125.596904 -218.692222) (xy 125.596396 -218.718129) (xy 125.58829 -218.769306) (xy 125.572278 -218.818585)
			(xy 125.548755 -218.864752) (xy 125.518299 -218.906671) (xy 125.481661 -218.943309) (xy 125.439742 -218.973765)
			(xy 125.393575 -218.997288) (xy 125.344296 -219.0133) (xy 125.293119 -219.021406) (xy 125.241305 -219.021406)
			(xy 125.190128 -219.0133) (xy 125.140849 -218.997288) (xy 125.094682 -218.973765) (xy 125.052763 -218.943309)
			(xy 125.016125 -218.906671) (xy 124.985669 -218.864752) (xy 124.962146 -218.818585) (xy 124.946134 -218.769306)
			(xy 124.938028 -218.718129) (xy 124.93752 -218.692222) (xy 123.717304 -218.692222) (xy 123.716796 -218.718129)
			(xy 123.70869 -218.769306) (xy 123.692678 -218.818585) (xy 123.669155 -218.864752) (xy 123.638699 -218.906671)
			(xy 123.602061 -218.943309) (xy 123.560142 -218.973765) (xy 123.513975 -218.997288) (xy 123.464696 -219.0133)
			(xy 123.413519 -219.021406) (xy 123.361705 -219.021406) (xy 123.310528 -219.0133) (xy 123.261249 -218.997288)
			(xy 123.215082 -218.973765) (xy 123.173163 -218.943309) (xy 123.136525 -218.906671) (xy 123.106069 -218.864752)
			(xy 123.082546 -218.818585) (xy 123.066534 -218.769306) (xy 123.058428 -218.718129) (xy 123.05792 -218.692222)
			(xy 121.837704 -218.692222) (xy 121.837196 -218.718129) (xy 121.82909 -218.769306) (xy 121.813078 -218.818585)
			(xy 121.789555 -218.864752) (xy 121.759099 -218.906671) (xy 121.722461 -218.943309) (xy 121.680542 -218.973765)
			(xy 121.634375 -218.997288) (xy 121.585096 -219.0133) (xy 121.533919 -219.021406) (xy 121.482105 -219.021406)
			(xy 121.430928 -219.0133) (xy 121.381649 -218.997288) (xy 121.335482 -218.973765) (xy 121.293563 -218.943309)
			(xy 121.256925 -218.906671) (xy 121.226469 -218.864752) (xy 121.202946 -218.818585) (xy 121.186934 -218.769306)
			(xy 121.178828 -218.718129) (xy 121.17832 -218.692222) (xy 119.958104 -218.692222) (xy 119.957596 -218.718129)
			(xy 119.94949 -218.769306) (xy 119.933478 -218.818585) (xy 119.909955 -218.864752) (xy 119.879499 -218.906671)
			(xy 119.842861 -218.943309) (xy 119.800942 -218.973765) (xy 119.754775 -218.997288) (xy 119.705496 -219.0133)
			(xy 119.654319 -219.021406) (xy 119.602505 -219.021406) (xy 119.551328 -219.0133) (xy 119.502049 -218.997288)
			(xy 119.455882 -218.973765) (xy 119.413963 -218.943309) (xy 119.377325 -218.906671) (xy 119.346869 -218.864752)
			(xy 119.323346 -218.818585) (xy 119.307334 -218.769306) (xy 119.299228 -218.718129) (xy 119.29872 -218.692222)
			(xy 118.078504 -218.692222) (xy 118.077996 -218.718129) (xy 118.06989 -218.769306) (xy 118.053878 -218.818585)
			(xy 118.030355 -218.864752) (xy 117.999899 -218.906671) (xy 117.963261 -218.943309) (xy 117.921342 -218.973765)
			(xy 117.875175 -218.997288) (xy 117.825896 -219.0133) (xy 117.774719 -219.021406) (xy 117.722905 -219.021406)
			(xy 117.671728 -219.0133) (xy 117.622449 -218.997288) (xy 117.576282 -218.973765) (xy 117.534363 -218.943309)
			(xy 117.497725 -218.906671) (xy 117.467269 -218.864752) (xy 117.443746 -218.818585) (xy 117.427734 -218.769306)
			(xy 117.419628 -218.718129) (xy 117.41912 -218.692222) (xy 116.198904 -218.692222) (xy 116.198396 -218.718129)
			(xy 116.19029 -218.769306) (xy 116.174278 -218.818585) (xy 116.150755 -218.864752) (xy 116.120299 -218.906671)
			(xy 116.083661 -218.943309) (xy 116.041742 -218.973765) (xy 115.995575 -218.997288) (xy 115.946296 -219.0133)
			(xy 115.895119 -219.021406) (xy 115.843305 -219.021406) (xy 115.792128 -219.0133) (xy 115.742849 -218.997288)
			(xy 115.696682 -218.973765) (xy 115.654763 -218.943309) (xy 115.618125 -218.906671) (xy 115.587669 -218.864752)
			(xy 115.564146 -218.818585) (xy 115.548134 -218.769306) (xy 115.540028 -218.718129) (xy 115.53952 -218.692222)
			(xy 114.319304 -218.692222) (xy 114.318796 -218.718109) (xy 114.310697 -218.769247) (xy 114.294698 -218.818487)
			(xy 114.271192 -218.864619) (xy 114.24076 -218.906506) (xy 114.20415 -218.943116) (xy 114.162263 -218.973548)
			(xy 114.116131 -218.997054) (xy 114.066891 -219.013053) (xy 114.015753 -219.021152) (xy 113.963979 -219.021152)
			(xy 113.912841 -219.013053) (xy 113.863601 -218.997054) (xy 113.817469 -218.973548) (xy 113.775582 -218.943116)
			(xy 113.738972 -218.906506) (xy 113.70854 -218.864619) (xy 113.685034 -218.818487) (xy 113.669035 -218.769247)
			(xy 113.660936 -218.718109) (xy 113.660428 -218.692222) (xy 112.439704 -218.692222) (xy 112.439196 -218.718129)
			(xy 112.43109 -218.769306) (xy 112.415078 -218.818585) (xy 112.391555 -218.864752) (xy 112.361099 -218.906671)
			(xy 112.324461 -218.943309) (xy 112.282542 -218.973765) (xy 112.236375 -218.997288) (xy 112.187096 -219.0133)
			(xy 112.135919 -219.021406) (xy 112.084105 -219.021406) (xy 112.032928 -219.0133) (xy 111.983649 -218.997288)
			(xy 111.937482 -218.973765) (xy 111.895563 -218.943309) (xy 111.858925 -218.906671) (xy 111.828469 -218.864752)
			(xy 111.804946 -218.818585) (xy 111.788934 -218.769306) (xy 111.780828 -218.718129) (xy 111.78032 -218.692222)
			(xy 110.560104 -218.692222) (xy 110.559596 -218.718109) (xy 110.551497 -218.769247) (xy 110.535498 -218.818487)
			(xy 110.511992 -218.864619) (xy 110.48156 -218.906506) (xy 110.44495 -218.943116) (xy 110.403063 -218.973548)
			(xy 110.356931 -218.997054) (xy 110.307691 -219.013053) (xy 110.256553 -219.021152) (xy 110.204779 -219.021152)
			(xy 110.153641 -219.013053) (xy 110.104401 -218.997054) (xy 110.058269 -218.973548) (xy 110.016382 -218.943116)
			(xy 109.979772 -218.906506) (xy 109.94934 -218.864619) (xy 109.925834 -218.818487) (xy 109.909835 -218.769247)
			(xy 109.901736 -218.718109) (xy 109.901228 -218.692222) (xy 109.901766 -218.664514) (xy 109.910956 -218.609868)
			(xy 109.919516 -218.58351) (xy 109.92739 -218.561412) (xy 109.722412 -218.206574) (xy 109.699552 -218.202256)
			(xy 109.67472 -218.197133) (xy 109.626938 -218.180175) (xy 109.582316 -218.1561) (xy 109.541908 -218.125474)
			(xy 109.506667 -218.089022) (xy 109.477424 -218.047602) (xy 109.45487 -218.002192) (xy 109.439537 -217.953864)
			(xy 109.431786 -217.903757) (xy 109.431328 -217.878406) (xy 109.150404 -217.878406) (xy 109.149896 -217.904293)
			(xy 109.141797 -217.955431) (xy 109.125798 -218.004671) (xy 109.102292 -218.050803) (xy 109.07186 -218.09269)
			(xy 109.03525 -218.1293) (xy 108.993363 -218.159732) (xy 108.947231 -218.183238) (xy 108.897991 -218.199237)
			(xy 108.846853 -218.207336) (xy 108.795079 -218.207336) (xy 108.743941 -218.199237) (xy 108.694701 -218.183238)
			(xy 108.648569 -218.159732) (xy 108.606682 -218.1293) (xy 108.570072 -218.09269) (xy 108.53964 -218.050803)
			(xy 108.516134 -218.004671) (xy 108.500135 -217.955431) (xy 108.492036 -217.904293) (xy 108.491528 -217.878406)
			(xy 108.210604 -217.878406) (xy 108.210076 -217.906114) (xy 108.20088 -217.960761) (xy 108.192316 -217.987118)
			(xy 108.184442 -218.009216) (xy 108.38942 -218.364054) (xy 108.41228 -218.368372) (xy 108.4371 -218.37354)
			(xy 108.484878 -218.390497) (xy 108.529495 -218.41457) (xy 108.5699 -218.44519) (xy 108.60514 -218.481637)
			(xy 108.634384 -218.52305) (xy 108.656942 -218.568452) (xy 108.672281 -218.616773) (xy 108.680041 -218.666873)
			(xy 108.680504 -218.692222) (xy 108.679996 -218.718129) (xy 108.67189 -218.769306) (xy 108.655878 -218.818585)
			(xy 108.632355 -218.864752) (xy 108.601899 -218.906671) (xy 108.565261 -218.943309) (xy 108.523342 -218.973765)
			(xy 108.477175 -218.997288) (xy 108.427896 -219.0133) (xy 108.376719 -219.021406) (xy 108.324905 -219.021406)
			(xy 108.273728 -219.0133) (xy 108.224449 -218.997288) (xy 108.178282 -218.973765) (xy 108.136363 -218.943309)
			(xy 108.099725 -218.906671) (xy 108.069269 -218.864752) (xy 108.045746 -218.818585) (xy 108.029734 -218.769306)
			(xy 108.021628 -218.718129) (xy 108.02112 -218.692222) (xy 108.021718 -218.664505) (xy 108.031039 -218.609858)
			(xy 108.039662 -218.58351) (xy 108.047536 -218.561412) (xy 107.842558 -218.206574) (xy 107.819698 -218.202256)
			(xy 107.794899 -218.197049) (xy 107.747162 -218.180062) (xy 107.702585 -218.15597) (xy 107.66222 -218.125341)
			(xy 107.627017 -218.088897) (xy 107.597804 -218.047495) (xy 107.575271 -218.002112) (xy 107.559946 -217.953814)
			(xy 107.552192 -217.903741) (xy 107.551728 -217.878406) (xy 107.270804 -217.878406) (xy 107.270296 -217.904293)
			(xy 107.262197 -217.955431) (xy 107.246198 -218.004671) (xy 107.222692 -218.050803) (xy 107.19226 -218.09269)
			(xy 107.15565 -218.1293) (xy 107.113763 -218.159732) (xy 107.067631 -218.183238) (xy 107.018391 -218.199237)
			(xy 106.967253 -218.207336) (xy 106.915479 -218.207336) (xy 106.864341 -218.199237) (xy 106.815101 -218.183238)
			(xy 106.768969 -218.159732) (xy 106.727082 -218.1293) (xy 106.690472 -218.09269) (xy 106.66004 -218.050803)
			(xy 106.636534 -218.004671) (xy 106.620535 -217.955431) (xy 106.612436 -217.904293) (xy 106.611928 -217.878406)
			(xy 106.331004 -217.878406) (xy 106.330476 -217.906114) (xy 106.32128 -217.960761) (xy 106.312716 -217.987118)
			(xy 106.304842 -218.009216) (xy 106.50982 -218.364054) (xy 106.53268 -218.368372) (xy 106.5575 -218.37354)
			(xy 106.605278 -218.390497) (xy 106.649895 -218.41457) (xy 106.6903 -218.44519) (xy 106.72554 -218.481637)
			(xy 106.754784 -218.52305) (xy 106.777342 -218.568452) (xy 106.792681 -218.616773) (xy 106.800441 -218.666873)
			(xy 106.800904 -218.692222) (xy 106.800396 -218.718129) (xy 106.79229 -218.769306) (xy 106.776278 -218.818585)
			(xy 106.752755 -218.864752) (xy 106.722299 -218.906671) (xy 106.685661 -218.943309) (xy 106.643742 -218.973765)
			(xy 106.597575 -218.997288) (xy 106.548296 -219.0133) (xy 106.497119 -219.021406) (xy 106.445305 -219.021406)
			(xy 106.394128 -219.0133) (xy 106.344849 -218.997288) (xy 106.298682 -218.973765) (xy 106.256763 -218.943309)
			(xy 106.220125 -218.906671) (xy 106.189669 -218.864752) (xy 106.166146 -218.818585) (xy 106.150134 -218.769306)
			(xy 106.142028 -218.718129) (xy 106.14152 -218.692222) (xy 106.142118 -218.664505) (xy 106.151439 -218.609858)
			(xy 106.160062 -218.58351) (xy 106.167936 -218.561412) (xy 105.962958 -218.206574) (xy 105.940098 -218.202256)
			(xy 105.915299 -218.197049) (xy 105.867562 -218.180062) (xy 105.822985 -218.15597) (xy 105.78262 -218.125341)
			(xy 105.747417 -218.088897) (xy 105.718204 -218.047495) (xy 105.695671 -218.002112) (xy 105.680346 -217.953814)
			(xy 105.672592 -217.903741) (xy 105.672128 -217.878406) (xy 105.391204 -217.878406) (xy 105.390696 -217.904293)
			(xy 105.382597 -217.955431) (xy 105.366598 -218.004671) (xy 105.343092 -218.050803) (xy 105.31266 -218.09269)
			(xy 105.27605 -218.1293) (xy 105.234163 -218.159732) (xy 105.188031 -218.183238) (xy 105.138791 -218.199237)
			(xy 105.087653 -218.207336) (xy 105.035879 -218.207336) (xy 104.984741 -218.199237) (xy 104.935501 -218.183238)
			(xy 104.889369 -218.159732) (xy 104.847482 -218.1293) (xy 104.810872 -218.09269) (xy 104.78044 -218.050803)
			(xy 104.756934 -218.004671) (xy 104.740935 -217.955431) (xy 104.732836 -217.904293) (xy 104.732328 -217.878406)
			(xy 104.451404 -217.878406) (xy 104.450876 -217.906114) (xy 104.44168 -217.960761) (xy 104.433116 -217.987118)
			(xy 104.425242 -218.009216) (xy 104.63022 -218.364054) (xy 104.65308 -218.368372) (xy 104.6779 -218.37354)
			(xy 104.725678 -218.390497) (xy 104.770295 -218.41457) (xy 104.8107 -218.44519) (xy 104.84594 -218.481637)
			(xy 104.875184 -218.52305) (xy 104.897742 -218.568452) (xy 104.913081 -218.616773) (xy 104.920841 -218.666873)
			(xy 104.921304 -218.692222) (xy 104.920796 -218.718129) (xy 104.91269 -218.769306) (xy 104.896678 -218.818585)
			(xy 104.873155 -218.864752) (xy 104.842699 -218.906671) (xy 104.806061 -218.943309) (xy 104.764142 -218.973765)
			(xy 104.717975 -218.997288) (xy 104.668696 -219.0133) (xy 104.617519 -219.021406) (xy 104.565705 -219.021406)
			(xy 104.514528 -219.0133) (xy 104.465249 -218.997288) (xy 104.419082 -218.973765) (xy 104.377163 -218.943309)
			(xy 104.340525 -218.906671) (xy 104.310069 -218.864752) (xy 104.286546 -218.818585) (xy 104.270534 -218.769306)
			(xy 104.262428 -218.718129) (xy 104.26192 -218.692222) (xy 104.262518 -218.664505) (xy 104.271839 -218.609858)
			(xy 104.280462 -218.58351) (xy 104.288336 -218.561412) (xy 104.083358 -218.206574) (xy 104.060498 -218.202256)
			(xy 104.035699 -218.197049) (xy 103.987962 -218.180062) (xy 103.943385 -218.15597) (xy 103.90302 -218.125341)
			(xy 103.867817 -218.088897) (xy 103.838604 -218.047495) (xy 103.816071 -218.002112) (xy 103.800746 -217.953814)
			(xy 103.792992 -217.903741) (xy 103.792528 -217.878406) (xy 103.511604 -217.878406) (xy 103.511096 -217.904293)
			(xy 103.502997 -217.955431) (xy 103.486998 -218.004671) (xy 103.463492 -218.050803) (xy 103.43306 -218.09269)
			(xy 103.39645 -218.1293) (xy 103.354563 -218.159732) (xy 103.308431 -218.183238) (xy 103.259191 -218.199237)
			(xy 103.208053 -218.207336) (xy 103.156279 -218.207336) (xy 103.105141 -218.199237) (xy 103.055901 -218.183238)
			(xy 103.009769 -218.159732) (xy 102.967882 -218.1293) (xy 102.931272 -218.09269) (xy 102.90084 -218.050803)
			(xy 102.877334 -218.004671) (xy 102.861335 -217.955431) (xy 102.853236 -217.904293) (xy 102.852728 -217.878406)
			(xy 102.571804 -217.878406) (xy 102.571276 -217.906114) (xy 102.56208 -217.960761) (xy 102.553516 -217.987118)
			(xy 102.545642 -218.009216) (xy 102.75062 -218.364054) (xy 102.77348 -218.368372) (xy 102.7983 -218.37354)
			(xy 102.846078 -218.390497) (xy 102.890695 -218.41457) (xy 102.9311 -218.44519) (xy 102.96634 -218.481637)
			(xy 102.995584 -218.52305) (xy 103.018142 -218.568452) (xy 103.033481 -218.616773) (xy 103.041241 -218.666873)
			(xy 103.041704 -218.692222) (xy 103.041196 -218.718129) (xy 103.03309 -218.769306) (xy 103.017078 -218.818585)
			(xy 102.993555 -218.864752) (xy 102.963099 -218.906671) (xy 102.926461 -218.943309) (xy 102.884542 -218.973765)
			(xy 102.838375 -218.997288) (xy 102.789096 -219.0133) (xy 102.737919 -219.021406) (xy 102.686105 -219.021406)
			(xy 102.634928 -219.0133) (xy 102.585649 -218.997288) (xy 102.539482 -218.973765) (xy 102.497563 -218.943309)
			(xy 102.460925 -218.906671) (xy 102.430469 -218.864752) (xy 102.406946 -218.818585) (xy 102.390934 -218.769306)
			(xy 102.382828 -218.718129) (xy 102.38232 -218.692222) (xy 102.382918 -218.664505) (xy 102.392239 -218.609858)
			(xy 102.400862 -218.58351) (xy 102.408736 -218.561412) (xy 102.203758 -218.206574) (xy 102.180898 -218.202256)
			(xy 102.156099 -218.197049) (xy 102.108362 -218.180062) (xy 102.063785 -218.15597) (xy 102.02342 -218.125341)
			(xy 101.988217 -218.088897) (xy 101.959004 -218.047495) (xy 101.936471 -218.002112) (xy 101.921146 -217.953814)
			(xy 101.913392 -217.903741) (xy 101.912928 -217.878406) (xy 101.632004 -217.878406) (xy 101.631496 -217.904293)
			(xy 101.623397 -217.955431) (xy 101.607398 -218.004671) (xy 101.583892 -218.050803) (xy 101.55346 -218.09269)
			(xy 101.51685 -218.1293) (xy 101.474963 -218.159732) (xy 101.428831 -218.183238) (xy 101.379591 -218.199237)
			(xy 101.328453 -218.207336) (xy 101.276679 -218.207336) (xy 101.225541 -218.199237) (xy 101.176301 -218.183238)
			(xy 101.130169 -218.159732) (xy 101.088282 -218.1293) (xy 101.051672 -218.09269) (xy 101.02124 -218.050803)
			(xy 100.997734 -218.004671) (xy 100.981735 -217.955431) (xy 100.973636 -217.904293) (xy 100.973128 -217.878406)
			(xy 100.692204 -217.878406) (xy 100.691676 -217.906114) (xy 100.68248 -217.960761) (xy 100.673916 -217.987118)
			(xy 100.666042 -218.009216) (xy 100.87102 -218.364054) (xy 100.89388 -218.368372) (xy 100.9187 -218.37354)
			(xy 100.966478 -218.390497) (xy 101.011095 -218.41457) (xy 101.0515 -218.44519) (xy 101.08674 -218.481637)
			(xy 101.115984 -218.52305) (xy 101.138542 -218.568452) (xy 101.153881 -218.616773) (xy 101.161641 -218.666873)
			(xy 101.162104 -218.692222) (xy 101.161596 -218.718129) (xy 101.15349 -218.769306) (xy 101.137478 -218.818585)
			(xy 101.113955 -218.864752) (xy 101.083499 -218.906671) (xy 101.046861 -218.943309) (xy 101.004942 -218.973765)
			(xy 100.958775 -218.997288) (xy 100.909496 -219.0133) (xy 100.858319 -219.021406) (xy 100.806505 -219.021406)
			(xy 100.755328 -219.0133) (xy 100.706049 -218.997288) (xy 100.659882 -218.973765) (xy 100.617963 -218.943309)
			(xy 100.581325 -218.906671) (xy 100.550869 -218.864752) (xy 100.527346 -218.818585) (xy 100.511334 -218.769306)
			(xy 100.503228 -218.718129) (xy 100.50272 -218.692222) (xy 100.503318 -218.664505) (xy 100.512639 -218.609858)
			(xy 100.521262 -218.58351) (xy 100.529136 -218.561412) (xy 100.324158 -218.206574) (xy 100.301298 -218.202256)
			(xy 100.276499 -218.197049) (xy 100.228762 -218.180062) (xy 100.184185 -218.15597) (xy 100.14382 -218.125341)
			(xy 100.108617 -218.088897) (xy 100.079404 -218.047495) (xy 100.056871 -218.002112) (xy 100.041546 -217.953814)
			(xy 100.033792 -217.903741) (xy 100.033328 -217.878406) (xy 99.752404 -217.878406) (xy 99.751896 -217.904293)
			(xy 99.743797 -217.955431) (xy 99.727798 -218.004671) (xy 99.704292 -218.050803) (xy 99.67386 -218.09269)
			(xy 99.63725 -218.1293) (xy 99.595363 -218.159732) (xy 99.549231 -218.183238) (xy 99.499991 -218.199237)
			(xy 99.448853 -218.207336) (xy 99.397079 -218.207336) (xy 99.345941 -218.199237) (xy 99.296701 -218.183238)
			(xy 99.250569 -218.159732) (xy 99.208682 -218.1293) (xy 99.172072 -218.09269) (xy 99.14164 -218.050803)
			(xy 99.118134 -218.004671) (xy 99.102135 -217.955431) (xy 99.094036 -217.904293) (xy 99.093528 -217.878406)
			(xy 98.812604 -217.878406) (xy 98.812076 -217.906114) (xy 98.80288 -217.960761) (xy 98.794316 -217.987118)
			(xy 98.786442 -218.009216) (xy 98.99142 -218.364054) (xy 99.01428 -218.368372) (xy 99.0391 -218.37354)
			(xy 99.086878 -218.390497) (xy 99.131495 -218.41457) (xy 99.1719 -218.44519) (xy 99.20714 -218.481637)
			(xy 99.236384 -218.52305) (xy 99.258942 -218.568452) (xy 99.274281 -218.616773) (xy 99.282041 -218.666873)
			(xy 99.282504 -218.692222) (xy 99.281996 -218.718129) (xy 99.27389 -218.769306) (xy 99.257878 -218.818585)
			(xy 99.234355 -218.864752) (xy 99.203899 -218.906671) (xy 99.167261 -218.943309) (xy 99.125342 -218.973765)
			(xy 99.079175 -218.997288) (xy 99.029896 -219.0133) (xy 98.978719 -219.021406) (xy 98.926905 -219.021406)
			(xy 98.875728 -219.0133) (xy 98.826449 -218.997288) (xy 98.780282 -218.973765) (xy 98.738363 -218.943309)
			(xy 98.701725 -218.906671) (xy 98.671269 -218.864752) (xy 98.647746 -218.818585) (xy 98.631734 -218.769306)
			(xy 98.623628 -218.718129) (xy 98.62312 -218.692222) (xy 98.623718 -218.664505) (xy 98.633039 -218.609858)
			(xy 98.641662 -218.58351) (xy 98.649536 -218.561412) (xy 98.444558 -218.206574) (xy 98.421698 -218.202256)
			(xy 98.396899 -218.197049) (xy 98.349162 -218.180062) (xy 98.304585 -218.15597) (xy 98.26422 -218.125341)
			(xy 98.229017 -218.088897) (xy 98.199804 -218.047495) (xy 98.177271 -218.002112) (xy 98.161946 -217.953814)
			(xy 98.154192 -217.903741) (xy 98.153728 -217.878406) (xy 97.872804 -217.878406) (xy 97.872296 -217.904293)
			(xy 97.864197 -217.955431) (xy 97.848198 -218.004671) (xy 97.824692 -218.050803) (xy 97.79426 -218.09269)
			(xy 97.75765 -218.1293) (xy 97.715763 -218.159732) (xy 97.669631 -218.183238) (xy 97.620391 -218.199237)
			(xy 97.569253 -218.207336) (xy 97.517479 -218.207336) (xy 97.466341 -218.199237) (xy 97.417101 -218.183238)
			(xy 97.370969 -218.159732) (xy 97.329082 -218.1293) (xy 97.292472 -218.09269) (xy 97.26204 -218.050803)
			(xy 97.238534 -218.004671) (xy 97.222535 -217.955431) (xy 97.214436 -217.904293) (xy 97.213928 -217.878406)
			(xy 96.933004 -217.878406) (xy 96.932476 -217.906114) (xy 96.92328 -217.960761) (xy 96.914716 -217.987118)
			(xy 96.906842 -218.009216) (xy 97.11182 -218.364054) (xy 97.13468 -218.368372) (xy 97.1595 -218.37354)
			(xy 97.207278 -218.390497) (xy 97.251895 -218.41457) (xy 97.2923 -218.44519) (xy 97.32754 -218.481637)
			(xy 97.356784 -218.52305) (xy 97.379342 -218.568452) (xy 97.394681 -218.616773) (xy 97.402441 -218.666873)
			(xy 97.402904 -218.692222) (xy 97.402396 -218.718129) (xy 97.39429 -218.769306) (xy 97.378278 -218.818585)
			(xy 97.354755 -218.864752) (xy 97.324299 -218.906671) (xy 97.287661 -218.943309) (xy 97.245742 -218.973765)
			(xy 97.199575 -218.997288) (xy 97.150296 -219.0133) (xy 97.099119 -219.021406) (xy 97.047305 -219.021406)
			(xy 96.996128 -219.0133) (xy 96.946849 -218.997288) (xy 96.900682 -218.973765) (xy 96.858763 -218.943309)
			(xy 96.822125 -218.906671) (xy 96.791669 -218.864752) (xy 96.768146 -218.818585) (xy 96.752134 -218.769306)
			(xy 96.744028 -218.718129) (xy 96.74352 -218.692222) (xy 96.744118 -218.664505) (xy 96.753439 -218.609858)
			(xy 96.762062 -218.58351) (xy 96.769936 -218.561412) (xy 96.564958 -218.206574) (xy 96.542098 -218.202256)
			(xy 96.517299 -218.197049) (xy 96.469562 -218.180062) (xy 96.424985 -218.15597) (xy 96.38462 -218.125341)
			(xy 96.349417 -218.088897) (xy 96.320204 -218.047495) (xy 96.297671 -218.002112) (xy 96.282346 -217.953814)
			(xy 96.274592 -217.903741) (xy 96.274128 -217.878406) (xy 95.993204 -217.878406) (xy 95.992696 -217.904293)
			(xy 95.984597 -217.955431) (xy 95.968598 -218.004671) (xy 95.945092 -218.050803) (xy 95.91466 -218.09269)
			(xy 95.87805 -218.1293) (xy 95.836163 -218.159732) (xy 95.790031 -218.183238) (xy 95.740791 -218.199237)
			(xy 95.689653 -218.207336) (xy 95.637879 -218.207336) (xy 95.586741 -218.199237) (xy 95.537501 -218.183238)
			(xy 95.491369 -218.159732) (xy 95.449482 -218.1293) (xy 95.412872 -218.09269) (xy 95.38244 -218.050803)
			(xy 95.358934 -218.004671) (xy 95.342935 -217.955431) (xy 95.334836 -217.904293) (xy 95.334328 -217.878406)
			(xy 95.053404 -217.878406) (xy 95.052876 -217.906114) (xy 95.04368 -217.960761) (xy 95.035116 -217.987118)
			(xy 95.027242 -218.009216) (xy 95.23222 -218.364054) (xy 95.25508 -218.368372) (xy 95.2799 -218.37354)
			(xy 95.327678 -218.390497) (xy 95.372295 -218.41457) (xy 95.4127 -218.44519) (xy 95.44794 -218.481637)
			(xy 95.477184 -218.52305) (xy 95.499742 -218.568452) (xy 95.515081 -218.616773) (xy 95.522841 -218.666873)
			(xy 95.523304 -218.692222) (xy 95.522796 -218.718129) (xy 95.51469 -218.769306) (xy 95.498678 -218.818585)
			(xy 95.475155 -218.864752) (xy 95.444699 -218.906671) (xy 95.408061 -218.943309) (xy 95.366142 -218.973765)
			(xy 95.319975 -218.997288) (xy 95.270696 -219.0133) (xy 95.219519 -219.021406) (xy 95.167705 -219.021406)
			(xy 95.116528 -219.0133) (xy 95.067249 -218.997288) (xy 95.021082 -218.973765) (xy 94.979163 -218.943309)
			(xy 94.942525 -218.906671) (xy 94.912069 -218.864752) (xy 94.888546 -218.818585) (xy 94.872534 -218.769306)
			(xy 94.864428 -218.718129) (xy 94.86392 -218.692222) (xy 94.864518 -218.664505) (xy 94.873839 -218.609858)
			(xy 94.882462 -218.58351) (xy 94.890336 -218.561412) (xy 94.685358 -218.206574) (xy 94.662498 -218.202256)
			(xy 94.637699 -218.197049) (xy 94.589962 -218.180062) (xy 94.545385 -218.15597) (xy 94.50502 -218.125341)
			(xy 94.469817 -218.088897) (xy 94.440604 -218.047495) (xy 94.418071 -218.002112) (xy 94.402746 -217.953814)
			(xy 94.394992 -217.903741) (xy 94.394528 -217.878406) (xy 94.113604 -217.878406) (xy 94.113096 -217.904293)
			(xy 94.104997 -217.955431) (xy 94.088998 -218.004671) (xy 94.065492 -218.050803) (xy 94.03506 -218.09269)
			(xy 93.99845 -218.1293) (xy 93.956563 -218.159732) (xy 93.910431 -218.183238) (xy 93.861191 -218.199237)
			(xy 93.810053 -218.207336) (xy 93.758279 -218.207336) (xy 93.707141 -218.199237) (xy 93.657901 -218.183238)
			(xy 93.611769 -218.159732) (xy 93.569882 -218.1293) (xy 93.533272 -218.09269) (xy 93.50284 -218.050803)
			(xy 93.479334 -218.004671) (xy 93.463335 -217.955431) (xy 93.455236 -217.904293) (xy 93.454728 -217.878406)
			(xy 93.173804 -217.878406) (xy 93.173276 -217.906114) (xy 93.16408 -217.960761) (xy 93.155516 -217.987118)
			(xy 93.147642 -218.009216) (xy 93.35262 -218.364054) (xy 93.37548 -218.368372) (xy 93.4003 -218.37354)
			(xy 93.448078 -218.390497) (xy 93.492695 -218.41457) (xy 93.5331 -218.44519) (xy 93.56834 -218.481637)
			(xy 93.597584 -218.52305) (xy 93.620142 -218.568452) (xy 93.635481 -218.616773) (xy 93.643241 -218.666873)
			(xy 93.643704 -218.692222) (xy 93.643196 -218.718129) (xy 93.63509 -218.769306) (xy 93.619078 -218.818585)
			(xy 93.595555 -218.864752) (xy 93.565099 -218.906671) (xy 93.528461 -218.943309) (xy 93.486542 -218.973765)
			(xy 93.440375 -218.997288) (xy 93.391096 -219.0133) (xy 93.339919 -219.021406) (xy 93.288105 -219.021406)
			(xy 93.236928 -219.0133) (xy 93.187649 -218.997288) (xy 93.141482 -218.973765) (xy 93.099563 -218.943309)
			(xy 93.062925 -218.906671) (xy 93.032469 -218.864752) (xy 93.008946 -218.818585) (xy 92.992934 -218.769306)
			(xy 92.984828 -218.718129) (xy 92.98432 -218.692222) (xy 92.984918 -218.664505) (xy 92.994239 -218.609858)
			(xy 93.002862 -218.58351) (xy 93.010736 -218.561412) (xy 92.805758 -218.206574) (xy 92.782898 -218.202256)
			(xy 92.758099 -218.197049) (xy 92.710362 -218.180062) (xy 92.665785 -218.15597) (xy 92.62542 -218.125341)
			(xy 92.590217 -218.088897) (xy 92.561004 -218.047495) (xy 92.538471 -218.002112) (xy 92.523146 -217.953814)
			(xy 92.515392 -217.903741) (xy 92.514928 -217.878406) (xy 92.234004 -217.878406) (xy 92.233496 -217.904293)
			(xy 92.225397 -217.955431) (xy 92.209398 -218.004671) (xy 92.185892 -218.050803) (xy 92.15546 -218.09269)
			(xy 92.11885 -218.1293) (xy 92.076963 -218.159732) (xy 92.030831 -218.183238) (xy 91.981591 -218.199237)
			(xy 91.930453 -218.207336) (xy 91.878679 -218.207336) (xy 91.827541 -218.199237) (xy 91.778301 -218.183238)
			(xy 91.732169 -218.159732) (xy 91.690282 -218.1293) (xy 91.653672 -218.09269) (xy 91.62324 -218.050803)
			(xy 91.599734 -218.004671) (xy 91.583735 -217.955431) (xy 91.575636 -217.904293) (xy 91.575128 -217.878406)
			(xy 91.294204 -217.878406) (xy 91.293676 -217.906114) (xy 91.28448 -217.960761) (xy 91.275916 -217.987118)
			(xy 91.268042 -218.009216) (xy 91.47302 -218.364054) (xy 91.49588 -218.368372) (xy 91.5207 -218.37354)
			(xy 91.568478 -218.390497) (xy 91.613095 -218.41457) (xy 91.6535 -218.44519) (xy 91.68874 -218.481637)
			(xy 91.717984 -218.52305) (xy 91.740542 -218.568452) (xy 91.755881 -218.616773) (xy 91.763641 -218.666873)
			(xy 91.764104 -218.692222) (xy 91.763596 -218.718129) (xy 91.75549 -218.769306) (xy 91.739478 -218.818585)
			(xy 91.715955 -218.864752) (xy 91.685499 -218.906671) (xy 91.648861 -218.943309) (xy 91.606942 -218.973765)
			(xy 91.560775 -218.997288) (xy 91.511496 -219.0133) (xy 91.460319 -219.021406) (xy 91.408505 -219.021406)
			(xy 91.357328 -219.0133) (xy 91.308049 -218.997288) (xy 91.261882 -218.973765) (xy 91.219963 -218.943309)
			(xy 91.183325 -218.906671) (xy 91.152869 -218.864752) (xy 91.129346 -218.818585) (xy 91.113334 -218.769306)
			(xy 91.105228 -218.718129) (xy 91.10472 -218.692222) (xy 91.105318 -218.664505) (xy 91.114639 -218.609858)
			(xy 91.123262 -218.58351) (xy 91.131136 -218.561412) (xy 90.926158 -218.206574) (xy 90.903298 -218.202256)
			(xy 90.878499 -218.197049) (xy 90.830762 -218.180062) (xy 90.786185 -218.15597) (xy 90.74582 -218.125341)
			(xy 90.710617 -218.088897) (xy 90.681404 -218.047495) (xy 90.658871 -218.002112) (xy 90.643546 -217.953814)
			(xy 90.635792 -217.903741) (xy 90.635328 -217.878406) (xy 90.354404 -217.878406) (xy 90.353896 -217.904293)
			(xy 90.345797 -217.955431) (xy 90.329798 -218.004671) (xy 90.306292 -218.050803) (xy 90.27586 -218.09269)
			(xy 90.23925 -218.1293) (xy 90.197363 -218.159732) (xy 90.151231 -218.183238) (xy 90.101991 -218.199237)
			(xy 90.050853 -218.207336) (xy 89.999079 -218.207336) (xy 89.947941 -218.199237) (xy 89.898701 -218.183238)
			(xy 89.852569 -218.159732) (xy 89.810682 -218.1293) (xy 89.774072 -218.09269) (xy 89.74364 -218.050803)
			(xy 89.720134 -218.004671) (xy 89.704135 -217.955431) (xy 89.696036 -217.904293) (xy 89.695528 -217.878406)
			(xy 89.414604 -217.878406) (xy 89.414076 -217.906114) (xy 89.40488 -217.960761) (xy 89.396316 -217.987118)
			(xy 89.388442 -218.009216) (xy 89.59342 -218.364054) (xy 89.61628 -218.368372) (xy 89.6411 -218.37354)
			(xy 89.688878 -218.390497) (xy 89.733495 -218.41457) (xy 89.7739 -218.44519) (xy 89.80914 -218.481637)
			(xy 89.838384 -218.52305) (xy 89.860942 -218.568452) (xy 89.876281 -218.616773) (xy 89.884041 -218.666873)
			(xy 89.884504 -218.692222) (xy 89.883996 -218.718129) (xy 89.87589 -218.769306) (xy 89.859878 -218.818585)
			(xy 89.836355 -218.864752) (xy 89.805899 -218.906671) (xy 89.769261 -218.943309) (xy 89.727342 -218.973765)
			(xy 89.681175 -218.997288) (xy 89.631896 -219.0133) (xy 89.580719 -219.021406) (xy 89.528905 -219.021406)
			(xy 89.477728 -219.0133) (xy 89.428449 -218.997288) (xy 89.382282 -218.973765) (xy 89.340363 -218.943309)
			(xy 89.303725 -218.906671) (xy 89.273269 -218.864752) (xy 89.249746 -218.818585) (xy 89.233734 -218.769306)
			(xy 89.225628 -218.718129) (xy 89.22512 -218.692222) (xy 89.225718 -218.664505) (xy 89.235039 -218.609858)
			(xy 89.243662 -218.58351) (xy 89.251536 -218.561412) (xy 89.046558 -218.206574) (xy 89.023698 -218.202256)
			(xy 88.998899 -218.197049) (xy 88.951162 -218.180062) (xy 88.906585 -218.15597) (xy 88.86622 -218.125341)
			(xy 88.831017 -218.088897) (xy 88.801804 -218.047495) (xy 88.779271 -218.002112) (xy 88.763946 -217.953814)
			(xy 88.756192 -217.903741) (xy 88.755728 -217.878406) (xy 2.509012 -217.878406) (xy 2.509012 -221.133924)
			(xy 88.755728 -221.133924) (xy 88.756236 -221.108037) (xy 88.764335 -221.056899) (xy 88.780334 -221.007659)
			(xy 88.80384 -220.961527) (xy 88.834272 -220.91964) (xy 88.870882 -220.88303) (xy 88.912769 -220.852598)
			(xy 88.958901 -220.829092) (xy 89.008141 -220.813093) (xy 89.059279 -220.804994) (xy 89.111053 -220.804994)
			(xy 89.162191 -220.813093) (xy 89.211431 -220.829092) (xy 89.257563 -220.852598) (xy 89.29945 -220.88303)
			(xy 89.33606 -220.91964) (xy 89.366492 -220.961527) (xy 89.389998 -221.007659) (xy 89.405997 -221.056899)
			(xy 89.414096 -221.108037) (xy 89.414604 -221.133924) (xy 89.695528 -221.133924) (xy 89.69601 -221.108589)
			(xy 89.70376 -221.058515) (xy 89.71908 -221.010217) (xy 89.741611 -220.964832) (xy 89.770821 -220.923429)
			(xy 89.806022 -220.886984) (xy 89.846386 -220.856354) (xy 89.890961 -220.83226) (xy 89.938698 -220.815272)
			(xy 89.963498 -220.810074) (xy 89.986358 -220.805756) (xy 90.191336 -220.450664) (xy 90.183462 -220.42882)
			(xy 90.174829 -220.402408) (xy 90.1655 -220.347635) (xy 90.16492 -220.319854) (xy 90.165428 -220.293947)
			(xy 90.173534 -220.24277) (xy 90.189546 -220.193491) (xy 90.213069 -220.147324) (xy 90.243525 -220.105405)
			(xy 90.280163 -220.068767) (xy 90.322082 -220.038311) (xy 90.368249 -220.014788) (xy 90.417528 -219.998776)
			(xy 90.468705 -219.99067) (xy 90.520519 -219.99067) (xy 90.571696 -219.998776) (xy 90.620975 -220.014788)
			(xy 90.667142 -220.038311) (xy 90.709061 -220.068767) (xy 90.745699 -220.105405) (xy 90.776155 -220.147324)
			(xy 90.799678 -220.193491) (xy 90.81569 -220.24277) (xy 90.823796 -220.293947) (xy 90.824304 -220.319854)
			(xy 90.823828 -220.345199) (xy 90.816049 -220.395289) (xy 90.800697 -220.443599) (xy 90.778134 -220.48899)
			(xy 90.748891 -220.530396) (xy 90.713657 -220.566839) (xy 90.673262 -220.597461) (xy 90.628657 -220.621543)
			(xy 90.580893 -220.638516) (xy 90.55608 -220.643704) (xy 90.53322 -220.648022) (xy 90.328242 -221.003114)
			(xy 90.336116 -221.024958) (xy 90.34471 -221.051373) (xy 90.353897 -221.106151) (xy 90.354404 -221.133924)
			(xy 90.635328 -221.133924) (xy 90.635836 -221.108037) (xy 90.643935 -221.056899) (xy 90.659934 -221.007659)
			(xy 90.68344 -220.961527) (xy 90.713872 -220.91964) (xy 90.750482 -220.88303) (xy 90.792369 -220.852598)
			(xy 90.838501 -220.829092) (xy 90.887741 -220.813093) (xy 90.938879 -220.804994) (xy 90.990653 -220.804994)
			(xy 91.041791 -220.813093) (xy 91.091031 -220.829092) (xy 91.137163 -220.852598) (xy 91.17905 -220.88303)
			(xy 91.21566 -220.91964) (xy 91.246092 -220.961527) (xy 91.269598 -221.007659) (xy 91.285597 -221.056899)
			(xy 91.293696 -221.108037) (xy 91.294204 -221.133924) (xy 91.575128 -221.133924) (xy 91.57561 -221.108589)
			(xy 91.58336 -221.058515) (xy 91.59868 -221.010217) (xy 91.621211 -220.964832) (xy 91.650421 -220.923429)
			(xy 91.685622 -220.886984) (xy 91.725986 -220.856354) (xy 91.770561 -220.83226) (xy 91.818298 -220.815272)
			(xy 91.843098 -220.810074) (xy 91.865958 -220.805756) (xy 92.070936 -220.450664) (xy 92.063062 -220.42882)
			(xy 92.054429 -220.402408) (xy 92.0451 -220.347635) (xy 92.04452 -220.319854) (xy 92.045028 -220.293947)
			(xy 92.053134 -220.24277) (xy 92.069146 -220.193491) (xy 92.092669 -220.147324) (xy 92.123125 -220.105405)
			(xy 92.159763 -220.068767) (xy 92.201682 -220.038311) (xy 92.247849 -220.014788) (xy 92.297128 -219.998776)
			(xy 92.348305 -219.99067) (xy 92.400119 -219.99067) (xy 92.451296 -219.998776) (xy 92.500575 -220.014788)
			(xy 92.546742 -220.038311) (xy 92.588661 -220.068767) (xy 92.625299 -220.105405) (xy 92.655755 -220.147324)
			(xy 92.679278 -220.193491) (xy 92.69529 -220.24277) (xy 92.703396 -220.293947) (xy 92.703904 -220.319854)
			(xy 92.703428 -220.345199) (xy 92.695649 -220.395289) (xy 92.680297 -220.443599) (xy 92.657734 -220.48899)
			(xy 92.628491 -220.530396) (xy 92.593257 -220.566839) (xy 92.552862 -220.597461) (xy 92.508257 -220.621543)
			(xy 92.460493 -220.638516) (xy 92.43568 -220.643704) (xy 92.41282 -220.648022) (xy 92.207842 -221.003114)
			(xy 92.215716 -221.024958) (xy 92.22431 -221.051373) (xy 92.233497 -221.106151) (xy 92.234004 -221.133924)
			(xy 92.514928 -221.133924) (xy 92.515436 -221.108037) (xy 92.523535 -221.056899) (xy 92.539534 -221.007659)
			(xy 92.56304 -220.961527) (xy 92.593472 -220.91964) (xy 92.630082 -220.88303) (xy 92.671969 -220.852598)
			(xy 92.718101 -220.829092) (xy 92.767341 -220.813093) (xy 92.818479 -220.804994) (xy 92.870253 -220.804994)
			(xy 92.921391 -220.813093) (xy 92.970631 -220.829092) (xy 93.016763 -220.852598) (xy 93.05865 -220.88303)
			(xy 93.09526 -220.91964) (xy 93.125692 -220.961527) (xy 93.149198 -221.007659) (xy 93.165197 -221.056899)
			(xy 93.173296 -221.108037) (xy 93.173804 -221.133924) (xy 93.454728 -221.133924) (xy 93.45521 -221.108589)
			(xy 93.46296 -221.058515) (xy 93.47828 -221.010217) (xy 93.500811 -220.964832) (xy 93.530021 -220.923429)
			(xy 93.565222 -220.886984) (xy 93.605586 -220.856354) (xy 93.650161 -220.83226) (xy 93.697898 -220.815272)
			(xy 93.722698 -220.810074) (xy 93.745558 -220.805756) (xy 93.950536 -220.450664) (xy 93.942662 -220.42882)
			(xy 93.934029 -220.402408) (xy 93.9247 -220.347635) (xy 93.92412 -220.319854) (xy 93.924628 -220.293947)
			(xy 93.932734 -220.24277) (xy 93.948746 -220.193491) (xy 93.972269 -220.147324) (xy 94.002725 -220.105405)
			(xy 94.039363 -220.068767) (xy 94.081282 -220.038311) (xy 94.127449 -220.014788) (xy 94.176728 -219.998776)
			(xy 94.227905 -219.99067) (xy 94.279719 -219.99067) (xy 94.330896 -219.998776) (xy 94.380175 -220.014788)
			(xy 94.426342 -220.038311) (xy 94.468261 -220.068767) (xy 94.504899 -220.105405) (xy 94.535355 -220.147324)
			(xy 94.558878 -220.193491) (xy 94.57489 -220.24277) (xy 94.582996 -220.293947) (xy 94.583504 -220.319854)
			(xy 94.583028 -220.345199) (xy 94.575249 -220.395289) (xy 94.559897 -220.443599) (xy 94.537334 -220.48899)
			(xy 94.508091 -220.530396) (xy 94.472857 -220.566839) (xy 94.432462 -220.597461) (xy 94.387857 -220.621543)
			(xy 94.340093 -220.638516) (xy 94.31528 -220.643704) (xy 94.29242 -220.648022) (xy 94.087442 -221.003114)
			(xy 94.095316 -221.024958) (xy 94.10391 -221.051373) (xy 94.113097 -221.106151) (xy 94.113604 -221.133924)
			(xy 94.394528 -221.133924) (xy 94.395036 -221.108037) (xy 94.403135 -221.056899) (xy 94.419134 -221.007659)
			(xy 94.44264 -220.961527) (xy 94.473072 -220.91964) (xy 94.509682 -220.88303) (xy 94.551569 -220.852598)
			(xy 94.597701 -220.829092) (xy 94.646941 -220.813093) (xy 94.698079 -220.804994) (xy 94.749853 -220.804994)
			(xy 94.800991 -220.813093) (xy 94.850231 -220.829092) (xy 94.896363 -220.852598) (xy 94.93825 -220.88303)
			(xy 94.97486 -220.91964) (xy 95.005292 -220.961527) (xy 95.028798 -221.007659) (xy 95.044797 -221.056899)
			(xy 95.052896 -221.108037) (xy 95.053404 -221.133924) (xy 95.334328 -221.133924) (xy 95.33481 -221.108589)
			(xy 95.34256 -221.058515) (xy 95.35788 -221.010217) (xy 95.380411 -220.964832) (xy 95.409621 -220.923429)
			(xy 95.444822 -220.886984) (xy 95.485186 -220.856354) (xy 95.529761 -220.83226) (xy 95.577498 -220.815272)
			(xy 95.602298 -220.810074) (xy 95.625158 -220.805756) (xy 95.830136 -220.450664) (xy 95.822262 -220.42882)
			(xy 95.813629 -220.402408) (xy 95.8043 -220.347635) (xy 95.80372 -220.319854) (xy 95.804228 -220.293947)
			(xy 95.812334 -220.24277) (xy 95.828346 -220.193491) (xy 95.851869 -220.147324) (xy 95.882325 -220.105405)
			(xy 95.918963 -220.068767) (xy 95.960882 -220.038311) (xy 96.007049 -220.014788) (xy 96.056328 -219.998776)
			(xy 96.107505 -219.99067) (xy 96.159319 -219.99067) (xy 96.210496 -219.998776) (xy 96.259775 -220.014788)
			(xy 96.305942 -220.038311) (xy 96.347861 -220.068767) (xy 96.384499 -220.105405) (xy 96.414955 -220.147324)
			(xy 96.438478 -220.193491) (xy 96.45449 -220.24277) (xy 96.462596 -220.293947) (xy 96.463104 -220.319854)
			(xy 96.462628 -220.345199) (xy 96.454849 -220.395289) (xy 96.439497 -220.443599) (xy 96.416934 -220.48899)
			(xy 96.387691 -220.530396) (xy 96.352457 -220.566839) (xy 96.312062 -220.597461) (xy 96.267457 -220.621543)
			(xy 96.219693 -220.638516) (xy 96.19488 -220.643704) (xy 96.17202 -220.648022) (xy 95.967042 -221.003114)
			(xy 95.974916 -221.024958) (xy 95.98351 -221.051373) (xy 95.992697 -221.106151) (xy 95.993204 -221.133924)
			(xy 96.274128 -221.133924) (xy 96.274636 -221.108037) (xy 96.282735 -221.056899) (xy 96.298734 -221.007659)
			(xy 96.32224 -220.961527) (xy 96.352672 -220.91964) (xy 96.389282 -220.88303) (xy 96.431169 -220.852598)
			(xy 96.477301 -220.829092) (xy 96.526541 -220.813093) (xy 96.577679 -220.804994) (xy 96.629453 -220.804994)
			(xy 96.680591 -220.813093) (xy 96.729831 -220.829092) (xy 96.775963 -220.852598) (xy 96.81785 -220.88303)
			(xy 96.85446 -220.91964) (xy 96.884892 -220.961527) (xy 96.908398 -221.007659) (xy 96.924397 -221.056899)
			(xy 96.932496 -221.108037) (xy 96.933004 -221.133924) (xy 97.213928 -221.133924) (xy 97.21441 -221.108589)
			(xy 97.22216 -221.058515) (xy 97.23748 -221.010217) (xy 97.260011 -220.964832) (xy 97.289221 -220.923429)
			(xy 97.324422 -220.886984) (xy 97.364786 -220.856354) (xy 97.409361 -220.83226) (xy 97.457098 -220.815272)
			(xy 97.481898 -220.810074) (xy 97.504758 -220.805756) (xy 97.709736 -220.450664) (xy 97.701862 -220.42882)
			(xy 97.693229 -220.402408) (xy 97.6839 -220.347635) (xy 97.68332 -220.319854) (xy 97.683828 -220.293947)
			(xy 97.691934 -220.24277) (xy 97.707946 -220.193491) (xy 97.731469 -220.147324) (xy 97.761925 -220.105405)
			(xy 97.798563 -220.068767) (xy 97.840482 -220.038311) (xy 97.886649 -220.014788) (xy 97.935928 -219.998776)
			(xy 97.987105 -219.99067) (xy 98.038919 -219.99067) (xy 98.090096 -219.998776) (xy 98.139375 -220.014788)
			(xy 98.185542 -220.038311) (xy 98.227461 -220.068767) (xy 98.264099 -220.105405) (xy 98.294555 -220.147324)
			(xy 98.318078 -220.193491) (xy 98.33409 -220.24277) (xy 98.342196 -220.293947) (xy 98.342704 -220.319854)
			(xy 98.342228 -220.345199) (xy 98.334449 -220.395289) (xy 98.319097 -220.443599) (xy 98.296534 -220.48899)
			(xy 98.267291 -220.530396) (xy 98.232057 -220.566839) (xy 98.191662 -220.597461) (xy 98.147057 -220.621543)
			(xy 98.099293 -220.638516) (xy 98.07448 -220.643704) (xy 98.05162 -220.648022) (xy 97.846642 -221.003114)
			(xy 97.854516 -221.024958) (xy 97.86311 -221.051373) (xy 97.872297 -221.106151) (xy 97.872804 -221.133924)
			(xy 98.153728 -221.133924) (xy 98.154236 -221.108037) (xy 98.162335 -221.056899) (xy 98.178334 -221.007659)
			(xy 98.20184 -220.961527) (xy 98.232272 -220.91964) (xy 98.268882 -220.88303) (xy 98.310769 -220.852598)
			(xy 98.356901 -220.829092) (xy 98.406141 -220.813093) (xy 98.457279 -220.804994) (xy 98.509053 -220.804994)
			(xy 98.560191 -220.813093) (xy 98.609431 -220.829092) (xy 98.655563 -220.852598) (xy 98.69745 -220.88303)
			(xy 98.73406 -220.91964) (xy 98.764492 -220.961527) (xy 98.787998 -221.007659) (xy 98.803997 -221.056899)
			(xy 98.812096 -221.108037) (xy 98.812604 -221.133924) (xy 99.093528 -221.133924) (xy 99.09401 -221.108589)
			(xy 99.10176 -221.058515) (xy 99.11708 -221.010217) (xy 99.139611 -220.964832) (xy 99.168821 -220.923429)
			(xy 99.204022 -220.886984) (xy 99.244386 -220.856354) (xy 99.288961 -220.83226) (xy 99.336698 -220.815272)
			(xy 99.361498 -220.810074) (xy 99.384358 -220.805756) (xy 99.589336 -220.450664) (xy 99.581462 -220.42882)
			(xy 99.572829 -220.402408) (xy 99.5635 -220.347635) (xy 99.56292 -220.319854) (xy 99.563428 -220.293947)
			(xy 99.571534 -220.24277) (xy 99.587546 -220.193491) (xy 99.611069 -220.147324) (xy 99.641525 -220.105405)
			(xy 99.678163 -220.068767) (xy 99.720082 -220.038311) (xy 99.766249 -220.014788) (xy 99.815528 -219.998776)
			(xy 99.866705 -219.99067) (xy 99.918519 -219.99067) (xy 99.969696 -219.998776) (xy 100.018975 -220.014788)
			(xy 100.065142 -220.038311) (xy 100.107061 -220.068767) (xy 100.143699 -220.105405) (xy 100.174155 -220.147324)
			(xy 100.197678 -220.193491) (xy 100.21369 -220.24277) (xy 100.221796 -220.293947) (xy 100.222304 -220.319854)
			(xy 100.221828 -220.345199) (xy 100.214049 -220.395289) (xy 100.198697 -220.443599) (xy 100.176134 -220.48899)
			(xy 100.146891 -220.530396) (xy 100.111657 -220.566839) (xy 100.071262 -220.597461) (xy 100.026657 -220.621543)
			(xy 99.978893 -220.638516) (xy 99.95408 -220.643704) (xy 99.93122 -220.648022) (xy 99.726242 -221.003114)
			(xy 99.734116 -221.024958) (xy 99.74271 -221.051373) (xy 99.751897 -221.106151) (xy 99.752404 -221.133924)
			(xy 100.033328 -221.133924) (xy 100.033836 -221.108037) (xy 100.041935 -221.056899) (xy 100.057934 -221.007659)
			(xy 100.08144 -220.961527) (xy 100.111872 -220.91964) (xy 100.148482 -220.88303) (xy 100.190369 -220.852598)
			(xy 100.236501 -220.829092) (xy 100.285741 -220.813093) (xy 100.336879 -220.804994) (xy 100.388653 -220.804994)
			(xy 100.439791 -220.813093) (xy 100.489031 -220.829092) (xy 100.535163 -220.852598) (xy 100.57705 -220.88303)
			(xy 100.61366 -220.91964) (xy 100.644092 -220.961527) (xy 100.667598 -221.007659) (xy 100.683597 -221.056899)
			(xy 100.691696 -221.108037) (xy 100.692204 -221.133924) (xy 100.973128 -221.133924) (xy 100.97361 -221.108589)
			(xy 100.98136 -221.058515) (xy 100.99668 -221.010217) (xy 101.019211 -220.964832) (xy 101.048421 -220.923429)
			(xy 101.083622 -220.886984) (xy 101.123986 -220.856354) (xy 101.168561 -220.83226) (xy 101.216298 -220.815272)
			(xy 101.241098 -220.810074) (xy 101.263958 -220.805756) (xy 101.468936 -220.450664) (xy 101.461062 -220.42882)
			(xy 101.452429 -220.402408) (xy 101.4431 -220.347635) (xy 101.44252 -220.319854) (xy 101.443028 -220.293947)
			(xy 101.451134 -220.24277) (xy 101.467146 -220.193491) (xy 101.490669 -220.147324) (xy 101.521125 -220.105405)
			(xy 101.557763 -220.068767) (xy 101.599682 -220.038311) (xy 101.645849 -220.014788) (xy 101.695128 -219.998776)
			(xy 101.746305 -219.99067) (xy 101.798119 -219.99067) (xy 101.849296 -219.998776) (xy 101.898575 -220.014788)
			(xy 101.944742 -220.038311) (xy 101.986661 -220.068767) (xy 102.023299 -220.105405) (xy 102.053755 -220.147324)
			(xy 102.077278 -220.193491) (xy 102.09329 -220.24277) (xy 102.101396 -220.293947) (xy 102.101904 -220.319854)
			(xy 102.101428 -220.345199) (xy 102.093649 -220.395289) (xy 102.078297 -220.443599) (xy 102.055734 -220.48899)
			(xy 102.026491 -220.530396) (xy 101.991257 -220.566839) (xy 101.950862 -220.597461) (xy 101.906257 -220.621543)
			(xy 101.858493 -220.638516) (xy 101.83368 -220.643704) (xy 101.81082 -220.648022) (xy 101.605842 -221.003114)
			(xy 101.613716 -221.024958) (xy 101.62231 -221.051373) (xy 101.631497 -221.106151) (xy 101.632004 -221.133924)
			(xy 101.912928 -221.133924) (xy 101.913436 -221.108037) (xy 101.921535 -221.056899) (xy 101.937534 -221.007659)
			(xy 101.96104 -220.961527) (xy 101.991472 -220.91964) (xy 102.028082 -220.88303) (xy 102.069969 -220.852598)
			(xy 102.116101 -220.829092) (xy 102.165341 -220.813093) (xy 102.216479 -220.804994) (xy 102.268253 -220.804994)
			(xy 102.319391 -220.813093) (xy 102.368631 -220.829092) (xy 102.414763 -220.852598) (xy 102.45665 -220.88303)
			(xy 102.49326 -220.91964) (xy 102.523692 -220.961527) (xy 102.547198 -221.007659) (xy 102.563197 -221.056899)
			(xy 102.571296 -221.108037) (xy 102.571804 -221.133924) (xy 102.852728 -221.133924) (xy 102.85321 -221.108589)
			(xy 102.86096 -221.058515) (xy 102.87628 -221.010217) (xy 102.898811 -220.964832) (xy 102.928021 -220.923429)
			(xy 102.963222 -220.886984) (xy 103.003586 -220.856354) (xy 103.048161 -220.83226) (xy 103.095898 -220.815272)
			(xy 103.120698 -220.810074) (xy 103.143558 -220.805756) (xy 103.348536 -220.450664) (xy 103.340662 -220.42882)
			(xy 103.332029 -220.402408) (xy 103.3227 -220.347635) (xy 103.32212 -220.319854) (xy 103.322628 -220.293947)
			(xy 103.330734 -220.24277) (xy 103.346746 -220.193491) (xy 103.370269 -220.147324) (xy 103.400725 -220.105405)
			(xy 103.437363 -220.068767) (xy 103.479282 -220.038311) (xy 103.525449 -220.014788) (xy 103.574728 -219.998776)
			(xy 103.625905 -219.99067) (xy 103.677719 -219.99067) (xy 103.728896 -219.998776) (xy 103.778175 -220.014788)
			(xy 103.824342 -220.038311) (xy 103.866261 -220.068767) (xy 103.902899 -220.105405) (xy 103.933355 -220.147324)
			(xy 103.956878 -220.193491) (xy 103.97289 -220.24277) (xy 103.980996 -220.293947) (xy 103.981504 -220.319854)
			(xy 105.20172 -220.319854) (xy 105.202228 -220.293947) (xy 105.210334 -220.24277) (xy 105.226346 -220.193491)
			(xy 105.249869 -220.147324) (xy 105.280325 -220.105405) (xy 105.316963 -220.068767) (xy 105.358882 -220.038311)
			(xy 105.405049 -220.014788) (xy 105.454328 -219.998776) (xy 105.505505 -219.99067) (xy 105.557319 -219.99067)
			(xy 105.608496 -219.998776) (xy 105.657775 -220.014788) (xy 105.703942 -220.038311) (xy 105.745861 -220.068767)
			(xy 105.782499 -220.105405) (xy 105.812955 -220.147324) (xy 105.836478 -220.193491) (xy 105.85249 -220.24277)
			(xy 105.860596 -220.293947) (xy 105.861104 -220.319854) (xy 107.08132 -220.319854) (xy 107.081828 -220.293947)
			(xy 107.089934 -220.24277) (xy 107.105946 -220.193491) (xy 107.129469 -220.147324) (xy 107.159925 -220.105405)
			(xy 107.196563 -220.068767) (xy 107.238482 -220.038311) (xy 107.284649 -220.014788) (xy 107.333928 -219.998776)
			(xy 107.385105 -219.99067) (xy 107.436919 -219.99067) (xy 107.488096 -219.998776) (xy 107.537375 -220.014788)
			(xy 107.583542 -220.038311) (xy 107.625461 -220.068767) (xy 107.662099 -220.105405) (xy 107.692555 -220.147324)
			(xy 107.716078 -220.193491) (xy 107.73209 -220.24277) (xy 107.740196 -220.293947) (xy 107.740704 -220.319854)
			(xy 108.96092 -220.319854) (xy 108.961428 -220.293947) (xy 108.969534 -220.24277) (xy 108.985546 -220.193491)
			(xy 109.009069 -220.147324) (xy 109.039525 -220.105405) (xy 109.076163 -220.068767) (xy 109.118082 -220.038311)
			(xy 109.164249 -220.014788) (xy 109.213528 -219.998776) (xy 109.264705 -219.99067) (xy 109.316519 -219.99067)
			(xy 109.367696 -219.998776) (xy 109.416975 -220.014788) (xy 109.463142 -220.038311) (xy 109.505061 -220.068767)
			(xy 109.541699 -220.105405) (xy 109.572155 -220.147324) (xy 109.595678 -220.193491) (xy 109.61169 -220.24277)
			(xy 109.619796 -220.293947) (xy 109.620304 -220.319854) (xy 110.84052 -220.319854) (xy 110.841028 -220.293947)
			(xy 110.849134 -220.24277) (xy 110.865146 -220.193491) (xy 110.888669 -220.147324) (xy 110.919125 -220.105405)
			(xy 110.955763 -220.068767) (xy 110.997682 -220.038311) (xy 111.043849 -220.014788) (xy 111.093128 -219.998776)
			(xy 111.144305 -219.99067) (xy 111.196119 -219.99067) (xy 111.247296 -219.998776) (xy 111.296575 -220.014788)
			(xy 111.342742 -220.038311) (xy 111.384661 -220.068767) (xy 111.421299 -220.105405) (xy 111.451755 -220.147324)
			(xy 111.475278 -220.193491) (xy 111.49129 -220.24277) (xy 111.499396 -220.293947) (xy 111.499904 -220.319854)
			(xy 112.72012 -220.319854) (xy 112.720628 -220.293947) (xy 112.728734 -220.24277) (xy 112.744746 -220.193491)
			(xy 112.768269 -220.147324) (xy 112.798725 -220.105405) (xy 112.835363 -220.068767) (xy 112.877282 -220.038311)
			(xy 112.923449 -220.014788) (xy 112.972728 -219.998776) (xy 113.023905 -219.99067) (xy 113.075719 -219.99067)
			(xy 113.126896 -219.998776) (xy 113.176175 -220.014788) (xy 113.222342 -220.038311) (xy 113.264261 -220.068767)
			(xy 113.300899 -220.105405) (xy 113.331355 -220.147324) (xy 113.354878 -220.193491) (xy 113.37089 -220.24277)
			(xy 113.378996 -220.293947) (xy 113.379504 -220.319854) (xy 114.59972 -220.319854) (xy 114.600228 -220.293947)
			(xy 114.608334 -220.24277) (xy 114.624346 -220.193491) (xy 114.647869 -220.147324) (xy 114.678325 -220.105405)
			(xy 114.714963 -220.068767) (xy 114.756882 -220.038311) (xy 114.803049 -220.014788) (xy 114.852328 -219.998776)
			(xy 114.903505 -219.99067) (xy 114.955319 -219.99067) (xy 115.006496 -219.998776) (xy 115.055775 -220.014788)
			(xy 115.101942 -220.038311) (xy 115.143861 -220.068767) (xy 115.180499 -220.105405) (xy 115.210955 -220.147324)
			(xy 115.234478 -220.193491) (xy 115.25049 -220.24277) (xy 115.258596 -220.293947) (xy 115.259104 -220.319854)
			(xy 116.47932 -220.319854) (xy 116.479828 -220.293947) (xy 116.487934 -220.24277) (xy 116.503946 -220.193491)
			(xy 116.527469 -220.147324) (xy 116.557925 -220.105405) (xy 116.594563 -220.068767) (xy 116.636482 -220.038311)
			(xy 116.682649 -220.014788) (xy 116.731928 -219.998776) (xy 116.783105 -219.99067) (xy 116.834919 -219.99067)
			(xy 116.886096 -219.998776) (xy 116.935375 -220.014788) (xy 116.981542 -220.038311) (xy 117.023461 -220.068767)
			(xy 117.060099 -220.105405) (xy 117.090555 -220.147324) (xy 117.114078 -220.193491) (xy 117.13009 -220.24277)
			(xy 117.138196 -220.293947) (xy 117.138704 -220.319854) (xy 118.35892 -220.319854) (xy 118.359428 -220.293947)
			(xy 118.367534 -220.24277) (xy 118.383546 -220.193491) (xy 118.407069 -220.147324) (xy 118.437525 -220.105405)
			(xy 118.474163 -220.068767) (xy 118.516082 -220.038311) (xy 118.562249 -220.014788) (xy 118.611528 -219.998776)
			(xy 118.662705 -219.99067) (xy 118.714519 -219.99067) (xy 118.765696 -219.998776) (xy 118.814975 -220.014788)
			(xy 118.861142 -220.038311) (xy 118.903061 -220.068767) (xy 118.939699 -220.105405) (xy 118.970155 -220.147324)
			(xy 118.993678 -220.193491) (xy 119.00969 -220.24277) (xy 119.017796 -220.293947) (xy 119.018304 -220.319854)
			(xy 120.23852 -220.319854) (xy 120.239028 -220.293947) (xy 120.247134 -220.24277) (xy 120.263146 -220.193491)
			(xy 120.286669 -220.147324) (xy 120.317125 -220.105405) (xy 120.353763 -220.068767) (xy 120.395682 -220.038311)
			(xy 120.441849 -220.014788) (xy 120.491128 -219.998776) (xy 120.542305 -219.99067) (xy 120.594119 -219.99067)
			(xy 120.645296 -219.998776) (xy 120.694575 -220.014788) (xy 120.740742 -220.038311) (xy 120.782661 -220.068767)
			(xy 120.819299 -220.105405) (xy 120.849755 -220.147324) (xy 120.873278 -220.193491) (xy 120.88929 -220.24277)
			(xy 120.897396 -220.293947) (xy 120.897904 -220.319854) (xy 122.11812 -220.319854) (xy 122.118628 -220.293947)
			(xy 122.126734 -220.24277) (xy 122.142746 -220.193491) (xy 122.166269 -220.147324) (xy 122.196725 -220.105405)
			(xy 122.233363 -220.068767) (xy 122.275282 -220.038311) (xy 122.321449 -220.014788) (xy 122.370728 -219.998776)
			(xy 122.421905 -219.99067) (xy 122.473719 -219.99067) (xy 122.524896 -219.998776) (xy 122.574175 -220.014788)
			(xy 122.620342 -220.038311) (xy 122.662261 -220.068767) (xy 122.698899 -220.105405) (xy 122.729355 -220.147324)
			(xy 122.752878 -220.193491) (xy 122.76889 -220.24277) (xy 122.776996 -220.293947) (xy 122.777504 -220.319854)
			(xy 123.99772 -220.319854) (xy 123.998228 -220.293947) (xy 124.006334 -220.24277) (xy 124.022346 -220.193491)
			(xy 124.045869 -220.147324) (xy 124.076325 -220.105405) (xy 124.112963 -220.068767) (xy 124.154882 -220.038311)
			(xy 124.201049 -220.014788) (xy 124.250328 -219.998776) (xy 124.301505 -219.99067) (xy 124.353319 -219.99067)
			(xy 124.404496 -219.998776) (xy 124.453775 -220.014788) (xy 124.499942 -220.038311) (xy 124.541861 -220.068767)
			(xy 124.578499 -220.105405) (xy 124.608955 -220.147324) (xy 124.632478 -220.193491) (xy 124.64849 -220.24277)
			(xy 124.656596 -220.293947) (xy 124.657104 -220.319854) (xy 125.87732 -220.319854) (xy 125.877828 -220.293947)
			(xy 125.885934 -220.24277) (xy 125.901946 -220.193491) (xy 125.925469 -220.147324) (xy 125.955925 -220.105405)
			(xy 125.992563 -220.068767) (xy 126.034482 -220.038311) (xy 126.080649 -220.014788) (xy 126.129928 -219.998776)
			(xy 126.181105 -219.99067) (xy 126.232919 -219.99067) (xy 126.284096 -219.998776) (xy 126.333375 -220.014788)
			(xy 126.379542 -220.038311) (xy 126.421461 -220.068767) (xy 126.458099 -220.105405) (xy 126.488555 -220.147324)
			(xy 126.512078 -220.193491) (xy 126.52809 -220.24277) (xy 126.536196 -220.293947) (xy 126.536704 -220.319854)
			(xy 127.75692 -220.319854) (xy 127.757428 -220.293947) (xy 127.765534 -220.24277) (xy 127.781546 -220.193491)
			(xy 127.805069 -220.147324) (xy 127.835525 -220.105405) (xy 127.872163 -220.068767) (xy 127.914082 -220.038311)
			(xy 127.960249 -220.014788) (xy 128.009528 -219.998776) (xy 128.060705 -219.99067) (xy 128.112519 -219.99067)
			(xy 128.163696 -219.998776) (xy 128.212975 -220.014788) (xy 128.259142 -220.038311) (xy 128.301061 -220.068767)
			(xy 128.337699 -220.105405) (xy 128.368155 -220.147324) (xy 128.391678 -220.193491) (xy 128.40769 -220.24277)
			(xy 128.415796 -220.293947) (xy 128.416304 -220.319854) (xy 129.63652 -220.319854) (xy 129.637028 -220.293947)
			(xy 129.645134 -220.24277) (xy 129.661146 -220.193491) (xy 129.684669 -220.147324) (xy 129.715125 -220.105405)
			(xy 129.751763 -220.068767) (xy 129.793682 -220.038311) (xy 129.839849 -220.014788) (xy 129.889128 -219.998776)
			(xy 129.940305 -219.99067) (xy 129.992119 -219.99067) (xy 130.043296 -219.998776) (xy 130.092575 -220.014788)
			(xy 130.138742 -220.038311) (xy 130.180661 -220.068767) (xy 130.217299 -220.105405) (xy 130.247755 -220.147324)
			(xy 130.271278 -220.193491) (xy 130.28729 -220.24277) (xy 130.295396 -220.293947) (xy 130.295904 -220.319854)
			(xy 131.51612 -220.319854) (xy 131.516628 -220.293947) (xy 131.524734 -220.24277) (xy 131.540746 -220.193491)
			(xy 131.564269 -220.147324) (xy 131.594725 -220.105405) (xy 131.631363 -220.068767) (xy 131.673282 -220.038311)
			(xy 131.719449 -220.014788) (xy 131.768728 -219.998776) (xy 131.819905 -219.99067) (xy 131.871719 -219.99067)
			(xy 131.922896 -219.998776) (xy 131.972175 -220.014788) (xy 132.018342 -220.038311) (xy 132.060261 -220.068767)
			(xy 132.096899 -220.105405) (xy 132.127355 -220.147324) (xy 132.150878 -220.193491) (xy 132.16689 -220.24277)
			(xy 132.174996 -220.293947) (xy 132.175504 -220.319854) (xy 133.396228 -220.319854) (xy 133.396736 -220.293967)
			(xy 133.404835 -220.242829) (xy 133.420834 -220.193589) (xy 133.44434 -220.147457) (xy 133.474772 -220.10557)
			(xy 133.511382 -220.06896) (xy 133.553269 -220.038528) (xy 133.599401 -220.015022) (xy 133.648641 -219.999023)
			(xy 133.699779 -219.990924) (xy 133.751553 -219.990924) (xy 133.802691 -219.999023) (xy 133.851931 -220.015022)
			(xy 133.898063 -220.038528) (xy 133.93995 -220.06896) (xy 133.97656 -220.10557) (xy 134.006992 -220.147457)
			(xy 134.030498 -220.193589) (xy 134.046497 -220.242829) (xy 134.054596 -220.293967) (xy 134.055104 -220.319854)
			(xy 134.054563 -220.347562) (xy 134.045375 -220.402208) (xy 134.036816 -220.428566) (xy 134.029196 -220.450664)
			(xy 134.234174 -220.805756) (xy 134.257034 -220.810074) (xy 134.281845 -220.815229) (xy 134.329584 -220.832223)
			(xy 134.374162 -220.856322) (xy 134.414527 -220.886957) (xy 134.44973 -220.923408) (xy 134.47894 -220.964816)
			(xy 134.501472 -221.010206) (xy 134.516792 -221.058509) (xy 134.524542 -221.108587) (xy 134.525004 -221.133924)
			(xy 336.695796 -221.133924) (xy 336.696304 -221.108037) (xy 336.704403 -221.056899) (xy 336.720402 -221.007659)
			(xy 336.743908 -220.961527) (xy 336.77434 -220.91964) (xy 336.81095 -220.88303) (xy 336.852837 -220.852598)
			(xy 336.898969 -220.829092) (xy 336.948209 -220.813093) (xy 336.999347 -220.804994) (xy 337.051121 -220.804994)
			(xy 337.102259 -220.813093) (xy 337.151499 -220.829092) (xy 337.197631 -220.852598) (xy 337.239518 -220.88303)
			(xy 337.276128 -220.91964) (xy 337.30656 -220.961527) (xy 337.330066 -221.007659) (xy 337.346065 -221.056899)
			(xy 337.354164 -221.108037) (xy 337.354672 -221.133924) (xy 337.635596 -221.133924) (xy 337.636104 -221.10859)
			(xy 337.643853 -221.058519) (xy 337.659172 -221.010223) (xy 337.6817 -220.96484) (xy 337.710906 -220.923438)
			(xy 337.746104 -220.886992) (xy 337.786463 -220.856361) (xy 337.831034 -220.832266) (xy 337.878767 -220.815274)
			(xy 337.903566 -220.810074) (xy 337.926426 -220.805756) (xy 338.131404 -220.450664) (xy 338.12353 -220.42882)
			(xy 338.114896 -220.402408) (xy 338.105568 -220.347635) (xy 338.104988 -220.319854) (xy 338.105496 -220.293947)
			(xy 338.113602 -220.24277) (xy 338.129614 -220.193491) (xy 338.153137 -220.147324) (xy 338.183593 -220.105405)
			(xy 338.220231 -220.068767) (xy 338.26215 -220.038311) (xy 338.308317 -220.014788) (xy 338.357596 -219.998776)
			(xy 338.408773 -219.99067) (xy 338.460587 -219.99067) (xy 338.511764 -219.998776) (xy 338.561043 -220.014788)
			(xy 338.60721 -220.038311) (xy 338.649129 -220.068767) (xy 338.685767 -220.105405) (xy 338.716223 -220.147324)
			(xy 338.739746 -220.193491) (xy 338.755758 -220.24277) (xy 338.763864 -220.293947) (xy 338.764372 -220.319854)
			(xy 338.763922 -220.3452) (xy 338.756142 -220.395293) (xy 338.740788 -220.443604) (xy 338.718222 -220.488998)
			(xy 338.688976 -220.530404) (xy 338.653739 -220.566847) (xy 338.61334 -220.597469) (xy 338.568731 -220.621548)
			(xy 338.520963 -220.638518) (xy 338.496148 -220.643704) (xy 338.473288 -220.648022) (xy 338.26831 -221.003114)
			(xy 338.276184 -221.024958) (xy 338.284777 -221.051373) (xy 338.293965 -221.106151) (xy 338.294472 -221.133924)
			(xy 338.575396 -221.133924) (xy 338.575904 -221.108037) (xy 338.584003 -221.056899) (xy 338.600002 -221.007659)
			(xy 338.623508 -220.961527) (xy 338.65394 -220.91964) (xy 338.69055 -220.88303) (xy 338.732437 -220.852598)
			(xy 338.778569 -220.829092) (xy 338.827809 -220.813093) (xy 338.878947 -220.804994) (xy 338.930721 -220.804994)
			(xy 338.981859 -220.813093) (xy 339.031099 -220.829092) (xy 339.077231 -220.852598) (xy 339.119118 -220.88303)
			(xy 339.155728 -220.91964) (xy 339.18616 -220.961527) (xy 339.209666 -221.007659) (xy 339.225665 -221.056899)
			(xy 339.233764 -221.108037) (xy 339.234272 -221.133924) (xy 339.515196 -221.133924) (xy 339.515704 -221.10859)
			(xy 339.523453 -221.058519) (xy 339.538772 -221.010223) (xy 339.5613 -220.96484) (xy 339.590506 -220.923438)
			(xy 339.625704 -220.886992) (xy 339.666063 -220.856361) (xy 339.710634 -220.832266) (xy 339.758367 -220.815274)
			(xy 339.783166 -220.810074) (xy 339.806026 -220.805756) (xy 340.011004 -220.450664) (xy 340.00313 -220.42882)
			(xy 339.994496 -220.402408) (xy 339.985168 -220.347635) (xy 339.984588 -220.319854) (xy 339.985096 -220.293947)
			(xy 339.993202 -220.24277) (xy 340.009214 -220.193491) (xy 340.032737 -220.147324) (xy 340.063193 -220.105405)
			(xy 340.099831 -220.068767) (xy 340.14175 -220.038311) (xy 340.187917 -220.014788) (xy 340.237196 -219.998776)
			(xy 340.288373 -219.99067) (xy 340.340187 -219.99067) (xy 340.391364 -219.998776) (xy 340.440643 -220.014788)
			(xy 340.48681 -220.038311) (xy 340.528729 -220.068767) (xy 340.565367 -220.105405) (xy 340.595823 -220.147324)
			(xy 340.619346 -220.193491) (xy 340.635358 -220.24277) (xy 340.643464 -220.293947) (xy 340.643972 -220.319854)
			(xy 340.643522 -220.3452) (xy 340.635742 -220.395293) (xy 340.620388 -220.443604) (xy 340.597822 -220.488998)
			(xy 340.568576 -220.530404) (xy 340.533339 -220.566847) (xy 340.49294 -220.597469) (xy 340.448331 -220.621548)
			(xy 340.400563 -220.638518) (xy 340.375748 -220.643704) (xy 340.352888 -220.648022) (xy 340.14791 -221.003114)
			(xy 340.155784 -221.024958) (xy 340.164377 -221.051373) (xy 340.173565 -221.106151) (xy 340.174072 -221.133924)
			(xy 340.454996 -221.133924) (xy 340.455504 -221.108037) (xy 340.463603 -221.056899) (xy 340.479602 -221.007659)
			(xy 340.503108 -220.961527) (xy 340.53354 -220.91964) (xy 340.57015 -220.88303) (xy 340.612037 -220.852598)
			(xy 340.658169 -220.829092) (xy 340.707409 -220.813093) (xy 340.758547 -220.804994) (xy 340.810321 -220.804994)
			(xy 340.861459 -220.813093) (xy 340.910699 -220.829092) (xy 340.956831 -220.852598) (xy 340.998718 -220.88303)
			(xy 341.035328 -220.91964) (xy 341.06576 -220.961527) (xy 341.089266 -221.007659) (xy 341.105265 -221.056899)
			(xy 341.113364 -221.108037) (xy 341.113872 -221.133924) (xy 341.394796 -221.133924) (xy 341.395304 -221.10859)
			(xy 341.403053 -221.058519) (xy 341.418372 -221.010223) (xy 341.4409 -220.96484) (xy 341.470106 -220.923438)
			(xy 341.505304 -220.886992) (xy 341.545663 -220.856361) (xy 341.590234 -220.832266) (xy 341.637967 -220.815274)
			(xy 341.662766 -220.810074) (xy 341.685626 -220.805756) (xy 341.890604 -220.450664) (xy 341.88273 -220.42882)
			(xy 341.874096 -220.402408) (xy 341.864768 -220.347635) (xy 341.864188 -220.319854) (xy 341.864696 -220.293947)
			(xy 341.872802 -220.24277) (xy 341.888814 -220.193491) (xy 341.912337 -220.147324) (xy 341.942793 -220.105405)
			(xy 341.979431 -220.068767) (xy 342.02135 -220.038311) (xy 342.067517 -220.014788) (xy 342.116796 -219.998776)
			(xy 342.167973 -219.99067) (xy 342.219787 -219.99067) (xy 342.270964 -219.998776) (xy 342.320243 -220.014788)
			(xy 342.36641 -220.038311) (xy 342.408329 -220.068767) (xy 342.444967 -220.105405) (xy 342.475423 -220.147324)
			(xy 342.498946 -220.193491) (xy 342.514958 -220.24277) (xy 342.523064 -220.293947) (xy 342.523572 -220.319854)
			(xy 342.523122 -220.3452) (xy 342.515342 -220.395293) (xy 342.499988 -220.443604) (xy 342.477422 -220.488998)
			(xy 342.448176 -220.530404) (xy 342.412939 -220.566847) (xy 342.37254 -220.597469) (xy 342.327931 -220.621548)
			(xy 342.280163 -220.638518) (xy 342.255348 -220.643704) (xy 342.232488 -220.648022) (xy 342.02751 -221.003114)
			(xy 342.035384 -221.024958) (xy 342.043977 -221.051373) (xy 342.053165 -221.106151) (xy 342.053672 -221.133924)
			(xy 342.334596 -221.133924) (xy 342.335104 -221.108037) (xy 342.343203 -221.056899) (xy 342.359202 -221.007659)
			(xy 342.382708 -220.961527) (xy 342.41314 -220.91964) (xy 342.44975 -220.88303) (xy 342.491637 -220.852598)
			(xy 342.537769 -220.829092) (xy 342.587009 -220.813093) (xy 342.638147 -220.804994) (xy 342.689921 -220.804994)
			(xy 342.741059 -220.813093) (xy 342.790299 -220.829092) (xy 342.836431 -220.852598) (xy 342.878318 -220.88303)
			(xy 342.914928 -220.91964) (xy 342.94536 -220.961527) (xy 342.968866 -221.007659) (xy 342.984865 -221.056899)
			(xy 342.992964 -221.108037) (xy 342.993472 -221.133924) (xy 343.274396 -221.133924) (xy 343.274904 -221.10859)
			(xy 343.282653 -221.058519) (xy 343.297972 -221.010223) (xy 343.3205 -220.96484) (xy 343.349706 -220.923438)
			(xy 343.384904 -220.886992) (xy 343.425263 -220.856361) (xy 343.469834 -220.832266) (xy 343.517567 -220.815274)
			(xy 343.542366 -220.810074) (xy 343.565226 -220.805756) (xy 343.770204 -220.450664) (xy 343.76233 -220.42882)
			(xy 343.753696 -220.402408) (xy 343.744368 -220.347635) (xy 343.743788 -220.319854) (xy 343.744296 -220.293947)
			(xy 343.752402 -220.24277) (xy 343.768414 -220.193491) (xy 343.791937 -220.147324) (xy 343.822393 -220.105405)
			(xy 343.859031 -220.068767) (xy 343.90095 -220.038311) (xy 343.947117 -220.014788) (xy 343.996396 -219.998776)
			(xy 344.047573 -219.99067) (xy 344.099387 -219.99067) (xy 344.150564 -219.998776) (xy 344.199843 -220.014788)
			(xy 344.24601 -220.038311) (xy 344.287929 -220.068767) (xy 344.324567 -220.105405) (xy 344.355023 -220.147324)
			(xy 344.378546 -220.193491) (xy 344.394558 -220.24277) (xy 344.402664 -220.293947) (xy 344.403172 -220.319854)
			(xy 344.402722 -220.3452) (xy 344.394942 -220.395293) (xy 344.379588 -220.443604) (xy 344.357022 -220.488998)
			(xy 344.327776 -220.530404) (xy 344.292539 -220.566847) (xy 344.25214 -220.597469) (xy 344.207531 -220.621548)
			(xy 344.159763 -220.638518) (xy 344.134948 -220.643704) (xy 344.112088 -220.648022) (xy 343.90711 -221.003114)
			(xy 343.914984 -221.024958) (xy 343.923577 -221.051373) (xy 343.932765 -221.106151) (xy 343.933272 -221.133924)
			(xy 344.214196 -221.133924) (xy 344.214704 -221.108037) (xy 344.222803 -221.056899) (xy 344.238802 -221.007659)
			(xy 344.262308 -220.961527) (xy 344.29274 -220.91964) (xy 344.32935 -220.88303) (xy 344.371237 -220.852598)
			(xy 344.417369 -220.829092) (xy 344.466609 -220.813093) (xy 344.517747 -220.804994) (xy 344.569521 -220.804994)
			(xy 344.620659 -220.813093) (xy 344.669899 -220.829092) (xy 344.716031 -220.852598) (xy 344.757918 -220.88303)
			(xy 344.794528 -220.91964) (xy 344.82496 -220.961527) (xy 344.848466 -221.007659) (xy 344.864465 -221.056899)
			(xy 344.872564 -221.108037) (xy 344.873072 -221.133924) (xy 345.153996 -221.133924) (xy 345.154504 -221.10859)
			(xy 345.162253 -221.058519) (xy 345.177572 -221.010223) (xy 345.2001 -220.96484) (xy 345.229306 -220.923438)
			(xy 345.264504 -220.886992) (xy 345.304863 -220.856361) (xy 345.349434 -220.832266) (xy 345.397167 -220.815274)
			(xy 345.421966 -220.810074) (xy 345.444826 -220.805756) (xy 345.649804 -220.450664) (xy 345.64193 -220.42882)
			(xy 345.633296 -220.402408) (xy 345.623968 -220.347635) (xy 345.623388 -220.319854) (xy 345.623896 -220.293947)
			(xy 345.632002 -220.24277) (xy 345.648014 -220.193491) (xy 345.671537 -220.147324) (xy 345.701993 -220.105405)
			(xy 345.738631 -220.068767) (xy 345.78055 -220.038311) (xy 345.826717 -220.014788) (xy 345.875996 -219.998776)
			(xy 345.927173 -219.99067) (xy 345.978987 -219.99067) (xy 346.030164 -219.998776) (xy 346.079443 -220.014788)
			(xy 346.12561 -220.038311) (xy 346.167529 -220.068767) (xy 346.204167 -220.105405) (xy 346.234623 -220.147324)
			(xy 346.258146 -220.193491) (xy 346.274158 -220.24277) (xy 346.282264 -220.293947) (xy 346.282772 -220.319854)
			(xy 346.282322 -220.3452) (xy 346.274542 -220.395293) (xy 346.259188 -220.443604) (xy 346.236622 -220.488998)
			(xy 346.207376 -220.530404) (xy 346.172139 -220.566847) (xy 346.13174 -220.597469) (xy 346.087131 -220.621548)
			(xy 346.039363 -220.638518) (xy 346.014548 -220.643704) (xy 345.991688 -220.648022) (xy 345.78671 -221.003114)
			(xy 345.794584 -221.024958) (xy 345.803177 -221.051373) (xy 345.812365 -221.106151) (xy 345.812872 -221.133924)
			(xy 346.093796 -221.133924) (xy 346.094304 -221.108037) (xy 346.102403 -221.056899) (xy 346.118402 -221.007659)
			(xy 346.141908 -220.961527) (xy 346.17234 -220.91964) (xy 346.20895 -220.88303) (xy 346.250837 -220.852598)
			(xy 346.296969 -220.829092) (xy 346.346209 -220.813093) (xy 346.397347 -220.804994) (xy 346.449121 -220.804994)
			(xy 346.500259 -220.813093) (xy 346.549499 -220.829092) (xy 346.595631 -220.852598) (xy 346.637518 -220.88303)
			(xy 346.674128 -220.91964) (xy 346.70456 -220.961527) (xy 346.728066 -221.007659) (xy 346.744065 -221.056899)
			(xy 346.752164 -221.108037) (xy 346.752672 -221.133924) (xy 347.033596 -221.133924) (xy 347.034104 -221.10859)
			(xy 347.041853 -221.058519) (xy 347.057172 -221.010223) (xy 347.0797 -220.96484) (xy 347.108906 -220.923438)
			(xy 347.144104 -220.886992) (xy 347.184463 -220.856361) (xy 347.229034 -220.832266) (xy 347.276767 -220.815274)
			(xy 347.301566 -220.810074) (xy 347.324426 -220.805756) (xy 347.529404 -220.450664) (xy 347.52153 -220.42882)
			(xy 347.512896 -220.402408) (xy 347.503568 -220.347635) (xy 347.502988 -220.319854) (xy 347.503496 -220.293947)
			(xy 347.511602 -220.24277) (xy 347.527614 -220.193491) (xy 347.551137 -220.147324) (xy 347.581593 -220.105405)
			(xy 347.618231 -220.068767) (xy 347.66015 -220.038311) (xy 347.706317 -220.014788) (xy 347.755596 -219.998776)
			(xy 347.806773 -219.99067) (xy 347.858587 -219.99067) (xy 347.909764 -219.998776) (xy 347.959043 -220.014788)
			(xy 348.00521 -220.038311) (xy 348.047129 -220.068767) (xy 348.083767 -220.105405) (xy 348.114223 -220.147324)
			(xy 348.137746 -220.193491) (xy 348.153758 -220.24277) (xy 348.161864 -220.293947) (xy 348.162372 -220.319854)
			(xy 348.161922 -220.3452) (xy 348.154142 -220.395293) (xy 348.138788 -220.443604) (xy 348.116222 -220.488998)
			(xy 348.086976 -220.530404) (xy 348.051739 -220.566847) (xy 348.01134 -220.597469) (xy 347.966731 -220.621548)
			(xy 347.918963 -220.638518) (xy 347.894148 -220.643704) (xy 347.871288 -220.648022) (xy 347.66631 -221.003114)
			(xy 347.674184 -221.024958) (xy 347.682777 -221.051373) (xy 347.691965 -221.106151) (xy 347.692472 -221.133924)
			(xy 347.973396 -221.133924) (xy 347.973904 -221.108037) (xy 347.982003 -221.056899) (xy 347.998002 -221.007659)
			(xy 348.021508 -220.961527) (xy 348.05194 -220.91964) (xy 348.08855 -220.88303) (xy 348.130437 -220.852598)
			(xy 348.176569 -220.829092) (xy 348.225809 -220.813093) (xy 348.276947 -220.804994) (xy 348.328721 -220.804994)
			(xy 348.379859 -220.813093) (xy 348.429099 -220.829092) (xy 348.475231 -220.852598) (xy 348.517118 -220.88303)
			(xy 348.553728 -220.91964) (xy 348.58416 -220.961527) (xy 348.607666 -221.007659) (xy 348.623665 -221.056899)
			(xy 348.631764 -221.108037) (xy 348.632272 -221.133924) (xy 348.913196 -221.133924) (xy 348.913704 -221.10859)
			(xy 348.921453 -221.058519) (xy 348.936772 -221.010223) (xy 348.9593 -220.96484) (xy 348.988506 -220.923438)
			(xy 349.023704 -220.886992) (xy 349.064063 -220.856361) (xy 349.108634 -220.832266) (xy 349.156367 -220.815274)
			(xy 349.181166 -220.810074) (xy 349.204026 -220.805756) (xy 349.409004 -220.450664) (xy 349.40113 -220.42882)
			(xy 349.392496 -220.402408) (xy 349.383168 -220.347635) (xy 349.382588 -220.319854) (xy 349.383096 -220.293947)
			(xy 349.391202 -220.24277) (xy 349.407214 -220.193491) (xy 349.430737 -220.147324) (xy 349.461193 -220.105405)
			(xy 349.497831 -220.068767) (xy 349.53975 -220.038311) (xy 349.585917 -220.014788) (xy 349.635196 -219.998776)
			(xy 349.686373 -219.99067) (xy 349.738187 -219.99067) (xy 349.789364 -219.998776) (xy 349.838643 -220.014788)
			(xy 349.88481 -220.038311) (xy 349.926729 -220.068767) (xy 349.963367 -220.105405) (xy 349.993823 -220.147324)
			(xy 350.017346 -220.193491) (xy 350.033358 -220.24277) (xy 350.041464 -220.293947) (xy 350.041972 -220.319854)
			(xy 350.041522 -220.3452) (xy 350.033742 -220.395293) (xy 350.018388 -220.443604) (xy 349.995822 -220.488998)
			(xy 349.966576 -220.530404) (xy 349.931339 -220.566847) (xy 349.89094 -220.597469) (xy 349.846331 -220.621548)
			(xy 349.798563 -220.638518) (xy 349.773748 -220.643704) (xy 349.750888 -220.648022) (xy 349.54591 -221.003114)
			(xy 349.553784 -221.024958) (xy 349.562377 -221.051373) (xy 349.571565 -221.106151) (xy 349.572072 -221.133924)
			(xy 349.852996 -221.133924) (xy 349.853504 -221.108037) (xy 349.861603 -221.056899) (xy 349.877602 -221.007659)
			(xy 349.901108 -220.961527) (xy 349.93154 -220.91964) (xy 349.96815 -220.88303) (xy 350.010037 -220.852598)
			(xy 350.056169 -220.829092) (xy 350.105409 -220.813093) (xy 350.156547 -220.804994) (xy 350.208321 -220.804994)
			(xy 350.259459 -220.813093) (xy 350.308699 -220.829092) (xy 350.354831 -220.852598) (xy 350.396718 -220.88303)
			(xy 350.433328 -220.91964) (xy 350.46376 -220.961527) (xy 350.487266 -221.007659) (xy 350.503265 -221.056899)
			(xy 350.511364 -221.108037) (xy 350.511872 -221.133924) (xy 350.792796 -221.133924) (xy 350.793304 -221.10859)
			(xy 350.801053 -221.058519) (xy 350.816372 -221.010223) (xy 350.8389 -220.96484) (xy 350.868106 -220.923438)
			(xy 350.903304 -220.886992) (xy 350.943663 -220.856361) (xy 350.988234 -220.832266) (xy 351.035967 -220.815274)
			(xy 351.060766 -220.810074) (xy 351.083626 -220.805756) (xy 351.288604 -220.450664) (xy 351.28073 -220.42882)
			(xy 351.272096 -220.402408) (xy 351.262768 -220.347635) (xy 351.262188 -220.319854) (xy 351.262696 -220.293947)
			(xy 351.270802 -220.24277) (xy 351.286814 -220.193491) (xy 351.310337 -220.147324) (xy 351.340793 -220.105405)
			(xy 351.377431 -220.068767) (xy 351.41935 -220.038311) (xy 351.465517 -220.014788) (xy 351.514796 -219.998776)
			(xy 351.565973 -219.99067) (xy 351.617787 -219.99067) (xy 351.668964 -219.998776) (xy 351.718243 -220.014788)
			(xy 351.76441 -220.038311) (xy 351.806329 -220.068767) (xy 351.842967 -220.105405) (xy 351.873423 -220.147324)
			(xy 351.896946 -220.193491) (xy 351.912958 -220.24277) (xy 351.921064 -220.293947) (xy 351.921572 -220.319854)
			(xy 353.141788 -220.319854) (xy 353.142296 -220.293947) (xy 353.150402 -220.24277) (xy 353.166414 -220.193491)
			(xy 353.189937 -220.147324) (xy 353.220393 -220.105405) (xy 353.257031 -220.068767) (xy 353.29895 -220.038311)
			(xy 353.345117 -220.014788) (xy 353.394396 -219.998776) (xy 353.445573 -219.99067) (xy 353.497387 -219.99067)
			(xy 353.548564 -219.998776) (xy 353.597843 -220.014788) (xy 353.64401 -220.038311) (xy 353.685929 -220.068767)
			(xy 353.722567 -220.105405) (xy 353.753023 -220.147324) (xy 353.776546 -220.193491) (xy 353.792558 -220.24277)
			(xy 353.800664 -220.293947) (xy 353.801172 -220.319854) (xy 355.021388 -220.319854) (xy 355.021896 -220.293947)
			(xy 355.030002 -220.24277) (xy 355.046014 -220.193491) (xy 355.069537 -220.147324) (xy 355.099993 -220.105405)
			(xy 355.136631 -220.068767) (xy 355.17855 -220.038311) (xy 355.224717 -220.014788) (xy 355.273996 -219.998776)
			(xy 355.325173 -219.99067) (xy 355.376987 -219.99067) (xy 355.428164 -219.998776) (xy 355.477443 -220.014788)
			(xy 355.52361 -220.038311) (xy 355.565529 -220.068767) (xy 355.602167 -220.105405) (xy 355.632623 -220.147324)
			(xy 355.656146 -220.193491) (xy 355.672158 -220.24277) (xy 355.680264 -220.293947) (xy 355.680772 -220.319854)
			(xy 356.900988 -220.319854) (xy 356.901496 -220.293947) (xy 356.909602 -220.24277) (xy 356.925614 -220.193491)
			(xy 356.949137 -220.147324) (xy 356.979593 -220.105405) (xy 357.016231 -220.068767) (xy 357.05815 -220.038311)
			(xy 357.104317 -220.014788) (xy 357.153596 -219.998776) (xy 357.204773 -219.99067) (xy 357.256587 -219.99067)
			(xy 357.307764 -219.998776) (xy 357.357043 -220.014788) (xy 357.40321 -220.038311) (xy 357.445129 -220.068767)
			(xy 357.481767 -220.105405) (xy 357.512223 -220.147324) (xy 357.535746 -220.193491) (xy 357.551758 -220.24277)
			(xy 357.559864 -220.293947) (xy 357.560372 -220.319854) (xy 358.780588 -220.319854) (xy 358.781096 -220.293947)
			(xy 358.789202 -220.24277) (xy 358.805214 -220.193491) (xy 358.828737 -220.147324) (xy 358.859193 -220.105405)
			(xy 358.895831 -220.068767) (xy 358.93775 -220.038311) (xy 358.983917 -220.014788) (xy 359.033196 -219.998776)
			(xy 359.084373 -219.99067) (xy 359.136187 -219.99067) (xy 359.187364 -219.998776) (xy 359.236643 -220.014788)
			(xy 359.28281 -220.038311) (xy 359.324729 -220.068767) (xy 359.361367 -220.105405) (xy 359.391823 -220.147324)
			(xy 359.415346 -220.193491) (xy 359.431358 -220.24277) (xy 359.439464 -220.293947) (xy 359.439972 -220.319854)
			(xy 360.660188 -220.319854) (xy 360.660696 -220.293947) (xy 360.668802 -220.24277) (xy 360.684814 -220.193491)
			(xy 360.708337 -220.147324) (xy 360.738793 -220.105405) (xy 360.775431 -220.068767) (xy 360.81735 -220.038311)
			(xy 360.863517 -220.014788) (xy 360.912796 -219.998776) (xy 360.963973 -219.99067) (xy 361.015787 -219.99067)
			(xy 361.066964 -219.998776) (xy 361.116243 -220.014788) (xy 361.16241 -220.038311) (xy 361.204329 -220.068767)
			(xy 361.240967 -220.105405) (xy 361.271423 -220.147324) (xy 361.294946 -220.193491) (xy 361.310958 -220.24277)
			(xy 361.319064 -220.293947) (xy 361.319572 -220.319854) (xy 362.539788 -220.319854) (xy 362.540296 -220.293947)
			(xy 362.548402 -220.24277) (xy 362.564414 -220.193491) (xy 362.587937 -220.147324) (xy 362.618393 -220.105405)
			(xy 362.655031 -220.068767) (xy 362.69695 -220.038311) (xy 362.743117 -220.014788) (xy 362.792396 -219.998776)
			(xy 362.843573 -219.99067) (xy 362.895387 -219.99067) (xy 362.946564 -219.998776) (xy 362.995843 -220.014788)
			(xy 363.04201 -220.038311) (xy 363.083929 -220.068767) (xy 363.120567 -220.105405) (xy 363.151023 -220.147324)
			(xy 363.174546 -220.193491) (xy 363.190558 -220.24277) (xy 363.198664 -220.293947) (xy 363.199172 -220.319854)
			(xy 364.419388 -220.319854) (xy 364.419896 -220.293947) (xy 364.428002 -220.24277) (xy 364.444014 -220.193491)
			(xy 364.467537 -220.147324) (xy 364.497993 -220.105405) (xy 364.534631 -220.068767) (xy 364.57655 -220.038311)
			(xy 364.622717 -220.014788) (xy 364.671996 -219.998776) (xy 364.723173 -219.99067) (xy 364.774987 -219.99067)
			(xy 364.826164 -219.998776) (xy 364.875443 -220.014788) (xy 364.92161 -220.038311) (xy 364.963529 -220.068767)
			(xy 365.000167 -220.105405) (xy 365.030623 -220.147324) (xy 365.054146 -220.193491) (xy 365.070158 -220.24277)
			(xy 365.078264 -220.293947) (xy 365.078772 -220.319854) (xy 366.298988 -220.319854) (xy 366.299496 -220.293947)
			(xy 366.307602 -220.24277) (xy 366.323614 -220.193491) (xy 366.347137 -220.147324) (xy 366.377593 -220.105405)
			(xy 366.414231 -220.068767) (xy 366.45615 -220.038311) (xy 366.502317 -220.014788) (xy 366.551596 -219.998776)
			(xy 366.602773 -219.99067) (xy 366.654587 -219.99067) (xy 366.705764 -219.998776) (xy 366.755043 -220.014788)
			(xy 366.80121 -220.038311) (xy 366.843129 -220.068767) (xy 366.879767 -220.105405) (xy 366.910223 -220.147324)
			(xy 366.933746 -220.193491) (xy 366.949758 -220.24277) (xy 366.957864 -220.293947) (xy 366.958372 -220.319854)
			(xy 368.178588 -220.319854) (xy 368.179096 -220.293947) (xy 368.187202 -220.24277) (xy 368.203214 -220.193491)
			(xy 368.226737 -220.147324) (xy 368.257193 -220.105405) (xy 368.293831 -220.068767) (xy 368.33575 -220.038311)
			(xy 368.381917 -220.014788) (xy 368.431196 -219.998776) (xy 368.482373 -219.99067) (xy 368.534187 -219.99067)
			(xy 368.585364 -219.998776) (xy 368.634643 -220.014788) (xy 368.68081 -220.038311) (xy 368.722729 -220.068767)
			(xy 368.759367 -220.105405) (xy 368.789823 -220.147324) (xy 368.813346 -220.193491) (xy 368.829358 -220.24277)
			(xy 368.837464 -220.293947) (xy 368.837972 -220.319854) (xy 370.058188 -220.319854) (xy 370.058696 -220.293947)
			(xy 370.066802 -220.24277) (xy 370.082814 -220.193491) (xy 370.106337 -220.147324) (xy 370.136793 -220.105405)
			(xy 370.173431 -220.068767) (xy 370.21535 -220.038311) (xy 370.261517 -220.014788) (xy 370.310796 -219.998776)
			(xy 370.361973 -219.99067) (xy 370.413787 -219.99067) (xy 370.464964 -219.998776) (xy 370.514243 -220.014788)
			(xy 370.56041 -220.038311) (xy 370.602329 -220.068767) (xy 370.638967 -220.105405) (xy 370.669423 -220.147324)
			(xy 370.692946 -220.193491) (xy 370.708958 -220.24277) (xy 370.717064 -220.293947) (xy 370.717572 -220.319854)
			(xy 371.937788 -220.319854) (xy 371.938296 -220.293947) (xy 371.946402 -220.24277) (xy 371.962414 -220.193491)
			(xy 371.985937 -220.147324) (xy 372.016393 -220.105405) (xy 372.053031 -220.068767) (xy 372.09495 -220.038311)
			(xy 372.141117 -220.014788) (xy 372.190396 -219.998776) (xy 372.241573 -219.99067) (xy 372.293387 -219.99067)
			(xy 372.344564 -219.998776) (xy 372.393843 -220.014788) (xy 372.44001 -220.038311) (xy 372.481929 -220.068767)
			(xy 372.518567 -220.105405) (xy 372.549023 -220.147324) (xy 372.572546 -220.193491) (xy 372.588558 -220.24277)
			(xy 372.596664 -220.293947) (xy 372.597172 -220.319854) (xy 373.817388 -220.319854) (xy 373.817896 -220.293947)
			(xy 373.826002 -220.24277) (xy 373.842014 -220.193491) (xy 373.865537 -220.147324) (xy 373.895993 -220.105405)
			(xy 373.932631 -220.068767) (xy 373.97455 -220.038311) (xy 374.020717 -220.014788) (xy 374.069996 -219.998776)
			(xy 374.121173 -219.99067) (xy 374.172987 -219.99067) (xy 374.224164 -219.998776) (xy 374.273443 -220.014788)
			(xy 374.31961 -220.038311) (xy 374.361529 -220.068767) (xy 374.398167 -220.105405) (xy 374.428623 -220.147324)
			(xy 374.452146 -220.193491) (xy 374.468158 -220.24277) (xy 374.476264 -220.293947) (xy 374.476772 -220.319854)
			(xy 375.696988 -220.319854) (xy 375.697496 -220.293947) (xy 375.705602 -220.24277) (xy 375.721614 -220.193491)
			(xy 375.745137 -220.147324) (xy 375.775593 -220.105405) (xy 375.812231 -220.068767) (xy 375.85415 -220.038311)
			(xy 375.900317 -220.014788) (xy 375.949596 -219.998776) (xy 376.000773 -219.99067) (xy 376.052587 -219.99067)
			(xy 376.103764 -219.998776) (xy 376.153043 -220.014788) (xy 376.19921 -220.038311) (xy 376.241129 -220.068767)
			(xy 376.277767 -220.105405) (xy 376.308223 -220.147324) (xy 376.331746 -220.193491) (xy 376.347758 -220.24277)
			(xy 376.355864 -220.293947) (xy 376.356372 -220.319854) (xy 377.576588 -220.319854) (xy 377.577096 -220.293947)
			(xy 377.585202 -220.24277) (xy 377.601214 -220.193491) (xy 377.624737 -220.147324) (xy 377.655193 -220.105405)
			(xy 377.691831 -220.068767) (xy 377.73375 -220.038311) (xy 377.779917 -220.014788) (xy 377.829196 -219.998776)
			(xy 377.880373 -219.99067) (xy 377.932187 -219.99067) (xy 377.983364 -219.998776) (xy 378.032643 -220.014788)
			(xy 378.07881 -220.038311) (xy 378.120729 -220.068767) (xy 378.157367 -220.105405) (xy 378.187823 -220.147324)
			(xy 378.211346 -220.193491) (xy 378.227358 -220.24277) (xy 378.235464 -220.293947) (xy 378.235972 -220.319854)
			(xy 379.456188 -220.319854) (xy 379.456696 -220.293947) (xy 379.464802 -220.24277) (xy 379.480814 -220.193491)
			(xy 379.504337 -220.147324) (xy 379.534793 -220.105405) (xy 379.571431 -220.068767) (xy 379.61335 -220.038311)
			(xy 379.659517 -220.014788) (xy 379.708796 -219.998776) (xy 379.759973 -219.99067) (xy 379.811787 -219.99067)
			(xy 379.862964 -219.998776) (xy 379.912243 -220.014788) (xy 379.95841 -220.038311) (xy 380.000329 -220.068767)
			(xy 380.036967 -220.105405) (xy 380.067423 -220.147324) (xy 380.090946 -220.193491) (xy 380.106958 -220.24277)
			(xy 380.115064 -220.293947) (xy 380.115572 -220.319854) (xy 381.336296 -220.319854) (xy 381.336804 -220.293967)
			(xy 381.344903 -220.242829) (xy 381.360902 -220.193589) (xy 381.384408 -220.147457) (xy 381.41484 -220.10557)
			(xy 381.45145 -220.06896) (xy 381.493337 -220.038528) (xy 381.539469 -220.015022) (xy 381.588709 -219.999023)
			(xy 381.639847 -219.990924) (xy 381.691621 -219.990924) (xy 381.742759 -219.999023) (xy 381.791999 -220.015022)
			(xy 381.838131 -220.038528) (xy 381.880018 -220.06896) (xy 381.916628 -220.10557) (xy 381.94706 -220.147457)
			(xy 381.970566 -220.193589) (xy 381.986565 -220.242829) (xy 381.994664 -220.293967) (xy 381.995172 -220.319854)
			(xy 381.994628 -220.347561) (xy 381.985442 -220.402208) (xy 381.976884 -220.428566) (xy 381.969264 -220.450664)
			(xy 382.174242 -220.805756) (xy 382.197102 -220.810074) (xy 382.221908 -220.815252) (xy 382.269647 -220.832242)
			(xy 382.314225 -220.856337) (xy 382.354591 -220.886969) (xy 382.389795 -220.923417) (xy 382.419006 -220.964822)
			(xy 382.441538 -221.01021) (xy 382.45686 -221.058511) (xy 382.46461 -221.108588) (xy 382.465072 -221.133924)
			(xy 382.464564 -221.159811) (xy 382.456465 -221.210949) (xy 382.440466 -221.260189) (xy 382.41696 -221.306321)
			(xy 382.386528 -221.348208) (xy 382.349918 -221.384818) (xy 382.308031 -221.41525) (xy 382.261899 -221.438756)
			(xy 382.212659 -221.454755) (xy 382.161521 -221.462854) (xy 382.109747 -221.462854) (xy 382.058609 -221.454755)
			(xy 382.009369 -221.438756) (xy 381.963237 -221.41525) (xy 381.92135 -221.384818) (xy 381.88474 -221.348208)
			(xy 381.854308 -221.306321) (xy 381.830802 -221.260189) (xy 381.814803 -221.210949) (xy 381.806704 -221.159811)
			(xy 381.806196 -221.133924) (xy 381.806732 -221.106216) (xy 381.815923 -221.051569) (xy 381.824484 -221.025212)
			(xy 381.832358 -221.003114) (xy 381.62738 -220.648022) (xy 381.60452 -220.643704) (xy 381.579694 -220.638559)
			(xy 381.531915 -220.6216) (xy 381.487296 -220.597525) (xy 381.446891 -220.566902) (xy 381.41165 -220.530452)
			(xy 381.382408 -220.489036) (xy 381.359851 -220.44363) (xy 381.344514 -220.395306) (xy 381.336758 -220.345204)
			(xy 381.336296 -220.319854) (xy 380.115572 -220.319854) (xy 380.114963 -220.347508) (xy 380.105639 -220.402026)
			(xy 380.09703 -220.428312) (xy 380.08941 -220.45041) (xy 380.294642 -220.805756) (xy 380.317502 -220.810074)
			(xy 380.342308 -220.815252) (xy 380.390047 -220.832242) (xy 380.434625 -220.856337) (xy 380.474991 -220.886969)
			(xy 380.510195 -220.923417) (xy 380.539406 -220.964822) (xy 380.561938 -221.01021) (xy 380.57726 -221.058511)
			(xy 380.58501 -221.108588) (xy 380.585472 -221.133924) (xy 380.584964 -221.159811) (xy 380.576865 -221.210949)
			(xy 380.560866 -221.260189) (xy 380.53736 -221.306321) (xy 380.506928 -221.348208) (xy 380.470318 -221.384818)
			(xy 380.428431 -221.41525) (xy 380.382299 -221.438756) (xy 380.333059 -221.454755) (xy 380.281921 -221.462854)
			(xy 380.230147 -221.462854) (xy 380.179009 -221.454755) (xy 380.129769 -221.438756) (xy 380.083637 -221.41525)
			(xy 380.04175 -221.384818) (xy 380.00514 -221.348208) (xy 379.974708 -221.306321) (xy 379.951202 -221.260189)
			(xy 379.935203 -221.210949) (xy 379.927104 -221.159811) (xy 379.926596 -221.133924) (xy 379.927132 -221.106216)
			(xy 379.936323 -221.051569) (xy 379.944884 -221.025212) (xy 379.952758 -221.003114) (xy 379.74778 -220.648022)
			(xy 379.72492 -220.643704) (xy 379.700079 -220.638521) (xy 379.652232 -220.621628) (xy 379.60754 -220.5976)
			(xy 379.567059 -220.567005) (xy 379.531748 -220.530566) (xy 379.502439 -220.489145) (xy 379.479827 -220.44372)
			(xy 379.464446 -220.395365) (xy 379.456659 -220.345225) (xy 379.456188 -220.319854) (xy 378.235972 -220.319854)
			(xy 378.235363 -220.347508) (xy 378.226039 -220.402026) (xy 378.21743 -220.428312) (xy 378.20981 -220.45041)
			(xy 378.415042 -220.805756) (xy 378.437902 -220.810074) (xy 378.462708 -220.815252) (xy 378.510447 -220.832242)
			(xy 378.555025 -220.856337) (xy 378.595391 -220.886969) (xy 378.630595 -220.923417) (xy 378.659806 -220.964822)
			(xy 378.682338 -221.01021) (xy 378.69766 -221.058511) (xy 378.70541 -221.108588) (xy 378.705872 -221.133924)
			(xy 378.705364 -221.159811) (xy 378.697265 -221.210949) (xy 378.681266 -221.260189) (xy 378.65776 -221.306321)
			(xy 378.627328 -221.348208) (xy 378.590718 -221.384818) (xy 378.548831 -221.41525) (xy 378.502699 -221.438756)
			(xy 378.453459 -221.454755) (xy 378.402321 -221.462854) (xy 378.350547 -221.462854) (xy 378.299409 -221.454755)
			(xy 378.250169 -221.438756) (xy 378.204037 -221.41525) (xy 378.16215 -221.384818) (xy 378.12554 -221.348208)
			(xy 378.095108 -221.306321) (xy 378.071602 -221.260189) (xy 378.055603 -221.210949) (xy 378.047504 -221.159811)
			(xy 378.046996 -221.133924) (xy 378.047532 -221.106216) (xy 378.056723 -221.051569) (xy 378.065284 -221.025212)
			(xy 378.073158 -221.003114) (xy 377.86818 -220.648022) (xy 377.84532 -220.643704) (xy 377.820479 -220.638521)
			(xy 377.772632 -220.621628) (xy 377.72794 -220.5976) (xy 377.687459 -220.567005) (xy 377.652148 -220.530566)
			(xy 377.622839 -220.489145) (xy 377.600227 -220.44372) (xy 377.584846 -220.395365) (xy 377.577059 -220.345225)
			(xy 377.576588 -220.319854) (xy 376.356372 -220.319854) (xy 376.355763 -220.347508) (xy 376.346439 -220.402026)
			(xy 376.33783 -220.428312) (xy 376.33021 -220.45041) (xy 376.535442 -220.805756) (xy 376.558302 -220.810074)
			(xy 376.583108 -220.815252) (xy 376.630847 -220.832242) (xy 376.675425 -220.856337) (xy 376.715791 -220.886969)
			(xy 376.750995 -220.923417) (xy 376.780206 -220.964822) (xy 376.802738 -221.01021) (xy 376.81806 -221.058511)
			(xy 376.82581 -221.108588) (xy 376.826272 -221.133924) (xy 376.825764 -221.159811) (xy 376.817665 -221.210949)
			(xy 376.801666 -221.260189) (xy 376.77816 -221.306321) (xy 376.747728 -221.348208) (xy 376.711118 -221.384818)
			(xy 376.669231 -221.41525) (xy 376.623099 -221.438756) (xy 376.573859 -221.454755) (xy 376.522721 -221.462854)
			(xy 376.470947 -221.462854) (xy 376.419809 -221.454755) (xy 376.370569 -221.438756) (xy 376.324437 -221.41525)
			(xy 376.28255 -221.384818) (xy 376.24594 -221.348208) (xy 376.215508 -221.306321) (xy 376.192002 -221.260189)
			(xy 376.176003 -221.210949) (xy 376.167904 -221.159811) (xy 376.167396 -221.133924) (xy 376.167932 -221.106216)
			(xy 376.177123 -221.051569) (xy 376.185684 -221.025212) (xy 376.193558 -221.003114) (xy 375.98858 -220.648022)
			(xy 375.96572 -220.643704) (xy 375.940879 -220.638521) (xy 375.893032 -220.621628) (xy 375.84834 -220.5976)
			(xy 375.807859 -220.567005) (xy 375.772548 -220.530566) (xy 375.743239 -220.489145) (xy 375.720627 -220.44372)
			(xy 375.705246 -220.395365) (xy 375.697459 -220.345225) (xy 375.696988 -220.319854) (xy 374.476772 -220.319854)
			(xy 374.476163 -220.347508) (xy 374.466839 -220.402026) (xy 374.45823 -220.428312) (xy 374.45061 -220.45041)
			(xy 374.655842 -220.805756) (xy 374.678702 -220.810074) (xy 374.703508 -220.815252) (xy 374.751247 -220.832242)
			(xy 374.795825 -220.856337) (xy 374.836191 -220.886969) (xy 374.871395 -220.923417) (xy 374.900606 -220.964822)
			(xy 374.923138 -221.01021) (xy 374.93846 -221.058511) (xy 374.94621 -221.108588) (xy 374.946672 -221.133924)
			(xy 374.946164 -221.159811) (xy 374.938065 -221.210949) (xy 374.922066 -221.260189) (xy 374.89856 -221.306321)
			(xy 374.868128 -221.348208) (xy 374.831518 -221.384818) (xy 374.789631 -221.41525) (xy 374.743499 -221.438756)
			(xy 374.694259 -221.454755) (xy 374.643121 -221.462854) (xy 374.591347 -221.462854) (xy 374.540209 -221.454755)
			(xy 374.490969 -221.438756) (xy 374.444837 -221.41525) (xy 374.40295 -221.384818) (xy 374.36634 -221.348208)
			(xy 374.335908 -221.306321) (xy 374.312402 -221.260189) (xy 374.296403 -221.210949) (xy 374.288304 -221.159811)
			(xy 374.287796 -221.133924) (xy 374.288332 -221.106216) (xy 374.297523 -221.051569) (xy 374.306084 -221.025212)
			(xy 374.313958 -221.003114) (xy 374.10898 -220.648022) (xy 374.08612 -220.643704) (xy 374.061279 -220.638521)
			(xy 374.013432 -220.621628) (xy 373.96874 -220.5976) (xy 373.928259 -220.567005) (xy 373.892948 -220.530566)
			(xy 373.863639 -220.489145) (xy 373.841027 -220.44372) (xy 373.825646 -220.395365) (xy 373.817859 -220.345225)
			(xy 373.817388 -220.319854) (xy 372.597172 -220.319854) (xy 372.596563 -220.347508) (xy 372.587239 -220.402026)
			(xy 372.57863 -220.428312) (xy 372.57101 -220.45041) (xy 372.776242 -220.805756) (xy 372.799102 -220.810074)
			(xy 372.823908 -220.815252) (xy 372.871647 -220.832242) (xy 372.916225 -220.856337) (xy 372.956591 -220.886969)
			(xy 372.991795 -220.923417) (xy 373.021006 -220.964822) (xy 373.043538 -221.01021) (xy 373.05886 -221.058511)
			(xy 373.06661 -221.108588) (xy 373.067072 -221.133924) (xy 373.066564 -221.159811) (xy 373.058465 -221.210949)
			(xy 373.042466 -221.260189) (xy 373.01896 -221.306321) (xy 372.988528 -221.348208) (xy 372.951918 -221.384818)
			(xy 372.910031 -221.41525) (xy 372.863899 -221.438756) (xy 372.814659 -221.454755) (xy 372.763521 -221.462854)
			(xy 372.711747 -221.462854) (xy 372.660609 -221.454755) (xy 372.611369 -221.438756) (xy 372.565237 -221.41525)
			(xy 372.52335 -221.384818) (xy 372.48674 -221.348208) (xy 372.456308 -221.306321) (xy 372.432802 -221.260189)
			(xy 372.416803 -221.210949) (xy 372.408704 -221.159811) (xy 372.408196 -221.133924) (xy 372.408732 -221.106216)
			(xy 372.417923 -221.051569) (xy 372.426484 -221.025212) (xy 372.434358 -221.003114) (xy 372.22938 -220.648022)
			(xy 372.20652 -220.643704) (xy 372.181679 -220.638521) (xy 372.133832 -220.621628) (xy 372.08914 -220.5976)
			(xy 372.048659 -220.567005) (xy 372.013348 -220.530566) (xy 371.984039 -220.489145) (xy 371.961427 -220.44372)
			(xy 371.946046 -220.395365) (xy 371.938259 -220.345225) (xy 371.937788 -220.319854) (xy 370.717572 -220.319854)
			(xy 370.716963 -220.347508) (xy 370.707639 -220.402026) (xy 370.69903 -220.428312) (xy 370.69141 -220.45041)
			(xy 370.896642 -220.805756) (xy 370.919502 -220.810074) (xy 370.944308 -220.815252) (xy 370.992047 -220.832242)
			(xy 371.036625 -220.856337) (xy 371.076991 -220.886969) (xy 371.112195 -220.923417) (xy 371.141406 -220.964822)
			(xy 371.163938 -221.01021) (xy 371.17926 -221.058511) (xy 371.18701 -221.108588) (xy 371.187472 -221.133924)
			(xy 371.186964 -221.159811) (xy 371.178865 -221.210949) (xy 371.162866 -221.260189) (xy 371.13936 -221.306321)
			(xy 371.108928 -221.348208) (xy 371.072318 -221.384818) (xy 371.030431 -221.41525) (xy 370.984299 -221.438756)
			(xy 370.935059 -221.454755) (xy 370.883921 -221.462854) (xy 370.832147 -221.462854) (xy 370.781009 -221.454755)
			(xy 370.731769 -221.438756) (xy 370.685637 -221.41525) (xy 370.64375 -221.384818) (xy 370.60714 -221.348208)
			(xy 370.576708 -221.306321) (xy 370.553202 -221.260189) (xy 370.537203 -221.210949) (xy 370.529104 -221.159811)
			(xy 370.528596 -221.133924) (xy 370.529132 -221.106216) (xy 370.538323 -221.051569) (xy 370.546884 -221.025212)
			(xy 370.554758 -221.003114) (xy 370.34978 -220.648022) (xy 370.32692 -220.643704) (xy 370.302079 -220.638521)
			(xy 370.254232 -220.621628) (xy 370.20954 -220.5976) (xy 370.169059 -220.567005) (xy 370.133748 -220.530566)
			(xy 370.104439 -220.489145) (xy 370.081827 -220.44372) (xy 370.066446 -220.395365) (xy 370.058659 -220.345225)
			(xy 370.058188 -220.319854) (xy 368.837972 -220.319854) (xy 368.837363 -220.347508) (xy 368.828039 -220.402026)
			(xy 368.81943 -220.428312) (xy 368.81181 -220.45041) (xy 369.017042 -220.805756) (xy 369.039902 -220.810074)
			(xy 369.064708 -220.815252) (xy 369.112447 -220.832242) (xy 369.157025 -220.856337) (xy 369.197391 -220.886969)
			(xy 369.232595 -220.923417) (xy 369.261806 -220.964822) (xy 369.284338 -221.01021) (xy 369.29966 -221.058511)
			(xy 369.30741 -221.108588) (xy 369.307872 -221.133924) (xy 369.307364 -221.159811) (xy 369.299265 -221.210949)
			(xy 369.283266 -221.260189) (xy 369.25976 -221.306321) (xy 369.229328 -221.348208) (xy 369.192718 -221.384818)
			(xy 369.150831 -221.41525) (xy 369.104699 -221.438756) (xy 369.055459 -221.454755) (xy 369.004321 -221.462854)
			(xy 368.952547 -221.462854) (xy 368.901409 -221.454755) (xy 368.852169 -221.438756) (xy 368.806037 -221.41525)
			(xy 368.76415 -221.384818) (xy 368.72754 -221.348208) (xy 368.697108 -221.306321) (xy 368.673602 -221.260189)
			(xy 368.657603 -221.210949) (xy 368.649504 -221.159811) (xy 368.648996 -221.133924) (xy 368.649532 -221.106216)
			(xy 368.658723 -221.051569) (xy 368.667284 -221.025212) (xy 368.675158 -221.003114) (xy 368.47018 -220.648022)
			(xy 368.44732 -220.643704) (xy 368.422479 -220.638521) (xy 368.374632 -220.621628) (xy 368.32994 -220.5976)
			(xy 368.289459 -220.567005) (xy 368.254148 -220.530566) (xy 368.224839 -220.489145) (xy 368.202227 -220.44372)
			(xy 368.186846 -220.395365) (xy 368.179059 -220.345225) (xy 368.178588 -220.319854) (xy 366.958372 -220.319854)
			(xy 366.957763 -220.347508) (xy 366.948439 -220.402026) (xy 366.93983 -220.428312) (xy 366.93221 -220.45041)
			(xy 367.137442 -220.805756) (xy 367.160302 -220.810074) (xy 367.185108 -220.815252) (xy 367.232847 -220.832242)
			(xy 367.277425 -220.856337) (xy 367.317791 -220.886969) (xy 367.352995 -220.923417) (xy 367.382206 -220.964822)
			(xy 367.404738 -221.01021) (xy 367.42006 -221.058511) (xy 367.42781 -221.108588) (xy 367.428272 -221.133924)
			(xy 367.427764 -221.159811) (xy 367.419665 -221.210949) (xy 367.403666 -221.260189) (xy 367.38016 -221.306321)
			(xy 367.349728 -221.348208) (xy 367.313118 -221.384818) (xy 367.271231 -221.41525) (xy 367.225099 -221.438756)
			(xy 367.175859 -221.454755) (xy 367.124721 -221.462854) (xy 367.072947 -221.462854) (xy 367.021809 -221.454755)
			(xy 366.972569 -221.438756) (xy 366.926437 -221.41525) (xy 366.88455 -221.384818) (xy 366.84794 -221.348208)
			(xy 366.817508 -221.306321) (xy 366.794002 -221.260189) (xy 366.778003 -221.210949) (xy 366.769904 -221.159811)
			(xy 366.769396 -221.133924) (xy 366.769932 -221.106216) (xy 366.779123 -221.051569) (xy 366.787684 -221.025212)
			(xy 366.795558 -221.003114) (xy 366.59058 -220.648022) (xy 366.56772 -220.643704) (xy 366.542879 -220.638521)
			(xy 366.495032 -220.621628) (xy 366.45034 -220.5976) (xy 366.409859 -220.567005) (xy 366.374548 -220.530566)
			(xy 366.345239 -220.489145) (xy 366.322627 -220.44372) (xy 366.307246 -220.395365) (xy 366.299459 -220.345225)
			(xy 366.298988 -220.319854) (xy 365.078772 -220.319854) (xy 365.078163 -220.347508) (xy 365.068839 -220.402026)
			(xy 365.06023 -220.428312) (xy 365.05261 -220.45041) (xy 365.257842 -220.805756) (xy 365.280702 -220.810074)
			(xy 365.305508 -220.815252) (xy 365.353247 -220.832242) (xy 365.397825 -220.856337) (xy 365.438191 -220.886969)
			(xy 365.473395 -220.923417) (xy 365.502606 -220.964822) (xy 365.525138 -221.01021) (xy 365.54046 -221.058511)
			(xy 365.54821 -221.108588) (xy 365.548672 -221.133924) (xy 365.548164 -221.159811) (xy 365.540065 -221.210949)
			(xy 365.524066 -221.260189) (xy 365.50056 -221.306321) (xy 365.470128 -221.348208) (xy 365.433518 -221.384818)
			(xy 365.391631 -221.41525) (xy 365.345499 -221.438756) (xy 365.296259 -221.454755) (xy 365.245121 -221.462854)
			(xy 365.193347 -221.462854) (xy 365.142209 -221.454755) (xy 365.092969 -221.438756) (xy 365.046837 -221.41525)
			(xy 365.00495 -221.384818) (xy 364.96834 -221.348208) (xy 364.937908 -221.306321) (xy 364.914402 -221.260189)
			(xy 364.898403 -221.210949) (xy 364.890304 -221.159811) (xy 364.889796 -221.133924) (xy 364.890332 -221.106216)
			(xy 364.899523 -221.051569) (xy 364.908084 -221.025212) (xy 364.915958 -221.003114) (xy 364.71098 -220.648022)
			(xy 364.68812 -220.643704) (xy 364.663279 -220.638521) (xy 364.615432 -220.621628) (xy 364.57074 -220.5976)
			(xy 364.530259 -220.567005) (xy 364.494948 -220.530566) (xy 364.465639 -220.489145) (xy 364.443027 -220.44372)
			(xy 364.427646 -220.395365) (xy 364.419859 -220.345225) (xy 364.419388 -220.319854) (xy 363.199172 -220.319854)
			(xy 363.198563 -220.347508) (xy 363.189239 -220.402026) (xy 363.18063 -220.428312) (xy 363.17301 -220.45041)
			(xy 363.378242 -220.805756) (xy 363.401102 -220.810074) (xy 363.425908 -220.815252) (xy 363.473647 -220.832242)
			(xy 363.518225 -220.856337) (xy 363.558591 -220.886969) (xy 363.593795 -220.923417) (xy 363.623006 -220.964822)
			(xy 363.645538 -221.01021) (xy 363.66086 -221.058511) (xy 363.66861 -221.108588) (xy 363.669072 -221.133924)
			(xy 363.668564 -221.159811) (xy 363.660465 -221.210949) (xy 363.644466 -221.260189) (xy 363.62096 -221.306321)
			(xy 363.590528 -221.348208) (xy 363.553918 -221.384818) (xy 363.512031 -221.41525) (xy 363.465899 -221.438756)
			(xy 363.416659 -221.454755) (xy 363.365521 -221.462854) (xy 363.313747 -221.462854) (xy 363.262609 -221.454755)
			(xy 363.213369 -221.438756) (xy 363.167237 -221.41525) (xy 363.12535 -221.384818) (xy 363.08874 -221.348208)
			(xy 363.058308 -221.306321) (xy 363.034802 -221.260189) (xy 363.018803 -221.210949) (xy 363.010704 -221.159811)
			(xy 363.010196 -221.133924) (xy 363.010732 -221.106216) (xy 363.019923 -221.051569) (xy 363.028484 -221.025212)
			(xy 363.036358 -221.003114) (xy 362.83138 -220.648022) (xy 362.80852 -220.643704) (xy 362.783679 -220.638521)
			(xy 362.735832 -220.621628) (xy 362.69114 -220.5976) (xy 362.650659 -220.567005) (xy 362.615348 -220.530566)
			(xy 362.586039 -220.489145) (xy 362.563427 -220.44372) (xy 362.548046 -220.395365) (xy 362.540259 -220.345225)
			(xy 362.539788 -220.319854) (xy 361.319572 -220.319854) (xy 361.318963 -220.347508) (xy 361.309639 -220.402026)
			(xy 361.30103 -220.428312) (xy 361.29341 -220.45041) (xy 361.498642 -220.805756) (xy 361.521502 -220.810074)
			(xy 361.546308 -220.815252) (xy 361.594047 -220.832242) (xy 361.638625 -220.856337) (xy 361.678991 -220.886969)
			(xy 361.714195 -220.923417) (xy 361.743406 -220.964822) (xy 361.765938 -221.01021) (xy 361.78126 -221.058511)
			(xy 361.78901 -221.108588) (xy 361.789472 -221.133924) (xy 361.788964 -221.159811) (xy 361.780865 -221.210949)
			(xy 361.764866 -221.260189) (xy 361.74136 -221.306321) (xy 361.710928 -221.348208) (xy 361.674318 -221.384818)
			(xy 361.632431 -221.41525) (xy 361.586299 -221.438756) (xy 361.537059 -221.454755) (xy 361.485921 -221.462854)
			(xy 361.434147 -221.462854) (xy 361.383009 -221.454755) (xy 361.333769 -221.438756) (xy 361.287637 -221.41525)
			(xy 361.24575 -221.384818) (xy 361.20914 -221.348208) (xy 361.178708 -221.306321) (xy 361.155202 -221.260189)
			(xy 361.139203 -221.210949) (xy 361.131104 -221.159811) (xy 361.130596 -221.133924) (xy 361.131132 -221.106216)
			(xy 361.140323 -221.051569) (xy 361.148884 -221.025212) (xy 361.156758 -221.003114) (xy 360.95178 -220.648022)
			(xy 360.92892 -220.643704) (xy 360.904079 -220.638521) (xy 360.856232 -220.621628) (xy 360.81154 -220.5976)
			(xy 360.771059 -220.567005) (xy 360.735748 -220.530566) (xy 360.706439 -220.489145) (xy 360.683827 -220.44372)
			(xy 360.668446 -220.395365) (xy 360.660659 -220.345225) (xy 360.660188 -220.319854) (xy 359.439972 -220.319854)
			(xy 359.439363 -220.347508) (xy 359.430039 -220.402026) (xy 359.42143 -220.428312) (xy 359.41381 -220.45041)
			(xy 359.619042 -220.805756) (xy 359.641902 -220.810074) (xy 359.666708 -220.815252) (xy 359.714447 -220.832242)
			(xy 359.759025 -220.856337) (xy 359.799391 -220.886969) (xy 359.834595 -220.923417) (xy 359.863806 -220.964822)
			(xy 359.886338 -221.01021) (xy 359.90166 -221.058511) (xy 359.90941 -221.108588) (xy 359.909872 -221.133924)
			(xy 359.909364 -221.159811) (xy 359.901265 -221.210949) (xy 359.885266 -221.260189) (xy 359.86176 -221.306321)
			(xy 359.831328 -221.348208) (xy 359.794718 -221.384818) (xy 359.752831 -221.41525) (xy 359.706699 -221.438756)
			(xy 359.657459 -221.454755) (xy 359.606321 -221.462854) (xy 359.554547 -221.462854) (xy 359.503409 -221.454755)
			(xy 359.454169 -221.438756) (xy 359.408037 -221.41525) (xy 359.36615 -221.384818) (xy 359.32954 -221.348208)
			(xy 359.299108 -221.306321) (xy 359.275602 -221.260189) (xy 359.259603 -221.210949) (xy 359.251504 -221.159811)
			(xy 359.250996 -221.133924) (xy 359.251532 -221.106216) (xy 359.260723 -221.051569) (xy 359.269284 -221.025212)
			(xy 359.277158 -221.003114) (xy 359.07218 -220.648022) (xy 359.04932 -220.643704) (xy 359.024479 -220.638521)
			(xy 358.976632 -220.621628) (xy 358.93194 -220.5976) (xy 358.891459 -220.567005) (xy 358.856148 -220.530566)
			(xy 358.826839 -220.489145) (xy 358.804227 -220.44372) (xy 358.788846 -220.395365) (xy 358.781059 -220.345225)
			(xy 358.780588 -220.319854) (xy 357.560372 -220.319854) (xy 357.559763 -220.347508) (xy 357.550439 -220.402026)
			(xy 357.54183 -220.428312) (xy 357.53421 -220.45041) (xy 357.739442 -220.805756) (xy 357.762302 -220.810074)
			(xy 357.787108 -220.815252) (xy 357.834847 -220.832242) (xy 357.879425 -220.856337) (xy 357.919791 -220.886969)
			(xy 357.954995 -220.923417) (xy 357.984206 -220.964822) (xy 358.006738 -221.01021) (xy 358.02206 -221.058511)
			(xy 358.02981 -221.108588) (xy 358.030272 -221.133924) (xy 358.029764 -221.159811) (xy 358.021665 -221.210949)
			(xy 358.005666 -221.260189) (xy 357.98216 -221.306321) (xy 357.951728 -221.348208) (xy 357.915118 -221.384818)
			(xy 357.873231 -221.41525) (xy 357.827099 -221.438756) (xy 357.777859 -221.454755) (xy 357.726721 -221.462854)
			(xy 357.674947 -221.462854) (xy 357.623809 -221.454755) (xy 357.574569 -221.438756) (xy 357.528437 -221.41525)
			(xy 357.48655 -221.384818) (xy 357.44994 -221.348208) (xy 357.419508 -221.306321) (xy 357.396002 -221.260189)
			(xy 357.380003 -221.210949) (xy 357.371904 -221.159811) (xy 357.371396 -221.133924) (xy 357.371932 -221.106216)
			(xy 357.381123 -221.051569) (xy 357.389684 -221.025212) (xy 357.397558 -221.003114) (xy 357.19258 -220.648022)
			(xy 357.16972 -220.643704) (xy 357.144879 -220.638521) (xy 357.097032 -220.621628) (xy 357.05234 -220.5976)
			(xy 357.011859 -220.567005) (xy 356.976548 -220.530566) (xy 356.947239 -220.489145) (xy 356.924627 -220.44372)
			(xy 356.909246 -220.395365) (xy 356.901459 -220.345225) (xy 356.900988 -220.319854) (xy 355.680772 -220.319854)
			(xy 355.680163 -220.347508) (xy 355.670839 -220.402026) (xy 355.66223 -220.428312) (xy 355.65461 -220.45041)
			(xy 355.859842 -220.805756) (xy 355.882702 -220.810074) (xy 355.907508 -220.815252) (xy 355.955247 -220.832242)
			(xy 355.999825 -220.856337) (xy 356.040191 -220.886969) (xy 356.075395 -220.923417) (xy 356.104606 -220.964822)
			(xy 356.127138 -221.01021) (xy 356.14246 -221.058511) (xy 356.15021 -221.108588) (xy 356.150672 -221.133924)
			(xy 356.150164 -221.159811) (xy 356.142065 -221.210949) (xy 356.126066 -221.260189) (xy 356.10256 -221.306321)
			(xy 356.072128 -221.348208) (xy 356.035518 -221.384818) (xy 355.993631 -221.41525) (xy 355.947499 -221.438756)
			(xy 355.898259 -221.454755) (xy 355.847121 -221.462854) (xy 355.795347 -221.462854) (xy 355.744209 -221.454755)
			(xy 355.694969 -221.438756) (xy 355.648837 -221.41525) (xy 355.60695 -221.384818) (xy 355.57034 -221.348208)
			(xy 355.539908 -221.306321) (xy 355.516402 -221.260189) (xy 355.500403 -221.210949) (xy 355.492304 -221.159811)
			(xy 355.491796 -221.133924) (xy 355.492332 -221.106216) (xy 355.501523 -221.051569) (xy 355.510084 -221.025212)
			(xy 355.517958 -221.003114) (xy 355.31298 -220.648022) (xy 355.29012 -220.643704) (xy 355.265279 -220.638521)
			(xy 355.217432 -220.621628) (xy 355.17274 -220.5976) (xy 355.132259 -220.567005) (xy 355.096948 -220.530566)
			(xy 355.067639 -220.489145) (xy 355.045027 -220.44372) (xy 355.029646 -220.395365) (xy 355.021859 -220.345225)
			(xy 355.021388 -220.319854) (xy 353.801172 -220.319854) (xy 353.800563 -220.347508) (xy 353.791239 -220.402026)
			(xy 353.78263 -220.428312) (xy 353.77501 -220.45041) (xy 353.980242 -220.805756) (xy 354.003102 -220.810074)
			(xy 354.027908 -220.815252) (xy 354.075647 -220.832242) (xy 354.120225 -220.856337) (xy 354.160591 -220.886969)
			(xy 354.195795 -220.923417) (xy 354.225006 -220.964822) (xy 354.247538 -221.01021) (xy 354.26286 -221.058511)
			(xy 354.27061 -221.108588) (xy 354.271072 -221.133924) (xy 354.270564 -221.159811) (xy 354.262465 -221.210949)
			(xy 354.246466 -221.260189) (xy 354.22296 -221.306321) (xy 354.192528 -221.348208) (xy 354.155918 -221.384818)
			(xy 354.114031 -221.41525) (xy 354.067899 -221.438756) (xy 354.018659 -221.454755) (xy 353.967521 -221.462854)
			(xy 353.915747 -221.462854) (xy 353.864609 -221.454755) (xy 353.815369 -221.438756) (xy 353.769237 -221.41525)
			(xy 353.72735 -221.384818) (xy 353.69074 -221.348208) (xy 353.660308 -221.306321) (xy 353.636802 -221.260189)
			(xy 353.620803 -221.210949) (xy 353.612704 -221.159811) (xy 353.612196 -221.133924) (xy 353.612732 -221.106216)
			(xy 353.621923 -221.051569) (xy 353.630484 -221.025212) (xy 353.638358 -221.003114) (xy 353.43338 -220.648022)
			(xy 353.41052 -220.643704) (xy 353.385679 -220.638521) (xy 353.337832 -220.621628) (xy 353.29314 -220.5976)
			(xy 353.252659 -220.567005) (xy 353.217348 -220.530566) (xy 353.188039 -220.489145) (xy 353.165427 -220.44372)
			(xy 353.150046 -220.395365) (xy 353.142259 -220.345225) (xy 353.141788 -220.319854) (xy 351.921572 -220.319854)
			(xy 351.921122 -220.3452) (xy 351.913342 -220.395293) (xy 351.897988 -220.443604) (xy 351.875422 -220.488998)
			(xy 351.846176 -220.530404) (xy 351.810939 -220.566847) (xy 351.77054 -220.597469) (xy 351.725931 -220.621548)
			(xy 351.678163 -220.638518) (xy 351.653348 -220.643704) (xy 351.630488 -220.648022) (xy 351.42551 -221.003114)
			(xy 351.433384 -221.024958) (xy 351.441977 -221.051373) (xy 351.451165 -221.106151) (xy 351.451672 -221.133924)
			(xy 351.451164 -221.159811) (xy 351.443065 -221.210949) (xy 351.427066 -221.260189) (xy 351.40356 -221.306321)
			(xy 351.373128 -221.348208) (xy 351.336518 -221.384818) (xy 351.294631 -221.41525) (xy 351.248499 -221.438756)
			(xy 351.199259 -221.454755) (xy 351.148121 -221.462854) (xy 351.096347 -221.462854) (xy 351.045209 -221.454755)
			(xy 350.995969 -221.438756) (xy 350.949837 -221.41525) (xy 350.90795 -221.384818) (xy 350.87134 -221.348208)
			(xy 350.840908 -221.306321) (xy 350.817402 -221.260189) (xy 350.801403 -221.210949) (xy 350.793304 -221.159811)
			(xy 350.792796 -221.133924) (xy 350.511872 -221.133924) (xy 350.511345 -221.161632) (xy 350.502148 -221.216279)
			(xy 350.493584 -221.242636) (xy 350.48571 -221.264734) (xy 350.690688 -221.619572) (xy 350.713548 -221.62389)
			(xy 350.738367 -221.629064) (xy 350.786146 -221.646018) (xy 350.830765 -221.670088) (xy 350.871172 -221.700708)
			(xy 350.906413 -221.737154) (xy 350.935657 -221.778566) (xy 350.958214 -221.823969) (xy 350.973552 -221.872291)
			(xy 350.98131 -221.922391) (xy 350.981772 -221.94774) (xy 352.201988 -221.94774) (xy 352.202465 -221.922395)
			(xy 352.210245 -221.872306) (xy 352.225597 -221.823996) (xy 352.24816 -221.778605) (xy 352.277403 -221.7372)
			(xy 352.312637 -221.700757) (xy 352.353031 -221.670134) (xy 352.397636 -221.646052) (xy 352.445399 -221.629078)
			(xy 352.470212 -221.62389) (xy 352.493072 -221.619572) (xy 352.698304 -221.264226) (xy 352.69043 -221.242128)
			(xy 352.681965 -221.215883) (xy 352.672893 -221.161495) (xy 352.672396 -221.133924) (xy 352.672904 -221.108037)
			(xy 352.681003 -221.056899) (xy 352.697002 -221.007659) (xy 352.720508 -220.961527) (xy 352.75094 -220.91964)
			(xy 352.78755 -220.88303) (xy 352.829437 -220.852598) (xy 352.875569 -220.829092) (xy 352.924809 -220.813093)
			(xy 352.975947 -220.804994) (xy 353.027721 -220.804994) (xy 353.078859 -220.813093) (xy 353.128099 -220.829092)
			(xy 353.174231 -220.852598) (xy 353.216118 -220.88303) (xy 353.252728 -220.91964) (xy 353.28316 -220.961527)
			(xy 353.306666 -221.007659) (xy 353.322665 -221.056899) (xy 353.330764 -221.108037) (xy 353.331272 -221.133924)
			(xy 353.330842 -221.1593) (xy 353.323069 -221.209454) (xy 353.307696 -221.257821) (xy 353.285086 -221.303259)
			(xy 353.255774 -221.344691) (xy 353.220455 -221.381137) (xy 353.179963 -221.411734) (xy 353.135258 -221.435759)
			(xy 353.087396 -221.452643) (xy 353.06254 -221.457774) (xy 353.03968 -221.462092) (xy 352.834956 -221.81693)
			(xy 352.84283 -221.838774) (xy 352.851486 -221.865179) (xy 352.8608 -221.919958) (xy 352.861372 -221.94774)
			(xy 354.081588 -221.94774) (xy 354.082065 -221.922395) (xy 354.089845 -221.872306) (xy 354.105197 -221.823996)
			(xy 354.12776 -221.778605) (xy 354.157003 -221.7372) (xy 354.192237 -221.700757) (xy 354.232631 -221.670134)
			(xy 354.277236 -221.646052) (xy 354.324999 -221.629078) (xy 354.349812 -221.62389) (xy 354.372672 -221.619572)
			(xy 354.577904 -221.264226) (xy 354.57003 -221.242128) (xy 354.561565 -221.215883) (xy 354.552493 -221.161495)
			(xy 354.551996 -221.133924) (xy 354.552504 -221.108037) (xy 354.560603 -221.056899) (xy 354.576602 -221.007659)
			(xy 354.600108 -220.961527) (xy 354.63054 -220.91964) (xy 354.66715 -220.88303) (xy 354.709037 -220.852598)
			(xy 354.755169 -220.829092) (xy 354.804409 -220.813093) (xy 354.855547 -220.804994) (xy 354.907321 -220.804994)
			(xy 354.958459 -220.813093) (xy 355.007699 -220.829092) (xy 355.053831 -220.852598) (xy 355.095718 -220.88303)
			(xy 355.132328 -220.91964) (xy 355.16276 -220.961527) (xy 355.186266 -221.007659) (xy 355.202265 -221.056899)
			(xy 355.210364 -221.108037) (xy 355.210872 -221.133924) (xy 355.210442 -221.1593) (xy 355.202669 -221.209454)
			(xy 355.187296 -221.257821) (xy 355.164686 -221.303259) (xy 355.135374 -221.344691) (xy 355.100055 -221.381137)
			(xy 355.059563 -221.411734) (xy 355.014858 -221.435759) (xy 354.966996 -221.452643) (xy 354.94214 -221.457774)
			(xy 354.91928 -221.462092) (xy 354.714556 -221.81693) (xy 354.72243 -221.838774) (xy 354.731086 -221.865179)
			(xy 354.7404 -221.919958) (xy 354.740972 -221.94774) (xy 355.961188 -221.94774) (xy 355.961665 -221.922395)
			(xy 355.969445 -221.872306) (xy 355.984797 -221.823996) (xy 356.00736 -221.778605) (xy 356.036603 -221.7372)
			(xy 356.071837 -221.700757) (xy 356.112231 -221.670134) (xy 356.156836 -221.646052) (xy 356.204599 -221.629078)
			(xy 356.229412 -221.62389) (xy 356.252272 -221.619572) (xy 356.457504 -221.264226) (xy 356.44963 -221.242128)
			(xy 356.441165 -221.215883) (xy 356.432093 -221.161495) (xy 356.431596 -221.133924) (xy 356.432104 -221.108037)
			(xy 356.440203 -221.056899) (xy 356.456202 -221.007659) (xy 356.479708 -220.961527) (xy 356.51014 -220.91964)
			(xy 356.54675 -220.88303) (xy 356.588637 -220.852598) (xy 356.634769 -220.829092) (xy 356.684009 -220.813093)
			(xy 356.735147 -220.804994) (xy 356.786921 -220.804994) (xy 356.838059 -220.813093) (xy 356.887299 -220.829092)
			(xy 356.933431 -220.852598) (xy 356.975318 -220.88303) (xy 357.011928 -220.91964) (xy 357.04236 -220.961527)
			(xy 357.065866 -221.007659) (xy 357.081865 -221.056899) (xy 357.089964 -221.108037) (xy 357.090472 -221.133924)
			(xy 357.090042 -221.1593) (xy 357.082269 -221.209454) (xy 357.066896 -221.257821) (xy 357.044286 -221.303259)
			(xy 357.014974 -221.344691) (xy 356.979655 -221.381137) (xy 356.939163 -221.411734) (xy 356.894458 -221.435759)
			(xy 356.846596 -221.452643) (xy 356.82174 -221.457774) (xy 356.79888 -221.462092) (xy 356.594156 -221.81693)
			(xy 356.60203 -221.838774) (xy 356.610686 -221.865179) (xy 356.62 -221.919958) (xy 356.620572 -221.94774)
			(xy 357.841296 -221.94774) (xy 357.841727 -221.922404) (xy 357.849489 -221.872329) (xy 357.864819 -221.824032)
			(xy 357.887358 -221.778648) (xy 357.916574 -221.737246) (xy 357.95178 -221.700802) (xy 357.992148 -221.670172)
			(xy 358.036725 -221.646079) (xy 358.084465 -221.629089) (xy 358.109266 -221.62389) (xy 358.132126 -221.619572)
			(xy 358.337104 -221.26448) (xy 358.329484 -221.242382) (xy 358.320964 -221.216211) (xy 358.311771 -221.161949)
			(xy 358.311196 -221.134432) (xy 358.311196 -221.133924) (xy 358.311704 -221.108037) (xy 358.319803 -221.056899)
			(xy 358.335802 -221.007659) (xy 358.359308 -220.961527) (xy 358.38974 -220.91964) (xy 358.42635 -220.88303)
			(xy 358.468237 -220.852598) (xy 358.514369 -220.829092) (xy 358.563609 -220.813093) (xy 358.614747 -220.804994)
			(xy 358.666521 -220.804994) (xy 358.717659 -220.813093) (xy 358.766899 -220.829092) (xy 358.813031 -220.852598)
			(xy 358.854918 -220.88303) (xy 358.891528 -220.91964) (xy 358.92196 -220.961527) (xy 358.945466 -221.007659)
			(xy 358.961465 -221.056899) (xy 358.969564 -221.108037) (xy 358.970072 -221.133924) (xy 358.969679 -221.159291)
			(xy 358.961926 -221.209429) (xy 358.946575 -221.257784) (xy 358.923991 -221.303213) (xy 358.894706 -221.344642)
			(xy 358.859415 -221.381089) (xy 358.818952 -221.411694) (xy 358.774274 -221.435731) (xy 358.726438 -221.452632)
			(xy 358.701594 -221.457774) (xy 358.678734 -221.462092) (xy 358.47401 -221.81693) (xy 358.481884 -221.838774)
			(xy 358.490481 -221.865188) (xy 358.499666 -221.919967) (xy 358.500172 -221.94774) (xy 359.720388 -221.94774)
			(xy 359.720865 -221.922395) (xy 359.728645 -221.872306) (xy 359.743997 -221.823996) (xy 359.76656 -221.778605)
			(xy 359.795803 -221.7372) (xy 359.831037 -221.700757) (xy 359.871431 -221.670134) (xy 359.916036 -221.646052)
			(xy 359.963799 -221.629078) (xy 359.988612 -221.62389) (xy 360.011472 -221.619572) (xy 360.216704 -221.264226)
			(xy 360.20883 -221.242128) (xy 360.200365 -221.215883) (xy 360.191293 -221.161495) (xy 360.190796 -221.133924)
			(xy 360.191304 -221.108037) (xy 360.199403 -221.056899) (xy 360.215402 -221.007659) (xy 360.238908 -220.961527)
			(xy 360.26934 -220.91964) (xy 360.30595 -220.88303) (xy 360.347837 -220.852598) (xy 360.393969 -220.829092)
			(xy 360.443209 -220.813093) (xy 360.494347 -220.804994) (xy 360.546121 -220.804994) (xy 360.597259 -220.813093)
			(xy 360.646499 -220.829092) (xy 360.692631 -220.852598) (xy 360.734518 -220.88303) (xy 360.771128 -220.91964)
			(xy 360.80156 -220.961527) (xy 360.825066 -221.007659) (xy 360.841065 -221.056899) (xy 360.849164 -221.108037)
			(xy 360.849672 -221.133924) (xy 360.849242 -221.1593) (xy 360.841469 -221.209454) (xy 360.826096 -221.257821)
			(xy 360.803486 -221.303259) (xy 360.774174 -221.344691) (xy 360.738855 -221.381137) (xy 360.698363 -221.411734)
			(xy 360.653658 -221.435759) (xy 360.605796 -221.452643) (xy 360.58094 -221.457774) (xy 360.55808 -221.462092)
			(xy 360.353356 -221.81693) (xy 360.36123 -221.838774) (xy 360.369886 -221.865179) (xy 360.3792 -221.919958)
			(xy 360.379772 -221.94774) (xy 361.600496 -221.94774) (xy 361.600927 -221.922404) (xy 361.608689 -221.872329)
			(xy 361.624019 -221.824032) (xy 361.646558 -221.778648) (xy 361.675774 -221.737246) (xy 361.71098 -221.700802)
			(xy 361.751348 -221.670172) (xy 361.795925 -221.646079) (xy 361.843665 -221.629089) (xy 361.868466 -221.62389)
			(xy 361.891326 -221.619572) (xy 362.096304 -221.26448) (xy 362.088684 -221.242382) (xy 362.080164 -221.216211)
			(xy 362.070971 -221.161949) (xy 362.070396 -221.134432) (xy 362.070396 -221.133924) (xy 362.070904 -221.108037)
			(xy 362.079003 -221.056899) (xy 362.095002 -221.007659) (xy 362.118508 -220.961527) (xy 362.14894 -220.91964)
			(xy 362.18555 -220.88303) (xy 362.227437 -220.852598) (xy 362.273569 -220.829092) (xy 362.322809 -220.813093)
			(xy 362.373947 -220.804994) (xy 362.425721 -220.804994) (xy 362.476859 -220.813093) (xy 362.526099 -220.829092)
			(xy 362.572231 -220.852598) (xy 362.614118 -220.88303) (xy 362.650728 -220.91964) (xy 362.68116 -220.961527)
			(xy 362.704666 -221.007659) (xy 362.720665 -221.056899) (xy 362.728764 -221.108037) (xy 362.729272 -221.133924)
			(xy 362.728879 -221.159291) (xy 362.721126 -221.209429) (xy 362.705775 -221.257784) (xy 362.683191 -221.303213)
			(xy 362.653906 -221.344642) (xy 362.618615 -221.381089) (xy 362.578152 -221.411694) (xy 362.533474 -221.435731)
			(xy 362.485638 -221.452632) (xy 362.460794 -221.457774) (xy 362.437934 -221.462092) (xy 362.23321 -221.81693)
			(xy 362.241084 -221.838774) (xy 362.249681 -221.865188) (xy 362.258866 -221.919967) (xy 362.259372 -221.94774)
			(xy 363.479588 -221.94774) (xy 363.480065 -221.922395) (xy 363.487845 -221.872306) (xy 363.503197 -221.823996)
			(xy 363.52576 -221.778605) (xy 363.555003 -221.7372) (xy 363.590237 -221.700757) (xy 363.630631 -221.670134)
			(xy 363.675236 -221.646052) (xy 363.722999 -221.629078) (xy 363.747812 -221.62389) (xy 363.770672 -221.619572)
			(xy 363.975904 -221.264226) (xy 363.96803 -221.242128) (xy 363.959565 -221.215883) (xy 363.950493 -221.161495)
			(xy 363.949996 -221.133924) (xy 363.950504 -221.108037) (xy 363.958603 -221.056899) (xy 363.974602 -221.007659)
			(xy 363.998108 -220.961527) (xy 364.02854 -220.91964) (xy 364.06515 -220.88303) (xy 364.107037 -220.852598)
			(xy 364.153169 -220.829092) (xy 364.202409 -220.813093) (xy 364.253547 -220.804994) (xy 364.305321 -220.804994)
			(xy 364.356459 -220.813093) (xy 364.405699 -220.829092) (xy 364.451831 -220.852598) (xy 364.493718 -220.88303)
			(xy 364.530328 -220.91964) (xy 364.56076 -220.961527) (xy 364.584266 -221.007659) (xy 364.600265 -221.056899)
			(xy 364.608364 -221.108037) (xy 364.608872 -221.133924) (xy 364.608442 -221.1593) (xy 364.600669 -221.209454)
			(xy 364.585296 -221.257821) (xy 364.562686 -221.303259) (xy 364.533374 -221.344691) (xy 364.498055 -221.381137)
			(xy 364.457563 -221.411734) (xy 364.412858 -221.435759) (xy 364.364996 -221.452643) (xy 364.34014 -221.457774)
			(xy 364.31728 -221.462092) (xy 364.112556 -221.81693) (xy 364.12043 -221.838774) (xy 364.129086 -221.865179)
			(xy 364.1384 -221.919958) (xy 364.138972 -221.94774) (xy 365.359188 -221.94774) (xy 365.359665 -221.922395)
			(xy 365.367445 -221.872306) (xy 365.382797 -221.823996) (xy 365.40536 -221.778605) (xy 365.434603 -221.7372)
			(xy 365.469837 -221.700757) (xy 365.510231 -221.670134) (xy 365.554836 -221.646052) (xy 365.602599 -221.629078)
			(xy 365.627412 -221.62389) (xy 365.650272 -221.619572) (xy 365.855504 -221.264226) (xy 365.84763 -221.242128)
			(xy 365.839165 -221.215883) (xy 365.830093 -221.161495) (xy 365.829596 -221.133924) (xy 365.830104 -221.108037)
			(xy 365.838203 -221.056899) (xy 365.854202 -221.007659) (xy 365.877708 -220.961527) (xy 365.90814 -220.91964)
			(xy 365.94475 -220.88303) (xy 365.986637 -220.852598) (xy 366.032769 -220.829092) (xy 366.082009 -220.813093)
			(xy 366.133147 -220.804994) (xy 366.184921 -220.804994) (xy 366.236059 -220.813093) (xy 366.285299 -220.829092)
			(xy 366.331431 -220.852598) (xy 366.373318 -220.88303) (xy 366.409928 -220.91964) (xy 366.44036 -220.961527)
			(xy 366.463866 -221.007659) (xy 366.479865 -221.056899) (xy 366.487964 -221.108037) (xy 366.488472 -221.133924)
			(xy 366.488042 -221.1593) (xy 366.480269 -221.209454) (xy 366.464896 -221.257821) (xy 366.442286 -221.303259)
			(xy 366.412974 -221.344691) (xy 366.377655 -221.381137) (xy 366.337163 -221.411734) (xy 366.292458 -221.435759)
			(xy 366.244596 -221.452643) (xy 366.21974 -221.457774) (xy 366.19688 -221.462092) (xy 365.992156 -221.81693)
			(xy 366.00003 -221.838774) (xy 366.008686 -221.865179) (xy 366.018 -221.919958) (xy 366.018572 -221.94774)
			(xy 369.118388 -221.94774) (xy 369.118865 -221.922395) (xy 369.126645 -221.872306) (xy 369.141997 -221.823996)
			(xy 369.16456 -221.778605) (xy 369.193803 -221.7372) (xy 369.229037 -221.700757) (xy 369.269431 -221.670134)
			(xy 369.314036 -221.646052) (xy 369.361799 -221.629078) (xy 369.386612 -221.62389) (xy 369.409472 -221.619572)
			(xy 369.614704 -221.264226) (xy 369.60683 -221.242128) (xy 369.598365 -221.215883) (xy 369.589293 -221.161495)
			(xy 369.588796 -221.133924) (xy 369.589304 -221.108037) (xy 369.597403 -221.056899) (xy 369.613402 -221.007659)
			(xy 369.636908 -220.961527) (xy 369.66734 -220.91964) (xy 369.70395 -220.88303) (xy 369.745837 -220.852598)
			(xy 369.791969 -220.829092) (xy 369.841209 -220.813093) (xy 369.892347 -220.804994) (xy 369.944121 -220.804994)
			(xy 369.995259 -220.813093) (xy 370.044499 -220.829092) (xy 370.090631 -220.852598) (xy 370.132518 -220.88303)
			(xy 370.169128 -220.91964) (xy 370.19956 -220.961527) (xy 370.223066 -221.007659) (xy 370.239065 -221.056899)
			(xy 370.247164 -221.108037) (xy 370.247672 -221.133924) (xy 370.247242 -221.1593) (xy 370.239469 -221.209454)
			(xy 370.224096 -221.257821) (xy 370.201486 -221.303259) (xy 370.172174 -221.344691) (xy 370.136855 -221.381137)
			(xy 370.096363 -221.411734) (xy 370.051658 -221.435759) (xy 370.003796 -221.452643) (xy 369.97894 -221.457774)
			(xy 369.95608 -221.462092) (xy 369.751356 -221.81693) (xy 369.75923 -221.838774) (xy 369.767886 -221.865179)
			(xy 369.7772 -221.919958) (xy 369.777772 -221.94774) (xy 370.997988 -221.94774) (xy 370.998465 -221.922395)
			(xy 371.006245 -221.872306) (xy 371.021597 -221.823996) (xy 371.04416 -221.778605) (xy 371.073403 -221.7372)
			(xy 371.108637 -221.700757) (xy 371.149031 -221.670134) (xy 371.193636 -221.646052) (xy 371.241399 -221.629078)
			(xy 371.266212 -221.62389) (xy 371.289072 -221.619572) (xy 371.494304 -221.264226) (xy 371.48643 -221.242128)
			(xy 371.477965 -221.215883) (xy 371.468893 -221.161495) (xy 371.468396 -221.133924) (xy 371.468904 -221.108037)
			(xy 371.477003 -221.056899) (xy 371.493002 -221.007659) (xy 371.516508 -220.961527) (xy 371.54694 -220.91964)
			(xy 371.58355 -220.88303) (xy 371.625437 -220.852598) (xy 371.671569 -220.829092) (xy 371.720809 -220.813093)
			(xy 371.771947 -220.804994) (xy 371.823721 -220.804994) (xy 371.874859 -220.813093) (xy 371.924099 -220.829092)
			(xy 371.970231 -220.852598) (xy 372.012118 -220.88303) (xy 372.048728 -220.91964) (xy 372.07916 -220.961527)
			(xy 372.102666 -221.007659) (xy 372.118665 -221.056899) (xy 372.126764 -221.108037) (xy 372.127272 -221.133924)
			(xy 372.126842 -221.1593) (xy 372.119069 -221.209454) (xy 372.103696 -221.257821) (xy 372.081086 -221.303259)
			(xy 372.051774 -221.344691) (xy 372.016455 -221.381137) (xy 371.975963 -221.411734) (xy 371.931258 -221.435759)
			(xy 371.883396 -221.452643) (xy 371.85854 -221.457774) (xy 371.83568 -221.462092) (xy 371.630956 -221.81693)
			(xy 371.63883 -221.838774) (xy 371.647486 -221.865179) (xy 371.6568 -221.919958) (xy 371.657372 -221.94774)
			(xy 372.877588 -221.94774) (xy 372.878065 -221.922395) (xy 372.885845 -221.872306) (xy 372.901197 -221.823996)
			(xy 372.92376 -221.778605) (xy 372.953003 -221.7372) (xy 372.988237 -221.700757) (xy 373.028631 -221.670134)
			(xy 373.073236 -221.646052) (xy 373.120999 -221.629078) (xy 373.145812 -221.62389) (xy 373.168672 -221.619572)
			(xy 373.373904 -221.264226) (xy 373.36603 -221.242128) (xy 373.357565 -221.215883) (xy 373.348493 -221.161495)
			(xy 373.347996 -221.133924) (xy 373.348504 -221.108037) (xy 373.356603 -221.056899) (xy 373.372602 -221.007659)
			(xy 373.396108 -220.961527) (xy 373.42654 -220.91964) (xy 373.46315 -220.88303) (xy 373.505037 -220.852598)
			(xy 373.551169 -220.829092) (xy 373.600409 -220.813093) (xy 373.651547 -220.804994) (xy 373.703321 -220.804994)
			(xy 373.754459 -220.813093) (xy 373.803699 -220.829092) (xy 373.849831 -220.852598) (xy 373.891718 -220.88303)
			(xy 373.928328 -220.91964) (xy 373.95876 -220.961527) (xy 373.982266 -221.007659) (xy 373.998265 -221.056899)
			(xy 374.006364 -221.108037) (xy 374.006872 -221.133924) (xy 374.006442 -221.1593) (xy 373.998669 -221.209454)
			(xy 373.983296 -221.257821) (xy 373.960686 -221.303259) (xy 373.931374 -221.344691) (xy 373.896055 -221.381137)
			(xy 373.855563 -221.411734) (xy 373.810858 -221.435759) (xy 373.762996 -221.452643) (xy 373.73814 -221.457774)
			(xy 373.71528 -221.462092) (xy 373.510556 -221.81693) (xy 373.51843 -221.838774) (xy 373.527086 -221.865179)
			(xy 373.5364 -221.919958) (xy 373.536972 -221.94774) (xy 374.757188 -221.94774) (xy 374.757665 -221.922395)
			(xy 374.765445 -221.872306) (xy 374.780797 -221.823996) (xy 374.80336 -221.778605) (xy 374.832603 -221.7372)
			(xy 374.867837 -221.700757) (xy 374.908231 -221.670134) (xy 374.952836 -221.646052) (xy 375.000599 -221.629078)
			(xy 375.025412 -221.62389) (xy 375.048272 -221.619572) (xy 375.253504 -221.264226) (xy 375.24563 -221.242128)
			(xy 375.237165 -221.215883) (xy 375.228093 -221.161495) (xy 375.227596 -221.133924) (xy 375.228104 -221.108037)
			(xy 375.236203 -221.056899) (xy 375.252202 -221.007659) (xy 375.275708 -220.961527) (xy 375.30614 -220.91964)
			(xy 375.34275 -220.88303) (xy 375.384637 -220.852598) (xy 375.430769 -220.829092) (xy 375.480009 -220.813093)
			(xy 375.531147 -220.804994) (xy 375.582921 -220.804994) (xy 375.634059 -220.813093) (xy 375.683299 -220.829092)
			(xy 375.729431 -220.852598) (xy 375.771318 -220.88303) (xy 375.807928 -220.91964) (xy 375.83836 -220.961527)
			(xy 375.861866 -221.007659) (xy 375.877865 -221.056899) (xy 375.885964 -221.108037) (xy 375.886472 -221.133924)
			(xy 375.886042 -221.1593) (xy 375.878269 -221.209454) (xy 375.862896 -221.257821) (xy 375.840286 -221.303259)
			(xy 375.810974 -221.344691) (xy 375.775655 -221.381137) (xy 375.735163 -221.411734) (xy 375.690458 -221.435759)
			(xy 375.642596 -221.452643) (xy 375.61774 -221.457774) (xy 375.59488 -221.462092) (xy 375.390156 -221.81693)
			(xy 375.39803 -221.838774) (xy 375.406686 -221.865179) (xy 375.416 -221.919958) (xy 375.416572 -221.94774)
			(xy 376.636788 -221.94774) (xy 376.637265 -221.922395) (xy 376.645045 -221.872306) (xy 376.660397 -221.823996)
			(xy 376.68296 -221.778605) (xy 376.712203 -221.7372) (xy 376.747437 -221.700757) (xy 376.787831 -221.670134)
			(xy 376.832436 -221.646052) (xy 376.880199 -221.629078) (xy 376.905012 -221.62389) (xy 376.927872 -221.619572)
			(xy 377.133104 -221.264226) (xy 377.12523 -221.242128) (xy 377.116765 -221.215883) (xy 377.107693 -221.161495)
			(xy 377.107196 -221.133924) (xy 377.107704 -221.108037) (xy 377.115803 -221.056899) (xy 377.131802 -221.007659)
			(xy 377.155308 -220.961527) (xy 377.18574 -220.91964) (xy 377.22235 -220.88303) (xy 377.264237 -220.852598)
			(xy 377.310369 -220.829092) (xy 377.359609 -220.813093) (xy 377.410747 -220.804994) (xy 377.462521 -220.804994)
			(xy 377.513659 -220.813093) (xy 377.562899 -220.829092) (xy 377.609031 -220.852598) (xy 377.650918 -220.88303)
			(xy 377.687528 -220.91964) (xy 377.71796 -220.961527) (xy 377.741466 -221.007659) (xy 377.757465 -221.056899)
			(xy 377.765564 -221.108037) (xy 377.766072 -221.133924) (xy 377.765642 -221.1593) (xy 377.757869 -221.209454)
			(xy 377.742496 -221.257821) (xy 377.719886 -221.303259) (xy 377.690574 -221.344691) (xy 377.655255 -221.381137)
			(xy 377.614763 -221.411734) (xy 377.570058 -221.435759) (xy 377.522196 -221.452643) (xy 377.49734 -221.457774)
			(xy 377.47448 -221.462092) (xy 377.269756 -221.81693) (xy 377.27763 -221.838774) (xy 377.286286 -221.865179)
			(xy 377.2956 -221.919958) (xy 377.296172 -221.94774) (xy 378.516388 -221.94774) (xy 378.516865 -221.922395)
			(xy 378.524645 -221.872306) (xy 378.539997 -221.823996) (xy 378.56256 -221.778605) (xy 378.591803 -221.7372)
			(xy 378.627037 -221.700757) (xy 378.667431 -221.670134) (xy 378.712036 -221.646052) (xy 378.759799 -221.629078)
			(xy 378.784612 -221.62389) (xy 378.807472 -221.619572) (xy 379.012704 -221.264226) (xy 379.00483 -221.242128)
			(xy 378.996365 -221.215883) (xy 378.987293 -221.161495) (xy 378.986796 -221.133924) (xy 378.987304 -221.108037)
			(xy 378.995403 -221.056899) (xy 379.011402 -221.007659) (xy 379.034908 -220.961527) (xy 379.06534 -220.91964)
			(xy 379.10195 -220.88303) (xy 379.143837 -220.852598) (xy 379.189969 -220.829092) (xy 379.239209 -220.813093)
			(xy 379.290347 -220.804994) (xy 379.342121 -220.804994) (xy 379.393259 -220.813093) (xy 379.442499 -220.829092)
			(xy 379.488631 -220.852598) (xy 379.530518 -220.88303) (xy 379.567128 -220.91964) (xy 379.59756 -220.961527)
			(xy 379.621066 -221.007659) (xy 379.637065 -221.056899) (xy 379.645164 -221.108037) (xy 379.645672 -221.133924)
			(xy 379.645242 -221.1593) (xy 379.637469 -221.209454) (xy 379.622096 -221.257821) (xy 379.599486 -221.303259)
			(xy 379.570174 -221.344691) (xy 379.534855 -221.381137) (xy 379.494363 -221.411734) (xy 379.449658 -221.435759)
			(xy 379.401796 -221.452643) (xy 379.37694 -221.457774) (xy 379.35408 -221.462092) (xy 379.149356 -221.81693)
			(xy 379.15723 -221.838774) (xy 379.165886 -221.865179) (xy 379.1752 -221.919958) (xy 379.175772 -221.94774)
			(xy 379.175264 -221.973647) (xy 379.167158 -222.024824) (xy 379.151146 -222.074103) (xy 379.127623 -222.12027)
			(xy 379.097167 -222.162189) (xy 379.060529 -222.198827) (xy 379.01861 -222.229283) (xy 378.972443 -222.252806)
			(xy 378.923164 -222.268818) (xy 378.871987 -222.276924) (xy 378.820173 -222.276924) (xy 378.768996 -222.268818)
			(xy 378.719717 -222.252806) (xy 378.67355 -222.229283) (xy 378.631631 -222.198827) (xy 378.594993 -222.162189)
			(xy 378.564537 -222.12027) (xy 378.541014 -222.074103) (xy 378.525002 -222.024824) (xy 378.516896 -221.973647)
			(xy 378.516388 -221.94774) (xy 377.296172 -221.94774) (xy 377.295664 -221.973647) (xy 377.287558 -222.024824)
			(xy 377.271546 -222.074103) (xy 377.248023 -222.12027) (xy 377.217567 -222.162189) (xy 377.180929 -222.198827)
			(xy 377.13901 -222.229283) (xy 377.092843 -222.252806) (xy 377.043564 -222.268818) (xy 376.992387 -222.276924)
			(xy 376.940573 -222.276924) (xy 376.889396 -222.268818) (xy 376.840117 -222.252806) (xy 376.79395 -222.229283)
			(xy 376.752031 -222.198827) (xy 376.715393 -222.162189) (xy 376.684937 -222.12027) (xy 376.661414 -222.074103)
			(xy 376.645402 -222.024824) (xy 376.637296 -221.973647) (xy 376.636788 -221.94774) (xy 375.416572 -221.94774)
			(xy 375.416064 -221.973647) (xy 375.407958 -222.024824) (xy 375.391946 -222.074103) (xy 375.368423 -222.12027)
			(xy 375.337967 -222.162189) (xy 375.301329 -222.198827) (xy 375.25941 -222.229283) (xy 375.213243 -222.252806)
			(xy 375.163964 -222.268818) (xy 375.112787 -222.276924) (xy 375.060973 -222.276924) (xy 375.009796 -222.268818)
			(xy 374.960517 -222.252806) (xy 374.91435 -222.229283) (xy 374.872431 -222.198827) (xy 374.835793 -222.162189)
			(xy 374.805337 -222.12027) (xy 374.781814 -222.074103) (xy 374.765802 -222.024824) (xy 374.757696 -221.973647)
			(xy 374.757188 -221.94774) (xy 373.536972 -221.94774) (xy 373.536464 -221.973647) (xy 373.528358 -222.024824)
			(xy 373.512346 -222.074103) (xy 373.488823 -222.12027) (xy 373.458367 -222.162189) (xy 373.421729 -222.198827)
			(xy 373.37981 -222.229283) (xy 373.333643 -222.252806) (xy 373.284364 -222.268818) (xy 373.233187 -222.276924)
			(xy 373.181373 -222.276924) (xy 373.130196 -222.268818) (xy 373.080917 -222.252806) (xy 373.03475 -222.229283)
			(xy 372.992831 -222.198827) (xy 372.956193 -222.162189) (xy 372.925737 -222.12027) (xy 372.902214 -222.074103)
			(xy 372.886202 -222.024824) (xy 372.878096 -221.973647) (xy 372.877588 -221.94774) (xy 371.657372 -221.94774)
			(xy 371.656864 -221.973647) (xy 371.648758 -222.024824) (xy 371.632746 -222.074103) (xy 371.609223 -222.12027)
			(xy 371.578767 -222.162189) (xy 371.542129 -222.198827) (xy 371.50021 -222.229283) (xy 371.454043 -222.252806)
			(xy 371.404764 -222.268818) (xy 371.353587 -222.276924) (xy 371.301773 -222.276924) (xy 371.250596 -222.268818)
			(xy 371.201317 -222.252806) (xy 371.15515 -222.229283) (xy 371.113231 -222.198827) (xy 371.076593 -222.162189)
			(xy 371.046137 -222.12027) (xy 371.022614 -222.074103) (xy 371.006602 -222.024824) (xy 370.998496 -221.973647)
			(xy 370.997988 -221.94774) (xy 369.777772 -221.94774) (xy 369.777264 -221.973647) (xy 369.769158 -222.024824)
			(xy 369.753146 -222.074103) (xy 369.729623 -222.12027) (xy 369.699167 -222.162189) (xy 369.662529 -222.198827)
			(xy 369.62061 -222.229283) (xy 369.574443 -222.252806) (xy 369.525164 -222.268818) (xy 369.473987 -222.276924)
			(xy 369.422173 -222.276924) (xy 369.370996 -222.268818) (xy 369.321717 -222.252806) (xy 369.27555 -222.229283)
			(xy 369.233631 -222.198827) (xy 369.196993 -222.162189) (xy 369.166537 -222.12027) (xy 369.143014 -222.074103)
			(xy 369.127002 -222.024824) (xy 369.118896 -221.973647) (xy 369.118388 -221.94774) (xy 366.018572 -221.94774)
			(xy 366.018064 -221.973647) (xy 366.009958 -222.024824) (xy 365.993946 -222.074103) (xy 365.970423 -222.12027)
			(xy 365.939967 -222.162189) (xy 365.903329 -222.198827) (xy 365.86141 -222.229283) (xy 365.815243 -222.252806)
			(xy 365.765964 -222.268818) (xy 365.714787 -222.276924) (xy 365.662973 -222.276924) (xy 365.611796 -222.268818)
			(xy 365.562517 -222.252806) (xy 365.51635 -222.229283) (xy 365.474431 -222.198827) (xy 365.437793 -222.162189)
			(xy 365.407337 -222.12027) (xy 365.383814 -222.074103) (xy 365.367802 -222.024824) (xy 365.359696 -221.973647)
			(xy 365.359188 -221.94774) (xy 364.138972 -221.94774) (xy 364.138464 -221.973647) (xy 364.130358 -222.024824)
			(xy 364.114346 -222.074103) (xy 364.090823 -222.12027) (xy 364.060367 -222.162189) (xy 364.023729 -222.198827)
			(xy 363.98181 -222.229283) (xy 363.935643 -222.252806) (xy 363.886364 -222.268818) (xy 363.835187 -222.276924)
			(xy 363.783373 -222.276924) (xy 363.732196 -222.268818) (xy 363.682917 -222.252806) (xy 363.63675 -222.229283)
			(xy 363.594831 -222.198827) (xy 363.558193 -222.162189) (xy 363.527737 -222.12027) (xy 363.504214 -222.074103)
			(xy 363.488202 -222.024824) (xy 363.480096 -221.973647) (xy 363.479588 -221.94774) (xy 362.259372 -221.94774)
			(xy 362.258864 -221.973627) (xy 362.250765 -222.024765) (xy 362.234766 -222.074005) (xy 362.21126 -222.120137)
			(xy 362.180828 -222.162024) (xy 362.144218 -222.198634) (xy 362.102331 -222.229066) (xy 362.056199 -222.252572)
			(xy 362.006959 -222.268571) (xy 361.955821 -222.27667) (xy 361.904047 -222.27667) (xy 361.852909 -222.268571)
			(xy 361.803669 -222.252572) (xy 361.757537 -222.229066) (xy 361.71565 -222.198634) (xy 361.67904 -222.162024)
			(xy 361.648608 -222.120137) (xy 361.625102 -222.074005) (xy 361.609103 -222.024765) (xy 361.601004 -221.973627)
			(xy 361.600496 -221.94774) (xy 360.379772 -221.94774) (xy 360.379264 -221.973647) (xy 360.371158 -222.024824)
			(xy 360.355146 -222.074103) (xy 360.331623 -222.12027) (xy 360.301167 -222.162189) (xy 360.264529 -222.198827)
			(xy 360.22261 -222.229283) (xy 360.176443 -222.252806) (xy 360.127164 -222.268818) (xy 360.075987 -222.276924)
			(xy 360.024173 -222.276924) (xy 359.972996 -222.268818) (xy 359.923717 -222.252806) (xy 359.87755 -222.229283)
			(xy 359.835631 -222.198827) (xy 359.798993 -222.162189) (xy 359.768537 -222.12027) (xy 359.745014 -222.074103)
			(xy 359.729002 -222.024824) (xy 359.720896 -221.973647) (xy 359.720388 -221.94774) (xy 358.500172 -221.94774)
			(xy 358.499664 -221.973627) (xy 358.491565 -222.024765) (xy 358.475566 -222.074005) (xy 358.45206 -222.120137)
			(xy 358.421628 -222.162024) (xy 358.385018 -222.198634) (xy 358.343131 -222.229066) (xy 358.296999 -222.252572)
			(xy 358.247759 -222.268571) (xy 358.196621 -222.27667) (xy 358.144847 -222.27667) (xy 358.093709 -222.268571)
			(xy 358.044469 -222.252572) (xy 357.998337 -222.229066) (xy 357.95645 -222.198634) (xy 357.91984 -222.162024)
			(xy 357.889408 -222.120137) (xy 357.865902 -222.074005) (xy 357.849903 -222.024765) (xy 357.841804 -221.973627)
			(xy 357.841296 -221.94774) (xy 356.620572 -221.94774) (xy 356.620064 -221.973647) (xy 356.611958 -222.024824)
			(xy 356.595946 -222.074103) (xy 356.572423 -222.12027) (xy 356.541967 -222.162189) (xy 356.505329 -222.198827)
			(xy 356.46341 -222.229283) (xy 356.417243 -222.252806) (xy 356.367964 -222.268818) (xy 356.316787 -222.276924)
			(xy 356.264973 -222.276924) (xy 356.213796 -222.268818) (xy 356.164517 -222.252806) (xy 356.11835 -222.229283)
			(xy 356.076431 -222.198827) (xy 356.039793 -222.162189) (xy 356.009337 -222.12027) (xy 355.985814 -222.074103)
			(xy 355.969802 -222.024824) (xy 355.961696 -221.973647) (xy 355.961188 -221.94774) (xy 354.740972 -221.94774)
			(xy 354.740464 -221.973647) (xy 354.732358 -222.024824) (xy 354.716346 -222.074103) (xy 354.692823 -222.12027)
			(xy 354.662367 -222.162189) (xy 354.625729 -222.198827) (xy 354.58381 -222.229283) (xy 354.537643 -222.252806)
			(xy 354.488364 -222.268818) (xy 354.437187 -222.276924) (xy 354.385373 -222.276924) (xy 354.334196 -222.268818)
			(xy 354.284917 -222.252806) (xy 354.23875 -222.229283) (xy 354.196831 -222.198827) (xy 354.160193 -222.162189)
			(xy 354.129737 -222.12027) (xy 354.106214 -222.074103) (xy 354.090202 -222.024824) (xy 354.082096 -221.973647)
			(xy 354.081588 -221.94774) (xy 352.861372 -221.94774) (xy 352.860864 -221.973647) (xy 352.852758 -222.024824)
			(xy 352.836746 -222.074103) (xy 352.813223 -222.12027) (xy 352.782767 -222.162189) (xy 352.746129 -222.198827)
			(xy 352.70421 -222.229283) (xy 352.658043 -222.252806) (xy 352.608764 -222.268818) (xy 352.557587 -222.276924)
			(xy 352.505773 -222.276924) (xy 352.454596 -222.268818) (xy 352.405317 -222.252806) (xy 352.35915 -222.229283)
			(xy 352.317231 -222.198827) (xy 352.280593 -222.162189) (xy 352.250137 -222.12027) (xy 352.226614 -222.074103)
			(xy 352.210602 -222.024824) (xy 352.202496 -221.973647) (xy 352.201988 -221.94774) (xy 350.981772 -221.94774)
			(xy 350.981264 -221.973647) (xy 350.973158 -222.024824) (xy 350.957146 -222.074103) (xy 350.933623 -222.12027)
			(xy 350.903167 -222.162189) (xy 350.866529 -222.198827) (xy 350.82461 -222.229283) (xy 350.778443 -222.252806)
			(xy 350.729164 -222.268818) (xy 350.677987 -222.276924) (xy 350.626173 -222.276924) (xy 350.574996 -222.268818)
			(xy 350.525717 -222.252806) (xy 350.47955 -222.229283) (xy 350.437631 -222.198827) (xy 350.400993 -222.162189)
			(xy 350.370537 -222.12027) (xy 350.347014 -222.074103) (xy 350.331002 -222.024824) (xy 350.322896 -221.973647)
			(xy 350.322388 -221.94774) (xy 350.322992 -221.920023) (xy 350.332309 -221.865377) (xy 350.34093 -221.839028)
			(xy 350.348804 -221.81693) (xy 350.143826 -221.462092) (xy 350.120966 -221.457774) (xy 350.096166 -221.452574)
			(xy 350.04843 -221.435583) (xy 350.003855 -221.411489) (xy 349.963491 -221.380859) (xy 349.928289 -221.344414)
			(xy 349.899076 -221.303012) (xy 349.876542 -221.257629) (xy 349.861217 -221.209332) (xy 349.853461 -221.159259)
			(xy 349.852996 -221.133924) (xy 349.572072 -221.133924) (xy 349.571564 -221.159811) (xy 349.563465 -221.210949)
			(xy 349.547466 -221.260189) (xy 349.52396 -221.306321) (xy 349.493528 -221.348208) (xy 349.456918 -221.384818)
			(xy 349.415031 -221.41525) (xy 349.368899 -221.438756) (xy 349.319659 -221.454755) (xy 349.268521 -221.462854)
			(xy 349.216747 -221.462854) (xy 349.165609 -221.454755) (xy 349.116369 -221.438756) (xy 349.070237 -221.41525)
			(xy 349.02835 -221.384818) (xy 348.99174 -221.348208) (xy 348.961308 -221.306321) (xy 348.937802 -221.260189)
			(xy 348.921803 -221.210949) (xy 348.913704 -221.159811) (xy 348.913196 -221.133924) (xy 348.632272 -221.133924)
			(xy 348.631745 -221.161632) (xy 348.622548 -221.216279) (xy 348.613984 -221.242636) (xy 348.60611 -221.264734)
			(xy 348.811088 -221.619572) (xy 348.833948 -221.62389) (xy 348.858767 -221.629064) (xy 348.906546 -221.646018)
			(xy 348.951165 -221.670088) (xy 348.991572 -221.700708) (xy 349.026813 -221.737154) (xy 349.056057 -221.778566)
			(xy 349.078614 -221.823969) (xy 349.093952 -221.872291) (xy 349.10171 -221.922391) (xy 349.102172 -221.94774)
			(xy 349.101664 -221.973647) (xy 349.093558 -222.024824) (xy 349.077546 -222.074103) (xy 349.054023 -222.12027)
			(xy 349.023567 -222.162189) (xy 348.986929 -222.198827) (xy 348.94501 -222.229283) (xy 348.898843 -222.252806)
			(xy 348.849564 -222.268818) (xy 348.798387 -222.276924) (xy 348.746573 -222.276924) (xy 348.695396 -222.268818)
			(xy 348.646117 -222.252806) (xy 348.59995 -222.229283) (xy 348.558031 -222.198827) (xy 348.521393 -222.162189)
			(xy 348.490937 -222.12027) (xy 348.467414 -222.074103) (xy 348.451402 -222.024824) (xy 348.443296 -221.973647)
			(xy 348.442788 -221.94774) (xy 348.443392 -221.920023) (xy 348.452709 -221.865377) (xy 348.46133 -221.839028)
			(xy 348.469204 -221.81693) (xy 348.264226 -221.462092) (xy 348.241366 -221.457774) (xy 348.216566 -221.452574)
			(xy 348.16883 -221.435583) (xy 348.124255 -221.411489) (xy 348.083891 -221.380859) (xy 348.048689 -221.344414)
			(xy 348.019476 -221.303012) (xy 347.996942 -221.257629) (xy 347.981617 -221.209332) (xy 347.973861 -221.159259)
			(xy 347.973396 -221.133924) (xy 347.692472 -221.133924) (xy 347.691964 -221.159811) (xy 347.683865 -221.210949)
			(xy 347.667866 -221.260189) (xy 347.64436 -221.306321) (xy 347.613928 -221.348208) (xy 347.577318 -221.384818)
			(xy 347.535431 -221.41525) (xy 347.489299 -221.438756) (xy 347.440059 -221.454755) (xy 347.388921 -221.462854)
			(xy 347.337147 -221.462854) (xy 347.286009 -221.454755) (xy 347.236769 -221.438756) (xy 347.190637 -221.41525)
			(xy 347.14875 -221.384818) (xy 347.11214 -221.348208) (xy 347.081708 -221.306321) (xy 347.058202 -221.260189)
			(xy 347.042203 -221.210949) (xy 347.034104 -221.159811) (xy 347.033596 -221.133924) (xy 346.752672 -221.133924)
			(xy 346.752145 -221.161632) (xy 346.742948 -221.216279) (xy 346.734384 -221.242636) (xy 346.72651 -221.264734)
			(xy 346.931488 -221.619572) (xy 346.954348 -221.62389) (xy 346.979167 -221.629064) (xy 347.026946 -221.646018)
			(xy 347.071565 -221.670088) (xy 347.111972 -221.700708) (xy 347.147213 -221.737154) (xy 347.176457 -221.778566)
			(xy 347.199014 -221.823969) (xy 347.214352 -221.872291) (xy 347.22211 -221.922391) (xy 347.222572 -221.94774)
			(xy 347.222064 -221.973647) (xy 347.213958 -222.024824) (xy 347.197946 -222.074103) (xy 347.174423 -222.12027)
			(xy 347.143967 -222.162189) (xy 347.107329 -222.198827) (xy 347.06541 -222.229283) (xy 347.019243 -222.252806)
			(xy 346.969964 -222.268818) (xy 346.918787 -222.276924) (xy 346.866973 -222.276924) (xy 346.815796 -222.268818)
			(xy 346.766517 -222.252806) (xy 346.72035 -222.229283) (xy 346.678431 -222.198827) (xy 346.641793 -222.162189)
			(xy 346.611337 -222.12027) (xy 346.587814 -222.074103) (xy 346.571802 -222.024824) (xy 346.563696 -221.973647)
			(xy 346.563188 -221.94774) (xy 346.563792 -221.920023) (xy 346.573109 -221.865377) (xy 346.58173 -221.839028)
			(xy 346.589604 -221.81693) (xy 346.384626 -221.462092) (xy 346.361766 -221.457774) (xy 346.336966 -221.452574)
			(xy 346.28923 -221.435583) (xy 346.244655 -221.411489) (xy 346.204291 -221.380859) (xy 346.169089 -221.344414)
			(xy 346.139876 -221.303012) (xy 346.117342 -221.257629) (xy 346.102017 -221.209332) (xy 346.094261 -221.159259)
			(xy 346.093796 -221.133924) (xy 345.812872 -221.133924) (xy 345.812364 -221.159811) (xy 345.804265 -221.210949)
			(xy 345.788266 -221.260189) (xy 345.76476 -221.306321) (xy 345.734328 -221.348208) (xy 345.697718 -221.384818)
			(xy 345.655831 -221.41525) (xy 345.609699 -221.438756) (xy 345.560459 -221.454755) (xy 345.509321 -221.462854)
			(xy 345.457547 -221.462854) (xy 345.406409 -221.454755) (xy 345.357169 -221.438756) (xy 345.311037 -221.41525)
			(xy 345.26915 -221.384818) (xy 345.23254 -221.348208) (xy 345.202108 -221.306321) (xy 345.178602 -221.260189)
			(xy 345.162603 -221.210949) (xy 345.154504 -221.159811) (xy 345.153996 -221.133924) (xy 344.873072 -221.133924)
			(xy 344.872545 -221.161632) (xy 344.863348 -221.216279) (xy 344.854784 -221.242636) (xy 344.84691 -221.264734)
			(xy 345.051888 -221.619572) (xy 345.074748 -221.62389) (xy 345.099567 -221.629064) (xy 345.147346 -221.646018)
			(xy 345.191965 -221.670088) (xy 345.232372 -221.700708) (xy 345.267613 -221.737154) (xy 345.296857 -221.778566)
			(xy 345.319414 -221.823969) (xy 345.334752 -221.872291) (xy 345.34251 -221.922391) (xy 345.342972 -221.94774)
			(xy 345.342464 -221.973647) (xy 345.334358 -222.024824) (xy 345.318346 -222.074103) (xy 345.294823 -222.12027)
			(xy 345.264367 -222.162189) (xy 345.227729 -222.198827) (xy 345.18581 -222.229283) (xy 345.139643 -222.252806)
			(xy 345.090364 -222.268818) (xy 345.039187 -222.276924) (xy 344.987373 -222.276924) (xy 344.936196 -222.268818)
			(xy 344.886917 -222.252806) (xy 344.84075 -222.229283) (xy 344.798831 -222.198827) (xy 344.762193 -222.162189)
			(xy 344.731737 -222.12027) (xy 344.708214 -222.074103) (xy 344.692202 -222.024824) (xy 344.684096 -221.973647)
			(xy 344.683588 -221.94774) (xy 344.684192 -221.920023) (xy 344.693509 -221.865377) (xy 344.70213 -221.839028)
			(xy 344.710004 -221.81693) (xy 344.505026 -221.462092) (xy 344.482166 -221.457774) (xy 344.457366 -221.452574)
			(xy 344.40963 -221.435583) (xy 344.365055 -221.411489) (xy 344.324691 -221.380859) (xy 344.289489 -221.344414)
			(xy 344.260276 -221.303012) (xy 344.237742 -221.257629) (xy 344.222417 -221.209332) (xy 344.214661 -221.159259)
			(xy 344.214196 -221.133924) (xy 343.933272 -221.133924) (xy 343.932764 -221.159811) (xy 343.924665 -221.210949)
			(xy 343.908666 -221.260189) (xy 343.88516 -221.306321) (xy 343.854728 -221.348208) (xy 343.818118 -221.384818)
			(xy 343.776231 -221.41525) (xy 343.730099 -221.438756) (xy 343.680859 -221.454755) (xy 343.629721 -221.462854)
			(xy 343.577947 -221.462854) (xy 343.526809 -221.454755) (xy 343.477569 -221.438756) (xy 343.431437 -221.41525)
			(xy 343.38955 -221.384818) (xy 343.35294 -221.348208) (xy 343.322508 -221.306321) (xy 343.299002 -221.260189)
			(xy 343.283003 -221.210949) (xy 343.274904 -221.159811) (xy 343.274396 -221.133924) (xy 342.993472 -221.133924)
			(xy 342.992945 -221.161632) (xy 342.983748 -221.216279) (xy 342.975184 -221.242636) (xy 342.96731 -221.264734)
			(xy 343.172288 -221.619572) (xy 343.195148 -221.62389) (xy 343.219967 -221.629064) (xy 343.267746 -221.646018)
			(xy 343.312365 -221.670088) (xy 343.352772 -221.700708) (xy 343.388013 -221.737154) (xy 343.417257 -221.778566)
			(xy 343.439814 -221.823969) (xy 343.455152 -221.872291) (xy 343.46291 -221.922391) (xy 343.463372 -221.94774)
			(xy 343.462864 -221.973647) (xy 343.454758 -222.024824) (xy 343.438746 -222.074103) (xy 343.415223 -222.12027)
			(xy 343.384767 -222.162189) (xy 343.348129 -222.198827) (xy 343.30621 -222.229283) (xy 343.260043 -222.252806)
			(xy 343.210764 -222.268818) (xy 343.159587 -222.276924) (xy 343.107773 -222.276924) (xy 343.056596 -222.268818)
			(xy 343.007317 -222.252806) (xy 342.96115 -222.229283) (xy 342.919231 -222.198827) (xy 342.882593 -222.162189)
			(xy 342.852137 -222.12027) (xy 342.828614 -222.074103) (xy 342.812602 -222.024824) (xy 342.804496 -221.973647)
			(xy 342.803988 -221.94774) (xy 342.804592 -221.920023) (xy 342.813909 -221.865377) (xy 342.82253 -221.839028)
			(xy 342.830404 -221.81693) (xy 342.625426 -221.462092) (xy 342.602566 -221.457774) (xy 342.577766 -221.452574)
			(xy 342.53003 -221.435583) (xy 342.485455 -221.411489) (xy 342.445091 -221.380859) (xy 342.409889 -221.344414)
			(xy 342.380676 -221.303012) (xy 342.358142 -221.257629) (xy 342.342817 -221.209332) (xy 342.335061 -221.159259)
			(xy 342.334596 -221.133924) (xy 342.053672 -221.133924) (xy 342.053164 -221.159811) (xy 342.045065 -221.210949)
			(xy 342.029066 -221.260189) (xy 342.00556 -221.306321) (xy 341.975128 -221.348208) (xy 341.938518 -221.384818)
			(xy 341.896631 -221.41525) (xy 341.850499 -221.438756) (xy 341.801259 -221.454755) (xy 341.750121 -221.462854)
			(xy 341.698347 -221.462854) (xy 341.647209 -221.454755) (xy 341.597969 -221.438756) (xy 341.551837 -221.41525)
			(xy 341.50995 -221.384818) (xy 341.47334 -221.348208) (xy 341.442908 -221.306321) (xy 341.419402 -221.260189)
			(xy 341.403403 -221.210949) (xy 341.395304 -221.159811) (xy 341.394796 -221.133924) (xy 341.113872 -221.133924)
			(xy 341.113345 -221.161632) (xy 341.104148 -221.216279) (xy 341.095584 -221.242636) (xy 341.08771 -221.264734)
			(xy 341.292688 -221.619572) (xy 341.315548 -221.62389) (xy 341.340367 -221.629064) (xy 341.388146 -221.646018)
			(xy 341.432765 -221.670088) (xy 341.473172 -221.700708) (xy 341.508413 -221.737154) (xy 341.537657 -221.778566)
			(xy 341.560214 -221.823969) (xy 341.575552 -221.872291) (xy 341.58331 -221.922391) (xy 341.583772 -221.94774)
			(xy 341.583264 -221.973647) (xy 341.575158 -222.024824) (xy 341.559146 -222.074103) (xy 341.535623 -222.12027)
			(xy 341.505167 -222.162189) (xy 341.468529 -222.198827) (xy 341.42661 -222.229283) (xy 341.380443 -222.252806)
			(xy 341.331164 -222.268818) (xy 341.279987 -222.276924) (xy 341.228173 -222.276924) (xy 341.176996 -222.268818)
			(xy 341.127717 -222.252806) (xy 341.08155 -222.229283) (xy 341.039631 -222.198827) (xy 341.002993 -222.162189)
			(xy 340.972537 -222.12027) (xy 340.949014 -222.074103) (xy 340.933002 -222.024824) (xy 340.924896 -221.973647)
			(xy 340.924388 -221.94774) (xy 340.924992 -221.920023) (xy 340.934309 -221.865377) (xy 340.94293 -221.839028)
			(xy 340.950804 -221.81693) (xy 340.745826 -221.462092) (xy 340.722966 -221.457774) (xy 340.698166 -221.452574)
			(xy 340.65043 -221.435583) (xy 340.605855 -221.411489) (xy 340.565491 -221.380859) (xy 340.530289 -221.344414)
			(xy 340.501076 -221.303012) (xy 340.478542 -221.257629) (xy 340.463217 -221.209332) (xy 340.455461 -221.159259)
			(xy 340.454996 -221.133924) (xy 340.174072 -221.133924) (xy 340.173564 -221.159811) (xy 340.165465 -221.210949)
			(xy 340.149466 -221.260189) (xy 340.12596 -221.306321) (xy 340.095528 -221.348208) (xy 340.058918 -221.384818)
			(xy 340.017031 -221.41525) (xy 339.970899 -221.438756) (xy 339.921659 -221.454755) (xy 339.870521 -221.462854)
			(xy 339.818747 -221.462854) (xy 339.767609 -221.454755) (xy 339.718369 -221.438756) (xy 339.672237 -221.41525)
			(xy 339.63035 -221.384818) (xy 339.59374 -221.348208) (xy 339.563308 -221.306321) (xy 339.539802 -221.260189)
			(xy 339.523803 -221.210949) (xy 339.515704 -221.159811) (xy 339.515196 -221.133924) (xy 339.234272 -221.133924)
			(xy 339.233745 -221.161632) (xy 339.224548 -221.216279) (xy 339.215984 -221.242636) (xy 339.20811 -221.264734)
			(xy 339.413088 -221.619572) (xy 339.435948 -221.62389) (xy 339.460767 -221.629064) (xy 339.508546 -221.646018)
			(xy 339.553165 -221.670088) (xy 339.593572 -221.700708) (xy 339.628813 -221.737154) (xy 339.658057 -221.778566)
			(xy 339.680614 -221.823969) (xy 339.695952 -221.872291) (xy 339.70371 -221.922391) (xy 339.704172 -221.94774)
			(xy 339.703664 -221.973647) (xy 339.695558 -222.024824) (xy 339.679546 -222.074103) (xy 339.656023 -222.12027)
			(xy 339.625567 -222.162189) (xy 339.588929 -222.198827) (xy 339.54701 -222.229283) (xy 339.500843 -222.252806)
			(xy 339.451564 -222.268818) (xy 339.400387 -222.276924) (xy 339.348573 -222.276924) (xy 339.297396 -222.268818)
			(xy 339.248117 -222.252806) (xy 339.20195 -222.229283) (xy 339.160031 -222.198827) (xy 339.123393 -222.162189)
			(xy 339.092937 -222.12027) (xy 339.069414 -222.074103) (xy 339.053402 -222.024824) (xy 339.045296 -221.973647)
			(xy 339.044788 -221.94774) (xy 339.045392 -221.920023) (xy 339.054709 -221.865377) (xy 339.06333 -221.839028)
			(xy 339.071204 -221.81693) (xy 338.866226 -221.462092) (xy 338.843366 -221.457774) (xy 338.818566 -221.452574)
			(xy 338.77083 -221.435583) (xy 338.726255 -221.411489) (xy 338.685891 -221.380859) (xy 338.650689 -221.344414)
			(xy 338.621476 -221.303012) (xy 338.598942 -221.257629) (xy 338.583617 -221.209332) (xy 338.575861 -221.159259)
			(xy 338.575396 -221.133924) (xy 338.294472 -221.133924) (xy 338.293964 -221.159811) (xy 338.285865 -221.210949)
			(xy 338.269866 -221.260189) (xy 338.24636 -221.306321) (xy 338.215928 -221.348208) (xy 338.179318 -221.384818)
			(xy 338.137431 -221.41525) (xy 338.091299 -221.438756) (xy 338.042059 -221.454755) (xy 337.990921 -221.462854)
			(xy 337.939147 -221.462854) (xy 337.888009 -221.454755) (xy 337.838769 -221.438756) (xy 337.792637 -221.41525)
			(xy 337.75075 -221.384818) (xy 337.71414 -221.348208) (xy 337.683708 -221.306321) (xy 337.660202 -221.260189)
			(xy 337.644203 -221.210949) (xy 337.636104 -221.159811) (xy 337.635596 -221.133924) (xy 337.354672 -221.133924)
			(xy 337.354145 -221.161632) (xy 337.344948 -221.216279) (xy 337.336384 -221.242636) (xy 337.32851 -221.264734)
			(xy 337.533488 -221.619572) (xy 337.556348 -221.62389) (xy 337.581167 -221.629064) (xy 337.628946 -221.646018)
			(xy 337.673565 -221.670088) (xy 337.713972 -221.700708) (xy 337.749213 -221.737154) (xy 337.778457 -221.778566)
			(xy 337.801014 -221.823969) (xy 337.816352 -221.872291) (xy 337.82411 -221.922391) (xy 337.824572 -221.94774)
			(xy 337.824064 -221.973647) (xy 337.815958 -222.024824) (xy 337.799946 -222.074103) (xy 337.776423 -222.12027)
			(xy 337.745967 -222.162189) (xy 337.709329 -222.198827) (xy 337.66741 -222.229283) (xy 337.621243 -222.252806)
			(xy 337.571964 -222.268818) (xy 337.520787 -222.276924) (xy 337.468973 -222.276924) (xy 337.417796 -222.268818)
			(xy 337.368517 -222.252806) (xy 337.32235 -222.229283) (xy 337.280431 -222.198827) (xy 337.243793 -222.162189)
			(xy 337.213337 -222.12027) (xy 337.189814 -222.074103) (xy 337.173802 -222.024824) (xy 337.165696 -221.973647)
			(xy 337.165188 -221.94774) (xy 337.165792 -221.920023) (xy 337.175109 -221.865377) (xy 337.18373 -221.839028)
			(xy 337.191604 -221.81693) (xy 336.986626 -221.462092) (xy 336.963766 -221.457774) (xy 336.938966 -221.452574)
			(xy 336.89123 -221.435583) (xy 336.846655 -221.411489) (xy 336.806291 -221.380859) (xy 336.771089 -221.344414)
			(xy 336.741876 -221.303012) (xy 336.719342 -221.257629) (xy 336.704017 -221.209332) (xy 336.696261 -221.159259)
			(xy 336.695796 -221.133924) (xy 134.525004 -221.133924) (xy 134.524496 -221.159811) (xy 134.516397 -221.210949)
			(xy 134.500398 -221.260189) (xy 134.476892 -221.306321) (xy 134.44646 -221.348208) (xy 134.40985 -221.384818)
			(xy 134.367963 -221.41525) (xy 134.321831 -221.438756) (xy 134.272591 -221.454755) (xy 134.221453 -221.462854)
			(xy 134.169679 -221.462854) (xy 134.118541 -221.454755) (xy 134.069301 -221.438756) (xy 134.023169 -221.41525)
			(xy 133.981282 -221.384818) (xy 133.944672 -221.348208) (xy 133.91424 -221.306321) (xy 133.890734 -221.260189)
			(xy 133.874735 -221.210949) (xy 133.866636 -221.159811) (xy 133.866128 -221.133924) (xy 133.866667 -221.106216)
			(xy 133.875856 -221.05157) (xy 133.884416 -221.025212) (xy 133.89229 -221.003114) (xy 133.687312 -220.648022)
			(xy 133.664452 -220.643704) (xy 133.639631 -220.638536) (xy 133.591852 -220.621582) (xy 133.547233 -220.59751)
			(xy 133.506826 -220.56689) (xy 133.471585 -220.530444) (xy 133.442341 -220.48903) (xy 133.419784 -220.443627)
			(xy 133.404447 -220.395304) (xy 133.39669 -220.345203) (xy 133.396228 -220.319854) (xy 132.175504 -220.319854)
			(xy 132.174894 -220.347507) (xy 132.165571 -220.402025) (xy 132.156962 -220.428312) (xy 132.149342 -220.45041)
			(xy 132.354574 -220.805756) (xy 132.377434 -220.810074) (xy 132.402245 -220.815229) (xy 132.449984 -220.832223)
			(xy 132.494562 -220.856322) (xy 132.534927 -220.886957) (xy 132.57013 -220.923408) (xy 132.59934 -220.964816)
			(xy 132.621872 -221.010206) (xy 132.637192 -221.058509) (xy 132.644942 -221.108587) (xy 132.645404 -221.133924)
			(xy 132.644896 -221.159811) (xy 132.636797 -221.210949) (xy 132.620798 -221.260189) (xy 132.597292 -221.306321)
			(xy 132.56686 -221.348208) (xy 132.53025 -221.384818) (xy 132.488363 -221.41525) (xy 132.442231 -221.438756)
			(xy 132.392991 -221.454755) (xy 132.341853 -221.462854) (xy 132.290079 -221.462854) (xy 132.238941 -221.454755)
			(xy 132.189701 -221.438756) (xy 132.143569 -221.41525) (xy 132.101682 -221.384818) (xy 132.065072 -221.348208)
			(xy 132.03464 -221.306321) (xy 132.011134 -221.260189) (xy 131.995135 -221.210949) (xy 131.987036 -221.159811)
			(xy 131.986528 -221.133924) (xy 131.987067 -221.106216) (xy 131.996256 -221.05157) (xy 132.004816 -221.025212)
			(xy 132.01269 -221.003114) (xy 131.807712 -220.648022) (xy 131.784852 -220.643704) (xy 131.76 -220.63857)
			(xy 131.712153 -220.621668) (xy 131.667462 -220.597632) (xy 131.626984 -220.567029) (xy 131.591674 -220.530584)
			(xy 131.562368 -220.489157) (xy 131.539757 -220.443728) (xy 131.524377 -220.39537) (xy 131.516591 -220.345226)
			(xy 131.51612 -220.319854) (xy 130.295904 -220.319854) (xy 130.295294 -220.347507) (xy 130.285971 -220.402025)
			(xy 130.277362 -220.428312) (xy 130.269742 -220.45041) (xy 130.474974 -220.805756) (xy 130.497834 -220.810074)
			(xy 130.522645 -220.815229) (xy 130.570384 -220.832223) (xy 130.614962 -220.856322) (xy 130.655327 -220.886957)
			(xy 130.69053 -220.923408) (xy 130.71974 -220.964816) (xy 130.742272 -221.010206) (xy 130.757592 -221.058509)
			(xy 130.765342 -221.108587) (xy 130.765804 -221.133924) (xy 130.765296 -221.159811) (xy 130.757197 -221.210949)
			(xy 130.741198 -221.260189) (xy 130.717692 -221.306321) (xy 130.68726 -221.348208) (xy 130.65065 -221.384818)
			(xy 130.608763 -221.41525) (xy 130.562631 -221.438756) (xy 130.513391 -221.454755) (xy 130.462253 -221.462854)
			(xy 130.410479 -221.462854) (xy 130.359341 -221.454755) (xy 130.310101 -221.438756) (xy 130.263969 -221.41525)
			(xy 130.222082 -221.384818) (xy 130.185472 -221.348208) (xy 130.15504 -221.306321) (xy 130.131534 -221.260189)
			(xy 130.115535 -221.210949) (xy 130.107436 -221.159811) (xy 130.106928 -221.133924) (xy 130.107467 -221.106216)
			(xy 130.116656 -221.05157) (xy 130.125216 -221.025212) (xy 130.13309 -221.003114) (xy 129.928112 -220.648022)
			(xy 129.905252 -220.643704) (xy 129.8804 -220.63857) (xy 129.832553 -220.621668) (xy 129.787862 -220.597632)
			(xy 129.747384 -220.567029) (xy 129.712074 -220.530584) (xy 129.682768 -220.489157) (xy 129.660157 -220.443728)
			(xy 129.644777 -220.39537) (xy 129.636991 -220.345226) (xy 129.63652 -220.319854) (xy 128.416304 -220.319854)
			(xy 128.415694 -220.347507) (xy 128.406371 -220.402025) (xy 128.397762 -220.428312) (xy 128.390142 -220.45041)
			(xy 128.595374 -220.805756) (xy 128.618234 -220.810074) (xy 128.643045 -220.815229) (xy 128.690784 -220.832223)
			(xy 128.735362 -220.856322) (xy 128.775727 -220.886957) (xy 128.81093 -220.923408) (xy 128.84014 -220.964816)
			(xy 128.862672 -221.010206) (xy 128.877992 -221.058509) (xy 128.885742 -221.108587) (xy 128.886204 -221.133924)
			(xy 128.885696 -221.159811) (xy 128.877597 -221.210949) (xy 128.861598 -221.260189) (xy 128.838092 -221.306321)
			(xy 128.80766 -221.348208) (xy 128.77105 -221.384818) (xy 128.729163 -221.41525) (xy 128.683031 -221.438756)
			(xy 128.633791 -221.454755) (xy 128.582653 -221.462854) (xy 128.530879 -221.462854) (xy 128.479741 -221.454755)
			(xy 128.430501 -221.438756) (xy 128.384369 -221.41525) (xy 128.342482 -221.384818) (xy 128.305872 -221.348208)
			(xy 128.27544 -221.306321) (xy 128.251934 -221.260189) (xy 128.235935 -221.210949) (xy 128.227836 -221.159811)
			(xy 128.227328 -221.133924) (xy 128.227867 -221.106216) (xy 128.237056 -221.05157) (xy 128.245616 -221.025212)
			(xy 128.25349 -221.003114) (xy 128.048512 -220.648022) (xy 128.025652 -220.643704) (xy 128.0008 -220.63857)
			(xy 127.952953 -220.621668) (xy 127.908262 -220.597632) (xy 127.867784 -220.567029) (xy 127.832474 -220.530584)
			(xy 127.803168 -220.489157) (xy 127.780557 -220.443728) (xy 127.765177 -220.39537) (xy 127.757391 -220.345226)
			(xy 127.75692 -220.319854) (xy 126.536704 -220.319854) (xy 126.536094 -220.347507) (xy 126.526771 -220.402025)
			(xy 126.518162 -220.428312) (xy 126.510542 -220.45041) (xy 126.715774 -220.805756) (xy 126.738634 -220.810074)
			(xy 126.763445 -220.815229) (xy 126.811184 -220.832223) (xy 126.855762 -220.856322) (xy 126.896127 -220.886957)
			(xy 126.93133 -220.923408) (xy 126.96054 -220.964816) (xy 126.983072 -221.010206) (xy 126.998392 -221.058509)
			(xy 127.006142 -221.108587) (xy 127.006604 -221.133924) (xy 127.006096 -221.159811) (xy 126.997997 -221.210949)
			(xy 126.981998 -221.260189) (xy 126.958492 -221.306321) (xy 126.92806 -221.348208) (xy 126.89145 -221.384818)
			(xy 126.849563 -221.41525) (xy 126.803431 -221.438756) (xy 126.754191 -221.454755) (xy 126.703053 -221.462854)
			(xy 126.651279 -221.462854) (xy 126.600141 -221.454755) (xy 126.550901 -221.438756) (xy 126.504769 -221.41525)
			(xy 126.462882 -221.384818) (xy 126.426272 -221.348208) (xy 126.39584 -221.306321) (xy 126.372334 -221.260189)
			(xy 126.356335 -221.210949) (xy 126.348236 -221.159811) (xy 126.347728 -221.133924) (xy 126.348267 -221.106216)
			(xy 126.357456 -221.05157) (xy 126.366016 -221.025212) (xy 126.37389 -221.003114) (xy 126.168912 -220.648022)
			(xy 126.146052 -220.643704) (xy 126.1212 -220.63857) (xy 126.073353 -220.621668) (xy 126.028662 -220.597632)
			(xy 125.988184 -220.567029) (xy 125.952874 -220.530584) (xy 125.923568 -220.489157) (xy 125.900957 -220.443728)
			(xy 125.885577 -220.39537) (xy 125.877791 -220.345226) (xy 125.87732 -220.319854) (xy 124.657104 -220.319854)
			(xy 124.656494 -220.347507) (xy 124.647171 -220.402025) (xy 124.638562 -220.428312) (xy 124.630942 -220.45041)
			(xy 124.836174 -220.805756) (xy 124.859034 -220.810074) (xy 124.883845 -220.815229) (xy 124.931584 -220.832223)
			(xy 124.976162 -220.856322) (xy 125.016527 -220.886957) (xy 125.05173 -220.923408) (xy 125.08094 -220.964816)
			(xy 125.103472 -221.010206) (xy 125.118792 -221.058509) (xy 125.126542 -221.108587) (xy 125.127004 -221.133924)
			(xy 125.126496 -221.159811) (xy 125.118397 -221.210949) (xy 125.102398 -221.260189) (xy 125.078892 -221.306321)
			(xy 125.04846 -221.348208) (xy 125.01185 -221.384818) (xy 124.969963 -221.41525) (xy 124.923831 -221.438756)
			(xy 124.874591 -221.454755) (xy 124.823453 -221.462854) (xy 124.771679 -221.462854) (xy 124.720541 -221.454755)
			(xy 124.671301 -221.438756) (xy 124.625169 -221.41525) (xy 124.583282 -221.384818) (xy 124.546672 -221.348208)
			(xy 124.51624 -221.306321) (xy 124.492734 -221.260189) (xy 124.476735 -221.210949) (xy 124.468636 -221.159811)
			(xy 124.468128 -221.133924) (xy 124.468667 -221.106216) (xy 124.477856 -221.05157) (xy 124.486416 -221.025212)
			(xy 124.49429 -221.003114) (xy 124.289312 -220.648022) (xy 124.266452 -220.643704) (xy 124.2416 -220.63857)
			(xy 124.193753 -220.621668) (xy 124.149062 -220.597632) (xy 124.108584 -220.567029) (xy 124.073274 -220.530584)
			(xy 124.043968 -220.489157) (xy 124.021357 -220.443728) (xy 124.005977 -220.39537) (xy 123.998191 -220.345226)
			(xy 123.99772 -220.319854) (xy 122.777504 -220.319854) (xy 122.776894 -220.347507) (xy 122.767571 -220.402025)
			(xy 122.758962 -220.428312) (xy 122.751342 -220.45041) (xy 122.956574 -220.805756) (xy 122.979434 -220.810074)
			(xy 123.004245 -220.815229) (xy 123.051984 -220.832223) (xy 123.096562 -220.856322) (xy 123.136927 -220.886957)
			(xy 123.17213 -220.923408) (xy 123.20134 -220.964816) (xy 123.223872 -221.010206) (xy 123.239192 -221.058509)
			(xy 123.246942 -221.108587) (xy 123.247404 -221.133924) (xy 123.246896 -221.159811) (xy 123.238797 -221.210949)
			(xy 123.222798 -221.260189) (xy 123.199292 -221.306321) (xy 123.16886 -221.348208) (xy 123.13225 -221.384818)
			(xy 123.090363 -221.41525) (xy 123.044231 -221.438756) (xy 122.994991 -221.454755) (xy 122.943853 -221.462854)
			(xy 122.892079 -221.462854) (xy 122.840941 -221.454755) (xy 122.791701 -221.438756) (xy 122.745569 -221.41525)
			(xy 122.703682 -221.384818) (xy 122.667072 -221.348208) (xy 122.63664 -221.306321) (xy 122.613134 -221.260189)
			(xy 122.597135 -221.210949) (xy 122.589036 -221.159811) (xy 122.588528 -221.133924) (xy 122.589067 -221.106216)
			(xy 122.598256 -221.05157) (xy 122.606816 -221.025212) (xy 122.61469 -221.003114) (xy 122.409712 -220.648022)
			(xy 122.386852 -220.643704) (xy 122.362 -220.63857) (xy 122.314153 -220.621668) (xy 122.269462 -220.597632)
			(xy 122.228984 -220.567029) (xy 122.193674 -220.530584) (xy 122.164368 -220.489157) (xy 122.141757 -220.443728)
			(xy 122.126377 -220.39537) (xy 122.118591 -220.345226) (xy 122.11812 -220.319854) (xy 120.897904 -220.319854)
			(xy 120.897294 -220.347507) (xy 120.887971 -220.402025) (xy 120.879362 -220.428312) (xy 120.871742 -220.45041)
			(xy 121.076974 -220.805756) (xy 121.099834 -220.810074) (xy 121.124645 -220.815229) (xy 121.172384 -220.832223)
			(xy 121.216962 -220.856322) (xy 121.257327 -220.886957) (xy 121.29253 -220.923408) (xy 121.32174 -220.964816)
			(xy 121.344272 -221.010206) (xy 121.359592 -221.058509) (xy 121.367342 -221.108587) (xy 121.367804 -221.133924)
			(xy 121.367296 -221.159811) (xy 121.359197 -221.210949) (xy 121.343198 -221.260189) (xy 121.319692 -221.306321)
			(xy 121.28926 -221.348208) (xy 121.25265 -221.384818) (xy 121.210763 -221.41525) (xy 121.164631 -221.438756)
			(xy 121.115391 -221.454755) (xy 121.064253 -221.462854) (xy 121.012479 -221.462854) (xy 120.961341 -221.454755)
			(xy 120.912101 -221.438756) (xy 120.865969 -221.41525) (xy 120.824082 -221.384818) (xy 120.787472 -221.348208)
			(xy 120.75704 -221.306321) (xy 120.733534 -221.260189) (xy 120.717535 -221.210949) (xy 120.709436 -221.159811)
			(xy 120.708928 -221.133924) (xy 120.709467 -221.106216) (xy 120.718656 -221.05157) (xy 120.727216 -221.025212)
			(xy 120.73509 -221.003114) (xy 120.530112 -220.648022) (xy 120.507252 -220.643704) (xy 120.4824 -220.63857)
			(xy 120.434553 -220.621668) (xy 120.389862 -220.597632) (xy 120.349384 -220.567029) (xy 120.314074 -220.530584)
			(xy 120.284768 -220.489157) (xy 120.262157 -220.443728) (xy 120.246777 -220.39537) (xy 120.238991 -220.345226)
			(xy 120.23852 -220.319854) (xy 119.018304 -220.319854) (xy 119.017694 -220.347507) (xy 119.008371 -220.402025)
			(xy 118.999762 -220.428312) (xy 118.992142 -220.45041) (xy 119.197374 -220.805756) (xy 119.220234 -220.810074)
			(xy 119.245045 -220.815229) (xy 119.292784 -220.832223) (xy 119.337362 -220.856322) (xy 119.377727 -220.886957)
			(xy 119.41293 -220.923408) (xy 119.44214 -220.964816) (xy 119.464672 -221.010206) (xy 119.479992 -221.058509)
			(xy 119.487742 -221.108587) (xy 119.488204 -221.133924) (xy 119.487696 -221.159811) (xy 119.479597 -221.210949)
			(xy 119.463598 -221.260189) (xy 119.440092 -221.306321) (xy 119.40966 -221.348208) (xy 119.37305 -221.384818)
			(xy 119.331163 -221.41525) (xy 119.285031 -221.438756) (xy 119.235791 -221.454755) (xy 119.184653 -221.462854)
			(xy 119.132879 -221.462854) (xy 119.081741 -221.454755) (xy 119.032501 -221.438756) (xy 118.986369 -221.41525)
			(xy 118.944482 -221.384818) (xy 118.907872 -221.348208) (xy 118.87744 -221.306321) (xy 118.853934 -221.260189)
			(xy 118.837935 -221.210949) (xy 118.829836 -221.159811) (xy 118.829328 -221.133924) (xy 118.829867 -221.106216)
			(xy 118.839056 -221.05157) (xy 118.847616 -221.025212) (xy 118.85549 -221.003114) (xy 118.650512 -220.648022)
			(xy 118.627652 -220.643704) (xy 118.6028 -220.63857) (xy 118.554953 -220.621668) (xy 118.510262 -220.597632)
			(xy 118.469784 -220.567029) (xy 118.434474 -220.530584) (xy 118.405168 -220.489157) (xy 118.382557 -220.443728)
			(xy 118.367177 -220.39537) (xy 118.359391 -220.345226) (xy 118.35892 -220.319854) (xy 117.138704 -220.319854)
			(xy 117.138094 -220.347507) (xy 117.128771 -220.402025) (xy 117.120162 -220.428312) (xy 117.112542 -220.45041)
			(xy 117.317774 -220.805756) (xy 117.340634 -220.810074) (xy 117.365445 -220.815229) (xy 117.413184 -220.832223)
			(xy 117.457762 -220.856322) (xy 117.498127 -220.886957) (xy 117.53333 -220.923408) (xy 117.56254 -220.964816)
			(xy 117.585072 -221.010206) (xy 117.600392 -221.058509) (xy 117.608142 -221.108587) (xy 117.608604 -221.133924)
			(xy 117.608096 -221.159811) (xy 117.599997 -221.210949) (xy 117.583998 -221.260189) (xy 117.560492 -221.306321)
			(xy 117.53006 -221.348208) (xy 117.49345 -221.384818) (xy 117.451563 -221.41525) (xy 117.405431 -221.438756)
			(xy 117.356191 -221.454755) (xy 117.305053 -221.462854) (xy 117.253279 -221.462854) (xy 117.202141 -221.454755)
			(xy 117.152901 -221.438756) (xy 117.106769 -221.41525) (xy 117.064882 -221.384818) (xy 117.028272 -221.348208)
			(xy 116.99784 -221.306321) (xy 116.974334 -221.260189) (xy 116.958335 -221.210949) (xy 116.950236 -221.159811)
			(xy 116.949728 -221.133924) (xy 116.950267 -221.106216) (xy 116.959456 -221.05157) (xy 116.968016 -221.025212)
			(xy 116.97589 -221.003114) (xy 116.770912 -220.648022) (xy 116.748052 -220.643704) (xy 116.7232 -220.63857)
			(xy 116.675353 -220.621668) (xy 116.630662 -220.597632) (xy 116.590184 -220.567029) (xy 116.554874 -220.530584)
			(xy 116.525568 -220.489157) (xy 116.502957 -220.443728) (xy 116.487577 -220.39537) (xy 116.479791 -220.345226)
			(xy 116.47932 -220.319854) (xy 115.259104 -220.319854) (xy 115.258494 -220.347507) (xy 115.249171 -220.402025)
			(xy 115.240562 -220.428312) (xy 115.232942 -220.45041) (xy 115.438174 -220.805756) (xy 115.461034 -220.810074)
			(xy 115.485845 -220.815229) (xy 115.533584 -220.832223) (xy 115.578162 -220.856322) (xy 115.618527 -220.886957)
			(xy 115.65373 -220.923408) (xy 115.68294 -220.964816) (xy 115.705472 -221.010206) (xy 115.720792 -221.058509)
			(xy 115.728542 -221.108587) (xy 115.729004 -221.133924) (xy 115.728496 -221.159811) (xy 115.720397 -221.210949)
			(xy 115.704398 -221.260189) (xy 115.680892 -221.306321) (xy 115.65046 -221.348208) (xy 115.61385 -221.384818)
			(xy 115.571963 -221.41525) (xy 115.525831 -221.438756) (xy 115.476591 -221.454755) (xy 115.425453 -221.462854)
			(xy 115.373679 -221.462854) (xy 115.322541 -221.454755) (xy 115.273301 -221.438756) (xy 115.227169 -221.41525)
			(xy 115.185282 -221.384818) (xy 115.148672 -221.348208) (xy 115.11824 -221.306321) (xy 115.094734 -221.260189)
			(xy 115.078735 -221.210949) (xy 115.070636 -221.159811) (xy 115.070128 -221.133924) (xy 115.070667 -221.106216)
			(xy 115.079856 -221.05157) (xy 115.088416 -221.025212) (xy 115.09629 -221.003114) (xy 114.891312 -220.648022)
			(xy 114.868452 -220.643704) (xy 114.8436 -220.63857) (xy 114.795753 -220.621668) (xy 114.751062 -220.597632)
			(xy 114.710584 -220.567029) (xy 114.675274 -220.530584) (xy 114.645968 -220.489157) (xy 114.623357 -220.443728)
			(xy 114.607977 -220.39537) (xy 114.600191 -220.345226) (xy 114.59972 -220.319854) (xy 113.379504 -220.319854)
			(xy 113.378894 -220.347507) (xy 113.369571 -220.402025) (xy 113.360962 -220.428312) (xy 113.353342 -220.45041)
			(xy 113.558574 -220.805756) (xy 113.581434 -220.810074) (xy 113.606245 -220.815229) (xy 113.653984 -220.832223)
			(xy 113.698562 -220.856322) (xy 113.738927 -220.886957) (xy 113.77413 -220.923408) (xy 113.80334 -220.964816)
			(xy 113.825872 -221.010206) (xy 113.841192 -221.058509) (xy 113.848942 -221.108587) (xy 113.849404 -221.133924)
			(xy 113.848896 -221.159811) (xy 113.840797 -221.210949) (xy 113.824798 -221.260189) (xy 113.801292 -221.306321)
			(xy 113.77086 -221.348208) (xy 113.73425 -221.384818) (xy 113.692363 -221.41525) (xy 113.646231 -221.438756)
			(xy 113.596991 -221.454755) (xy 113.545853 -221.462854) (xy 113.494079 -221.462854) (xy 113.442941 -221.454755)
			(xy 113.393701 -221.438756) (xy 113.347569 -221.41525) (xy 113.305682 -221.384818) (xy 113.269072 -221.348208)
			(xy 113.23864 -221.306321) (xy 113.215134 -221.260189) (xy 113.199135 -221.210949) (xy 113.191036 -221.159811)
			(xy 113.190528 -221.133924) (xy 113.191067 -221.106216) (xy 113.200256 -221.05157) (xy 113.208816 -221.025212)
			(xy 113.21669 -221.003114) (xy 113.011712 -220.648022) (xy 112.988852 -220.643704) (xy 112.964 -220.63857)
			(xy 112.916153 -220.621668) (xy 112.871462 -220.597632) (xy 112.830984 -220.567029) (xy 112.795674 -220.530584)
			(xy 112.766368 -220.489157) (xy 112.743757 -220.443728) (xy 112.728377 -220.39537) (xy 112.720591 -220.345226)
			(xy 112.72012 -220.319854) (xy 111.499904 -220.319854) (xy 111.499294 -220.347507) (xy 111.489971 -220.402025)
			(xy 111.481362 -220.428312) (xy 111.473742 -220.45041) (xy 111.678974 -220.805756) (xy 111.701834 -220.810074)
			(xy 111.726645 -220.815229) (xy 111.774384 -220.832223) (xy 111.818962 -220.856322) (xy 111.859327 -220.886957)
			(xy 111.89453 -220.923408) (xy 111.92374 -220.964816) (xy 111.946272 -221.010206) (xy 111.961592 -221.058509)
			(xy 111.969342 -221.108587) (xy 111.969804 -221.133924) (xy 111.969296 -221.159811) (xy 111.961197 -221.210949)
			(xy 111.945198 -221.260189) (xy 111.921692 -221.306321) (xy 111.89126 -221.348208) (xy 111.85465 -221.384818)
			(xy 111.812763 -221.41525) (xy 111.766631 -221.438756) (xy 111.717391 -221.454755) (xy 111.666253 -221.462854)
			(xy 111.614479 -221.462854) (xy 111.563341 -221.454755) (xy 111.514101 -221.438756) (xy 111.467969 -221.41525)
			(xy 111.426082 -221.384818) (xy 111.389472 -221.348208) (xy 111.35904 -221.306321) (xy 111.335534 -221.260189)
			(xy 111.319535 -221.210949) (xy 111.311436 -221.159811) (xy 111.310928 -221.133924) (xy 111.311467 -221.106216)
			(xy 111.320656 -221.05157) (xy 111.329216 -221.025212) (xy 111.33709 -221.003114) (xy 111.132112 -220.648022)
			(xy 111.109252 -220.643704) (xy 111.0844 -220.63857) (xy 111.036553 -220.621668) (xy 110.991862 -220.597632)
			(xy 110.951384 -220.567029) (xy 110.916074 -220.530584) (xy 110.886768 -220.489157) (xy 110.864157 -220.443728)
			(xy 110.848777 -220.39537) (xy 110.840991 -220.345226) (xy 110.84052 -220.319854) (xy 109.620304 -220.319854)
			(xy 109.619694 -220.347507) (xy 109.610371 -220.402025) (xy 109.601762 -220.428312) (xy 109.594142 -220.45041)
			(xy 109.799374 -220.805756) (xy 109.822234 -220.810074) (xy 109.847045 -220.815229) (xy 109.894784 -220.832223)
			(xy 109.939362 -220.856322) (xy 109.979727 -220.886957) (xy 110.01493 -220.923408) (xy 110.04414 -220.964816)
			(xy 110.066672 -221.010206) (xy 110.081992 -221.058509) (xy 110.089742 -221.108587) (xy 110.090204 -221.133924)
			(xy 110.089696 -221.159811) (xy 110.081597 -221.210949) (xy 110.065598 -221.260189) (xy 110.042092 -221.306321)
			(xy 110.01166 -221.348208) (xy 109.97505 -221.384818) (xy 109.933163 -221.41525) (xy 109.887031 -221.438756)
			(xy 109.837791 -221.454755) (xy 109.786653 -221.462854) (xy 109.734879 -221.462854) (xy 109.683741 -221.454755)
			(xy 109.634501 -221.438756) (xy 109.588369 -221.41525) (xy 109.546482 -221.384818) (xy 109.509872 -221.348208)
			(xy 109.47944 -221.306321) (xy 109.455934 -221.260189) (xy 109.439935 -221.210949) (xy 109.431836 -221.159811)
			(xy 109.431328 -221.133924) (xy 109.431867 -221.106216) (xy 109.441056 -221.05157) (xy 109.449616 -221.025212)
			(xy 109.45749 -221.003114) (xy 109.252512 -220.648022) (xy 109.229652 -220.643704) (xy 109.2048 -220.63857)
			(xy 109.156953 -220.621668) (xy 109.112262 -220.597632) (xy 109.071784 -220.567029) (xy 109.036474 -220.530584)
			(xy 109.007168 -220.489157) (xy 108.984557 -220.443728) (xy 108.969177 -220.39537) (xy 108.961391 -220.345226)
			(xy 108.96092 -220.319854) (xy 107.740704 -220.319854) (xy 107.740094 -220.347507) (xy 107.730771 -220.402025)
			(xy 107.722162 -220.428312) (xy 107.714542 -220.45041) (xy 107.919774 -220.805756) (xy 107.942634 -220.810074)
			(xy 107.967445 -220.815229) (xy 108.015184 -220.832223) (xy 108.059762 -220.856322) (xy 108.100127 -220.886957)
			(xy 108.13533 -220.923408) (xy 108.16454 -220.964816) (xy 108.187072 -221.010206) (xy 108.202392 -221.058509)
			(xy 108.210142 -221.108587) (xy 108.210604 -221.133924) (xy 108.210096 -221.159811) (xy 108.201997 -221.210949)
			(xy 108.185998 -221.260189) (xy 108.162492 -221.306321) (xy 108.13206 -221.348208) (xy 108.09545 -221.384818)
			(xy 108.053563 -221.41525) (xy 108.007431 -221.438756) (xy 107.958191 -221.454755) (xy 107.907053 -221.462854)
			(xy 107.855279 -221.462854) (xy 107.804141 -221.454755) (xy 107.754901 -221.438756) (xy 107.708769 -221.41525)
			(xy 107.666882 -221.384818) (xy 107.630272 -221.348208) (xy 107.59984 -221.306321) (xy 107.576334 -221.260189)
			(xy 107.560335 -221.210949) (xy 107.552236 -221.159811) (xy 107.551728 -221.133924) (xy 107.552267 -221.106216)
			(xy 107.561456 -221.05157) (xy 107.570016 -221.025212) (xy 107.57789 -221.003114) (xy 107.372912 -220.648022)
			(xy 107.350052 -220.643704) (xy 107.3252 -220.63857) (xy 107.277353 -220.621668) (xy 107.232662 -220.597632)
			(xy 107.192184 -220.567029) (xy 107.156874 -220.530584) (xy 107.127568 -220.489157) (xy 107.104957 -220.443728)
			(xy 107.089577 -220.39537) (xy 107.081791 -220.345226) (xy 107.08132 -220.319854) (xy 105.861104 -220.319854)
			(xy 105.860494 -220.347507) (xy 105.851171 -220.402025) (xy 105.842562 -220.428312) (xy 105.834942 -220.45041)
			(xy 106.040174 -220.805756) (xy 106.063034 -220.810074) (xy 106.087845 -220.815229) (xy 106.135584 -220.832223)
			(xy 106.180162 -220.856322) (xy 106.220527 -220.886957) (xy 106.25573 -220.923408) (xy 106.28494 -220.964816)
			(xy 106.307472 -221.010206) (xy 106.322792 -221.058509) (xy 106.330542 -221.108587) (xy 106.331004 -221.133924)
			(xy 106.330496 -221.159811) (xy 106.322397 -221.210949) (xy 106.306398 -221.260189) (xy 106.282892 -221.306321)
			(xy 106.25246 -221.348208) (xy 106.21585 -221.384818) (xy 106.173963 -221.41525) (xy 106.127831 -221.438756)
			(xy 106.078591 -221.454755) (xy 106.027453 -221.462854) (xy 105.975679 -221.462854) (xy 105.924541 -221.454755)
			(xy 105.875301 -221.438756) (xy 105.829169 -221.41525) (xy 105.787282 -221.384818) (xy 105.750672 -221.348208)
			(xy 105.72024 -221.306321) (xy 105.696734 -221.260189) (xy 105.680735 -221.210949) (xy 105.672636 -221.159811)
			(xy 105.672128 -221.133924) (xy 105.672667 -221.106216) (xy 105.681856 -221.05157) (xy 105.690416 -221.025212)
			(xy 105.69829 -221.003114) (xy 105.493312 -220.648022) (xy 105.470452 -220.643704) (xy 105.4456 -220.63857)
			(xy 105.397753 -220.621668) (xy 105.353062 -220.597632) (xy 105.312584 -220.567029) (xy 105.277274 -220.530584)
			(xy 105.247968 -220.489157) (xy 105.225357 -220.443728) (xy 105.209977 -220.39537) (xy 105.202191 -220.345226)
			(xy 105.20172 -220.319854) (xy 103.981504 -220.319854) (xy 103.981028 -220.345199) (xy 103.973249 -220.395289)
			(xy 103.957897 -220.443599) (xy 103.935334 -220.48899) (xy 103.906091 -220.530396) (xy 103.870857 -220.566839)
			(xy 103.830462 -220.597461) (xy 103.785857 -220.621543) (xy 103.738093 -220.638516) (xy 103.71328 -220.643704)
			(xy 103.69042 -220.648022) (xy 103.485442 -221.003114) (xy 103.493316 -221.024958) (xy 103.50191 -221.051373)
			(xy 103.511097 -221.106151) (xy 103.511604 -221.133924) (xy 103.511096 -221.159811) (xy 103.502997 -221.210949)
			(xy 103.486998 -221.260189) (xy 103.463492 -221.306321) (xy 103.43306 -221.348208) (xy 103.39645 -221.384818)
			(xy 103.354563 -221.41525) (xy 103.308431 -221.438756) (xy 103.259191 -221.454755) (xy 103.208053 -221.462854)
			(xy 103.156279 -221.462854) (xy 103.105141 -221.454755) (xy 103.055901 -221.438756) (xy 103.009769 -221.41525)
			(xy 102.967882 -221.384818) (xy 102.931272 -221.348208) (xy 102.90084 -221.306321) (xy 102.877334 -221.260189)
			(xy 102.861335 -221.210949) (xy 102.853236 -221.159811) (xy 102.852728 -221.133924) (xy 102.571804 -221.133924)
			(xy 102.57128 -221.161632) (xy 102.562081 -221.216279) (xy 102.553516 -221.242636) (xy 102.545642 -221.264734)
			(xy 102.75062 -221.619572) (xy 102.77348 -221.62389) (xy 102.798305 -221.629041) (xy 102.846083 -221.645999)
			(xy 102.890702 -221.670074) (xy 102.931107 -221.700696) (xy 102.966347 -221.737145) (xy 102.99559 -221.778561)
			(xy 103.018147 -221.823965) (xy 103.033485 -221.872289) (xy 103.041242 -221.92239) (xy 103.041704 -221.94774)
			(xy 104.26192 -221.94774) (xy 104.262371 -221.922394) (xy 104.270152 -221.872302) (xy 104.285506 -221.82399)
			(xy 104.308072 -221.778597) (xy 104.337318 -221.737192) (xy 104.372555 -221.700749) (xy 104.412954 -221.670127)
			(xy 104.457562 -221.646047) (xy 104.50533 -221.629076) (xy 104.530144 -221.62389) (xy 104.553004 -221.619572)
			(xy 104.758236 -221.264226) (xy 104.750362 -221.242128) (xy 104.741898 -221.215883) (xy 104.732825 -221.161495)
			(xy 104.732328 -221.133924) (xy 104.732836 -221.108037) (xy 104.740935 -221.056899) (xy 104.756934 -221.007659)
			(xy 104.78044 -220.961527) (xy 104.810872 -220.91964) (xy 104.847482 -220.88303) (xy 104.889369 -220.852598)
			(xy 104.935501 -220.829092) (xy 104.984741 -220.813093) (xy 105.035879 -220.804994) (xy 105.087653 -220.804994)
			(xy 105.138791 -220.813093) (xy 105.188031 -220.829092) (xy 105.234163 -220.852598) (xy 105.27605 -220.88303)
			(xy 105.31266 -220.91964) (xy 105.343092 -220.961527) (xy 105.366598 -221.007659) (xy 105.382597 -221.056899)
			(xy 105.390696 -221.108037) (xy 105.391204 -221.133924) (xy 105.390748 -221.159299) (xy 105.382976 -221.20945)
			(xy 105.367604 -221.257815) (xy 105.344997 -221.303251) (xy 105.315689 -221.344682) (xy 105.280373 -221.381128)
			(xy 105.239885 -221.411727) (xy 105.195184 -221.435754) (xy 105.147326 -221.452641) (xy 105.122472 -221.457774)
			(xy 105.099612 -221.462092) (xy 104.894888 -221.81693) (xy 104.902762 -221.838774) (xy 104.911419 -221.865179)
			(xy 104.920732 -221.919958) (xy 104.921304 -221.94774) (xy 106.14152 -221.94774) (xy 106.141971 -221.922394)
			(xy 106.149752 -221.872302) (xy 106.165106 -221.82399) (xy 106.187672 -221.778597) (xy 106.216918 -221.737192)
			(xy 106.252155 -221.700749) (xy 106.292554 -221.670127) (xy 106.337162 -221.646047) (xy 106.38493 -221.629076)
			(xy 106.409744 -221.62389) (xy 106.432604 -221.619572) (xy 106.637836 -221.264226) (xy 106.629962 -221.242128)
			(xy 106.621498 -221.215883) (xy 106.612425 -221.161495) (xy 106.611928 -221.133924) (xy 106.612436 -221.108037)
			(xy 106.620535 -221.056899) (xy 106.636534 -221.007659) (xy 106.66004 -220.961527) (xy 106.690472 -220.91964)
			(xy 106.727082 -220.88303) (xy 106.768969 -220.852598) (xy 106.815101 -220.829092) (xy 106.864341 -220.813093)
			(xy 106.915479 -220.804994) (xy 106.967253 -220.804994) (xy 107.018391 -220.813093) (xy 107.067631 -220.829092)
			(xy 107.113763 -220.852598) (xy 107.15565 -220.88303) (xy 107.19226 -220.91964) (xy 107.222692 -220.961527)
			(xy 107.246198 -221.007659) (xy 107.262197 -221.056899) (xy 107.270296 -221.108037) (xy 107.270804 -221.133924)
			(xy 107.270348 -221.159299) (xy 107.262576 -221.20945) (xy 107.247204 -221.257815) (xy 107.224597 -221.303251)
			(xy 107.195289 -221.344682) (xy 107.159973 -221.381128) (xy 107.119485 -221.411727) (xy 107.074784 -221.435754)
			(xy 107.026926 -221.452641) (xy 107.002072 -221.457774) (xy 106.979212 -221.462092) (xy 106.774488 -221.81693)
			(xy 106.782362 -221.838774) (xy 106.791019 -221.865179) (xy 106.800332 -221.919958) (xy 106.800904 -221.94774)
			(xy 108.02112 -221.94774) (xy 108.021571 -221.922394) (xy 108.029352 -221.872302) (xy 108.044706 -221.82399)
			(xy 108.067272 -221.778597) (xy 108.096518 -221.737192) (xy 108.131755 -221.700749) (xy 108.172154 -221.670127)
			(xy 108.216762 -221.646047) (xy 108.26453 -221.629076) (xy 108.289344 -221.62389) (xy 108.312204 -221.619572)
			(xy 108.517436 -221.264226) (xy 108.509562 -221.242128) (xy 108.501098 -221.215883) (xy 108.492025 -221.161495)
			(xy 108.491528 -221.133924) (xy 108.492036 -221.108037) (xy 108.500135 -221.056899) (xy 108.516134 -221.007659)
			(xy 108.53964 -220.961527) (xy 108.570072 -220.91964) (xy 108.606682 -220.88303) (xy 108.648569 -220.852598)
			(xy 108.694701 -220.829092) (xy 108.743941 -220.813093) (xy 108.795079 -220.804994) (xy 108.846853 -220.804994)
			(xy 108.897991 -220.813093) (xy 108.947231 -220.829092) (xy 108.993363 -220.852598) (xy 109.03525 -220.88303)
			(xy 109.07186 -220.91964) (xy 109.102292 -220.961527) (xy 109.125798 -221.007659) (xy 109.141797 -221.056899)
			(xy 109.149896 -221.108037) (xy 109.150404 -221.133924) (xy 109.149948 -221.159299) (xy 109.142176 -221.20945)
			(xy 109.126804 -221.257815) (xy 109.104197 -221.303251) (xy 109.074889 -221.344682) (xy 109.039573 -221.381128)
			(xy 108.999085 -221.411727) (xy 108.954384 -221.435754) (xy 108.906526 -221.452641) (xy 108.881672 -221.457774)
			(xy 108.858812 -221.462092) (xy 108.654088 -221.81693) (xy 108.661962 -221.838774) (xy 108.670619 -221.865179)
			(xy 108.679932 -221.919958) (xy 108.680504 -221.94774) (xy 109.901228 -221.94774) (xy 109.901634 -221.922403)
			(xy 109.909396 -221.872326) (xy 109.924728 -221.824026) (xy 109.947269 -221.77864) (xy 109.976489 -221.737238)
			(xy 110.011699 -221.700794) (xy 110.05207 -221.670165) (xy 110.096652 -221.646074) (xy 110.144395 -221.629087)
			(xy 110.169198 -221.62389) (xy 110.192058 -221.619572) (xy 110.397036 -221.26448) (xy 110.389416 -221.242382)
			(xy 110.380897 -221.216211) (xy 110.371703 -221.161949) (xy 110.371128 -221.134432) (xy 110.371128 -221.133924)
			(xy 110.371636 -221.108037) (xy 110.379735 -221.056899) (xy 110.395734 -221.007659) (xy 110.41924 -220.961527)
			(xy 110.449672 -220.91964) (xy 110.486282 -220.88303) (xy 110.528169 -220.852598) (xy 110.574301 -220.829092)
			(xy 110.623541 -220.813093) (xy 110.674679 -220.804994) (xy 110.726453 -220.804994) (xy 110.777591 -220.813093)
			(xy 110.826831 -220.829092) (xy 110.872963 -220.852598) (xy 110.91485 -220.88303) (xy 110.95146 -220.91964)
			(xy 110.981892 -220.961527) (xy 111.005398 -221.007659) (xy 111.021397 -221.056899) (xy 111.029496 -221.108037)
			(xy 111.030004 -221.133924) (xy 111.029585 -221.15929) (xy 111.021833 -221.209425) (xy 111.006484 -221.257778)
			(xy 110.983902 -221.303206) (xy 110.954621 -221.344633) (xy 110.919333 -221.381081) (xy 110.878874 -221.411686)
			(xy 110.8342 -221.435725) (xy 110.786369 -221.45263) (xy 110.761526 -221.457774) (xy 110.738666 -221.462092)
			(xy 110.533942 -221.81693) (xy 110.541816 -221.838774) (xy 110.550414 -221.865187) (xy 110.559598 -221.919967)
			(xy 110.560104 -221.94774) (xy 111.78032 -221.94774) (xy 111.780771 -221.922394) (xy 111.788552 -221.872302)
			(xy 111.803906 -221.82399) (xy 111.826472 -221.778597) (xy 111.855718 -221.737192) (xy 111.890955 -221.700749)
			(xy 111.931354 -221.670127) (xy 111.975962 -221.646047) (xy 112.02373 -221.629076) (xy 112.048544 -221.62389)
			(xy 112.071404 -221.619572) (xy 112.276636 -221.264226) (xy 112.268762 -221.242128) (xy 112.260298 -221.215883)
			(xy 112.251225 -221.161495) (xy 112.250728 -221.133924) (xy 112.251236 -221.108037) (xy 112.259335 -221.056899)
			(xy 112.275334 -221.007659) (xy 112.29884 -220.961527) (xy 112.329272 -220.91964) (xy 112.365882 -220.88303)
			(xy 112.407769 -220.852598) (xy 112.453901 -220.829092) (xy 112.503141 -220.813093) (xy 112.554279 -220.804994)
			(xy 112.606053 -220.804994) (xy 112.657191 -220.813093) (xy 112.706431 -220.829092) (xy 112.752563 -220.852598)
			(xy 112.79445 -220.88303) (xy 112.83106 -220.91964) (xy 112.861492 -220.961527) (xy 112.884998 -221.007659)
			(xy 112.900997 -221.056899) (xy 112.909096 -221.108037) (xy 112.909604 -221.133924) (xy 112.909148 -221.159299)
			(xy 112.901376 -221.20945) (xy 112.886004 -221.257815) (xy 112.863397 -221.303251) (xy 112.834089 -221.344682)
			(xy 112.798773 -221.381128) (xy 112.758285 -221.411727) (xy 112.713584 -221.435754) (xy 112.665726 -221.452641)
			(xy 112.640872 -221.457774) (xy 112.618012 -221.462092) (xy 112.413288 -221.81693) (xy 112.421162 -221.838774)
			(xy 112.429819 -221.865179) (xy 112.439132 -221.919958) (xy 112.439704 -221.94774) (xy 113.660428 -221.94774)
			(xy 113.660834 -221.922403) (xy 113.668596 -221.872326) (xy 113.683928 -221.824026) (xy 113.706469 -221.77864)
			(xy 113.735689 -221.737238) (xy 113.770899 -221.700794) (xy 113.81127 -221.670165) (xy 113.855852 -221.646074)
			(xy 113.903595 -221.629087) (xy 113.928398 -221.62389) (xy 113.951258 -221.619572) (xy 114.156236 -221.26448)
			(xy 114.148616 -221.242382) (xy 114.140097 -221.216211) (xy 114.130903 -221.161949) (xy 114.130328 -221.134432)
			(xy 114.130328 -221.133924) (xy 114.130836 -221.108037) (xy 114.138935 -221.056899) (xy 114.154934 -221.007659)
			(xy 114.17844 -220.961527) (xy 114.208872 -220.91964) (xy 114.245482 -220.88303) (xy 114.287369 -220.852598)
			(xy 114.333501 -220.829092) (xy 114.382741 -220.813093) (xy 114.433879 -220.804994) (xy 114.485653 -220.804994)
			(xy 114.536791 -220.813093) (xy 114.586031 -220.829092) (xy 114.632163 -220.852598) (xy 114.67405 -220.88303)
			(xy 114.71066 -220.91964) (xy 114.741092 -220.961527) (xy 114.764598 -221.007659) (xy 114.780597 -221.056899)
			(xy 114.788696 -221.108037) (xy 114.789204 -221.133924) (xy 114.788785 -221.15929) (xy 114.781033 -221.209425)
			(xy 114.765684 -221.257778) (xy 114.743102 -221.303206) (xy 114.713821 -221.344633) (xy 114.678533 -221.381081)
			(xy 114.638074 -221.411686) (xy 114.5934 -221.435725) (xy 114.545569 -221.45263) (xy 114.520726 -221.457774)
			(xy 114.497866 -221.462092) (xy 114.293142 -221.81693) (xy 114.301016 -221.838774) (xy 114.309614 -221.865187)
			(xy 114.318798 -221.919967) (xy 114.319304 -221.94774) (xy 115.53952 -221.94774) (xy 115.539971 -221.922394)
			(xy 115.547752 -221.872302) (xy 115.563106 -221.82399) (xy 115.585672 -221.778597) (xy 115.614918 -221.737192)
			(xy 115.650155 -221.700749) (xy 115.690554 -221.670127) (xy 115.735162 -221.646047) (xy 115.78293 -221.629076)
			(xy 115.807744 -221.62389) (xy 115.830604 -221.619572) (xy 116.035836 -221.264226) (xy 116.027962 -221.242128)
			(xy 116.019498 -221.215883) (xy 116.010425 -221.161495) (xy 116.009928 -221.133924) (xy 116.010436 -221.108037)
			(xy 116.018535 -221.056899) (xy 116.034534 -221.007659) (xy 116.05804 -220.961527) (xy 116.088472 -220.91964)
			(xy 116.125082 -220.88303) (xy 116.166969 -220.852598) (xy 116.213101 -220.829092) (xy 116.262341 -220.813093)
			(xy 116.313479 -220.804994) (xy 116.365253 -220.804994) (xy 116.416391 -220.813093) (xy 116.465631 -220.829092)
			(xy 116.511763 -220.852598) (xy 116.55365 -220.88303) (xy 116.59026 -220.91964) (xy 116.620692 -220.961527)
			(xy 116.644198 -221.007659) (xy 116.660197 -221.056899) (xy 116.668296 -221.108037) (xy 116.668804 -221.133924)
			(xy 116.668348 -221.159299) (xy 116.660576 -221.20945) (xy 116.645204 -221.257815) (xy 116.622597 -221.303251)
			(xy 116.593289 -221.344682) (xy 116.557973 -221.381128) (xy 116.517485 -221.411727) (xy 116.472784 -221.435754)
			(xy 116.424926 -221.452641) (xy 116.400072 -221.457774) (xy 116.377212 -221.462092) (xy 116.172488 -221.81693)
			(xy 116.180362 -221.838774) (xy 116.189019 -221.865179) (xy 116.198332 -221.919958) (xy 116.198904 -221.94774)
			(xy 117.41912 -221.94774) (xy 117.419571 -221.922394) (xy 117.427352 -221.872302) (xy 117.442706 -221.82399)
			(xy 117.465272 -221.778597) (xy 117.494518 -221.737192) (xy 117.529755 -221.700749) (xy 117.570154 -221.670127)
			(xy 117.614762 -221.646047) (xy 117.66253 -221.629076) (xy 117.687344 -221.62389) (xy 117.710204 -221.619572)
			(xy 117.915436 -221.264226) (xy 117.907562 -221.242128) (xy 117.899098 -221.215883) (xy 117.890025 -221.161495)
			(xy 117.889528 -221.133924) (xy 117.890036 -221.108037) (xy 117.898135 -221.056899) (xy 117.914134 -221.007659)
			(xy 117.93764 -220.961527) (xy 117.968072 -220.91964) (xy 118.004682 -220.88303) (xy 118.046569 -220.852598)
			(xy 118.092701 -220.829092) (xy 118.141941 -220.813093) (xy 118.193079 -220.804994) (xy 118.244853 -220.804994)
			(xy 118.295991 -220.813093) (xy 118.345231 -220.829092) (xy 118.391363 -220.852598) (xy 118.43325 -220.88303)
			(xy 118.46986 -220.91964) (xy 118.500292 -220.961527) (xy 118.523798 -221.007659) (xy 118.539797 -221.056899)
			(xy 118.547896 -221.108037) (xy 118.548404 -221.133924) (xy 118.547948 -221.159299) (xy 118.540176 -221.20945)
			(xy 118.524804 -221.257815) (xy 118.502197 -221.303251) (xy 118.472889 -221.344682) (xy 118.437573 -221.381128)
			(xy 118.397085 -221.411727) (xy 118.352384 -221.435754) (xy 118.304526 -221.452641) (xy 118.279672 -221.457774)
			(xy 118.256812 -221.462092) (xy 118.052088 -221.81693) (xy 118.059962 -221.838774) (xy 118.068619 -221.865179)
			(xy 118.077932 -221.919958) (xy 118.078504 -221.94774) (xy 121.17832 -221.94774) (xy 121.178771 -221.922394)
			(xy 121.186552 -221.872302) (xy 121.201906 -221.82399) (xy 121.224472 -221.778597) (xy 121.253718 -221.737192)
			(xy 121.288955 -221.700749) (xy 121.329354 -221.670127) (xy 121.373962 -221.646047) (xy 121.42173 -221.629076)
			(xy 121.446544 -221.62389) (xy 121.469404 -221.619572) (xy 121.674636 -221.264226) (xy 121.666762 -221.242128)
			(xy 121.658298 -221.215883) (xy 121.649225 -221.161495) (xy 121.648728 -221.133924) (xy 121.649236 -221.108037)
			(xy 121.657335 -221.056899) (xy 121.673334 -221.007659) (xy 121.69684 -220.961527) (xy 121.727272 -220.91964)
			(xy 121.763882 -220.88303) (xy 121.805769 -220.852598) (xy 121.851901 -220.829092) (xy 121.901141 -220.813093)
			(xy 121.952279 -220.804994) (xy 122.004053 -220.804994) (xy 122.055191 -220.813093) (xy 122.104431 -220.829092)
			(xy 122.150563 -220.852598) (xy 122.19245 -220.88303) (xy 122.22906 -220.91964) (xy 122.259492 -220.961527)
			(xy 122.282998 -221.007659) (xy 122.298997 -221.056899) (xy 122.307096 -221.108037) (xy 122.307604 -221.133924)
			(xy 122.307148 -221.159299) (xy 122.299376 -221.20945) (xy 122.284004 -221.257815) (xy 122.261397 -221.303251)
			(xy 122.232089 -221.344682) (xy 122.196773 -221.381128) (xy 122.156285 -221.411727) (xy 122.111584 -221.435754)
			(xy 122.063726 -221.452641) (xy 122.038872 -221.457774) (xy 122.016012 -221.462092) (xy 121.811288 -221.81693)
			(xy 121.819162 -221.838774) (xy 121.827819 -221.865179) (xy 121.837132 -221.919958) (xy 121.837704 -221.94774)
			(xy 123.05792 -221.94774) (xy 123.058371 -221.922394) (xy 123.066152 -221.872302) (xy 123.081506 -221.82399)
			(xy 123.104072 -221.778597) (xy 123.133318 -221.737192) (xy 123.168555 -221.700749) (xy 123.208954 -221.670127)
			(xy 123.253562 -221.646047) (xy 123.30133 -221.629076) (xy 123.326144 -221.62389) (xy 123.349004 -221.619572)
			(xy 123.554236 -221.264226) (xy 123.546362 -221.242128) (xy 123.537898 -221.215883) (xy 123.528825 -221.161495)
			(xy 123.528328 -221.133924) (xy 123.528836 -221.108037) (xy 123.536935 -221.056899) (xy 123.552934 -221.007659)
			(xy 123.57644 -220.961527) (xy 123.606872 -220.91964) (xy 123.643482 -220.88303) (xy 123.685369 -220.852598)
			(xy 123.731501 -220.829092) (xy 123.780741 -220.813093) (xy 123.831879 -220.804994) (xy 123.883653 -220.804994)
			(xy 123.934791 -220.813093) (xy 123.984031 -220.829092) (xy 124.030163 -220.852598) (xy 124.07205 -220.88303)
			(xy 124.10866 -220.91964) (xy 124.139092 -220.961527) (xy 124.162598 -221.007659) (xy 124.178597 -221.056899)
			(xy 124.186696 -221.108037) (xy 124.187204 -221.133924) (xy 124.186748 -221.159299) (xy 124.178976 -221.20945)
			(xy 124.163604 -221.257815) (xy 124.140997 -221.303251) (xy 124.111689 -221.344682) (xy 124.076373 -221.381128)
			(xy 124.035885 -221.411727) (xy 123.991184 -221.435754) (xy 123.943326 -221.452641) (xy 123.918472 -221.457774)
			(xy 123.895612 -221.462092) (xy 123.690888 -221.81693) (xy 123.698762 -221.838774) (xy 123.707419 -221.865179)
			(xy 123.716732 -221.919958) (xy 123.717304 -221.94774) (xy 124.93752 -221.94774) (xy 124.937971 -221.922394)
			(xy 124.945752 -221.872302) (xy 124.961106 -221.82399) (xy 124.983672 -221.778597) (xy 125.012918 -221.737192)
			(xy 125.048155 -221.700749) (xy 125.088554 -221.670127) (xy 125.133162 -221.646047) (xy 125.18093 -221.629076)
			(xy 125.205744 -221.62389) (xy 125.228604 -221.619572) (xy 125.433836 -221.264226) (xy 125.425962 -221.242128)
			(xy 125.417498 -221.215883) (xy 125.408425 -221.161495) (xy 125.407928 -221.133924) (xy 125.408436 -221.108037)
			(xy 125.416535 -221.056899) (xy 125.432534 -221.007659) (xy 125.45604 -220.961527) (xy 125.486472 -220.91964)
			(xy 125.523082 -220.88303) (xy 125.564969 -220.852598) (xy 125.611101 -220.829092) (xy 125.660341 -220.813093)
			(xy 125.711479 -220.804994) (xy 125.763253 -220.804994) (xy 125.814391 -220.813093) (xy 125.863631 -220.829092)
			(xy 125.909763 -220.852598) (xy 125.95165 -220.88303) (xy 125.98826 -220.91964) (xy 126.018692 -220.961527)
			(xy 126.042198 -221.007659) (xy 126.058197 -221.056899) (xy 126.066296 -221.108037) (xy 126.066804 -221.133924)
			(xy 126.066348 -221.159299) (xy 126.058576 -221.20945) (xy 126.043204 -221.257815) (xy 126.020597 -221.303251)
			(xy 125.991289 -221.344682) (xy 125.955973 -221.381128) (xy 125.915485 -221.411727) (xy 125.870784 -221.435754)
			(xy 125.822926 -221.452641) (xy 125.798072 -221.457774) (xy 125.775212 -221.462092) (xy 125.570488 -221.81693)
			(xy 125.578362 -221.838774) (xy 125.587019 -221.865179) (xy 125.596332 -221.919958) (xy 125.596904 -221.94774)
			(xy 126.81712 -221.94774) (xy 126.817571 -221.922394) (xy 126.825352 -221.872302) (xy 126.840706 -221.82399)
			(xy 126.863272 -221.778597) (xy 126.892518 -221.737192) (xy 126.927755 -221.700749) (xy 126.968154 -221.670127)
			(xy 127.012762 -221.646047) (xy 127.06053 -221.629076) (xy 127.085344 -221.62389) (xy 127.108204 -221.619572)
			(xy 127.313436 -221.264226) (xy 127.305562 -221.242128) (xy 127.297098 -221.215883) (xy 127.288025 -221.161495)
			(xy 127.287528 -221.133924) (xy 127.288036 -221.108037) (xy 127.296135 -221.056899) (xy 127.312134 -221.007659)
			(xy 127.33564 -220.961527) (xy 127.366072 -220.91964) (xy 127.402682 -220.88303) (xy 127.444569 -220.852598)
			(xy 127.490701 -220.829092) (xy 127.539941 -220.813093) (xy 127.591079 -220.804994) (xy 127.642853 -220.804994)
			(xy 127.693991 -220.813093) (xy 127.743231 -220.829092) (xy 127.789363 -220.852598) (xy 127.83125 -220.88303)
			(xy 127.86786 -220.91964) (xy 127.898292 -220.961527) (xy 127.921798 -221.007659) (xy 127.937797 -221.056899)
			(xy 127.945896 -221.108037) (xy 127.946404 -221.133924) (xy 127.945948 -221.159299) (xy 127.938176 -221.20945)
			(xy 127.922804 -221.257815) (xy 127.900197 -221.303251) (xy 127.870889 -221.344682) (xy 127.835573 -221.381128)
			(xy 127.795085 -221.411727) (xy 127.750384 -221.435754) (xy 127.702526 -221.452641) (xy 127.677672 -221.457774)
			(xy 127.654812 -221.462092) (xy 127.450088 -221.81693) (xy 127.457962 -221.838774) (xy 127.466619 -221.865179)
			(xy 127.475932 -221.919958) (xy 127.476504 -221.94774) (xy 128.69672 -221.94774) (xy 128.697171 -221.922394)
			(xy 128.704952 -221.872302) (xy 128.720306 -221.82399) (xy 128.742872 -221.778597) (xy 128.772118 -221.737192)
			(xy 128.807355 -221.700749) (xy 128.847754 -221.670127) (xy 128.892362 -221.646047) (xy 128.94013 -221.629076)
			(xy 128.964944 -221.62389) (xy 128.987804 -221.619572) (xy 129.193036 -221.264226) (xy 129.185162 -221.242128)
			(xy 129.176698 -221.215883) (xy 129.167625 -221.161495) (xy 129.167128 -221.133924) (xy 129.167636 -221.108037)
			(xy 129.175735 -221.056899) (xy 129.191734 -221.007659) (xy 129.21524 -220.961527) (xy 129.245672 -220.91964)
			(xy 129.282282 -220.88303) (xy 129.324169 -220.852598) (xy 129.370301 -220.829092) (xy 129.419541 -220.813093)
			(xy 129.470679 -220.804994) (xy 129.522453 -220.804994) (xy 129.573591 -220.813093) (xy 129.622831 -220.829092)
			(xy 129.668963 -220.852598) (xy 129.71085 -220.88303) (xy 129.74746 -220.91964) (xy 129.777892 -220.961527)
			(xy 129.801398 -221.007659) (xy 129.817397 -221.056899) (xy 129.825496 -221.108037) (xy 129.826004 -221.133924)
			(xy 129.825548 -221.159299) (xy 129.817776 -221.20945) (xy 129.802404 -221.257815) (xy 129.779797 -221.303251)
			(xy 129.750489 -221.344682) (xy 129.715173 -221.381128) (xy 129.674685 -221.411727) (xy 129.629984 -221.435754)
			(xy 129.582126 -221.452641) (xy 129.557272 -221.457774) (xy 129.534412 -221.462092) (xy 129.329688 -221.81693)
			(xy 129.337562 -221.838774) (xy 129.346219 -221.865179) (xy 129.355532 -221.919958) (xy 129.356104 -221.94774)
			(xy 130.57632 -221.94774) (xy 130.576771 -221.922394) (xy 130.584552 -221.872302) (xy 130.599906 -221.82399)
			(xy 130.622472 -221.778597) (xy 130.651718 -221.737192) (xy 130.686955 -221.700749) (xy 130.727354 -221.670127)
			(xy 130.771962 -221.646047) (xy 130.81973 -221.629076) (xy 130.844544 -221.62389) (xy 130.867404 -221.619572)
			(xy 131.072636 -221.264226) (xy 131.064762 -221.242128) (xy 131.056298 -221.215883) (xy 131.047225 -221.161495)
			(xy 131.046728 -221.133924) (xy 131.047236 -221.108037) (xy 131.055335 -221.056899) (xy 131.071334 -221.007659)
			(xy 131.09484 -220.961527) (xy 131.125272 -220.91964) (xy 131.161882 -220.88303) (xy 131.203769 -220.852598)
			(xy 131.249901 -220.829092) (xy 131.299141 -220.813093) (xy 131.350279 -220.804994) (xy 131.402053 -220.804994)
			(xy 131.453191 -220.813093) (xy 131.502431 -220.829092) (xy 131.548563 -220.852598) (xy 131.59045 -220.88303)
			(xy 131.62706 -220.91964) (xy 131.657492 -220.961527) (xy 131.680998 -221.007659) (xy 131.696997 -221.056899)
			(xy 131.705096 -221.108037) (xy 131.705604 -221.133924) (xy 131.705148 -221.159299) (xy 131.697376 -221.20945)
			(xy 131.682004 -221.257815) (xy 131.659397 -221.303251) (xy 131.630089 -221.344682) (xy 131.594773 -221.381128)
			(xy 131.554285 -221.411727) (xy 131.509584 -221.435754) (xy 131.461726 -221.452641) (xy 131.436872 -221.457774)
			(xy 131.414012 -221.462092) (xy 131.209288 -221.81693) (xy 131.217162 -221.838774) (xy 131.225819 -221.865179)
			(xy 131.235132 -221.919958) (xy 131.235704 -221.94774) (xy 131.235196 -221.973647) (xy 131.22709 -222.024824)
			(xy 131.211078 -222.074103) (xy 131.187555 -222.12027) (xy 131.157099 -222.162189) (xy 131.120461 -222.198827)
			(xy 131.078542 -222.229283) (xy 131.032375 -222.252806) (xy 130.983096 -222.268818) (xy 130.931919 -222.276924)
			(xy 130.880105 -222.276924) (xy 130.828928 -222.268818) (xy 130.779649 -222.252806) (xy 130.733482 -222.229283)
			(xy 130.691563 -222.198827) (xy 130.654925 -222.162189) (xy 130.624469 -222.12027) (xy 130.600946 -222.074103)
			(xy 130.584934 -222.024824) (xy 130.576828 -221.973647) (xy 130.57632 -221.94774) (xy 129.356104 -221.94774)
			(xy 129.355596 -221.973647) (xy 129.34749 -222.024824) (xy 129.331478 -222.074103) (xy 129.307955 -222.12027)
			(xy 129.277499 -222.162189) (xy 129.240861 -222.198827) (xy 129.198942 -222.229283) (xy 129.152775 -222.252806)
			(xy 129.103496 -222.268818) (xy 129.052319 -222.276924) (xy 129.000505 -222.276924) (xy 128.949328 -222.268818)
			(xy 128.900049 -222.252806) (xy 128.853882 -222.229283) (xy 128.811963 -222.198827) (xy 128.775325 -222.162189)
			(xy 128.744869 -222.12027) (xy 128.721346 -222.074103) (xy 128.705334 -222.024824) (xy 128.697228 -221.973647)
			(xy 128.69672 -221.94774) (xy 127.476504 -221.94774) (xy 127.475996 -221.973647) (xy 127.46789 -222.024824)
			(xy 127.451878 -222.074103) (xy 127.428355 -222.12027) (xy 127.397899 -222.162189) (xy 127.361261 -222.198827)
			(xy 127.319342 -222.229283) (xy 127.273175 -222.252806) (xy 127.223896 -222.268818) (xy 127.172719 -222.276924)
			(xy 127.120905 -222.276924) (xy 127.069728 -222.268818) (xy 127.020449 -222.252806) (xy 126.974282 -222.229283)
			(xy 126.932363 -222.198827) (xy 126.895725 -222.162189) (xy 126.865269 -222.12027) (xy 126.841746 -222.074103)
			(xy 126.825734 -222.024824) (xy 126.817628 -221.973647) (xy 126.81712 -221.94774) (xy 125.596904 -221.94774)
			(xy 125.596396 -221.973647) (xy 125.58829 -222.024824) (xy 125.572278 -222.074103) (xy 125.548755 -222.12027)
			(xy 125.518299 -222.162189) (xy 125.481661 -222.198827) (xy 125.439742 -222.229283) (xy 125.393575 -222.252806)
			(xy 125.344296 -222.268818) (xy 125.293119 -222.276924) (xy 125.241305 -222.276924) (xy 125.190128 -222.268818)
			(xy 125.140849 -222.252806) (xy 125.094682 -222.229283) (xy 125.052763 -222.198827) (xy 125.016125 -222.162189)
			(xy 124.985669 -222.12027) (xy 124.962146 -222.074103) (xy 124.946134 -222.024824) (xy 124.938028 -221.973647)
			(xy 124.93752 -221.94774) (xy 123.717304 -221.94774) (xy 123.716796 -221.973647) (xy 123.70869 -222.024824)
			(xy 123.692678 -222.074103) (xy 123.669155 -222.12027) (xy 123.638699 -222.162189) (xy 123.602061 -222.198827)
			(xy 123.560142 -222.229283) (xy 123.513975 -222.252806) (xy 123.464696 -222.268818) (xy 123.413519 -222.276924)
			(xy 123.361705 -222.276924) (xy 123.310528 -222.268818) (xy 123.261249 -222.252806) (xy 123.215082 -222.229283)
			(xy 123.173163 -222.198827) (xy 123.136525 -222.162189) (xy 123.106069 -222.12027) (xy 123.082546 -222.074103)
			(xy 123.066534 -222.024824) (xy 123.058428 -221.973647) (xy 123.05792 -221.94774) (xy 121.837704 -221.94774)
			(xy 121.837196 -221.973647) (xy 121.82909 -222.024824) (xy 121.813078 -222.074103) (xy 121.789555 -222.12027)
			(xy 121.759099 -222.162189) (xy 121.722461 -222.198827) (xy 121.680542 -222.229283) (xy 121.634375 -222.252806)
			(xy 121.585096 -222.268818) (xy 121.533919 -222.276924) (xy 121.482105 -222.276924) (xy 121.430928 -222.268818)
			(xy 121.381649 -222.252806) (xy 121.335482 -222.229283) (xy 121.293563 -222.198827) (xy 121.256925 -222.162189)
			(xy 121.226469 -222.12027) (xy 121.202946 -222.074103) (xy 121.186934 -222.024824) (xy 121.178828 -221.973647)
			(xy 121.17832 -221.94774) (xy 118.078504 -221.94774) (xy 118.077996 -221.973647) (xy 118.06989 -222.024824)
			(xy 118.053878 -222.074103) (xy 118.030355 -222.12027) (xy 117.999899 -222.162189) (xy 117.963261 -222.198827)
			(xy 117.921342 -222.229283) (xy 117.875175 -222.252806) (xy 117.825896 -222.268818) (xy 117.774719 -222.276924)
			(xy 117.722905 -222.276924) (xy 117.671728 -222.268818) (xy 117.622449 -222.252806) (xy 117.576282 -222.229283)
			(xy 117.534363 -222.198827) (xy 117.497725 -222.162189) (xy 117.467269 -222.12027) (xy 117.443746 -222.074103)
			(xy 117.427734 -222.024824) (xy 117.419628 -221.973647) (xy 117.41912 -221.94774) (xy 116.198904 -221.94774)
			(xy 116.198396 -221.973647) (xy 116.19029 -222.024824) (xy 116.174278 -222.074103) (xy 116.150755 -222.12027)
			(xy 116.120299 -222.162189) (xy 116.083661 -222.198827) (xy 116.041742 -222.229283) (xy 115.995575 -222.252806)
			(xy 115.946296 -222.268818) (xy 115.895119 -222.276924) (xy 115.843305 -222.276924) (xy 115.792128 -222.268818)
			(xy 115.742849 -222.252806) (xy 115.696682 -222.229283) (xy 115.654763 -222.198827) (xy 115.618125 -222.162189)
			(xy 115.587669 -222.12027) (xy 115.564146 -222.074103) (xy 115.548134 -222.024824) (xy 115.540028 -221.973647)
			(xy 115.53952 -221.94774) (xy 114.319304 -221.94774) (xy 114.318796 -221.973627) (xy 114.310697 -222.024765)
			(xy 114.294698 -222.074005) (xy 114.271192 -222.120137) (xy 114.24076 -222.162024) (xy 114.20415 -222.198634)
			(xy 114.162263 -222.229066) (xy 114.116131 -222.252572) (xy 114.066891 -222.268571) (xy 114.015753 -222.27667)
			(xy 113.963979 -222.27667) (xy 113.912841 -222.268571) (xy 113.863601 -222.252572) (xy 113.817469 -222.229066)
			(xy 113.775582 -222.198634) (xy 113.738972 -222.162024) (xy 113.70854 -222.120137) (xy 113.685034 -222.074005)
			(xy 113.669035 -222.024765) (xy 113.660936 -221.973627) (xy 113.660428 -221.94774) (xy 112.439704 -221.94774)
			(xy 112.439196 -221.973647) (xy 112.43109 -222.024824) (xy 112.415078 -222.074103) (xy 112.391555 -222.12027)
			(xy 112.361099 -222.162189) (xy 112.324461 -222.198827) (xy 112.282542 -222.229283) (xy 112.236375 -222.252806)
			(xy 112.187096 -222.268818) (xy 112.135919 -222.276924) (xy 112.084105 -222.276924) (xy 112.032928 -222.268818)
			(xy 111.983649 -222.252806) (xy 111.937482 -222.229283) (xy 111.895563 -222.198827) (xy 111.858925 -222.162189)
			(xy 111.828469 -222.12027) (xy 111.804946 -222.074103) (xy 111.788934 -222.024824) (xy 111.780828 -221.973647)
			(xy 111.78032 -221.94774) (xy 110.560104 -221.94774) (xy 110.559596 -221.973627) (xy 110.551497 -222.024765)
			(xy 110.535498 -222.074005) (xy 110.511992 -222.120137) (xy 110.48156 -222.162024) (xy 110.44495 -222.198634)
			(xy 110.403063 -222.229066) (xy 110.356931 -222.252572) (xy 110.307691 -222.268571) (xy 110.256553 -222.27667)
			(xy 110.204779 -222.27667) (xy 110.153641 -222.268571) (xy 110.104401 -222.252572) (xy 110.058269 -222.229066)
			(xy 110.016382 -222.198634) (xy 109.979772 -222.162024) (xy 109.94934 -222.120137) (xy 109.925834 -222.074005)
			(xy 109.909835 -222.024765) (xy 109.901736 -221.973627) (xy 109.901228 -221.94774) (xy 108.680504 -221.94774)
			(xy 108.679996 -221.973647) (xy 108.67189 -222.024824) (xy 108.655878 -222.074103) (xy 108.632355 -222.12027)
			(xy 108.601899 -222.162189) (xy 108.565261 -222.198827) (xy 108.523342 -222.229283) (xy 108.477175 -222.252806)
			(xy 108.427896 -222.268818) (xy 108.376719 -222.276924) (xy 108.324905 -222.276924) (xy 108.273728 -222.268818)
			(xy 108.224449 -222.252806) (xy 108.178282 -222.229283) (xy 108.136363 -222.198827) (xy 108.099725 -222.162189)
			(xy 108.069269 -222.12027) (xy 108.045746 -222.074103) (xy 108.029734 -222.024824) (xy 108.021628 -221.973647)
			(xy 108.02112 -221.94774) (xy 106.800904 -221.94774) (xy 106.800396 -221.973647) (xy 106.79229 -222.024824)
			(xy 106.776278 -222.074103) (xy 106.752755 -222.12027) (xy 106.722299 -222.162189) (xy 106.685661 -222.198827)
			(xy 106.643742 -222.229283) (xy 106.597575 -222.252806) (xy 106.548296 -222.268818) (xy 106.497119 -222.276924)
			(xy 106.445305 -222.276924) (xy 106.394128 -222.268818) (xy 106.344849 -222.252806) (xy 106.298682 -222.229283)
			(xy 106.256763 -222.198827) (xy 106.220125 -222.162189) (xy 106.189669 -222.12027) (xy 106.166146 -222.074103)
			(xy 106.150134 -222.024824) (xy 106.142028 -221.973647) (xy 106.14152 -221.94774) (xy 104.921304 -221.94774)
			(xy 104.920796 -221.973647) (xy 104.91269 -222.024824) (xy 104.896678 -222.074103) (xy 104.873155 -222.12027)
			(xy 104.842699 -222.162189) (xy 104.806061 -222.198827) (xy 104.764142 -222.229283) (xy 104.717975 -222.252806)
			(xy 104.668696 -222.268818) (xy 104.617519 -222.276924) (xy 104.565705 -222.276924) (xy 104.514528 -222.268818)
			(xy 104.465249 -222.252806) (xy 104.419082 -222.229283) (xy 104.377163 -222.198827) (xy 104.340525 -222.162189)
			(xy 104.310069 -222.12027) (xy 104.286546 -222.074103) (xy 104.270534 -222.024824) (xy 104.262428 -221.973647)
			(xy 104.26192 -221.94774) (xy 103.041704 -221.94774) (xy 103.041196 -221.973647) (xy 103.03309 -222.024824)
			(xy 103.017078 -222.074103) (xy 102.993555 -222.12027) (xy 102.963099 -222.162189) (xy 102.926461 -222.198827)
			(xy 102.884542 -222.229283) (xy 102.838375 -222.252806) (xy 102.789096 -222.268818) (xy 102.737919 -222.276924)
			(xy 102.686105 -222.276924) (xy 102.634928 -222.268818) (xy 102.585649 -222.252806) (xy 102.539482 -222.229283)
			(xy 102.497563 -222.198827) (xy 102.460925 -222.162189) (xy 102.430469 -222.12027) (xy 102.406946 -222.074103)
			(xy 102.390934 -222.024824) (xy 102.382828 -221.973647) (xy 102.38232 -221.94774) (xy 102.382923 -221.920023)
			(xy 102.39224 -221.865377) (xy 102.400862 -221.839028) (xy 102.408736 -221.81693) (xy 102.203758 -221.462092)
			(xy 102.180898 -221.457774) (xy 102.156103 -221.45255) (xy 102.108367 -221.435564) (xy 102.063792 -221.411474)
			(xy 102.023427 -221.380847) (xy 101.988224 -221.344405) (xy 101.959011 -221.303006) (xy 101.936476 -221.257625)
			(xy 101.92115 -221.20933) (xy 101.913394 -221.159258) (xy 101.912928 -221.133924) (xy 101.632004 -221.133924)
			(xy 101.631496 -221.159811) (xy 101.623397 -221.210949) (xy 101.607398 -221.260189) (xy 101.583892 -221.306321)
			(xy 101.55346 -221.348208) (xy 101.51685 -221.384818) (xy 101.474963 -221.41525) (xy 101.428831 -221.438756)
			(xy 101.379591 -221.454755) (xy 101.328453 -221.462854) (xy 101.276679 -221.462854) (xy 101.225541 -221.454755)
			(xy 101.176301 -221.438756) (xy 101.130169 -221.41525) (xy 101.088282 -221.384818) (xy 101.051672 -221.348208)
			(xy 101.02124 -221.306321) (xy 100.997734 -221.260189) (xy 100.981735 -221.210949) (xy 100.973636 -221.159811)
			(xy 100.973128 -221.133924) (xy 100.692204 -221.133924) (xy 100.69168 -221.161632) (xy 100.682481 -221.216279)
			(xy 100.673916 -221.242636) (xy 100.666042 -221.264734) (xy 100.87102 -221.619572) (xy 100.89388 -221.62389)
			(xy 100.918705 -221.629041) (xy 100.966483 -221.645999) (xy 101.011102 -221.670074) (xy 101.051507 -221.700696)
			(xy 101.086747 -221.737145) (xy 101.11599 -221.778561) (xy 101.138547 -221.823965) (xy 101.153885 -221.872289)
			(xy 101.161642 -221.92239) (xy 101.162104 -221.94774) (xy 101.161596 -221.973647) (xy 101.15349 -222.024824)
			(xy 101.137478 -222.074103) (xy 101.113955 -222.12027) (xy 101.083499 -222.162189) (xy 101.046861 -222.198827)
			(xy 101.004942 -222.229283) (xy 100.958775 -222.252806) (xy 100.909496 -222.268818) (xy 100.858319 -222.276924)
			(xy 100.806505 -222.276924) (xy 100.755328 -222.268818) (xy 100.706049 -222.252806) (xy 100.659882 -222.229283)
			(xy 100.617963 -222.198827) (xy 100.581325 -222.162189) (xy 100.550869 -222.12027) (xy 100.527346 -222.074103)
			(xy 100.511334 -222.024824) (xy 100.503228 -221.973647) (xy 100.50272 -221.94774) (xy 100.503323 -221.920023)
			(xy 100.51264 -221.865377) (xy 100.521262 -221.839028) (xy 100.529136 -221.81693) (xy 100.324158 -221.462092)
			(xy 100.301298 -221.457774) (xy 100.276503 -221.45255) (xy 100.228767 -221.435564) (xy 100.184192 -221.411474)
			(xy 100.143827 -221.380847) (xy 100.108624 -221.344405) (xy 100.079411 -221.303006) (xy 100.056876 -221.257625)
			(xy 100.04155 -221.20933) (xy 100.033794 -221.159258) (xy 100.033328 -221.133924) (xy 99.752404 -221.133924)
			(xy 99.751896 -221.159811) (xy 99.743797 -221.210949) (xy 99.727798 -221.260189) (xy 99.704292 -221.306321)
			(xy 99.67386 -221.348208) (xy 99.63725 -221.384818) (xy 99.595363 -221.41525) (xy 99.549231 -221.438756)
			(xy 99.499991 -221.454755) (xy 99.448853 -221.462854) (xy 99.397079 -221.462854) (xy 99.345941 -221.454755)
			(xy 99.296701 -221.438756) (xy 99.250569 -221.41525) (xy 99.208682 -221.384818) (xy 99.172072 -221.348208)
			(xy 99.14164 -221.306321) (xy 99.118134 -221.260189) (xy 99.102135 -221.210949) (xy 99.094036 -221.159811)
			(xy 99.093528 -221.133924) (xy 98.812604 -221.133924) (xy 98.81208 -221.161632) (xy 98.802881 -221.216279)
			(xy 98.794316 -221.242636) (xy 98.786442 -221.264734) (xy 98.99142 -221.619572) (xy 99.01428 -221.62389)
			(xy 99.039105 -221.629041) (xy 99.086883 -221.645999) (xy 99.131502 -221.670074) (xy 99.171907 -221.700696)
			(xy 99.207147 -221.737145) (xy 99.23639 -221.778561) (xy 99.258947 -221.823965) (xy 99.274285 -221.872289)
			(xy 99.282042 -221.92239) (xy 99.282504 -221.94774) (xy 99.281996 -221.973647) (xy 99.27389 -222.024824)
			(xy 99.257878 -222.074103) (xy 99.234355 -222.12027) (xy 99.203899 -222.162189) (xy 99.167261 -222.198827)
			(xy 99.125342 -222.229283) (xy 99.079175 -222.252806) (xy 99.029896 -222.268818) (xy 98.978719 -222.276924)
			(xy 98.926905 -222.276924) (xy 98.875728 -222.268818) (xy 98.826449 -222.252806) (xy 98.780282 -222.229283)
			(xy 98.738363 -222.198827) (xy 98.701725 -222.162189) (xy 98.671269 -222.12027) (xy 98.647746 -222.074103)
			(xy 98.631734 -222.024824) (xy 98.623628 -221.973647) (xy 98.62312 -221.94774) (xy 98.623723 -221.920023)
			(xy 98.63304 -221.865377) (xy 98.641662 -221.839028) (xy 98.649536 -221.81693) (xy 98.444558 -221.462092)
			(xy 98.421698 -221.457774) (xy 98.396903 -221.45255) (xy 98.349167 -221.435564) (xy 98.304592 -221.411474)
			(xy 98.264227 -221.380847) (xy 98.229024 -221.344405) (xy 98.199811 -221.303006) (xy 98.177276 -221.257625)
			(xy 98.16195 -221.20933) (xy 98.154194 -221.159258) (xy 98.153728 -221.133924) (xy 97.872804 -221.133924)
			(xy 97.872296 -221.159811) (xy 97.864197 -221.210949) (xy 97.848198 -221.260189) (xy 97.824692 -221.306321)
			(xy 97.79426 -221.348208) (xy 97.75765 -221.384818) (xy 97.715763 -221.41525) (xy 97.669631 -221.438756)
			(xy 97.620391 -221.454755) (xy 97.569253 -221.462854) (xy 97.517479 -221.462854) (xy 97.466341 -221.454755)
			(xy 97.417101 -221.438756) (xy 97.370969 -221.41525) (xy 97.329082 -221.384818) (xy 97.292472 -221.348208)
			(xy 97.26204 -221.306321) (xy 97.238534 -221.260189) (xy 97.222535 -221.210949) (xy 97.214436 -221.159811)
			(xy 97.213928 -221.133924) (xy 96.933004 -221.133924) (xy 96.93248 -221.161632) (xy 96.923281 -221.216279)
			(xy 96.914716 -221.242636) (xy 96.906842 -221.264734) (xy 97.11182 -221.619572) (xy 97.13468 -221.62389)
			(xy 97.159505 -221.629041) (xy 97.207283 -221.645999) (xy 97.251902 -221.670074) (xy 97.292307 -221.700696)
			(xy 97.327547 -221.737145) (xy 97.35679 -221.778561) (xy 97.379347 -221.823965) (xy 97.394685 -221.872289)
			(xy 97.402442 -221.92239) (xy 97.402904 -221.94774) (xy 97.402396 -221.973647) (xy 97.39429 -222.024824)
			(xy 97.378278 -222.074103) (xy 97.354755 -222.12027) (xy 97.324299 -222.162189) (xy 97.287661 -222.198827)
			(xy 97.245742 -222.229283) (xy 97.199575 -222.252806) (xy 97.150296 -222.268818) (xy 97.099119 -222.276924)
			(xy 97.047305 -222.276924) (xy 96.996128 -222.268818) (xy 96.946849 -222.252806) (xy 96.900682 -222.229283)
			(xy 96.858763 -222.198827) (xy 96.822125 -222.162189) (xy 96.791669 -222.12027) (xy 96.768146 -222.074103)
			(xy 96.752134 -222.024824) (xy 96.744028 -221.973647) (xy 96.74352 -221.94774) (xy 96.744123 -221.920023)
			(xy 96.75344 -221.865377) (xy 96.762062 -221.839028) (xy 96.769936 -221.81693) (xy 96.564958 -221.462092)
			(xy 96.542098 -221.457774) (xy 96.517303 -221.45255) (xy 96.469567 -221.435564) (xy 96.424992 -221.411474)
			(xy 96.384627 -221.380847) (xy 96.349424 -221.344405) (xy 96.320211 -221.303006) (xy 96.297676 -221.257625)
			(xy 96.28235 -221.20933) (xy 96.274594 -221.159258) (xy 96.274128 -221.133924) (xy 95.993204 -221.133924)
			(xy 95.992696 -221.159811) (xy 95.984597 -221.210949) (xy 95.968598 -221.260189) (xy 95.945092 -221.306321)
			(xy 95.91466 -221.348208) (xy 95.87805 -221.384818) (xy 95.836163 -221.41525) (xy 95.790031 -221.438756)
			(xy 95.740791 -221.454755) (xy 95.689653 -221.462854) (xy 95.637879 -221.462854) (xy 95.586741 -221.454755)
			(xy 95.537501 -221.438756) (xy 95.491369 -221.41525) (xy 95.449482 -221.384818) (xy 95.412872 -221.348208)
			(xy 95.38244 -221.306321) (xy 95.358934 -221.260189) (xy 95.342935 -221.210949) (xy 95.334836 -221.159811)
			(xy 95.334328 -221.133924) (xy 95.053404 -221.133924) (xy 95.05288 -221.161632) (xy 95.043681 -221.216279)
			(xy 95.035116 -221.242636) (xy 95.027242 -221.264734) (xy 95.23222 -221.619572) (xy 95.25508 -221.62389)
			(xy 95.279905 -221.629041) (xy 95.327683 -221.645999) (xy 95.372302 -221.670074) (xy 95.412707 -221.700696)
			(xy 95.447947 -221.737145) (xy 95.47719 -221.778561) (xy 95.499747 -221.823965) (xy 95.515085 -221.872289)
			(xy 95.522842 -221.92239) (xy 95.523304 -221.94774) (xy 95.522796 -221.973647) (xy 95.51469 -222.024824)
			(xy 95.498678 -222.074103) (xy 95.475155 -222.12027) (xy 95.444699 -222.162189) (xy 95.408061 -222.198827)
			(xy 95.366142 -222.229283) (xy 95.319975 -222.252806) (xy 95.270696 -222.268818) (xy 95.219519 -222.276924)
			(xy 95.167705 -222.276924) (xy 95.116528 -222.268818) (xy 95.067249 -222.252806) (xy 95.021082 -222.229283)
			(xy 94.979163 -222.198827) (xy 94.942525 -222.162189) (xy 94.912069 -222.12027) (xy 94.888546 -222.074103)
			(xy 94.872534 -222.024824) (xy 94.864428 -221.973647) (xy 94.86392 -221.94774) (xy 94.864523 -221.920023)
			(xy 94.87384 -221.865377) (xy 94.882462 -221.839028) (xy 94.890336 -221.81693) (xy 94.685358 -221.462092)
			(xy 94.662498 -221.457774) (xy 94.637703 -221.45255) (xy 94.589967 -221.435564) (xy 94.545392 -221.411474)
			(xy 94.505027 -221.380847) (xy 94.469824 -221.344405) (xy 94.440611 -221.303006) (xy 94.418076 -221.257625)
			(xy 94.40275 -221.20933) (xy 94.394994 -221.159258) (xy 94.394528 -221.133924) (xy 94.113604 -221.133924)
			(xy 94.113096 -221.159811) (xy 94.104997 -221.210949) (xy 94.088998 -221.260189) (xy 94.065492 -221.306321)
			(xy 94.03506 -221.348208) (xy 93.99845 -221.384818) (xy 93.956563 -221.41525) (xy 93.910431 -221.438756)
			(xy 93.861191 -221.454755) (xy 93.810053 -221.462854) (xy 93.758279 -221.462854) (xy 93.707141 -221.454755)
			(xy 93.657901 -221.438756) (xy 93.611769 -221.41525) (xy 93.569882 -221.384818) (xy 93.533272 -221.348208)
			(xy 93.50284 -221.306321) (xy 93.479334 -221.260189) (xy 93.463335 -221.210949) (xy 93.455236 -221.159811)
			(xy 93.454728 -221.133924) (xy 93.173804 -221.133924) (xy 93.17328 -221.161632) (xy 93.164081 -221.216279)
			(xy 93.155516 -221.242636) (xy 93.147642 -221.264734) (xy 93.35262 -221.619572) (xy 93.37548 -221.62389)
			(xy 93.400305 -221.629041) (xy 93.448083 -221.645999) (xy 93.492702 -221.670074) (xy 93.533107 -221.700696)
			(xy 93.568347 -221.737145) (xy 93.59759 -221.778561) (xy 93.620147 -221.823965) (xy 93.635485 -221.872289)
			(xy 93.643242 -221.92239) (xy 93.643704 -221.94774) (xy 93.643196 -221.973647) (xy 93.63509 -222.024824)
			(xy 93.619078 -222.074103) (xy 93.595555 -222.12027) (xy 93.565099 -222.162189) (xy 93.528461 -222.198827)
			(xy 93.486542 -222.229283) (xy 93.440375 -222.252806) (xy 93.391096 -222.268818) (xy 93.339919 -222.276924)
			(xy 93.288105 -222.276924) (xy 93.236928 -222.268818) (xy 93.187649 -222.252806) (xy 93.141482 -222.229283)
			(xy 93.099563 -222.198827) (xy 93.062925 -222.162189) (xy 93.032469 -222.12027) (xy 93.008946 -222.074103)
			(xy 92.992934 -222.024824) (xy 92.984828 -221.973647) (xy 92.98432 -221.94774) (xy 92.984923 -221.920023)
			(xy 92.99424 -221.865377) (xy 93.002862 -221.839028) (xy 93.010736 -221.81693) (xy 92.805758 -221.462092)
			(xy 92.782898 -221.457774) (xy 92.758103 -221.45255) (xy 92.710367 -221.435564) (xy 92.665792 -221.411474)
			(xy 92.625427 -221.380847) (xy 92.590224 -221.344405) (xy 92.561011 -221.303006) (xy 92.538476 -221.257625)
			(xy 92.52315 -221.20933) (xy 92.515394 -221.159258) (xy 92.514928 -221.133924) (xy 92.234004 -221.133924)
			(xy 92.233496 -221.159811) (xy 92.225397 -221.210949) (xy 92.209398 -221.260189) (xy 92.185892 -221.306321)
			(xy 92.15546 -221.348208) (xy 92.11885 -221.384818) (xy 92.076963 -221.41525) (xy 92.030831 -221.438756)
			(xy 91.981591 -221.454755) (xy 91.930453 -221.462854) (xy 91.878679 -221.462854) (xy 91.827541 -221.454755)
			(xy 91.778301 -221.438756) (xy 91.732169 -221.41525) (xy 91.690282 -221.384818) (xy 91.653672 -221.348208)
			(xy 91.62324 -221.306321) (xy 91.599734 -221.260189) (xy 91.583735 -221.210949) (xy 91.575636 -221.159811)
			(xy 91.575128 -221.133924) (xy 91.294204 -221.133924) (xy 91.29368 -221.161632) (xy 91.284481 -221.216279)
			(xy 91.275916 -221.242636) (xy 91.268042 -221.264734) (xy 91.47302 -221.619572) (xy 91.49588 -221.62389)
			(xy 91.520705 -221.629041) (xy 91.568483 -221.645999) (xy 91.613102 -221.670074) (xy 91.653507 -221.700696)
			(xy 91.688747 -221.737145) (xy 91.71799 -221.778561) (xy 91.740547 -221.823965) (xy 91.755885 -221.872289)
			(xy 91.763642 -221.92239) (xy 91.764104 -221.94774) (xy 91.763596 -221.973647) (xy 91.75549 -222.024824)
			(xy 91.739478 -222.074103) (xy 91.715955 -222.12027) (xy 91.685499 -222.162189) (xy 91.648861 -222.198827)
			(xy 91.606942 -222.229283) (xy 91.560775 -222.252806) (xy 91.511496 -222.268818) (xy 91.460319 -222.276924)
			(xy 91.408505 -222.276924) (xy 91.357328 -222.268818) (xy 91.308049 -222.252806) (xy 91.261882 -222.229283)
			(xy 91.219963 -222.198827) (xy 91.183325 -222.162189) (xy 91.152869 -222.12027) (xy 91.129346 -222.074103)
			(xy 91.113334 -222.024824) (xy 91.105228 -221.973647) (xy 91.10472 -221.94774) (xy 91.105323 -221.920023)
			(xy 91.11464 -221.865377) (xy 91.123262 -221.839028) (xy 91.131136 -221.81693) (xy 90.926158 -221.462092)
			(xy 90.903298 -221.457774) (xy 90.878503 -221.45255) (xy 90.830767 -221.435564) (xy 90.786192 -221.411474)
			(xy 90.745827 -221.380847) (xy 90.710624 -221.344405) (xy 90.681411 -221.303006) (xy 90.658876 -221.257625)
			(xy 90.64355 -221.20933) (xy 90.635794 -221.159258) (xy 90.635328 -221.133924) (xy 90.354404 -221.133924)
			(xy 90.353896 -221.159811) (xy 90.345797 -221.210949) (xy 90.329798 -221.260189) (xy 90.306292 -221.306321)
			(xy 90.27586 -221.348208) (xy 90.23925 -221.384818) (xy 90.197363 -221.41525) (xy 90.151231 -221.438756)
			(xy 90.101991 -221.454755) (xy 90.050853 -221.462854) (xy 89.999079 -221.462854) (xy 89.947941 -221.454755)
			(xy 89.898701 -221.438756) (xy 89.852569 -221.41525) (xy 89.810682 -221.384818) (xy 89.774072 -221.348208)
			(xy 89.74364 -221.306321) (xy 89.720134 -221.260189) (xy 89.704135 -221.210949) (xy 89.696036 -221.159811)
			(xy 89.695528 -221.133924) (xy 89.414604 -221.133924) (xy 89.41408 -221.161632) (xy 89.404881 -221.216279)
			(xy 89.396316 -221.242636) (xy 89.388442 -221.264734) (xy 89.59342 -221.619572) (xy 89.61628 -221.62389)
			(xy 89.641105 -221.629041) (xy 89.688883 -221.645999) (xy 89.733502 -221.670074) (xy 89.773907 -221.700696)
			(xy 89.809147 -221.737145) (xy 89.83839 -221.778561) (xy 89.860947 -221.823965) (xy 89.876285 -221.872289)
			(xy 89.884042 -221.92239) (xy 89.884504 -221.94774) (xy 89.883996 -221.973647) (xy 89.87589 -222.024824)
			(xy 89.859878 -222.074103) (xy 89.836355 -222.12027) (xy 89.805899 -222.162189) (xy 89.769261 -222.198827)
			(xy 89.727342 -222.229283) (xy 89.681175 -222.252806) (xy 89.631896 -222.268818) (xy 89.580719 -222.276924)
			(xy 89.528905 -222.276924) (xy 89.477728 -222.268818) (xy 89.428449 -222.252806) (xy 89.382282 -222.229283)
			(xy 89.340363 -222.198827) (xy 89.303725 -222.162189) (xy 89.273269 -222.12027) (xy 89.249746 -222.074103)
			(xy 89.233734 -222.024824) (xy 89.225628 -221.973647) (xy 89.22512 -221.94774) (xy 89.225723 -221.920023)
			(xy 89.23504 -221.865377) (xy 89.243662 -221.839028) (xy 89.251536 -221.81693) (xy 89.046558 -221.462092)
			(xy 89.023698 -221.457774) (xy 88.998903 -221.45255) (xy 88.951167 -221.435564) (xy 88.906592 -221.411474)
			(xy 88.866227 -221.380847) (xy 88.831024 -221.344405) (xy 88.801811 -221.303006) (xy 88.779276 -221.257625)
			(xy 88.76395 -221.20933) (xy 88.756194 -221.159258) (xy 88.755728 -221.133924) (xy 2.509012 -221.133924)
			(xy 2.509012 -224.389442) (xy 89.695528 -224.389442) (xy 89.695935 -224.364105) (xy 89.703697 -224.314028)
			(xy 89.719029 -224.265728) (xy 89.74157 -224.220343) (xy 89.770789 -224.17894) (xy 89.805999 -224.142496)
			(xy 89.84637 -224.111867) (xy 89.890952 -224.087776) (xy 89.938695 -224.070789) (xy 89.963498 -224.065592)
			(xy 89.986358 -224.061274) (xy 90.191082 -223.706182) (xy 90.183462 -223.684338) (xy 90.174817 -223.657995)
			(xy 90.165504 -223.603345) (xy 90.16492 -223.575626) (xy 90.165428 -223.549719) (xy 90.173534 -223.498542)
			(xy 90.189546 -223.449263) (xy 90.213069 -223.403096) (xy 90.243525 -223.361177) (xy 90.280163 -223.324539)
			(xy 90.322082 -223.294083) (xy 90.368249 -223.27056) (xy 90.417528 -223.254548) (xy 90.468705 -223.246442)
			(xy 90.520519 -223.246442) (xy 90.571696 -223.254548) (xy 90.620975 -223.27056) (xy 90.667142 -223.294083)
			(xy 90.709061 -223.324539) (xy 90.745699 -223.361177) (xy 90.776155 -223.403096) (xy 90.799678 -223.449263)
			(xy 90.81569 -223.498542) (xy 90.823796 -223.549719) (xy 90.824304 -223.575626) (xy 90.823803 -223.60097)
			(xy 90.816028 -223.651059) (xy 90.800679 -223.699368) (xy 90.77812 -223.74476) (xy 90.74888 -223.786165)
			(xy 90.713649 -223.822609) (xy 90.673257 -223.853232) (xy 90.628654 -223.877314) (xy 90.580892 -223.894288)
			(xy 90.55608 -223.899476) (xy 90.53322 -223.903794) (xy 90.328496 -224.258632) (xy 90.336116 -224.280476)
			(xy 90.344672 -224.306769) (xy 90.353865 -224.361289) (xy 90.354404 -224.388934) (xy 90.354404 -224.389442)
			(xy 90.635328 -224.389442) (xy 90.635836 -224.363555) (xy 90.643935 -224.312417) (xy 90.659934 -224.263177)
			(xy 90.68344 -224.217045) (xy 90.713872 -224.175158) (xy 90.750482 -224.138548) (xy 90.792369 -224.108116)
			(xy 90.838501 -224.08461) (xy 90.887741 -224.068611) (xy 90.938879 -224.060512) (xy 90.990653 -224.060512)
			(xy 91.041791 -224.068611) (xy 91.091031 -224.08461) (xy 91.137163 -224.108116) (xy 91.17905 -224.138548)
			(xy 91.21566 -224.175158) (xy 91.246092 -224.217045) (xy 91.269598 -224.263177) (xy 91.285597 -224.312417)
			(xy 91.293696 -224.363555) (xy 91.294204 -224.389442) (xy 91.575128 -224.389442) (xy 91.575535 -224.364105)
			(xy 91.583297 -224.314028) (xy 91.598629 -224.265728) (xy 91.62117 -224.220343) (xy 91.650389 -224.17894)
			(xy 91.685599 -224.142496) (xy 91.72597 -224.111867) (xy 91.770552 -224.087776) (xy 91.818295 -224.070789)
			(xy 91.843098 -224.065592) (xy 91.865958 -224.061274) (xy 92.070682 -223.706182) (xy 92.063062 -223.684338)
			(xy 92.054417 -223.657995) (xy 92.045104 -223.603345) (xy 92.04452 -223.575626) (xy 92.045028 -223.549719)
			(xy 92.053134 -223.498542) (xy 92.069146 -223.449263) (xy 92.092669 -223.403096) (xy 92.123125 -223.361177)
			(xy 92.159763 -223.324539) (xy 92.201682 -223.294083) (xy 92.247849 -223.27056) (xy 92.297128 -223.254548)
			(xy 92.348305 -223.246442) (xy 92.400119 -223.246442) (xy 92.451296 -223.254548) (xy 92.500575 -223.27056)
			(xy 92.546742 -223.294083) (xy 92.588661 -223.324539) (xy 92.625299 -223.361177) (xy 92.655755 -223.403096)
			(xy 92.679278 -223.449263) (xy 92.69529 -223.498542) (xy 92.703396 -223.549719) (xy 92.703904 -223.575626)
			(xy 92.703403 -223.60097) (xy 92.695628 -223.651059) (xy 92.680279 -223.699368) (xy 92.65772 -223.74476)
			(xy 92.62848 -223.786165) (xy 92.593249 -223.822609) (xy 92.552857 -223.853232) (xy 92.508254 -223.877314)
			(xy 92.460492 -223.894288) (xy 92.43568 -223.899476) (xy 92.41282 -223.903794) (xy 92.208096 -224.258632)
			(xy 92.215716 -224.280476) (xy 92.224272 -224.306769) (xy 92.233465 -224.361289) (xy 92.234004 -224.388934)
			(xy 92.234004 -224.389442) (xy 92.514928 -224.389442) (xy 92.515436 -224.363555) (xy 92.523535 -224.312417)
			(xy 92.539534 -224.263177) (xy 92.56304 -224.217045) (xy 92.593472 -224.175158) (xy 92.630082 -224.138548)
			(xy 92.671969 -224.108116) (xy 92.718101 -224.08461) (xy 92.767341 -224.068611) (xy 92.818479 -224.060512)
			(xy 92.870253 -224.060512) (xy 92.921391 -224.068611) (xy 92.970631 -224.08461) (xy 93.016763 -224.108116)
			(xy 93.05865 -224.138548) (xy 93.09526 -224.175158) (xy 93.125692 -224.217045) (xy 93.149198 -224.263177)
			(xy 93.165197 -224.312417) (xy 93.173296 -224.363555) (xy 93.173804 -224.389442) (xy 93.454728 -224.389442)
			(xy 93.455135 -224.364105) (xy 93.462897 -224.314028) (xy 93.478229 -224.265728) (xy 93.50077 -224.220343)
			(xy 93.529989 -224.17894) (xy 93.565199 -224.142496) (xy 93.60557 -224.111867) (xy 93.650152 -224.087776)
			(xy 93.697895 -224.070789) (xy 93.722698 -224.065592) (xy 93.745558 -224.061274) (xy 93.950282 -223.706436)
			(xy 93.942662 -223.684338) (xy 93.934031 -223.657991) (xy 93.92471 -223.603344) (xy 93.92412 -223.575626)
			(xy 93.924628 -223.549719) (xy 93.932734 -223.498542) (xy 93.948746 -223.449263) (xy 93.972269 -223.403096)
			(xy 94.002725 -223.361177) (xy 94.039363 -223.324539) (xy 94.081282 -223.294083) (xy 94.127449 -223.27056)
			(xy 94.176728 -223.254548) (xy 94.227905 -223.246442) (xy 94.279719 -223.246442) (xy 94.330896 -223.254548)
			(xy 94.380175 -223.27056) (xy 94.426342 -223.294083) (xy 94.468261 -223.324539) (xy 94.504899 -223.361177)
			(xy 94.535355 -223.403096) (xy 94.558878 -223.449263) (xy 94.57489 -223.498542) (xy 94.582996 -223.549719)
			(xy 94.583504 -223.575626) (xy 94.583087 -223.600992) (xy 94.575334 -223.651127) (xy 94.559985 -223.69948)
			(xy 94.537403 -223.744908) (xy 94.508122 -223.786336) (xy 94.472834 -223.822783) (xy 94.432375 -223.853388)
			(xy 94.387701 -223.877427) (xy 94.339869 -223.894332) (xy 94.315026 -223.899476) (xy 94.292166 -223.903794)
			(xy 94.087442 -224.258632) (xy 94.095316 -224.280476) (xy 94.10389 -224.306896) (xy 94.11309 -224.36167)
			(xy 94.113604 -224.389442) (xy 94.394528 -224.389442) (xy 94.395036 -224.363555) (xy 94.403135 -224.312417)
			(xy 94.419134 -224.263177) (xy 94.44264 -224.217045) (xy 94.473072 -224.175158) (xy 94.509682 -224.138548)
			(xy 94.551569 -224.108116) (xy 94.597701 -224.08461) (xy 94.646941 -224.068611) (xy 94.698079 -224.060512)
			(xy 94.749853 -224.060512) (xy 94.800991 -224.068611) (xy 94.850231 -224.08461) (xy 94.896363 -224.108116)
			(xy 94.93825 -224.138548) (xy 94.97486 -224.175158) (xy 95.005292 -224.217045) (xy 95.028798 -224.263177)
			(xy 95.044797 -224.312417) (xy 95.052896 -224.363555) (xy 95.053404 -224.389442) (xy 95.334328 -224.389442)
			(xy 95.334735 -224.364105) (xy 95.342497 -224.314028) (xy 95.357829 -224.265728) (xy 95.38037 -224.220343)
			(xy 95.409589 -224.17894) (xy 95.444799 -224.142496) (xy 95.48517 -224.111867) (xy 95.529752 -224.087776)
			(xy 95.577495 -224.070789) (xy 95.602298 -224.065592) (xy 95.625158 -224.061274) (xy 95.829882 -223.706436)
			(xy 95.822262 -223.684338) (xy 95.813631 -223.657991) (xy 95.80431 -223.603344) (xy 95.80372 -223.575626)
			(xy 95.804228 -223.549719) (xy 95.812334 -223.498542) (xy 95.828346 -223.449263) (xy 95.851869 -223.403096)
			(xy 95.882325 -223.361177) (xy 95.918963 -223.324539) (xy 95.960882 -223.294083) (xy 96.007049 -223.27056)
			(xy 96.056328 -223.254548) (xy 96.107505 -223.246442) (xy 96.159319 -223.246442) (xy 96.210496 -223.254548)
			(xy 96.259775 -223.27056) (xy 96.305942 -223.294083) (xy 96.347861 -223.324539) (xy 96.384499 -223.361177)
			(xy 96.414955 -223.403096) (xy 96.438478 -223.449263) (xy 96.45449 -223.498542) (xy 96.462596 -223.549719)
			(xy 96.463104 -223.575626) (xy 96.462687 -223.600992) (xy 96.454934 -223.651127) (xy 96.439585 -223.69948)
			(xy 96.417003 -223.744908) (xy 96.387722 -223.786336) (xy 96.352434 -223.822783) (xy 96.311975 -223.853388)
			(xy 96.267301 -223.877427) (xy 96.219469 -223.894332) (xy 96.194626 -223.899476) (xy 96.171766 -223.903794)
			(xy 95.967042 -224.258632) (xy 95.974916 -224.280476) (xy 95.98349 -224.306896) (xy 95.99269 -224.36167)
			(xy 95.993204 -224.389442) (xy 96.274128 -224.389442) (xy 96.274636 -224.363555) (xy 96.282735 -224.312417)
			(xy 96.298734 -224.263177) (xy 96.32224 -224.217045) (xy 96.352672 -224.175158) (xy 96.389282 -224.138548)
			(xy 96.431169 -224.108116) (xy 96.477301 -224.08461) (xy 96.526541 -224.068611) (xy 96.577679 -224.060512)
			(xy 96.629453 -224.060512) (xy 96.680591 -224.068611) (xy 96.729831 -224.08461) (xy 96.775963 -224.108116)
			(xy 96.81785 -224.138548) (xy 96.85446 -224.175158) (xy 96.884892 -224.217045) (xy 96.908398 -224.263177)
			(xy 96.924397 -224.312417) (xy 96.932496 -224.363555) (xy 96.933004 -224.389442) (xy 97.213928 -224.389442)
			(xy 97.214335 -224.364105) (xy 97.222097 -224.314028) (xy 97.237429 -224.265728) (xy 97.25997 -224.220343)
			(xy 97.289189 -224.17894) (xy 97.324399 -224.142496) (xy 97.36477 -224.111867) (xy 97.409352 -224.087776)
			(xy 97.457095 -224.070789) (xy 97.481898 -224.065592) (xy 97.504758 -224.061274) (xy 97.709482 -223.706436)
			(xy 97.701862 -223.684338) (xy 97.693231 -223.657991) (xy 97.68391 -223.603344) (xy 97.68332 -223.575626)
			(xy 97.683828 -223.549719) (xy 97.691934 -223.498542) (xy 97.707946 -223.449263) (xy 97.731469 -223.403096)
			(xy 97.761925 -223.361177) (xy 97.798563 -223.324539) (xy 97.840482 -223.294083) (xy 97.886649 -223.27056)
			(xy 97.935928 -223.254548) (xy 97.987105 -223.246442) (xy 98.038919 -223.246442) (xy 98.090096 -223.254548)
			(xy 98.139375 -223.27056) (xy 98.185542 -223.294083) (xy 98.227461 -223.324539) (xy 98.264099 -223.361177)
			(xy 98.294555 -223.403096) (xy 98.318078 -223.449263) (xy 98.33409 -223.498542) (xy 98.342196 -223.549719)
			(xy 98.342704 -223.575626) (xy 98.342287 -223.600992) (xy 98.334534 -223.651127) (xy 98.319185 -223.69948)
			(xy 98.296603 -223.744908) (xy 98.267322 -223.786336) (xy 98.232034 -223.822783) (xy 98.191575 -223.853388)
			(xy 98.146901 -223.877427) (xy 98.099069 -223.894332) (xy 98.074226 -223.899476) (xy 98.051366 -223.903794)
			(xy 97.846642 -224.258632) (xy 97.854516 -224.280476) (xy 97.86309 -224.306896) (xy 97.87229 -224.36167)
			(xy 97.872804 -224.389442) (xy 98.153728 -224.389442) (xy 98.154236 -224.363555) (xy 98.162335 -224.312417)
			(xy 98.178334 -224.263177) (xy 98.20184 -224.217045) (xy 98.232272 -224.175158) (xy 98.268882 -224.138548)
			(xy 98.310769 -224.108116) (xy 98.356901 -224.08461) (xy 98.406141 -224.068611) (xy 98.457279 -224.060512)
			(xy 98.509053 -224.060512) (xy 98.560191 -224.068611) (xy 98.609431 -224.08461) (xy 98.655563 -224.108116)
			(xy 98.69745 -224.138548) (xy 98.73406 -224.175158) (xy 98.764492 -224.217045) (xy 98.787998 -224.263177)
			(xy 98.803997 -224.312417) (xy 98.812096 -224.363555) (xy 98.812604 -224.389442) (xy 99.093528 -224.389442)
			(xy 99.093935 -224.364105) (xy 99.101697 -224.314028) (xy 99.117029 -224.265728) (xy 99.13957 -224.220343)
			(xy 99.168789 -224.17894) (xy 99.203999 -224.142496) (xy 99.24437 -224.111867) (xy 99.288952 -224.087776)
			(xy 99.336695 -224.070789) (xy 99.361498 -224.065592) (xy 99.384358 -224.061274) (xy 99.589082 -223.706436)
			(xy 99.581462 -223.684338) (xy 99.572831 -223.657991) (xy 99.56351 -223.603344) (xy 99.56292 -223.575626)
			(xy 99.563428 -223.549719) (xy 99.571534 -223.498542) (xy 99.587546 -223.449263) (xy 99.611069 -223.403096)
			(xy 99.641525 -223.361177) (xy 99.678163 -223.324539) (xy 99.720082 -223.294083) (xy 99.766249 -223.27056)
			(xy 99.815528 -223.254548) (xy 99.866705 -223.246442) (xy 99.918519 -223.246442) (xy 99.969696 -223.254548)
			(xy 100.018975 -223.27056) (xy 100.065142 -223.294083) (xy 100.107061 -223.324539) (xy 100.143699 -223.361177)
			(xy 100.174155 -223.403096) (xy 100.197678 -223.449263) (xy 100.21369 -223.498542) (xy 100.221796 -223.549719)
			(xy 100.222304 -223.575626) (xy 100.221887 -223.600992) (xy 100.214134 -223.651127) (xy 100.198785 -223.69948)
			(xy 100.176203 -223.744908) (xy 100.146922 -223.786336) (xy 100.111634 -223.822783) (xy 100.071175 -223.853388)
			(xy 100.026501 -223.877427) (xy 99.978669 -223.894332) (xy 99.953826 -223.899476) (xy 99.930966 -223.903794)
			(xy 99.726242 -224.258632) (xy 99.734116 -224.280476) (xy 99.74269 -224.306896) (xy 99.75189 -224.36167)
			(xy 99.752404 -224.389442) (xy 100.033328 -224.389442) (xy 100.033836 -224.363555) (xy 100.041935 -224.312417)
			(xy 100.057934 -224.263177) (xy 100.08144 -224.217045) (xy 100.111872 -224.175158) (xy 100.148482 -224.138548)
			(xy 100.190369 -224.108116) (xy 100.236501 -224.08461) (xy 100.285741 -224.068611) (xy 100.336879 -224.060512)
			(xy 100.388653 -224.060512) (xy 100.439791 -224.068611) (xy 100.489031 -224.08461) (xy 100.535163 -224.108116)
			(xy 100.57705 -224.138548) (xy 100.61366 -224.175158) (xy 100.644092 -224.217045) (xy 100.667598 -224.263177)
			(xy 100.683597 -224.312417) (xy 100.691696 -224.363555) (xy 100.692204 -224.389442) (xy 100.973128 -224.389442)
			(xy 100.973535 -224.364105) (xy 100.981297 -224.314028) (xy 100.996629 -224.265728) (xy 101.01917 -224.220343)
			(xy 101.048389 -224.17894) (xy 101.083599 -224.142496) (xy 101.12397 -224.111867) (xy 101.168552 -224.087776)
			(xy 101.216295 -224.070789) (xy 101.241098 -224.065592) (xy 101.263958 -224.061274) (xy 101.468682 -223.706436)
			(xy 101.461062 -223.684338) (xy 101.452431 -223.657991) (xy 101.44311 -223.603344) (xy 101.44252 -223.575626)
			(xy 101.443028 -223.549719) (xy 101.451134 -223.498542) (xy 101.467146 -223.449263) (xy 101.490669 -223.403096)
			(xy 101.521125 -223.361177) (xy 101.557763 -223.324539) (xy 101.599682 -223.294083) (xy 101.645849 -223.27056)
			(xy 101.695128 -223.254548) (xy 101.746305 -223.246442) (xy 101.798119 -223.246442) (xy 101.849296 -223.254548)
			(xy 101.898575 -223.27056) (xy 101.944742 -223.294083) (xy 101.986661 -223.324539) (xy 102.023299 -223.361177)
			(xy 102.053755 -223.403096) (xy 102.077278 -223.449263) (xy 102.09329 -223.498542) (xy 102.101396 -223.549719)
			(xy 102.101904 -223.575626) (xy 102.101487 -223.600992) (xy 102.093734 -223.651127) (xy 102.078385 -223.69948)
			(xy 102.055803 -223.744908) (xy 102.026522 -223.786336) (xy 101.991234 -223.822783) (xy 101.950775 -223.853388)
			(xy 101.906101 -223.877427) (xy 101.858269 -223.894332) (xy 101.833426 -223.899476) (xy 101.810566 -223.903794)
			(xy 101.605842 -224.258632) (xy 101.613716 -224.280476) (xy 101.62229 -224.306896) (xy 101.63149 -224.36167)
			(xy 101.632004 -224.389442) (xy 101.912928 -224.389442) (xy 101.913436 -224.363555) (xy 101.921535 -224.312417)
			(xy 101.937534 -224.263177) (xy 101.96104 -224.217045) (xy 101.991472 -224.175158) (xy 102.028082 -224.138548)
			(xy 102.069969 -224.108116) (xy 102.116101 -224.08461) (xy 102.165341 -224.068611) (xy 102.216479 -224.060512)
			(xy 102.268253 -224.060512) (xy 102.319391 -224.068611) (xy 102.368631 -224.08461) (xy 102.414763 -224.108116)
			(xy 102.45665 -224.138548) (xy 102.49326 -224.175158) (xy 102.523692 -224.217045) (xy 102.547198 -224.263177)
			(xy 102.563197 -224.312417) (xy 102.571296 -224.363555) (xy 102.571804 -224.389442) (xy 102.852728 -224.389442)
			(xy 102.853135 -224.364105) (xy 102.860897 -224.314028) (xy 102.876229 -224.265728) (xy 102.89877 -224.220343)
			(xy 102.927989 -224.17894) (xy 102.963199 -224.142496) (xy 103.00357 -224.111867) (xy 103.048152 -224.087776)
			(xy 103.095895 -224.070789) (xy 103.120698 -224.065592) (xy 103.143558 -224.061274) (xy 103.348282 -223.706436)
			(xy 103.340662 -223.684338) (xy 103.332031 -223.657991) (xy 103.32271 -223.603344) (xy 103.32212 -223.575626)
			(xy 103.322628 -223.549719) (xy 103.330734 -223.498542) (xy 103.346746 -223.449263) (xy 103.370269 -223.403096)
			(xy 103.400725 -223.361177) (xy 103.437363 -223.324539) (xy 103.479282 -223.294083) (xy 103.525449 -223.27056)
			(xy 103.574728 -223.254548) (xy 103.625905 -223.246442) (xy 103.677719 -223.246442) (xy 103.728896 -223.254548)
			(xy 103.778175 -223.27056) (xy 103.824342 -223.294083) (xy 103.866261 -223.324539) (xy 103.902899 -223.361177)
			(xy 103.933355 -223.403096) (xy 103.956878 -223.449263) (xy 103.97289 -223.498542) (xy 103.980996 -223.549719)
			(xy 103.981504 -223.575626) (xy 103.981087 -223.600992) (xy 103.973334 -223.651127) (xy 103.957985 -223.69948)
			(xy 103.935403 -223.744908) (xy 103.906122 -223.786336) (xy 103.870834 -223.822783) (xy 103.830375 -223.853388)
			(xy 103.785701 -223.877427) (xy 103.737869 -223.894332) (xy 103.713026 -223.899476) (xy 103.690166 -223.903794)
			(xy 103.485442 -224.258632) (xy 103.493316 -224.280476) (xy 103.50189 -224.306896) (xy 103.51109 -224.36167)
			(xy 103.511604 -224.389442) (xy 103.792528 -224.389442) (xy 103.793036 -224.363555) (xy 103.801135 -224.312417)
			(xy 103.817134 -224.263177) (xy 103.84064 -224.217045) (xy 103.871072 -224.175158) (xy 103.907682 -224.138548)
			(xy 103.949569 -224.108116) (xy 103.995701 -224.08461) (xy 104.044941 -224.068611) (xy 104.096079 -224.060512)
			(xy 104.147853 -224.060512) (xy 104.198991 -224.068611) (xy 104.248231 -224.08461) (xy 104.294363 -224.108116)
			(xy 104.33625 -224.138548) (xy 104.37286 -224.175158) (xy 104.403292 -224.217045) (xy 104.426798 -224.263177)
			(xy 104.442797 -224.312417) (xy 104.450896 -224.363555) (xy 104.451404 -224.389442) (xy 104.732328 -224.389442)
			(xy 104.732735 -224.364105) (xy 104.740497 -224.314028) (xy 104.755829 -224.265728) (xy 104.77837 -224.220343)
			(xy 104.807589 -224.17894) (xy 104.842799 -224.142496) (xy 104.88317 -224.111867) (xy 104.927752 -224.087776)
			(xy 104.975495 -224.070789) (xy 105.000298 -224.065592) (xy 105.023158 -224.061274) (xy 105.227882 -223.706436)
			(xy 105.220262 -223.684338) (xy 105.211631 -223.657991) (xy 105.20231 -223.603344) (xy 105.20172 -223.575626)
			(xy 105.202228 -223.549719) (xy 105.210334 -223.498542) (xy 105.226346 -223.449263) (xy 105.249869 -223.403096)
			(xy 105.280325 -223.361177) (xy 105.316963 -223.324539) (xy 105.358882 -223.294083) (xy 105.405049 -223.27056)
			(xy 105.454328 -223.254548) (xy 105.505505 -223.246442) (xy 105.557319 -223.246442) (xy 105.608496 -223.254548)
			(xy 105.657775 -223.27056) (xy 105.703942 -223.294083) (xy 105.745861 -223.324539) (xy 105.782499 -223.361177)
			(xy 105.812955 -223.403096) (xy 105.836478 -223.449263) (xy 105.85249 -223.498542) (xy 105.860596 -223.549719)
			(xy 105.861104 -223.575626) (xy 105.860687 -223.600992) (xy 105.852934 -223.651127) (xy 105.837585 -223.69948)
			(xy 105.815003 -223.744908) (xy 105.785722 -223.786336) (xy 105.750434 -223.822783) (xy 105.709975 -223.853388)
			(xy 105.665301 -223.877427) (xy 105.617469 -223.894332) (xy 105.592626 -223.899476) (xy 105.569766 -223.903794)
			(xy 105.365042 -224.258632) (xy 105.372916 -224.280476) (xy 105.38149 -224.306896) (xy 105.39069 -224.36167)
			(xy 105.391204 -224.389442) (xy 105.672128 -224.389442) (xy 105.672636 -224.363555) (xy 105.680735 -224.312417)
			(xy 105.696734 -224.263177) (xy 105.72024 -224.217045) (xy 105.750672 -224.175158) (xy 105.787282 -224.138548)
			(xy 105.829169 -224.108116) (xy 105.875301 -224.08461) (xy 105.924541 -224.068611) (xy 105.975679 -224.060512)
			(xy 106.027453 -224.060512) (xy 106.078591 -224.068611) (xy 106.127831 -224.08461) (xy 106.173963 -224.108116)
			(xy 106.21585 -224.138548) (xy 106.25246 -224.175158) (xy 106.282892 -224.217045) (xy 106.306398 -224.263177)
			(xy 106.322397 -224.312417) (xy 106.330496 -224.363555) (xy 106.331004 -224.389442) (xy 106.611928 -224.389442)
			(xy 106.612335 -224.364105) (xy 106.620097 -224.314028) (xy 106.635429 -224.265728) (xy 106.65797 -224.220343)
			(xy 106.687189 -224.17894) (xy 106.722399 -224.142496) (xy 106.76277 -224.111867) (xy 106.807352 -224.087776)
			(xy 106.855095 -224.070789) (xy 106.879898 -224.065592) (xy 106.902758 -224.061274) (xy 107.107482 -223.706436)
			(xy 107.099862 -223.684338) (xy 107.091231 -223.657991) (xy 107.08191 -223.603344) (xy 107.08132 -223.575626)
			(xy 107.081828 -223.549719) (xy 107.089934 -223.498542) (xy 107.105946 -223.449263) (xy 107.129469 -223.403096)
			(xy 107.159925 -223.361177) (xy 107.196563 -223.324539) (xy 107.238482 -223.294083) (xy 107.284649 -223.27056)
			(xy 107.333928 -223.254548) (xy 107.385105 -223.246442) (xy 107.436919 -223.246442) (xy 107.488096 -223.254548)
			(xy 107.537375 -223.27056) (xy 107.583542 -223.294083) (xy 107.625461 -223.324539) (xy 107.662099 -223.361177)
			(xy 107.692555 -223.403096) (xy 107.716078 -223.449263) (xy 107.73209 -223.498542) (xy 107.740196 -223.549719)
			(xy 107.740704 -223.575626) (xy 107.740287 -223.600992) (xy 107.732534 -223.651127) (xy 107.717185 -223.69948)
			(xy 107.694603 -223.744908) (xy 107.665322 -223.786336) (xy 107.630034 -223.822783) (xy 107.589575 -223.853388)
			(xy 107.544901 -223.877427) (xy 107.497069 -223.894332) (xy 107.472226 -223.899476) (xy 107.449366 -223.903794)
			(xy 107.244642 -224.258632) (xy 107.252516 -224.280476) (xy 107.26109 -224.306896) (xy 107.27029 -224.36167)
			(xy 107.270804 -224.389442) (xy 107.551728 -224.389442) (xy 107.552236 -224.363555) (xy 107.560335 -224.312417)
			(xy 107.576334 -224.263177) (xy 107.59984 -224.217045) (xy 107.630272 -224.175158) (xy 107.666882 -224.138548)
			(xy 107.708769 -224.108116) (xy 107.754901 -224.08461) (xy 107.804141 -224.068611) (xy 107.855279 -224.060512)
			(xy 107.907053 -224.060512) (xy 107.958191 -224.068611) (xy 108.007431 -224.08461) (xy 108.053563 -224.108116)
			(xy 108.09545 -224.138548) (xy 108.13206 -224.175158) (xy 108.162492 -224.217045) (xy 108.185998 -224.263177)
			(xy 108.201997 -224.312417) (xy 108.210096 -224.363555) (xy 108.210604 -224.389442) (xy 108.491528 -224.389442)
			(xy 108.491935 -224.364105) (xy 108.499697 -224.314028) (xy 108.515029 -224.265728) (xy 108.53757 -224.220343)
			(xy 108.566789 -224.17894) (xy 108.601999 -224.142496) (xy 108.64237 -224.111867) (xy 108.686952 -224.087776)
			(xy 108.734695 -224.070789) (xy 108.759498 -224.065592) (xy 108.782358 -224.061274) (xy 108.987082 -223.706436)
			(xy 108.979462 -223.684338) (xy 108.970831 -223.657991) (xy 108.96151 -223.603344) (xy 108.96092 -223.575626)
			(xy 108.961428 -223.549719) (xy 108.969534 -223.498542) (xy 108.985546 -223.449263) (xy 109.009069 -223.403096)
			(xy 109.039525 -223.361177) (xy 109.076163 -223.324539) (xy 109.118082 -223.294083) (xy 109.164249 -223.27056)
			(xy 109.213528 -223.254548) (xy 109.264705 -223.246442) (xy 109.316519 -223.246442) (xy 109.367696 -223.254548)
			(xy 109.416975 -223.27056) (xy 109.463142 -223.294083) (xy 109.505061 -223.324539) (xy 109.541699 -223.361177)
			(xy 109.572155 -223.403096) (xy 109.595678 -223.449263) (xy 109.61169 -223.498542) (xy 109.619796 -223.549719)
			(xy 109.620304 -223.575626) (xy 109.619887 -223.600992) (xy 109.612134 -223.651127) (xy 109.596785 -223.69948)
			(xy 109.574203 -223.744908) (xy 109.544922 -223.786336) (xy 109.509634 -223.822783) (xy 109.469175 -223.853388)
			(xy 109.424501 -223.877427) (xy 109.376669 -223.894332) (xy 109.351826 -223.899476) (xy 109.328966 -223.903794)
			(xy 109.124242 -224.258632) (xy 109.132116 -224.280476) (xy 109.14069 -224.306896) (xy 109.14989 -224.36167)
			(xy 109.150404 -224.389442) (xy 109.431328 -224.389442) (xy 109.431836 -224.363555) (xy 109.439935 -224.312417)
			(xy 109.455934 -224.263177) (xy 109.47944 -224.217045) (xy 109.509872 -224.175158) (xy 109.546482 -224.138548)
			(xy 109.588369 -224.108116) (xy 109.634501 -224.08461) (xy 109.683741 -224.068611) (xy 109.734879 -224.060512)
			(xy 109.786653 -224.060512) (xy 109.837791 -224.068611) (xy 109.887031 -224.08461) (xy 109.933163 -224.108116)
			(xy 109.97505 -224.138548) (xy 110.01166 -224.175158) (xy 110.042092 -224.217045) (xy 110.065598 -224.263177)
			(xy 110.081597 -224.312417) (xy 110.089696 -224.363555) (xy 110.090204 -224.389442) (xy 110.371128 -224.389442)
			(xy 110.371535 -224.364105) (xy 110.379297 -224.314028) (xy 110.394629 -224.265728) (xy 110.41717 -224.220343)
			(xy 110.446389 -224.17894) (xy 110.481599 -224.142496) (xy 110.52197 -224.111867) (xy 110.566552 -224.087776)
			(xy 110.614295 -224.070789) (xy 110.639098 -224.065592) (xy 110.661958 -224.061274) (xy 110.866682 -223.706436)
			(xy 110.859062 -223.684338) (xy 110.850431 -223.657991) (xy 110.84111 -223.603344) (xy 110.84052 -223.575626)
			(xy 110.841028 -223.549719) (xy 110.849134 -223.498542) (xy 110.865146 -223.449263) (xy 110.888669 -223.403096)
			(xy 110.919125 -223.361177) (xy 110.955763 -223.324539) (xy 110.997682 -223.294083) (xy 111.043849 -223.27056)
			(xy 111.093128 -223.254548) (xy 111.144305 -223.246442) (xy 111.196119 -223.246442) (xy 111.247296 -223.254548)
			(xy 111.296575 -223.27056) (xy 111.342742 -223.294083) (xy 111.384661 -223.324539) (xy 111.421299 -223.361177)
			(xy 111.451755 -223.403096) (xy 111.475278 -223.449263) (xy 111.49129 -223.498542) (xy 111.499396 -223.549719)
			(xy 111.499904 -223.575626) (xy 111.499487 -223.600992) (xy 111.491734 -223.651127) (xy 111.476385 -223.69948)
			(xy 111.453803 -223.744908) (xy 111.424522 -223.786336) (xy 111.389234 -223.822783) (xy 111.348775 -223.853388)
			(xy 111.304101 -223.877427) (xy 111.256269 -223.894332) (xy 111.231426 -223.899476) (xy 111.208566 -223.903794)
			(xy 111.003842 -224.258632) (xy 111.011716 -224.280476) (xy 111.02029 -224.306896) (xy 111.02949 -224.36167)
			(xy 111.030004 -224.389442) (xy 111.310928 -224.389442) (xy 111.311436 -224.363555) (xy 111.319535 -224.312417)
			(xy 111.335534 -224.263177) (xy 111.35904 -224.217045) (xy 111.389472 -224.175158) (xy 111.426082 -224.138548)
			(xy 111.467969 -224.108116) (xy 111.514101 -224.08461) (xy 111.563341 -224.068611) (xy 111.614479 -224.060512)
			(xy 111.666253 -224.060512) (xy 111.717391 -224.068611) (xy 111.766631 -224.08461) (xy 111.812763 -224.108116)
			(xy 111.85465 -224.138548) (xy 111.89126 -224.175158) (xy 111.921692 -224.217045) (xy 111.945198 -224.263177)
			(xy 111.961197 -224.312417) (xy 111.969296 -224.363555) (xy 111.969804 -224.389442) (xy 112.250728 -224.389442)
			(xy 112.251135 -224.364105) (xy 112.258897 -224.314028) (xy 112.274229 -224.265728) (xy 112.29677 -224.220343)
			(xy 112.325989 -224.17894) (xy 112.361199 -224.142496) (xy 112.40157 -224.111867) (xy 112.446152 -224.087776)
			(xy 112.493895 -224.070789) (xy 112.518698 -224.065592) (xy 112.541558 -224.061274) (xy 112.746282 -223.706436)
			(xy 112.738662 -223.684338) (xy 112.730031 -223.657991) (xy 112.72071 -223.603344) (xy 112.72012 -223.575626)
			(xy 112.720628 -223.549719) (xy 112.728734 -223.498542) (xy 112.744746 -223.449263) (xy 112.768269 -223.403096)
			(xy 112.798725 -223.361177) (xy 112.835363 -223.324539) (xy 112.877282 -223.294083) (xy 112.923449 -223.27056)
			(xy 112.972728 -223.254548) (xy 113.023905 -223.246442) (xy 113.075719 -223.246442) (xy 113.126896 -223.254548)
			(xy 113.176175 -223.27056) (xy 113.222342 -223.294083) (xy 113.264261 -223.324539) (xy 113.300899 -223.361177)
			(xy 113.331355 -223.403096) (xy 113.354878 -223.449263) (xy 113.37089 -223.498542) (xy 113.378996 -223.549719)
			(xy 113.379504 -223.575626) (xy 113.379087 -223.600992) (xy 113.371334 -223.651127) (xy 113.355985 -223.69948)
			(xy 113.333403 -223.744908) (xy 113.304122 -223.786336) (xy 113.268834 -223.822783) (xy 113.228375 -223.853388)
			(xy 113.183701 -223.877427) (xy 113.135869 -223.894332) (xy 113.111026 -223.899476) (xy 113.088166 -223.903794)
			(xy 112.883442 -224.258632) (xy 112.891316 -224.280476) (xy 112.89989 -224.306896) (xy 112.90909 -224.36167)
			(xy 112.909604 -224.389442) (xy 113.190528 -224.389442) (xy 113.191036 -224.363555) (xy 113.199135 -224.312417)
			(xy 113.215134 -224.263177) (xy 113.23864 -224.217045) (xy 113.269072 -224.175158) (xy 113.305682 -224.138548)
			(xy 113.347569 -224.108116) (xy 113.393701 -224.08461) (xy 113.442941 -224.068611) (xy 113.494079 -224.060512)
			(xy 113.545853 -224.060512) (xy 113.596991 -224.068611) (xy 113.646231 -224.08461) (xy 113.692363 -224.108116)
			(xy 113.73425 -224.138548) (xy 113.77086 -224.175158) (xy 113.801292 -224.217045) (xy 113.824798 -224.263177)
			(xy 113.840797 -224.312417) (xy 113.848896 -224.363555) (xy 113.849404 -224.389442) (xy 114.130328 -224.389442)
			(xy 114.130735 -224.364105) (xy 114.138497 -224.314028) (xy 114.153829 -224.265728) (xy 114.17637 -224.220343)
			(xy 114.205589 -224.17894) (xy 114.240799 -224.142496) (xy 114.28117 -224.111867) (xy 114.325752 -224.087776)
			(xy 114.373495 -224.070789) (xy 114.398298 -224.065592) (xy 114.421158 -224.061274) (xy 114.626136 -223.706182)
			(xy 114.618516 -223.684084) (xy 114.609997 -223.657912) (xy 114.600803 -223.603651) (xy 114.600228 -223.576134)
			(xy 114.600228 -223.575626) (xy 114.600736 -223.549739) (xy 114.608835 -223.498601) (xy 114.624834 -223.449361)
			(xy 114.64834 -223.403229) (xy 114.678772 -223.361342) (xy 114.715382 -223.324732) (xy 114.757269 -223.2943)
			(xy 114.803401 -223.270794) (xy 114.852641 -223.254795) (xy 114.903779 -223.246696) (xy 114.955553 -223.246696)
			(xy 115.006691 -223.254795) (xy 115.055931 -223.270794) (xy 115.102063 -223.2943) (xy 115.14395 -223.324732)
			(xy 115.18056 -223.361342) (xy 115.210992 -223.403229) (xy 115.234498 -223.449361) (xy 115.250497 -223.498601)
			(xy 115.258596 -223.549739) (xy 115.259104 -223.575626) (xy 115.258687 -223.600992) (xy 115.250934 -223.651127)
			(xy 115.235585 -223.69948) (xy 115.213003 -223.744908) (xy 115.183722 -223.786336) (xy 115.148434 -223.822783)
			(xy 115.107975 -223.853388) (xy 115.063301 -223.877427) (xy 115.015469 -223.894332) (xy 114.990626 -223.899476)
			(xy 114.967766 -223.903794) (xy 114.763042 -224.258632) (xy 114.770916 -224.280476) (xy 114.77949 -224.306896)
			(xy 114.78869 -224.36167) (xy 114.789204 -224.389442) (xy 115.070128 -224.389442) (xy 115.070636 -224.363555)
			(xy 115.078735 -224.312417) (xy 115.094734 -224.263177) (xy 115.11824 -224.217045) (xy 115.148672 -224.175158)
			(xy 115.185282 -224.138548) (xy 115.227169 -224.108116) (xy 115.273301 -224.08461) (xy 115.322541 -224.068611)
			(xy 115.373679 -224.060512) (xy 115.425453 -224.060512) (xy 115.476591 -224.068611) (xy 115.525831 -224.08461)
			(xy 115.571963 -224.108116) (xy 115.61385 -224.138548) (xy 115.65046 -224.175158) (xy 115.680892 -224.217045)
			(xy 115.704398 -224.263177) (xy 115.720397 -224.312417) (xy 115.728496 -224.363555) (xy 115.729004 -224.389442)
			(xy 116.009928 -224.389442) (xy 116.010335 -224.364105) (xy 116.018097 -224.314028) (xy 116.033429 -224.265728)
			(xy 116.05597 -224.220343) (xy 116.085189 -224.17894) (xy 116.120399 -224.142496) (xy 116.16077 -224.111867)
			(xy 116.205352 -224.087776) (xy 116.253095 -224.070789) (xy 116.277898 -224.065592) (xy 116.300758 -224.061274)
			(xy 116.505482 -223.706436) (xy 116.497862 -223.684338) (xy 116.489231 -223.657991) (xy 116.47991 -223.603344)
			(xy 116.47932 -223.575626) (xy 116.479828 -223.549719) (xy 116.487934 -223.498542) (xy 116.503946 -223.449263)
			(xy 116.527469 -223.403096) (xy 116.557925 -223.361177) (xy 116.594563 -223.324539) (xy 116.636482 -223.294083)
			(xy 116.682649 -223.27056) (xy 116.731928 -223.254548) (xy 116.783105 -223.246442) (xy 116.834919 -223.246442)
			(xy 116.886096 -223.254548) (xy 116.935375 -223.27056) (xy 116.981542 -223.294083) (xy 117.023461 -223.324539)
			(xy 117.060099 -223.361177) (xy 117.090555 -223.403096) (xy 117.114078 -223.449263) (xy 117.13009 -223.498542)
			(xy 117.138196 -223.549719) (xy 117.138704 -223.575626) (xy 117.138287 -223.600992) (xy 117.130534 -223.651127)
			(xy 117.115185 -223.69948) (xy 117.092603 -223.744908) (xy 117.063322 -223.786336) (xy 117.028034 -223.822783)
			(xy 116.987575 -223.853388) (xy 116.942901 -223.877427) (xy 116.895069 -223.894332) (xy 116.870226 -223.899476)
			(xy 116.847366 -223.903794) (xy 116.642642 -224.258632) (xy 116.650516 -224.280476) (xy 116.65909 -224.306896)
			(xy 116.66829 -224.36167) (xy 116.668804 -224.389442) (xy 116.949728 -224.389442) (xy 116.950236 -224.363555)
			(xy 116.958335 -224.312417) (xy 116.974334 -224.263177) (xy 116.99784 -224.217045) (xy 117.028272 -224.175158)
			(xy 117.064882 -224.138548) (xy 117.106769 -224.108116) (xy 117.152901 -224.08461) (xy 117.202141 -224.068611)
			(xy 117.253279 -224.060512) (xy 117.305053 -224.060512) (xy 117.356191 -224.068611) (xy 117.405431 -224.08461)
			(xy 117.451563 -224.108116) (xy 117.49345 -224.138548) (xy 117.53006 -224.175158) (xy 117.560492 -224.217045)
			(xy 117.583998 -224.263177) (xy 117.599997 -224.312417) (xy 117.608096 -224.363555) (xy 117.608604 -224.389442)
			(xy 117.889528 -224.389442) (xy 117.889935 -224.364105) (xy 117.897697 -224.314028) (xy 117.913029 -224.265728)
			(xy 117.93557 -224.220343) (xy 117.964789 -224.17894) (xy 117.999999 -224.142496) (xy 118.04037 -224.111867)
			(xy 118.084952 -224.087776) (xy 118.132695 -224.070789) (xy 118.157498 -224.065592) (xy 118.180358 -224.061274)
			(xy 118.385082 -223.706436) (xy 118.377462 -223.684338) (xy 118.368831 -223.657991) (xy 118.35951 -223.603344)
			(xy 118.35892 -223.575626) (xy 118.359428 -223.549719) (xy 118.367534 -223.498542) (xy 118.383546 -223.449263)
			(xy 118.407069 -223.403096) (xy 118.437525 -223.361177) (xy 118.474163 -223.324539) (xy 118.516082 -223.294083)
			(xy 118.562249 -223.27056) (xy 118.611528 -223.254548) (xy 118.662705 -223.246442) (xy 118.714519 -223.246442)
			(xy 118.765696 -223.254548) (xy 118.814975 -223.27056) (xy 118.861142 -223.294083) (xy 118.903061 -223.324539)
			(xy 118.939699 -223.361177) (xy 118.970155 -223.403096) (xy 118.993678 -223.449263) (xy 119.00969 -223.498542)
			(xy 119.017796 -223.549719) (xy 119.018304 -223.575626) (xy 119.017887 -223.600992) (xy 119.010134 -223.651127)
			(xy 118.994785 -223.69948) (xy 118.972203 -223.744908) (xy 118.942922 -223.786336) (xy 118.907634 -223.822783)
			(xy 118.867175 -223.853388) (xy 118.822501 -223.877427) (xy 118.774669 -223.894332) (xy 118.749826 -223.899476)
			(xy 118.726966 -223.903794) (xy 118.522242 -224.258632) (xy 118.530116 -224.280476) (xy 118.53869 -224.306896)
			(xy 118.54789 -224.36167) (xy 118.548404 -224.389442) (xy 118.829328 -224.389442) (xy 118.829836 -224.363555)
			(xy 118.837935 -224.312417) (xy 118.853934 -224.263177) (xy 118.87744 -224.217045) (xy 118.907872 -224.175158)
			(xy 118.944482 -224.138548) (xy 118.986369 -224.108116) (xy 119.032501 -224.08461) (xy 119.081741 -224.068611)
			(xy 119.132879 -224.060512) (xy 119.184653 -224.060512) (xy 119.235791 -224.068611) (xy 119.285031 -224.08461)
			(xy 119.331163 -224.108116) (xy 119.37305 -224.138548) (xy 119.40966 -224.175158) (xy 119.440092 -224.217045)
			(xy 119.463598 -224.263177) (xy 119.479597 -224.312417) (xy 119.487696 -224.363555) (xy 119.488204 -224.389442)
			(xy 119.769128 -224.389442) (xy 119.769535 -224.364105) (xy 119.777297 -224.314028) (xy 119.792629 -224.265728)
			(xy 119.81517 -224.220343) (xy 119.844389 -224.17894) (xy 119.879599 -224.142496) (xy 119.91997 -224.111867)
			(xy 119.964552 -224.087776) (xy 120.012295 -224.070789) (xy 120.037098 -224.065592) (xy 120.059958 -224.061274)
			(xy 120.264682 -223.706436) (xy 120.257062 -223.684338) (xy 120.248431 -223.657991) (xy 120.23911 -223.603344)
			(xy 120.23852 -223.575626) (xy 120.239028 -223.549719) (xy 120.247134 -223.498542) (xy 120.263146 -223.449263)
			(xy 120.286669 -223.403096) (xy 120.317125 -223.361177) (xy 120.353763 -223.324539) (xy 120.395682 -223.294083)
			(xy 120.441849 -223.27056) (xy 120.491128 -223.254548) (xy 120.542305 -223.246442) (xy 120.594119 -223.246442)
			(xy 120.645296 -223.254548) (xy 120.694575 -223.27056) (xy 120.740742 -223.294083) (xy 120.782661 -223.324539)
			(xy 120.819299 -223.361177) (xy 120.849755 -223.403096) (xy 120.873278 -223.449263) (xy 120.88929 -223.498542)
			(xy 120.897396 -223.549719) (xy 120.897904 -223.575626) (xy 120.897487 -223.600992) (xy 120.889734 -223.651127)
			(xy 120.874385 -223.69948) (xy 120.851803 -223.744908) (xy 120.822522 -223.786336) (xy 120.787234 -223.822783)
			(xy 120.746775 -223.853388) (xy 120.702101 -223.877427) (xy 120.654269 -223.894332) (xy 120.629426 -223.899476)
			(xy 120.606566 -223.903794) (xy 120.401842 -224.258632) (xy 120.409716 -224.280476) (xy 120.41829 -224.306896)
			(xy 120.42749 -224.36167) (xy 120.428004 -224.389442) (xy 120.708928 -224.389442) (xy 120.709436 -224.363555)
			(xy 120.717535 -224.312417) (xy 120.733534 -224.263177) (xy 120.75704 -224.217045) (xy 120.787472 -224.175158)
			(xy 120.824082 -224.138548) (xy 120.865969 -224.108116) (xy 120.912101 -224.08461) (xy 120.961341 -224.068611)
			(xy 121.012479 -224.060512) (xy 121.064253 -224.060512) (xy 121.115391 -224.068611) (xy 121.164631 -224.08461)
			(xy 121.210763 -224.108116) (xy 121.25265 -224.138548) (xy 121.28926 -224.175158) (xy 121.319692 -224.217045)
			(xy 121.343198 -224.263177) (xy 121.359197 -224.312417) (xy 121.367296 -224.363555) (xy 121.367804 -224.389442)
			(xy 121.648728 -224.389442) (xy 121.649135 -224.364105) (xy 121.656897 -224.314028) (xy 121.672229 -224.265728)
			(xy 121.69477 -224.220343) (xy 121.723989 -224.17894) (xy 121.759199 -224.142496) (xy 121.79957 -224.111867)
			(xy 121.844152 -224.087776) (xy 121.891895 -224.070789) (xy 121.916698 -224.065592) (xy 121.939558 -224.061274)
			(xy 122.144282 -223.706436) (xy 122.136662 -223.684338) (xy 122.128031 -223.657991) (xy 122.11871 -223.603344)
			(xy 122.11812 -223.575626) (xy 122.118628 -223.549719) (xy 122.126734 -223.498542) (xy 122.142746 -223.449263)
			(xy 122.166269 -223.403096) (xy 122.196725 -223.361177) (xy 122.233363 -223.324539) (xy 122.275282 -223.294083)
			(xy 122.321449 -223.27056) (xy 122.370728 -223.254548) (xy 122.421905 -223.246442) (xy 122.473719 -223.246442)
			(xy 122.524896 -223.254548) (xy 122.574175 -223.27056) (xy 122.620342 -223.294083) (xy 122.662261 -223.324539)
			(xy 122.698899 -223.361177) (xy 122.729355 -223.403096) (xy 122.752878 -223.449263) (xy 122.76889 -223.498542)
			(xy 122.776996 -223.549719) (xy 122.777504 -223.575626) (xy 122.777087 -223.600992) (xy 122.769334 -223.651127)
			(xy 122.753985 -223.69948) (xy 122.731403 -223.744908) (xy 122.702122 -223.786336) (xy 122.666834 -223.822783)
			(xy 122.626375 -223.853388) (xy 122.581701 -223.877427) (xy 122.533869 -223.894332) (xy 122.509026 -223.899476)
			(xy 122.486166 -223.903794) (xy 122.281442 -224.258632) (xy 122.289316 -224.280476) (xy 122.29789 -224.306896)
			(xy 122.30709 -224.36167) (xy 122.307604 -224.389442) (xy 122.588528 -224.389442) (xy 122.589036 -224.363555)
			(xy 122.597135 -224.312417) (xy 122.613134 -224.263177) (xy 122.63664 -224.217045) (xy 122.667072 -224.175158)
			(xy 122.703682 -224.138548) (xy 122.745569 -224.108116) (xy 122.791701 -224.08461) (xy 122.840941 -224.068611)
			(xy 122.892079 -224.060512) (xy 122.943853 -224.060512) (xy 122.994991 -224.068611) (xy 123.044231 -224.08461)
			(xy 123.090363 -224.108116) (xy 123.13225 -224.138548) (xy 123.16886 -224.175158) (xy 123.199292 -224.217045)
			(xy 123.222798 -224.263177) (xy 123.238797 -224.312417) (xy 123.246896 -224.363555) (xy 123.247404 -224.389442)
			(xy 123.528328 -224.389442) (xy 123.528735 -224.364105) (xy 123.536497 -224.314028) (xy 123.551829 -224.265728)
			(xy 123.57437 -224.220343) (xy 123.603589 -224.17894) (xy 123.638799 -224.142496) (xy 123.67917 -224.111867)
			(xy 123.723752 -224.087776) (xy 123.771495 -224.070789) (xy 123.796298 -224.065592) (xy 123.819158 -224.061274)
			(xy 124.023882 -223.706436) (xy 124.016262 -223.684338) (xy 124.007631 -223.657991) (xy 123.99831 -223.603344)
			(xy 123.99772 -223.575626) (xy 123.998228 -223.549719) (xy 124.006334 -223.498542) (xy 124.022346 -223.449263)
			(xy 124.045869 -223.403096) (xy 124.076325 -223.361177) (xy 124.112963 -223.324539) (xy 124.154882 -223.294083)
			(xy 124.201049 -223.27056) (xy 124.250328 -223.254548) (xy 124.301505 -223.246442) (xy 124.353319 -223.246442)
			(xy 124.404496 -223.254548) (xy 124.453775 -223.27056) (xy 124.499942 -223.294083) (xy 124.541861 -223.324539)
			(xy 124.578499 -223.361177) (xy 124.608955 -223.403096) (xy 124.632478 -223.449263) (xy 124.64849 -223.498542)
			(xy 124.656596 -223.549719) (xy 124.657104 -223.575626) (xy 124.656687 -223.600992) (xy 124.648934 -223.651127)
			(xy 124.633585 -223.69948) (xy 124.611003 -223.744908) (xy 124.581722 -223.786336) (xy 124.546434 -223.822783)
			(xy 124.505975 -223.853388) (xy 124.461301 -223.877427) (xy 124.413469 -223.894332) (xy 124.388626 -223.899476)
			(xy 124.365766 -223.903794) (xy 124.161042 -224.258632) (xy 124.168916 -224.280476) (xy 124.17749 -224.306896)
			(xy 124.18669 -224.36167) (xy 124.187204 -224.389442) (xy 124.468128 -224.389442) (xy 124.468636 -224.363555)
			(xy 124.476735 -224.312417) (xy 124.492734 -224.263177) (xy 124.51624 -224.217045) (xy 124.546672 -224.175158)
			(xy 124.583282 -224.138548) (xy 124.625169 -224.108116) (xy 124.671301 -224.08461) (xy 124.720541 -224.068611)
			(xy 124.771679 -224.060512) (xy 124.823453 -224.060512) (xy 124.874591 -224.068611) (xy 124.923831 -224.08461)
			(xy 124.969963 -224.108116) (xy 125.01185 -224.138548) (xy 125.04846 -224.175158) (xy 125.078892 -224.217045)
			(xy 125.102398 -224.263177) (xy 125.118397 -224.312417) (xy 125.126496 -224.363555) (xy 125.127004 -224.389442)
			(xy 125.407928 -224.389442) (xy 125.408335 -224.364105) (xy 125.416097 -224.314028) (xy 125.431429 -224.265728)
			(xy 125.45397 -224.220343) (xy 125.483189 -224.17894) (xy 125.518399 -224.142496) (xy 125.55877 -224.111867)
			(xy 125.603352 -224.087776) (xy 125.651095 -224.070789) (xy 125.675898 -224.065592) (xy 125.698758 -224.061274)
			(xy 125.903482 -223.706436) (xy 125.895862 -223.684338) (xy 125.887231 -223.657991) (xy 125.87791 -223.603344)
			(xy 125.87732 -223.575626) (xy 125.877828 -223.549719) (xy 125.885934 -223.498542) (xy 125.901946 -223.449263)
			(xy 125.925469 -223.403096) (xy 125.955925 -223.361177) (xy 125.992563 -223.324539) (xy 126.034482 -223.294083)
			(xy 126.080649 -223.27056) (xy 126.129928 -223.254548) (xy 126.181105 -223.246442) (xy 126.232919 -223.246442)
			(xy 126.284096 -223.254548) (xy 126.333375 -223.27056) (xy 126.379542 -223.294083) (xy 126.421461 -223.324539)
			(xy 126.458099 -223.361177) (xy 126.488555 -223.403096) (xy 126.512078 -223.449263) (xy 126.52809 -223.498542)
			(xy 126.536196 -223.549719) (xy 126.536704 -223.575626) (xy 126.536287 -223.600992) (xy 126.528534 -223.651127)
			(xy 126.513185 -223.69948) (xy 126.490603 -223.744908) (xy 126.461322 -223.786336) (xy 126.426034 -223.822783)
			(xy 126.385575 -223.853388) (xy 126.340901 -223.877427) (xy 126.293069 -223.894332) (xy 126.268226 -223.899476)
			(xy 126.245366 -223.903794) (xy 126.040642 -224.258632) (xy 126.048516 -224.280476) (xy 126.05709 -224.306896)
			(xy 126.06629 -224.36167) (xy 126.066804 -224.389442) (xy 126.347728 -224.389442) (xy 126.348236 -224.363555)
			(xy 126.356335 -224.312417) (xy 126.372334 -224.263177) (xy 126.39584 -224.217045) (xy 126.426272 -224.175158)
			(xy 126.462882 -224.138548) (xy 126.504769 -224.108116) (xy 126.550901 -224.08461) (xy 126.600141 -224.068611)
			(xy 126.651279 -224.060512) (xy 126.703053 -224.060512) (xy 126.754191 -224.068611) (xy 126.803431 -224.08461)
			(xy 126.849563 -224.108116) (xy 126.89145 -224.138548) (xy 126.92806 -224.175158) (xy 126.958492 -224.217045)
			(xy 126.981998 -224.263177) (xy 126.997997 -224.312417) (xy 127.006096 -224.363555) (xy 127.006604 -224.389442)
			(xy 127.287528 -224.389442) (xy 127.287935 -224.364105) (xy 127.295697 -224.314028) (xy 127.311029 -224.265728)
			(xy 127.33357 -224.220343) (xy 127.362789 -224.17894) (xy 127.397999 -224.142496) (xy 127.43837 -224.111867)
			(xy 127.482952 -224.087776) (xy 127.530695 -224.070789) (xy 127.555498 -224.065592) (xy 127.578358 -224.061274)
			(xy 127.783082 -223.706436) (xy 127.775462 -223.684338) (xy 127.766831 -223.657991) (xy 127.75751 -223.603344)
			(xy 127.75692 -223.575626) (xy 127.757428 -223.549719) (xy 127.765534 -223.498542) (xy 127.781546 -223.449263)
			(xy 127.805069 -223.403096) (xy 127.835525 -223.361177) (xy 127.872163 -223.324539) (xy 127.914082 -223.294083)
			(xy 127.960249 -223.27056) (xy 128.009528 -223.254548) (xy 128.060705 -223.246442) (xy 128.112519 -223.246442)
			(xy 128.163696 -223.254548) (xy 128.212975 -223.27056) (xy 128.259142 -223.294083) (xy 128.301061 -223.324539)
			(xy 128.337699 -223.361177) (xy 128.368155 -223.403096) (xy 128.391678 -223.449263) (xy 128.40769 -223.498542)
			(xy 128.415796 -223.549719) (xy 128.416304 -223.575626) (xy 128.415887 -223.600992) (xy 128.408134 -223.651127)
			(xy 128.392785 -223.69948) (xy 128.370203 -223.744908) (xy 128.340922 -223.786336) (xy 128.305634 -223.822783)
			(xy 128.265175 -223.853388) (xy 128.220501 -223.877427) (xy 128.172669 -223.894332) (xy 128.147826 -223.899476)
			(xy 128.124966 -223.903794) (xy 127.920242 -224.258632) (xy 127.928116 -224.280476) (xy 127.93669 -224.306896)
			(xy 127.94589 -224.36167) (xy 127.946404 -224.389442) (xy 128.227328 -224.389442) (xy 128.227836 -224.363555)
			(xy 128.235935 -224.312417) (xy 128.251934 -224.263177) (xy 128.27544 -224.217045) (xy 128.305872 -224.175158)
			(xy 128.342482 -224.138548) (xy 128.384369 -224.108116) (xy 128.430501 -224.08461) (xy 128.479741 -224.068611)
			(xy 128.530879 -224.060512) (xy 128.582653 -224.060512) (xy 128.633791 -224.068611) (xy 128.683031 -224.08461)
			(xy 128.729163 -224.108116) (xy 128.77105 -224.138548) (xy 128.80766 -224.175158) (xy 128.838092 -224.217045)
			(xy 128.861598 -224.263177) (xy 128.877597 -224.312417) (xy 128.885696 -224.363555) (xy 128.886204 -224.389442)
			(xy 129.167128 -224.389442) (xy 129.167535 -224.364105) (xy 129.175297 -224.314028) (xy 129.190629 -224.265728)
			(xy 129.21317 -224.220343) (xy 129.242389 -224.17894) (xy 129.277599 -224.142496) (xy 129.31797 -224.111867)
			(xy 129.362552 -224.087776) (xy 129.410295 -224.070789) (xy 129.435098 -224.065592) (xy 129.457958 -224.061274)
			(xy 129.662682 -223.706436) (xy 129.655062 -223.684338) (xy 129.646431 -223.657991) (xy 129.63711 -223.603344)
			(xy 129.63652 -223.575626) (xy 129.637028 -223.549719) (xy 129.645134 -223.498542) (xy 129.661146 -223.449263)
			(xy 129.684669 -223.403096) (xy 129.715125 -223.361177) (xy 129.751763 -223.324539) (xy 129.793682 -223.294083)
			(xy 129.839849 -223.27056) (xy 129.889128 -223.254548) (xy 129.940305 -223.246442) (xy 129.992119 -223.246442)
			(xy 130.043296 -223.254548) (xy 130.092575 -223.27056) (xy 130.138742 -223.294083) (xy 130.180661 -223.324539)
			(xy 130.217299 -223.361177) (xy 130.247755 -223.403096) (xy 130.271278 -223.449263) (xy 130.28729 -223.498542)
			(xy 130.295396 -223.549719) (xy 130.295904 -223.575626) (xy 130.295487 -223.600992) (xy 130.287734 -223.651127)
			(xy 130.272385 -223.69948) (xy 130.249803 -223.744908) (xy 130.220522 -223.786336) (xy 130.185234 -223.822783)
			(xy 130.144775 -223.853388) (xy 130.100101 -223.877427) (xy 130.052269 -223.894332) (xy 130.027426 -223.899476)
			(xy 130.004566 -223.903794) (xy 129.799842 -224.258632) (xy 129.807716 -224.280476) (xy 129.81629 -224.306896)
			(xy 129.82549 -224.36167) (xy 129.826004 -224.389442) (xy 130.106928 -224.389442) (xy 130.107436 -224.363555)
			(xy 130.115535 -224.312417) (xy 130.131534 -224.263177) (xy 130.15504 -224.217045) (xy 130.185472 -224.175158)
			(xy 130.222082 -224.138548) (xy 130.263969 -224.108116) (xy 130.310101 -224.08461) (xy 130.359341 -224.068611)
			(xy 130.410479 -224.060512) (xy 130.462253 -224.060512) (xy 130.513391 -224.068611) (xy 130.562631 -224.08461)
			(xy 130.608763 -224.108116) (xy 130.65065 -224.138548) (xy 130.68726 -224.175158) (xy 130.717692 -224.217045)
			(xy 130.741198 -224.263177) (xy 130.757197 -224.312417) (xy 130.765296 -224.363555) (xy 130.765804 -224.389442)
			(xy 131.986528 -224.389442) (xy 131.987036 -224.363555) (xy 131.995135 -224.312417) (xy 132.011134 -224.263177)
			(xy 132.03464 -224.217045) (xy 132.065072 -224.175158) (xy 132.101682 -224.138548) (xy 132.143569 -224.108116)
			(xy 132.189701 -224.08461) (xy 132.238941 -224.068611) (xy 132.290079 -224.060512) (xy 132.341853 -224.060512)
			(xy 132.392991 -224.068611) (xy 132.442231 -224.08461) (xy 132.488363 -224.108116) (xy 132.53025 -224.138548)
			(xy 132.56686 -224.175158) (xy 132.597292 -224.217045) (xy 132.620798 -224.263177) (xy 132.636797 -224.312417)
			(xy 132.644896 -224.363555) (xy 132.645404 -224.389442) (xy 337.635596 -224.389442) (xy 337.636029 -224.364106)
			(xy 337.64379 -224.314032) (xy 337.65912 -224.265734) (xy 337.681659 -224.22035) (xy 337.710875 -224.178949)
			(xy 337.746081 -224.142504) (xy 337.786448 -224.111874) (xy 337.831026 -224.087781) (xy 337.878765 -224.070791)
			(xy 337.903566 -224.065592) (xy 337.926426 -224.061274) (xy 338.13115 -223.706182) (xy 338.12353 -223.684338)
			(xy 338.114887 -223.657995) (xy 338.105572 -223.603345) (xy 338.104988 -223.575626) (xy 338.105496 -223.549719)
			(xy 338.113602 -223.498542) (xy 338.129614 -223.449263) (xy 338.153137 -223.403096) (xy 338.183593 -223.361177)
			(xy 338.220231 -223.324539) (xy 338.26215 -223.294083) (xy 338.308317 -223.27056) (xy 338.357596 -223.254548)
			(xy 338.408773 -223.246442) (xy 338.460587 -223.246442) (xy 338.511764 -223.254548) (xy 338.561043 -223.27056)
			(xy 338.60721 -223.294083) (xy 338.649129 -223.324539) (xy 338.685767 -223.361177) (xy 338.716223 -223.403096)
			(xy 338.739746 -223.449263) (xy 338.755758 -223.498542) (xy 338.763864 -223.549719) (xy 338.764372 -223.575626)
			(xy 338.763897 -223.600971) (xy 338.756121 -223.651063) (xy 338.740771 -223.699374) (xy 338.718208 -223.744767)
			(xy 338.688966 -223.786173) (xy 338.653731 -223.822617) (xy 338.613335 -223.853239) (xy 338.568728 -223.877319)
			(xy 338.520962 -223.89429) (xy 338.496148 -223.899476) (xy 338.473288 -223.903794) (xy 338.268564 -224.258632)
			(xy 338.276184 -224.280476) (xy 338.284739 -224.306769) (xy 338.293932 -224.361289) (xy 338.294472 -224.388934)
			(xy 338.294472 -224.389442) (xy 338.575396 -224.389442) (xy 338.575904 -224.363555) (xy 338.584003 -224.312417)
			(xy 338.600002 -224.263177) (xy 338.623508 -224.217045) (xy 338.65394 -224.175158) (xy 338.69055 -224.138548)
			(xy 338.732437 -224.108116) (xy 338.778569 -224.08461) (xy 338.827809 -224.068611) (xy 338.878947 -224.060512)
			(xy 338.930721 -224.060512) (xy 338.981859 -224.068611) (xy 339.031099 -224.08461) (xy 339.077231 -224.108116)
			(xy 339.119118 -224.138548) (xy 339.155728 -224.175158) (xy 339.18616 -224.217045) (xy 339.209666 -224.263177)
			(xy 339.225665 -224.312417) (xy 339.233764 -224.363555) (xy 339.234272 -224.389442) (xy 339.515196 -224.389442)
			(xy 339.515629 -224.364106) (xy 339.52339 -224.314032) (xy 339.53872 -224.265734) (xy 339.561259 -224.22035)
			(xy 339.590475 -224.178949) (xy 339.625681 -224.142504) (xy 339.666048 -224.111874) (xy 339.710626 -224.087781)
			(xy 339.758365 -224.070791) (xy 339.783166 -224.065592) (xy 339.806026 -224.061274) (xy 340.01075 -223.706182)
			(xy 340.00313 -223.684338) (xy 339.994487 -223.657995) (xy 339.985172 -223.603345) (xy 339.984588 -223.575626)
			(xy 339.985096 -223.549719) (xy 339.993202 -223.498542) (xy 340.009214 -223.449263) (xy 340.032737 -223.403096)
			(xy 340.063193 -223.361177) (xy 340.099831 -223.324539) (xy 340.14175 -223.294083) (xy 340.187917 -223.27056)
			(xy 340.237196 -223.254548) (xy 340.288373 -223.246442) (xy 340.340187 -223.246442) (xy 340.391364 -223.254548)
			(xy 340.440643 -223.27056) (xy 340.48681 -223.294083) (xy 340.528729 -223.324539) (xy 340.565367 -223.361177)
			(xy 340.595823 -223.403096) (xy 340.619346 -223.449263) (xy 340.635358 -223.498542) (xy 340.643464 -223.549719)
			(xy 340.643972 -223.575626) (xy 340.643497 -223.600971) (xy 340.635721 -223.651063) (xy 340.620371 -223.699374)
			(xy 340.597808 -223.744767) (xy 340.568566 -223.786173) (xy 340.533331 -223.822617) (xy 340.492935 -223.853239)
			(xy 340.448328 -223.877319) (xy 340.400562 -223.89429) (xy 340.375748 -223.899476) (xy 340.352888 -223.903794)
			(xy 340.148164 -224.258632) (xy 340.155784 -224.280476) (xy 340.164339 -224.306769) (xy 340.173532 -224.361289)
			(xy 340.174072 -224.388934) (xy 340.174072 -224.389442) (xy 340.454996 -224.389442) (xy 340.455504 -224.363555)
			(xy 340.463603 -224.312417) (xy 340.479602 -224.263177) (xy 340.503108 -224.217045) (xy 340.53354 -224.175158)
			(xy 340.57015 -224.138548) (xy 340.612037 -224.108116) (xy 340.658169 -224.08461) (xy 340.707409 -224.068611)
			(xy 340.758547 -224.060512) (xy 340.810321 -224.060512) (xy 340.861459 -224.068611) (xy 340.910699 -224.08461)
			(xy 340.956831 -224.108116) (xy 340.998718 -224.138548) (xy 341.035328 -224.175158) (xy 341.06576 -224.217045)
			(xy 341.089266 -224.263177) (xy 341.105265 -224.312417) (xy 341.113364 -224.363555) (xy 341.113872 -224.389442)
			(xy 341.394796 -224.389442) (xy 341.395229 -224.364106) (xy 341.40299 -224.314032) (xy 341.41832 -224.265734)
			(xy 341.440859 -224.22035) (xy 341.470075 -224.178949) (xy 341.505281 -224.142504) (xy 341.545648 -224.111874)
			(xy 341.590226 -224.087781) (xy 341.637965 -224.070791) (xy 341.662766 -224.065592) (xy 341.685626 -224.061274)
			(xy 341.89035 -223.706436) (xy 341.88273 -223.684338) (xy 341.874102 -223.657991) (xy 341.864779 -223.603344)
			(xy 341.864188 -223.575626) (xy 341.864696 -223.549719) (xy 341.872802 -223.498542) (xy 341.888814 -223.449263)
			(xy 341.912337 -223.403096) (xy 341.942793 -223.361177) (xy 341.979431 -223.324539) (xy 342.02135 -223.294083)
			(xy 342.067517 -223.27056) (xy 342.116796 -223.254548) (xy 342.167973 -223.246442) (xy 342.219787 -223.246442)
			(xy 342.270964 -223.254548) (xy 342.320243 -223.27056) (xy 342.36641 -223.294083) (xy 342.408329 -223.324539)
			(xy 342.444967 -223.361177) (xy 342.475423 -223.403096) (xy 342.498946 -223.449263) (xy 342.514958 -223.498542)
			(xy 342.523064 -223.549719) (xy 342.523572 -223.575626) (xy 342.523181 -223.600993) (xy 342.515428 -223.651131)
			(xy 342.500077 -223.699486) (xy 342.477492 -223.744915) (xy 342.448207 -223.786344) (xy 342.412916 -223.822791)
			(xy 342.372452 -223.853396) (xy 342.327774 -223.877433) (xy 342.279939 -223.894334) (xy 342.255094 -223.899476)
			(xy 342.232234 -223.903794) (xy 342.02751 -224.258632) (xy 342.035384 -224.280476) (xy 342.043957 -224.306897)
			(xy 342.053158 -224.36167) (xy 342.053672 -224.389442) (xy 342.334596 -224.389442) (xy 342.335104 -224.363555)
			(xy 342.343203 -224.312417) (xy 342.359202 -224.263177) (xy 342.382708 -224.217045) (xy 342.41314 -224.175158)
			(xy 342.44975 -224.138548) (xy 342.491637 -224.108116) (xy 342.537769 -224.08461) (xy 342.587009 -224.068611)
			(xy 342.638147 -224.060512) (xy 342.689921 -224.060512) (xy 342.741059 -224.068611) (xy 342.790299 -224.08461)
			(xy 342.836431 -224.108116) (xy 342.878318 -224.138548) (xy 342.914928 -224.175158) (xy 342.94536 -224.217045)
			(xy 342.968866 -224.263177) (xy 342.984865 -224.312417) (xy 342.992964 -224.363555) (xy 342.993472 -224.389442)
			(xy 343.274396 -224.389442) (xy 343.274829 -224.364106) (xy 343.28259 -224.314032) (xy 343.29792 -224.265734)
			(xy 343.320459 -224.22035) (xy 343.349675 -224.178949) (xy 343.384881 -224.142504) (xy 343.425248 -224.111874)
			(xy 343.469826 -224.087781) (xy 343.517565 -224.070791) (xy 343.542366 -224.065592) (xy 343.565226 -224.061274)
			(xy 343.76995 -223.706436) (xy 343.76233 -223.684338) (xy 343.753702 -223.657991) (xy 343.744379 -223.603344)
			(xy 343.743788 -223.575626) (xy 343.744296 -223.549719) (xy 343.752402 -223.498542) (xy 343.768414 -223.449263)
			(xy 343.791937 -223.403096) (xy 343.822393 -223.361177) (xy 343.859031 -223.324539) (xy 343.90095 -223.294083)
			(xy 343.947117 -223.27056) (xy 343.996396 -223.254548) (xy 344.047573 -223.246442) (xy 344.099387 -223.246442)
			(xy 344.150564 -223.254548) (xy 344.199843 -223.27056) (xy 344.24601 -223.294083) (xy 344.287929 -223.324539)
			(xy 344.324567 -223.361177) (xy 344.355023 -223.403096) (xy 344.378546 -223.449263) (xy 344.394558 -223.498542)
			(xy 344.402664 -223.549719) (xy 344.403172 -223.575626) (xy 344.402781 -223.600993) (xy 344.395028 -223.651131)
			(xy 344.379677 -223.699486) (xy 344.357092 -223.744915) (xy 344.327807 -223.786344) (xy 344.292516 -223.822791)
			(xy 344.252052 -223.853396) (xy 344.207374 -223.877433) (xy 344.159539 -223.894334) (xy 344.134694 -223.899476)
			(xy 344.111834 -223.903794) (xy 343.90711 -224.258632) (xy 343.914984 -224.280476) (xy 343.923557 -224.306897)
			(xy 343.932758 -224.36167) (xy 343.933272 -224.389442) (xy 344.214196 -224.389442) (xy 344.214704 -224.363555)
			(xy 344.222803 -224.312417) (xy 344.238802 -224.263177) (xy 344.262308 -224.217045) (xy 344.29274 -224.175158)
			(xy 344.32935 -224.138548) (xy 344.371237 -224.108116) (xy 344.417369 -224.08461) (xy 344.466609 -224.068611)
			(xy 344.517747 -224.060512) (xy 344.569521 -224.060512) (xy 344.620659 -224.068611) (xy 344.669899 -224.08461)
			(xy 344.716031 -224.108116) (xy 344.757918 -224.138548) (xy 344.794528 -224.175158) (xy 344.82496 -224.217045)
			(xy 344.848466 -224.263177) (xy 344.864465 -224.312417) (xy 344.872564 -224.363555) (xy 344.873072 -224.389442)
			(xy 345.153996 -224.389442) (xy 345.154429 -224.364106) (xy 345.16219 -224.314032) (xy 345.17752 -224.265734)
			(xy 345.200059 -224.22035) (xy 345.229275 -224.178949) (xy 345.264481 -224.142504) (xy 345.304848 -224.111874)
			(xy 345.349426 -224.087781) (xy 345.397165 -224.070791) (xy 345.421966 -224.065592) (xy 345.444826 -224.061274)
			(xy 345.64955 -223.706436) (xy 345.64193 -223.684338) (xy 345.633302 -223.657991) (xy 345.623979 -223.603344)
			(xy 345.623388 -223.575626) (xy 345.623896 -223.549719) (xy 345.632002 -223.498542) (xy 345.648014 -223.449263)
			(xy 345.671537 -223.403096) (xy 345.701993 -223.361177) (xy 345.738631 -223.324539) (xy 345.78055 -223.294083)
			(xy 345.826717 -223.27056) (xy 345.875996 -223.254548) (xy 345.927173 -223.246442) (xy 345.978987 -223.246442)
			(xy 346.030164 -223.254548) (xy 346.079443 -223.27056) (xy 346.12561 -223.294083) (xy 346.167529 -223.324539)
			(xy 346.204167 -223.361177) (xy 346.234623 -223.403096) (xy 346.258146 -223.449263) (xy 346.274158 -223.498542)
			(xy 346.282264 -223.549719) (xy 346.282772 -223.575626) (xy 346.282381 -223.600993) (xy 346.274628 -223.651131)
			(xy 346.259277 -223.699486) (xy 346.236692 -223.744915) (xy 346.207407 -223.786344) (xy 346.172116 -223.822791)
			(xy 346.131652 -223.853396) (xy 346.086974 -223.877433) (xy 346.039139 -223.894334) (xy 346.014294 -223.899476)
			(xy 345.991434 -223.903794) (xy 345.78671 -224.258632) (xy 345.794584 -224.280476) (xy 345.803157 -224.306897)
			(xy 345.812358 -224.36167) (xy 345.812872 -224.389442) (xy 346.093796 -224.389442) (xy 346.094304 -224.363555)
			(xy 346.102403 -224.312417) (xy 346.118402 -224.263177) (xy 346.141908 -224.217045) (xy 346.17234 -224.175158)
			(xy 346.20895 -224.138548) (xy 346.250837 -224.108116) (xy 346.296969 -224.08461) (xy 346.346209 -224.068611)
			(xy 346.397347 -224.060512) (xy 346.449121 -224.060512) (xy 346.500259 -224.068611) (xy 346.549499 -224.08461)
			(xy 346.595631 -224.108116) (xy 346.637518 -224.138548) (xy 346.674128 -224.175158) (xy 346.70456 -224.217045)
			(xy 346.728066 -224.263177) (xy 346.744065 -224.312417) (xy 346.752164 -224.363555) (xy 346.752672 -224.389442)
			(xy 347.033596 -224.389442) (xy 347.034029 -224.364106) (xy 347.04179 -224.314032) (xy 347.05712 -224.265734)
			(xy 347.079659 -224.22035) (xy 347.108875 -224.178949) (xy 347.144081 -224.142504) (xy 347.184448 -224.111874)
			(xy 347.229026 -224.087781) (xy 347.276765 -224.070791) (xy 347.301566 -224.065592) (xy 347.324426 -224.061274)
			(xy 347.52915 -223.706436) (xy 347.52153 -223.684338) (xy 347.512902 -223.657991) (xy 347.503579 -223.603344)
			(xy 347.502988 -223.575626) (xy 347.503496 -223.549719) (xy 347.511602 -223.498542) (xy 347.527614 -223.449263)
			(xy 347.551137 -223.403096) (xy 347.581593 -223.361177) (xy 347.618231 -223.324539) (xy 347.66015 -223.294083)
			(xy 347.706317 -223.27056) (xy 347.755596 -223.254548) (xy 347.806773 -223.246442) (xy 347.858587 -223.246442)
			(xy 347.909764 -223.254548) (xy 347.959043 -223.27056) (xy 348.00521 -223.294083) (xy 348.047129 -223.324539)
			(xy 348.083767 -223.361177) (xy 348.114223 -223.403096) (xy 348.137746 -223.449263) (xy 348.153758 -223.498542)
			(xy 348.161864 -223.549719) (xy 348.162372 -223.575626) (xy 348.161981 -223.600993) (xy 348.154228 -223.651131)
			(xy 348.138877 -223.699486) (xy 348.116292 -223.744915) (xy 348.087007 -223.786344) (xy 348.051716 -223.822791)
			(xy 348.011252 -223.853396) (xy 347.966574 -223.877433) (xy 347.918739 -223.894334) (xy 347.893894 -223.899476)
			(xy 347.871034 -223.903794) (xy 347.66631 -224.258632) (xy 347.674184 -224.280476) (xy 347.682757 -224.306897)
			(xy 347.691958 -224.36167) (xy 347.692472 -224.389442) (xy 347.973396 -224.389442) (xy 347.973904 -224.363555)
			(xy 347.982003 -224.312417) (xy 347.998002 -224.263177) (xy 348.021508 -224.217045) (xy 348.05194 -224.175158)
			(xy 348.08855 -224.138548) (xy 348.130437 -224.108116) (xy 348.176569 -224.08461) (xy 348.225809 -224.068611)
			(xy 348.276947 -224.060512) (xy 348.328721 -224.060512) (xy 348.379859 -224.068611) (xy 348.429099 -224.08461)
			(xy 348.475231 -224.108116) (xy 348.517118 -224.138548) (xy 348.553728 -224.175158) (xy 348.58416 -224.217045)
			(xy 348.607666 -224.263177) (xy 348.623665 -224.312417) (xy 348.631764 -224.363555) (xy 348.632272 -224.389442)
			(xy 348.913196 -224.389442) (xy 348.913629 -224.364106) (xy 348.92139 -224.314032) (xy 348.93672 -224.265734)
			(xy 348.959259 -224.22035) (xy 348.988475 -224.178949) (xy 349.023681 -224.142504) (xy 349.064048 -224.111874)
			(xy 349.108626 -224.087781) (xy 349.156365 -224.070791) (xy 349.181166 -224.065592) (xy 349.204026 -224.061274)
			(xy 349.40875 -223.706436) (xy 349.40113 -223.684338) (xy 349.392502 -223.657991) (xy 349.383179 -223.603344)
			(xy 349.382588 -223.575626) (xy 349.383096 -223.549719) (xy 349.391202 -223.498542) (xy 349.407214 -223.449263)
			(xy 349.430737 -223.403096) (xy 349.461193 -223.361177) (xy 349.497831 -223.324539) (xy 349.53975 -223.294083)
			(xy 349.585917 -223.27056) (xy 349.635196 -223.254548) (xy 349.686373 -223.246442) (xy 349.738187 -223.246442)
			(xy 349.789364 -223.254548) (xy 349.838643 -223.27056) (xy 349.88481 -223.294083) (xy 349.926729 -223.324539)
			(xy 349.963367 -223.361177) (xy 349.993823 -223.403096) (xy 350.017346 -223.449263) (xy 350.033358 -223.498542)
			(xy 350.041464 -223.549719) (xy 350.041972 -223.575626) (xy 350.041581 -223.600993) (xy 350.033828 -223.651131)
			(xy 350.018477 -223.699486) (xy 349.995892 -223.744915) (xy 349.966607 -223.786344) (xy 349.931316 -223.822791)
			(xy 349.890852 -223.853396) (xy 349.846174 -223.877433) (xy 349.798339 -223.894334) (xy 349.773494 -223.899476)
			(xy 349.750634 -223.903794) (xy 349.54591 -224.258632) (xy 349.553784 -224.280476) (xy 349.562357 -224.306897)
			(xy 349.571558 -224.36167) (xy 349.572072 -224.389442) (xy 349.852996 -224.389442) (xy 349.853504 -224.363555)
			(xy 349.861603 -224.312417) (xy 349.877602 -224.263177) (xy 349.901108 -224.217045) (xy 349.93154 -224.175158)
			(xy 349.96815 -224.138548) (xy 350.010037 -224.108116) (xy 350.056169 -224.08461) (xy 350.105409 -224.068611)
			(xy 350.156547 -224.060512) (xy 350.208321 -224.060512) (xy 350.259459 -224.068611) (xy 350.308699 -224.08461)
			(xy 350.354831 -224.108116) (xy 350.396718 -224.138548) (xy 350.433328 -224.175158) (xy 350.46376 -224.217045)
			(xy 350.487266 -224.263177) (xy 350.503265 -224.312417) (xy 350.511364 -224.363555) (xy 350.511872 -224.389442)
			(xy 350.792796 -224.389442) (xy 350.793229 -224.364106) (xy 350.80099 -224.314032) (xy 350.81632 -224.265734)
			(xy 350.838859 -224.22035) (xy 350.868075 -224.178949) (xy 350.903281 -224.142504) (xy 350.943648 -224.111874)
			(xy 350.988226 -224.087781) (xy 351.035965 -224.070791) (xy 351.060766 -224.065592) (xy 351.083626 -224.061274)
			(xy 351.28835 -223.706436) (xy 351.28073 -223.684338) (xy 351.272102 -223.657991) (xy 351.262779 -223.603344)
			(xy 351.262188 -223.575626) (xy 351.262696 -223.549719) (xy 351.270802 -223.498542) (xy 351.286814 -223.449263)
			(xy 351.310337 -223.403096) (xy 351.340793 -223.361177) (xy 351.377431 -223.324539) (xy 351.41935 -223.294083)
			(xy 351.465517 -223.27056) (xy 351.514796 -223.254548) (xy 351.565973 -223.246442) (xy 351.617787 -223.246442)
			(xy 351.668964 -223.254548) (xy 351.718243 -223.27056) (xy 351.76441 -223.294083) (xy 351.806329 -223.324539)
			(xy 351.842967 -223.361177) (xy 351.873423 -223.403096) (xy 351.896946 -223.449263) (xy 351.912958 -223.498542)
			(xy 351.921064 -223.549719) (xy 351.921572 -223.575626) (xy 351.921181 -223.600993) (xy 351.913428 -223.651131)
			(xy 351.898077 -223.699486) (xy 351.875492 -223.744915) (xy 351.846207 -223.786344) (xy 351.810916 -223.822791)
			(xy 351.770452 -223.853396) (xy 351.725774 -223.877433) (xy 351.677939 -223.894334) (xy 351.653094 -223.899476)
			(xy 351.630234 -223.903794) (xy 351.42551 -224.258632) (xy 351.433384 -224.280476) (xy 351.441957 -224.306897)
			(xy 351.451158 -224.36167) (xy 351.451672 -224.389442) (xy 351.732596 -224.389442) (xy 351.733104 -224.363555)
			(xy 351.741203 -224.312417) (xy 351.757202 -224.263177) (xy 351.780708 -224.217045) (xy 351.81114 -224.175158)
			(xy 351.84775 -224.138548) (xy 351.889637 -224.108116) (xy 351.935769 -224.08461) (xy 351.985009 -224.068611)
			(xy 352.036147 -224.060512) (xy 352.087921 -224.060512) (xy 352.139059 -224.068611) (xy 352.188299 -224.08461)
			(xy 352.234431 -224.108116) (xy 352.276318 -224.138548) (xy 352.312928 -224.175158) (xy 352.34336 -224.217045)
			(xy 352.366866 -224.263177) (xy 352.382865 -224.312417) (xy 352.390964 -224.363555) (xy 352.391472 -224.389442)
			(xy 352.672396 -224.389442) (xy 352.672829 -224.364106) (xy 352.68059 -224.314032) (xy 352.69592 -224.265734)
			(xy 352.718459 -224.22035) (xy 352.747675 -224.178949) (xy 352.782881 -224.142504) (xy 352.823248 -224.111874)
			(xy 352.867826 -224.087781) (xy 352.915565 -224.070791) (xy 352.940366 -224.065592) (xy 352.963226 -224.061274)
			(xy 353.16795 -223.706436) (xy 353.16033 -223.684338) (xy 353.151702 -223.657991) (xy 353.142379 -223.603344)
			(xy 353.141788 -223.575626) (xy 353.142296 -223.549719) (xy 353.150402 -223.498542) (xy 353.166414 -223.449263)
			(xy 353.189937 -223.403096) (xy 353.220393 -223.361177) (xy 353.257031 -223.324539) (xy 353.29895 -223.294083)
			(xy 353.345117 -223.27056) (xy 353.394396 -223.254548) (xy 353.445573 -223.246442) (xy 353.497387 -223.246442)
			(xy 353.548564 -223.254548) (xy 353.597843 -223.27056) (xy 353.64401 -223.294083) (xy 353.685929 -223.324539)
			(xy 353.722567 -223.361177) (xy 353.753023 -223.403096) (xy 353.776546 -223.449263) (xy 353.792558 -223.498542)
			(xy 353.800664 -223.549719) (xy 353.801172 -223.575626) (xy 353.800781 -223.600993) (xy 353.793028 -223.651131)
			(xy 353.777677 -223.699486) (xy 353.755092 -223.744915) (xy 353.725807 -223.786344) (xy 353.690516 -223.822791)
			(xy 353.650052 -223.853396) (xy 353.605374 -223.877433) (xy 353.557539 -223.894334) (xy 353.532694 -223.899476)
			(xy 353.509834 -223.903794) (xy 353.30511 -224.258632) (xy 353.312984 -224.280476) (xy 353.321557 -224.306897)
			(xy 353.330758 -224.36167) (xy 353.331272 -224.389442) (xy 353.612196 -224.389442) (xy 353.612704 -224.363555)
			(xy 353.620803 -224.312417) (xy 353.636802 -224.263177) (xy 353.660308 -224.217045) (xy 353.69074 -224.175158)
			(xy 353.72735 -224.138548) (xy 353.769237 -224.108116) (xy 353.815369 -224.08461) (xy 353.864609 -224.068611)
			(xy 353.915747 -224.060512) (xy 353.967521 -224.060512) (xy 354.018659 -224.068611) (xy 354.067899 -224.08461)
			(xy 354.114031 -224.108116) (xy 354.155918 -224.138548) (xy 354.192528 -224.175158) (xy 354.22296 -224.217045)
			(xy 354.246466 -224.263177) (xy 354.262465 -224.312417) (xy 354.270564 -224.363555) (xy 354.271072 -224.389442)
			(xy 354.551996 -224.389442) (xy 354.552429 -224.364106) (xy 354.56019 -224.314032) (xy 354.57552 -224.265734)
			(xy 354.598059 -224.22035) (xy 354.627275 -224.178949) (xy 354.662481 -224.142504) (xy 354.702848 -224.111874)
			(xy 354.747426 -224.087781) (xy 354.795165 -224.070791) (xy 354.819966 -224.065592) (xy 354.842826 -224.061274)
			(xy 355.04755 -223.706436) (xy 355.03993 -223.684338) (xy 355.031302 -223.657991) (xy 355.021979 -223.603344)
			(xy 355.021388 -223.575626) (xy 355.021896 -223.549719) (xy 355.030002 -223.498542) (xy 355.046014 -223.449263)
			(xy 355.069537 -223.403096) (xy 355.099993 -223.361177) (xy 355.136631 -223.324539) (xy 355.17855 -223.294083)
			(xy 355.224717 -223.27056) (xy 355.273996 -223.254548) (xy 355.325173 -223.246442) (xy 355.376987 -223.246442)
			(xy 355.428164 -223.254548) (xy 355.477443 -223.27056) (xy 355.52361 -223.294083) (xy 355.565529 -223.324539)
			(xy 355.602167 -223.361177) (xy 355.632623 -223.403096) (xy 355.656146 -223.449263) (xy 355.672158 -223.498542)
			(xy 355.680264 -223.549719) (xy 355.680772 -223.575626) (xy 355.680381 -223.600993) (xy 355.672628 -223.651131)
			(xy 355.657277 -223.699486) (xy 355.634692 -223.744915) (xy 355.605407 -223.786344) (xy 355.570116 -223.822791)
			(xy 355.529652 -223.853396) (xy 355.484974 -223.877433) (xy 355.437139 -223.894334) (xy 355.412294 -223.899476)
			(xy 355.389434 -223.903794) (xy 355.18471 -224.258632) (xy 355.192584 -224.280476) (xy 355.201157 -224.306897)
			(xy 355.210358 -224.36167) (xy 355.210872 -224.389442) (xy 355.491796 -224.389442) (xy 355.492304 -224.363555)
			(xy 355.500403 -224.312417) (xy 355.516402 -224.263177) (xy 355.539908 -224.217045) (xy 355.57034 -224.175158)
			(xy 355.60695 -224.138548) (xy 355.648837 -224.108116) (xy 355.694969 -224.08461) (xy 355.744209 -224.068611)
			(xy 355.795347 -224.060512) (xy 355.847121 -224.060512) (xy 355.898259 -224.068611) (xy 355.947499 -224.08461)
			(xy 355.993631 -224.108116) (xy 356.035518 -224.138548) (xy 356.072128 -224.175158) (xy 356.10256 -224.217045)
			(xy 356.126066 -224.263177) (xy 356.142065 -224.312417) (xy 356.150164 -224.363555) (xy 356.150672 -224.389442)
			(xy 356.431596 -224.389442) (xy 356.432029 -224.364106) (xy 356.43979 -224.314032) (xy 356.45512 -224.265734)
			(xy 356.477659 -224.22035) (xy 356.506875 -224.178949) (xy 356.542081 -224.142504) (xy 356.582448 -224.111874)
			(xy 356.627026 -224.087781) (xy 356.674765 -224.070791) (xy 356.699566 -224.065592) (xy 356.722426 -224.061274)
			(xy 356.92715 -223.706436) (xy 356.91953 -223.684338) (xy 356.910902 -223.657991) (xy 356.901579 -223.603344)
			(xy 356.900988 -223.575626) (xy 356.901496 -223.549719) (xy 356.909602 -223.498542) (xy 356.925614 -223.449263)
			(xy 356.949137 -223.403096) (xy 356.979593 -223.361177) (xy 357.016231 -223.324539) (xy 357.05815 -223.294083)
			(xy 357.104317 -223.27056) (xy 357.153596 -223.254548) (xy 357.204773 -223.246442) (xy 357.256587 -223.246442)
			(xy 357.307764 -223.254548) (xy 357.357043 -223.27056) (xy 357.40321 -223.294083) (xy 357.445129 -223.324539)
			(xy 357.481767 -223.361177) (xy 357.512223 -223.403096) (xy 357.535746 -223.449263) (xy 357.551758 -223.498542)
			(xy 357.559864 -223.549719) (xy 357.560372 -223.575626) (xy 357.559981 -223.600993) (xy 357.552228 -223.651131)
			(xy 357.536877 -223.699486) (xy 357.514292 -223.744915) (xy 357.485007 -223.786344) (xy 357.449716 -223.822791)
			(xy 357.409252 -223.853396) (xy 357.364574 -223.877433) (xy 357.316739 -223.894334) (xy 357.291894 -223.899476)
			(xy 357.269034 -223.903794) (xy 357.06431 -224.258632) (xy 357.072184 -224.280476) (xy 357.080757 -224.306897)
			(xy 357.089958 -224.36167) (xy 357.090472 -224.389442) (xy 357.371396 -224.389442) (xy 357.371904 -224.363555)
			(xy 357.380003 -224.312417) (xy 357.396002 -224.263177) (xy 357.419508 -224.217045) (xy 357.44994 -224.175158)
			(xy 357.48655 -224.138548) (xy 357.528437 -224.108116) (xy 357.574569 -224.08461) (xy 357.623809 -224.068611)
			(xy 357.674947 -224.060512) (xy 357.726721 -224.060512) (xy 357.777859 -224.068611) (xy 357.827099 -224.08461)
			(xy 357.873231 -224.108116) (xy 357.915118 -224.138548) (xy 357.951728 -224.175158) (xy 357.98216 -224.217045)
			(xy 358.005666 -224.263177) (xy 358.021665 -224.312417) (xy 358.029764 -224.363555) (xy 358.030272 -224.389442)
			(xy 358.311196 -224.389442) (xy 358.311629 -224.364106) (xy 358.31939 -224.314032) (xy 358.33472 -224.265734)
			(xy 358.357259 -224.22035) (xy 358.386475 -224.178949) (xy 358.421681 -224.142504) (xy 358.462048 -224.111874)
			(xy 358.506626 -224.087781) (xy 358.554365 -224.070791) (xy 358.579166 -224.065592) (xy 358.602026 -224.061274)
			(xy 358.80675 -223.706436) (xy 358.79913 -223.684338) (xy 358.790502 -223.657991) (xy 358.781179 -223.603344)
			(xy 358.780588 -223.575626) (xy 358.781096 -223.549719) (xy 358.789202 -223.498542) (xy 358.805214 -223.449263)
			(xy 358.828737 -223.403096) (xy 358.859193 -223.361177) (xy 358.895831 -223.324539) (xy 358.93775 -223.294083)
			(xy 358.983917 -223.27056) (xy 359.033196 -223.254548) (xy 359.084373 -223.246442) (xy 359.136187 -223.246442)
			(xy 359.187364 -223.254548) (xy 359.236643 -223.27056) (xy 359.28281 -223.294083) (xy 359.324729 -223.324539)
			(xy 359.361367 -223.361177) (xy 359.391823 -223.403096) (xy 359.415346 -223.449263) (xy 359.431358 -223.498542)
			(xy 359.439464 -223.549719) (xy 359.439972 -223.575626) (xy 359.439581 -223.600993) (xy 359.431828 -223.651131)
			(xy 359.416477 -223.699486) (xy 359.393892 -223.744915) (xy 359.364607 -223.786344) (xy 359.329316 -223.822791)
			(xy 359.288852 -223.853396) (xy 359.244174 -223.877433) (xy 359.196339 -223.894334) (xy 359.171494 -223.899476)
			(xy 359.148634 -223.903794) (xy 358.94391 -224.258632) (xy 358.951784 -224.280476) (xy 358.960357 -224.306897)
			(xy 358.969558 -224.36167) (xy 358.970072 -224.389442) (xy 359.250996 -224.389442) (xy 359.251504 -224.363555)
			(xy 359.259603 -224.312417) (xy 359.275602 -224.263177) (xy 359.299108 -224.217045) (xy 359.32954 -224.175158)
			(xy 359.36615 -224.138548) (xy 359.408037 -224.108116) (xy 359.454169 -224.08461) (xy 359.503409 -224.068611)
			(xy 359.554547 -224.060512) (xy 359.606321 -224.060512) (xy 359.657459 -224.068611) (xy 359.706699 -224.08461)
			(xy 359.752831 -224.108116) (xy 359.794718 -224.138548) (xy 359.831328 -224.175158) (xy 359.86176 -224.217045)
			(xy 359.885266 -224.263177) (xy 359.901265 -224.312417) (xy 359.909364 -224.363555) (xy 359.909872 -224.389442)
			(xy 360.190796 -224.389442) (xy 360.191229 -224.364106) (xy 360.19899 -224.314032) (xy 360.21432 -224.265734)
			(xy 360.236859 -224.22035) (xy 360.266075 -224.178949) (xy 360.301281 -224.142504) (xy 360.341648 -224.111874)
			(xy 360.386226 -224.087781) (xy 360.433965 -224.070791) (xy 360.458766 -224.065592) (xy 360.481626 -224.061274)
			(xy 360.68635 -223.706436) (xy 360.67873 -223.684338) (xy 360.670102 -223.657991) (xy 360.660779 -223.603344)
			(xy 360.660188 -223.575626) (xy 360.660696 -223.549719) (xy 360.668802 -223.498542) (xy 360.684814 -223.449263)
			(xy 360.708337 -223.403096) (xy 360.738793 -223.361177) (xy 360.775431 -223.324539) (xy 360.81735 -223.294083)
			(xy 360.863517 -223.27056) (xy 360.912796 -223.254548) (xy 360.963973 -223.246442) (xy 361.015787 -223.246442)
			(xy 361.066964 -223.254548) (xy 361.116243 -223.27056) (xy 361.16241 -223.294083) (xy 361.204329 -223.324539)
			(xy 361.240967 -223.361177) (xy 361.271423 -223.403096) (xy 361.294946 -223.449263) (xy 361.310958 -223.498542)
			(xy 361.319064 -223.549719) (xy 361.319572 -223.575626) (xy 361.319181 -223.600993) (xy 361.311428 -223.651131)
			(xy 361.296077 -223.699486) (xy 361.273492 -223.744915) (xy 361.244207 -223.786344) (xy 361.208916 -223.822791)
			(xy 361.168452 -223.853396) (xy 361.123774 -223.877433) (xy 361.075939 -223.894334) (xy 361.051094 -223.899476)
			(xy 361.028234 -223.903794) (xy 360.82351 -224.258632) (xy 360.831384 -224.280476) (xy 360.839957 -224.306897)
			(xy 360.849158 -224.36167) (xy 360.849672 -224.389442) (xy 361.130596 -224.389442) (xy 361.131104 -224.363555)
			(xy 361.139203 -224.312417) (xy 361.155202 -224.263177) (xy 361.178708 -224.217045) (xy 361.20914 -224.175158)
			(xy 361.24575 -224.138548) (xy 361.287637 -224.108116) (xy 361.333769 -224.08461) (xy 361.383009 -224.068611)
			(xy 361.434147 -224.060512) (xy 361.485921 -224.060512) (xy 361.537059 -224.068611) (xy 361.586299 -224.08461)
			(xy 361.632431 -224.108116) (xy 361.674318 -224.138548) (xy 361.710928 -224.175158) (xy 361.74136 -224.217045)
			(xy 361.764866 -224.263177) (xy 361.780865 -224.312417) (xy 361.788964 -224.363555) (xy 361.789472 -224.389442)
			(xy 362.070396 -224.389442) (xy 362.070829 -224.364106) (xy 362.07859 -224.314032) (xy 362.09392 -224.265734)
			(xy 362.116459 -224.22035) (xy 362.145675 -224.178949) (xy 362.180881 -224.142504) (xy 362.221248 -224.111874)
			(xy 362.265826 -224.087781) (xy 362.313565 -224.070791) (xy 362.338366 -224.065592) (xy 362.361226 -224.061274)
			(xy 362.566204 -223.706182) (xy 362.558584 -223.684084) (xy 362.550064 -223.657913) (xy 362.540871 -223.603651)
			(xy 362.540296 -223.576134) (xy 362.540296 -223.575626) (xy 362.540804 -223.549739) (xy 362.548903 -223.498601)
			(xy 362.564902 -223.449361) (xy 362.588408 -223.403229) (xy 362.61884 -223.361342) (xy 362.65545 -223.324732)
			(xy 362.697337 -223.2943) (xy 362.743469 -223.270794) (xy 362.792709 -223.254795) (xy 362.843847 -223.246696)
			(xy 362.895621 -223.246696) (xy 362.946759 -223.254795) (xy 362.995999 -223.270794) (xy 363.042131 -223.2943)
			(xy 363.084018 -223.324732) (xy 363.120628 -223.361342) (xy 363.15106 -223.403229) (xy 363.174566 -223.449361)
			(xy 363.190565 -223.498601) (xy 363.198664 -223.549739) (xy 363.199172 -223.575626) (xy 363.198781 -223.600993)
			(xy 363.191028 -223.651131) (xy 363.175677 -223.699486) (xy 363.153092 -223.744915) (xy 363.123807 -223.786344)
			(xy 363.088516 -223.822791) (xy 363.048052 -223.853396) (xy 363.003374 -223.877433) (xy 362.955539 -223.894334)
			(xy 362.930694 -223.899476) (xy 362.907834 -223.903794) (xy 362.70311 -224.258632) (xy 362.710984 -224.280476)
			(xy 362.719557 -224.306897) (xy 362.728758 -224.36167) (xy 362.729272 -224.389442) (xy 363.010196 -224.389442)
			(xy 363.010704 -224.363555) (xy 363.018803 -224.312417) (xy 363.034802 -224.263177) (xy 363.058308 -224.217045)
			(xy 363.08874 -224.175158) (xy 363.12535 -224.138548) (xy 363.167237 -224.108116) (xy 363.213369 -224.08461)
			(xy 363.262609 -224.068611) (xy 363.313747 -224.060512) (xy 363.365521 -224.060512) (xy 363.416659 -224.068611)
			(xy 363.465899 -224.08461) (xy 363.512031 -224.108116) (xy 363.553918 -224.138548) (xy 363.590528 -224.175158)
			(xy 363.62096 -224.217045) (xy 363.644466 -224.263177) (xy 363.660465 -224.312417) (xy 363.668564 -224.363555)
			(xy 363.669072 -224.389442) (xy 363.949996 -224.389442) (xy 363.950429 -224.364106) (xy 363.95819 -224.314032)
			(xy 363.97352 -224.265734) (xy 363.996059 -224.22035) (xy 364.025275 -224.178949) (xy 364.060481 -224.142504)
			(xy 364.100848 -224.111874) (xy 364.145426 -224.087781) (xy 364.193165 -224.070791) (xy 364.217966 -224.065592)
			(xy 364.240826 -224.061274) (xy 364.44555 -223.706436) (xy 364.43793 -223.684338) (xy 364.429302 -223.657991)
			(xy 364.419979 -223.603344) (xy 364.419388 -223.575626) (xy 364.419896 -223.549719) (xy 364.428002 -223.498542)
			(xy 364.444014 -223.449263) (xy 364.467537 -223.403096) (xy 364.497993 -223.361177) (xy 364.534631 -223.324539)
			(xy 364.57655 -223.294083) (xy 364.622717 -223.27056) (xy 364.671996 -223.254548) (xy 364.723173 -223.246442)
			(xy 364.774987 -223.246442) (xy 364.826164 -223.254548) (xy 364.875443 -223.27056) (xy 364.92161 -223.294083)
			(xy 364.963529 -223.324539) (xy 365.000167 -223.361177) (xy 365.030623 -223.403096) (xy 365.054146 -223.449263)
			(xy 365.070158 -223.498542) (xy 365.078264 -223.549719) (xy 365.078772 -223.575626) (xy 365.078381 -223.600993)
			(xy 365.070628 -223.651131) (xy 365.055277 -223.699486) (xy 365.032692 -223.744915) (xy 365.003407 -223.786344)
			(xy 364.968116 -223.822791) (xy 364.927652 -223.853396) (xy 364.882974 -223.877433) (xy 364.835139 -223.894334)
			(xy 364.810294 -223.899476) (xy 364.787434 -223.903794) (xy 364.58271 -224.258632) (xy 364.590584 -224.280476)
			(xy 364.599157 -224.306897) (xy 364.608358 -224.36167) (xy 364.608872 -224.389442) (xy 364.889796 -224.389442)
			(xy 364.890304 -224.363555) (xy 364.898403 -224.312417) (xy 364.914402 -224.263177) (xy 364.937908 -224.217045)
			(xy 364.96834 -224.175158) (xy 365.00495 -224.138548) (xy 365.046837 -224.108116) (xy 365.092969 -224.08461)
			(xy 365.142209 -224.068611) (xy 365.193347 -224.060512) (xy 365.245121 -224.060512) (xy 365.296259 -224.068611)
			(xy 365.345499 -224.08461) (xy 365.391631 -224.108116) (xy 365.433518 -224.138548) (xy 365.470128 -224.175158)
			(xy 365.50056 -224.217045) (xy 365.524066 -224.263177) (xy 365.540065 -224.312417) (xy 365.548164 -224.363555)
			(xy 365.548672 -224.389442) (xy 365.829596 -224.389442) (xy 365.830029 -224.364106) (xy 365.83779 -224.314032)
			(xy 365.85312 -224.265734) (xy 365.875659 -224.22035) (xy 365.904875 -224.178949) (xy 365.940081 -224.142504)
			(xy 365.980448 -224.111874) (xy 366.025026 -224.087781) (xy 366.072765 -224.070791) (xy 366.097566 -224.065592)
			(xy 366.120426 -224.061274) (xy 366.32515 -223.706436) (xy 366.31753 -223.684338) (xy 366.308902 -223.657991)
			(xy 366.299579 -223.603344) (xy 366.298988 -223.575626) (xy 366.299496 -223.549719) (xy 366.307602 -223.498542)
			(xy 366.323614 -223.449263) (xy 366.347137 -223.403096) (xy 366.377593 -223.361177) (xy 366.414231 -223.324539)
			(xy 366.45615 -223.294083) (xy 366.502317 -223.27056) (xy 366.551596 -223.254548) (xy 366.602773 -223.246442)
			(xy 366.654587 -223.246442) (xy 366.705764 -223.254548) (xy 366.755043 -223.27056) (xy 366.80121 -223.294083)
			(xy 366.843129 -223.324539) (xy 366.879767 -223.361177) (xy 366.910223 -223.403096) (xy 366.933746 -223.449263)
			(xy 366.949758 -223.498542) (xy 366.957864 -223.549719) (xy 366.958372 -223.575626) (xy 366.957981 -223.600993)
			(xy 366.950228 -223.651131) (xy 366.934877 -223.699486) (xy 366.912292 -223.744915) (xy 366.883007 -223.786344)
			(xy 366.847716 -223.822791) (xy 366.807252 -223.853396) (xy 366.762574 -223.877433) (xy 366.714739 -223.894334)
			(xy 366.689894 -223.899476) (xy 366.667034 -223.903794) (xy 366.46231 -224.258632) (xy 366.470184 -224.280476)
			(xy 366.478757 -224.306897) (xy 366.487958 -224.36167) (xy 366.488472 -224.389442) (xy 366.769396 -224.389442)
			(xy 366.769904 -224.363555) (xy 366.778003 -224.312417) (xy 366.794002 -224.263177) (xy 366.817508 -224.217045)
			(xy 366.84794 -224.175158) (xy 366.88455 -224.138548) (xy 366.926437 -224.108116) (xy 366.972569 -224.08461)
			(xy 367.021809 -224.068611) (xy 367.072947 -224.060512) (xy 367.124721 -224.060512) (xy 367.175859 -224.068611)
			(xy 367.225099 -224.08461) (xy 367.271231 -224.108116) (xy 367.313118 -224.138548) (xy 367.349728 -224.175158)
			(xy 367.38016 -224.217045) (xy 367.403666 -224.263177) (xy 367.419665 -224.312417) (xy 367.427764 -224.363555)
			(xy 367.428272 -224.389442) (xy 367.709196 -224.389442) (xy 367.709629 -224.364106) (xy 367.71739 -224.314032)
			(xy 367.73272 -224.265734) (xy 367.755259 -224.22035) (xy 367.784475 -224.178949) (xy 367.819681 -224.142504)
			(xy 367.860048 -224.111874) (xy 367.904626 -224.087781) (xy 367.952365 -224.070791) (xy 367.977166 -224.065592)
			(xy 368.000026 -224.061274) (xy 368.20475 -223.706436) (xy 368.19713 -223.684338) (xy 368.188502 -223.657991)
			(xy 368.179179 -223.603344) (xy 368.178588 -223.575626) (xy 368.179096 -223.549719) (xy 368.187202 -223.498542)
			(xy 368.203214 -223.449263) (xy 368.226737 -223.403096) (xy 368.257193 -223.361177) (xy 368.293831 -223.324539)
			(xy 368.33575 -223.294083) (xy 368.381917 -223.27056) (xy 368.431196 -223.254548) (xy 368.482373 -223.246442)
			(xy 368.534187 -223.246442) (xy 368.585364 -223.254548) (xy 368.634643 -223.27056) (xy 368.68081 -223.294083)
			(xy 368.722729 -223.324539) (xy 368.759367 -223.361177) (xy 368.789823 -223.403096) (xy 368.813346 -223.449263)
			(xy 368.829358 -223.498542) (xy 368.837464 -223.549719) (xy 368.837972 -223.575626) (xy 368.837581 -223.600993)
			(xy 368.829828 -223.651131) (xy 368.814477 -223.699486) (xy 368.791892 -223.744915) (xy 368.762607 -223.786344)
			(xy 368.727316 -223.822791) (xy 368.686852 -223.853396) (xy 368.642174 -223.877433) (xy 368.594339 -223.894334)
			(xy 368.569494 -223.899476) (xy 368.546634 -223.903794) (xy 368.34191 -224.258632) (xy 368.349784 -224.280476)
			(xy 368.358357 -224.306897) (xy 368.367558 -224.36167) (xy 368.368072 -224.389442) (xy 368.648996 -224.389442)
			(xy 368.649504 -224.363555) (xy 368.657603 -224.312417) (xy 368.673602 -224.263177) (xy 368.697108 -224.217045)
			(xy 368.72754 -224.175158) (xy 368.76415 -224.138548) (xy 368.806037 -224.108116) (xy 368.852169 -224.08461)
			(xy 368.901409 -224.068611) (xy 368.952547 -224.060512) (xy 369.004321 -224.060512) (xy 369.055459 -224.068611)
			(xy 369.104699 -224.08461) (xy 369.150831 -224.108116) (xy 369.192718 -224.138548) (xy 369.229328 -224.175158)
			(xy 369.25976 -224.217045) (xy 369.283266 -224.263177) (xy 369.299265 -224.312417) (xy 369.307364 -224.363555)
			(xy 369.307872 -224.389442) (xy 369.588796 -224.389442) (xy 369.589229 -224.364106) (xy 369.59699 -224.314032)
			(xy 369.61232 -224.265734) (xy 369.634859 -224.22035) (xy 369.664075 -224.178949) (xy 369.699281 -224.142504)
			(xy 369.739648 -224.111874) (xy 369.784226 -224.087781) (xy 369.831965 -224.070791) (xy 369.856766 -224.065592)
			(xy 369.879626 -224.061274) (xy 370.08435 -223.706436) (xy 370.07673 -223.684338) (xy 370.068102 -223.657991)
			(xy 370.058779 -223.603344) (xy 370.058188 -223.575626) (xy 370.058696 -223.549719) (xy 370.066802 -223.498542)
			(xy 370.082814 -223.449263) (xy 370.106337 -223.403096) (xy 370.136793 -223.361177) (xy 370.173431 -223.324539)
			(xy 370.21535 -223.294083) (xy 370.261517 -223.27056) (xy 370.310796 -223.254548) (xy 370.361973 -223.246442)
			(xy 370.413787 -223.246442) (xy 370.464964 -223.254548) (xy 370.514243 -223.27056) (xy 370.56041 -223.294083)
			(xy 370.602329 -223.324539) (xy 370.638967 -223.361177) (xy 370.669423 -223.403096) (xy 370.692946 -223.449263)
			(xy 370.708958 -223.498542) (xy 370.717064 -223.549719) (xy 370.717572 -223.575626) (xy 370.717181 -223.600993)
			(xy 370.709428 -223.651131) (xy 370.694077 -223.699486) (xy 370.671492 -223.744915) (xy 370.642207 -223.786344)
			(xy 370.606916 -223.822791) (xy 370.566452 -223.853396) (xy 370.521774 -223.877433) (xy 370.473939 -223.894334)
			(xy 370.449094 -223.899476) (xy 370.426234 -223.903794) (xy 370.22151 -224.258632) (xy 370.229384 -224.280476)
			(xy 370.237957 -224.306897) (xy 370.247158 -224.36167) (xy 370.247672 -224.389442) (xy 370.528596 -224.389442)
			(xy 370.529104 -224.363555) (xy 370.537203 -224.312417) (xy 370.553202 -224.263177) (xy 370.576708 -224.217045)
			(xy 370.60714 -224.175158) (xy 370.64375 -224.138548) (xy 370.685637 -224.108116) (xy 370.731769 -224.08461)
			(xy 370.781009 -224.068611) (xy 370.832147 -224.060512) (xy 370.883921 -224.060512) (xy 370.935059 -224.068611)
			(xy 370.984299 -224.08461) (xy 371.030431 -224.108116) (xy 371.072318 -224.138548) (xy 371.108928 -224.175158)
			(xy 371.13936 -224.217045) (xy 371.162866 -224.263177) (xy 371.178865 -224.312417) (xy 371.186964 -224.363555)
			(xy 371.187472 -224.389442) (xy 371.468396 -224.389442) (xy 371.468829 -224.364106) (xy 371.47659 -224.314032)
			(xy 371.49192 -224.265734) (xy 371.514459 -224.22035) (xy 371.543675 -224.178949) (xy 371.578881 -224.142504)
			(xy 371.619248 -224.111874) (xy 371.663826 -224.087781) (xy 371.711565 -224.070791) (xy 371.736366 -224.065592)
			(xy 371.759226 -224.061274) (xy 371.96395 -223.706436) (xy 371.95633 -223.684338) (xy 371.947702 -223.657991)
			(xy 371.938379 -223.603344) (xy 371.937788 -223.575626) (xy 371.938296 -223.549719) (xy 371.946402 -223.498542)
			(xy 371.962414 -223.449263) (xy 371.985937 -223.403096) (xy 372.016393 -223.361177) (xy 372.053031 -223.324539)
			(xy 372.09495 -223.294083) (xy 372.141117 -223.27056) (xy 372.190396 -223.254548) (xy 372.241573 -223.246442)
			(xy 372.293387 -223.246442) (xy 372.344564 -223.254548) (xy 372.393843 -223.27056) (xy 372.44001 -223.294083)
			(xy 372.481929 -223.324539) (xy 372.518567 -223.361177) (xy 372.549023 -223.403096) (xy 372.572546 -223.449263)
			(xy 372.588558 -223.498542) (xy 372.596664 -223.549719) (xy 372.597172 -223.575626) (xy 372.596781 -223.600993)
			(xy 372.589028 -223.651131) (xy 372.573677 -223.699486) (xy 372.551092 -223.744915) (xy 372.521807 -223.786344)
			(xy 372.486516 -223.822791) (xy 372.446052 -223.853396) (xy 372.401374 -223.877433) (xy 372.353539 -223.894334)
			(xy 372.328694 -223.899476) (xy 372.305834 -223.903794) (xy 372.10111 -224.258632) (xy 372.108984 -224.280476)
			(xy 372.117557 -224.306897) (xy 372.126758 -224.36167) (xy 372.127272 -224.389442) (xy 372.408196 -224.389442)
			(xy 372.408704 -224.363555) (xy 372.416803 -224.312417) (xy 372.432802 -224.263177) (xy 372.456308 -224.217045)
			(xy 372.48674 -224.175158) (xy 372.52335 -224.138548) (xy 372.565237 -224.108116) (xy 372.611369 -224.08461)
			(xy 372.660609 -224.068611) (xy 372.711747 -224.060512) (xy 372.763521 -224.060512) (xy 372.814659 -224.068611)
			(xy 372.863899 -224.08461) (xy 372.910031 -224.108116) (xy 372.951918 -224.138548) (xy 372.988528 -224.175158)
			(xy 373.01896 -224.217045) (xy 373.042466 -224.263177) (xy 373.058465 -224.312417) (xy 373.066564 -224.363555)
			(xy 373.067072 -224.389442) (xy 373.347996 -224.389442) (xy 373.348429 -224.364106) (xy 373.35619 -224.314032)
			(xy 373.37152 -224.265734) (xy 373.394059 -224.22035) (xy 373.423275 -224.178949) (xy 373.458481 -224.142504)
			(xy 373.498848 -224.111874) (xy 373.543426 -224.087781) (xy 373.591165 -224.070791) (xy 373.615966 -224.065592)
			(xy 373.638826 -224.061274) (xy 373.84355 -223.706436) (xy 373.83593 -223.684338) (xy 373.827302 -223.657991)
			(xy 373.817979 -223.603344) (xy 373.817388 -223.575626) (xy 373.817896 -223.549719) (xy 373.826002 -223.498542)
			(xy 373.842014 -223.449263) (xy 373.865537 -223.403096) (xy 373.895993 -223.361177) (xy 373.932631 -223.324539)
			(xy 373.97455 -223.294083) (xy 374.020717 -223.27056) (xy 374.069996 -223.254548) (xy 374.121173 -223.246442)
			(xy 374.172987 -223.246442) (xy 374.224164 -223.254548) (xy 374.273443 -223.27056) (xy 374.31961 -223.294083)
			(xy 374.361529 -223.324539) (xy 374.398167 -223.361177) (xy 374.428623 -223.403096) (xy 374.452146 -223.449263)
			(xy 374.468158 -223.498542) (xy 374.476264 -223.549719) (xy 374.476772 -223.575626) (xy 374.476381 -223.600993)
			(xy 374.468628 -223.651131) (xy 374.453277 -223.699486) (xy 374.430692 -223.744915) (xy 374.401407 -223.786344)
			(xy 374.366116 -223.822791) (xy 374.325652 -223.853396) (xy 374.280974 -223.877433) (xy 374.233139 -223.894334)
			(xy 374.208294 -223.899476) (xy 374.185434 -223.903794) (xy 373.98071 -224.258632) (xy 373.988584 -224.280476)
			(xy 373.997157 -224.306897) (xy 374.006358 -224.36167) (xy 374.006872 -224.389442) (xy 374.287796 -224.389442)
			(xy 374.288304 -224.363555) (xy 374.296403 -224.312417) (xy 374.312402 -224.263177) (xy 374.335908 -224.217045)
			(xy 374.36634 -224.175158) (xy 374.40295 -224.138548) (xy 374.444837 -224.108116) (xy 374.490969 -224.08461)
			(xy 374.540209 -224.068611) (xy 374.591347 -224.060512) (xy 374.643121 -224.060512) (xy 374.694259 -224.068611)
			(xy 374.743499 -224.08461) (xy 374.789631 -224.108116) (xy 374.831518 -224.138548) (xy 374.868128 -224.175158)
			(xy 374.89856 -224.217045) (xy 374.922066 -224.263177) (xy 374.938065 -224.312417) (xy 374.946164 -224.363555)
			(xy 374.946672 -224.389442) (xy 375.227596 -224.389442) (xy 375.228029 -224.364106) (xy 375.23579 -224.314032)
			(xy 375.25112 -224.265734) (xy 375.273659 -224.22035) (xy 375.302875 -224.178949) (xy 375.338081 -224.142504)
			(xy 375.378448 -224.111874) (xy 375.423026 -224.087781) (xy 375.470765 -224.070791) (xy 375.495566 -224.065592)
			(xy 375.518426 -224.061274) (xy 375.72315 -223.706436) (xy 375.71553 -223.684338) (xy 375.706902 -223.657991)
			(xy 375.697579 -223.603344) (xy 375.696988 -223.575626) (xy 375.697496 -223.549719) (xy 375.705602 -223.498542)
			(xy 375.721614 -223.449263) (xy 375.745137 -223.403096) (xy 375.775593 -223.361177) (xy 375.812231 -223.324539)
			(xy 375.85415 -223.294083) (xy 375.900317 -223.27056) (xy 375.949596 -223.254548) (xy 376.000773 -223.246442)
			(xy 376.052587 -223.246442) (xy 376.103764 -223.254548) (xy 376.153043 -223.27056) (xy 376.19921 -223.294083)
			(xy 376.241129 -223.324539) (xy 376.277767 -223.361177) (xy 376.308223 -223.403096) (xy 376.331746 -223.449263)
			(xy 376.347758 -223.498542) (xy 376.355864 -223.549719) (xy 376.356372 -223.575626) (xy 376.355981 -223.600993)
			(xy 376.348228 -223.651131) (xy 376.332877 -223.699486) (xy 376.310292 -223.744915) (xy 376.281007 -223.786344)
			(xy 376.245716 -223.822791) (xy 376.205252 -223.853396) (xy 376.160574 -223.877433) (xy 376.112739 -223.894334)
			(xy 376.087894 -223.899476) (xy 376.065034 -223.903794) (xy 375.86031 -224.258632) (xy 375.868184 -224.280476)
			(xy 375.876757 -224.306897) (xy 375.885958 -224.36167) (xy 375.886472 -224.389442) (xy 376.167396 -224.389442)
			(xy 376.167904 -224.363555) (xy 376.176003 -224.312417) (xy 376.192002 -224.263177) (xy 376.215508 -224.217045)
			(xy 376.24594 -224.175158) (xy 376.28255 -224.138548) (xy 376.324437 -224.108116) (xy 376.370569 -224.08461)
			(xy 376.419809 -224.068611) (xy 376.470947 -224.060512) (xy 376.522721 -224.060512) (xy 376.573859 -224.068611)
			(xy 376.623099 -224.08461) (xy 376.669231 -224.108116) (xy 376.711118 -224.138548) (xy 376.747728 -224.175158)
			(xy 376.77816 -224.217045) (xy 376.801666 -224.263177) (xy 376.817665 -224.312417) (xy 376.825764 -224.363555)
			(xy 376.826272 -224.389442) (xy 377.107196 -224.389442) (xy 377.107629 -224.364106) (xy 377.11539 -224.314032)
			(xy 377.13072 -224.265734) (xy 377.153259 -224.22035) (xy 377.182475 -224.178949) (xy 377.217681 -224.142504)
			(xy 377.258048 -224.111874) (xy 377.302626 -224.087781) (xy 377.350365 -224.070791) (xy 377.375166 -224.065592)
			(xy 377.398026 -224.061274) (xy 377.60275 -223.706436) (xy 377.59513 -223.684338) (xy 377.586502 -223.657991)
			(xy 377.577179 -223.603344) (xy 377.576588 -223.575626) (xy 377.577096 -223.549719) (xy 377.585202 -223.498542)
			(xy 377.601214 -223.449263) (xy 377.624737 -223.403096) (xy 377.655193 -223.361177) (xy 377.691831 -223.324539)
			(xy 377.73375 -223.294083) (xy 377.779917 -223.27056) (xy 377.829196 -223.254548) (xy 377.880373 -223.246442)
			(xy 377.932187 -223.246442) (xy 377.983364 -223.254548) (xy 378.032643 -223.27056) (xy 378.07881 -223.294083)
			(xy 378.120729 -223.324539) (xy 378.157367 -223.361177) (xy 378.187823 -223.403096) (xy 378.211346 -223.449263)
			(xy 378.227358 -223.498542) (xy 378.235464 -223.549719) (xy 378.235972 -223.575626) (xy 378.235581 -223.600993)
			(xy 378.227828 -223.651131) (xy 378.212477 -223.699486) (xy 378.189892 -223.744915) (xy 378.160607 -223.786344)
			(xy 378.125316 -223.822791) (xy 378.084852 -223.853396) (xy 378.040174 -223.877433) (xy 377.992339 -223.894334)
			(xy 377.967494 -223.899476) (xy 377.944634 -223.903794) (xy 377.73991 -224.258632) (xy 377.747784 -224.280476)
			(xy 377.756357 -224.306897) (xy 377.765558 -224.36167) (xy 377.766072 -224.389442) (xy 378.046996 -224.389442)
			(xy 378.047504 -224.363555) (xy 378.055603 -224.312417) (xy 378.071602 -224.263177) (xy 378.095108 -224.217045)
			(xy 378.12554 -224.175158) (xy 378.16215 -224.138548) (xy 378.204037 -224.108116) (xy 378.250169 -224.08461)
			(xy 378.299409 -224.068611) (xy 378.350547 -224.060512) (xy 378.402321 -224.060512) (xy 378.453459 -224.068611)
			(xy 378.502699 -224.08461) (xy 378.548831 -224.108116) (xy 378.590718 -224.138548) (xy 378.627328 -224.175158)
			(xy 378.65776 -224.217045) (xy 378.681266 -224.263177) (xy 378.697265 -224.312417) (xy 378.705364 -224.363555)
			(xy 378.705872 -224.389442) (xy 379.926596 -224.389442) (xy 379.927104 -224.363555) (xy 379.935203 -224.312417)
			(xy 379.951202 -224.263177) (xy 379.974708 -224.217045) (xy 380.00514 -224.175158) (xy 380.04175 -224.138548)
			(xy 380.083637 -224.108116) (xy 380.129769 -224.08461) (xy 380.179009 -224.068611) (xy 380.230147 -224.060512)
			(xy 380.281921 -224.060512) (xy 380.333059 -224.068611) (xy 380.382299 -224.08461) (xy 380.428431 -224.108116)
			(xy 380.470318 -224.138548) (xy 380.506928 -224.175158) (xy 380.53736 -224.217045) (xy 380.560866 -224.263177)
			(xy 380.576865 -224.312417) (xy 380.584964 -224.363555) (xy 380.585472 -224.389442) (xy 380.584925 -224.417149)
			(xy 380.575741 -224.471796) (xy 380.567184 -224.498154) (xy 380.55931 -224.520252) (xy 380.764288 -224.87509)
			(xy 380.787148 -224.879408) (xy 380.811971 -224.884565) (xy 380.859751 -224.90152) (xy 380.904371 -224.925592)
			(xy 380.944778 -224.956214) (xy 380.980019 -224.992662) (xy 381.009263 -225.034077) (xy 381.031819 -225.079482)
			(xy 381.047156 -225.127806) (xy 381.054911 -225.177908) (xy 381.055372 -225.203258) (xy 381.054864 -225.229165)
			(xy 381.046758 -225.280342) (xy 381.030746 -225.329621) (xy 381.007223 -225.375788) (xy 380.976767 -225.417707)
			(xy 380.940129 -225.454345) (xy 380.89821 -225.484801) (xy 380.852043 -225.508324) (xy 380.802764 -225.524336)
			(xy 380.751587 -225.532442) (xy 380.699773 -225.532442) (xy 380.648596 -225.524336) (xy 380.599317 -225.508324)
			(xy 380.55315 -225.484801) (xy 380.511231 -225.454345) (xy 380.474593 -225.417707) (xy 380.444137 -225.375788)
			(xy 380.420614 -225.329621) (xy 380.404602 -225.280342) (xy 380.396496 -225.229165) (xy 380.395988 -225.203258)
			(xy 380.396597 -225.175541) (xy 380.40591 -225.120895) (xy 380.41453 -225.094546) (xy 380.422404 -225.072448)
			(xy 380.217426 -224.71761) (xy 380.194566 -224.713292) (xy 380.169748 -224.708169) (xy 380.122005 -224.691172)
			(xy 380.077426 -224.667071) (xy 380.03706 -224.636431) (xy 380.001857 -224.599976) (xy 379.972648 -224.558564)
			(xy 379.950119 -224.51317) (xy 379.934801 -224.464863) (xy 379.927055 -224.414781) (xy 379.926596 -224.389442)
			(xy 378.705872 -224.389442) (xy 378.705325 -224.417149) (xy 378.696141 -224.471796) (xy 378.687584 -224.498154)
			(xy 378.67971 -224.520252) (xy 378.884688 -224.87509) (xy 378.907548 -224.879408) (xy 378.932371 -224.884565)
			(xy 378.980151 -224.90152) (xy 379.024771 -224.925592) (xy 379.065178 -224.956214) (xy 379.100419 -224.992662)
			(xy 379.129663 -225.034077) (xy 379.152219 -225.079482) (xy 379.167556 -225.127806) (xy 379.175311 -225.177908)
			(xy 379.175772 -225.203258) (xy 379.175264 -225.229165) (xy 379.167158 -225.280342) (xy 379.151146 -225.329621)
			(xy 379.127623 -225.375788) (xy 379.097167 -225.417707) (xy 379.060529 -225.454345) (xy 379.01861 -225.484801)
			(xy 378.972443 -225.508324) (xy 378.923164 -225.524336) (xy 378.871987 -225.532442) (xy 378.820173 -225.532442)
			(xy 378.768996 -225.524336) (xy 378.719717 -225.508324) (xy 378.67355 -225.484801) (xy 378.631631 -225.454345)
			(xy 378.594993 -225.417707) (xy 378.564537 -225.375788) (xy 378.541014 -225.329621) (xy 378.525002 -225.280342)
			(xy 378.516896 -225.229165) (xy 378.516388 -225.203258) (xy 378.516997 -225.175541) (xy 378.52631 -225.120895)
			(xy 378.53493 -225.094546) (xy 378.542804 -225.072448) (xy 378.337826 -224.71761) (xy 378.314966 -224.713292)
			(xy 378.290148 -224.708169) (xy 378.242405 -224.691172) (xy 378.197826 -224.667071) (xy 378.15746 -224.636431)
			(xy 378.122257 -224.599976) (xy 378.093048 -224.558564) (xy 378.070519 -224.51317) (xy 378.055201 -224.464863)
			(xy 378.047455 -224.414781) (xy 378.046996 -224.389442) (xy 377.766072 -224.389442) (xy 377.765564 -224.415329)
			(xy 377.757465 -224.466467) (xy 377.741466 -224.515707) (xy 377.71796 -224.561839) (xy 377.687528 -224.603726)
			(xy 377.650918 -224.640336) (xy 377.609031 -224.670768) (xy 377.562899 -224.694274) (xy 377.513659 -224.710273)
			(xy 377.462521 -224.718372) (xy 377.410747 -224.718372) (xy 377.359609 -224.710273) (xy 377.310369 -224.694274)
			(xy 377.264237 -224.670768) (xy 377.22235 -224.640336) (xy 377.18574 -224.603726) (xy 377.155308 -224.561839)
			(xy 377.131802 -224.515707) (xy 377.115803 -224.466467) (xy 377.107704 -224.415329) (xy 377.107196 -224.389442)
			(xy 376.826272 -224.389442) (xy 376.825725 -224.417149) (xy 376.816541 -224.471796) (xy 376.807984 -224.498154)
			(xy 376.80011 -224.520252) (xy 377.005088 -224.87509) (xy 377.027948 -224.879408) (xy 377.052771 -224.884565)
			(xy 377.100551 -224.90152) (xy 377.145171 -224.925592) (xy 377.185578 -224.956214) (xy 377.220819 -224.992662)
			(xy 377.250063 -225.034077) (xy 377.272619 -225.079482) (xy 377.287956 -225.127806) (xy 377.295711 -225.177908)
			(xy 377.296172 -225.203258) (xy 377.295664 -225.229165) (xy 377.287558 -225.280342) (xy 377.271546 -225.329621)
			(xy 377.248023 -225.375788) (xy 377.217567 -225.417707) (xy 377.180929 -225.454345) (xy 377.13901 -225.484801)
			(xy 377.092843 -225.508324) (xy 377.043564 -225.524336) (xy 376.992387 -225.532442) (xy 376.940573 -225.532442)
			(xy 376.889396 -225.524336) (xy 376.840117 -225.508324) (xy 376.79395 -225.484801) (xy 376.752031 -225.454345)
			(xy 376.715393 -225.417707) (xy 376.684937 -225.375788) (xy 376.661414 -225.329621) (xy 376.645402 -225.280342)
			(xy 376.637296 -225.229165) (xy 376.636788 -225.203258) (xy 376.637397 -225.175541) (xy 376.64671 -225.120895)
			(xy 376.65533 -225.094546) (xy 376.663204 -225.072448) (xy 376.458226 -224.71761) (xy 376.435366 -224.713292)
			(xy 376.410548 -224.708169) (xy 376.362805 -224.691172) (xy 376.318226 -224.667071) (xy 376.27786 -224.636431)
			(xy 376.242657 -224.599976) (xy 376.213448 -224.558564) (xy 376.190919 -224.51317) (xy 376.175601 -224.464863)
			(xy 376.167855 -224.414781) (xy 376.167396 -224.389442) (xy 375.886472 -224.389442) (xy 375.885964 -224.415329)
			(xy 375.877865 -224.466467) (xy 375.861866 -224.515707) (xy 375.83836 -224.561839) (xy 375.807928 -224.603726)
			(xy 375.771318 -224.640336) (xy 375.729431 -224.670768) (xy 375.683299 -224.694274) (xy 375.634059 -224.710273)
			(xy 375.582921 -224.718372) (xy 375.531147 -224.718372) (xy 375.480009 -224.710273) (xy 375.430769 -224.694274)
			(xy 375.384637 -224.670768) (xy 375.34275 -224.640336) (xy 375.30614 -224.603726) (xy 375.275708 -224.561839)
			(xy 375.252202 -224.515707) (xy 375.236203 -224.466467) (xy 375.228104 -224.415329) (xy 375.227596 -224.389442)
			(xy 374.946672 -224.389442) (xy 374.946125 -224.417149) (xy 374.936941 -224.471796) (xy 374.928384 -224.498154)
			(xy 374.92051 -224.520252) (xy 375.125488 -224.87509) (xy 375.148348 -224.879408) (xy 375.173171 -224.884565)
			(xy 375.220951 -224.90152) (xy 375.265571 -224.925592) (xy 375.305978 -224.956214) (xy 375.341219 -224.992662)
			(xy 375.370463 -225.034077) (xy 375.393019 -225.079482) (xy 375.408356 -225.127806) (xy 375.416111 -225.177908)
			(xy 375.416572 -225.203258) (xy 375.416064 -225.229165) (xy 375.407958 -225.280342) (xy 375.391946 -225.329621)
			(xy 375.368423 -225.375788) (xy 375.337967 -225.417707) (xy 375.301329 -225.454345) (xy 375.25941 -225.484801)
			(xy 375.213243 -225.508324) (xy 375.163964 -225.524336) (xy 375.112787 -225.532442) (xy 375.060973 -225.532442)
			(xy 375.009796 -225.524336) (xy 374.960517 -225.508324) (xy 374.91435 -225.484801) (xy 374.872431 -225.454345)
			(xy 374.835793 -225.417707) (xy 374.805337 -225.375788) (xy 374.781814 -225.329621) (xy 374.765802 -225.280342)
			(xy 374.757696 -225.229165) (xy 374.757188 -225.203258) (xy 374.757797 -225.175541) (xy 374.76711 -225.120895)
			(xy 374.77573 -225.094546) (xy 374.783604 -225.072448) (xy 374.578626 -224.71761) (xy 374.555766 -224.713292)
			(xy 374.530948 -224.708169) (xy 374.483205 -224.691172) (xy 374.438626 -224.667071) (xy 374.39826 -224.636431)
			(xy 374.363057 -224.599976) (xy 374.333848 -224.558564) (xy 374.311319 -224.51317) (xy 374.296001 -224.464863)
			(xy 374.288255 -224.414781) (xy 374.287796 -224.389442) (xy 374.006872 -224.389442) (xy 374.006364 -224.415329)
			(xy 373.998265 -224.466467) (xy 373.982266 -224.515707) (xy 373.95876 -224.561839) (xy 373.928328 -224.603726)
			(xy 373.891718 -224.640336) (xy 373.849831 -224.670768) (xy 373.803699 -224.694274) (xy 373.754459 -224.710273)
			(xy 373.703321 -224.718372) (xy 373.651547 -224.718372) (xy 373.600409 -224.710273) (xy 373.551169 -224.694274)
			(xy 373.505037 -224.670768) (xy 373.46315 -224.640336) (xy 373.42654 -224.603726) (xy 373.396108 -224.561839)
			(xy 373.372602 -224.515707) (xy 373.356603 -224.466467) (xy 373.348504 -224.415329) (xy 373.347996 -224.389442)
			(xy 373.067072 -224.389442) (xy 373.066525 -224.417149) (xy 373.057341 -224.471796) (xy 373.048784 -224.498154)
			(xy 373.04091 -224.520252) (xy 373.245888 -224.87509) (xy 373.268748 -224.879408) (xy 373.293571 -224.884565)
			(xy 373.341351 -224.90152) (xy 373.385971 -224.925592) (xy 373.426378 -224.956214) (xy 373.461619 -224.992662)
			(xy 373.490863 -225.034077) (xy 373.513419 -225.079482) (xy 373.528756 -225.127806) (xy 373.536511 -225.177908)
			(xy 373.536972 -225.203258) (xy 373.536464 -225.229165) (xy 373.528358 -225.280342) (xy 373.512346 -225.329621)
			(xy 373.488823 -225.375788) (xy 373.458367 -225.417707) (xy 373.421729 -225.454345) (xy 373.37981 -225.484801)
			(xy 373.333643 -225.508324) (xy 373.284364 -225.524336) (xy 373.233187 -225.532442) (xy 373.181373 -225.532442)
			(xy 373.130196 -225.524336) (xy 373.080917 -225.508324) (xy 373.03475 -225.484801) (xy 372.992831 -225.454345)
			(xy 372.956193 -225.417707) (xy 372.925737 -225.375788) (xy 372.902214 -225.329621) (xy 372.886202 -225.280342)
			(xy 372.878096 -225.229165) (xy 372.877588 -225.203258) (xy 372.878197 -225.175541) (xy 372.88751 -225.120895)
			(xy 372.89613 -225.094546) (xy 372.904004 -225.072448) (xy 372.699026 -224.71761) (xy 372.676166 -224.713292)
			(xy 372.651348 -224.708169) (xy 372.603605 -224.691172) (xy 372.559026 -224.667071) (xy 372.51866 -224.636431)
			(xy 372.483457 -224.599976) (xy 372.454248 -224.558564) (xy 372.431719 -224.51317) (xy 372.416401 -224.464863)
			(xy 372.408655 -224.414781) (xy 372.408196 -224.389442) (xy 372.127272 -224.389442) (xy 372.126764 -224.415329)
			(xy 372.118665 -224.466467) (xy 372.102666 -224.515707) (xy 372.07916 -224.561839) (xy 372.048728 -224.603726)
			(xy 372.012118 -224.640336) (xy 371.970231 -224.670768) (xy 371.924099 -224.694274) (xy 371.874859 -224.710273)
			(xy 371.823721 -224.718372) (xy 371.771947 -224.718372) (xy 371.720809 -224.710273) (xy 371.671569 -224.694274)
			(xy 371.625437 -224.670768) (xy 371.58355 -224.640336) (xy 371.54694 -224.603726) (xy 371.516508 -224.561839)
			(xy 371.493002 -224.515707) (xy 371.477003 -224.466467) (xy 371.468904 -224.415329) (xy 371.468396 -224.389442)
			(xy 371.187472 -224.389442) (xy 371.186925 -224.417149) (xy 371.177741 -224.471796) (xy 371.169184 -224.498154)
			(xy 371.16131 -224.520252) (xy 371.366288 -224.87509) (xy 371.389148 -224.879408) (xy 371.413971 -224.884565)
			(xy 371.461751 -224.90152) (xy 371.506371 -224.925592) (xy 371.546778 -224.956214) (xy 371.582019 -224.992662)
			(xy 371.611263 -225.034077) (xy 371.633819 -225.079482) (xy 371.649156 -225.127806) (xy 371.656911 -225.177908)
			(xy 371.657372 -225.203258) (xy 371.656864 -225.229165) (xy 371.648758 -225.280342) (xy 371.632746 -225.329621)
			(xy 371.609223 -225.375788) (xy 371.578767 -225.417707) (xy 371.542129 -225.454345) (xy 371.50021 -225.484801)
			(xy 371.454043 -225.508324) (xy 371.404764 -225.524336) (xy 371.353587 -225.532442) (xy 371.301773 -225.532442)
			(xy 371.250596 -225.524336) (xy 371.201317 -225.508324) (xy 371.15515 -225.484801) (xy 371.113231 -225.454345)
			(xy 371.076593 -225.417707) (xy 371.046137 -225.375788) (xy 371.022614 -225.329621) (xy 371.006602 -225.280342)
			(xy 370.998496 -225.229165) (xy 370.997988 -225.203258) (xy 370.998597 -225.175541) (xy 371.00791 -225.120895)
			(xy 371.01653 -225.094546) (xy 371.024404 -225.072448) (xy 370.819426 -224.71761) (xy 370.796566 -224.713292)
			(xy 370.771748 -224.708169) (xy 370.724005 -224.691172) (xy 370.679426 -224.667071) (xy 370.63906 -224.636431)
			(xy 370.603857 -224.599976) (xy 370.574648 -224.558564) (xy 370.552119 -224.51317) (xy 370.536801 -224.464863)
			(xy 370.529055 -224.414781) (xy 370.528596 -224.389442) (xy 370.247672 -224.389442) (xy 370.247164 -224.415329)
			(xy 370.239065 -224.466467) (xy 370.223066 -224.515707) (xy 370.19956 -224.561839) (xy 370.169128 -224.603726)
			(xy 370.132518 -224.640336) (xy 370.090631 -224.670768) (xy 370.044499 -224.694274) (xy 369.995259 -224.710273)
			(xy 369.944121 -224.718372) (xy 369.892347 -224.718372) (xy 369.841209 -224.710273) (xy 369.791969 -224.694274)
			(xy 369.745837 -224.670768) (xy 369.70395 -224.640336) (xy 369.66734 -224.603726) (xy 369.636908 -224.561839)
			(xy 369.613402 -224.515707) (xy 369.597403 -224.466467) (xy 369.589304 -224.415329) (xy 369.588796 -224.389442)
			(xy 369.307872 -224.389442) (xy 369.307325 -224.417149) (xy 369.298141 -224.471796) (xy 369.289584 -224.498154)
			(xy 369.28171 -224.520252) (xy 369.486688 -224.87509) (xy 369.509548 -224.879408) (xy 369.534371 -224.884565)
			(xy 369.582151 -224.90152) (xy 369.626771 -224.925592) (xy 369.667178 -224.956214) (xy 369.702419 -224.992662)
			(xy 369.731663 -225.034077) (xy 369.754219 -225.079482) (xy 369.769556 -225.127806) (xy 369.777311 -225.177908)
			(xy 369.777772 -225.203258) (xy 369.777264 -225.229165) (xy 369.769158 -225.280342) (xy 369.753146 -225.329621)
			(xy 369.729623 -225.375788) (xy 369.699167 -225.417707) (xy 369.662529 -225.454345) (xy 369.62061 -225.484801)
			(xy 369.574443 -225.508324) (xy 369.525164 -225.524336) (xy 369.473987 -225.532442) (xy 369.422173 -225.532442)
			(xy 369.370996 -225.524336) (xy 369.321717 -225.508324) (xy 369.27555 -225.484801) (xy 369.233631 -225.454345)
			(xy 369.196993 -225.417707) (xy 369.166537 -225.375788) (xy 369.143014 -225.329621) (xy 369.127002 -225.280342)
			(xy 369.118896 -225.229165) (xy 369.118388 -225.203258) (xy 369.118997 -225.175541) (xy 369.12831 -225.120895)
			(xy 369.13693 -225.094546) (xy 369.144804 -225.072448) (xy 368.939826 -224.71761) (xy 368.916966 -224.713292)
			(xy 368.892148 -224.708169) (xy 368.844405 -224.691172) (xy 368.799826 -224.667071) (xy 368.75946 -224.636431)
			(xy 368.724257 -224.599976) (xy 368.695048 -224.558564) (xy 368.672519 -224.51317) (xy 368.657201 -224.464863)
			(xy 368.649455 -224.414781) (xy 368.648996 -224.389442) (xy 368.368072 -224.389442) (xy 368.367564 -224.415329)
			(xy 368.359465 -224.466467) (xy 368.343466 -224.515707) (xy 368.31996 -224.561839) (xy 368.289528 -224.603726)
			(xy 368.252918 -224.640336) (xy 368.211031 -224.670768) (xy 368.164899 -224.694274) (xy 368.115659 -224.710273)
			(xy 368.064521 -224.718372) (xy 368.012747 -224.718372) (xy 367.961609 -224.710273) (xy 367.912369 -224.694274)
			(xy 367.866237 -224.670768) (xy 367.82435 -224.640336) (xy 367.78774 -224.603726) (xy 367.757308 -224.561839)
			(xy 367.733802 -224.515707) (xy 367.717803 -224.466467) (xy 367.709704 -224.415329) (xy 367.709196 -224.389442)
			(xy 367.428272 -224.389442) (xy 367.427725 -224.417149) (xy 367.418541 -224.471796) (xy 367.409984 -224.498154)
			(xy 367.40211 -224.520252) (xy 367.607088 -224.87509) (xy 367.629948 -224.879408) (xy 367.654771 -224.884565)
			(xy 367.702551 -224.90152) (xy 367.747171 -224.925592) (xy 367.787578 -224.956214) (xy 367.822819 -224.992662)
			(xy 367.852063 -225.034077) (xy 367.874619 -225.079482) (xy 367.889956 -225.127806) (xy 367.897711 -225.177908)
			(xy 367.898172 -225.203258) (xy 367.897664 -225.229165) (xy 367.889558 -225.280342) (xy 367.873546 -225.329621)
			(xy 367.850023 -225.375788) (xy 367.819567 -225.417707) (xy 367.782929 -225.454345) (xy 367.74101 -225.484801)
			(xy 367.694843 -225.508324) (xy 367.645564 -225.524336) (xy 367.594387 -225.532442) (xy 367.542573 -225.532442)
			(xy 367.491396 -225.524336) (xy 367.442117 -225.508324) (xy 367.39595 -225.484801) (xy 367.354031 -225.454345)
			(xy 367.317393 -225.417707) (xy 367.286937 -225.375788) (xy 367.263414 -225.329621) (xy 367.247402 -225.280342)
			(xy 367.239296 -225.229165) (xy 367.238788 -225.203258) (xy 367.239397 -225.175541) (xy 367.24871 -225.120895)
			(xy 367.25733 -225.094546) (xy 367.265204 -225.072448) (xy 367.060226 -224.71761) (xy 367.037366 -224.713292)
			(xy 367.012548 -224.708169) (xy 366.964805 -224.691172) (xy 366.920226 -224.667071) (xy 366.87986 -224.636431)
			(xy 366.844657 -224.599976) (xy 366.815448 -224.558564) (xy 366.792919 -224.51317) (xy 366.777601 -224.464863)
			(xy 366.769855 -224.414781) (xy 366.769396 -224.389442) (xy 366.488472 -224.389442) (xy 366.487964 -224.415329)
			(xy 366.479865 -224.466467) (xy 366.463866 -224.515707) (xy 366.44036 -224.561839) (xy 366.409928 -224.603726)
			(xy 366.373318 -224.640336) (xy 366.331431 -224.670768) (xy 366.285299 -224.694274) (xy 366.236059 -224.710273)
			(xy 366.184921 -224.718372) (xy 366.133147 -224.718372) (xy 366.082009 -224.710273) (xy 366.032769 -224.694274)
			(xy 365.986637 -224.670768) (xy 365.94475 -224.640336) (xy 365.90814 -224.603726) (xy 365.877708 -224.561839)
			(xy 365.854202 -224.515707) (xy 365.838203 -224.466467) (xy 365.830104 -224.415329) (xy 365.829596 -224.389442)
			(xy 365.548672 -224.389442) (xy 365.548125 -224.417149) (xy 365.538941 -224.471796) (xy 365.530384 -224.498154)
			(xy 365.52251 -224.520252) (xy 365.727488 -224.87509) (xy 365.750348 -224.879408) (xy 365.775171 -224.884565)
			(xy 365.822951 -224.90152) (xy 365.867571 -224.925592) (xy 365.907978 -224.956214) (xy 365.943219 -224.992662)
			(xy 365.972463 -225.034077) (xy 365.995019 -225.079482) (xy 366.010356 -225.127806) (xy 366.018111 -225.177908)
			(xy 366.018572 -225.203258) (xy 366.018064 -225.229165) (xy 366.009958 -225.280342) (xy 365.993946 -225.329621)
			(xy 365.970423 -225.375788) (xy 365.939967 -225.417707) (xy 365.903329 -225.454345) (xy 365.86141 -225.484801)
			(xy 365.815243 -225.508324) (xy 365.765964 -225.524336) (xy 365.714787 -225.532442) (xy 365.662973 -225.532442)
			(xy 365.611796 -225.524336) (xy 365.562517 -225.508324) (xy 365.51635 -225.484801) (xy 365.474431 -225.454345)
			(xy 365.437793 -225.417707) (xy 365.407337 -225.375788) (xy 365.383814 -225.329621) (xy 365.367802 -225.280342)
			(xy 365.359696 -225.229165) (xy 365.359188 -225.203258) (xy 365.359797 -225.175541) (xy 365.36911 -225.120895)
			(xy 365.37773 -225.094546) (xy 365.385604 -225.072448) (xy 365.180626 -224.71761) (xy 365.157766 -224.713292)
			(xy 365.132948 -224.708169) (xy 365.085205 -224.691172) (xy 365.040626 -224.667071) (xy 365.00026 -224.636431)
			(xy 364.965057 -224.599976) (xy 364.935848 -224.558564) (xy 364.913319 -224.51317) (xy 364.898001 -224.464863)
			(xy 364.890255 -224.414781) (xy 364.889796 -224.389442) (xy 364.608872 -224.389442) (xy 364.608364 -224.415329)
			(xy 364.600265 -224.466467) (xy 364.584266 -224.515707) (xy 364.56076 -224.561839) (xy 364.530328 -224.603726)
			(xy 364.493718 -224.640336) (xy 364.451831 -224.670768) (xy 364.405699 -224.694274) (xy 364.356459 -224.710273)
			(xy 364.305321 -224.718372) (xy 364.253547 -224.718372) (xy 364.202409 -224.710273) (xy 364.153169 -224.694274)
			(xy 364.107037 -224.670768) (xy 364.06515 -224.640336) (xy 364.02854 -224.603726) (xy 363.998108 -224.561839)
			(xy 363.974602 -224.515707) (xy 363.958603 -224.466467) (xy 363.950504 -224.415329) (xy 363.949996 -224.389442)
			(xy 363.669072 -224.389442) (xy 363.668525 -224.417149) (xy 363.659341 -224.471796) (xy 363.650784 -224.498154)
			(xy 363.64291 -224.520252) (xy 363.847888 -224.87509) (xy 363.870748 -224.879408) (xy 363.895571 -224.884565)
			(xy 363.943351 -224.90152) (xy 363.987971 -224.925592) (xy 364.028378 -224.956214) (xy 364.063619 -224.992662)
			(xy 364.092863 -225.034077) (xy 364.115419 -225.079482) (xy 364.130756 -225.127806) (xy 364.138511 -225.177908)
			(xy 364.138972 -225.203258) (xy 364.138464 -225.229165) (xy 364.130358 -225.280342) (xy 364.114346 -225.329621)
			(xy 364.090823 -225.375788) (xy 364.060367 -225.417707) (xy 364.023729 -225.454345) (xy 363.98181 -225.484801)
			(xy 363.935643 -225.508324) (xy 363.886364 -225.524336) (xy 363.835187 -225.532442) (xy 363.783373 -225.532442)
			(xy 363.732196 -225.524336) (xy 363.682917 -225.508324) (xy 363.63675 -225.484801) (xy 363.594831 -225.454345)
			(xy 363.558193 -225.417707) (xy 363.527737 -225.375788) (xy 363.504214 -225.329621) (xy 363.488202 -225.280342)
			(xy 363.480096 -225.229165) (xy 363.479588 -225.203258) (xy 363.480197 -225.175541) (xy 363.48951 -225.120895)
			(xy 363.49813 -225.094546) (xy 363.506004 -225.072448) (xy 363.301026 -224.71761) (xy 363.278166 -224.713292)
			(xy 363.253348 -224.708169) (xy 363.205605 -224.691172) (xy 363.161026 -224.667071) (xy 363.12066 -224.636431)
			(xy 363.085457 -224.599976) (xy 363.056248 -224.558564) (xy 363.033719 -224.51317) (xy 363.018401 -224.464863)
			(xy 363.010655 -224.414781) (xy 363.010196 -224.389442) (xy 362.729272 -224.389442) (xy 362.728764 -224.415329)
			(xy 362.720665 -224.466467) (xy 362.704666 -224.515707) (xy 362.68116 -224.561839) (xy 362.650728 -224.603726)
			(xy 362.614118 -224.640336) (xy 362.572231 -224.670768) (xy 362.526099 -224.694274) (xy 362.476859 -224.710273)
			(xy 362.425721 -224.718372) (xy 362.373947 -224.718372) (xy 362.322809 -224.710273) (xy 362.273569 -224.694274)
			(xy 362.227437 -224.670768) (xy 362.18555 -224.640336) (xy 362.14894 -224.603726) (xy 362.118508 -224.561839)
			(xy 362.095002 -224.515707) (xy 362.079003 -224.466467) (xy 362.070904 -224.415329) (xy 362.070396 -224.389442)
			(xy 361.789472 -224.389442) (xy 361.788925 -224.417149) (xy 361.779741 -224.471796) (xy 361.771184 -224.498154)
			(xy 361.76331 -224.520252) (xy 361.968288 -224.87509) (xy 361.991148 -224.879408) (xy 362.015971 -224.884565)
			(xy 362.063751 -224.90152) (xy 362.108371 -224.925592) (xy 362.148778 -224.956214) (xy 362.184019 -224.992662)
			(xy 362.213263 -225.034077) (xy 362.235819 -225.079482) (xy 362.251156 -225.127806) (xy 362.258911 -225.177908)
			(xy 362.259372 -225.203258) (xy 362.258864 -225.229165) (xy 362.250758 -225.280342) (xy 362.234746 -225.329621)
			(xy 362.211223 -225.375788) (xy 362.180767 -225.417707) (xy 362.144129 -225.454345) (xy 362.10221 -225.484801)
			(xy 362.056043 -225.508324) (xy 362.006764 -225.524336) (xy 361.955587 -225.532442) (xy 361.903773 -225.532442)
			(xy 361.852596 -225.524336) (xy 361.803317 -225.508324) (xy 361.75715 -225.484801) (xy 361.715231 -225.454345)
			(xy 361.678593 -225.417707) (xy 361.648137 -225.375788) (xy 361.624614 -225.329621) (xy 361.608602 -225.280342)
			(xy 361.600496 -225.229165) (xy 361.599988 -225.203258) (xy 361.600597 -225.175541) (xy 361.60991 -225.120895)
			(xy 361.61853 -225.094546) (xy 361.626404 -225.072448) (xy 361.421426 -224.71761) (xy 361.398566 -224.713292)
			(xy 361.373748 -224.708169) (xy 361.326005 -224.691172) (xy 361.281426 -224.667071) (xy 361.24106 -224.636431)
			(xy 361.205857 -224.599976) (xy 361.176648 -224.558564) (xy 361.154119 -224.51317) (xy 361.138801 -224.464863)
			(xy 361.131055 -224.414781) (xy 361.130596 -224.389442) (xy 360.849672 -224.389442) (xy 360.849164 -224.415329)
			(xy 360.841065 -224.466467) (xy 360.825066 -224.515707) (xy 360.80156 -224.561839) (xy 360.771128 -224.603726)
			(xy 360.734518 -224.640336) (xy 360.692631 -224.670768) (xy 360.646499 -224.694274) (xy 360.597259 -224.710273)
			(xy 360.546121 -224.718372) (xy 360.494347 -224.718372) (xy 360.443209 -224.710273) (xy 360.393969 -224.694274)
			(xy 360.347837 -224.670768) (xy 360.30595 -224.640336) (xy 360.26934 -224.603726) (xy 360.238908 -224.561839)
			(xy 360.215402 -224.515707) (xy 360.199403 -224.466467) (xy 360.191304 -224.415329) (xy 360.190796 -224.389442)
			(xy 359.909872 -224.389442) (xy 359.909325 -224.417149) (xy 359.900141 -224.471796) (xy 359.891584 -224.498154)
			(xy 359.88371 -224.520252) (xy 360.088688 -224.87509) (xy 360.111548 -224.879408) (xy 360.136371 -224.884565)
			(xy 360.184151 -224.90152) (xy 360.228771 -224.925592) (xy 360.269178 -224.956214) (xy 360.304419 -224.992662)
			(xy 360.333663 -225.034077) (xy 360.356219 -225.079482) (xy 360.371556 -225.127806) (xy 360.379311 -225.177908)
			(xy 360.379772 -225.203258) (xy 360.379264 -225.229165) (xy 360.371158 -225.280342) (xy 360.355146 -225.329621)
			(xy 360.331623 -225.375788) (xy 360.301167 -225.417707) (xy 360.264529 -225.454345) (xy 360.22261 -225.484801)
			(xy 360.176443 -225.508324) (xy 360.127164 -225.524336) (xy 360.075987 -225.532442) (xy 360.024173 -225.532442)
			(xy 359.972996 -225.524336) (xy 359.923717 -225.508324) (xy 359.87755 -225.484801) (xy 359.835631 -225.454345)
			(xy 359.798993 -225.417707) (xy 359.768537 -225.375788) (xy 359.745014 -225.329621) (xy 359.729002 -225.280342)
			(xy 359.720896 -225.229165) (xy 359.720388 -225.203258) (xy 359.720997 -225.175541) (xy 359.73031 -225.120895)
			(xy 359.73893 -225.094546) (xy 359.746804 -225.072448) (xy 359.541826 -224.71761) (xy 359.518966 -224.713292)
			(xy 359.494148 -224.708169) (xy 359.446405 -224.691172) (xy 359.401826 -224.667071) (xy 359.36146 -224.636431)
			(xy 359.326257 -224.599976) (xy 359.297048 -224.558564) (xy 359.274519 -224.51317) (xy 359.259201 -224.464863)
			(xy 359.251455 -224.414781) (xy 359.250996 -224.389442) (xy 358.970072 -224.389442) (xy 358.969564 -224.415329)
			(xy 358.961465 -224.466467) (xy 358.945466 -224.515707) (xy 358.92196 -224.561839) (xy 358.891528 -224.603726)
			(xy 358.854918 -224.640336) (xy 358.813031 -224.670768) (xy 358.766899 -224.694274) (xy 358.717659 -224.710273)
			(xy 358.666521 -224.718372) (xy 358.614747 -224.718372) (xy 358.563609 -224.710273) (xy 358.514369 -224.694274)
			(xy 358.468237 -224.670768) (xy 358.42635 -224.640336) (xy 358.38974 -224.603726) (xy 358.359308 -224.561839)
			(xy 358.335802 -224.515707) (xy 358.319803 -224.466467) (xy 358.311704 -224.415329) (xy 358.311196 -224.389442)
			(xy 358.030272 -224.389442) (xy 358.029725 -224.417149) (xy 358.020541 -224.471796) (xy 358.011984 -224.498154)
			(xy 358.00411 -224.520252) (xy 358.209088 -224.87509) (xy 358.231948 -224.879408) (xy 358.256771 -224.884565)
			(xy 358.304551 -224.90152) (xy 358.349171 -224.925592) (xy 358.389578 -224.956214) (xy 358.424819 -224.992662)
			(xy 358.454063 -225.034077) (xy 358.476619 -225.079482) (xy 358.491956 -225.127806) (xy 358.499711 -225.177908)
			(xy 358.500172 -225.203258) (xy 358.499664 -225.229165) (xy 358.491558 -225.280342) (xy 358.475546 -225.329621)
			(xy 358.452023 -225.375788) (xy 358.421567 -225.417707) (xy 358.384929 -225.454345) (xy 358.34301 -225.484801)
			(xy 358.296843 -225.508324) (xy 358.247564 -225.524336) (xy 358.196387 -225.532442) (xy 358.144573 -225.532442)
			(xy 358.093396 -225.524336) (xy 358.044117 -225.508324) (xy 357.99795 -225.484801) (xy 357.956031 -225.454345)
			(xy 357.919393 -225.417707) (xy 357.888937 -225.375788) (xy 357.865414 -225.329621) (xy 357.849402 -225.280342)
			(xy 357.841296 -225.229165) (xy 357.840788 -225.203258) (xy 357.841397 -225.175541) (xy 357.85071 -225.120895)
			(xy 357.85933 -225.094546) (xy 357.867204 -225.072448) (xy 357.662226 -224.71761) (xy 357.639366 -224.713292)
			(xy 357.614548 -224.708169) (xy 357.566805 -224.691172) (xy 357.522226 -224.667071) (xy 357.48186 -224.636431)
			(xy 357.446657 -224.599976) (xy 357.417448 -224.558564) (xy 357.394919 -224.51317) (xy 357.379601 -224.464863)
			(xy 357.371855 -224.414781) (xy 357.371396 -224.389442) (xy 357.090472 -224.389442) (xy 357.089964 -224.415329)
			(xy 357.081865 -224.466467) (xy 357.065866 -224.515707) (xy 357.04236 -224.561839) (xy 357.011928 -224.603726)
			(xy 356.975318 -224.640336) (xy 356.933431 -224.670768) (xy 356.887299 -224.694274) (xy 356.838059 -224.710273)
			(xy 356.786921 -224.718372) (xy 356.735147 -224.718372) (xy 356.684009 -224.710273) (xy 356.634769 -224.694274)
			(xy 356.588637 -224.670768) (xy 356.54675 -224.640336) (xy 356.51014 -224.603726) (xy 356.479708 -224.561839)
			(xy 356.456202 -224.515707) (xy 356.440203 -224.466467) (xy 356.432104 -224.415329) (xy 356.431596 -224.389442)
			(xy 356.150672 -224.389442) (xy 356.150125 -224.417149) (xy 356.140941 -224.471796) (xy 356.132384 -224.498154)
			(xy 356.12451 -224.520252) (xy 356.329488 -224.87509) (xy 356.352348 -224.879408) (xy 356.377171 -224.884565)
			(xy 356.424951 -224.90152) (xy 356.469571 -224.925592) (xy 356.509978 -224.956214) (xy 356.545219 -224.992662)
			(xy 356.574463 -225.034077) (xy 356.597019 -225.079482) (xy 356.612356 -225.127806) (xy 356.620111 -225.177908)
			(xy 356.620572 -225.203258) (xy 356.620064 -225.229165) (xy 356.611958 -225.280342) (xy 356.595946 -225.329621)
			(xy 356.572423 -225.375788) (xy 356.541967 -225.417707) (xy 356.505329 -225.454345) (xy 356.46341 -225.484801)
			(xy 356.417243 -225.508324) (xy 356.367964 -225.524336) (xy 356.316787 -225.532442) (xy 356.264973 -225.532442)
			(xy 356.213796 -225.524336) (xy 356.164517 -225.508324) (xy 356.11835 -225.484801) (xy 356.076431 -225.454345)
			(xy 356.039793 -225.417707) (xy 356.009337 -225.375788) (xy 355.985814 -225.329621) (xy 355.969802 -225.280342)
			(xy 355.961696 -225.229165) (xy 355.961188 -225.203258) (xy 355.961797 -225.175541) (xy 355.97111 -225.120895)
			(xy 355.97973 -225.094546) (xy 355.987604 -225.072448) (xy 355.782626 -224.71761) (xy 355.759766 -224.713292)
			(xy 355.734948 -224.708169) (xy 355.687205 -224.691172) (xy 355.642626 -224.667071) (xy 355.60226 -224.636431)
			(xy 355.567057 -224.599976) (xy 355.537848 -224.558564) (xy 355.515319 -224.51317) (xy 355.500001 -224.464863)
			(xy 355.492255 -224.414781) (xy 355.491796 -224.389442) (xy 355.210872 -224.389442) (xy 355.210364 -224.415329)
			(xy 355.202265 -224.466467) (xy 355.186266 -224.515707) (xy 355.16276 -224.561839) (xy 355.132328 -224.603726)
			(xy 355.095718 -224.640336) (xy 355.053831 -224.670768) (xy 355.007699 -224.694274) (xy 354.958459 -224.710273)
			(xy 354.907321 -224.718372) (xy 354.855547 -224.718372) (xy 354.804409 -224.710273) (xy 354.755169 -224.694274)
			(xy 354.709037 -224.670768) (xy 354.66715 -224.640336) (xy 354.63054 -224.603726) (xy 354.600108 -224.561839)
			(xy 354.576602 -224.515707) (xy 354.560603 -224.466467) (xy 354.552504 -224.415329) (xy 354.551996 -224.389442)
			(xy 354.271072 -224.389442) (xy 354.270525 -224.417149) (xy 354.261341 -224.471796) (xy 354.252784 -224.498154)
			(xy 354.24491 -224.520252) (xy 354.449888 -224.87509) (xy 354.472748 -224.879408) (xy 354.497571 -224.884565)
			(xy 354.545351 -224.90152) (xy 354.589971 -224.925592) (xy 354.630378 -224.956214) (xy 354.665619 -224.992662)
			(xy 354.694863 -225.034077) (xy 354.717419 -225.079482) (xy 354.732756 -225.127806) (xy 354.740511 -225.177908)
			(xy 354.740972 -225.203258) (xy 354.740464 -225.229165) (xy 354.732358 -225.280342) (xy 354.716346 -225.329621)
			(xy 354.692823 -225.375788) (xy 354.662367 -225.417707) (xy 354.625729 -225.454345) (xy 354.58381 -225.484801)
			(xy 354.537643 -225.508324) (xy 354.488364 -225.524336) (xy 354.437187 -225.532442) (xy 354.385373 -225.532442)
			(xy 354.334196 -225.524336) (xy 354.284917 -225.508324) (xy 354.23875 -225.484801) (xy 354.196831 -225.454345)
			(xy 354.160193 -225.417707) (xy 354.129737 -225.375788) (xy 354.106214 -225.329621) (xy 354.090202 -225.280342)
			(xy 354.082096 -225.229165) (xy 354.081588 -225.203258) (xy 354.082197 -225.175541) (xy 354.09151 -225.120895)
			(xy 354.10013 -225.094546) (xy 354.108004 -225.072448) (xy 353.903026 -224.71761) (xy 353.880166 -224.713292)
			(xy 353.855348 -224.708169) (xy 353.807605 -224.691172) (xy 353.763026 -224.667071) (xy 353.72266 -224.636431)
			(xy 353.687457 -224.599976) (xy 353.658248 -224.558564) (xy 353.635719 -224.51317) (xy 353.620401 -224.464863)
			(xy 353.612655 -224.414781) (xy 353.612196 -224.389442) (xy 353.331272 -224.389442) (xy 353.330764 -224.415329)
			(xy 353.322665 -224.466467) (xy 353.306666 -224.515707) (xy 353.28316 -224.561839) (xy 353.252728 -224.603726)
			(xy 353.216118 -224.640336) (xy 353.174231 -224.670768) (xy 353.128099 -224.694274) (xy 353.078859 -224.710273)
			(xy 353.027721 -224.718372) (xy 352.975947 -224.718372) (xy 352.924809 -224.710273) (xy 352.875569 -224.694274)
			(xy 352.829437 -224.670768) (xy 352.78755 -224.640336) (xy 352.75094 -224.603726) (xy 352.720508 -224.561839)
			(xy 352.697002 -224.515707) (xy 352.681003 -224.466467) (xy 352.672904 -224.415329) (xy 352.672396 -224.389442)
			(xy 352.391472 -224.389442) (xy 352.390925 -224.417149) (xy 352.381741 -224.471796) (xy 352.373184 -224.498154)
			(xy 352.36531 -224.520252) (xy 352.570288 -224.87509) (xy 352.593148 -224.879408) (xy 352.617971 -224.884565)
			(xy 352.665751 -224.90152) (xy 352.710371 -224.925592) (xy 352.750778 -224.956214) (xy 352.786019 -224.992662)
			(xy 352.815263 -225.034077) (xy 352.837819 -225.079482) (xy 352.853156 -225.127806) (xy 352.860911 -225.177908)
			(xy 352.861372 -225.203258) (xy 352.860864 -225.229165) (xy 352.852758 -225.280342) (xy 352.836746 -225.329621)
			(xy 352.813223 -225.375788) (xy 352.782767 -225.417707) (xy 352.746129 -225.454345) (xy 352.70421 -225.484801)
			(xy 352.658043 -225.508324) (xy 352.608764 -225.524336) (xy 352.557587 -225.532442) (xy 352.505773 -225.532442)
			(xy 352.454596 -225.524336) (xy 352.405317 -225.508324) (xy 352.35915 -225.484801) (xy 352.317231 -225.454345)
			(xy 352.280593 -225.417707) (xy 352.250137 -225.375788) (xy 352.226614 -225.329621) (xy 352.210602 -225.280342)
			(xy 352.202496 -225.229165) (xy 352.201988 -225.203258) (xy 352.202597 -225.175541) (xy 352.21191 -225.120895)
			(xy 352.22053 -225.094546) (xy 352.228404 -225.072448) (xy 352.023426 -224.71761) (xy 352.000566 -224.713292)
			(xy 351.975748 -224.708169) (xy 351.928005 -224.691172) (xy 351.883426 -224.667071) (xy 351.84306 -224.636431)
			(xy 351.807857 -224.599976) (xy 351.778648 -224.558564) (xy 351.756119 -224.51317) (xy 351.740801 -224.464863)
			(xy 351.733055 -224.414781) (xy 351.732596 -224.389442) (xy 351.451672 -224.389442) (xy 351.451164 -224.415329)
			(xy 351.443065 -224.466467) (xy 351.427066 -224.515707) (xy 351.40356 -224.561839) (xy 351.373128 -224.603726)
			(xy 351.336518 -224.640336) (xy 351.294631 -224.670768) (xy 351.248499 -224.694274) (xy 351.199259 -224.710273)
			(xy 351.148121 -224.718372) (xy 351.096347 -224.718372) (xy 351.045209 -224.710273) (xy 350.995969 -224.694274)
			(xy 350.949837 -224.670768) (xy 350.90795 -224.640336) (xy 350.87134 -224.603726) (xy 350.840908 -224.561839)
			(xy 350.817402 -224.515707) (xy 350.801403 -224.466467) (xy 350.793304 -224.415329) (xy 350.792796 -224.389442)
			(xy 350.511872 -224.389442) (xy 350.511325 -224.417149) (xy 350.502141 -224.471796) (xy 350.493584 -224.498154)
			(xy 350.48571 -224.520252) (xy 350.690688 -224.87509) (xy 350.713548 -224.879408) (xy 350.738371 -224.884565)
			(xy 350.786151 -224.90152) (xy 350.830771 -224.925592) (xy 350.871178 -224.956214) (xy 350.906419 -224.992662)
			(xy 350.935663 -225.034077) (xy 350.958219 -225.079482) (xy 350.973556 -225.127806) (xy 350.981311 -225.177908)
			(xy 350.981772 -225.203258) (xy 350.981264 -225.229165) (xy 350.973158 -225.280342) (xy 350.957146 -225.329621)
			(xy 350.933623 -225.375788) (xy 350.903167 -225.417707) (xy 350.866529 -225.454345) (xy 350.82461 -225.484801)
			(xy 350.778443 -225.508324) (xy 350.729164 -225.524336) (xy 350.677987 -225.532442) (xy 350.626173 -225.532442)
			(xy 350.574996 -225.524336) (xy 350.525717 -225.508324) (xy 350.47955 -225.484801) (xy 350.437631 -225.454345)
			(xy 350.400993 -225.417707) (xy 350.370537 -225.375788) (xy 350.347014 -225.329621) (xy 350.331002 -225.280342)
			(xy 350.322896 -225.229165) (xy 350.322388 -225.203258) (xy 350.322997 -225.175541) (xy 350.33231 -225.120895)
			(xy 350.34093 -225.094546) (xy 350.348804 -225.072448) (xy 350.143826 -224.71761) (xy 350.120966 -224.713292)
			(xy 350.096148 -224.708169) (xy 350.048405 -224.691172) (xy 350.003826 -224.667071) (xy 349.96346 -224.636431)
			(xy 349.928257 -224.599976) (xy 349.899048 -224.558564) (xy 349.876519 -224.51317) (xy 349.861201 -224.464863)
			(xy 349.853455 -224.414781) (xy 349.852996 -224.389442) (xy 349.572072 -224.389442) (xy 349.571564 -224.415329)
			(xy 349.563465 -224.466467) (xy 349.547466 -224.515707) (xy 349.52396 -224.561839) (xy 349.493528 -224.603726)
			(xy 349.456918 -224.640336) (xy 349.415031 -224.670768) (xy 349.368899 -224.694274) (xy 349.319659 -224.710273)
			(xy 349.268521 -224.718372) (xy 349.216747 -224.718372) (xy 349.165609 -224.710273) (xy 349.116369 -224.694274)
			(xy 349.070237 -224.670768) (xy 349.02835 -224.640336) (xy 348.99174 -224.603726) (xy 348.961308 -224.561839)
			(xy 348.937802 -224.515707) (xy 348.921803 -224.466467) (xy 348.913704 -224.415329) (xy 348.913196 -224.389442)
			(xy 348.632272 -224.389442) (xy 348.631725 -224.417149) (xy 348.622541 -224.471796) (xy 348.613984 -224.498154)
			(xy 348.60611 -224.520252) (xy 348.811088 -224.87509) (xy 348.833948 -224.879408) (xy 348.858771 -224.884565)
			(xy 348.906551 -224.90152) (xy 348.951171 -224.925592) (xy 348.991578 -224.956214) (xy 349.026819 -224.992662)
			(xy 349.056063 -225.034077) (xy 349.078619 -225.079482) (xy 349.093956 -225.127806) (xy 349.101711 -225.177908)
			(xy 349.102172 -225.203258) (xy 349.101664 -225.229165) (xy 349.093558 -225.280342) (xy 349.077546 -225.329621)
			(xy 349.054023 -225.375788) (xy 349.023567 -225.417707) (xy 348.986929 -225.454345) (xy 348.94501 -225.484801)
			(xy 348.898843 -225.508324) (xy 348.849564 -225.524336) (xy 348.798387 -225.532442) (xy 348.746573 -225.532442)
			(xy 348.695396 -225.524336) (xy 348.646117 -225.508324) (xy 348.59995 -225.484801) (xy 348.558031 -225.454345)
			(xy 348.521393 -225.417707) (xy 348.490937 -225.375788) (xy 348.467414 -225.329621) (xy 348.451402 -225.280342)
			(xy 348.443296 -225.229165) (xy 348.442788 -225.203258) (xy 348.443397 -225.175541) (xy 348.45271 -225.120895)
			(xy 348.46133 -225.094546) (xy 348.469204 -225.072448) (xy 348.264226 -224.71761) (xy 348.241366 -224.713292)
			(xy 348.216548 -224.708169) (xy 348.168805 -224.691172) (xy 348.124226 -224.667071) (xy 348.08386 -224.636431)
			(xy 348.048657 -224.599976) (xy 348.019448 -224.558564) (xy 347.996919 -224.51317) (xy 347.981601 -224.464863)
			(xy 347.973855 -224.414781) (xy 347.973396 -224.389442) (xy 347.692472 -224.389442) (xy 347.691964 -224.415329)
			(xy 347.683865 -224.466467) (xy 347.667866 -224.515707) (xy 347.64436 -224.561839) (xy 347.613928 -224.603726)
			(xy 347.577318 -224.640336) (xy 347.535431 -224.670768) (xy 347.489299 -224.694274) (xy 347.440059 -224.710273)
			(xy 347.388921 -224.718372) (xy 347.337147 -224.718372) (xy 347.286009 -224.710273) (xy 347.236769 -224.694274)
			(xy 347.190637 -224.670768) (xy 347.14875 -224.640336) (xy 347.11214 -224.603726) (xy 347.081708 -224.561839)
			(xy 347.058202 -224.515707) (xy 347.042203 -224.466467) (xy 347.034104 -224.415329) (xy 347.033596 -224.389442)
			(xy 346.752672 -224.389442) (xy 346.752125 -224.417149) (xy 346.742941 -224.471796) (xy 346.734384 -224.498154)
			(xy 346.72651 -224.520252) (xy 346.931488 -224.87509) (xy 346.954348 -224.879408) (xy 346.979171 -224.884565)
			(xy 347.026951 -224.90152) (xy 347.071571 -224.925592) (xy 347.111978 -224.956214) (xy 347.147219 -224.992662)
			(xy 347.176463 -225.034077) (xy 347.199019 -225.079482) (xy 347.214356 -225.127806) (xy 347.222111 -225.177908)
			(xy 347.222572 -225.203258) (xy 347.222064 -225.229165) (xy 347.213958 -225.280342) (xy 347.197946 -225.329621)
			(xy 347.174423 -225.375788) (xy 347.143967 -225.417707) (xy 347.107329 -225.454345) (xy 347.06541 -225.484801)
			(xy 347.019243 -225.508324) (xy 346.969964 -225.524336) (xy 346.918787 -225.532442) (xy 346.866973 -225.532442)
			(xy 346.815796 -225.524336) (xy 346.766517 -225.508324) (xy 346.72035 -225.484801) (xy 346.678431 -225.454345)
			(xy 346.641793 -225.417707) (xy 346.611337 -225.375788) (xy 346.587814 -225.329621) (xy 346.571802 -225.280342)
			(xy 346.563696 -225.229165) (xy 346.563188 -225.203258) (xy 346.563797 -225.175541) (xy 346.57311 -225.120895)
			(xy 346.58173 -225.094546) (xy 346.589604 -225.072448) (xy 346.384626 -224.71761) (xy 346.361766 -224.713292)
			(xy 346.336948 -224.708169) (xy 346.289205 -224.691172) (xy 346.244626 -224.667071) (xy 346.20426 -224.636431)
			(xy 346.169057 -224.599976) (xy 346.139848 -224.558564) (xy 346.117319 -224.51317) (xy 346.102001 -224.464863)
			(xy 346.094255 -224.414781) (xy 346.093796 -224.389442) (xy 345.812872 -224.389442) (xy 345.812364 -224.415329)
			(xy 345.804265 -224.466467) (xy 345.788266 -224.515707) (xy 345.76476 -224.561839) (xy 345.734328 -224.603726)
			(xy 345.697718 -224.640336) (xy 345.655831 -224.670768) (xy 345.609699 -224.694274) (xy 345.560459 -224.710273)
			(xy 345.509321 -224.718372) (xy 345.457547 -224.718372) (xy 345.406409 -224.710273) (xy 345.357169 -224.694274)
			(xy 345.311037 -224.670768) (xy 345.26915 -224.640336) (xy 345.23254 -224.603726) (xy 345.202108 -224.561839)
			(xy 345.178602 -224.515707) (xy 345.162603 -224.466467) (xy 345.154504 -224.415329) (xy 345.153996 -224.389442)
			(xy 344.873072 -224.389442) (xy 344.872525 -224.417149) (xy 344.863341 -224.471796) (xy 344.854784 -224.498154)
			(xy 344.84691 -224.520252) (xy 345.051888 -224.87509) (xy 345.074748 -224.879408) (xy 345.099571 -224.884565)
			(xy 345.147351 -224.90152) (xy 345.191971 -224.925592) (xy 345.232378 -224.956214) (xy 345.267619 -224.992662)
			(xy 345.296863 -225.034077) (xy 345.319419 -225.079482) (xy 345.334756 -225.127806) (xy 345.342511 -225.177908)
			(xy 345.342972 -225.203258) (xy 345.342464 -225.229165) (xy 345.334358 -225.280342) (xy 345.318346 -225.329621)
			(xy 345.294823 -225.375788) (xy 345.264367 -225.417707) (xy 345.227729 -225.454345) (xy 345.18581 -225.484801)
			(xy 345.139643 -225.508324) (xy 345.090364 -225.524336) (xy 345.039187 -225.532442) (xy 344.987373 -225.532442)
			(xy 344.936196 -225.524336) (xy 344.886917 -225.508324) (xy 344.84075 -225.484801) (xy 344.798831 -225.454345)
			(xy 344.762193 -225.417707) (xy 344.731737 -225.375788) (xy 344.708214 -225.329621) (xy 344.692202 -225.280342)
			(xy 344.684096 -225.229165) (xy 344.683588 -225.203258) (xy 344.684197 -225.175541) (xy 344.69351 -225.120895)
			(xy 344.70213 -225.094546) (xy 344.710004 -225.072448) (xy 344.505026 -224.71761) (xy 344.482166 -224.713292)
			(xy 344.457348 -224.708169) (xy 344.409605 -224.691172) (xy 344.365026 -224.667071) (xy 344.32466 -224.636431)
			(xy 344.289457 -224.599976) (xy 344.260248 -224.558564) (xy 344.237719 -224.51317) (xy 344.222401 -224.464863)
			(xy 344.214655 -224.414781) (xy 344.214196 -224.389442) (xy 343.933272 -224.389442) (xy 343.932764 -224.415329)
			(xy 343.924665 -224.466467) (xy 343.908666 -224.515707) (xy 343.88516 -224.561839) (xy 343.854728 -224.603726)
			(xy 343.818118 -224.640336) (xy 343.776231 -224.670768) (xy 343.730099 -224.694274) (xy 343.680859 -224.710273)
			(xy 343.629721 -224.718372) (xy 343.577947 -224.718372) (xy 343.526809 -224.710273) (xy 343.477569 -224.694274)
			(xy 343.431437 -224.670768) (xy 343.38955 -224.640336) (xy 343.35294 -224.603726) (xy 343.322508 -224.561839)
			(xy 343.299002 -224.515707) (xy 343.283003 -224.466467) (xy 343.274904 -224.415329) (xy 343.274396 -224.389442)
			(xy 342.993472 -224.389442) (xy 342.992925 -224.417149) (xy 342.983741 -224.471796) (xy 342.975184 -224.498154)
			(xy 342.96731 -224.520252) (xy 343.172288 -224.87509) (xy 343.195148 -224.879408) (xy 343.219971 -224.884565)
			(xy 343.267751 -224.90152) (xy 343.312371 -224.925592) (xy 343.352778 -224.956214) (xy 343.388019 -224.992662)
			(xy 343.417263 -225.034077) (xy 343.439819 -225.079482) (xy 343.455156 -225.127806) (xy 343.462911 -225.177908)
			(xy 343.463372 -225.203258) (xy 343.462864 -225.229165) (xy 343.454758 -225.280342) (xy 343.438746 -225.329621)
			(xy 343.415223 -225.375788) (xy 343.384767 -225.417707) (xy 343.348129 -225.454345) (xy 343.30621 -225.484801)
			(xy 343.260043 -225.508324) (xy 343.210764 -225.524336) (xy 343.159587 -225.532442) (xy 343.107773 -225.532442)
			(xy 343.056596 -225.524336) (xy 343.007317 -225.508324) (xy 342.96115 -225.484801) (xy 342.919231 -225.454345)
			(xy 342.882593 -225.417707) (xy 342.852137 -225.375788) (xy 342.828614 -225.329621) (xy 342.812602 -225.280342)
			(xy 342.804496 -225.229165) (xy 342.803988 -225.203258) (xy 342.804597 -225.175541) (xy 342.81391 -225.120895)
			(xy 342.82253 -225.094546) (xy 342.830404 -225.072448) (xy 342.625426 -224.71761) (xy 342.602566 -224.713292)
			(xy 342.577748 -224.708169) (xy 342.530005 -224.691172) (xy 342.485426 -224.667071) (xy 342.44506 -224.636431)
			(xy 342.409857 -224.599976) (xy 342.380648 -224.558564) (xy 342.358119 -224.51317) (xy 342.342801 -224.464863)
			(xy 342.335055 -224.414781) (xy 342.334596 -224.389442) (xy 342.053672 -224.389442) (xy 342.053164 -224.415329)
			(xy 342.045065 -224.466467) (xy 342.029066 -224.515707) (xy 342.00556 -224.561839) (xy 341.975128 -224.603726)
			(xy 341.938518 -224.640336) (xy 341.896631 -224.670768) (xy 341.850499 -224.694274) (xy 341.801259 -224.710273)
			(xy 341.750121 -224.718372) (xy 341.698347 -224.718372) (xy 341.647209 -224.710273) (xy 341.597969 -224.694274)
			(xy 341.551837 -224.670768) (xy 341.50995 -224.640336) (xy 341.47334 -224.603726) (xy 341.442908 -224.561839)
			(xy 341.419402 -224.515707) (xy 341.403403 -224.466467) (xy 341.395304 -224.415329) (xy 341.394796 -224.389442)
			(xy 341.113872 -224.389442) (xy 341.113872 -224.38995) (xy 341.113311 -224.417593) (xy 341.104122 -224.472111)
			(xy 341.095584 -224.498408) (xy 341.087964 -224.520252) (xy 341.292688 -224.87509) (xy 341.315548 -224.879408)
			(xy 341.340371 -224.884565) (xy 341.388151 -224.90152) (xy 341.432771 -224.925592) (xy 341.473178 -224.956214)
			(xy 341.508419 -224.992662) (xy 341.537663 -225.034077) (xy 341.560219 -225.079482) (xy 341.575556 -225.127806)
			(xy 341.583311 -225.177908) (xy 341.583772 -225.203258) (xy 341.583264 -225.229165) (xy 341.575158 -225.280342)
			(xy 341.559146 -225.329621) (xy 341.535623 -225.375788) (xy 341.505167 -225.417707) (xy 341.468529 -225.454345)
			(xy 341.42661 -225.484801) (xy 341.380443 -225.508324) (xy 341.331164 -225.524336) (xy 341.279987 -225.532442)
			(xy 341.228173 -225.532442) (xy 341.176996 -225.524336) (xy 341.127717 -225.508324) (xy 341.08155 -225.484801)
			(xy 341.039631 -225.454345) (xy 341.002993 -225.417707) (xy 340.972537 -225.375788) (xy 340.949014 -225.329621)
			(xy 340.933002 -225.280342) (xy 340.924896 -225.229165) (xy 340.924388 -225.203258) (xy 340.924388 -225.20275)
			(xy 340.924995 -225.175096) (xy 340.93432 -225.120578) (xy 340.94293 -225.094292) (xy 340.95055 -225.072448)
			(xy 340.745826 -224.71761) (xy 340.722966 -224.713292) (xy 340.698148 -224.708169) (xy 340.650405 -224.691172)
			(xy 340.605826 -224.667071) (xy 340.56546 -224.636431) (xy 340.530257 -224.599976) (xy 340.501048 -224.558564)
			(xy 340.478519 -224.51317) (xy 340.463201 -224.464863) (xy 340.455455 -224.414781) (xy 340.454996 -224.389442)
			(xy 340.174072 -224.389442) (xy 340.173564 -224.415329) (xy 340.165465 -224.466467) (xy 340.149466 -224.515707)
			(xy 340.12596 -224.561839) (xy 340.095528 -224.603726) (xy 340.058918 -224.640336) (xy 340.017031 -224.670768)
			(xy 339.970899 -224.694274) (xy 339.921659 -224.710273) (xy 339.870521 -224.718372) (xy 339.818747 -224.718372)
			(xy 339.767609 -224.710273) (xy 339.718369 -224.694274) (xy 339.672237 -224.670768) (xy 339.63035 -224.640336)
			(xy 339.59374 -224.603726) (xy 339.563308 -224.561839) (xy 339.539802 -224.515707) (xy 339.523803 -224.466467)
			(xy 339.515704 -224.415329) (xy 339.515196 -224.389442) (xy 339.234272 -224.389442) (xy 339.234272 -224.38995)
			(xy 339.233711 -224.417593) (xy 339.224522 -224.472111) (xy 339.215984 -224.498408) (xy 339.208364 -224.520252)
			(xy 339.413088 -224.87509) (xy 339.435948 -224.879408) (xy 339.460771 -224.884565) (xy 339.508551 -224.90152)
			(xy 339.553171 -224.925592) (xy 339.593578 -224.956214) (xy 339.628819 -224.992662) (xy 339.658063 -225.034077)
			(xy 339.680619 -225.079482) (xy 339.695956 -225.127806) (xy 339.703711 -225.177908) (xy 339.704172 -225.203258)
			(xy 339.703664 -225.229165) (xy 339.695558 -225.280342) (xy 339.679546 -225.329621) (xy 339.656023 -225.375788)
			(xy 339.625567 -225.417707) (xy 339.588929 -225.454345) (xy 339.54701 -225.484801) (xy 339.500843 -225.508324)
			(xy 339.451564 -225.524336) (xy 339.400387 -225.532442) (xy 339.348573 -225.532442) (xy 339.297396 -225.524336)
			(xy 339.248117 -225.508324) (xy 339.20195 -225.484801) (xy 339.160031 -225.454345) (xy 339.123393 -225.417707)
			(xy 339.092937 -225.375788) (xy 339.069414 -225.329621) (xy 339.053402 -225.280342) (xy 339.045296 -225.229165)
			(xy 339.044788 -225.203258) (xy 339.044788 -225.20275) (xy 339.045395 -225.175096) (xy 339.05472 -225.120578)
			(xy 339.06333 -225.094292) (xy 339.07095 -225.072448) (xy 338.866226 -224.71761) (xy 338.843366 -224.713292)
			(xy 338.818548 -224.708169) (xy 338.770805 -224.691172) (xy 338.726226 -224.667071) (xy 338.68586 -224.636431)
			(xy 338.650657 -224.599976) (xy 338.621448 -224.558564) (xy 338.598919 -224.51317) (xy 338.583601 -224.464863)
			(xy 338.575855 -224.414781) (xy 338.575396 -224.389442) (xy 338.294472 -224.389442) (xy 338.293964 -224.415329)
			(xy 338.285865 -224.466467) (xy 338.269866 -224.515707) (xy 338.24636 -224.561839) (xy 338.215928 -224.603726)
			(xy 338.179318 -224.640336) (xy 338.137431 -224.670768) (xy 338.091299 -224.694274) (xy 338.042059 -224.710273)
			(xy 337.990921 -224.718372) (xy 337.939147 -224.718372) (xy 337.888009 -224.710273) (xy 337.838769 -224.694274)
			(xy 337.792637 -224.670768) (xy 337.75075 -224.640336) (xy 337.71414 -224.603726) (xy 337.683708 -224.561839)
			(xy 337.660202 -224.515707) (xy 337.644203 -224.466467) (xy 337.636104 -224.415329) (xy 337.635596 -224.389442)
			(xy 132.645404 -224.389442) (xy 132.64486 -224.417149) (xy 132.635674 -224.471796) (xy 132.627116 -224.498154)
			(xy 132.619242 -224.520252) (xy 132.82422 -224.87509) (xy 132.84708 -224.879408) (xy 132.871909 -224.884542)
			(xy 132.919688 -224.901501) (xy 132.964308 -224.925578) (xy 133.004714 -224.956202) (xy 133.039954 -224.992654)
			(xy 133.069197 -225.034071) (xy 133.091752 -225.079478) (xy 133.107088 -225.127804) (xy 133.114843 -225.177908)
			(xy 133.115304 -225.203258) (xy 133.114796 -225.229165) (xy 133.10669 -225.280342) (xy 133.090678 -225.329621)
			(xy 133.067155 -225.375788) (xy 133.036699 -225.417707) (xy 133.000061 -225.454345) (xy 132.958142 -225.484801)
			(xy 132.911975 -225.508324) (xy 132.862696 -225.524336) (xy 132.811519 -225.532442) (xy 132.759705 -225.532442)
			(xy 132.708528 -225.524336) (xy 132.659249 -225.508324) (xy 132.613082 -225.484801) (xy 132.571163 -225.454345)
			(xy 132.534525 -225.417707) (xy 132.504069 -225.375788) (xy 132.480546 -225.329621) (xy 132.464534 -225.280342)
			(xy 132.456428 -225.229165) (xy 132.45592 -225.203258) (xy 132.456527 -225.175541) (xy 132.465842 -225.120895)
			(xy 132.474462 -225.094546) (xy 132.482336 -225.072448) (xy 132.277358 -224.71761) (xy 132.254498 -224.713292)
			(xy 132.229685 -224.708145) (xy 132.181943 -224.691153) (xy 132.137363 -224.667056) (xy 132.096996 -224.63642)
			(xy 132.061793 -224.599968) (xy 132.032582 -224.558558) (xy 132.010052 -224.513166) (xy 131.994734 -224.46486)
			(xy 131.986988 -224.41478) (xy 131.986528 -224.389442) (xy 130.765804 -224.389442) (xy 130.76526 -224.417149)
			(xy 130.756074 -224.471796) (xy 130.747516 -224.498154) (xy 130.739642 -224.520252) (xy 130.94462 -224.87509)
			(xy 130.96748 -224.879408) (xy 130.992309 -224.884542) (xy 131.040088 -224.901501) (xy 131.084708 -224.925578)
			(xy 131.125114 -224.956202) (xy 131.160354 -224.992654) (xy 131.189597 -225.034071) (xy 131.212152 -225.079478)
			(xy 131.227488 -225.127804) (xy 131.235243 -225.177908) (xy 131.235704 -225.203258) (xy 131.235196 -225.229165)
			(xy 131.22709 -225.280342) (xy 131.211078 -225.329621) (xy 131.187555 -225.375788) (xy 131.157099 -225.417707)
			(xy 131.120461 -225.454345) (xy 131.078542 -225.484801) (xy 131.032375 -225.508324) (xy 130.983096 -225.524336)
			(xy 130.931919 -225.532442) (xy 130.880105 -225.532442) (xy 130.828928 -225.524336) (xy 130.779649 -225.508324)
			(xy 130.733482 -225.484801) (xy 130.691563 -225.454345) (xy 130.654925 -225.417707) (xy 130.624469 -225.375788)
			(xy 130.600946 -225.329621) (xy 130.584934 -225.280342) (xy 130.576828 -225.229165) (xy 130.57632 -225.203258)
			(xy 130.576927 -225.175541) (xy 130.586242 -225.120895) (xy 130.594862 -225.094546) (xy 130.602736 -225.072448)
			(xy 130.397758 -224.71761) (xy 130.374898 -224.713292) (xy 130.350085 -224.708145) (xy 130.302343 -224.691153)
			(xy 130.257763 -224.667056) (xy 130.217396 -224.63642) (xy 130.182193 -224.599968) (xy 130.152982 -224.558558)
			(xy 130.130452 -224.513166) (xy 130.115134 -224.46486) (xy 130.107388 -224.41478) (xy 130.106928 -224.389442)
			(xy 129.826004 -224.389442) (xy 129.825496 -224.415329) (xy 129.817397 -224.466467) (xy 129.801398 -224.515707)
			(xy 129.777892 -224.561839) (xy 129.74746 -224.603726) (xy 129.71085 -224.640336) (xy 129.668963 -224.670768)
			(xy 129.622831 -224.694274) (xy 129.573591 -224.710273) (xy 129.522453 -224.718372) (xy 129.470679 -224.718372)
			(xy 129.419541 -224.710273) (xy 129.370301 -224.694274) (xy 129.324169 -224.670768) (xy 129.282282 -224.640336)
			(xy 129.245672 -224.603726) (xy 129.21524 -224.561839) (xy 129.191734 -224.515707) (xy 129.175735 -224.466467)
			(xy 129.167636 -224.415329) (xy 129.167128 -224.389442) (xy 128.886204 -224.389442) (xy 128.88566 -224.417149)
			(xy 128.876474 -224.471796) (xy 128.867916 -224.498154) (xy 128.860042 -224.520252) (xy 129.06502 -224.87509)
			(xy 129.08788 -224.879408) (xy 129.112709 -224.884542) (xy 129.160488 -224.901501) (xy 129.205108 -224.925578)
			(xy 129.245514 -224.956202) (xy 129.280754 -224.992654) (xy 129.309997 -225.034071) (xy 129.332552 -225.079478)
			(xy 129.347888 -225.127804) (xy 129.355643 -225.177908) (xy 129.356104 -225.203258) (xy 129.355596 -225.229165)
			(xy 129.34749 -225.280342) (xy 129.331478 -225.329621) (xy 129.307955 -225.375788) (xy 129.277499 -225.417707)
			(xy 129.240861 -225.454345) (xy 129.198942 -225.484801) (xy 129.152775 -225.508324) (xy 129.103496 -225.524336)
			(xy 129.052319 -225.532442) (xy 129.000505 -225.532442) (xy 128.949328 -225.524336) (xy 128.900049 -225.508324)
			(xy 128.853882 -225.484801) (xy 128.811963 -225.454345) (xy 128.775325 -225.417707) (xy 128.744869 -225.375788)
			(xy 128.721346 -225.329621) (xy 128.705334 -225.280342) (xy 128.697228 -225.229165) (xy 128.69672 -225.203258)
			(xy 128.697327 -225.175541) (xy 128.706642 -225.120895) (xy 128.715262 -225.094546) (xy 128.723136 -225.072448)
			(xy 128.518158 -224.71761) (xy 128.495298 -224.713292) (xy 128.470485 -224.708145) (xy 128.422743 -224.691153)
			(xy 128.378163 -224.667056) (xy 128.337796 -224.63642) (xy 128.302593 -224.599968) (xy 128.273382 -224.558558)
			(xy 128.250852 -224.513166) (xy 128.235534 -224.46486) (xy 128.227788 -224.41478) (xy 128.227328 -224.389442)
			(xy 127.946404 -224.389442) (xy 127.945896 -224.415329) (xy 127.937797 -224.466467) (xy 127.921798 -224.515707)
			(xy 127.898292 -224.561839) (xy 127.86786 -224.603726) (xy 127.83125 -224.640336) (xy 127.789363 -224.670768)
			(xy 127.743231 -224.694274) (xy 127.693991 -224.710273) (xy 127.642853 -224.718372) (xy 127.591079 -224.718372)
			(xy 127.539941 -224.710273) (xy 127.490701 -224.694274) (xy 127.444569 -224.670768) (xy 127.402682 -224.640336)
			(xy 127.366072 -224.603726) (xy 127.33564 -224.561839) (xy 127.312134 -224.515707) (xy 127.296135 -224.466467)
			(xy 127.288036 -224.415329) (xy 127.287528 -224.389442) (xy 127.006604 -224.389442) (xy 127.00606 -224.417149)
			(xy 126.996874 -224.471796) (xy 126.988316 -224.498154) (xy 126.980442 -224.520252) (xy 127.18542 -224.87509)
			(xy 127.20828 -224.879408) (xy 127.233109 -224.884542) (xy 127.280888 -224.901501) (xy 127.325508 -224.925578)
			(xy 127.365914 -224.956202) (xy 127.401154 -224.992654) (xy 127.430397 -225.034071) (xy 127.452952 -225.079478)
			(xy 127.468288 -225.127804) (xy 127.476043 -225.177908) (xy 127.476504 -225.203258) (xy 127.475996 -225.229165)
			(xy 127.46789 -225.280342) (xy 127.451878 -225.329621) (xy 127.428355 -225.375788) (xy 127.397899 -225.417707)
			(xy 127.361261 -225.454345) (xy 127.319342 -225.484801) (xy 127.273175 -225.508324) (xy 127.223896 -225.524336)
			(xy 127.172719 -225.532442) (xy 127.120905 -225.532442) (xy 127.069728 -225.524336) (xy 127.020449 -225.508324)
			(xy 126.974282 -225.484801) (xy 126.932363 -225.454345) (xy 126.895725 -225.417707) (xy 126.865269 -225.375788)
			(xy 126.841746 -225.329621) (xy 126.825734 -225.280342) (xy 126.817628 -225.229165) (xy 126.81712 -225.203258)
			(xy 126.817727 -225.175541) (xy 126.827042 -225.120895) (xy 126.835662 -225.094546) (xy 126.843536 -225.072448)
			(xy 126.638558 -224.71761) (xy 126.615698 -224.713292) (xy 126.590885 -224.708145) (xy 126.543143 -224.691153)
			(xy 126.498563 -224.667056) (xy 126.458196 -224.63642) (xy 126.422993 -224.599968) (xy 126.393782 -224.558558)
			(xy 126.371252 -224.513166) (xy 126.355934 -224.46486) (xy 126.348188 -224.41478) (xy 126.347728 -224.389442)
			(xy 126.066804 -224.389442) (xy 126.066296 -224.415329) (xy 126.058197 -224.466467) (xy 126.042198 -224.515707)
			(xy 126.018692 -224.561839) (xy 125.98826 -224.603726) (xy 125.95165 -224.640336) (xy 125.909763 -224.670768)
			(xy 125.863631 -224.694274) (xy 125.814391 -224.710273) (xy 125.763253 -224.718372) (xy 125.711479 -224.718372)
			(xy 125.660341 -224.710273) (xy 125.611101 -224.694274) (xy 125.564969 -224.670768) (xy 125.523082 -224.640336)
			(xy 125.486472 -224.603726) (xy 125.45604 -224.561839) (xy 125.432534 -224.515707) (xy 125.416535 -224.466467)
			(xy 125.408436 -224.415329) (xy 125.407928 -224.389442) (xy 125.127004 -224.389442) (xy 125.12646 -224.417149)
			(xy 125.117274 -224.471796) (xy 125.108716 -224.498154) (xy 125.100842 -224.520252) (xy 125.30582 -224.87509)
			(xy 125.32868 -224.879408) (xy 125.353509 -224.884542) (xy 125.401288 -224.901501) (xy 125.445908 -224.925578)
			(xy 125.486314 -224.956202) (xy 125.521554 -224.992654) (xy 125.550797 -225.034071) (xy 125.573352 -225.079478)
			(xy 125.588688 -225.127804) (xy 125.596443 -225.177908) (xy 125.596904 -225.203258) (xy 125.596396 -225.229165)
			(xy 125.58829 -225.280342) (xy 125.572278 -225.329621) (xy 125.548755 -225.375788) (xy 125.518299 -225.417707)
			(xy 125.481661 -225.454345) (xy 125.439742 -225.484801) (xy 125.393575 -225.508324) (xy 125.344296 -225.524336)
			(xy 125.293119 -225.532442) (xy 125.241305 -225.532442) (xy 125.190128 -225.524336) (xy 125.140849 -225.508324)
			(xy 125.094682 -225.484801) (xy 125.052763 -225.454345) (xy 125.016125 -225.417707) (xy 124.985669 -225.375788)
			(xy 124.962146 -225.329621) (xy 124.946134 -225.280342) (xy 124.938028 -225.229165) (xy 124.93752 -225.203258)
			(xy 124.938127 -225.175541) (xy 124.947442 -225.120895) (xy 124.956062 -225.094546) (xy 124.963936 -225.072448)
			(xy 124.758958 -224.71761) (xy 124.736098 -224.713292) (xy 124.711285 -224.708145) (xy 124.663543 -224.691153)
			(xy 124.618963 -224.667056) (xy 124.578596 -224.63642) (xy 124.543393 -224.599968) (xy 124.514182 -224.558558)
			(xy 124.491652 -224.513166) (xy 124.476334 -224.46486) (xy 124.468588 -224.41478) (xy 124.468128 -224.389442)
			(xy 124.187204 -224.389442) (xy 124.186696 -224.415329) (xy 124.178597 -224.466467) (xy 124.162598 -224.515707)
			(xy 124.139092 -224.561839) (xy 124.10866 -224.603726) (xy 124.07205 -224.640336) (xy 124.030163 -224.670768)
			(xy 123.984031 -224.694274) (xy 123.934791 -224.710273) (xy 123.883653 -224.718372) (xy 123.831879 -224.718372)
			(xy 123.780741 -224.710273) (xy 123.731501 -224.694274) (xy 123.685369 -224.670768) (xy 123.643482 -224.640336)
			(xy 123.606872 -224.603726) (xy 123.57644 -224.561839) (xy 123.552934 -224.515707) (xy 123.536935 -224.466467)
			(xy 123.528836 -224.415329) (xy 123.528328 -224.389442) (xy 123.247404 -224.389442) (xy 123.24686 -224.417149)
			(xy 123.237674 -224.471796) (xy 123.229116 -224.498154) (xy 123.221242 -224.520252) (xy 123.42622 -224.87509)
			(xy 123.44908 -224.879408) (xy 123.473909 -224.884542) (xy 123.521688 -224.901501) (xy 123.566308 -224.925578)
			(xy 123.606714 -224.956202) (xy 123.641954 -224.992654) (xy 123.671197 -225.034071) (xy 123.693752 -225.079478)
			(xy 123.709088 -225.127804) (xy 123.716843 -225.177908) (xy 123.717304 -225.203258) (xy 123.716796 -225.229165)
			(xy 123.70869 -225.280342) (xy 123.692678 -225.329621) (xy 123.669155 -225.375788) (xy 123.638699 -225.417707)
			(xy 123.602061 -225.454345) (xy 123.560142 -225.484801) (xy 123.513975 -225.508324) (xy 123.464696 -225.524336)
			(xy 123.413519 -225.532442) (xy 123.361705 -225.532442) (xy 123.310528 -225.524336) (xy 123.261249 -225.508324)
			(xy 123.215082 -225.484801) (xy 123.173163 -225.454345) (xy 123.136525 -225.417707) (xy 123.106069 -225.375788)
			(xy 123.082546 -225.329621) (xy 123.066534 -225.280342) (xy 123.058428 -225.229165) (xy 123.05792 -225.203258)
			(xy 123.058527 -225.175541) (xy 123.067842 -225.120895) (xy 123.076462 -225.094546) (xy 123.084336 -225.072448)
			(xy 122.879358 -224.71761) (xy 122.856498 -224.713292) (xy 122.831685 -224.708145) (xy 122.783943 -224.691153)
			(xy 122.739363 -224.667056) (xy 122.698996 -224.63642) (xy 122.663793 -224.599968) (xy 122.634582 -224.558558)
			(xy 122.612052 -224.513166) (xy 122.596734 -224.46486) (xy 122.588988 -224.41478) (xy 122.588528 -224.389442)
			(xy 122.307604 -224.389442) (xy 122.307096 -224.415329) (xy 122.298997 -224.466467) (xy 122.282998 -224.515707)
			(xy 122.259492 -224.561839) (xy 122.22906 -224.603726) (xy 122.19245 -224.640336) (xy 122.150563 -224.670768)
			(xy 122.104431 -224.694274) (xy 122.055191 -224.710273) (xy 122.004053 -224.718372) (xy 121.952279 -224.718372)
			(xy 121.901141 -224.710273) (xy 121.851901 -224.694274) (xy 121.805769 -224.670768) (xy 121.763882 -224.640336)
			(xy 121.727272 -224.603726) (xy 121.69684 -224.561839) (xy 121.673334 -224.515707) (xy 121.657335 -224.466467)
			(xy 121.649236 -224.415329) (xy 121.648728 -224.389442) (xy 121.367804 -224.389442) (xy 121.36726 -224.417149)
			(xy 121.358074 -224.471796) (xy 121.349516 -224.498154) (xy 121.341642 -224.520252) (xy 121.54662 -224.87509)
			(xy 121.56948 -224.879408) (xy 121.594309 -224.884542) (xy 121.642088 -224.901501) (xy 121.686708 -224.925578)
			(xy 121.727114 -224.956202) (xy 121.762354 -224.992654) (xy 121.791597 -225.034071) (xy 121.814152 -225.079478)
			(xy 121.829488 -225.127804) (xy 121.837243 -225.177908) (xy 121.837704 -225.203258) (xy 121.837196 -225.229165)
			(xy 121.82909 -225.280342) (xy 121.813078 -225.329621) (xy 121.789555 -225.375788) (xy 121.759099 -225.417707)
			(xy 121.722461 -225.454345) (xy 121.680542 -225.484801) (xy 121.634375 -225.508324) (xy 121.585096 -225.524336)
			(xy 121.533919 -225.532442) (xy 121.482105 -225.532442) (xy 121.430928 -225.524336) (xy 121.381649 -225.508324)
			(xy 121.335482 -225.484801) (xy 121.293563 -225.454345) (xy 121.256925 -225.417707) (xy 121.226469 -225.375788)
			(xy 121.202946 -225.329621) (xy 121.186934 -225.280342) (xy 121.178828 -225.229165) (xy 121.17832 -225.203258)
			(xy 121.178927 -225.175541) (xy 121.188242 -225.120895) (xy 121.196862 -225.094546) (xy 121.204736 -225.072448)
			(xy 120.999758 -224.71761) (xy 120.976898 -224.713292) (xy 120.952085 -224.708145) (xy 120.904343 -224.691153)
			(xy 120.859763 -224.667056) (xy 120.819396 -224.63642) (xy 120.784193 -224.599968) (xy 120.754982 -224.558558)
			(xy 120.732452 -224.513166) (xy 120.717134 -224.46486) (xy 120.709388 -224.41478) (xy 120.708928 -224.389442)
			(xy 120.428004 -224.389442) (xy 120.427496 -224.415329) (xy 120.419397 -224.466467) (xy 120.403398 -224.515707)
			(xy 120.379892 -224.561839) (xy 120.34946 -224.603726) (xy 120.31285 -224.640336) (xy 120.270963 -224.670768)
			(xy 120.224831 -224.694274) (xy 120.175591 -224.710273) (xy 120.124453 -224.718372) (xy 120.072679 -224.718372)
			(xy 120.021541 -224.710273) (xy 119.972301 -224.694274) (xy 119.926169 -224.670768) (xy 119.884282 -224.640336)
			(xy 119.847672 -224.603726) (xy 119.81724 -224.561839) (xy 119.793734 -224.515707) (xy 119.777735 -224.466467)
			(xy 119.769636 -224.415329) (xy 119.769128 -224.389442) (xy 119.488204 -224.389442) (xy 119.48766 -224.417149)
			(xy 119.478474 -224.471796) (xy 119.469916 -224.498154) (xy 119.462042 -224.520252) (xy 119.66702 -224.87509)
			(xy 119.68988 -224.879408) (xy 119.714709 -224.884542) (xy 119.762488 -224.901501) (xy 119.807108 -224.925578)
			(xy 119.847514 -224.956202) (xy 119.882754 -224.992654) (xy 119.911997 -225.034071) (xy 119.934552 -225.079478)
			(xy 119.949888 -225.127804) (xy 119.957643 -225.177908) (xy 119.958104 -225.203258) (xy 119.957596 -225.229165)
			(xy 119.94949 -225.280342) (xy 119.933478 -225.329621) (xy 119.909955 -225.375788) (xy 119.879499 -225.417707)
			(xy 119.842861 -225.454345) (xy 119.800942 -225.484801) (xy 119.754775 -225.508324) (xy 119.705496 -225.524336)
			(xy 119.654319 -225.532442) (xy 119.602505 -225.532442) (xy 119.551328 -225.524336) (xy 119.502049 -225.508324)
			(xy 119.455882 -225.484801) (xy 119.413963 -225.454345) (xy 119.377325 -225.417707) (xy 119.346869 -225.375788)
			(xy 119.323346 -225.329621) (xy 119.307334 -225.280342) (xy 119.299228 -225.229165) (xy 119.29872 -225.203258)
			(xy 119.299327 -225.175541) (xy 119.308642 -225.120895) (xy 119.317262 -225.094546) (xy 119.325136 -225.072448)
			(xy 119.120158 -224.71761) (xy 119.097298 -224.713292) (xy 119.072485 -224.708145) (xy 119.024743 -224.691153)
			(xy 118.980163 -224.667056) (xy 118.939796 -224.63642) (xy 118.904593 -224.599968) (xy 118.875382 -224.558558)
			(xy 118.852852 -224.513166) (xy 118.837534 -224.46486) (xy 118.829788 -224.41478) (xy 118.829328 -224.389442)
			(xy 118.548404 -224.389442) (xy 118.547896 -224.415329) (xy 118.539797 -224.466467) (xy 118.523798 -224.515707)
			(xy 118.500292 -224.561839) (xy 118.46986 -224.603726) (xy 118.43325 -224.640336) (xy 118.391363 -224.670768)
			(xy 118.345231 -224.694274) (xy 118.295991 -224.710273) (xy 118.244853 -224.718372) (xy 118.193079 -224.718372)
			(xy 118.141941 -224.710273) (xy 118.092701 -224.694274) (xy 118.046569 -224.670768) (xy 118.004682 -224.640336)
			(xy 117.968072 -224.603726) (xy 117.93764 -224.561839) (xy 117.914134 -224.515707) (xy 117.898135 -224.466467)
			(xy 117.890036 -224.415329) (xy 117.889528 -224.389442) (xy 117.608604 -224.389442) (xy 117.60806 -224.417149)
			(xy 117.598874 -224.471796) (xy 117.590316 -224.498154) (xy 117.582442 -224.520252) (xy 117.78742 -224.87509)
			(xy 117.81028 -224.879408) (xy 117.835109 -224.884542) (xy 117.882888 -224.901501) (xy 117.927508 -224.925578)
			(xy 117.967914 -224.956202) (xy 118.003154 -224.992654) (xy 118.032397 -225.034071) (xy 118.054952 -225.079478)
			(xy 118.070288 -225.127804) (xy 118.078043 -225.177908) (xy 118.078504 -225.203258) (xy 118.077996 -225.229165)
			(xy 118.06989 -225.280342) (xy 118.053878 -225.329621) (xy 118.030355 -225.375788) (xy 117.999899 -225.417707)
			(xy 117.963261 -225.454345) (xy 117.921342 -225.484801) (xy 117.875175 -225.508324) (xy 117.825896 -225.524336)
			(xy 117.774719 -225.532442) (xy 117.722905 -225.532442) (xy 117.671728 -225.524336) (xy 117.622449 -225.508324)
			(xy 117.576282 -225.484801) (xy 117.534363 -225.454345) (xy 117.497725 -225.417707) (xy 117.467269 -225.375788)
			(xy 117.443746 -225.329621) (xy 117.427734 -225.280342) (xy 117.419628 -225.229165) (xy 117.41912 -225.203258)
			(xy 117.419727 -225.175541) (xy 117.429042 -225.120895) (xy 117.437662 -225.094546) (xy 117.445536 -225.072448)
			(xy 117.240558 -224.71761) (xy 117.217698 -224.713292) (xy 117.192885 -224.708145) (xy 117.145143 -224.691153)
			(xy 117.100563 -224.667056) (xy 117.060196 -224.63642) (xy 117.024993 -224.599968) (xy 116.995782 -224.558558)
			(xy 116.973252 -224.513166) (xy 116.957934 -224.46486) (xy 116.950188 -224.41478) (xy 116.949728 -224.389442)
			(xy 116.668804 -224.389442) (xy 116.668296 -224.415329) (xy 116.660197 -224.466467) (xy 116.644198 -224.515707)
			(xy 116.620692 -224.561839) (xy 116.59026 -224.603726) (xy 116.55365 -224.640336) (xy 116.511763 -224.670768)
			(xy 116.465631 -224.694274) (xy 116.416391 -224.710273) (xy 116.365253 -224.718372) (xy 116.313479 -224.718372)
			(xy 116.262341 -224.710273) (xy 116.213101 -224.694274) (xy 116.166969 -224.670768) (xy 116.125082 -224.640336)
			(xy 116.088472 -224.603726) (xy 116.05804 -224.561839) (xy 116.034534 -224.515707) (xy 116.018535 -224.466467)
			(xy 116.010436 -224.415329) (xy 116.009928 -224.389442) (xy 115.729004 -224.389442) (xy 115.72846 -224.417149)
			(xy 115.719274 -224.471796) (xy 115.710716 -224.498154) (xy 115.702842 -224.520252) (xy 115.90782 -224.87509)
			(xy 115.93068 -224.879408) (xy 115.955509 -224.884542) (xy 116.003288 -224.901501) (xy 116.047908 -224.925578)
			(xy 116.088314 -224.956202) (xy 116.123554 -224.992654) (xy 116.152797 -225.034071) (xy 116.175352 -225.079478)
			(xy 116.190688 -225.127804) (xy 116.198443 -225.177908) (xy 116.198904 -225.203258) (xy 116.198396 -225.229165)
			(xy 116.19029 -225.280342) (xy 116.174278 -225.329621) (xy 116.150755 -225.375788) (xy 116.120299 -225.417707)
			(xy 116.083661 -225.454345) (xy 116.041742 -225.484801) (xy 115.995575 -225.508324) (xy 115.946296 -225.524336)
			(xy 115.895119 -225.532442) (xy 115.843305 -225.532442) (xy 115.792128 -225.524336) (xy 115.742849 -225.508324)
			(xy 115.696682 -225.484801) (xy 115.654763 -225.454345) (xy 115.618125 -225.417707) (xy 115.587669 -225.375788)
			(xy 115.564146 -225.329621) (xy 115.548134 -225.280342) (xy 115.540028 -225.229165) (xy 115.53952 -225.203258)
			(xy 115.540127 -225.175541) (xy 115.549442 -225.120895) (xy 115.558062 -225.094546) (xy 115.565936 -225.072448)
			(xy 115.360958 -224.71761) (xy 115.338098 -224.713292) (xy 115.313285 -224.708145) (xy 115.265543 -224.691153)
			(xy 115.220963 -224.667056) (xy 115.180596 -224.63642) (xy 115.145393 -224.599968) (xy 115.116182 -224.558558)
			(xy 115.093652 -224.513166) (xy 115.078334 -224.46486) (xy 115.070588 -224.41478) (xy 115.070128 -224.389442)
			(xy 114.789204 -224.389442) (xy 114.788696 -224.415329) (xy 114.780597 -224.466467) (xy 114.764598 -224.515707)
			(xy 114.741092 -224.561839) (xy 114.71066 -224.603726) (xy 114.67405 -224.640336) (xy 114.632163 -224.670768)
			(xy 114.586031 -224.694274) (xy 114.536791 -224.710273) (xy 114.485653 -224.718372) (xy 114.433879 -224.718372)
			(xy 114.382741 -224.710273) (xy 114.333501 -224.694274) (xy 114.287369 -224.670768) (xy 114.245482 -224.640336)
			(xy 114.208872 -224.603726) (xy 114.17844 -224.561839) (xy 114.154934 -224.515707) (xy 114.138935 -224.466467)
			(xy 114.130836 -224.415329) (xy 114.130328 -224.389442) (xy 113.849404 -224.389442) (xy 113.84886 -224.417149)
			(xy 113.839674 -224.471796) (xy 113.831116 -224.498154) (xy 113.823242 -224.520252) (xy 114.02822 -224.87509)
			(xy 114.05108 -224.879408) (xy 114.075909 -224.884542) (xy 114.123688 -224.901501) (xy 114.168308 -224.925578)
			(xy 114.208714 -224.956202) (xy 114.243954 -224.992654) (xy 114.273197 -225.034071) (xy 114.295752 -225.079478)
			(xy 114.311088 -225.127804) (xy 114.318843 -225.177908) (xy 114.319304 -225.203258) (xy 114.318796 -225.229165)
			(xy 114.31069 -225.280342) (xy 114.294678 -225.329621) (xy 114.271155 -225.375788) (xy 114.240699 -225.417707)
			(xy 114.204061 -225.454345) (xy 114.162142 -225.484801) (xy 114.115975 -225.508324) (xy 114.066696 -225.524336)
			(xy 114.015519 -225.532442) (xy 113.963705 -225.532442) (xy 113.912528 -225.524336) (xy 113.863249 -225.508324)
			(xy 113.817082 -225.484801) (xy 113.775163 -225.454345) (xy 113.738525 -225.417707) (xy 113.708069 -225.375788)
			(xy 113.684546 -225.329621) (xy 113.668534 -225.280342) (xy 113.660428 -225.229165) (xy 113.65992 -225.203258)
			(xy 113.660527 -225.175541) (xy 113.669842 -225.120895) (xy 113.678462 -225.094546) (xy 113.686336 -225.072448)
			(xy 113.481358 -224.71761) (xy 113.458498 -224.713292) (xy 113.433685 -224.708145) (xy 113.385943 -224.691153)
			(xy 113.341363 -224.667056) (xy 113.300996 -224.63642) (xy 113.265793 -224.599968) (xy 113.236582 -224.558558)
			(xy 113.214052 -224.513166) (xy 113.198734 -224.46486) (xy 113.190988 -224.41478) (xy 113.190528 -224.389442)
			(xy 112.909604 -224.389442) (xy 112.909096 -224.415329) (xy 112.900997 -224.466467) (xy 112.884998 -224.515707)
			(xy 112.861492 -224.561839) (xy 112.83106 -224.603726) (xy 112.79445 -224.640336) (xy 112.752563 -224.670768)
			(xy 112.706431 -224.694274) (xy 112.657191 -224.710273) (xy 112.606053 -224.718372) (xy 112.554279 -224.718372)
			(xy 112.503141 -224.710273) (xy 112.453901 -224.694274) (xy 112.407769 -224.670768) (xy 112.365882 -224.640336)
			(xy 112.329272 -224.603726) (xy 112.29884 -224.561839) (xy 112.275334 -224.515707) (xy 112.259335 -224.466467)
			(xy 112.251236 -224.415329) (xy 112.250728 -224.389442) (xy 111.969804 -224.389442) (xy 111.96926 -224.417149)
			(xy 111.960074 -224.471796) (xy 111.951516 -224.498154) (xy 111.943642 -224.520252) (xy 112.14862 -224.87509)
			(xy 112.17148 -224.879408) (xy 112.196309 -224.884542) (xy 112.244088 -224.901501) (xy 112.288708 -224.925578)
			(xy 112.329114 -224.956202) (xy 112.364354 -224.992654) (xy 112.393597 -225.034071) (xy 112.416152 -225.079478)
			(xy 112.431488 -225.127804) (xy 112.439243 -225.177908) (xy 112.439704 -225.203258) (xy 112.439196 -225.229165)
			(xy 112.43109 -225.280342) (xy 112.415078 -225.329621) (xy 112.391555 -225.375788) (xy 112.361099 -225.417707)
			(xy 112.324461 -225.454345) (xy 112.282542 -225.484801) (xy 112.236375 -225.508324) (xy 112.187096 -225.524336)
			(xy 112.135919 -225.532442) (xy 112.084105 -225.532442) (xy 112.032928 -225.524336) (xy 111.983649 -225.508324)
			(xy 111.937482 -225.484801) (xy 111.895563 -225.454345) (xy 111.858925 -225.417707) (xy 111.828469 -225.375788)
			(xy 111.804946 -225.329621) (xy 111.788934 -225.280342) (xy 111.780828 -225.229165) (xy 111.78032 -225.203258)
			(xy 111.780927 -225.175541) (xy 111.790242 -225.120895) (xy 111.798862 -225.094546) (xy 111.806736 -225.072448)
			(xy 111.601758 -224.71761) (xy 111.578898 -224.713292) (xy 111.554085 -224.708145) (xy 111.506343 -224.691153)
			(xy 111.461763 -224.667056) (xy 111.421396 -224.63642) (xy 111.386193 -224.599968) (xy 111.356982 -224.558558)
			(xy 111.334452 -224.513166) (xy 111.319134 -224.46486) (xy 111.311388 -224.41478) (xy 111.310928 -224.389442)
			(xy 111.030004 -224.389442) (xy 111.029496 -224.415329) (xy 111.021397 -224.466467) (xy 111.005398 -224.515707)
			(xy 110.981892 -224.561839) (xy 110.95146 -224.603726) (xy 110.91485 -224.640336) (xy 110.872963 -224.670768)
			(xy 110.826831 -224.694274) (xy 110.777591 -224.710273) (xy 110.726453 -224.718372) (xy 110.674679 -224.718372)
			(xy 110.623541 -224.710273) (xy 110.574301 -224.694274) (xy 110.528169 -224.670768) (xy 110.486282 -224.640336)
			(xy 110.449672 -224.603726) (xy 110.41924 -224.561839) (xy 110.395734 -224.515707) (xy 110.379735 -224.466467)
			(xy 110.371636 -224.415329) (xy 110.371128 -224.389442) (xy 110.090204 -224.389442) (xy 110.08966 -224.417149)
			(xy 110.080474 -224.471796) (xy 110.071916 -224.498154) (xy 110.064042 -224.520252) (xy 110.26902 -224.87509)
			(xy 110.29188 -224.879408) (xy 110.316709 -224.884542) (xy 110.364488 -224.901501) (xy 110.409108 -224.925578)
			(xy 110.449514 -224.956202) (xy 110.484754 -224.992654) (xy 110.513997 -225.034071) (xy 110.536552 -225.079478)
			(xy 110.551888 -225.127804) (xy 110.559643 -225.177908) (xy 110.560104 -225.203258) (xy 110.559596 -225.229165)
			(xy 110.55149 -225.280342) (xy 110.535478 -225.329621) (xy 110.511955 -225.375788) (xy 110.481499 -225.417707)
			(xy 110.444861 -225.454345) (xy 110.402942 -225.484801) (xy 110.356775 -225.508324) (xy 110.307496 -225.524336)
			(xy 110.256319 -225.532442) (xy 110.204505 -225.532442) (xy 110.153328 -225.524336) (xy 110.104049 -225.508324)
			(xy 110.057882 -225.484801) (xy 110.015963 -225.454345) (xy 109.979325 -225.417707) (xy 109.948869 -225.375788)
			(xy 109.925346 -225.329621) (xy 109.909334 -225.280342) (xy 109.901228 -225.229165) (xy 109.90072 -225.203258)
			(xy 109.901327 -225.175541) (xy 109.910642 -225.120895) (xy 109.919262 -225.094546) (xy 109.927136 -225.072448)
			(xy 109.722158 -224.71761) (xy 109.699298 -224.713292) (xy 109.674485 -224.708145) (xy 109.626743 -224.691153)
			(xy 109.582163 -224.667056) (xy 109.541796 -224.63642) (xy 109.506593 -224.599968) (xy 109.477382 -224.558558)
			(xy 109.454852 -224.513166) (xy 109.439534 -224.46486) (xy 109.431788 -224.41478) (xy 109.431328 -224.389442)
			(xy 109.150404 -224.389442) (xy 109.149896 -224.415329) (xy 109.141797 -224.466467) (xy 109.125798 -224.515707)
			(xy 109.102292 -224.561839) (xy 109.07186 -224.603726) (xy 109.03525 -224.640336) (xy 108.993363 -224.670768)
			(xy 108.947231 -224.694274) (xy 108.897991 -224.710273) (xy 108.846853 -224.718372) (xy 108.795079 -224.718372)
			(xy 108.743941 -224.710273) (xy 108.694701 -224.694274) (xy 108.648569 -224.670768) (xy 108.606682 -224.640336)
			(xy 108.570072 -224.603726) (xy 108.53964 -224.561839) (xy 108.516134 -224.515707) (xy 108.500135 -224.466467)
			(xy 108.492036 -224.415329) (xy 108.491528 -224.389442) (xy 108.210604 -224.389442) (xy 108.21006 -224.417149)
			(xy 108.200874 -224.471796) (xy 108.192316 -224.498154) (xy 108.184442 -224.520252) (xy 108.38942 -224.87509)
			(xy 108.41228 -224.879408) (xy 108.437109 -224.884542) (xy 108.484888 -224.901501) (xy 108.529508 -224.925578)
			(xy 108.569914 -224.956202) (xy 108.605154 -224.992654) (xy 108.634397 -225.034071) (xy 108.656952 -225.079478)
			(xy 108.672288 -225.127804) (xy 108.680043 -225.177908) (xy 108.680504 -225.203258) (xy 108.679996 -225.229165)
			(xy 108.67189 -225.280342) (xy 108.655878 -225.329621) (xy 108.632355 -225.375788) (xy 108.601899 -225.417707)
			(xy 108.565261 -225.454345) (xy 108.523342 -225.484801) (xy 108.477175 -225.508324) (xy 108.427896 -225.524336)
			(xy 108.376719 -225.532442) (xy 108.324905 -225.532442) (xy 108.273728 -225.524336) (xy 108.224449 -225.508324)
			(xy 108.178282 -225.484801) (xy 108.136363 -225.454345) (xy 108.099725 -225.417707) (xy 108.069269 -225.375788)
			(xy 108.045746 -225.329621) (xy 108.029734 -225.280342) (xy 108.021628 -225.229165) (xy 108.02112 -225.203258)
			(xy 108.021727 -225.175541) (xy 108.031042 -225.120895) (xy 108.039662 -225.094546) (xy 108.047536 -225.072448)
			(xy 107.842558 -224.71761) (xy 107.819698 -224.713292) (xy 107.794885 -224.708145) (xy 107.747143 -224.691153)
			(xy 107.702563 -224.667056) (xy 107.662196 -224.63642) (xy 107.626993 -224.599968) (xy 107.597782 -224.558558)
			(xy 107.575252 -224.513166) (xy 107.559934 -224.46486) (xy 107.552188 -224.41478) (xy 107.551728 -224.389442)
			(xy 107.270804 -224.389442) (xy 107.270296 -224.415329) (xy 107.262197 -224.466467) (xy 107.246198 -224.515707)
			(xy 107.222692 -224.561839) (xy 107.19226 -224.603726) (xy 107.15565 -224.640336) (xy 107.113763 -224.670768)
			(xy 107.067631 -224.694274) (xy 107.018391 -224.710273) (xy 106.967253 -224.718372) (xy 106.915479 -224.718372)
			(xy 106.864341 -224.710273) (xy 106.815101 -224.694274) (xy 106.768969 -224.670768) (xy 106.727082 -224.640336)
			(xy 106.690472 -224.603726) (xy 106.66004 -224.561839) (xy 106.636534 -224.515707) (xy 106.620535 -224.466467)
			(xy 106.612436 -224.415329) (xy 106.611928 -224.389442) (xy 106.331004 -224.389442) (xy 106.33046 -224.417149)
			(xy 106.321274 -224.471796) (xy 106.312716 -224.498154) (xy 106.304842 -224.520252) (xy 106.50982 -224.87509)
			(xy 106.53268 -224.879408) (xy 106.557509 -224.884542) (xy 106.605288 -224.901501) (xy 106.649908 -224.925578)
			(xy 106.690314 -224.956202) (xy 106.725554 -224.992654) (xy 106.754797 -225.034071) (xy 106.777352 -225.079478)
			(xy 106.792688 -225.127804) (xy 106.800443 -225.177908) (xy 106.800904 -225.203258) (xy 106.800396 -225.229165)
			(xy 106.79229 -225.280342) (xy 106.776278 -225.329621) (xy 106.752755 -225.375788) (xy 106.722299 -225.417707)
			(xy 106.685661 -225.454345) (xy 106.643742 -225.484801) (xy 106.597575 -225.508324) (xy 106.548296 -225.524336)
			(xy 106.497119 -225.532442) (xy 106.445305 -225.532442) (xy 106.394128 -225.524336) (xy 106.344849 -225.508324)
			(xy 106.298682 -225.484801) (xy 106.256763 -225.454345) (xy 106.220125 -225.417707) (xy 106.189669 -225.375788)
			(xy 106.166146 -225.329621) (xy 106.150134 -225.280342) (xy 106.142028 -225.229165) (xy 106.14152 -225.203258)
			(xy 106.142127 -225.175541) (xy 106.151442 -225.120895) (xy 106.160062 -225.094546) (xy 106.167936 -225.072448)
			(xy 105.962958 -224.71761) (xy 105.940098 -224.713292) (xy 105.915285 -224.708145) (xy 105.867543 -224.691153)
			(xy 105.822963 -224.667056) (xy 105.782596 -224.63642) (xy 105.747393 -224.599968) (xy 105.718182 -224.558558)
			(xy 105.695652 -224.513166) (xy 105.680334 -224.46486) (xy 105.672588 -224.41478) (xy 105.672128 -224.389442)
			(xy 105.391204 -224.389442) (xy 105.390696 -224.415329) (xy 105.382597 -224.466467) (xy 105.366598 -224.515707)
			(xy 105.343092 -224.561839) (xy 105.31266 -224.603726) (xy 105.27605 -224.640336) (xy 105.234163 -224.670768)
			(xy 105.188031 -224.694274) (xy 105.138791 -224.710273) (xy 105.087653 -224.718372) (xy 105.035879 -224.718372)
			(xy 104.984741 -224.710273) (xy 104.935501 -224.694274) (xy 104.889369 -224.670768) (xy 104.847482 -224.640336)
			(xy 104.810872 -224.603726) (xy 104.78044 -224.561839) (xy 104.756934 -224.515707) (xy 104.740935 -224.466467)
			(xy 104.732836 -224.415329) (xy 104.732328 -224.389442) (xy 104.451404 -224.389442) (xy 104.45086 -224.417149)
			(xy 104.441674 -224.471796) (xy 104.433116 -224.498154) (xy 104.425242 -224.520252) (xy 104.63022 -224.87509)
			(xy 104.65308 -224.879408) (xy 104.677909 -224.884542) (xy 104.725688 -224.901501) (xy 104.770308 -224.925578)
			(xy 104.810714 -224.956202) (xy 104.845954 -224.992654) (xy 104.875197 -225.034071) (xy 104.897752 -225.079478)
			(xy 104.913088 -225.127804) (xy 104.920843 -225.177908) (xy 104.921304 -225.203258) (xy 104.920796 -225.229165)
			(xy 104.91269 -225.280342) (xy 104.896678 -225.329621) (xy 104.873155 -225.375788) (xy 104.842699 -225.417707)
			(xy 104.806061 -225.454345) (xy 104.764142 -225.484801) (xy 104.717975 -225.508324) (xy 104.668696 -225.524336)
			(xy 104.617519 -225.532442) (xy 104.565705 -225.532442) (xy 104.514528 -225.524336) (xy 104.465249 -225.508324)
			(xy 104.419082 -225.484801) (xy 104.377163 -225.454345) (xy 104.340525 -225.417707) (xy 104.310069 -225.375788)
			(xy 104.286546 -225.329621) (xy 104.270534 -225.280342) (xy 104.262428 -225.229165) (xy 104.26192 -225.203258)
			(xy 104.262527 -225.175541) (xy 104.271842 -225.120895) (xy 104.280462 -225.094546) (xy 104.288336 -225.072448)
			(xy 104.083358 -224.71761) (xy 104.060498 -224.713292) (xy 104.035685 -224.708145) (xy 103.987943 -224.691153)
			(xy 103.943363 -224.667056) (xy 103.902996 -224.63642) (xy 103.867793 -224.599968) (xy 103.838582 -224.558558)
			(xy 103.816052 -224.513166) (xy 103.800734 -224.46486) (xy 103.792988 -224.41478) (xy 103.792528 -224.389442)
			(xy 103.511604 -224.389442) (xy 103.511096 -224.415329) (xy 103.502997 -224.466467) (xy 103.486998 -224.515707)
			(xy 103.463492 -224.561839) (xy 103.43306 -224.603726) (xy 103.39645 -224.640336) (xy 103.354563 -224.670768)
			(xy 103.308431 -224.694274) (xy 103.259191 -224.710273) (xy 103.208053 -224.718372) (xy 103.156279 -224.718372)
			(xy 103.105141 -224.710273) (xy 103.055901 -224.694274) (xy 103.009769 -224.670768) (xy 102.967882 -224.640336)
			(xy 102.931272 -224.603726) (xy 102.90084 -224.561839) (xy 102.877334 -224.515707) (xy 102.861335 -224.466467)
			(xy 102.853236 -224.415329) (xy 102.852728 -224.389442) (xy 102.571804 -224.389442) (xy 102.57126 -224.417149)
			(xy 102.562074 -224.471796) (xy 102.553516 -224.498154) (xy 102.545642 -224.520252) (xy 102.75062 -224.87509)
			(xy 102.77348 -224.879408) (xy 102.798309 -224.884542) (xy 102.846088 -224.901501) (xy 102.890708 -224.925578)
			(xy 102.931114 -224.956202) (xy 102.966354 -224.992654) (xy 102.995597 -225.034071) (xy 103.018152 -225.079478)
			(xy 103.033488 -225.127804) (xy 103.041243 -225.177908) (xy 103.041704 -225.203258) (xy 103.041196 -225.229165)
			(xy 103.03309 -225.280342) (xy 103.017078 -225.329621) (xy 102.993555 -225.375788) (xy 102.963099 -225.417707)
			(xy 102.926461 -225.454345) (xy 102.884542 -225.484801) (xy 102.838375 -225.508324) (xy 102.789096 -225.524336)
			(xy 102.737919 -225.532442) (xy 102.686105 -225.532442) (xy 102.634928 -225.524336) (xy 102.585649 -225.508324)
			(xy 102.539482 -225.484801) (xy 102.497563 -225.454345) (xy 102.460925 -225.417707) (xy 102.430469 -225.375788)
			(xy 102.406946 -225.329621) (xy 102.390934 -225.280342) (xy 102.382828 -225.229165) (xy 102.38232 -225.203258)
			(xy 102.382927 -225.175541) (xy 102.392242 -225.120895) (xy 102.400862 -225.094546) (xy 102.408736 -225.072448)
			(xy 102.203758 -224.71761) (xy 102.180898 -224.713292) (xy 102.156085 -224.708145) (xy 102.108343 -224.691153)
			(xy 102.063763 -224.667056) (xy 102.023396 -224.63642) (xy 101.988193 -224.599968) (xy 101.958982 -224.558558)
			(xy 101.936452 -224.513166) (xy 101.921134 -224.46486) (xy 101.913388 -224.41478) (xy 101.912928 -224.389442)
			(xy 101.632004 -224.389442) (xy 101.631496 -224.415329) (xy 101.623397 -224.466467) (xy 101.607398 -224.515707)
			(xy 101.583892 -224.561839) (xy 101.55346 -224.603726) (xy 101.51685 -224.640336) (xy 101.474963 -224.670768)
			(xy 101.428831 -224.694274) (xy 101.379591 -224.710273) (xy 101.328453 -224.718372) (xy 101.276679 -224.718372)
			(xy 101.225541 -224.710273) (xy 101.176301 -224.694274) (xy 101.130169 -224.670768) (xy 101.088282 -224.640336)
			(xy 101.051672 -224.603726) (xy 101.02124 -224.561839) (xy 100.997734 -224.515707) (xy 100.981735 -224.466467)
			(xy 100.973636 -224.415329) (xy 100.973128 -224.389442) (xy 100.692204 -224.389442) (xy 100.69166 -224.417149)
			(xy 100.682474 -224.471796) (xy 100.673916 -224.498154) (xy 100.666042 -224.520252) (xy 100.87102 -224.87509)
			(xy 100.89388 -224.879408) (xy 100.918709 -224.884542) (xy 100.966488 -224.901501) (xy 101.011108 -224.925578)
			(xy 101.051514 -224.956202) (xy 101.086754 -224.992654) (xy 101.115997 -225.034071) (xy 101.138552 -225.079478)
			(xy 101.153888 -225.127804) (xy 101.161643 -225.177908) (xy 101.162104 -225.203258) (xy 101.161596 -225.229165)
			(xy 101.15349 -225.280342) (xy 101.137478 -225.329621) (xy 101.113955 -225.375788) (xy 101.083499 -225.417707)
			(xy 101.046861 -225.454345) (xy 101.004942 -225.484801) (xy 100.958775 -225.508324) (xy 100.909496 -225.524336)
			(xy 100.858319 -225.532442) (xy 100.806505 -225.532442) (xy 100.755328 -225.524336) (xy 100.706049 -225.508324)
			(xy 100.659882 -225.484801) (xy 100.617963 -225.454345) (xy 100.581325 -225.417707) (xy 100.550869 -225.375788)
			(xy 100.527346 -225.329621) (xy 100.511334 -225.280342) (xy 100.503228 -225.229165) (xy 100.50272 -225.203258)
			(xy 100.503327 -225.175541) (xy 100.512642 -225.120895) (xy 100.521262 -225.094546) (xy 100.529136 -225.072448)
			(xy 100.324158 -224.71761) (xy 100.301298 -224.713292) (xy 100.276485 -224.708145) (xy 100.228743 -224.691153)
			(xy 100.184163 -224.667056) (xy 100.143796 -224.63642) (xy 100.108593 -224.599968) (xy 100.079382 -224.558558)
			(xy 100.056852 -224.513166) (xy 100.041534 -224.46486) (xy 100.033788 -224.41478) (xy 100.033328 -224.389442)
			(xy 99.752404 -224.389442) (xy 99.751896 -224.415329) (xy 99.743797 -224.466467) (xy 99.727798 -224.515707)
			(xy 99.704292 -224.561839) (xy 99.67386 -224.603726) (xy 99.63725 -224.640336) (xy 99.595363 -224.670768)
			(xy 99.549231 -224.694274) (xy 99.499991 -224.710273) (xy 99.448853 -224.718372) (xy 99.397079 -224.718372)
			(xy 99.345941 -224.710273) (xy 99.296701 -224.694274) (xy 99.250569 -224.670768) (xy 99.208682 -224.640336)
			(xy 99.172072 -224.603726) (xy 99.14164 -224.561839) (xy 99.118134 -224.515707) (xy 99.102135 -224.466467)
			(xy 99.094036 -224.415329) (xy 99.093528 -224.389442) (xy 98.812604 -224.389442) (xy 98.81206 -224.417149)
			(xy 98.802874 -224.471796) (xy 98.794316 -224.498154) (xy 98.786442 -224.520252) (xy 98.99142 -224.87509)
			(xy 99.01428 -224.879408) (xy 99.039109 -224.884542) (xy 99.086888 -224.901501) (xy 99.131508 -224.925578)
			(xy 99.171914 -224.956202) (xy 99.207154 -224.992654) (xy 99.236397 -225.034071) (xy 99.258952 -225.079478)
			(xy 99.274288 -225.127804) (xy 99.282043 -225.177908) (xy 99.282504 -225.203258) (xy 99.281996 -225.229165)
			(xy 99.27389 -225.280342) (xy 99.257878 -225.329621) (xy 99.234355 -225.375788) (xy 99.203899 -225.417707)
			(xy 99.167261 -225.454345) (xy 99.125342 -225.484801) (xy 99.079175 -225.508324) (xy 99.029896 -225.524336)
			(xy 98.978719 -225.532442) (xy 98.926905 -225.532442) (xy 98.875728 -225.524336) (xy 98.826449 -225.508324)
			(xy 98.780282 -225.484801) (xy 98.738363 -225.454345) (xy 98.701725 -225.417707) (xy 98.671269 -225.375788)
			(xy 98.647746 -225.329621) (xy 98.631734 -225.280342) (xy 98.623628 -225.229165) (xy 98.62312 -225.203258)
			(xy 98.623727 -225.175541) (xy 98.633042 -225.120895) (xy 98.641662 -225.094546) (xy 98.649536 -225.072448)
			(xy 98.444558 -224.71761) (xy 98.421698 -224.713292) (xy 98.396885 -224.708145) (xy 98.349143 -224.691153)
			(xy 98.304563 -224.667056) (xy 98.264196 -224.63642) (xy 98.228993 -224.599968) (xy 98.199782 -224.558558)
			(xy 98.177252 -224.513166) (xy 98.161934 -224.46486) (xy 98.154188 -224.41478) (xy 98.153728 -224.389442)
			(xy 97.872804 -224.389442) (xy 97.872296 -224.415329) (xy 97.864197 -224.466467) (xy 97.848198 -224.515707)
			(xy 97.824692 -224.561839) (xy 97.79426 -224.603726) (xy 97.75765 -224.640336) (xy 97.715763 -224.670768)
			(xy 97.669631 -224.694274) (xy 97.620391 -224.710273) (xy 97.569253 -224.718372) (xy 97.517479 -224.718372)
			(xy 97.466341 -224.710273) (xy 97.417101 -224.694274) (xy 97.370969 -224.670768) (xy 97.329082 -224.640336)
			(xy 97.292472 -224.603726) (xy 97.26204 -224.561839) (xy 97.238534 -224.515707) (xy 97.222535 -224.466467)
			(xy 97.214436 -224.415329) (xy 97.213928 -224.389442) (xy 96.933004 -224.389442) (xy 96.93246 -224.417149)
			(xy 96.923274 -224.471796) (xy 96.914716 -224.498154) (xy 96.906842 -224.520252) (xy 97.11182 -224.87509)
			(xy 97.13468 -224.879408) (xy 97.159509 -224.884542) (xy 97.207288 -224.901501) (xy 97.251908 -224.925578)
			(xy 97.292314 -224.956202) (xy 97.327554 -224.992654) (xy 97.356797 -225.034071) (xy 97.379352 -225.079478)
			(xy 97.394688 -225.127804) (xy 97.402443 -225.177908) (xy 97.402904 -225.203258) (xy 97.402396 -225.229165)
			(xy 97.39429 -225.280342) (xy 97.378278 -225.329621) (xy 97.354755 -225.375788) (xy 97.324299 -225.417707)
			(xy 97.287661 -225.454345) (xy 97.245742 -225.484801) (xy 97.199575 -225.508324) (xy 97.150296 -225.524336)
			(xy 97.099119 -225.532442) (xy 97.047305 -225.532442) (xy 96.996128 -225.524336) (xy 96.946849 -225.508324)
			(xy 96.900682 -225.484801) (xy 96.858763 -225.454345) (xy 96.822125 -225.417707) (xy 96.791669 -225.375788)
			(xy 96.768146 -225.329621) (xy 96.752134 -225.280342) (xy 96.744028 -225.229165) (xy 96.74352 -225.203258)
			(xy 96.744127 -225.175541) (xy 96.753442 -225.120895) (xy 96.762062 -225.094546) (xy 96.769936 -225.072448)
			(xy 96.564958 -224.71761) (xy 96.542098 -224.713292) (xy 96.517285 -224.708145) (xy 96.469543 -224.691153)
			(xy 96.424963 -224.667056) (xy 96.384596 -224.63642) (xy 96.349393 -224.599968) (xy 96.320182 -224.558558)
			(xy 96.297652 -224.513166) (xy 96.282334 -224.46486) (xy 96.274588 -224.41478) (xy 96.274128 -224.389442)
			(xy 95.993204 -224.389442) (xy 95.992696 -224.415329) (xy 95.984597 -224.466467) (xy 95.968598 -224.515707)
			(xy 95.945092 -224.561839) (xy 95.91466 -224.603726) (xy 95.87805 -224.640336) (xy 95.836163 -224.670768)
			(xy 95.790031 -224.694274) (xy 95.740791 -224.710273) (xy 95.689653 -224.718372) (xy 95.637879 -224.718372)
			(xy 95.586741 -224.710273) (xy 95.537501 -224.694274) (xy 95.491369 -224.670768) (xy 95.449482 -224.640336)
			(xy 95.412872 -224.603726) (xy 95.38244 -224.561839) (xy 95.358934 -224.515707) (xy 95.342935 -224.466467)
			(xy 95.334836 -224.415329) (xy 95.334328 -224.389442) (xy 95.053404 -224.389442) (xy 95.05286 -224.417149)
			(xy 95.043674 -224.471796) (xy 95.035116 -224.498154) (xy 95.027242 -224.520252) (xy 95.23222 -224.87509)
			(xy 95.25508 -224.879408) (xy 95.279909 -224.884542) (xy 95.327688 -224.901501) (xy 95.372308 -224.925578)
			(xy 95.412714 -224.956202) (xy 95.447954 -224.992654) (xy 95.477197 -225.034071) (xy 95.499752 -225.079478)
			(xy 95.515088 -225.127804) (xy 95.522843 -225.177908) (xy 95.523304 -225.203258) (xy 95.522796 -225.229165)
			(xy 95.51469 -225.280342) (xy 95.498678 -225.329621) (xy 95.475155 -225.375788) (xy 95.444699 -225.417707)
			(xy 95.408061 -225.454345) (xy 95.366142 -225.484801) (xy 95.319975 -225.508324) (xy 95.270696 -225.524336)
			(xy 95.219519 -225.532442) (xy 95.167705 -225.532442) (xy 95.116528 -225.524336) (xy 95.067249 -225.508324)
			(xy 95.021082 -225.484801) (xy 94.979163 -225.454345) (xy 94.942525 -225.417707) (xy 94.912069 -225.375788)
			(xy 94.888546 -225.329621) (xy 94.872534 -225.280342) (xy 94.864428 -225.229165) (xy 94.86392 -225.203258)
			(xy 94.864527 -225.175541) (xy 94.873842 -225.120895) (xy 94.882462 -225.094546) (xy 94.890336 -225.072448)
			(xy 94.685358 -224.71761) (xy 94.662498 -224.713292) (xy 94.637685 -224.708145) (xy 94.589943 -224.691153)
			(xy 94.545363 -224.667056) (xy 94.504996 -224.63642) (xy 94.469793 -224.599968) (xy 94.440582 -224.558558)
			(xy 94.418052 -224.513166) (xy 94.402734 -224.46486) (xy 94.394988 -224.41478) (xy 94.394528 -224.389442)
			(xy 94.113604 -224.389442) (xy 94.113096 -224.415329) (xy 94.104997 -224.466467) (xy 94.088998 -224.515707)
			(xy 94.065492 -224.561839) (xy 94.03506 -224.603726) (xy 93.99845 -224.640336) (xy 93.956563 -224.670768)
			(xy 93.910431 -224.694274) (xy 93.861191 -224.710273) (xy 93.810053 -224.718372) (xy 93.758279 -224.718372)
			(xy 93.707141 -224.710273) (xy 93.657901 -224.694274) (xy 93.611769 -224.670768) (xy 93.569882 -224.640336)
			(xy 93.533272 -224.603726) (xy 93.50284 -224.561839) (xy 93.479334 -224.515707) (xy 93.463335 -224.466467)
			(xy 93.455236 -224.415329) (xy 93.454728 -224.389442) (xy 93.173804 -224.389442) (xy 93.173804 -224.38995)
			(xy 93.173247 -224.417593) (xy 93.164056 -224.472111) (xy 93.155516 -224.498408) (xy 93.147896 -224.520252)
			(xy 93.35262 -224.87509) (xy 93.37548 -224.879408) (xy 93.400309 -224.884542) (xy 93.448088 -224.901501)
			(xy 93.492708 -224.925578) (xy 93.533114 -224.956202) (xy 93.568354 -224.992654) (xy 93.597597 -225.034071)
			(xy 93.620152 -225.079478) (xy 93.635488 -225.127804) (xy 93.643243 -225.177908) (xy 93.643704 -225.203258)
			(xy 93.643196 -225.229165) (xy 93.63509 -225.280342) (xy 93.619078 -225.329621) (xy 93.595555 -225.375788)
			(xy 93.565099 -225.417707) (xy 93.528461 -225.454345) (xy 93.486542 -225.484801) (xy 93.440375 -225.508324)
			(xy 93.391096 -225.524336) (xy 93.339919 -225.532442) (xy 93.288105 -225.532442) (xy 93.236928 -225.524336)
			(xy 93.187649 -225.508324) (xy 93.141482 -225.484801) (xy 93.099563 -225.454345) (xy 93.062925 -225.417707)
			(xy 93.032469 -225.375788) (xy 93.008946 -225.329621) (xy 92.992934 -225.280342) (xy 92.984828 -225.229165)
			(xy 92.98432 -225.203258) (xy 92.98432 -225.20275) (xy 92.98493 -225.175096) (xy 92.994253 -225.120579)
			(xy 93.002862 -225.094292) (xy 93.010482 -225.072448) (xy 92.805758 -224.71761) (xy 92.782898 -224.713292)
			(xy 92.758085 -224.708145) (xy 92.710343 -224.691153) (xy 92.665763 -224.667056) (xy 92.625396 -224.63642)
			(xy 92.590193 -224.599968) (xy 92.560982 -224.558558) (xy 92.538452 -224.513166) (xy 92.523134 -224.46486)
			(xy 92.515388 -224.41478) (xy 92.514928 -224.389442) (xy 92.234004 -224.389442) (xy 92.233496 -224.415329)
			(xy 92.225397 -224.466467) (xy 92.209398 -224.515707) (xy 92.185892 -224.561839) (xy 92.15546 -224.603726)
			(xy 92.11885 -224.640336) (xy 92.076963 -224.670768) (xy 92.030831 -224.694274) (xy 91.981591 -224.710273)
			(xy 91.930453 -224.718372) (xy 91.878679 -224.718372) (xy 91.827541 -224.710273) (xy 91.778301 -224.694274)
			(xy 91.732169 -224.670768) (xy 91.690282 -224.640336) (xy 91.653672 -224.603726) (xy 91.62324 -224.561839)
			(xy 91.599734 -224.515707) (xy 91.583735 -224.466467) (xy 91.575636 -224.415329) (xy 91.575128 -224.389442)
			(xy 91.294204 -224.389442) (xy 91.294204 -224.38995) (xy 91.293647 -224.417593) (xy 91.284456 -224.472111)
			(xy 91.275916 -224.498408) (xy 91.268296 -224.520252) (xy 91.47302 -224.87509) (xy 91.49588 -224.879408)
			(xy 91.520709 -224.884542) (xy 91.568488 -224.901501) (xy 91.613108 -224.925578) (xy 91.653514 -224.956202)
			(xy 91.688754 -224.992654) (xy 91.717997 -225.034071) (xy 91.740552 -225.079478) (xy 91.755888 -225.127804)
			(xy 91.763643 -225.177908) (xy 91.764104 -225.203258) (xy 91.763596 -225.229165) (xy 91.75549 -225.280342)
			(xy 91.739478 -225.329621) (xy 91.715955 -225.375788) (xy 91.685499 -225.417707) (xy 91.648861 -225.454345)
			(xy 91.606942 -225.484801) (xy 91.560775 -225.508324) (xy 91.511496 -225.524336) (xy 91.460319 -225.532442)
			(xy 91.408505 -225.532442) (xy 91.357328 -225.524336) (xy 91.308049 -225.508324) (xy 91.261882 -225.484801)
			(xy 91.219963 -225.454345) (xy 91.183325 -225.417707) (xy 91.152869 -225.375788) (xy 91.129346 -225.329621)
			(xy 91.113334 -225.280342) (xy 91.105228 -225.229165) (xy 91.10472 -225.203258) (xy 91.10472 -225.20275)
			(xy 91.10533 -225.175096) (xy 91.114653 -225.120579) (xy 91.123262 -225.094292) (xy 91.130882 -225.072448)
			(xy 90.926158 -224.71761) (xy 90.903298 -224.713292) (xy 90.878485 -224.708145) (xy 90.830743 -224.691153)
			(xy 90.786163 -224.667056) (xy 90.745796 -224.63642) (xy 90.710593 -224.599968) (xy 90.681382 -224.558558)
			(xy 90.658852 -224.513166) (xy 90.643534 -224.46486) (xy 90.635788 -224.41478) (xy 90.635328 -224.389442)
			(xy 90.354404 -224.389442) (xy 90.353896 -224.415329) (xy 90.345797 -224.466467) (xy 90.329798 -224.515707)
			(xy 90.306292 -224.561839) (xy 90.27586 -224.603726) (xy 90.23925 -224.640336) (xy 90.197363 -224.670768)
			(xy 90.151231 -224.694274) (xy 90.101991 -224.710273) (xy 90.050853 -224.718372) (xy 89.999079 -224.718372)
			(xy 89.947941 -224.710273) (xy 89.898701 -224.694274) (xy 89.852569 -224.670768) (xy 89.810682 -224.640336)
			(xy 89.774072 -224.603726) (xy 89.74364 -224.561839) (xy 89.720134 -224.515707) (xy 89.704135 -224.466467)
			(xy 89.696036 -224.415329) (xy 89.695528 -224.389442) (xy 2.509012 -224.389442) (xy 2.509012 -247.620536)
			(xy 228.175312 -247.620536) (xy 228.175312 -246.756936) (xy 228.175798 -246.729685) (xy 228.183554 -246.675737)
			(xy 228.198909 -246.623442) (xy 228.221551 -246.573865) (xy 228.251017 -246.528015) (xy 228.286708 -246.486824)
			(xy 228.327899 -246.451133) (xy 228.373749 -246.421667) (xy 228.423326 -246.399025) (xy 228.475621 -246.38367)
			(xy 228.529569 -246.375914) (xy 228.584071 -246.375914) (xy 228.638019 -246.38367) (xy 228.690314 -246.399025)
			(xy 228.739891 -246.421667) (xy 228.785741 -246.451133) (xy 228.826932 -246.486824) (xy 228.862623 -246.528015)
			(xy 228.892089 -246.573865) (xy 228.914731 -246.623442) (xy 228.930086 -246.675737) (xy 228.937842 -246.729685)
			(xy 228.938328 -246.756936) (xy 228.938328 -247.620536) (xy 228.937842 -247.647787) (xy 228.930086 -247.701735)
			(xy 228.914731 -247.75403) (xy 228.892089 -247.803607) (xy 228.862623 -247.849457) (xy 228.826932 -247.890648)
			(xy 228.785741 -247.926339) (xy 228.739891 -247.955805) (xy 228.690314 -247.978447) (xy 228.638019 -247.993802)
			(xy 228.584071 -248.001558) (xy 228.529569 -248.001558) (xy 228.475621 -247.993802) (xy 228.423326 -247.978447)
			(xy 228.373749 -247.955805) (xy 228.327899 -247.926339) (xy 228.286708 -247.890648) (xy 228.251017 -247.849457)
			(xy 228.221551 -247.803607) (xy 228.198909 -247.75403) (xy 228.183554 -247.701735) (xy 228.175798 -247.647787)
			(xy 228.175312 -247.620536) (xy 2.509012 -247.620536) (xy 2.509012 -251.76988) (xy 75.695566 -251.76988)
			(xy 75.699547 -251.63686) (xy 75.711476 -251.504315) (xy 75.731311 -251.372722) (xy 75.75898 -251.24255)
			(xy 75.794384 -251.114265) (xy 75.837397 -250.988328) (xy 75.887864 -250.865189) (xy 75.945605 -250.745288)
			(xy 76.010414 -250.629055) (xy 76.082058 -250.516905) (xy 76.16028 -250.409241) (xy 76.244801 -250.306448)
			(xy 76.335319 -250.208893) (xy 76.431508 -250.116927) (xy 76.533026 -250.030877) (xy 76.639507 -249.951053)
			(xy 76.750572 -249.87774) (xy 76.865823 -249.8112) (xy 76.984847 -249.751671) (xy 77.107218 -249.699367)
			(xy 77.232497 -249.654475) (xy 77.360238 -249.617156) (xy 77.489981 -249.587543) (xy 77.621263 -249.565742)
			(xy 77.753614 -249.551832) (xy 77.88656 -249.545861) (xy 78.019625 -249.547852) (xy 78.152333 -249.557797)
			(xy 78.284209 -249.575661) (xy 78.41478 -249.601379) (xy 78.54358 -249.63486) (xy 78.670146 -249.675984)
			(xy 78.794027 -249.724604) (xy 78.914778 -249.780545) (xy 79.031968 -249.843607) (xy 79.145177 -249.913565)
			(xy 79.253999 -249.990169) (xy 79.358045 -250.073143) (xy 79.456943 -250.162191) (xy 79.550338 -250.256994)
			(xy 79.637896 -250.357212) (xy 79.719305 -250.462488) (xy 79.794271 -250.572444) (xy 79.862528 -250.686686)
			(xy 79.92383 -250.804806) (xy 79.977959 -250.926381) (xy 80.02472 -251.050975) (xy 80.063946 -251.178143)
			(xy 80.095496 -251.307429) (xy 80.119259 -251.43837) (xy 80.135148 -251.570498) (xy 80.143106 -251.70334)
			(xy 80.143604 -251.76988) (xy 143.715496 -251.76988) (xy 143.719477 -251.63686) (xy 143.731406 -251.504315)
			(xy 143.751241 -251.372722) (xy 143.77891 -251.24255) (xy 143.814314 -251.114265) (xy 143.857327 -250.988328)
			(xy 143.907794 -250.865189) (xy 143.965535 -250.745288) (xy 144.030344 -250.629055) (xy 144.101988 -250.516905)
			(xy 144.18021 -250.409241) (xy 144.264731 -250.306448) (xy 144.355249 -250.208893) (xy 144.451438 -250.116927)
			(xy 144.552956 -250.030877) (xy 144.659437 -249.951053) (xy 144.770502 -249.87774) (xy 144.885753 -249.8112)
			(xy 145.004777 -249.751671) (xy 145.127148 -249.699367) (xy 145.252427 -249.654475) (xy 145.380168 -249.617156)
			(xy 145.509911 -249.587543) (xy 145.641193 -249.565742) (xy 145.773544 -249.551832) (xy 145.90649 -249.545861)
			(xy 146.039555 -249.547852) (xy 146.172263 -249.557797) (xy 146.304139 -249.575661) (xy 146.43471 -249.601379)
			(xy 146.56351 -249.63486) (xy 146.690076 -249.675984) (xy 146.813957 -249.724604) (xy 146.934708 -249.780545)
			(xy 147.051898 -249.843607) (xy 147.165107 -249.913565) (xy 147.273929 -249.990169) (xy 147.377975 -250.073143)
			(xy 147.476873 -250.162191) (xy 147.570268 -250.256994) (xy 147.657826 -250.357212) (xy 147.739235 -250.462488)
			(xy 147.814201 -250.572444) (xy 147.882458 -250.686686) (xy 147.94376 -250.804806) (xy 147.997889 -250.926381)
			(xy 148.04465 -251.050975) (xy 148.083876 -251.178143) (xy 148.115426 -251.307429) (xy 148.139189 -251.43837)
			(xy 148.155078 -251.570498) (xy 148.163036 -251.70334) (xy 148.163534 -251.76988) (xy 323.635634 -251.76988)
			(xy 323.639615 -251.63686) (xy 323.651544 -251.504315) (xy 323.671379 -251.372722) (xy 323.699048 -251.24255)
			(xy 323.734452 -251.114265) (xy 323.777465 -250.988328) (xy 323.827932 -250.865189) (xy 323.885673 -250.745288)
			(xy 323.950482 -250.629055) (xy 324.022126 -250.516905) (xy 324.100348 -250.409241) (xy 324.184869 -250.306448)
			(xy 324.275387 -250.208893) (xy 324.371576 -250.116927) (xy 324.473094 -250.030877) (xy 324.579575 -249.951053)
			(xy 324.69064 -249.87774) (xy 324.805891 -249.8112) (xy 324.924915 -249.751671) (xy 325.047286 -249.699367)
			(xy 325.172565 -249.654475) (xy 325.300306 -249.617156) (xy 325.430049 -249.587543) (xy 325.561331 -249.565742)
			(xy 325.693682 -249.551832) (xy 325.826628 -249.545861) (xy 325.959693 -249.547852) (xy 326.092401 -249.557797)
			(xy 326.224277 -249.575661) (xy 326.354848 -249.601379) (xy 326.483648 -249.63486) (xy 326.610214 -249.675984)
			(xy 326.734095 -249.724604) (xy 326.854846 -249.780545) (xy 326.972036 -249.843607) (xy 327.085245 -249.913565)
			(xy 327.194067 -249.990169) (xy 327.298113 -250.073143) (xy 327.397011 -250.162191) (xy 327.490406 -250.256994)
			(xy 327.577964 -250.357212) (xy 327.659373 -250.462488) (xy 327.734339 -250.572444) (xy 327.802596 -250.686686)
			(xy 327.863898 -250.804806) (xy 327.918027 -250.926381) (xy 327.964788 -251.050975) (xy 328.004014 -251.178143)
			(xy 328.035564 -251.307429) (xy 328.059327 -251.43837) (xy 328.075216 -251.570498) (xy 328.083174 -251.70334)
			(xy 328.083672 -251.76988) (xy 391.655564 -251.76988) (xy 391.659545 -251.63686) (xy 391.671474 -251.504315)
			(xy 391.691309 -251.372722) (xy 391.718978 -251.24255) (xy 391.754382 -251.114265) (xy 391.797395 -250.988328)
			(xy 391.847862 -250.865189) (xy 391.905603 -250.745288) (xy 391.970412 -250.629055) (xy 392.042056 -250.516905)
			(xy 392.120278 -250.409241) (xy 392.204799 -250.306448) (xy 392.295317 -250.208893) (xy 392.391506 -250.116927)
			(xy 392.493024 -250.030877) (xy 392.599505 -249.951053) (xy 392.71057 -249.87774) (xy 392.825821 -249.8112)
			(xy 392.944845 -249.751671) (xy 393.067216 -249.699367) (xy 393.192495 -249.654475) (xy 393.320236 -249.617156)
			(xy 393.449979 -249.587543) (xy 393.581261 -249.565742) (xy 393.713612 -249.551832) (xy 393.846558 -249.545861)
			(xy 393.979623 -249.547852) (xy 394.112331 -249.557797) (xy 394.244207 -249.575661) (xy 394.374778 -249.601379)
			(xy 394.503578 -249.63486) (xy 394.630144 -249.675984) (xy 394.754025 -249.724604) (xy 394.874776 -249.780545)
			(xy 394.991966 -249.843607) (xy 395.105175 -249.913565) (xy 395.213997 -249.990169) (xy 395.318043 -250.073143)
			(xy 395.416941 -250.162191) (xy 395.510336 -250.256994) (xy 395.597894 -250.357212) (xy 395.679303 -250.462488)
			(xy 395.754269 -250.572444) (xy 395.822526 -250.686686) (xy 395.883828 -250.804806) (xy 395.937957 -250.926381)
			(xy 395.984718 -251.050975) (xy 396.023944 -251.178143) (xy 396.055494 -251.307429) (xy 396.079257 -251.43837)
			(xy 396.095146 -251.570498) (xy 396.103104 -251.70334) (xy 396.103602 -251.76988) (xy 396.103104 -251.83642)
			(xy 396.095146 -251.969262) (xy 396.079257 -252.10139) (xy 396.055494 -252.232331) (xy 396.023944 -252.361617)
			(xy 395.984718 -252.488785) (xy 395.937957 -252.613379) (xy 395.883828 -252.734954) (xy 395.822526 -252.853074)
			(xy 395.754269 -252.967316) (xy 395.679303 -253.077272) (xy 395.597894 -253.182548) (xy 395.510336 -253.282766)
			(xy 395.416941 -253.377569) (xy 395.318043 -253.466617) (xy 395.213997 -253.549591) (xy 395.105175 -253.626195)
			(xy 394.991966 -253.696153) (xy 394.874776 -253.759215) (xy 394.754025 -253.815156) (xy 394.630144 -253.863776)
			(xy 394.503578 -253.9049) (xy 394.374778 -253.938381) (xy 394.244207 -253.964099) (xy 394.112331 -253.981963)
			(xy 393.979623 -253.991908) (xy 393.846558 -253.993899) (xy 393.713612 -253.987928) (xy 393.581261 -253.974018)
			(xy 393.449979 -253.952217) (xy 393.320236 -253.922604) (xy 393.192495 -253.885285) (xy 393.067216 -253.840393)
			(xy 392.944845 -253.788089) (xy 392.825821 -253.72856) (xy 392.71057 -253.66202) (xy 392.599505 -253.588707)
			(xy 392.493024 -253.508883) (xy 392.391506 -253.422833) (xy 392.295317 -253.330867) (xy 392.204799 -253.233312)
			(xy 392.120278 -253.130519) (xy 392.042056 -253.022855) (xy 391.970412 -252.910705) (xy 391.905603 -252.794472)
			(xy 391.847862 -252.674571) (xy 391.797395 -252.551432) (xy 391.754382 -252.425495) (xy 391.718978 -252.29721)
			(xy 391.691309 -252.167038) (xy 391.671474 -252.035445) (xy 391.659545 -251.9029) (xy 391.655564 -251.76988)
			(xy 328.083672 -251.76988) (xy 328.083174 -251.83642) (xy 328.075216 -251.969262) (xy 328.059327 -252.10139)
			(xy 328.035564 -252.232331) (xy 328.004014 -252.361617) (xy 327.964788 -252.488785) (xy 327.918027 -252.613379)
			(xy 327.863898 -252.734954) (xy 327.802596 -252.853074) (xy 327.734339 -252.967316) (xy 327.659373 -253.077272)
			(xy 327.577964 -253.182548) (xy 327.490406 -253.282766) (xy 327.397011 -253.377569) (xy 327.298113 -253.466617)
			(xy 327.194067 -253.549591) (xy 327.085245 -253.626195) (xy 326.972036 -253.696153) (xy 326.854846 -253.759215)
			(xy 326.734095 -253.815156) (xy 326.610214 -253.863776) (xy 326.483648 -253.9049) (xy 326.354848 -253.938381)
			(xy 326.224277 -253.964099) (xy 326.092401 -253.981963) (xy 325.959693 -253.991908) (xy 325.826628 -253.993899)
			(xy 325.693682 -253.987928) (xy 325.561331 -253.974018) (xy 325.430049 -253.952217) (xy 325.300306 -253.922604)
			(xy 325.172565 -253.885285) (xy 325.047286 -253.840393) (xy 324.924915 -253.788089) (xy 324.805891 -253.72856)
			(xy 324.69064 -253.66202) (xy 324.579575 -253.588707) (xy 324.473094 -253.508883) (xy 324.371576 -253.422833)
			(xy 324.275387 -253.330867) (xy 324.184869 -253.233312) (xy 324.100348 -253.130519) (xy 324.022126 -253.022855)
			(xy 323.950482 -252.910705) (xy 323.885673 -252.794472) (xy 323.827932 -252.674571) (xy 323.777465 -252.551432)
			(xy 323.734452 -252.425495) (xy 323.699048 -252.29721) (xy 323.671379 -252.167038) (xy 323.651544 -252.035445)
			(xy 323.639615 -251.9029) (xy 323.635634 -251.76988) (xy 148.163534 -251.76988) (xy 148.163036 -251.83642)
			(xy 148.155078 -251.969262) (xy 148.139189 -252.10139) (xy 148.115426 -252.232331) (xy 148.083876 -252.361617)
			(xy 148.04465 -252.488785) (xy 147.997889 -252.613379) (xy 147.94376 -252.734954) (xy 147.882458 -252.853074)
			(xy 147.814201 -252.967316) (xy 147.739235 -253.077272) (xy 147.657826 -253.182548) (xy 147.570268 -253.282766)
			(xy 147.476873 -253.377569) (xy 147.377975 -253.466617) (xy 147.273929 -253.549591) (xy 147.165107 -253.626195)
			(xy 147.051898 -253.696153) (xy 146.934708 -253.759215) (xy 146.813957 -253.815156) (xy 146.690076 -253.863776)
			(xy 146.56351 -253.9049) (xy 146.43471 -253.938381) (xy 146.304139 -253.964099) (xy 146.172263 -253.981963)
			(xy 146.039555 -253.991908) (xy 145.90649 -253.993899) (xy 145.773544 -253.987928) (xy 145.641193 -253.974018)
			(xy 145.509911 -253.952217) (xy 145.380168 -253.922604) (xy 145.252427 -253.885285) (xy 145.127148 -253.840393)
			(xy 145.004777 -253.788089) (xy 144.885753 -253.72856) (xy 144.770502 -253.66202) (xy 144.659437 -253.588707)
			(xy 144.552956 -253.508883) (xy 144.451438 -253.422833) (xy 144.355249 -253.330867) (xy 144.264731 -253.233312)
			(xy 144.18021 -253.130519) (xy 144.101988 -253.022855) (xy 144.030344 -252.910705) (xy 143.965535 -252.794472)
			(xy 143.907794 -252.674571) (xy 143.857327 -252.551432) (xy 143.814314 -252.425495) (xy 143.77891 -252.29721)
			(xy 143.751241 -252.167038) (xy 143.731406 -252.035445) (xy 143.719477 -251.9029) (xy 143.715496 -251.76988)
			(xy 80.143604 -251.76988) (xy 80.143106 -251.83642) (xy 80.135148 -251.969262) (xy 80.119259 -252.10139)
			(xy 80.095496 -252.232331) (xy 80.063946 -252.361617) (xy 80.02472 -252.488785) (xy 79.977959 -252.613379)
			(xy 79.92383 -252.734954) (xy 79.862528 -252.853074) (xy 79.794271 -252.967316) (xy 79.719305 -253.077272)
			(xy 79.637896 -253.182548) (xy 79.550338 -253.282766) (xy 79.456943 -253.377569) (xy 79.358045 -253.466617)
			(xy 79.253999 -253.549591) (xy 79.145177 -253.626195) (xy 79.031968 -253.696153) (xy 78.914778 -253.759215)
			(xy 78.794027 -253.815156) (xy 78.670146 -253.863776) (xy 78.54358 -253.9049) (xy 78.41478 -253.938381)
			(xy 78.284209 -253.964099) (xy 78.152333 -253.981963) (xy 78.019625 -253.991908) (xy 77.88656 -253.993899)
			(xy 77.753614 -253.987928) (xy 77.621263 -253.974018) (xy 77.489981 -253.952217) (xy 77.360238 -253.922604)
			(xy 77.232497 -253.885285) (xy 77.107218 -253.840393) (xy 76.984847 -253.788089) (xy 76.865823 -253.72856)
			(xy 76.750572 -253.66202) (xy 76.639507 -253.588707) (xy 76.533026 -253.508883) (xy 76.431508 -253.422833)
			(xy 76.335319 -253.330867) (xy 76.244801 -253.233312) (xy 76.16028 -253.130519) (xy 76.082058 -253.022855)
			(xy 76.010414 -252.910705) (xy 75.945605 -252.794472) (xy 75.887864 -252.674571) (xy 75.837397 -252.551432)
			(xy 75.794384 -252.425495) (xy 75.75898 -252.29721) (xy 75.731311 -252.167038) (xy 75.711476 -252.035445)
			(xy 75.699547 -251.9029) (xy 75.695566 -251.76988) (xy 2.509012 -251.76988) (xy 2.509012 -273.453098)
			(xy 108.601256 -273.453098) (xy 108.601764 -273.427211) (xy 108.609863 -273.376073) (xy 108.625862 -273.326833)
			(xy 108.649368 -273.280701) (xy 108.6798 -273.238814) (xy 108.71641 -273.202204) (xy 108.758297 -273.171772)
			(xy 108.804429 -273.148266) (xy 108.853669 -273.132267) (xy 108.904807 -273.124168) (xy 108.956581 -273.124168)
			(xy 109.007719 -273.132267) (xy 109.056959 -273.148266) (xy 109.103091 -273.171772) (xy 109.144978 -273.202204)
			(xy 109.181588 -273.238814) (xy 109.21202 -273.280701) (xy 109.235526 -273.326833) (xy 109.251525 -273.376073)
			(xy 109.259624 -273.427211) (xy 109.260132 -273.453098) (xy 356.541324 -273.453098) (xy 356.541832 -273.427211)
			(xy 356.549931 -273.376073) (xy 356.56593 -273.326833) (xy 356.589436 -273.280701) (xy 356.619868 -273.238814)
			(xy 356.656478 -273.202204) (xy 356.698365 -273.171772) (xy 356.744497 -273.148266) (xy 356.793737 -273.132267)
			(xy 356.844875 -273.124168) (xy 356.896649 -273.124168) (xy 356.947787 -273.132267) (xy 356.997027 -273.148266)
			(xy 357.043159 -273.171772) (xy 357.085046 -273.202204) (xy 357.121656 -273.238814) (xy 357.152088 -273.280701)
			(xy 357.175594 -273.326833) (xy 357.191593 -273.376073) (xy 357.199692 -273.427211) (xy 357.2002 -273.453098)
			(xy 357.19967 -273.480806) (xy 357.190475 -273.535453) (xy 357.181912 -273.56181) (xy 357.174292 -273.583654)
			(xy 357.37927 -273.938746) (xy 357.40213 -273.943064) (xy 357.426938 -273.948232) (xy 357.474677 -273.965225)
			(xy 357.519254 -273.989322) (xy 357.559619 -274.019956) (xy 357.594821 -274.056405) (xy 357.624032 -274.097811)
			(xy 357.646564 -274.143199) (xy 357.661886 -274.191501) (xy 357.669637 -274.241577) (xy 357.6701 -274.266914)
			(xy 357.669592 -274.292801) (xy 357.661493 -274.343939) (xy 357.645494 -274.393179) (xy 357.621988 -274.439311)
			(xy 357.591556 -274.481198) (xy 357.554946 -274.517808) (xy 357.513059 -274.54824) (xy 357.466927 -274.571746)
			(xy 357.417687 -274.587745) (xy 357.366549 -274.595844) (xy 357.314775 -274.595844) (xy 357.263637 -274.587745)
			(xy 357.214397 -274.571746) (xy 357.168265 -274.54824) (xy 357.126378 -274.517808) (xy 357.089768 -274.481198)
			(xy 357.059336 -274.439311) (xy 357.03583 -274.393179) (xy 357.019831 -274.343939) (xy 357.011732 -274.292801)
			(xy 357.011224 -274.266914) (xy 357.011756 -274.239206) (xy 357.020949 -274.184559) (xy 357.029512 -274.158202)
			(xy 357.037386 -274.136104) (xy 356.832408 -273.781266) (xy 356.809548 -273.776948) (xy 356.784736 -273.771741)
			(xy 356.73696 -273.75479) (xy 356.692344 -273.730722) (xy 356.651938 -273.700106) (xy 356.616698 -273.663665)
			(xy 356.587453 -273.622257) (xy 356.564893 -273.576859) (xy 356.549551 -273.528542) (xy 356.541789 -273.478445)
			(xy 356.541324 -273.453098) (xy 109.260132 -273.453098) (xy 109.259601 -273.480806) (xy 109.250407 -273.535453)
			(xy 109.241844 -273.56181) (xy 109.234224 -273.583654) (xy 109.439202 -273.938746) (xy 109.462062 -273.943064)
			(xy 109.486859 -273.948281) (xy 109.534598 -273.965264) (xy 109.579176 -273.989353) (xy 109.619543 -274.019979)
			(xy 109.654747 -274.056422) (xy 109.683961 -274.097824) (xy 109.706494 -274.143208) (xy 109.721817 -274.191505)
			(xy 109.729569 -274.241579) (xy 109.730032 -274.266914) (xy 351.372424 -274.266914) (xy 351.372932 -274.241027)
			(xy 351.381031 -274.189889) (xy 351.39703 -274.140649) (xy 351.420536 -274.094517) (xy 351.450968 -274.05263)
			(xy 351.487578 -274.01602) (xy 351.529465 -273.985588) (xy 351.575597 -273.962082) (xy 351.624837 -273.946083)
			(xy 351.675975 -273.937984) (xy 351.727749 -273.937984) (xy 351.778887 -273.946083) (xy 351.828127 -273.962082)
			(xy 351.874259 -273.985588) (xy 351.916146 -274.01602) (xy 351.952756 -274.05263) (xy 351.983188 -274.094517)
			(xy 352.006694 -274.140649) (xy 352.022693 -274.189889) (xy 352.030792 -274.241027) (xy 352.0313 -274.266914)
			(xy 352.0313 -274.267422) (xy 352.030713 -274.294938) (xy 352.021525 -274.349199) (xy 352.013012 -274.375372)
			(xy 352.005392 -274.397216) (xy 352.210624 -274.752562) (xy 352.233484 -274.75688) (xy 352.258307 -274.762037)
			(xy 352.306085 -274.778995) (xy 352.350703 -274.80307) (xy 352.391108 -274.833692) (xy 352.426348 -274.87014)
			(xy 352.455591 -274.911554) (xy 352.478148 -274.956958) (xy 352.493487 -275.00528) (xy 352.501245 -275.055381)
			(xy 352.501708 -275.08073) (xy 352.5012 -275.106637) (xy 352.493094 -275.157814) (xy 352.477082 -275.207093)
			(xy 352.453559 -275.25326) (xy 352.423103 -275.295179) (xy 352.386465 -275.331817) (xy 352.344546 -275.362273)
			(xy 352.298379 -275.385796) (xy 352.2491 -275.401808) (xy 352.197923 -275.409914) (xy 352.146109 -275.409914)
			(xy 352.094932 -275.401808) (xy 352.045653 -275.385796) (xy 351.999486 -275.362273) (xy 351.957567 -275.331817)
			(xy 351.920929 -275.295179) (xy 351.890473 -275.25326) (xy 351.86695 -275.207093) (xy 351.850938 -275.157814)
			(xy 351.842832 -275.106637) (xy 351.842324 -275.08073) (xy 351.842924 -275.053013) (xy 351.852243 -274.998366)
			(xy 351.860866 -274.972018) (xy 351.86874 -274.94992) (xy 351.663762 -274.595082) (xy 351.640902 -274.590764)
			(xy 351.616074 -274.585582) (xy 351.568269 -274.568647) (xy 351.523622 -274.544591) (xy 351.483185 -274.513981)
			(xy 351.447913 -274.47754) (xy 351.418638 -274.436127) (xy 351.39605 -274.390718) (xy 351.380683 -274.342387)
			(xy 351.372898 -274.292272) (xy 351.372424 -274.266914) (xy 109.730032 -274.266914) (xy 109.729524 -274.292801)
			(xy 109.721425 -274.343939) (xy 109.705426 -274.393179) (xy 109.68192 -274.439311) (xy 109.651488 -274.481198)
			(xy 109.614878 -274.517808) (xy 109.572991 -274.54824) (xy 109.526859 -274.571746) (xy 109.477619 -274.587745)
			(xy 109.426481 -274.595844) (xy 109.374707 -274.595844) (xy 109.323569 -274.587745) (xy 109.274329 -274.571746)
			(xy 109.228197 -274.54824) (xy 109.18631 -274.517808) (xy 109.1497 -274.481198) (xy 109.119268 -274.439311)
			(xy 109.095762 -274.393179) (xy 109.079763 -274.343939) (xy 109.071664 -274.292801) (xy 109.071156 -274.266914)
			(xy 109.071691 -274.239206) (xy 109.080883 -274.184559) (xy 109.089444 -274.158202) (xy 109.097318 -274.136104)
			(xy 108.89234 -273.781266) (xy 108.86948 -273.776948) (xy 108.844673 -273.771718) (xy 108.796897 -273.754771)
			(xy 108.75228 -273.730708) (xy 108.711874 -273.700095) (xy 108.676632 -273.663656) (xy 108.647386 -273.622251)
			(xy 108.624826 -273.576855) (xy 108.609484 -273.528539) (xy 108.601721 -273.478444) (xy 108.601256 -273.453098)
			(xy 2.509012 -273.453098) (xy 2.509012 -274.266914) (xy 103.432356 -274.266914) (xy 103.432864 -274.241027)
			(xy 103.440963 -274.189889) (xy 103.456962 -274.140649) (xy 103.480468 -274.094517) (xy 103.5109 -274.05263)
			(xy 103.54751 -274.01602) (xy 103.589397 -273.985588) (xy 103.635529 -273.962082) (xy 103.684769 -273.946083)
			(xy 103.735907 -273.937984) (xy 103.787681 -273.937984) (xy 103.838819 -273.946083) (xy 103.888059 -273.962082)
			(xy 103.934191 -273.985588) (xy 103.976078 -274.01602) (xy 104.012688 -274.05263) (xy 104.04312 -274.094517)
			(xy 104.066626 -274.140649) (xy 104.082625 -274.189889) (xy 104.090724 -274.241027) (xy 104.091232 -274.266914)
			(xy 104.091232 -274.267422) (xy 104.090643 -274.294938) (xy 104.081456 -274.349199) (xy 104.072944 -274.375372)
			(xy 104.065324 -274.397216) (xy 104.270556 -274.752562) (xy 104.293416 -274.75688) (xy 104.318228 -274.762086)
			(xy 104.366006 -274.779035) (xy 104.410625 -274.803101) (xy 104.451032 -274.833715) (xy 104.486274 -274.870157)
			(xy 104.515519 -274.911566) (xy 104.538078 -274.956966) (xy 104.553418 -275.005285) (xy 104.561177 -275.055382)
			(xy 104.56164 -275.08073) (xy 104.561132 -275.106637) (xy 104.553026 -275.157814) (xy 104.537014 -275.207093)
			(xy 104.513491 -275.25326) (xy 104.483035 -275.295179) (xy 104.446397 -275.331817) (xy 104.404478 -275.362273)
			(xy 104.358311 -275.385796) (xy 104.309032 -275.401808) (xy 104.257855 -275.409914) (xy 104.206041 -275.409914)
			(xy 104.154864 -275.401808) (xy 104.105585 -275.385796) (xy 104.059418 -275.362273) (xy 104.017499 -275.331817)
			(xy 103.980861 -275.295179) (xy 103.950405 -275.25326) (xy 103.926882 -275.207093) (xy 103.91087 -275.157814)
			(xy 103.902764 -275.106637) (xy 103.902256 -275.08073) (xy 103.902854 -275.053013) (xy 103.912174 -274.998366)
			(xy 103.920798 -274.972018) (xy 103.928672 -274.94992) (xy 103.723694 -274.595082) (xy 103.700834 -274.590764)
			(xy 103.676011 -274.585559) (xy 103.628206 -274.568629) (xy 103.583558 -274.544577) (xy 103.543121 -274.51397)
			(xy 103.507847 -274.477532) (xy 103.478571 -274.436121) (xy 103.455983 -274.390715) (xy 103.440615 -274.342385)
			(xy 103.43283 -274.292271) (xy 103.432356 -274.266914) (xy 2.509012 -274.266914) (xy 2.509012 -275.10659)
			(xy 102.023373 -275.10659) (xy 102.023373 -275.05481) (xy 102.031474 -275.003669) (xy 102.047476 -274.954425)
			(xy 102.070985 -274.90829) (xy 102.101423 -274.866402) (xy 102.138039 -274.829791) (xy 102.179931 -274.79936)
			(xy 102.226069 -274.775858) (xy 102.275316 -274.759863) (xy 102.326458 -274.75177) (xy 102.352348 -274.751292)
			(xy 102.377861 -274.751741) (xy 102.428277 -274.759608) (xy 102.476879 -274.775148) (xy 102.522507 -274.79799)
			(xy 102.564072 -274.827588) (xy 102.600581 -274.863235) (xy 102.616254 -274.883372) (xy 103.028242 -274.883372)
			(xy 103.043883 -274.86321) (xy 103.0804 -274.827569) (xy 103.121973 -274.797979) (xy 103.167607 -274.775148)
			(xy 103.216215 -274.75962) (xy 103.266634 -274.751765) (xy 103.292148 -274.751292) (xy 103.318035 -274.751743)
			(xy 103.369171 -274.759849) (xy 103.41841 -274.775854) (xy 103.464539 -274.799364) (xy 103.506423 -274.8298)
			(xy 103.543031 -274.866413) (xy 103.573461 -274.908302) (xy 103.596964 -274.954434) (xy 103.612962 -275.003675)
			(xy 103.62106 -275.054813) (xy 103.62106 -275.106587) (xy 103.612962 -275.157725) (xy 103.596964 -275.206966)
			(xy 103.573461 -275.253098) (xy 103.543031 -275.294987) (xy 103.506423 -275.3316) (xy 103.464539 -275.362036)
			(xy 103.41841 -275.385546) (xy 103.369171 -275.401551) (xy 103.318035 -275.409657) (xy 103.292148 -275.410168)
			(xy 103.266637 -275.409665) (xy 103.216223 -275.401811) (xy 103.167621 -275.386283) (xy 103.121992 -275.363452)
			(xy 103.080426 -275.333862) (xy 103.043916 -275.298222) (xy 103.028242 -275.278088) (xy 102.616254 -275.278088)
			(xy 102.600546 -275.298195) (xy 102.564044 -275.333841) (xy 102.522486 -275.363438) (xy 102.476864 -275.386279)
			(xy 102.428268 -275.401819) (xy 102.377858 -275.409687) (xy 102.352348 -275.410168) (xy 102.326458 -275.40963)
			(xy 102.275316 -275.401537) (xy 102.226069 -275.385542) (xy 102.179931 -275.36204) (xy 102.138039 -275.331609)
			(xy 102.101423 -275.294998) (xy 102.070985 -275.25311) (xy 102.047476 -275.206975) (xy 102.031474 -275.157731)
			(xy 102.023373 -275.10659) (xy 2.509012 -275.10659) (xy 2.509012 -276.708616) (xy 102.022656 -276.708616)
			(xy 102.023189 -276.683284) (xy 102.030938 -276.633215) (xy 102.046256 -276.584922) (xy 102.068781 -276.53954)
			(xy 102.097985 -276.498139) (xy 102.133179 -276.461694) (xy 102.173534 -276.431062) (xy 102.218101 -276.406964)
			(xy 102.265829 -276.389968) (xy 102.290626 -276.384766) (xy 102.313486 -276.380448) (xy 102.518464 -276.025356)
			(xy 102.510844 -276.003512) (xy 102.502285 -275.977153) (xy 102.493085 -275.922508) (xy 102.492556 -275.8948)
			(xy 102.493064 -275.868913) (xy 102.501163 -275.817775) (xy 102.517162 -275.768535) (xy 102.540668 -275.722403)
			(xy 102.5711 -275.680516) (xy 102.60771 -275.643906) (xy 102.649597 -275.613474) (xy 102.695729 -275.589968)
			(xy 102.744969 -275.573969) (xy 102.796107 -275.56587) (xy 102.847881 -275.56587) (xy 102.899019 -275.573969)
			(xy 102.948259 -275.589968) (xy 102.994391 -275.613474) (xy 103.036278 -275.643906) (xy 103.072888 -275.680516)
			(xy 103.10332 -275.722403) (xy 103.126826 -275.768535) (xy 103.142825 -275.817775) (xy 103.150924 -275.868913)
			(xy 103.151432 -275.8948) (xy 104.372156 -275.8948) (xy 104.372675 -275.869467) (xy 104.380426 -275.819398)
			(xy 104.395746 -275.771105) (xy 104.418273 -275.725723) (xy 104.447479 -275.684322) (xy 104.482674 -275.647877)
			(xy 104.523031 -275.617245) (xy 104.567599 -275.593147) (xy 104.615329 -275.576152) (xy 104.640126 -275.57095)
			(xy 104.662986 -275.566632) (xy 104.868218 -275.211286) (xy 104.860598 -275.189188) (xy 104.851972 -275.162906)
			(xy 104.842659 -275.108385) (xy 104.842056 -275.08073) (xy 104.842564 -275.054823) (xy 104.85067 -275.003646)
			(xy 104.866682 -274.954367) (xy 104.890205 -274.9082) (xy 104.920661 -274.866281) (xy 104.957299 -274.829643)
			(xy 104.999218 -274.799187) (xy 105.045385 -274.775664) (xy 105.094664 -274.759652) (xy 105.145841 -274.751546)
			(xy 105.197655 -274.751546) (xy 105.248832 -274.759652) (xy 105.298111 -274.775664) (xy 105.344278 -274.799187)
			(xy 105.386197 -274.829643) (xy 105.422835 -274.866281) (xy 105.453291 -274.9082) (xy 105.476814 -274.954367)
			(xy 105.492826 -275.003646) (xy 105.500932 -275.054823) (xy 105.50144 -275.08073) (xy 107.661456 -275.08073)
			(xy 107.661964 -275.054823) (xy 107.67007 -275.003646) (xy 107.686082 -274.954367) (xy 107.709605 -274.9082)
			(xy 107.740061 -274.866281) (xy 107.776699 -274.829643) (xy 107.818618 -274.799187) (xy 107.864785 -274.775664)
			(xy 107.914064 -274.759652) (xy 107.965241 -274.751546) (xy 108.017055 -274.751546) (xy 108.068232 -274.759652)
			(xy 108.117511 -274.775664) (xy 108.163678 -274.799187) (xy 108.205597 -274.829643) (xy 108.242235 -274.866281)
			(xy 108.272691 -274.9082) (xy 108.296214 -274.954367) (xy 108.312226 -275.003646) (xy 108.320332 -275.054823)
			(xy 108.32084 -275.08073) (xy 108.320273 -275.106588) (xy 349.963473 -275.106588) (xy 349.963473 -275.054812)
			(xy 349.971573 -275.003674) (xy 349.987573 -274.954432) (xy 350.011079 -274.9083) (xy 350.041513 -274.866413)
			(xy 350.078125 -274.829803) (xy 350.120014 -274.799371) (xy 350.166147 -274.775867) (xy 350.215389 -274.759869)
			(xy 350.266528 -274.751772) (xy 350.292416 -274.751292) (xy 350.317928 -274.751764) (xy 350.368343 -274.759627)
			(xy 350.416945 -274.775162) (xy 350.462573 -274.797999) (xy 350.504138 -274.827593) (xy 350.540648 -274.863237)
			(xy 350.556322 -274.883372) (xy 350.96831 -274.883372) (xy 350.98397 -274.863226) (xy 351.020483 -274.827584)
			(xy 351.062052 -274.797992) (xy 351.107683 -274.775158) (xy 351.156287 -274.759626) (xy 351.206703 -274.751768)
			(xy 351.232216 -274.751292) (xy 351.258105 -274.751741) (xy 351.309245 -274.759843) (xy 351.358488 -274.775845)
			(xy 351.404622 -274.799353) (xy 351.44651 -274.829789) (xy 351.483122 -274.866402) (xy 351.513555 -274.908292)
			(xy 351.537061 -274.954427) (xy 351.553061 -275.003671) (xy 351.56116 -275.054811) (xy 351.56116 -275.106589)
			(xy 351.553061 -275.157729) (xy 351.537061 -275.206973) (xy 351.513555 -275.253108) (xy 351.483122 -275.294998)
			(xy 351.44651 -275.331611) (xy 351.404622 -275.362047) (xy 351.358488 -275.385555) (xy 351.309245 -275.401557)
			(xy 351.258105 -275.409659) (xy 351.232216 -275.410168) (xy 351.206704 -275.409689) (xy 351.156289 -275.401829)
			(xy 351.107687 -275.386297) (xy 351.062058 -275.363461) (xy 351.020493 -275.333868) (xy 350.983983 -275.298224)
			(xy 350.96831 -275.278088) (xy 350.556322 -275.278088) (xy 350.540633 -275.29821) (xy 350.504126 -275.333856)
			(xy 350.462565 -275.363451) (xy 350.416939 -275.386289) (xy 350.36834 -275.401826) (xy 350.317927 -275.409689)
			(xy 350.292416 -275.410168) (xy 350.266528 -275.409628) (xy 350.215389 -275.401531) (xy 350.166147 -275.385533)
			(xy 350.120014 -275.362029) (xy 350.078125 -275.331597) (xy 350.041513 -275.294987) (xy 350.011079 -275.2531)
			(xy 349.987573 -275.206968) (xy 349.971573 -275.157726) (xy 349.963473 -275.106588) (xy 108.320273 -275.106588)
			(xy 108.320232 -275.108447) (xy 108.310918 -275.163093) (xy 108.302298 -275.189442) (xy 108.294424 -275.21154)
			(xy 108.499656 -275.566632) (xy 108.522516 -275.57095) (xy 108.547321 -275.576185) (xy 108.595097 -275.593131)
			(xy 108.639715 -275.617194) (xy 108.680121 -275.647805) (xy 108.715363 -275.684244) (xy 108.744609 -275.725649)
			(xy 108.767169 -275.771044) (xy 108.782512 -275.819359) (xy 108.790275 -275.869454) (xy 108.79074 -275.8948)
			(xy 108.790232 -275.920707) (xy 108.782126 -275.971884) (xy 108.766114 -276.021163) (xy 108.742591 -276.06733)
			(xy 108.712135 -276.109249) (xy 108.675497 -276.145887) (xy 108.633578 -276.176343) (xy 108.587411 -276.199866)
			(xy 108.538132 -276.215878) (xy 108.486955 -276.223984) (xy 108.435141 -276.223984) (xy 108.383964 -276.215878)
			(xy 108.334685 -276.199866) (xy 108.288518 -276.176343) (xy 108.246599 -276.145887) (xy 108.209961 -276.109249)
			(xy 108.179505 -276.06733) (xy 108.155982 -276.021163) (xy 108.13997 -275.971884) (xy 108.131864 -275.920707)
			(xy 108.131356 -275.8948) (xy 108.131947 -275.867082) (xy 108.141272 -275.812436) (xy 108.149898 -275.786088)
			(xy 108.157772 -275.76399) (xy 107.95254 -275.408898) (xy 107.92968 -275.40458) (xy 107.904858 -275.399414)
			(xy 107.857077 -275.382462) (xy 107.812456 -275.358392) (xy 107.772048 -275.327773) (xy 107.736806 -275.291325)
			(xy 107.707562 -275.249911) (xy 107.685006 -275.204506) (xy 107.66967 -275.156182) (xy 107.661916 -275.10608)
			(xy 107.661456 -275.08073) (xy 105.50144 -275.08073) (xy 105.500998 -275.106094) (xy 105.493245 -275.156227)
			(xy 105.477898 -275.204578) (xy 105.455318 -275.250004) (xy 105.42604 -275.291431) (xy 105.390756 -275.327878)
			(xy 105.350301 -275.358484) (xy 105.305631 -275.382526) (xy 105.257803 -275.399433) (xy 105.232962 -275.40458)
			(xy 105.209848 -275.408898) (xy 105.00487 -275.76399) (xy 105.012744 -275.786088) (xy 105.021303 -275.812447)
			(xy 105.030503 -275.867092) (xy 105.031032 -275.8948) (xy 105.030524 -275.920687) (xy 105.030521 -275.920707)
			(xy 106.252016 -275.920707) (xy 106.252016 -275.868893) (xy 106.260122 -275.817717) (xy 106.276133 -275.768439)
			(xy 106.299656 -275.722272) (xy 106.330111 -275.680353) (xy 106.366749 -275.643715) (xy 106.408667 -275.613259)
			(xy 106.454833 -275.589735) (xy 106.504111 -275.573723) (xy 106.555287 -275.565617) (xy 106.581194 -275.565108)
			(xy 106.606706 -275.56559) (xy 106.65712 -275.57345) (xy 106.705722 -275.588983) (xy 106.75135 -275.611818)
			(xy 106.792916 -275.64141) (xy 106.829426 -275.677053) (xy 106.8451 -275.697188) (xy 107.257088 -275.697188)
			(xy 107.272765 -275.677056) (xy 107.309275 -275.641412) (xy 107.350839 -275.611819) (xy 107.396467 -275.588982)
			(xy 107.445068 -275.573448) (xy 107.495482 -275.565586) (xy 107.520994 -275.565108) (xy 107.546904 -275.565589)
			(xy 107.598085 -275.573695) (xy 107.647369 -275.589707) (xy 107.693541 -275.613232) (xy 107.735464 -275.64369)
			(xy 107.772106 -275.680332) (xy 107.802565 -275.722254) (xy 107.826091 -275.768426) (xy 107.842104 -275.817709)
			(xy 107.85021 -275.86889) (xy 107.85021 -275.92071) (xy 107.842104 -275.971891) (xy 107.826091 -276.021174)
			(xy 107.802565 -276.067346) (xy 107.772106 -276.109268) (xy 107.735464 -276.14591) (xy 107.693541 -276.176368)
			(xy 107.647369 -276.199893) (xy 107.598085 -276.215905) (xy 107.546904 -276.224011) (xy 107.520994 -276.224492)
			(xy 107.495482 -276.224019) (xy 107.445067 -276.216157) (xy 107.396465 -276.200622) (xy 107.350837 -276.177785)
			(xy 107.309271 -276.148192) (xy 107.272762 -276.112547) (xy 107.257088 -276.092412) (xy 106.8451 -276.092412)
			(xy 106.82943 -276.11255) (xy 106.792919 -276.148193) (xy 106.751353 -276.177786) (xy 106.705724 -276.200622)
			(xy 106.657121 -276.216155) (xy 106.606706 -276.224015) (xy 106.581194 -276.224492) (xy 106.555287 -276.223983)
			(xy 106.504111 -276.215877) (xy 106.454833 -276.199865) (xy 106.408667 -276.176341) (xy 106.366749 -276.145885)
			(xy 106.330111 -276.109247) (xy 106.299656 -276.067328) (xy 106.276133 -276.021161) (xy 106.260122 -275.971883)
			(xy 106.252016 -275.920707) (xy 105.030521 -275.920707) (xy 105.022425 -275.971825) (xy 105.006426 -276.021065)
			(xy 104.98292 -276.067197) (xy 104.952488 -276.109084) (xy 104.915878 -276.145694) (xy 104.873991 -276.176126)
			(xy 104.827859 -276.199632) (xy 104.778619 -276.215631) (xy 104.727481 -276.22373) (xy 104.675707 -276.22373)
			(xy 104.624569 -276.215631) (xy 104.575329 -276.199632) (xy 104.529197 -276.176126) (xy 104.48731 -276.145694)
			(xy 104.4507 -276.109084) (xy 104.420268 -276.067197) (xy 104.396762 -276.021065) (xy 104.380763 -275.971825)
			(xy 104.372664 -275.920687) (xy 104.372156 -275.8948) (xy 103.151432 -275.8948) (xy 103.150966 -275.920146)
			(xy 103.143192 -275.97024) (xy 103.127843 -276.018553) (xy 103.105281 -276.063948) (xy 103.076038 -276.105356)
			(xy 103.040801 -276.1418) (xy 103.000402 -276.172421) (xy 102.955792 -276.196499) (xy 102.908023 -276.213466)
			(xy 102.883208 -276.21865) (xy 102.860348 -276.222968) (xy 102.65537 -276.577806) (xy 102.663244 -276.599904)
			(xy 102.671807 -276.626262) (xy 102.681004 -276.680908) (xy 102.681532 -276.708616) (xy 102.962456 -276.708616)
			(xy 102.962964 -276.682709) (xy 102.97107 -276.631532) (xy 102.987082 -276.582253) (xy 103.010605 -276.536086)
			(xy 103.041061 -276.494167) (xy 103.077699 -276.457529) (xy 103.119618 -276.427073) (xy 103.165785 -276.40355)
			(xy 103.215064 -276.387538) (xy 103.266241 -276.379432) (xy 103.318055 -276.379432) (xy 103.369232 -276.387538)
			(xy 103.418511 -276.40355) (xy 103.464678 -276.427073) (xy 103.506597 -276.457529) (xy 103.543235 -276.494167)
			(xy 103.573691 -276.536086) (xy 103.597214 -276.582253) (xy 103.613226 -276.631532) (xy 103.621332 -276.682709)
			(xy 103.62184 -276.708616) (xy 103.621308 -276.734511) (xy 103.902706 -276.734511) (xy 103.902706 -276.682689)
			(xy 103.910813 -276.631506) (xy 103.926828 -276.582222) (xy 103.950356 -276.53605) (xy 103.980818 -276.494128)
			(xy 104.017464 -276.457487) (xy 104.059391 -276.427031) (xy 104.105566 -276.40351) (xy 104.154853 -276.387502)
			(xy 104.206037 -276.379402) (xy 104.231948 -276.378924) (xy 104.257462 -276.37936) (xy 104.307879 -276.387228)
			(xy 104.356482 -276.40277) (xy 104.40211 -276.425614) (xy 104.443674 -276.455215) (xy 104.480182 -276.490865)
			(xy 104.495854 -276.511004) (xy 104.907842 -276.511004) (xy 104.923492 -276.490849) (xy 104.960006 -276.455206)
			(xy 105.001577 -276.425615) (xy 105.04721 -276.402782) (xy 105.095816 -276.387253) (xy 105.146235 -276.379398)
			(xy 105.171748 -276.378924) (xy 105.197654 -276.379404) (xy 105.248828 -276.387515) (xy 105.298102 -276.403532)
			(xy 105.344265 -276.427059) (xy 105.38618 -276.457517) (xy 105.422814 -276.494157) (xy 105.453266 -276.536076)
			(xy 105.476786 -276.582242) (xy 105.492796 -276.631519) (xy 105.5009 -276.682694) (xy 105.5009 -276.734506)
			(xy 105.492796 -276.785681) (xy 105.476786 -276.834958) (xy 105.453266 -276.881124) (xy 105.422814 -276.923043)
			(xy 105.38618 -276.959683) (xy 105.344265 -276.990141) (xy 105.298102 -277.013668) (xy 105.248828 -277.029685)
			(xy 105.197654 -277.037796) (xy 105.171748 -277.038308) (xy 105.146238 -277.037789) (xy 105.095825 -277.029936)
			(xy 105.047224 -277.01441) (xy 105.001596 -276.991582) (xy 104.960029 -276.961996) (xy 104.923517 -276.92636)
			(xy 104.907842 -276.906228) (xy 104.495854 -276.906228) (xy 104.480157 -276.926344) (xy 104.443651 -276.961988)
			(xy 104.40209 -276.991583) (xy 104.356467 -277.014422) (xy 104.307869 -277.029961) (xy 104.257458 -277.037827)
			(xy 104.231948 -277.038308) (xy 104.206037 -277.037798) (xy 104.154853 -277.029698) (xy 104.105566 -277.01369)
			(xy 104.059391 -276.990169) (xy 104.017464 -276.959713) (xy 103.980818 -276.923072) (xy 103.950356 -276.88115)
			(xy 103.926828 -276.834978) (xy 103.910813 -276.785694) (xy 103.902706 -276.734511) (xy 103.621308 -276.734511)
			(xy 103.621269 -276.736398) (xy 103.611945 -276.791174) (xy 103.603298 -276.817582) (xy 103.595424 -276.839426)
			(xy 103.800402 -277.194264) (xy 103.823262 -277.198582) (xy 103.848063 -277.203782) (xy 103.895803 -277.220766)
			(xy 103.940382 -277.244857) (xy 103.98075 -277.275485) (xy 104.015954 -277.311931) (xy 104.045167 -277.353334)
			(xy 104.067699 -277.398721) (xy 104.083021 -277.44702) (xy 104.09077 -277.497096) (xy 104.091232 -277.522432)
			(xy 106.251756 -277.522432) (xy 106.252213 -277.497097) (xy 106.259974 -277.447026) (xy 106.275303 -277.39873)
			(xy 106.297839 -277.353349) (xy 106.327053 -277.311948) (xy 106.362255 -277.275504) (xy 106.402618 -277.244873)
			(xy 106.447192 -277.220777) (xy 106.494926 -277.203783) (xy 106.519726 -277.198582) (xy 106.542586 -277.194264)
			(xy 106.747818 -276.838918) (xy 106.740198 -276.817074) (xy 106.731593 -276.790786) (xy 106.722266 -276.736269)
			(xy 106.721656 -276.708616) (xy 106.722164 -276.682709) (xy 106.73027 -276.631532) (xy 106.746282 -276.582253)
			(xy 106.769805 -276.536086) (xy 106.800261 -276.494167) (xy 106.836899 -276.457529) (xy 106.878818 -276.427073)
			(xy 106.924985 -276.40355) (xy 106.974264 -276.387538) (xy 107.025441 -276.379432) (xy 107.077255 -276.379432)
			(xy 107.128432 -276.387538) (xy 107.177711 -276.40355) (xy 107.223878 -276.427073) (xy 107.265797 -276.457529)
			(xy 107.302435 -276.494167) (xy 107.332891 -276.536086) (xy 107.356414 -276.582253) (xy 107.372426 -276.631532)
			(xy 107.380532 -276.682709) (xy 107.38104 -276.708616) (xy 108.601256 -276.708616) (xy 108.601789 -276.683284)
			(xy 108.609538 -276.633215) (xy 108.624856 -276.584922) (xy 108.647381 -276.53954) (xy 108.676585 -276.498139)
			(xy 108.711779 -276.461694) (xy 108.752134 -276.431062) (xy 108.796701 -276.406964) (xy 108.844429 -276.389968)
			(xy 108.869226 -276.384766) (xy 108.892086 -276.380448) (xy 109.097064 -276.02561) (xy 109.08919 -276.003766)
			(xy 109.080545 -275.977358) (xy 109.071224 -275.922582) (xy 109.070648 -275.8948) (xy 109.071156 -275.868893)
			(xy 109.079262 -275.817716) (xy 109.095274 -275.768437) (xy 109.118797 -275.72227) (xy 109.149253 -275.680351)
			(xy 109.185891 -275.643713) (xy 109.22781 -275.613257) (xy 109.273977 -275.589734) (xy 109.323256 -275.573722)
			(xy 109.374433 -275.565616) (xy 109.426247 -275.565616) (xy 109.477424 -275.573722) (xy 109.526703 -275.589734)
			(xy 109.57287 -275.613257) (xy 109.614789 -275.643713) (xy 109.651427 -275.680351) (xy 109.681883 -275.72227)
			(xy 109.705406 -275.768437) (xy 109.721418 -275.817716) (xy 109.729524 -275.868893) (xy 109.730032 -275.8948)
			(xy 109.729566 -275.920146) (xy 109.721792 -275.97024) (xy 109.706443 -276.018553) (xy 109.683881 -276.063948)
			(xy 109.654638 -276.105356) (xy 109.619401 -276.1418) (xy 109.579002 -276.172421) (xy 109.534392 -276.196499)
			(xy 109.486623 -276.213466) (xy 109.461808 -276.21865) (xy 109.438948 -276.222968) (xy 109.23397 -276.577806)
			(xy 109.241844 -276.599904) (xy 109.250407 -276.626262) (xy 109.259604 -276.680908) (xy 109.260132 -276.708616)
			(xy 349.962724 -276.708616) (xy 349.963202 -276.683281) (xy 349.970953 -276.633207) (xy 349.986274 -276.584909)
			(xy 350.008806 -276.539525) (xy 350.038016 -276.498122) (xy 350.073218 -276.461676) (xy 350.113581 -276.431046)
			(xy 350.158157 -276.406953) (xy 350.205894 -276.389964) (xy 350.230694 -276.384766) (xy 350.253554 -276.380448)
			(xy 350.458532 -276.025356) (xy 350.450912 -276.003512) (xy 350.442352 -275.977154) (xy 350.433153 -275.922508)
			(xy 350.432624 -275.8948) (xy 350.433132 -275.868913) (xy 350.441231 -275.817775) (xy 350.45723 -275.768535)
			(xy 350.480736 -275.722403) (xy 350.511168 -275.680516) (xy 350.547778 -275.643906) (xy 350.589665 -275.613474)
			(xy 350.635797 -275.589968) (xy 350.685037 -275.573969) (xy 350.736175 -275.56587) (xy 350.787949 -275.56587)
			(xy 350.839087 -275.573969) (xy 350.888327 -275.589968) (xy 350.934459 -275.613474) (xy 350.976346 -275.643906)
			(xy 351.012956 -275.680516) (xy 351.043388 -275.722403) (xy 351.066894 -275.768535) (xy 351.082893 -275.817775)
			(xy 351.090992 -275.868913) (xy 351.0915 -275.8948) (xy 352.312224 -275.8948) (xy 352.312688 -275.869465)
			(xy 352.320441 -275.81939) (xy 352.335764 -275.771092) (xy 352.358298 -275.725707) (xy 352.38751 -275.684304)
			(xy 352.422713 -275.647859) (xy 352.463078 -275.617229) (xy 352.507655 -275.593136) (xy 352.555393 -275.576148)
			(xy 352.580194 -275.57095) (xy 352.603054 -275.566632) (xy 352.808286 -275.211286) (xy 352.800666 -275.189188)
			(xy 352.792042 -275.162906) (xy 352.782727 -275.108385) (xy 352.782124 -275.08073) (xy 352.782632 -275.054823)
			(xy 352.790738 -275.003646) (xy 352.80675 -274.954367) (xy 352.830273 -274.9082) (xy 352.860729 -274.866281)
			(xy 352.897367 -274.829643) (xy 352.939286 -274.799187) (xy 352.985453 -274.775664) (xy 353.034732 -274.759652)
			(xy 353.085909 -274.751546) (xy 353.137723 -274.751546) (xy 353.1889 -274.759652) (xy 353.238179 -274.775664)
			(xy 353.284346 -274.799187) (xy 353.326265 -274.829643) (xy 353.362903 -274.866281) (xy 353.393359 -274.9082)
			(xy 353.416882 -274.954367) (xy 353.432894 -275.003646) (xy 353.441 -275.054823) (xy 353.441508 -275.08073)
			(xy 355.601524 -275.08073) (xy 355.602032 -275.054823) (xy 355.610138 -275.003646) (xy 355.62615 -274.954367)
			(xy 355.649673 -274.9082) (xy 355.680129 -274.866281) (xy 355.716767 -274.829643) (xy 355.758686 -274.799187)
			(xy 355.804853 -274.775664) (xy 355.854132 -274.759652) (xy 355.905309 -274.751546) (xy 355.957123 -274.751546)
			(xy 356.0083 -274.759652) (xy 356.057579 -274.775664) (xy 356.103746 -274.799187) (xy 356.145665 -274.829643)
			(xy 356.182303 -274.866281) (xy 356.212759 -274.9082) (xy 356.236282 -274.954367) (xy 356.252294 -275.003646)
			(xy 356.2604 -275.054823) (xy 356.260908 -275.08073) (xy 356.260296 -275.108446) (xy 356.250985 -275.163093)
			(xy 356.242366 -275.189442) (xy 356.234492 -275.21154) (xy 356.439724 -275.566632) (xy 356.462584 -275.57095)
			(xy 356.4874 -275.576135) (xy 356.535176 -275.593092) (xy 356.579792 -275.617163) (xy 356.620197 -275.647782)
			(xy 356.655436 -275.684226) (xy 356.684681 -275.725636) (xy 356.707239 -275.771036) (xy 356.722581 -275.819355)
			(xy 356.730343 -275.869452) (xy 356.730808 -275.8948) (xy 356.7303 -275.920707) (xy 356.722194 -275.971884)
			(xy 356.706182 -276.021163) (xy 356.682659 -276.06733) (xy 356.652203 -276.109249) (xy 356.615565 -276.145887)
			(xy 356.573646 -276.176343) (xy 356.527479 -276.199866) (xy 356.4782 -276.215878) (xy 356.427023 -276.223984)
			(xy 356.375209 -276.223984) (xy 356.324032 -276.215878) (xy 356.274753 -276.199866) (xy 356.228586 -276.176343)
			(xy 356.186667 -276.145887) (xy 356.150029 -276.109249) (xy 356.119573 -276.06733) (xy 356.09605 -276.021163)
			(xy 356.080038 -275.971884) (xy 356.071932 -275.920707) (xy 356.071424 -275.8948) (xy 356.072017 -275.867083)
			(xy 356.081341 -275.812436) (xy 356.089966 -275.786088) (xy 356.09784 -275.76399) (xy 355.892608 -275.408898)
			(xy 355.869748 -275.40458) (xy 355.844921 -275.399437) (xy 355.79714 -275.382481) (xy 355.75252 -275.358407)
			(xy 355.712113 -275.327784) (xy 355.676872 -275.291334) (xy 355.647629 -275.249917) (xy 355.625073 -275.20451)
			(xy 355.609738 -275.156184) (xy 355.601984 -275.10608) (xy 355.601524 -275.08073) (xy 353.441508 -275.08073)
			(xy 353.441092 -275.106096) (xy 353.433338 -275.156231) (xy 353.417989 -275.204584) (xy 353.395406 -275.250011)
			(xy 353.366125 -275.291439) (xy 353.330837 -275.327886) (xy 353.290378 -275.358492) (xy 353.245704 -275.382531)
			(xy 353.197873 -275.399435) (xy 353.17303 -275.40458) (xy 353.149916 -275.408898) (xy 352.944938 -275.76399)
			(xy 352.952812 -275.786088) (xy 352.96137 -275.812447) (xy 352.97057 -275.867092) (xy 352.9711 -275.8948)
			(xy 352.970592 -275.920687) (xy 352.970589 -275.920705) (xy 354.192116 -275.920705) (xy 354.192116 -275.868895)
			(xy 354.200221 -275.817722) (xy 354.21623 -275.768446) (xy 354.23975 -275.722282) (xy 354.270202 -275.680364)
			(xy 354.306835 -275.643726) (xy 354.348749 -275.61327) (xy 354.394911 -275.589745) (xy 354.444185 -275.57373)
			(xy 354.495357 -275.565619) (xy 354.521262 -275.565108) (xy 354.546773 -275.565613) (xy 354.597186 -275.573468)
			(xy 354.645788 -275.588996) (xy 354.691416 -275.611827) (xy 354.732982 -275.641416) (xy 354.769494 -275.677055)
			(xy 354.785168 -275.697188) (xy 355.197156 -275.697188) (xy 355.212852 -275.677071) (xy 355.249357 -275.641427)
			(xy 355.290918 -275.611831) (xy 355.336542 -275.588992) (xy 355.38514 -275.573454) (xy 355.435551 -275.565588)
			(xy 355.461062 -275.565108) (xy 355.486973 -275.565587) (xy 355.538159 -275.573688) (xy 355.587447 -275.589698)
			(xy 355.633623 -275.613221) (xy 355.67555 -275.643679) (xy 355.712197 -275.680321) (xy 355.742659 -275.722245)
			(xy 355.766188 -275.768418) (xy 355.782203 -275.817704) (xy 355.79031 -275.868889) (xy 355.79031 -275.920711)
			(xy 355.782203 -275.971896) (xy 355.766188 -276.021182) (xy 355.742659 -276.067355) (xy 355.712197 -276.109279)
			(xy 355.67555 -276.145921) (xy 355.633623 -276.176379) (xy 355.587447 -276.199902) (xy 355.538159 -276.215912)
			(xy 355.486973 -276.224013) (xy 355.461062 -276.224492) (xy 355.435549 -276.224043) (xy 355.385133 -276.216176)
			(xy 355.336531 -276.200636) (xy 355.290902 -276.177795) (xy 355.249337 -276.148197) (xy 355.212829 -276.112549)
			(xy 355.197156 -276.092412) (xy 354.785168 -276.092412) (xy 354.769516 -276.112565) (xy 354.733002 -276.148208)
			(xy 354.691432 -276.177799) (xy 354.645799 -276.200632) (xy 354.597193 -276.216162) (xy 354.546775 -276.224017)
			(xy 354.521262 -276.224492) (xy 354.495357 -276.223981) (xy 354.444185 -276.21587) (xy 354.394911 -276.199855)
			(xy 354.348749 -276.17633) (xy 354.306835 -276.145874) (xy 354.270202 -276.109236) (xy 354.23975 -276.067318)
			(xy 354.21623 -276.021154) (xy 354.200221 -275.971878) (xy 354.192116 -275.920705) (xy 352.970589 -275.920705)
			(xy 352.962493 -275.971825) (xy 352.946494 -276.021065) (xy 352.922988 -276.067197) (xy 352.892556 -276.109084)
			(xy 352.855946 -276.145694) (xy 352.814059 -276.176126) (xy 352.767927 -276.199632) (xy 352.718687 -276.215631)
			(xy 352.667549 -276.22373) (xy 352.615775 -276.22373) (xy 352.564637 -276.215631) (xy 352.515397 -276.199632)
			(xy 352.469265 -276.176126) (xy 352.427378 -276.145694) (xy 352.390768 -276.109084) (xy 352.360336 -276.067197)
			(xy 352.33683 -276.021065) (xy 352.320831 -275.971825) (xy 352.312732 -275.920687) (xy 352.312224 -275.8948)
			(xy 351.0915 -275.8948) (xy 351.090979 -275.920144) (xy 351.083207 -275.970232) (xy 351.067862 -276.018541)
			(xy 351.045306 -276.063932) (xy 351.016069 -276.105338) (xy 350.98084 -276.141782) (xy 350.940449 -276.172406)
			(xy 350.895848 -276.196488) (xy 350.848087 -276.213462) (xy 350.823276 -276.21865) (xy 350.800416 -276.222968)
			(xy 350.595438 -276.577806) (xy 350.603312 -276.599904) (xy 350.611874 -276.626262) (xy 350.621072 -276.680908)
			(xy 350.6216 -276.708616) (xy 350.902524 -276.708616) (xy 350.903032 -276.682709) (xy 350.911138 -276.631532)
			(xy 350.92715 -276.582253) (xy 350.950673 -276.536086) (xy 350.981129 -276.494167) (xy 351.017767 -276.457529)
			(xy 351.059686 -276.427073) (xy 351.105853 -276.40355) (xy 351.155132 -276.387538) (xy 351.206309 -276.379432)
			(xy 351.258123 -276.379432) (xy 351.3093 -276.387538) (xy 351.358579 -276.40355) (xy 351.404746 -276.427073)
			(xy 351.446665 -276.457529) (xy 351.483303 -276.494167) (xy 351.513759 -276.536086) (xy 351.537282 -276.582253)
			(xy 351.553294 -276.631532) (xy 351.5614 -276.682709) (xy 351.561908 -276.708616) (xy 351.561377 -276.734509)
			(xy 351.842805 -276.734509) (xy 351.842805 -276.682691) (xy 351.850912 -276.631511) (xy 351.866925 -276.582229)
			(xy 351.89045 -276.53606) (xy 351.920909 -276.494139) (xy 351.957551 -276.457499) (xy 351.999473 -276.427042)
			(xy 352.045644 -276.403519) (xy 352.094927 -276.387508) (xy 352.146107 -276.379404) (xy 352.172016 -276.378924)
			(xy 352.197529 -276.379383) (xy 352.247945 -276.387247) (xy 352.296547 -276.402784) (xy 352.342175 -276.425624)
			(xy 352.38374 -276.45522) (xy 352.420249 -276.490867) (xy 352.435922 -276.511004) (xy 352.84791 -276.511004)
			(xy 352.863579 -276.490865) (xy 352.900089 -276.455221) (xy 352.941656 -276.425628) (xy 352.987285 -276.402792)
			(xy 353.035888 -276.387259) (xy 353.086304 -276.3794) (xy 353.111816 -276.378924) (xy 353.137724 -276.379401)
			(xy 353.188901 -276.387509) (xy 353.23818 -276.403523) (xy 353.284347 -276.427048) (xy 353.326266 -276.457506)
			(xy 353.362904 -276.494146) (xy 353.39336 -276.536066) (xy 353.416883 -276.582235) (xy 353.432895 -276.631514)
			(xy 353.441 -276.682692) (xy 353.441 -276.734508) (xy 353.432895 -276.785686) (xy 353.416883 -276.834965)
			(xy 353.39336 -276.881134) (xy 353.362904 -276.923054) (xy 353.326266 -276.959694) (xy 353.284347 -276.990152)
			(xy 353.23818 -277.013677) (xy 353.188901 -277.029691) (xy 353.137724 -277.037799) (xy 353.111816 -277.038308)
			(xy 353.086305 -277.037813) (xy 353.035891 -277.029955) (xy 352.98729 -277.014424) (xy 352.941662 -276.991591)
			(xy 352.900096 -276.962001) (xy 352.863585 -276.926361) (xy 352.84791 -276.906228) (xy 352.435922 -276.906228)
			(xy 352.420244 -276.926359) (xy 352.383734 -276.962002) (xy 352.342169 -276.991595) (xy 352.296542 -277.014432)
			(xy 352.247941 -277.029967) (xy 352.197528 -277.03783) (xy 352.172016 -277.038308) (xy 352.146107 -277.037796)
			(xy 352.094927 -277.029692) (xy 352.045644 -277.013681) (xy 351.999473 -276.990158) (xy 351.957551 -276.959701)
			(xy 351.920909 -276.923061) (xy 351.89045 -276.88114) (xy 351.866925 -276.834971) (xy 351.850912 -276.785689)
			(xy 351.842805 -276.734509) (xy 351.561377 -276.734509) (xy 351.561338 -276.736398) (xy 351.552014 -276.791174)
			(xy 351.543366 -276.817582) (xy 351.535492 -276.839426) (xy 351.74047 -277.194264) (xy 351.76333 -277.198582)
			(xy 351.788142 -277.203733) (xy 351.835882 -277.220727) (xy 351.88046 -277.244826) (xy 351.920825 -277.275462)
			(xy 351.956028 -277.311913) (xy 351.985239 -277.353322) (xy 352.007769 -277.398712) (xy 352.02309 -277.447016)
			(xy 352.030838 -277.497095) (xy 352.0313 -277.522432) (xy 354.191824 -277.522432) (xy 354.192226 -277.497095)
			(xy 354.199989 -277.447018) (xy 354.215322 -277.398718) (xy 354.237864 -277.353333) (xy 354.267084 -277.31193)
			(xy 354.302294 -277.275486) (xy 354.342666 -277.244857) (xy 354.387248 -277.220766) (xy 354.434991 -277.203779)
			(xy 354.459794 -277.198582) (xy 354.482654 -277.194264) (xy 354.687886 -276.838918) (xy 354.680266 -276.817074)
			(xy 354.671663 -276.790785) (xy 354.662334 -276.736269) (xy 354.661724 -276.708616) (xy 354.662232 -276.682709)
			(xy 354.670338 -276.631532) (xy 354.68635 -276.582253) (xy 354.709873 -276.536086) (xy 354.740329 -276.494167)
			(xy 354.776967 -276.457529) (xy 354.818886 -276.427073) (xy 354.865053 -276.40355) (xy 354.914332 -276.387538)
			(xy 354.965509 -276.379432) (xy 355.017323 -276.379432) (xy 355.0685 -276.387538) (xy 355.117779 -276.40355)
			(xy 355.163946 -276.427073) (xy 355.205865 -276.457529) (xy 355.242503 -276.494167) (xy 355.272959 -276.536086)
			(xy 355.296482 -276.582253) (xy 355.312494 -276.631532) (xy 355.3206 -276.682709) (xy 355.321108 -276.708616)
			(xy 356.541324 -276.708616) (xy 356.541802 -276.683281) (xy 356.549553 -276.633207) (xy 356.564874 -276.584909)
			(xy 356.587406 -276.539525) (xy 356.616616 -276.498122) (xy 356.651818 -276.461676) (xy 356.692181 -276.431046)
			(xy 356.736757 -276.406953) (xy 356.784494 -276.389964) (xy 356.809294 -276.384766) (xy 356.832154 -276.380448)
			(xy 357.037132 -276.02561) (xy 357.029258 -276.003766) (xy 357.020612 -275.977358) (xy 357.011292 -275.922582)
			(xy 357.010716 -275.8948) (xy 357.011224 -275.868893) (xy 357.01933 -275.817716) (xy 357.035342 -275.768437)
			(xy 357.058865 -275.72227) (xy 357.089321 -275.680351) (xy 357.125959 -275.643713) (xy 357.167878 -275.613257)
			(xy 357.214045 -275.589734) (xy 357.263324 -275.573722) (xy 357.314501 -275.565616) (xy 357.366315 -275.565616)
			(xy 357.417492 -275.573722) (xy 357.466771 -275.589734) (xy 357.512938 -275.613257) (xy 357.554857 -275.643713)
			(xy 357.591495 -275.680351) (xy 357.621951 -275.72227) (xy 357.645474 -275.768437) (xy 357.661486 -275.817716)
			(xy 357.669592 -275.868893) (xy 357.6701 -275.8948) (xy 357.669579 -275.920144) (xy 357.661807 -275.970232)
			(xy 357.646462 -276.018541) (xy 357.623906 -276.063932) (xy 357.594669 -276.105338) (xy 357.55944 -276.141782)
			(xy 357.519049 -276.172406) (xy 357.474448 -276.196488) (xy 357.426687 -276.213462) (xy 357.401876 -276.21865)
			(xy 357.379016 -276.222968) (xy 357.174038 -276.577806) (xy 357.181912 -276.599904) (xy 357.190474 -276.626262)
			(xy 357.199672 -276.680908) (xy 357.2002 -276.708616) (xy 357.199692 -276.734503) (xy 357.191593 -276.785641)
			(xy 357.175594 -276.834881) (xy 357.152088 -276.881013) (xy 357.121656 -276.9229) (xy 357.085046 -276.95951)
			(xy 357.043159 -276.989942) (xy 356.997027 -277.013448) (xy 356.947787 -277.029447) (xy 356.896649 -277.037546)
			(xy 356.844875 -277.037546) (xy 356.793737 -277.029447) (xy 356.744497 -277.013448) (xy 356.698365 -276.989942)
			(xy 356.656478 -276.95951) (xy 356.619868 -276.9229) (xy 356.589436 -276.881013) (xy 356.56593 -276.834881)
			(xy 356.549931 -276.785641) (xy 356.541832 -276.734503) (xy 356.541324 -276.708616) (xy 355.321108 -276.708616)
			(xy 355.320641 -276.73399) (xy 355.312871 -276.784141) (xy 355.297501 -276.832506) (xy 355.274895 -276.877942)
			(xy 355.245588 -276.919373) (xy 355.210273 -276.955819) (xy 355.169787 -276.986418) (xy 355.125087 -277.010445)
			(xy 355.07723 -277.027332) (xy 355.052376 -277.032466) (xy 355.029516 -277.036784) (xy 354.824538 -277.391622)
			(xy 354.832412 -277.41372) (xy 354.840977 -277.440077) (xy 354.850173 -277.494724) (xy 354.8507 -277.522432)
			(xy 355.131624 -277.522432) (xy 355.132132 -277.496545) (xy 355.140231 -277.445407) (xy 355.15623 -277.396167)
			(xy 355.179736 -277.350035) (xy 355.210168 -277.308148) (xy 355.246778 -277.271538) (xy 355.288665 -277.241106)
			(xy 355.334797 -277.2176) (xy 355.384037 -277.201601) (xy 355.435175 -277.193502) (xy 355.486949 -277.193502)
			(xy 355.538087 -277.201601) (xy 355.587327 -277.2176) (xy 355.633459 -277.241106) (xy 355.675346 -277.271538)
			(xy 355.711956 -277.308148) (xy 355.742388 -277.350035) (xy 355.765894 -277.396167) (xy 355.781893 -277.445407)
			(xy 355.789992 -277.496545) (xy 355.7905 -277.522432) (xy 355.7905 -277.52294) (xy 355.789963 -277.548303)
			(xy 356.071748 -277.548303) (xy 356.071748 -277.496497) (xy 356.079852 -277.445329) (xy 356.09586 -277.396058)
			(xy 356.119377 -277.349898) (xy 356.149826 -277.307985) (xy 356.186456 -277.271351) (xy 356.228366 -277.240897)
			(xy 356.274523 -277.217374) (xy 356.323792 -277.201361) (xy 356.374959 -277.193251) (xy 356.400862 -277.19274)
			(xy 356.426374 -277.193232) (xy 356.476788 -277.201088) (xy 356.52539 -277.216618) (xy 356.571019 -277.239452)
			(xy 356.612585 -277.269043) (xy 356.649095 -277.304685) (xy 356.664768 -277.32482) (xy 357.076756 -277.32482)
			(xy 357.09246 -277.30471) (xy 357.128963 -277.269063) (xy 357.170522 -277.239467) (xy 357.216144 -277.216626)
			(xy 357.264741 -277.201087) (xy 357.315152 -277.19322) (xy 357.340662 -277.19274) (xy 357.366576 -277.193155)
			(xy 357.417766 -277.201257) (xy 357.467059 -277.217268) (xy 357.51324 -277.240794) (xy 357.555171 -277.271254)
			(xy 357.591821 -277.3079) (xy 357.622286 -277.349828) (xy 357.645817 -277.396006) (xy 357.661834 -277.445297)
			(xy 357.669942 -277.496486) (xy 357.669942 -277.548314) (xy 357.661834 -277.599503) (xy 357.645817 -277.648794)
			(xy 357.622286 -277.694972) (xy 357.591821 -277.7369) (xy 357.555171 -277.773546) (xy 357.51324 -277.804006)
			(xy 357.467059 -277.827532) (xy 357.417766 -277.843543) (xy 357.366576 -277.851645) (xy 357.340662 -277.852124)
			(xy 357.31515 -277.851662) (xy 357.264735 -277.843796) (xy 357.216133 -277.828258) (xy 357.170505 -277.805419)
			(xy 357.12894 -277.775824) (xy 357.09243 -277.74018) (xy 357.076756 -277.720044) (xy 356.664768 -277.720044)
			(xy 356.649125 -277.740204) (xy 356.612608 -277.775845) (xy 356.571036 -277.805434) (xy 356.525401 -277.828266)
			(xy 356.476795 -277.843795) (xy 356.426376 -277.85165) (xy 356.400862 -277.852124) (xy 356.374959 -277.851549)
			(xy 356.323792 -277.843439) (xy 356.274523 -277.827426) (xy 356.228366 -277.803903) (xy 356.186456 -277.773449)
			(xy 356.149826 -277.736815) (xy 356.119377 -277.694902) (xy 356.09586 -277.648742) (xy 356.079852 -277.599471)
			(xy 356.071748 -277.548303) (xy 355.789963 -277.548303) (xy 355.789917 -277.550456) (xy 355.780726 -277.604717)
			(xy 355.772212 -277.63089) (xy 355.764592 -277.652988) (xy 355.969824 -278.008334) (xy 355.992684 -278.012652)
			(xy 356.017501 -278.017836) (xy 356.065277 -278.034792) (xy 356.109893 -278.058863) (xy 356.150297 -278.089482)
			(xy 356.185537 -278.125927) (xy 356.214781 -278.167338) (xy 356.23734 -278.212738) (xy 356.252681 -278.261056)
			(xy 356.260443 -278.311154) (xy 356.260908 -278.336502) (xy 356.2604 -278.362409) (xy 356.252294 -278.413586)
			(xy 356.236282 -278.462865) (xy 356.212759 -278.509032) (xy 356.182303 -278.550951) (xy 356.145665 -278.587589)
			(xy 356.103746 -278.618045) (xy 356.057579 -278.641568) (xy 356.0083 -278.65758) (xy 355.957123 -278.665686)
			(xy 355.905309 -278.665686) (xy 355.854132 -278.65758) (xy 355.804853 -278.641568) (xy 355.758686 -278.618045)
			(xy 355.716767 -278.587589) (xy 355.680129 -278.550951) (xy 355.649673 -278.509032) (xy 355.62615 -278.462865)
			(xy 355.610138 -278.413586) (xy 355.602032 -278.362409) (xy 355.601524 -278.336502) (xy 355.602117 -278.308785)
			(xy 355.611441 -278.254138) (xy 355.620066 -278.22779) (xy 355.62794 -278.205692) (xy 355.422962 -277.8506)
			(xy 355.399848 -277.846282) (xy 355.375022 -277.841137) (xy 355.327241 -277.824181) (xy 355.282621 -277.800107)
			(xy 355.242213 -277.769484) (xy 355.206972 -277.733035) (xy 355.177729 -277.691618) (xy 355.155174 -277.646211)
			(xy 355.139838 -277.597886) (xy 355.132084 -277.547782) (xy 355.131624 -277.522432) (xy 354.8507 -277.522432)
			(xy 354.850192 -277.548319) (xy 354.842093 -277.599457) (xy 354.826094 -277.648697) (xy 354.802588 -277.694829)
			(xy 354.772156 -277.736716) (xy 354.735546 -277.773326) (xy 354.693659 -277.803758) (xy 354.647527 -277.827264)
			(xy 354.598287 -277.843263) (xy 354.547149 -277.851362) (xy 354.495375 -277.851362) (xy 354.444237 -277.843263)
			(xy 354.394997 -277.827264) (xy 354.348865 -277.803758) (xy 354.306978 -277.773326) (xy 354.270368 -277.736716)
			(xy 354.239936 -277.694829) (xy 354.21643 -277.648697) (xy 354.200431 -277.599457) (xy 354.192332 -277.548319)
			(xy 354.191824 -277.522432) (xy 352.0313 -277.522432) (xy 352.030792 -277.548319) (xy 352.022693 -277.599457)
			(xy 352.006694 -277.648697) (xy 351.983188 -277.694829) (xy 351.952756 -277.736716) (xy 351.916146 -277.773326)
			(xy 351.874259 -277.803758) (xy 351.828127 -277.827264) (xy 351.778887 -277.843263) (xy 351.727749 -277.851362)
			(xy 351.675975 -277.851362) (xy 351.624837 -277.843263) (xy 351.575597 -277.827264) (xy 351.529465 -277.803758)
			(xy 351.487578 -277.773326) (xy 351.450968 -277.736716) (xy 351.420536 -277.694829) (xy 351.39703 -277.648697)
			(xy 351.381031 -277.599457) (xy 351.372932 -277.548319) (xy 351.372424 -277.522432) (xy 351.37296 -277.494724)
			(xy 351.382151 -277.440077) (xy 351.390712 -277.41372) (xy 351.398586 -277.391622) (xy 351.193608 -277.036784)
			(xy 351.170748 -277.032466) (xy 351.145918 -277.027336) (xy 351.098136 -277.010379) (xy 351.053515 -276.986304)
			(xy 351.013107 -276.955679) (xy 350.977866 -276.919227) (xy 350.948624 -276.877808) (xy 350.926069 -276.8324)
			(xy 350.910735 -276.784072) (xy 350.902983 -276.733967) (xy 350.902524 -276.708616) (xy 350.6216 -276.708616)
			(xy 350.621092 -276.734503) (xy 350.612993 -276.785641) (xy 350.596994 -276.834881) (xy 350.573488 -276.881013)
			(xy 350.543056 -276.9229) (xy 350.506446 -276.95951) (xy 350.464559 -276.989942) (xy 350.418427 -277.013448)
			(xy 350.369187 -277.029447) (xy 350.318049 -277.037546) (xy 350.266275 -277.037546) (xy 350.215137 -277.029447)
			(xy 350.165897 -277.013448) (xy 350.119765 -276.989942) (xy 350.077878 -276.95951) (xy 350.041268 -276.9229)
			(xy 350.010836 -276.881013) (xy 349.98733 -276.834881) (xy 349.971331 -276.785641) (xy 349.963232 -276.734503)
			(xy 349.962724 -276.708616) (xy 109.260132 -276.708616) (xy 109.259624 -276.734503) (xy 109.251525 -276.785641)
			(xy 109.235526 -276.834881) (xy 109.21202 -276.881013) (xy 109.181588 -276.9229) (xy 109.144978 -276.95951)
			(xy 109.103091 -276.989942) (xy 109.056959 -277.013448) (xy 109.007719 -277.029447) (xy 108.956581 -277.037546)
			(xy 108.904807 -277.037546) (xy 108.853669 -277.029447) (xy 108.804429 -277.013448) (xy 108.758297 -276.989942)
			(xy 108.71641 -276.95951) (xy 108.6798 -276.9229) (xy 108.649368 -276.881013) (xy 108.625862 -276.834881)
			(xy 108.609863 -276.785641) (xy 108.601764 -276.734503) (xy 108.601256 -276.708616) (xy 107.38104 -276.708616)
			(xy 107.380628 -276.733993) (xy 107.372856 -276.784149) (xy 107.357482 -276.832518) (xy 107.334871 -276.877958)
			(xy 107.305557 -276.91939) (xy 107.270234 -276.955836) (xy 107.229739 -276.986433) (xy 107.18503 -277.010456)
			(xy 107.137166 -277.027337) (xy 107.112308 -277.032466) (xy 107.089448 -277.036784) (xy 106.88447 -277.391622)
			(xy 106.892344 -277.41372) (xy 106.90091 -277.440076) (xy 106.910105 -277.494723) (xy 106.910632 -277.522432)
			(xy 107.191556 -277.522432) (xy 107.192064 -277.496545) (xy 107.200163 -277.445407) (xy 107.216162 -277.396167)
			(xy 107.239668 -277.350035) (xy 107.2701 -277.308148) (xy 107.30671 -277.271538) (xy 107.348597 -277.241106)
			(xy 107.394729 -277.2176) (xy 107.443969 -277.201601) (xy 107.495107 -277.193502) (xy 107.546881 -277.193502)
			(xy 107.598019 -277.201601) (xy 107.647259 -277.2176) (xy 107.693391 -277.241106) (xy 107.735278 -277.271538)
			(xy 107.771888 -277.308148) (xy 107.80232 -277.350035) (xy 107.825826 -277.396167) (xy 107.841825 -277.445407)
			(xy 107.849924 -277.496545) (xy 107.850432 -277.522432) (xy 107.850432 -277.52294) (xy 107.849894 -277.548305)
			(xy 108.131648 -277.548305) (xy 108.131648 -277.496495) (xy 108.139753 -277.445324) (xy 108.155763 -277.396051)
			(xy 108.179283 -277.349889) (xy 108.209735 -277.307974) (xy 108.24637 -277.271339) (xy 108.288284 -277.240886)
			(xy 108.334445 -277.217365) (xy 108.383718 -277.201354) (xy 108.43489 -277.193249) (xy 108.460794 -277.19274)
			(xy 108.486306 -277.193209) (xy 108.536722 -277.20107) (xy 108.585325 -277.216605) (xy 108.630953 -277.239442)
			(xy 108.672518 -277.269037) (xy 108.709027 -277.304684) (xy 108.7247 -277.32482) (xy 109.136688 -277.32482)
			(xy 109.152374 -277.304695) (xy 109.18888 -277.269049) (xy 109.230443 -277.239454) (xy 109.276069 -277.216616)
			(xy 109.324669 -277.20108) (xy 109.375083 -277.193218) (xy 109.400594 -277.19274) (xy 109.426506 -277.193157)
			(xy 109.477693 -277.201263) (xy 109.526981 -277.217277) (xy 109.573157 -277.240805) (xy 109.615085 -277.271266)
			(xy 109.65173 -277.307911) (xy 109.682192 -277.349838) (xy 109.70572 -277.396013) (xy 109.721735 -277.445301)
			(xy 109.729842 -277.496488) (xy 109.729842 -277.548312) (xy 109.721735 -277.599499) (xy 109.70572 -277.648787)
			(xy 109.682192 -277.694962) (xy 109.65173 -277.736889) (xy 109.615085 -277.773534) (xy 109.573157 -277.803995)
			(xy 109.526981 -277.827523) (xy 109.477693 -277.843537) (xy 109.426506 -277.851643) (xy 109.400594 -277.852124)
			(xy 109.375083 -277.851639) (xy 109.324669 -277.843778) (xy 109.276068 -277.828245) (xy 109.230439 -277.80541)
			(xy 109.188874 -277.775819) (xy 109.152362 -277.740178) (xy 109.136688 -277.720044) (xy 108.7247 -277.720044)
			(xy 108.709039 -277.740189) (xy 108.672525 -277.77583) (xy 108.630957 -277.805422) (xy 108.585326 -277.828256)
			(xy 108.536723 -277.843788) (xy 108.486307 -277.851647) (xy 108.460794 -277.852124) (xy 108.43489 -277.851551)
			(xy 108.383718 -277.843446) (xy 108.334445 -277.827435) (xy 108.288284 -277.803914) (xy 108.24637 -277.773461)
			(xy 108.209735 -277.736826) (xy 108.179283 -277.694911) (xy 108.155763 -277.648749) (xy 108.139753 -277.599476)
			(xy 108.131648 -277.548305) (xy 107.849894 -277.548305) (xy 107.849848 -277.550456) (xy 107.840658 -277.604717)
			(xy 107.832144 -277.63089) (xy 107.824524 -277.652988) (xy 108.029756 -278.008334) (xy 108.052616 -278.012652)
			(xy 108.077422 -278.017885) (xy 108.125198 -278.034831) (xy 108.169815 -278.058894) (xy 108.210222 -278.089506)
			(xy 108.245463 -278.125945) (xy 108.27471 -278.16735) (xy 108.29727 -278.212746) (xy 108.312612 -278.261061)
			(xy 108.320375 -278.311156) (xy 108.32084 -278.336502) (xy 108.320332 -278.362409) (xy 108.312226 -278.413586)
			(xy 108.296214 -278.462865) (xy 108.272691 -278.509032) (xy 108.242235 -278.550951) (xy 108.205597 -278.587589)
			(xy 108.163678 -278.618045) (xy 108.117511 -278.641568) (xy 108.068232 -278.65758) (xy 108.017055 -278.665686)
			(xy 107.965241 -278.665686) (xy 107.914064 -278.65758) (xy 107.864785 -278.641568) (xy 107.818618 -278.618045)
			(xy 107.776699 -278.587589) (xy 107.740061 -278.550951) (xy 107.709605 -278.509032) (xy 107.686082 -278.462865)
			(xy 107.67007 -278.413586) (xy 107.661964 -278.362409) (xy 107.661456 -278.336502) (xy 107.662047 -278.308784)
			(xy 107.671372 -278.254138) (xy 107.679998 -278.22779) (xy 107.687872 -278.205692) (xy 107.482894 -277.8506)
			(xy 107.45978 -277.846282) (xy 107.434959 -277.841114) (xy 107.387178 -277.824162) (xy 107.342557 -277.800093)
			(xy 107.302149 -277.769473) (xy 107.266907 -277.733026) (xy 107.237663 -277.691612) (xy 107.215107 -277.646207)
			(xy 107.199771 -277.597884) (xy 107.192016 -277.547781) (xy 107.191556 -277.522432) (xy 106.910632 -277.522432)
			(xy 106.910124 -277.548319) (xy 106.902025 -277.599457) (xy 106.886026 -277.648697) (xy 106.86252 -277.694829)
			(xy 106.832088 -277.736716) (xy 106.795478 -277.773326) (xy 106.753591 -277.803758) (xy 106.707459 -277.827264)
			(xy 106.658219 -277.843263) (xy 106.607081 -277.851362) (xy 106.555307 -277.851362) (xy 106.504169 -277.843263)
			(xy 106.454929 -277.827264) (xy 106.408797 -277.803758) (xy 106.36691 -277.773326) (xy 106.3303 -277.736716)
			(xy 106.299868 -277.694829) (xy 106.276362 -277.648697) (xy 106.260363 -277.599457) (xy 106.252264 -277.548319)
			(xy 106.251756 -277.522432) (xy 104.091232 -277.522432) (xy 104.090724 -277.548319) (xy 104.082625 -277.599457)
			(xy 104.066626 -277.648697) (xy 104.04312 -277.694829) (xy 104.012688 -277.736716) (xy 103.976078 -277.773326)
			(xy 103.934191 -277.803758) (xy 103.888059 -277.827264) (xy 103.838819 -277.843263) (xy 103.787681 -277.851362)
			(xy 103.735907 -277.851362) (xy 103.684769 -277.843263) (xy 103.635529 -277.827264) (xy 103.589397 -277.803758)
			(xy 103.54751 -277.773326) (xy 103.5109 -277.736716) (xy 103.480468 -277.694829) (xy 103.456962 -277.648697)
			(xy 103.440963 -277.599457) (xy 103.432864 -277.548319) (xy 103.432356 -277.522432) (xy 103.432895 -277.494724)
			(xy 103.442084 -277.440078) (xy 103.450644 -277.41372) (xy 103.458518 -277.391622) (xy 103.25354 -277.036784)
			(xy 103.23068 -277.032466) (xy 103.205855 -277.027313) (xy 103.158073 -277.01036) (xy 103.113452 -276.986289)
			(xy 103.073043 -276.955668) (xy 103.037801 -276.919219) (xy 103.008557 -276.877803) (xy 102.986002 -276.832396)
			(xy 102.970667 -276.78407) (xy 102.962915 -276.733966) (xy 102.962456 -276.708616) (xy 102.681532 -276.708616)
			(xy 102.681024 -276.734503) (xy 102.672925 -276.785641) (xy 102.656926 -276.834881) (xy 102.63342 -276.881013)
			(xy 102.602988 -276.9229) (xy 102.566378 -276.95951) (xy 102.524491 -276.989942) (xy 102.478359 -277.013448)
			(xy 102.429119 -277.029447) (xy 102.377981 -277.037546) (xy 102.326207 -277.037546) (xy 102.275069 -277.029447)
			(xy 102.225829 -277.013448) (xy 102.179697 -276.989942) (xy 102.13781 -276.95951) (xy 102.1012 -276.9229)
			(xy 102.070768 -276.881013) (xy 102.047262 -276.834881) (xy 102.031263 -276.785641) (xy 102.023164 -276.734503)
			(xy 102.022656 -276.708616) (xy 2.509012 -276.708616) (xy 2.509012 -279.150318) (xy 101.552756 -279.150318)
			(xy 101.553264 -279.124431) (xy 101.561363 -279.073293) (xy 101.577362 -279.024053) (xy 101.600868 -278.977921)
			(xy 101.6313 -278.936034) (xy 101.66791 -278.899424) (xy 101.709797 -278.868992) (xy 101.755929 -278.845486)
			(xy 101.805169 -278.829487) (xy 101.856307 -278.821388) (xy 101.908081 -278.821388) (xy 101.959219 -278.829487)
			(xy 102.008459 -278.845486) (xy 102.054591 -278.868992) (xy 102.096478 -278.899424) (xy 102.133088 -278.936034)
			(xy 102.16352 -278.977921) (xy 102.187026 -279.024053) (xy 102.203025 -279.073293) (xy 102.211124 -279.124431)
			(xy 102.211632 -279.150318) (xy 102.211632 -279.150826) (xy 102.21109 -279.176186) (xy 102.493088 -279.176186)
			(xy 102.493088 -279.124414) (xy 102.501186 -279.07328) (xy 102.517184 -279.024043) (xy 102.540688 -278.977914)
			(xy 102.571118 -278.93603) (xy 102.607725 -278.899422) (xy 102.649609 -278.868991) (xy 102.695737 -278.845487)
			(xy 102.744975 -278.829488) (xy 102.796108 -278.821388) (xy 102.821994 -278.82088) (xy 102.847505 -278.821372)
			(xy 102.897919 -278.829232) (xy 102.94652 -278.844763) (xy 102.992148 -278.867597) (xy 103.033714 -278.897186)
			(xy 103.070226 -278.932826) (xy 103.0859 -278.95296) (xy 103.497888 -278.95296) (xy 103.513557 -278.932822)
			(xy 103.550069 -278.89718) (xy 103.591636 -278.867588) (xy 103.637265 -278.844752) (xy 103.685867 -278.829219)
			(xy 103.736282 -278.821357) (xy 103.761794 -278.82088) (xy 103.787685 -278.821325) (xy 103.83883 -278.829425)
			(xy 103.888078 -278.845425) (xy 103.934217 -278.868934) (xy 103.97611 -278.89937) (xy 104.012726 -278.935985)
			(xy 104.043163 -278.977878) (xy 104.066672 -279.024016) (xy 104.082674 -279.073264) (xy 104.090775 -279.124409)
			(xy 104.090775 -279.150318) (xy 349.492824 -279.150318) (xy 349.493332 -279.124431) (xy 349.501431 -279.073293)
			(xy 349.51743 -279.024053) (xy 349.540936 -278.977921) (xy 349.571368 -278.936034) (xy 349.607978 -278.899424)
			(xy 349.649865 -278.868992) (xy 349.695997 -278.845486) (xy 349.745237 -278.829487) (xy 349.796375 -278.821388)
			(xy 349.848149 -278.821388) (xy 349.899287 -278.829487) (xy 349.948527 -278.845486) (xy 349.994659 -278.868992)
			(xy 350.036546 -278.899424) (xy 350.073156 -278.936034) (xy 350.103588 -278.977921) (xy 350.127094 -279.024053)
			(xy 350.143093 -279.073293) (xy 350.151192 -279.124431) (xy 350.1517 -279.150318) (xy 350.1517 -279.150826)
			(xy 350.15116 -279.176184) (xy 350.433187 -279.176184) (xy 350.433187 -279.124416) (xy 350.441285 -279.073285)
			(xy 350.457281 -279.02405) (xy 350.480782 -278.977924) (xy 350.511209 -278.936041) (xy 350.547812 -278.899433)
			(xy 350.589691 -278.869002) (xy 350.635815 -278.845496) (xy 350.685048 -278.829494) (xy 350.736178 -278.82139)
			(xy 350.762062 -278.82088) (xy 350.787572 -278.821396) (xy 350.837985 -278.82925) (xy 350.886585 -278.844777)
			(xy 350.932214 -278.867606) (xy 350.97378 -278.897192) (xy 351.010293 -278.932828) (xy 351.025968 -278.95296)
			(xy 351.437956 -278.95296) (xy 351.453644 -278.932837) (xy 351.490152 -278.897194) (xy 351.531715 -278.8676)
			(xy 351.57734 -278.844762) (xy 351.625939 -278.829225) (xy 351.676351 -278.82136) (xy 351.701862 -278.82088)
			(xy 351.727755 -278.821322) (xy 351.778904 -278.829418) (xy 351.828156 -278.845416) (xy 351.874299 -278.868923)
			(xy 351.916197 -278.899359) (xy 351.952817 -278.935974) (xy 351.983257 -278.977868) (xy 352.006769 -279.024009)
			(xy 352.022773 -279.073259) (xy 352.030875 -279.124407) (xy 352.030875 -279.176193) (xy 352.022773 -279.227341)
			(xy 352.006769 -279.276591) (xy 351.983257 -279.322732) (xy 351.952817 -279.364626) (xy 351.916197 -279.401241)
			(xy 351.874299 -279.431677) (xy 351.828156 -279.455184) (xy 351.778904 -279.471182) (xy 351.727755 -279.479278)
			(xy 351.701862 -279.479756) (xy 351.676348 -279.47932) (xy 351.625931 -279.471453) (xy 351.577328 -279.455912)
			(xy 351.531699 -279.433068) (xy 351.490135 -279.403466) (xy 351.453628 -279.367815) (xy 351.437956 -279.347676)
			(xy 351.025968 -279.347676) (xy 351.010307 -279.367822) (xy 350.973795 -279.403466) (xy 350.932228 -279.433059)
			(xy 350.886597 -279.455894) (xy 350.837992 -279.471425) (xy 350.787575 -279.479281) (xy 350.762062 -279.479756)
			(xy 350.736178 -279.47921) (xy 350.685048 -279.471106) (xy 350.635815 -279.455104) (xy 350.589691 -279.431598)
			(xy 350.547812 -279.401167) (xy 350.511209 -279.364559) (xy 350.480782 -279.322676) (xy 350.457281 -279.27655)
			(xy 350.441285 -279.227315) (xy 350.433187 -279.176184) (xy 350.15116 -279.176184) (xy 350.151114 -279.178342)
			(xy 350.141925 -279.232603) (xy 350.133412 -279.258776) (xy 350.125792 -279.28062) (xy 350.331024 -279.635966)
			(xy 350.353884 -279.640284) (xy 350.378708 -279.645438) (xy 350.426486 -279.662396) (xy 350.471104 -279.68647)
			(xy 350.511509 -279.717093) (xy 350.546749 -279.753542) (xy 350.575992 -279.794956) (xy 350.598549 -279.84036)
			(xy 350.613887 -279.888683) (xy 350.621645 -279.938785) (xy 350.622108 -279.964134) (xy 350.6216 -279.990041)
			(xy 350.613494 -280.041218) (xy 350.597482 -280.090497) (xy 350.573959 -280.136664) (xy 350.543503 -280.178583)
			(xy 350.506865 -280.215221) (xy 350.464946 -280.245677) (xy 350.418779 -280.2692) (xy 350.3695 -280.285212)
			(xy 350.318323 -280.293318) (xy 350.266509 -280.293318) (xy 350.215332 -280.285212) (xy 350.166053 -280.2692)
			(xy 350.119886 -280.245677) (xy 350.077967 -280.215221) (xy 350.041329 -280.178583) (xy 350.010873 -280.136664)
			(xy 349.98735 -280.090497) (xy 349.971338 -280.041218) (xy 349.963232 -279.990041) (xy 349.962724 -279.964134)
			(xy 349.963325 -279.936417) (xy 349.972644 -279.88177) (xy 349.981266 -279.855422) (xy 349.98914 -279.833324)
			(xy 349.784162 -279.478486) (xy 349.761302 -279.474168) (xy 349.736475 -279.468982) (xy 349.688671 -279.452048)
			(xy 349.644023 -279.427992) (xy 349.603586 -279.397383) (xy 349.568314 -279.360942) (xy 349.539039 -279.319529)
			(xy 349.516451 -279.274121) (xy 349.501083 -279.22579) (xy 349.493299 -279.175676) (xy 349.492824 -279.150318)
			(xy 104.090775 -279.150318) (xy 104.090775 -279.176191) (xy 104.082674 -279.227336) (xy 104.066672 -279.276584)
			(xy 104.043163 -279.322722) (xy 104.012726 -279.364615) (xy 103.97611 -279.40123) (xy 103.934217 -279.431666)
			(xy 103.888078 -279.455175) (xy 103.83883 -279.471175) (xy 103.787685 -279.479275) (xy 103.761794 -279.479756)
			(xy 103.736281 -279.479297) (xy 103.685865 -279.471435) (xy 103.637262 -279.455898) (xy 103.591633 -279.433058)
			(xy 103.550069 -279.403461) (xy 103.51356 -279.367813) (xy 103.497888 -279.347676) (xy 103.0859 -279.347676)
			(xy 103.07022 -279.367806) (xy 103.033713 -279.403452) (xy 102.992149 -279.433046) (xy 102.946521 -279.455884)
			(xy 102.89792 -279.471418) (xy 102.847506 -279.479279) (xy 102.821994 -279.479756) (xy 102.796108 -279.479212)
			(xy 102.744975 -279.471112) (xy 102.695737 -279.455113) (xy 102.649609 -279.431609) (xy 102.607725 -279.401178)
			(xy 102.571118 -279.36457) (xy 102.540688 -279.322686) (xy 102.517184 -279.276557) (xy 102.501186 -279.22732)
			(xy 102.493088 -279.176186) (xy 102.21109 -279.176186) (xy 102.211044 -279.178342) (xy 102.201856 -279.232603)
			(xy 102.193344 -279.258776) (xy 102.185724 -279.28062) (xy 102.390956 -279.635966) (xy 102.413816 -279.640284)
			(xy 102.438629 -279.645487) (xy 102.486407 -279.662435) (xy 102.531027 -279.686501) (xy 102.571434 -279.717117)
			(xy 102.606676 -279.753559) (xy 102.635921 -279.794969) (xy 102.658479 -279.840369) (xy 102.673819 -279.888688)
			(xy 102.681577 -279.938786) (xy 102.68204 -279.964134) (xy 102.681532 -279.990041) (xy 102.673426 -280.041218)
			(xy 102.657414 -280.090497) (xy 102.633891 -280.136664) (xy 102.603435 -280.178583) (xy 102.566797 -280.215221)
			(xy 102.524878 -280.245677) (xy 102.478711 -280.2692) (xy 102.429432 -280.285212) (xy 102.378255 -280.293318)
			(xy 102.326441 -280.293318) (xy 102.275264 -280.285212) (xy 102.225985 -280.2692) (xy 102.179818 -280.245677)
			(xy 102.137899 -280.215221) (xy 102.101261 -280.178583) (xy 102.070805 -280.136664) (xy 102.047282 -280.090497)
			(xy 102.03127 -280.041218) (xy 102.023164 -279.990041) (xy 102.022656 -279.964134) (xy 102.023255 -279.936417)
			(xy 102.032575 -279.88177) (xy 102.041198 -279.855422) (xy 102.049072 -279.833324) (xy 101.844094 -279.478486)
			(xy 101.821234 -279.474168) (xy 101.796412 -279.468959) (xy 101.748608 -279.452029) (xy 101.70396 -279.427978)
			(xy 101.663522 -279.397372) (xy 101.628249 -279.360934) (xy 101.598973 -279.319523) (xy 101.576384 -279.274117)
			(xy 101.561016 -279.225788) (xy 101.553231 -279.175675) (xy 101.552756 -279.150318) (xy 2.509012 -279.150318)
			(xy 2.509012 -279.989984) (xy 88.866003 -279.989984) (xy 88.866003 -279.938216) (xy 88.874102 -279.887084)
			(xy 88.890099 -279.837849) (xy 88.913601 -279.791722) (xy 88.94403 -279.74984) (xy 88.980636 -279.713234)
			(xy 89.022517 -279.682805) (xy 89.068643 -279.659301) (xy 89.117878 -279.643303) (xy 89.16901 -279.635204)
			(xy 89.194894 -279.634696) (xy 89.220406 -279.635183) (xy 89.27082 -279.643042) (xy 89.319421 -279.658575)
			(xy 89.365049 -279.681409) (xy 89.406615 -279.711) (xy 89.443126 -279.746642) (xy 89.4588 -279.766776)
			(xy 89.870788 -279.766776) (xy 89.886462 -279.746641) (xy 89.922972 -279.710998) (xy 89.964538 -279.681405)
			(xy 90.010166 -279.658569) (xy 90.058768 -279.643035) (xy 90.109182 -279.635173) (xy 90.134694 -279.634696)
			(xy 90.160586 -279.635109) (xy 90.211734 -279.643209) (xy 90.260984 -279.659211) (xy 90.307125 -279.68272)
			(xy 90.349021 -279.713158) (xy 90.385638 -279.749775) (xy 90.416077 -279.791669) (xy 90.439587 -279.83781)
			(xy 90.45559 -279.88706) (xy 90.463691 -279.938208) (xy 90.463691 -279.964134) (xy 96.383856 -279.964134)
			(xy 96.384364 -279.938227) (xy 96.39247 -279.88705) (xy 96.408482 -279.837771) (xy 96.432005 -279.791604)
			(xy 96.462461 -279.749685) (xy 96.499099 -279.713047) (xy 96.541018 -279.682591) (xy 96.587185 -279.659068)
			(xy 96.636464 -279.643056) (xy 96.687641 -279.63495) (xy 96.739455 -279.63495) (xy 96.790632 -279.643056)
			(xy 96.839911 -279.659068) (xy 96.886078 -279.682591) (xy 96.927997 -279.713047) (xy 96.964635 -279.749685)
			(xy 96.995091 -279.791604) (xy 97.018614 -279.837771) (xy 97.034626 -279.88705) (xy 97.042732 -279.938227)
			(xy 97.04324 -279.964134) (xy 97.042606 -279.991926) (xy 97.033158 -280.046702) (xy 97.024444 -280.0731)
			(xy 97.016824 -280.095198) (xy 97.221802 -280.450036) (xy 97.244662 -280.454354) (xy 97.269457 -280.45958)
			(xy 97.317195 -280.476563) (xy 97.361773 -280.50065) (xy 97.402139 -280.531276) (xy 97.437344 -280.567718)
			(xy 97.466557 -280.609118) (xy 97.489091 -280.6545) (xy 97.504415 -280.702797) (xy 97.512168 -280.752869)
			(xy 97.512632 -280.778204) (xy 97.512124 -280.804091) (xy 97.504025 -280.855229) (xy 97.488026 -280.904469)
			(xy 97.46452 -280.950601) (xy 97.434088 -280.992488) (xy 97.397478 -281.029098) (xy 97.355591 -281.05953)
			(xy 97.309459 -281.083036) (xy 97.260219 -281.099035) (xy 97.209081 -281.107134) (xy 97.157307 -281.107134)
			(xy 97.106169 -281.099035) (xy 97.056929 -281.083036) (xy 97.010797 -281.05953) (xy 96.96891 -281.029098)
			(xy 96.9323 -280.992488) (xy 96.901868 -280.950601) (xy 96.878362 -280.904469) (xy 96.862363 -280.855229)
			(xy 96.854264 -280.804091) (xy 96.853756 -280.778204) (xy 96.854288 -280.750496) (xy 96.863482 -280.695849)
			(xy 96.872044 -280.669492) (xy 96.879918 -280.647394) (xy 96.674686 -280.292302) (xy 96.651826 -280.287984)
			(xy 96.627038 -280.282731) (xy 96.579302 -280.265749) (xy 96.534727 -280.241664) (xy 96.494362 -280.211041)
			(xy 96.459158 -280.174603) (xy 96.429944 -280.133207) (xy 96.407407 -280.087828) (xy 96.39208 -280.039536)
			(xy 96.384322 -279.989467) (xy 96.383856 -279.964134) (xy 90.463691 -279.964134) (xy 90.463691 -279.989992)
			(xy 90.45559 -280.04114) (xy 90.439587 -280.09039) (xy 90.416077 -280.13653) (xy 90.385638 -280.178425)
			(xy 90.349021 -280.215042) (xy 90.307125 -280.24548) (xy 90.260984 -280.268989) (xy 90.211734 -280.284991)
			(xy 90.160586 -280.293091) (xy 90.134694 -280.293572) (xy 90.109181 -280.293107) (xy 90.058766 -280.285245)
			(xy 90.010163 -280.269709) (xy 89.964535 -280.24687) (xy 89.92297 -280.217275) (xy 89.886461 -280.181628)
			(xy 89.870788 -280.161492) (xy 89.4588 -280.161492) (xy 89.443124 -280.181626) (xy 89.406615 -280.21727)
			(xy 89.365051 -280.246864) (xy 89.319422 -280.269701) (xy 89.270821 -280.285235) (xy 89.220406 -280.293095)
			(xy 89.194894 -280.293572) (xy 89.16901 -280.292996) (xy 89.117878 -280.284897) (xy 89.068643 -280.268899)
			(xy 89.022517 -280.245395) (xy 88.980636 -280.214966) (xy 88.94403 -280.17836) (xy 88.913601 -280.136478)
			(xy 88.890099 -280.090351) (xy 88.874102 -280.041116) (xy 88.866003 -279.989984) (xy 2.509012 -279.989984)
			(xy 2.509012 -280.804107) (xy 94.97442 -280.804107) (xy 94.97442 -280.752293) (xy 94.982526 -280.701118)
			(xy 94.998537 -280.65184) (xy 95.022059 -280.605674) (xy 95.052514 -280.563756) (xy 95.089151 -280.527118)
			(xy 95.131069 -280.496662) (xy 95.177235 -280.473139) (xy 95.226512 -280.457127) (xy 95.277687 -280.449021)
			(xy 95.303594 -280.448512) (xy 95.329106 -280.448992) (xy 95.379521 -280.456852) (xy 95.428122 -280.472385)
			(xy 95.473751 -280.495221) (xy 95.515316 -280.524814) (xy 95.551826 -280.560457) (xy 95.5675 -280.580592)
			(xy 95.979742 -280.580592) (xy 95.995389 -280.560435) (xy 96.031904 -280.524793) (xy 96.073475 -280.495202)
			(xy 96.119109 -280.472369) (xy 96.167716 -280.45684) (xy 96.218134 -280.448986) (xy 96.243648 -280.448512)
			(xy 96.269553 -280.449016) (xy 96.320725 -280.457128) (xy 96.369997 -280.473144) (xy 96.416159 -280.49667)
			(xy 96.458071 -280.527127) (xy 96.494704 -280.563765) (xy 96.525155 -280.605682) (xy 96.548675 -280.651847)
			(xy 96.564684 -280.701122) (xy 96.572788 -280.752295) (xy 96.572788 -280.804105) (xy 96.564684 -280.855278)
			(xy 96.548675 -280.904553) (xy 96.525155 -280.950718) (xy 96.494704 -280.992635) (xy 96.458071 -281.029273)
			(xy 96.416159 -281.05973) (xy 96.369997 -281.083256) (xy 96.320725 -281.099272) (xy 96.269553 -281.107384)
			(xy 96.243648 -281.107896) (xy 96.218137 -281.107382) (xy 96.167724 -281.099529) (xy 96.119123 -281.084002)
			(xy 96.073495 -281.061173) (xy 96.031928 -281.031586) (xy 95.995417 -280.995948) (xy 95.979742 -280.975816)
			(xy 95.5675 -280.975816) (xy 95.551831 -280.995955) (xy 95.51532 -281.031598) (xy 95.473753 -281.06119)
			(xy 95.428124 -281.084026) (xy 95.379522 -281.099559) (xy 95.329106 -281.107419) (xy 95.303594 -281.107896)
			(xy 95.277687 -281.107379) (xy 95.226512 -281.099273) (xy 95.177235 -281.083261) (xy 95.131069 -281.059738)
			(xy 95.089151 -281.029282) (xy 95.052514 -280.992644) (xy 95.022059 -280.950726) (xy 94.998537 -280.90456)
			(xy 94.982526 -280.855282) (xy 94.97442 -280.804107) (xy 2.509012 -280.804107) (xy 2.509012 -281.617905)
			(xy 90.745336 -281.617905) (xy 90.745336 -281.566095) (xy 90.753441 -281.514922) (xy 90.769451 -281.465646)
			(xy 90.792973 -281.419482) (xy 90.823426 -281.377566) (xy 90.860062 -281.34093) (xy 90.901977 -281.310476)
			(xy 90.948141 -281.286954) (xy 90.997416 -281.270943) (xy 91.048589 -281.262837) (xy 91.074494 -281.262328)
			(xy 91.100006 -281.262802) (xy 91.150421 -281.270662) (xy 91.199024 -281.286196) (xy 91.244652 -281.309033)
			(xy 91.286218 -281.338627) (xy 91.322727 -281.374272) (xy 91.3384 -281.394408) (xy 91.750388 -281.394408)
			(xy 91.766071 -281.37428) (xy 91.802578 -281.338635) (xy 91.844142 -281.309041) (xy 91.889768 -281.286203)
			(xy 91.938369 -281.270668) (xy 91.988782 -281.262806) (xy 92.014294 -281.262328) (xy 92.040205 -281.262769)
			(xy 92.09139 -281.270875) (xy 92.140676 -281.286888) (xy 92.186851 -281.310415) (xy 92.228777 -281.340875)
			(xy 92.265421 -281.377519) (xy 92.295882 -281.419444) (xy 92.319409 -281.465618) (xy 92.335423 -281.514904)
			(xy 92.34353 -281.566089) (xy 92.34353 -281.617911) (xy 92.335423 -281.669096) (xy 92.319409 -281.718382)
			(xy 92.295882 -281.764556) (xy 92.265421 -281.806481) (xy 92.228777 -281.843125) (xy 92.186851 -281.873585)
			(xy 92.140676 -281.897112) (xy 92.09139 -281.913125) (xy 92.040205 -281.921231) (xy 92.014294 -281.921712)
			(xy 91.988782 -281.921231) (xy 91.938368 -281.91337) (xy 91.889767 -281.897836) (xy 91.844138 -281.875001)
			(xy 91.802573 -281.845409) (xy 91.766062 -281.809767) (xy 91.750388 -281.789632) (xy 91.3384 -281.789632)
			(xy 91.322735 -281.809774) (xy 91.286223 -281.845417) (xy 91.244655 -281.875008) (xy 91.199025 -281.897843)
			(xy 91.150422 -281.913376) (xy 91.100006 -281.921235) (xy 91.074494 -281.921712) (xy 91.048589 -281.921163)
			(xy 90.997416 -281.913057) (xy 90.948141 -281.897046) (xy 90.901977 -281.873524) (xy 90.860062 -281.84307)
			(xy 90.823426 -281.806434) (xy 90.792973 -281.764518) (xy 90.769451 -281.718354) (xy 90.753441 -281.669078)
			(xy 90.745336 -281.617905) (xy 2.509012 -281.617905) (xy 2.509012 -282.405836) (xy 87.455756 -282.405836)
			(xy 87.456264 -282.379949) (xy 87.464363 -282.328811) (xy 87.480362 -282.279571) (xy 87.503868 -282.233439)
			(xy 87.5343 -282.191552) (xy 87.57091 -282.154942) (xy 87.612797 -282.12451) (xy 87.658929 -282.101004)
			(xy 87.708169 -282.085005) (xy 87.759307 -282.076906) (xy 87.811081 -282.076906) (xy 87.862219 -282.085005)
			(xy 87.911459 -282.101004) (xy 87.957591 -282.12451) (xy 87.999478 -282.154942) (xy 88.036088 -282.191552)
			(xy 88.06652 -282.233439) (xy 88.090026 -282.279571) (xy 88.106025 -282.328811) (xy 88.114124 -282.379949)
			(xy 88.114632 -282.405836) (xy 93.094556 -282.405836) (xy 93.094974 -282.380488) (xy 93.102757 -282.330393)
			(xy 93.118114 -282.282079) (xy 93.140683 -282.236685) (xy 93.169933 -282.195278) (xy 93.205175 -282.158835)
			(xy 93.245578 -282.128214) (xy 93.290191 -282.104137) (xy 93.337964 -282.08717) (xy 93.36278 -282.081986)
			(xy 93.38564 -282.077668) (xy 93.590618 -281.72283) (xy 93.582744 -281.700986) (xy 93.574162 -281.674568)
			(xy 93.564967 -281.619792) (xy 93.564456 -281.59202) (xy 93.564964 -281.566133) (xy 93.573063 -281.514995)
			(xy 93.589062 -281.465755) (xy 93.612568 -281.419623) (xy 93.643 -281.377736) (xy 93.67961 -281.341126)
			(xy 93.721497 -281.310694) (xy 93.767629 -281.287188) (xy 93.816869 -281.271189) (xy 93.868007 -281.26309)
			(xy 93.919781 -281.26309) (xy 93.970919 -281.271189) (xy 94.020159 -281.287188) (xy 94.066291 -281.310694)
			(xy 94.108178 -281.341126) (xy 94.144788 -281.377736) (xy 94.17522 -281.419623) (xy 94.198726 -281.465755)
			(xy 94.214725 -281.514995) (xy 94.222824 -281.566133) (xy 94.223332 -281.59202) (xy 94.222842 -281.617354)
			(xy 94.215087 -281.667425) (xy 94.199764 -281.71572) (xy 94.177233 -281.761102) (xy 94.148024 -281.802503)
			(xy 94.112825 -281.838948) (xy 94.072465 -281.869579) (xy 94.027893 -281.893676) (xy 93.980161 -281.910669)
			(xy 93.955362 -281.91587) (xy 93.932502 -281.920188) (xy 93.727524 -282.275026) (xy 93.735398 -282.297124)
			(xy 93.744018 -282.323474) (xy 93.753346 -282.378119) (xy 93.75394 -282.405836) (xy 94.974156 -282.405836)
			(xy 94.974616 -282.380501) (xy 94.982377 -282.33043) (xy 94.997705 -282.282135) (xy 95.020241 -282.236753)
			(xy 95.049454 -282.195352) (xy 95.084656 -282.158908) (xy 95.125019 -282.128277) (xy 95.169592 -282.104181)
			(xy 95.217327 -282.087187) (xy 95.242126 -282.081986) (xy 95.264986 -282.077668) (xy 95.470218 -281.722322)
			(xy 95.462598 -281.700478) (xy 95.45397 -281.674197) (xy 95.444658 -281.619675) (xy 95.444056 -281.59202)
			(xy 95.444564 -281.566113) (xy 95.45267 -281.514936) (xy 95.468682 -281.465657) (xy 95.492205 -281.41949)
			(xy 95.522661 -281.377571) (xy 95.559299 -281.340933) (xy 95.601218 -281.310477) (xy 95.647385 -281.286954)
			(xy 95.696664 -281.270942) (xy 95.747841 -281.262836) (xy 95.799655 -281.262836) (xy 95.850832 -281.270942)
			(xy 95.900111 -281.286954) (xy 95.946278 -281.310477) (xy 95.988197 -281.340933) (xy 96.024835 -281.377571)
			(xy 96.055291 -281.41949) (xy 96.078814 -281.465657) (xy 96.094826 -281.514936) (xy 96.102932 -281.566113)
			(xy 96.10344 -281.59202) (xy 97.323656 -281.59202) (xy 97.32415 -281.566675) (xy 97.33192 -281.516583)
			(xy 97.347266 -281.468271) (xy 97.369824 -281.422876) (xy 97.399064 -281.381469) (xy 97.434298 -281.345025)
			(xy 97.474693 -281.314403) (xy 97.5193 -281.290323) (xy 97.567066 -281.273355) (xy 97.59188 -281.26817)
			(xy 97.61474 -281.263852) (xy 97.819718 -280.909014) (xy 97.811844 -280.88717) (xy 97.803259 -280.860753)
			(xy 97.794066 -280.805977) (xy 97.793556 -280.778204) (xy 97.794064 -280.752317) (xy 97.802163 -280.701179)
			(xy 97.818162 -280.651939) (xy 97.841668 -280.605807) (xy 97.8721 -280.56392) (xy 97.90871 -280.52731)
			(xy 97.950597 -280.496878) (xy 97.996729 -280.473372) (xy 98.045969 -280.457373) (xy 98.097107 -280.449274)
			(xy 98.148881 -280.449274) (xy 98.200019 -280.457373) (xy 98.249259 -280.473372) (xy 98.295391 -280.496878)
			(xy 98.337278 -280.52731) (xy 98.373888 -280.56392) (xy 98.40432 -280.605807) (xy 98.427826 -280.651939)
			(xy 98.443825 -280.701179) (xy 98.451924 -280.752317) (xy 98.452432 -280.778204) (xy 100.612956 -280.778204)
			(xy 100.613464 -280.752317) (xy 100.621563 -280.701179) (xy 100.637562 -280.651939) (xy 100.661068 -280.605807)
			(xy 100.6915 -280.56392) (xy 100.72811 -280.52731) (xy 100.769997 -280.496878) (xy 100.816129 -280.473372)
			(xy 100.865369 -280.457373) (xy 100.916507 -280.449274) (xy 100.968281 -280.449274) (xy 101.019419 -280.457373)
			(xy 101.068659 -280.473372) (xy 101.114791 -280.496878) (xy 101.156678 -280.52731) (xy 101.193288 -280.56392)
			(xy 101.22372 -280.605807) (xy 101.247226 -280.651939) (xy 101.263225 -280.701179) (xy 101.271324 -280.752317)
			(xy 101.271832 -280.778204) (xy 103.432356 -280.778204) (xy 103.432864 -280.752317) (xy 103.440963 -280.701179)
			(xy 103.456962 -280.651939) (xy 103.480468 -280.605807) (xy 103.5109 -280.56392) (xy 103.54751 -280.52731)
			(xy 103.589397 -280.496878) (xy 103.635529 -280.473372) (xy 103.684769 -280.457373) (xy 103.735907 -280.449274)
			(xy 103.787681 -280.449274) (xy 103.838819 -280.457373) (xy 103.888059 -280.473372) (xy 103.934191 -280.496878)
			(xy 103.976078 -280.52731) (xy 104.012688 -280.56392) (xy 104.04312 -280.605807) (xy 104.066626 -280.651939)
			(xy 104.082625 -280.701179) (xy 104.090724 -280.752317) (xy 104.091232 -280.778204) (xy 104.372156 -280.778204)
			(xy 104.372678 -280.752871) (xy 104.380429 -280.702803) (xy 104.395748 -280.654509) (xy 104.418275 -280.609127)
			(xy 104.44748 -280.567726) (xy 104.482675 -280.531281) (xy 104.523032 -280.500649) (xy 104.567599 -280.476552)
			(xy 104.615329 -280.459556) (xy 104.640126 -280.454354) (xy 104.662986 -280.450036) (xy 104.868218 -280.09469)
			(xy 104.860598 -280.072592) (xy 104.851973 -280.04631) (xy 104.842659 -279.991789) (xy 104.842056 -279.964134)
			(xy 104.842564 -279.938227) (xy 104.85067 -279.88705) (xy 104.866682 -279.837771) (xy 104.890205 -279.791604)
			(xy 104.920661 -279.749685) (xy 104.957299 -279.713047) (xy 104.999218 -279.682591) (xy 105.045385 -279.659068)
			(xy 105.094664 -279.643056) (xy 105.145841 -279.63495) (xy 105.197655 -279.63495) (xy 105.248832 -279.643056)
			(xy 105.298111 -279.659068) (xy 105.344278 -279.682591) (xy 105.386197 -279.713047) (xy 105.422835 -279.749685)
			(xy 105.453291 -279.791604) (xy 105.476814 -279.837771) (xy 105.492826 -279.88705) (xy 105.500932 -279.938227)
			(xy 105.50144 -279.964134) (xy 105.501001 -279.989499) (xy 105.500926 -279.989983) (xy 336.806103 -279.989983)
			(xy 336.806103 -279.938217) (xy 336.814201 -279.887089) (xy 336.830196 -279.837856) (xy 336.853696 -279.791732)
			(xy 336.884121 -279.749851) (xy 336.920722 -279.713245) (xy 336.9626 -279.682815) (xy 337.008721 -279.659311)
			(xy 337.057952 -279.64331) (xy 337.109079 -279.635206) (xy 337.134962 -279.634696) (xy 337.160473 -279.635206)
			(xy 337.210886 -279.64306) (xy 337.259487 -279.658588) (xy 337.305115 -279.681418) (xy 337.346681 -279.711006)
			(xy 337.383193 -279.746643) (xy 337.398868 -279.766776) (xy 337.810856 -279.766776) (xy 337.826548 -279.746656)
			(xy 337.863055 -279.711012) (xy 337.904617 -279.681418) (xy 337.950241 -279.658579) (xy 337.998839 -279.643041)
			(xy 338.049251 -279.635176) (xy 338.074762 -279.634696) (xy 338.100656 -279.635106) (xy 338.151807 -279.643203)
			(xy 338.201062 -279.659201) (xy 338.247208 -279.682709) (xy 338.289107 -279.713146) (xy 338.325729 -279.749764)
			(xy 338.356171 -279.79166) (xy 338.379684 -279.837803) (xy 338.395689 -279.887056) (xy 338.403791 -279.938206)
			(xy 338.403791 -279.964134) (xy 344.323924 -279.964134) (xy 344.324432 -279.938227) (xy 344.332538 -279.88705)
			(xy 344.34855 -279.837771) (xy 344.372073 -279.791604) (xy 344.402529 -279.749685) (xy 344.439167 -279.713047)
			(xy 344.481086 -279.682591) (xy 344.527253 -279.659068) (xy 344.576532 -279.643056) (xy 344.627709 -279.63495)
			(xy 344.679523 -279.63495) (xy 344.7307 -279.643056) (xy 344.779979 -279.659068) (xy 344.826146 -279.682591)
			(xy 344.868065 -279.713047) (xy 344.904703 -279.749685) (xy 344.935159 -279.791604) (xy 344.958682 -279.837771)
			(xy 344.974694 -279.88705) (xy 344.9828 -279.938227) (xy 344.983308 -279.964134) (xy 344.982671 -279.991925)
			(xy 344.973225 -280.046702) (xy 344.964512 -280.0731) (xy 344.956892 -280.095198) (xy 345.16187 -280.450036)
			(xy 345.18473 -280.454354) (xy 345.209535 -280.459531) (xy 345.257274 -280.476523) (xy 345.30185 -280.500619)
			(xy 345.342215 -280.531252) (xy 345.377417 -280.5677) (xy 345.406629 -280.609105) (xy 345.429161 -280.654492)
			(xy 345.444484 -280.702792) (xy 345.452236 -280.752868) (xy 345.4527 -280.778204) (xy 345.452192 -280.804091)
			(xy 345.444093 -280.855229) (xy 345.428094 -280.904469) (xy 345.404588 -280.950601) (xy 345.374156 -280.992488)
			(xy 345.337546 -281.029098) (xy 345.295659 -281.05953) (xy 345.249527 -281.083036) (xy 345.200287 -281.099035)
			(xy 345.149149 -281.107134) (xy 345.097375 -281.107134) (xy 345.046237 -281.099035) (xy 344.996997 -281.083036)
			(xy 344.950865 -281.05953) (xy 344.908978 -281.029098) (xy 344.872368 -280.992488) (xy 344.841936 -280.950601)
			(xy 344.81843 -280.904469) (xy 344.802431 -280.855229) (xy 344.794332 -280.804091) (xy 344.793824 -280.778204)
			(xy 344.794353 -280.750496) (xy 344.803549 -280.695849) (xy 344.812112 -280.669492) (xy 344.819986 -280.647394)
			(xy 344.614754 -280.292302) (xy 344.591894 -280.287984) (xy 344.567101 -280.282754) (xy 344.519365 -280.265768)
			(xy 344.47479 -280.241678) (xy 344.434426 -280.211052) (xy 344.399223 -280.174611) (xy 344.37001 -280.133213)
			(xy 344.347475 -280.087832) (xy 344.332148 -280.039538) (xy 344.32439 -279.989468) (xy 344.323924 -279.964134)
			(xy 338.403791 -279.964134) (xy 338.403791 -279.989994) (xy 338.395689 -280.041144) (xy 338.379684 -280.090397)
			(xy 338.356171 -280.13654) (xy 338.325729 -280.178436) (xy 338.289107 -280.215054) (xy 338.247208 -280.245491)
			(xy 338.201062 -280.268999) (xy 338.151807 -280.284997) (xy 338.100656 -280.293094) (xy 338.074762 -280.293572)
			(xy 338.049249 -280.293131) (xy 337.998832 -280.285263) (xy 337.950229 -280.269723) (xy 337.9046 -280.24688)
			(xy 337.863036 -280.21728) (xy 337.826528 -280.18163) (xy 337.810856 -280.161492) (xy 337.398868 -280.161492)
			(xy 337.383211 -280.181641) (xy 337.346698 -280.217284) (xy 337.305129 -280.246877) (xy 337.259498 -280.269711)
			(xy 337.210893 -280.285241) (xy 337.160475 -280.293097) (xy 337.134962 -280.293572) (xy 337.109079 -280.292994)
			(xy 337.057952 -280.28489) (xy 337.008721 -280.268889) (xy 336.9626 -280.245385) (xy 336.920722 -280.214955)
			(xy 336.884121 -280.178349) (xy 336.853696 -280.136468) (xy 336.830196 -280.090344) (xy 336.814201 -280.041111)
			(xy 336.806103 -279.989983) (xy 105.500926 -279.989983) (xy 105.493248 -280.039631) (xy 105.4779 -280.087982)
			(xy 105.45532 -280.133408) (xy 105.426041 -280.174835) (xy 105.390757 -280.211282) (xy 105.350301 -280.241888)
			(xy 105.305631 -280.26593) (xy 105.257803 -280.282837) (xy 105.232962 -280.287984) (xy 105.209848 -280.292302)
			(xy 105.00487 -280.647394) (xy 105.012744 -280.669492) (xy 105.021304 -280.69585) (xy 105.030503 -280.750496)
			(xy 105.031032 -280.778204) (xy 105.030524 -280.804091) (xy 105.030521 -280.804107) (xy 105.31222 -280.804107)
			(xy 105.31222 -280.752293) (xy 105.320326 -280.701118) (xy 105.336337 -280.65184) (xy 105.359859 -280.605674)
			(xy 105.390314 -280.563756) (xy 105.426951 -280.527118) (xy 105.468869 -280.496662) (xy 105.515035 -280.473139)
			(xy 105.564312 -280.457127) (xy 105.615487 -280.449021) (xy 105.641394 -280.448512) (xy 105.666906 -280.448992)
			(xy 105.717321 -280.456852) (xy 105.765922 -280.472385) (xy 105.811551 -280.495221) (xy 105.853116 -280.524814)
			(xy 105.889626 -280.560457) (xy 105.9053 -280.580592) (xy 106.317288 -280.580592) (xy 106.332966 -280.560461)
			(xy 106.369475 -280.524817) (xy 106.41104 -280.495223) (xy 106.456667 -280.472386) (xy 106.505268 -280.456852)
			(xy 106.555682 -280.44899) (xy 106.581194 -280.448512) (xy 106.607104 -280.448985) (xy 106.658286 -280.457091)
			(xy 106.70757 -280.473103) (xy 106.753743 -280.496628) (xy 106.795666 -280.527087) (xy 106.832309 -280.563729)
			(xy 106.862768 -280.605652) (xy 106.886294 -280.651824) (xy 106.902308 -280.701108) (xy 106.910414 -280.75229)
			(xy 106.910414 -280.804105) (xy 342.91452 -280.804105) (xy 342.91452 -280.752295) (xy 342.922625 -280.701122)
			(xy 342.938634 -280.651848) (xy 342.962153 -280.605684) (xy 342.992605 -280.563767) (xy 343.029238 -280.527129)
			(xy 343.071151 -280.496673) (xy 343.117313 -280.473148) (xy 343.166585 -280.457133) (xy 343.217757 -280.449023)
			(xy 343.243662 -280.448512) (xy 343.269173 -280.449015) (xy 343.319587 -280.45687) (xy 343.368188 -280.472399)
			(xy 343.413817 -280.49523) (xy 343.455383 -280.524819) (xy 343.491894 -280.560459) (xy 343.507568 -280.580592)
			(xy 343.91981 -280.580592) (xy 343.935476 -280.56045) (xy 343.971987 -280.524807) (xy 344.013554 -280.495214)
			(xy 344.059184 -280.472379) (xy 344.107788 -280.456847) (xy 344.158204 -280.448988) (xy 344.183716 -280.448512)
			(xy 344.209623 -280.449014) (xy 344.260798 -280.457121) (xy 344.310075 -280.473134) (xy 344.356241 -280.496659)
			(xy 344.398158 -280.527115) (xy 344.434795 -280.563754) (xy 344.465249 -280.605673) (xy 344.488772 -280.65184)
			(xy 344.504782 -280.701117) (xy 344.512888 -280.752293) (xy 344.512888 -280.804107) (xy 344.504782 -280.855283)
			(xy 344.488772 -280.90456) (xy 344.465249 -280.950727) (xy 344.434795 -280.992646) (xy 344.398158 -281.029285)
			(xy 344.356241 -281.059741) (xy 344.310075 -281.083266) (xy 344.260798 -281.099279) (xy 344.209623 -281.107386)
			(xy 344.183716 -281.107896) (xy 344.158205 -281.107405) (xy 344.107791 -281.099547) (xy 344.059189 -281.084016)
			(xy 344.013561 -281.061182) (xy 343.971995 -281.031591) (xy 343.935484 -280.99595) (xy 343.91981 -280.975816)
			(xy 343.507568 -280.975816) (xy 343.491917 -280.99597) (xy 343.455403 -281.031612) (xy 343.413832 -281.061203)
			(xy 343.368199 -281.084036) (xy 343.319593 -281.099566) (xy 343.269175 -281.107421) (xy 343.243662 -281.107896)
			(xy 343.217757 -281.107377) (xy 343.166585 -281.099267) (xy 343.117313 -281.083252) (xy 343.071151 -281.059727)
			(xy 343.029238 -281.029271) (xy 342.992605 -280.992633) (xy 342.962153 -280.950716) (xy 342.938634 -280.904552)
			(xy 342.922625 -280.855278) (xy 342.91452 -280.804105) (xy 106.910414 -280.804105) (xy 106.910414 -280.80411)
			(xy 106.902308 -280.855292) (xy 106.886294 -280.904576) (xy 106.862768 -280.950748) (xy 106.832309 -280.992671)
			(xy 106.795666 -281.029313) (xy 106.753743 -281.059772) (xy 106.70757 -281.083297) (xy 106.658286 -281.099309)
			(xy 106.607104 -281.107415) (xy 106.581194 -281.107896) (xy 106.555682 -281.107421) (xy 106.505267 -281.09956)
			(xy 106.456665 -281.084025) (xy 106.411037 -281.061188) (xy 106.369472 -281.031595) (xy 106.332962 -280.995951)
			(xy 106.317288 -280.975816) (xy 105.9053 -280.975816) (xy 105.889631 -280.995955) (xy 105.85312 -281.031598)
			(xy 105.811553 -281.06119) (xy 105.765924 -281.084026) (xy 105.717322 -281.099559) (xy 105.666906 -281.107419)
			(xy 105.641394 -281.107896) (xy 105.615487 -281.107379) (xy 105.564312 -281.099273) (xy 105.515035 -281.083261)
			(xy 105.468869 -281.059738) (xy 105.426951 -281.029282) (xy 105.390314 -280.992644) (xy 105.359859 -280.950726)
			(xy 105.336337 -280.90456) (xy 105.320326 -280.855282) (xy 105.31222 -280.804107) (xy 105.030521 -280.804107)
			(xy 105.022425 -280.855229) (xy 105.006426 -280.904469) (xy 104.98292 -280.950601) (xy 104.952488 -280.992488)
			(xy 104.915878 -281.029098) (xy 104.873991 -281.05953) (xy 104.827859 -281.083036) (xy 104.778619 -281.099035)
			(xy 104.727481 -281.107134) (xy 104.675707 -281.107134) (xy 104.624569 -281.099035) (xy 104.575329 -281.083036)
			(xy 104.529197 -281.05953) (xy 104.48731 -281.029098) (xy 104.4507 -280.992488) (xy 104.420268 -280.950601)
			(xy 104.396762 -280.904469) (xy 104.380763 -280.855229) (xy 104.372664 -280.804091) (xy 104.372156 -280.778204)
			(xy 104.091232 -280.778204) (xy 104.091232 -280.778712) (xy 104.090641 -280.806228) (xy 104.081455 -280.860489)
			(xy 104.072944 -280.886662) (xy 104.065324 -280.908506) (xy 104.270556 -281.263852) (xy 104.293416 -281.26817)
			(xy 104.318226 -281.273386) (xy 104.366003 -281.290334) (xy 104.410622 -281.314398) (xy 104.451028 -281.345012)
			(xy 104.48627 -281.381453) (xy 104.515516 -281.422861) (xy 104.538075 -281.468259) (xy 104.553416 -281.516576)
			(xy 104.561176 -281.566673) (xy 104.56164 -281.59202) (xy 105.781856 -281.59202) (xy 105.782364 -281.566113)
			(xy 105.79047 -281.514936) (xy 105.806482 -281.465657) (xy 105.830005 -281.41949) (xy 105.860461 -281.377571)
			(xy 105.897099 -281.340933) (xy 105.939018 -281.310477) (xy 105.985185 -281.286954) (xy 106.034464 -281.270942)
			(xy 106.085641 -281.262836) (xy 106.137455 -281.262836) (xy 106.188632 -281.270942) (xy 106.237911 -281.286954)
			(xy 106.284078 -281.310477) (xy 106.325997 -281.340933) (xy 106.362635 -281.377571) (xy 106.393091 -281.41949)
			(xy 106.416614 -281.465657) (xy 106.432626 -281.514936) (xy 106.440732 -281.566113) (xy 106.44124 -281.59202)
			(xy 106.440709 -281.617904) (xy 338.685436 -281.617904) (xy 338.685436 -281.566096) (xy 338.69354 -281.514926)
			(xy 338.709548 -281.465654) (xy 338.733067 -281.419492) (xy 338.763517 -281.377577) (xy 338.800148 -281.340942)
			(xy 338.84206 -281.310487) (xy 338.888219 -281.286963) (xy 338.937489 -281.270949) (xy 338.988658 -281.262839)
			(xy 339.014562 -281.262328) (xy 339.040073 -281.262825) (xy 339.090487 -281.270681) (xy 339.139089 -281.28621)
			(xy 339.184718 -281.309042) (xy 339.226284 -281.338633) (xy 339.262794 -281.374274) (xy 339.278468 -281.394408)
			(xy 339.690456 -281.394408) (xy 339.706157 -281.374295) (xy 339.742661 -281.33865) (xy 339.784221 -281.309053)
			(xy 339.829844 -281.286213) (xy 339.878441 -281.270675) (xy 339.928852 -281.262808) (xy 339.954362 -281.262328)
			(xy 339.980275 -281.262767) (xy 340.031464 -281.270869) (xy 340.080754 -281.286879) (xy 340.126933 -281.310404)
			(xy 340.168863 -281.340863) (xy 340.205512 -281.377508) (xy 340.235976 -281.419434) (xy 340.259506 -281.465611)
			(xy 340.275522 -281.514899) (xy 340.28363 -281.566087) (xy 340.28363 -281.617913) (xy 340.275522 -281.669101)
			(xy 340.259506 -281.718389) (xy 340.235976 -281.764566) (xy 340.205512 -281.806492) (xy 340.168863 -281.843137)
			(xy 340.126933 -281.873596) (xy 340.080754 -281.897121) (xy 340.031464 -281.913131) (xy 339.980275 -281.921233)
			(xy 339.954362 -281.921712) (xy 339.928849 -281.921255) (xy 339.878434 -281.913389) (xy 339.829832 -281.89785)
			(xy 339.784204 -281.87501) (xy 339.742639 -281.845414) (xy 339.706129 -281.809768) (xy 339.690456 -281.789632)
			(xy 339.278468 -281.789632) (xy 339.262822 -281.80979) (xy 339.226306 -281.845431) (xy 339.184734 -281.875021)
			(xy 339.139101 -281.897853) (xy 339.090494 -281.913382) (xy 339.040076 -281.921238) (xy 339.014562 -281.921712)
			(xy 338.988658 -281.921161) (xy 338.937489 -281.913051) (xy 338.888219 -281.897037) (xy 338.84206 -281.873513)
			(xy 338.800148 -281.843058) (xy 338.763517 -281.806423) (xy 338.733067 -281.764508) (xy 338.709548 -281.718346)
			(xy 338.69354 -281.669074) (xy 338.685436 -281.617904) (xy 106.440709 -281.617904) (xy 106.44067 -281.619802)
			(xy 106.431345 -281.674578) (xy 106.422698 -281.700986) (xy 106.414824 -281.72283) (xy 106.619802 -282.077668)
			(xy 106.642662 -282.081986) (xy 106.667464 -282.087182) (xy 106.715205 -282.104167) (xy 106.759784 -282.128258)
			(xy 106.800151 -282.158887) (xy 106.835356 -282.195333) (xy 106.864568 -282.236737) (xy 106.8871 -282.282123)
			(xy 106.902422 -282.330424) (xy 106.910171 -282.3805) (xy 106.910632 -282.405836) (xy 335.395824 -282.405836)
			(xy 335.396332 -282.379949) (xy 335.404431 -282.328811) (xy 335.42043 -282.279571) (xy 335.443936 -282.233439)
			(xy 335.474368 -282.191552) (xy 335.510978 -282.154942) (xy 335.552865 -282.12451) (xy 335.598997 -282.101004)
			(xy 335.648237 -282.085005) (xy 335.699375 -282.076906) (xy 335.751149 -282.076906) (xy 335.802287 -282.085005)
			(xy 335.851527 -282.101004) (xy 335.897659 -282.12451) (xy 335.939546 -282.154942) (xy 335.976156 -282.191552)
			(xy 336.006588 -282.233439) (xy 336.030094 -282.279571) (xy 336.046093 -282.328811) (xy 336.054192 -282.379949)
			(xy 336.0547 -282.405836) (xy 341.034624 -282.405836) (xy 341.035068 -282.38049) (xy 341.04285 -282.330397)
			(xy 341.058205 -282.282085) (xy 341.080771 -282.236692) (xy 341.110018 -282.195286) (xy 341.145256 -282.158843)
			(xy 341.185656 -282.128222) (xy 341.230265 -282.104142) (xy 341.278033 -282.087172) (xy 341.302848 -282.081986)
			(xy 341.325708 -282.077668) (xy 341.530686 -281.72283) (xy 341.522812 -281.700986) (xy 341.514229 -281.674568)
			(xy 341.505035 -281.619792) (xy 341.504524 -281.59202) (xy 341.505032 -281.566133) (xy 341.513131 -281.514995)
			(xy 341.52913 -281.465755) (xy 341.552636 -281.419623) (xy 341.583068 -281.377736) (xy 341.619678 -281.341126)
			(xy 341.661565 -281.310694) (xy 341.707697 -281.287188) (xy 341.756937 -281.271189) (xy 341.808075 -281.26309)
			(xy 341.859849 -281.26309) (xy 341.910987 -281.271189) (xy 341.960227 -281.287188) (xy 342.006359 -281.310694)
			(xy 342.048246 -281.341126) (xy 342.084856 -281.377736) (xy 342.115288 -281.419623) (xy 342.138794 -281.465755)
			(xy 342.154793 -281.514995) (xy 342.162892 -281.566133) (xy 342.1634 -281.59202) (xy 342.162935 -281.617355)
			(xy 342.15518 -281.667428) (xy 342.139855 -281.715725) (xy 342.117321 -281.761109) (xy 342.088109 -281.802511)
			(xy 342.052906 -281.838956) (xy 342.012542 -281.869586) (xy 341.967967 -281.89368) (xy 341.92023 -281.910671)
			(xy 341.89543 -281.91587) (xy 341.87257 -281.920188) (xy 341.667592 -282.275026) (xy 341.675466 -282.297124)
			(xy 341.684085 -282.323474) (xy 341.693414 -282.378119) (xy 341.694008 -282.405836) (xy 342.914224 -282.405836)
			(xy 342.914629 -282.380499) (xy 342.922392 -282.330422) (xy 342.937724 -282.282122) (xy 342.960266 -282.236737)
			(xy 342.989485 -282.195335) (xy 343.024695 -282.15889) (xy 343.065066 -282.128262) (xy 343.109648 -282.10417)
			(xy 343.157391 -282.087183) (xy 343.182194 -282.081986) (xy 343.205054 -282.077668) (xy 343.410286 -281.722322)
			(xy 343.402666 -281.700478) (xy 343.39404 -281.674196) (xy 343.384726 -281.619675) (xy 343.384124 -281.59202)
			(xy 343.384632 -281.566113) (xy 343.392738 -281.514936) (xy 343.40875 -281.465657) (xy 343.432273 -281.41949)
			(xy 343.462729 -281.377571) (xy 343.499367 -281.340933) (xy 343.541286 -281.310477) (xy 343.587453 -281.286954)
			(xy 343.636732 -281.270942) (xy 343.687909 -281.262836) (xy 343.739723 -281.262836) (xy 343.7909 -281.270942)
			(xy 343.840179 -281.286954) (xy 343.886346 -281.310477) (xy 343.928265 -281.340933) (xy 343.964903 -281.377571)
			(xy 343.995359 -281.41949) (xy 344.018882 -281.465657) (xy 344.034894 -281.514936) (xy 344.043 -281.566113)
			(xy 344.043508 -281.59202) (xy 345.263724 -281.59202) (xy 345.264244 -281.566676) (xy 345.272013 -281.516587)
			(xy 345.287357 -281.468277) (xy 345.309913 -281.422884) (xy 345.33915 -281.381477) (xy 345.374379 -281.345033)
			(xy 345.414771 -281.31441) (xy 345.459374 -281.290329) (xy 345.507136 -281.273357) (xy 345.531948 -281.26817)
			(xy 345.554808 -281.263852) (xy 345.759786 -280.909014) (xy 345.751912 -280.88717) (xy 345.743326 -280.860753)
			(xy 345.734134 -280.805977) (xy 345.733624 -280.778204) (xy 345.734132 -280.752317) (xy 345.742231 -280.701179)
			(xy 345.75823 -280.651939) (xy 345.781736 -280.605807) (xy 345.812168 -280.56392) (xy 345.848778 -280.52731)
			(xy 345.890665 -280.496878) (xy 345.936797 -280.473372) (xy 345.986037 -280.457373) (xy 346.037175 -280.449274)
			(xy 346.088949 -280.449274) (xy 346.140087 -280.457373) (xy 346.189327 -280.473372) (xy 346.235459 -280.496878)
			(xy 346.277346 -280.52731) (xy 346.313956 -280.56392) (xy 346.344388 -280.605807) (xy 346.367894 -280.651939)
			(xy 346.383893 -280.701179) (xy 346.391992 -280.752317) (xy 346.3925 -280.778204) (xy 348.553024 -280.778204)
			(xy 348.553532 -280.752317) (xy 348.561631 -280.701179) (xy 348.57763 -280.651939) (xy 348.601136 -280.605807)
			(xy 348.631568 -280.56392) (xy 348.668178 -280.52731) (xy 348.710065 -280.496878) (xy 348.756197 -280.473372)
			(xy 348.805437 -280.457373) (xy 348.856575 -280.449274) (xy 348.908349 -280.449274) (xy 348.959487 -280.457373)
			(xy 349.008727 -280.473372) (xy 349.054859 -280.496878) (xy 349.096746 -280.52731) (xy 349.133356 -280.56392)
			(xy 349.163788 -280.605807) (xy 349.187294 -280.651939) (xy 349.203293 -280.701179) (xy 349.211392 -280.752317)
			(xy 349.2119 -280.778204) (xy 351.372424 -280.778204) (xy 351.372932 -280.752317) (xy 351.381031 -280.701179)
			(xy 351.39703 -280.651939) (xy 351.420536 -280.605807) (xy 351.450968 -280.56392) (xy 351.487578 -280.52731)
			(xy 351.529465 -280.496878) (xy 351.575597 -280.473372) (xy 351.624837 -280.457373) (xy 351.675975 -280.449274)
			(xy 351.727749 -280.449274) (xy 351.778887 -280.457373) (xy 351.828127 -280.473372) (xy 351.874259 -280.496878)
			(xy 351.916146 -280.52731) (xy 351.952756 -280.56392) (xy 351.983188 -280.605807) (xy 352.006694 -280.651939)
			(xy 352.022693 -280.701179) (xy 352.030792 -280.752317) (xy 352.0313 -280.778204) (xy 352.312224 -280.778204)
			(xy 352.312691 -280.752869) (xy 352.320444 -280.702795) (xy 352.335767 -280.654496) (xy 352.3583 -280.609112)
			(xy 352.387511 -280.567709) (xy 352.422714 -280.531263) (xy 352.463079 -280.500633) (xy 352.507655 -280.47654)
			(xy 352.555393 -280.459552) (xy 352.580194 -280.454354) (xy 352.603054 -280.450036) (xy 352.808286 -280.09469)
			(xy 352.800666 -280.072592) (xy 352.792043 -280.046309) (xy 352.782727 -279.991789) (xy 352.782124 -279.964134)
			(xy 352.782632 -279.938227) (xy 352.790738 -279.88705) (xy 352.80675 -279.837771) (xy 352.830273 -279.791604)
			(xy 352.860729 -279.749685) (xy 352.897367 -279.713047) (xy 352.939286 -279.682591) (xy 352.985453 -279.659068)
			(xy 353.034732 -279.643056) (xy 353.085909 -279.63495) (xy 353.137723 -279.63495) (xy 353.1889 -279.643056)
			(xy 353.238179 -279.659068) (xy 353.284346 -279.682591) (xy 353.326265 -279.713047) (xy 353.362903 -279.749685)
			(xy 353.393359 -279.791604) (xy 353.416882 -279.837771) (xy 353.432894 -279.88705) (xy 353.441 -279.938227)
			(xy 353.441508 -279.964134) (xy 353.441095 -279.9895) (xy 353.433341 -280.039635) (xy 353.417991 -280.087988)
			(xy 353.395408 -280.133416) (xy 353.366127 -280.174843) (xy 353.330839 -280.211291) (xy 353.290379 -280.241896)
			(xy 353.245705 -280.265935) (xy 353.197873 -280.282839) (xy 353.17303 -280.287984) (xy 353.149916 -280.292302)
			(xy 352.944938 -280.647394) (xy 352.952812 -280.669492) (xy 352.961371 -280.695851) (xy 352.970571 -280.750496)
			(xy 352.9711 -280.778204) (xy 352.970592 -280.804091) (xy 352.97059 -280.804105) (xy 353.25232 -280.804105)
			(xy 353.25232 -280.752295) (xy 353.260425 -280.701122) (xy 353.276434 -280.651848) (xy 353.299953 -280.605684)
			(xy 353.330405 -280.563767) (xy 353.367038 -280.527129) (xy 353.408951 -280.496673) (xy 353.455113 -280.473148)
			(xy 353.504385 -280.457133) (xy 353.555557 -280.449023) (xy 353.581462 -280.448512) (xy 353.606973 -280.449015)
			(xy 353.657387 -280.45687) (xy 353.705988 -280.472399) (xy 353.751617 -280.49523) (xy 353.793183 -280.524819)
			(xy 353.829694 -280.560459) (xy 353.845368 -280.580592) (xy 354.257356 -280.580592) (xy 354.273053 -280.560476)
			(xy 354.309558 -280.524831) (xy 354.351119 -280.495236) (xy 354.396742 -280.472396) (xy 354.44534 -280.456858)
			(xy 354.495751 -280.448992) (xy 354.521262 -280.448512) (xy 354.547174 -280.448983) (xy 354.59836 -280.457084)
			(xy 354.647648 -280.473094) (xy 354.693825 -280.496618) (xy 354.735753 -280.527076) (xy 354.7724 -280.563718)
			(xy 354.802863 -280.605643) (xy 354.826391 -280.651817) (xy 354.842407 -280.701103) (xy 354.850514 -280.752288)
			(xy 354.850514 -280.804112) (xy 354.842407 -280.855297) (xy 354.826391 -280.904583) (xy 354.802863 -280.950757)
			(xy 354.7724 -280.992682) (xy 354.735753 -281.029324) (xy 354.693825 -281.059782) (xy 354.647648 -281.083306)
			(xy 354.59836 -281.099316) (xy 354.547174 -281.107417) (xy 354.521262 -281.107896) (xy 354.495749 -281.107445)
			(xy 354.445333 -281.099578) (xy 354.396731 -281.084039) (xy 354.351103 -281.061198) (xy 354.309538 -281.031601)
			(xy 354.273029 -280.995953) (xy 354.257356 -280.975816) (xy 353.845368 -280.975816) (xy 353.829717 -280.99597)
			(xy 353.793203 -281.031612) (xy 353.751632 -281.061203) (xy 353.705999 -281.084036) (xy 353.657393 -281.099566)
			(xy 353.606975 -281.107421) (xy 353.581462 -281.107896) (xy 353.555557 -281.107377) (xy 353.504385 -281.099267)
			(xy 353.455113 -281.083252) (xy 353.408951 -281.059727) (xy 353.367038 -281.029271) (xy 353.330405 -280.992633)
			(xy 353.299953 -280.950716) (xy 353.276434 -280.904552) (xy 353.260425 -280.855278) (xy 353.25232 -280.804105)
			(xy 352.97059 -280.804105) (xy 352.962493 -280.855229) (xy 352.946494 -280.904469) (xy 352.922988 -280.950601)
			(xy 352.892556 -280.992488) (xy 352.855946 -281.029098) (xy 352.814059 -281.05953) (xy 352.767927 -281.083036)
			(xy 352.718687 -281.099035) (xy 352.667549 -281.107134) (xy 352.615775 -281.107134) (xy 352.564637 -281.099035)
			(xy 352.515397 -281.083036) (xy 352.469265 -281.05953) (xy 352.427378 -281.029098) (xy 352.390768 -280.992488)
			(xy 352.360336 -280.950601) (xy 352.33683 -280.904469) (xy 352.320831 -280.855229) (xy 352.312732 -280.804091)
			(xy 352.312224 -280.778204) (xy 352.0313 -280.778204) (xy 352.0313 -280.778712) (xy 352.03071 -280.806228)
			(xy 352.021524 -280.860489) (xy 352.013012 -280.886662) (xy 352.005392 -280.908506) (xy 352.210624 -281.263852)
			(xy 352.233484 -281.26817) (xy 352.258305 -281.273337) (xy 352.306082 -281.290294) (xy 352.350699 -281.314367)
			(xy 352.391104 -281.344988) (xy 352.426344 -281.381435) (xy 352.455588 -281.422848) (xy 352.478145 -281.46825)
			(xy 352.493485 -281.516571) (xy 352.501244 -281.566671) (xy 352.501708 -281.59202) (xy 353.721924 -281.59202)
			(xy 353.722432 -281.566113) (xy 353.730538 -281.514936) (xy 353.74655 -281.465657) (xy 353.770073 -281.41949)
			(xy 353.800529 -281.377571) (xy 353.837167 -281.340933) (xy 353.879086 -281.310477) (xy 353.925253 -281.286954)
			(xy 353.974532 -281.270942) (xy 354.025709 -281.262836) (xy 354.077523 -281.262836) (xy 354.1287 -281.270942)
			(xy 354.177979 -281.286954) (xy 354.224146 -281.310477) (xy 354.266065 -281.340933) (xy 354.302703 -281.377571)
			(xy 354.333159 -281.41949) (xy 354.356682 -281.465657) (xy 354.372694 -281.514936) (xy 354.3808 -281.566113)
			(xy 354.381308 -281.59202) (xy 354.380739 -281.619802) (xy 354.371414 -281.674578) (xy 354.362766 -281.700986)
			(xy 354.354892 -281.72283) (xy 354.55987 -282.077668) (xy 354.58273 -282.081986) (xy 354.607543 -282.087133)
			(xy 354.655283 -282.104127) (xy 354.699861 -282.128227) (xy 354.740227 -282.158863) (xy 354.775429 -282.195315)
			(xy 354.80464 -282.236724) (xy 354.82717 -282.282115) (xy 354.84249 -282.330419) (xy 354.850239 -282.380498)
			(xy 354.8507 -282.405836) (xy 354.850192 -282.431723) (xy 354.842093 -282.482861) (xy 354.826094 -282.532101)
			(xy 354.802588 -282.578233) (xy 354.772156 -282.62012) (xy 354.735546 -282.65673) (xy 354.693659 -282.687162)
			(xy 354.647527 -282.710668) (xy 354.598287 -282.726667) (xy 354.547149 -282.734766) (xy 354.495375 -282.734766)
			(xy 354.444237 -282.726667) (xy 354.394997 -282.710668) (xy 354.348865 -282.687162) (xy 354.306978 -282.65673)
			(xy 354.270368 -282.62012) (xy 354.239936 -282.578233) (xy 354.21643 -282.532101) (xy 354.200431 -282.482861)
			(xy 354.192332 -282.431723) (xy 354.191824 -282.405836) (xy 354.192361 -282.378128) (xy 354.201551 -282.323481)
			(xy 354.210112 -282.297124) (xy 354.217986 -282.275026) (xy 354.013008 -281.920188) (xy 353.990148 -281.91587)
			(xy 353.965319 -281.910737) (xy 353.917537 -281.893779) (xy 353.872916 -281.869705) (xy 353.832509 -281.83908)
			(xy 353.797268 -281.802629) (xy 353.768025 -281.761211) (xy 353.74547 -281.715803) (xy 353.730136 -281.667476)
			(xy 353.722383 -281.617371) (xy 353.721924 -281.59202) (xy 352.501708 -281.59202) (xy 352.5012 -281.617927)
			(xy 352.493094 -281.669104) (xy 352.477082 -281.718383) (xy 352.453559 -281.76455) (xy 352.423103 -281.806469)
			(xy 352.386465 -281.843107) (xy 352.344546 -281.873563) (xy 352.298379 -281.897086) (xy 352.2491 -281.913098)
			(xy 352.197923 -281.921204) (xy 352.146109 -281.921204) (xy 352.094932 -281.913098) (xy 352.045653 -281.897086)
			(xy 351.999486 -281.873563) (xy 351.957567 -281.843107) (xy 351.920929 -281.806469) (xy 351.890473 -281.76455)
			(xy 351.86695 -281.718383) (xy 351.850938 -281.669104) (xy 351.842832 -281.617927) (xy 351.842324 -281.59202)
			(xy 351.842922 -281.564303) (xy 351.852242 -281.509656) (xy 351.860866 -281.483308) (xy 351.86874 -281.46121)
			(xy 351.663762 -281.106372) (xy 351.640902 -281.102054) (xy 351.616072 -281.096882) (xy 351.568266 -281.079946)
			(xy 351.523618 -281.055889) (xy 351.483181 -281.025278) (xy 351.447909 -280.988835) (xy 351.418634 -280.947421)
			(xy 351.396047 -280.902011) (xy 351.380681 -280.853678) (xy 351.372898 -280.803562) (xy 351.372424 -280.778204)
			(xy 349.2119 -280.778204) (xy 349.2119 -280.778712) (xy 349.21131 -280.806228) (xy 349.202124 -280.860489)
			(xy 349.193612 -280.886662) (xy 349.185992 -280.908506) (xy 349.391224 -281.263852) (xy 349.414084 -281.26817)
			(xy 349.438905 -281.273337) (xy 349.486682 -281.290294) (xy 349.531299 -281.314367) (xy 349.571704 -281.344988)
			(xy 349.606944 -281.381435) (xy 349.636188 -281.422848) (xy 349.658745 -281.46825) (xy 349.674085 -281.516571)
			(xy 349.681844 -281.566671) (xy 349.682308 -281.59202) (xy 349.6818 -281.617927) (xy 349.673694 -281.669104)
			(xy 349.657682 -281.718383) (xy 349.634159 -281.76455) (xy 349.603703 -281.806469) (xy 349.567065 -281.843107)
			(xy 349.525146 -281.873563) (xy 349.478979 -281.897086) (xy 349.4297 -281.913098) (xy 349.378523 -281.921204)
			(xy 349.326709 -281.921204) (xy 349.275532 -281.913098) (xy 349.226253 -281.897086) (xy 349.180086 -281.873563)
			(xy 349.138167 -281.843107) (xy 349.101529 -281.806469) (xy 349.071073 -281.76455) (xy 349.04755 -281.718383)
			(xy 349.031538 -281.669104) (xy 349.023432 -281.617927) (xy 349.022924 -281.59202) (xy 349.023522 -281.564303)
			(xy 349.032842 -281.509656) (xy 349.041466 -281.483308) (xy 349.04934 -281.46121) (xy 348.844362 -281.106372)
			(xy 348.821502 -281.102054) (xy 348.796672 -281.096882) (xy 348.748866 -281.079946) (xy 348.704218 -281.055889)
			(xy 348.663781 -281.025278) (xy 348.628509 -280.988835) (xy 348.599234 -280.947421) (xy 348.576647 -280.902011)
			(xy 348.561281 -280.853678) (xy 348.553498 -280.803562) (xy 348.553024 -280.778204) (xy 346.3925 -280.778204)
			(xy 346.392021 -280.803539) (xy 346.384268 -280.853611) (xy 346.368945 -280.901908) (xy 346.346413 -280.947292)
			(xy 346.317203 -280.988694) (xy 346.282002 -281.025139) (xy 346.241639 -281.055769) (xy 346.197065 -281.079864)
			(xy 346.14933 -281.096855) (xy 346.12453 -281.102054) (xy 346.10167 -281.106372) (xy 345.896692 -281.46121)
			(xy 345.904566 -281.483308) (xy 345.913205 -281.509652) (xy 345.922521 -281.564301) (xy 345.923108 -281.59202)
			(xy 345.9226 -281.617909) (xy 347.143809 -281.617909) (xy 347.143809 -281.566091) (xy 347.151916 -281.514912)
			(xy 347.167929 -281.465631) (xy 347.191454 -281.419462) (xy 347.221912 -281.377541) (xy 347.258553 -281.340902)
			(xy 347.300475 -281.310446) (xy 347.346646 -281.286923) (xy 347.395928 -281.270912) (xy 347.447107 -281.262808)
			(xy 347.473016 -281.262328) (xy 347.498529 -281.262786) (xy 347.548945 -281.27065) (xy 347.597547 -281.286187)
			(xy 347.643176 -281.309027) (xy 347.684741 -281.338624) (xy 347.721249 -281.374271) (xy 347.736922 -281.394408)
			(xy 348.14891 -281.394408) (xy 348.16458 -281.37427) (xy 348.20109 -281.338625) (xy 348.242656 -281.309032)
			(xy 348.288285 -281.286196) (xy 348.336888 -281.270663) (xy 348.387304 -281.262804) (xy 348.412816 -281.262328)
			(xy 348.438724 -281.262797) (xy 348.489902 -281.270905) (xy 348.539182 -281.286919) (xy 348.585349 -281.310445)
			(xy 348.627269 -281.340903) (xy 348.663907 -281.377543) (xy 348.694363 -281.419464) (xy 348.717887 -281.465633)
			(xy 348.733899 -281.514914) (xy 348.742004 -281.566092) (xy 348.742004 -281.617908) (xy 348.733899 -281.669086)
			(xy 348.717887 -281.718367) (xy 348.694363 -281.764536) (xy 348.663907 -281.806457) (xy 348.627269 -281.843097)
			(xy 348.585349 -281.873555) (xy 348.539182 -281.897081) (xy 348.489902 -281.913095) (xy 348.438724 -281.921203)
			(xy 348.412816 -281.921712) (xy 348.387305 -281.921215) (xy 348.336891 -281.913357) (xy 348.28829 -281.897827)
			(xy 348.242662 -281.874994) (xy 348.201096 -281.845405) (xy 348.164585 -281.809765) (xy 348.14891 -281.789632)
			(xy 347.736922 -281.789632) (xy 347.721245 -281.809764) (xy 347.684735 -281.845407) (xy 347.64317 -281.875)
			(xy 347.597542 -281.897836) (xy 347.548942 -281.913371) (xy 347.498528 -281.921234) (xy 347.473016 -281.921712)
			(xy 347.447107 -281.921192) (xy 347.395928 -281.913088) (xy 347.346646 -281.897077) (xy 347.300475 -281.873554)
			(xy 347.258553 -281.843098) (xy 347.221912 -281.806459) (xy 347.191454 -281.764538) (xy 347.167929 -281.718369)
			(xy 347.151916 -281.669088) (xy 347.143809 -281.617909) (xy 345.9226 -281.617909) (xy 345.9226 -281.617927)
			(xy 345.914494 -281.669104) (xy 345.898482 -281.718383) (xy 345.874959 -281.76455) (xy 345.844503 -281.806469)
			(xy 345.807865 -281.843107) (xy 345.765946 -281.873563) (xy 345.719779 -281.897086) (xy 345.6705 -281.913098)
			(xy 345.619323 -281.921204) (xy 345.567509 -281.921204) (xy 345.516332 -281.913098) (xy 345.467053 -281.897086)
			(xy 345.420886 -281.873563) (xy 345.378967 -281.843107) (xy 345.342329 -281.806469) (xy 345.311873 -281.76455)
			(xy 345.28835 -281.718383) (xy 345.272338 -281.669104) (xy 345.264232 -281.617927) (xy 345.263724 -281.59202)
			(xy 344.043508 -281.59202) (xy 344.043045 -281.617395) (xy 344.035274 -281.667545) (xy 344.019903 -281.71591)
			(xy 343.997297 -281.761346) (xy 343.967989 -281.802777) (xy 343.932674 -281.839223) (xy 343.892188 -281.869822)
			(xy 343.847487 -281.893849) (xy 343.79963 -281.910736) (xy 343.774776 -281.91587) (xy 343.751916 -281.920188)
			(xy 343.546938 -282.275026) (xy 343.554812 -282.297124) (xy 343.563378 -282.32348) (xy 343.572573 -282.378127)
			(xy 343.5731 -282.405836) (xy 343.854024 -282.405836) (xy 343.854532 -282.379949) (xy 343.862631 -282.328811)
			(xy 343.87863 -282.279571) (xy 343.902136 -282.233439) (xy 343.932568 -282.191552) (xy 343.969178 -282.154942)
			(xy 344.011065 -282.12451) (xy 344.057197 -282.101004) (xy 344.106437 -282.085005) (xy 344.157575 -282.076906)
			(xy 344.209349 -282.076906) (xy 344.260487 -282.085005) (xy 344.309727 -282.101004) (xy 344.355859 -282.12451)
			(xy 344.397746 -282.154942) (xy 344.434356 -282.191552) (xy 344.464788 -282.233439) (xy 344.488294 -282.279571)
			(xy 344.504293 -282.328811) (xy 344.512392 -282.379949) (xy 344.5129 -282.405836) (xy 344.5129 -282.406344)
			(xy 344.512364 -282.431703) (xy 344.794152 -282.431703) (xy 344.794152 -282.379897) (xy 344.802256 -282.32873)
			(xy 344.818263 -282.27946) (xy 344.841781 -282.2333) (xy 344.872229 -282.191388) (xy 344.908859 -282.154754)
			(xy 344.950768 -282.124301) (xy 344.996925 -282.100778) (xy 345.046193 -282.084765) (xy 345.097359 -282.076655)
			(xy 345.123262 -282.076144) (xy 345.148774 -282.076635) (xy 345.199188 -282.084491) (xy 345.247791 -282.100021)
			(xy 345.293419 -282.122855) (xy 345.334985 -282.152446) (xy 345.371495 -282.188089) (xy 345.387168 -282.208224)
			(xy 345.799156 -282.208224) (xy 345.814861 -282.188115) (xy 345.851364 -282.152468) (xy 345.892922 -282.122871)
			(xy 345.938545 -282.10003) (xy 345.987141 -282.084491) (xy 346.037552 -282.076624) (xy 346.063062 -282.076144)
			(xy 346.088976 -282.076551) (xy 346.140167 -282.084653) (xy 346.18946 -282.100664) (xy 346.235642 -282.12419)
			(xy 346.277574 -282.154651) (xy 346.314224 -282.191297) (xy 346.34469 -282.233226) (xy 346.368221 -282.279404)
			(xy 346.384238 -282.328696) (xy 346.392346 -282.379886) (xy 346.392346 -282.431714) (xy 346.384238 -282.482904)
			(xy 346.368221 -282.532196) (xy 346.34469 -282.578374) (xy 346.314224 -282.620303) (xy 346.277574 -282.656949)
			(xy 346.235642 -282.68741) (xy 346.18946 -282.710936) (xy 346.140167 -282.726947) (xy 346.088976 -282.735049)
			(xy 346.063062 -282.735528) (xy 346.03755 -282.735064) (xy 345.987135 -282.727199) (xy 345.938534 -282.711661)
			(xy 345.892906 -282.688822) (xy 345.85134 -282.659228) (xy 345.81483 -282.623584) (xy 345.799156 -282.603448)
			(xy 345.387168 -282.603448) (xy 345.371526 -282.623609) (xy 345.335009 -282.659249) (xy 345.293436 -282.688839)
			(xy 345.247802 -282.71167) (xy 345.199195 -282.727199) (xy 345.148776 -282.735054) (xy 345.123262 -282.735528)
			(xy 345.097359 -282.734945) (xy 345.046193 -282.726835) (xy 344.996925 -282.710822) (xy 344.950768 -282.687299)
			(xy 344.908859 -282.656846) (xy 344.872229 -282.620212) (xy 344.841781 -282.5783) (xy 344.818263 -282.53214)
			(xy 344.802256 -282.48287) (xy 344.794152 -282.431703) (xy 344.512364 -282.431703) (xy 344.512318 -282.43386)
			(xy 344.503126 -282.488122) (xy 344.494612 -282.514294) (xy 344.486992 -282.536392) (xy 344.692224 -282.891738)
			(xy 344.715084 -282.896056) (xy 344.739902 -282.901236) (xy 344.787678 -282.918192) (xy 344.832294 -282.942264)
			(xy 344.872699 -282.972884) (xy 344.907939 -283.009329) (xy 344.937183 -283.05074) (xy 344.959741 -283.09614)
			(xy 344.975082 -283.14446) (xy 344.982843 -283.194558) (xy 344.983308 -283.219906) (xy 347.143324 -283.219906)
			(xy 347.143831 -283.194562) (xy 347.151603 -283.144472) (xy 347.166948 -283.096161) (xy 347.189506 -283.050768)
			(xy 347.218745 -283.009362) (xy 347.253975 -282.972918) (xy 347.294368 -282.942295) (xy 347.338972 -282.918214)
			(xy 347.386736 -282.901243) (xy 347.411548 -282.896056) (xy 347.434408 -282.891738) (xy 347.639386 -282.5369)
			(xy 347.631766 -282.514802) (xy 347.623129 -282.488391) (xy 347.613803 -282.433617) (xy 347.613224 -282.405836)
			(xy 347.613732 -282.379949) (xy 347.621831 -282.328811) (xy 347.63783 -282.279571) (xy 347.661336 -282.233439)
			(xy 347.691768 -282.191552) (xy 347.728378 -282.154942) (xy 347.770265 -282.12451) (xy 347.816397 -282.101004)
			(xy 347.865637 -282.085005) (xy 347.916775 -282.076906) (xy 347.968549 -282.076906) (xy 348.019687 -282.085005)
			(xy 348.068927 -282.101004) (xy 348.115059 -282.12451) (xy 348.156946 -282.154942) (xy 348.193556 -282.191552)
			(xy 348.223988 -282.233439) (xy 348.247494 -282.279571) (xy 348.263493 -282.328811) (xy 348.271592 -282.379949)
			(xy 348.2721 -282.405836) (xy 349.492824 -282.405836) (xy 349.493229 -282.380499) (xy 349.500992 -282.330422)
			(xy 349.516324 -282.282122) (xy 349.538866 -282.236737) (xy 349.568085 -282.195335) (xy 349.603295 -282.15889)
			(xy 349.643666 -282.128262) (xy 349.688248 -282.10417) (xy 349.735991 -282.087183) (xy 349.760794 -282.081986)
			(xy 349.783654 -282.077668) (xy 349.988886 -281.722322) (xy 349.981266 -281.700478) (xy 349.97264 -281.674196)
			(xy 349.963326 -281.619675) (xy 349.962724 -281.59202) (xy 349.963232 -281.566113) (xy 349.971338 -281.514936)
			(xy 349.98735 -281.465657) (xy 350.010873 -281.41949) (xy 350.041329 -281.377571) (xy 350.077967 -281.340933)
			(xy 350.119886 -281.310477) (xy 350.166053 -281.286954) (xy 350.215332 -281.270942) (xy 350.266509 -281.262836)
			(xy 350.318323 -281.262836) (xy 350.3695 -281.270942) (xy 350.418779 -281.286954) (xy 350.464946 -281.310477)
			(xy 350.506865 -281.340933) (xy 350.543503 -281.377571) (xy 350.573959 -281.41949) (xy 350.597482 -281.465657)
			(xy 350.613494 -281.514936) (xy 350.6216 -281.566113) (xy 350.622108 -281.59202) (xy 350.621645 -281.617395)
			(xy 350.613874 -281.667545) (xy 350.598503 -281.71591) (xy 350.575897 -281.761346) (xy 350.546589 -281.802777)
			(xy 350.511274 -281.839223) (xy 350.470788 -281.869822) (xy 350.426087 -281.893849) (xy 350.37823 -281.910736)
			(xy 350.353376 -281.91587) (xy 350.330516 -281.920188) (xy 350.125538 -282.275026) (xy 350.133412 -282.297124)
			(xy 350.141978 -282.32348) (xy 350.151173 -282.378127) (xy 350.1517 -282.405836) (xy 350.151192 -282.431703)
			(xy 351.372752 -282.431703) (xy 351.372752 -282.379897) (xy 351.380856 -282.32873) (xy 351.396863 -282.27946)
			(xy 351.420381 -282.2333) (xy 351.450829 -282.191388) (xy 351.487459 -282.154754) (xy 351.529368 -282.124301)
			(xy 351.575525 -282.100778) (xy 351.624793 -282.084765) (xy 351.675959 -282.076655) (xy 351.701862 -282.076144)
			(xy 351.727374 -282.076635) (xy 351.777788 -282.084491) (xy 351.826391 -282.100021) (xy 351.872019 -282.122855)
			(xy 351.913585 -282.152446) (xy 351.950095 -282.188089) (xy 351.965768 -282.208224) (xy 352.377756 -282.208224)
			(xy 352.393461 -282.188115) (xy 352.429964 -282.152468) (xy 352.471522 -282.122871) (xy 352.517145 -282.10003)
			(xy 352.565741 -282.084491) (xy 352.616152 -282.076624) (xy 352.641662 -282.076144) (xy 352.667576 -282.076551)
			(xy 352.718767 -282.084653) (xy 352.76806 -282.100664) (xy 352.814242 -282.12419) (xy 352.856174 -282.154651)
			(xy 352.892824 -282.191297) (xy 352.92329 -282.233226) (xy 352.946821 -282.279404) (xy 352.962838 -282.328696)
			(xy 352.970946 -282.379886) (xy 352.970946 -282.431714) (xy 352.962838 -282.482904) (xy 352.946821 -282.532196)
			(xy 352.92329 -282.578374) (xy 352.892824 -282.620303) (xy 352.856174 -282.656949) (xy 352.814242 -282.68741)
			(xy 352.76806 -282.710936) (xy 352.718767 -282.726947) (xy 352.667576 -282.735049) (xy 352.641662 -282.735528)
			(xy 352.61615 -282.735064) (xy 352.565735 -282.727199) (xy 352.517134 -282.711661) (xy 352.471506 -282.688822)
			(xy 352.42994 -282.659228) (xy 352.39343 -282.623584) (xy 352.377756 -282.603448) (xy 351.965768 -282.603448)
			(xy 351.950126 -282.623609) (xy 351.913609 -282.659249) (xy 351.872036 -282.688839) (xy 351.826402 -282.71167)
			(xy 351.777795 -282.727199) (xy 351.727376 -282.735054) (xy 351.701862 -282.735528) (xy 351.675959 -282.734945)
			(xy 351.624793 -282.726835) (xy 351.575525 -282.710822) (xy 351.529368 -282.687299) (xy 351.487459 -282.656846)
			(xy 351.450829 -282.620212) (xy 351.420381 -282.5783) (xy 351.396863 -282.53214) (xy 351.380856 -282.48287)
			(xy 351.372752 -282.431703) (xy 350.151192 -282.431703) (xy 350.151192 -282.431723) (xy 350.143093 -282.482861)
			(xy 350.127094 -282.532101) (xy 350.103588 -282.578233) (xy 350.073156 -282.62012) (xy 350.036546 -282.65673)
			(xy 349.994659 -282.687162) (xy 349.948527 -282.710668) (xy 349.899287 -282.726667) (xy 349.848149 -282.734766)
			(xy 349.796375 -282.734766) (xy 349.745237 -282.726667) (xy 349.695997 -282.710668) (xy 349.649865 -282.687162)
			(xy 349.607978 -282.65673) (xy 349.571368 -282.62012) (xy 349.540936 -282.578233) (xy 349.51743 -282.532101)
			(xy 349.501431 -282.482861) (xy 349.493332 -282.431723) (xy 349.492824 -282.405836) (xy 348.2721 -282.405836)
			(xy 348.271608 -282.431158) (xy 348.263872 -282.481209) (xy 348.248573 -282.529487) (xy 348.22607 -282.574858)
			(xy 348.196893 -282.616254) (xy 348.161729 -282.6527) (xy 348.121404 -282.68334) (xy 348.076868 -282.707453)
			(xy 348.029168 -282.72447) (xy 348.004384 -282.729686) (xy 347.981524 -282.734004) (xy 347.776292 -283.089096)
			(xy 347.784166 -283.111194) (xy 347.792802 -283.137539) (xy 347.80212 -283.192188) (xy 347.802708 -283.219906)
			(xy 347.8022 -283.24579) (xy 349.023649 -283.24579) (xy 349.023649 -283.19401) (xy 349.03175 -283.142868)
			(xy 349.047751 -283.093623) (xy 349.071259 -283.047487) (xy 349.101695 -283.005597) (xy 349.13831 -282.968985)
			(xy 349.180201 -282.938551) (xy 349.226338 -282.915045) (xy 349.275584 -282.899046) (xy 349.326726 -282.890948)
			(xy 349.352616 -282.890468) (xy 349.378128 -282.890949) (xy 349.428541 -282.898811) (xy 349.477143 -282.914346)
			(xy 349.522771 -282.937181) (xy 349.564336 -282.966773) (xy 349.600848 -283.002414) (xy 349.616522 -283.022548)
			(xy 350.02851 -283.022548) (xy 350.044163 -283.002397) (xy 350.080679 -282.966756) (xy 350.122249 -282.937166)
			(xy 350.167881 -282.914333) (xy 350.216486 -282.898802) (xy 350.266903 -282.890944) (xy 350.292416 -282.890468)
			(xy 350.318303 -282.890965) (xy 350.369439 -282.899066) (xy 350.418679 -282.915067) (xy 350.464809 -282.938574)
			(xy 350.506694 -282.969007) (xy 350.543303 -283.005618) (xy 350.573735 -283.047505) (xy 350.597239 -283.093636)
			(xy 350.613237 -283.142876) (xy 350.621336 -283.194013) (xy 350.621336 -283.219906) (xy 352.782124 -283.219906)
			(xy 352.782631 -283.194562) (xy 352.790403 -283.144472) (xy 352.805748 -283.096161) (xy 352.828306 -283.050768)
			(xy 352.857545 -283.009362) (xy 352.892775 -282.972918) (xy 352.933168 -282.942295) (xy 352.977772 -282.918214)
			(xy 353.025536 -282.901243) (xy 353.050348 -282.896056) (xy 353.073208 -282.891738) (xy 353.278186 -282.5369)
			(xy 353.270566 -282.514802) (xy 353.261929 -282.488391) (xy 353.252603 -282.433617) (xy 353.252024 -282.405836)
			(xy 353.252532 -282.379949) (xy 353.260631 -282.328811) (xy 353.27663 -282.279571) (xy 353.300136 -282.233439)
			(xy 353.330568 -282.191552) (xy 353.367178 -282.154942) (xy 353.409065 -282.12451) (xy 353.455197 -282.101004)
			(xy 353.504437 -282.085005) (xy 353.555575 -282.076906) (xy 353.607349 -282.076906) (xy 353.658487 -282.085005)
			(xy 353.707727 -282.101004) (xy 353.753859 -282.12451) (xy 353.795746 -282.154942) (xy 353.832356 -282.191552)
			(xy 353.862788 -282.233439) (xy 353.886294 -282.279571) (xy 353.902293 -282.328811) (xy 353.910392 -282.379949)
			(xy 353.9109 -282.405836) (xy 353.910408 -282.431158) (xy 353.902672 -282.481209) (xy 353.887373 -282.529487)
			(xy 353.86487 -282.574858) (xy 353.835693 -282.616254) (xy 353.800529 -282.6527) (xy 353.760204 -282.68334)
			(xy 353.715668 -282.707453) (xy 353.667968 -282.72447) (xy 353.643184 -282.729686) (xy 353.620324 -282.734004)
			(xy 353.415092 -283.089096) (xy 353.422966 -283.111194) (xy 353.431602 -283.137539) (xy 353.44092 -283.192188)
			(xy 353.441508 -283.219906) (xy 353.441 -283.245813) (xy 353.432894 -283.29699) (xy 353.416882 -283.346269)
			(xy 353.393359 -283.392436) (xy 353.362903 -283.434355) (xy 353.326265 -283.470993) (xy 353.284346 -283.501449)
			(xy 353.238179 -283.524972) (xy 353.1889 -283.540984) (xy 353.137723 -283.54909) (xy 353.085909 -283.54909)
			(xy 353.034732 -283.540984) (xy 352.985453 -283.524972) (xy 352.939286 -283.501449) (xy 352.897367 -283.470993)
			(xy 352.860729 -283.434355) (xy 352.830273 -283.392436) (xy 352.80675 -283.346269) (xy 352.790738 -283.29699)
			(xy 352.782632 -283.245813) (xy 352.782124 -283.219906) (xy 350.621336 -283.219906) (xy 350.621336 -283.245787)
			(xy 350.613237 -283.296924) (xy 350.597239 -283.346164) (xy 350.573735 -283.392295) (xy 350.543303 -283.434182)
			(xy 350.506694 -283.470793) (xy 350.464809 -283.501226) (xy 350.418679 -283.524733) (xy 350.369439 -283.540734)
			(xy 350.318303 -283.548835) (xy 350.292416 -283.549344) (xy 350.266904 -283.548874) (xy 350.216488 -283.541014)
			(xy 350.167885 -283.52548) (xy 350.122256 -283.502643) (xy 350.080691 -283.473047) (xy 350.044182 -283.437401)
			(xy 350.02851 -283.417264) (xy 349.616522 -283.417264) (xy 349.600826 -283.437381) (xy 349.564322 -283.473028)
			(xy 349.522762 -283.502625) (xy 349.477138 -283.525464) (xy 349.428539 -283.541001) (xy 349.378127 -283.548865)
			(xy 349.352616 -283.549344) (xy 349.326726 -283.548852) (xy 349.275584 -283.540754) (xy 349.226338 -283.524755)
			(xy 349.180201 -283.501249) (xy 349.13831 -283.470815) (xy 349.101695 -283.434203) (xy 349.071259 -283.392313)
			(xy 349.047751 -283.346177) (xy 349.03175 -283.296932) (xy 349.023649 -283.24579) (xy 347.8022 -283.24579)
			(xy 347.8022 -283.245813) (xy 347.794094 -283.29699) (xy 347.778082 -283.346269) (xy 347.754559 -283.392436)
			(xy 347.724103 -283.434355) (xy 347.687465 -283.470993) (xy 347.645546 -283.501449) (xy 347.599379 -283.524972)
			(xy 347.5501 -283.540984) (xy 347.498923 -283.54909) (xy 347.447109 -283.54909) (xy 347.395932 -283.540984)
			(xy 347.346653 -283.524972) (xy 347.300486 -283.501449) (xy 347.258567 -283.470993) (xy 347.221929 -283.434355)
			(xy 347.191473 -283.392436) (xy 347.16795 -283.346269) (xy 347.151938 -283.29699) (xy 347.143832 -283.245813)
			(xy 347.143324 -283.219906) (xy 344.983308 -283.219906) (xy 344.9828 -283.245813) (xy 344.974694 -283.29699)
			(xy 344.958682 -283.346269) (xy 344.935159 -283.392436) (xy 344.904703 -283.434355) (xy 344.868065 -283.470993)
			(xy 344.826146 -283.501449) (xy 344.779979 -283.524972) (xy 344.7307 -283.540984) (xy 344.679523 -283.54909)
			(xy 344.627709 -283.54909) (xy 344.576532 -283.540984) (xy 344.527253 -283.524972) (xy 344.481086 -283.501449)
			(xy 344.439167 -283.470993) (xy 344.402529 -283.434355) (xy 344.372073 -283.392436) (xy 344.34855 -283.346269)
			(xy 344.332538 -283.29699) (xy 344.324432 -283.245813) (xy 344.323924 -283.219906) (xy 344.324518 -283.192189)
			(xy 344.333841 -283.137542) (xy 344.342466 -283.111194) (xy 344.35034 -283.089096) (xy 344.145362 -282.734004)
			(xy 344.122248 -282.729686) (xy 344.097423 -282.724538) (xy 344.049642 -282.707582) (xy 344.005022 -282.683508)
			(xy 343.964615 -282.652886) (xy 343.929374 -282.616436) (xy 343.900131 -282.57502) (xy 343.877575 -282.529614)
			(xy 343.862239 -282.481289) (xy 343.854484 -282.431186) (xy 343.854024 -282.405836) (xy 343.5731 -282.405836)
			(xy 343.572592 -282.431723) (xy 343.564493 -282.482861) (xy 343.548494 -282.532101) (xy 343.524988 -282.578233)
			(xy 343.494556 -282.62012) (xy 343.457946 -282.65673) (xy 343.416059 -282.687162) (xy 343.369927 -282.710668)
			(xy 343.320687 -282.726667) (xy 343.269549 -282.734766) (xy 343.217775 -282.734766) (xy 343.166637 -282.726667)
			(xy 343.117397 -282.710668) (xy 343.071265 -282.687162) (xy 343.029378 -282.65673) (xy 342.992768 -282.62012)
			(xy 342.962336 -282.578233) (xy 342.93883 -282.532101) (xy 342.922831 -282.482861) (xy 342.914732 -282.431723)
			(xy 342.914224 -282.405836) (xy 341.694008 -282.405836) (xy 341.6935 -282.431743) (xy 341.685394 -282.48292)
			(xy 341.669382 -282.532199) (xy 341.645859 -282.578366) (xy 341.615403 -282.620285) (xy 341.578765 -282.656923)
			(xy 341.536846 -282.687379) (xy 341.490679 -282.710902) (xy 341.4414 -282.726914) (xy 341.390223 -282.73502)
			(xy 341.338409 -282.73502) (xy 341.287232 -282.726914) (xy 341.237953 -282.710902) (xy 341.191786 -282.687379)
			(xy 341.149867 -282.656923) (xy 341.113229 -282.620285) (xy 341.082773 -282.578366) (xy 341.05925 -282.532199)
			(xy 341.043238 -282.48292) (xy 341.035132 -282.431743) (xy 341.034624 -282.405836) (xy 336.0547 -282.405836)
			(xy 336.054179 -282.433545) (xy 336.044978 -282.488191) (xy 336.036412 -282.514548) (xy 336.028538 -282.536646)
			(xy 336.23377 -282.891738) (xy 336.25663 -282.896056) (xy 336.281436 -282.901231) (xy 336.329174 -282.918223)
			(xy 336.373751 -282.94232) (xy 336.414116 -282.972953) (xy 336.449318 -283.009401) (xy 336.478529 -283.050806)
			(xy 336.501062 -283.096194) (xy 336.516384 -283.144494) (xy 336.524137 -283.19457) (xy 336.5246 -283.219906)
			(xy 336.524092 -283.245785) (xy 340.565275 -283.245785) (xy 340.565275 -283.194015) (xy 340.573373 -283.142882)
			(xy 340.58937 -283.093646) (xy 340.612872 -283.047517) (xy 340.643299 -283.005633) (xy 340.679904 -282.969024)
			(xy 340.721785 -282.938592) (xy 340.76791 -282.915085) (xy 340.817145 -282.899082) (xy 340.868277 -282.890978)
			(xy 340.894162 -282.890468) (xy 340.919672 -282.890989) (xy 340.970084 -282.898843) (xy 341.018684 -282.914369)
			(xy 341.064312 -282.937197) (xy 341.105879 -282.966782) (xy 341.142392 -283.002417) (xy 341.158068 -283.022548)
			(xy 341.570056 -283.022548) (xy 341.585741 -283.002422) (xy 341.62225 -282.96678) (xy 341.663813 -282.937187)
			(xy 341.709439 -282.91435) (xy 341.758039 -282.898813) (xy 341.808451 -282.890948) (xy 341.833962 -282.890468)
			(xy 341.859854 -282.890934) (xy 341.911001 -282.89903) (xy 341.960252 -282.915027) (xy 342.006393 -282.938533)
			(xy 342.048289 -282.968968) (xy 342.084908 -283.005582) (xy 342.115347 -283.047475) (xy 342.138858 -283.093613)
			(xy 342.154861 -283.142862) (xy 342.162963 -283.194008) (xy 342.162963 -283.245792) (xy 342.154861 -283.296938)
			(xy 342.138858 -283.346187) (xy 342.115347 -283.392325) (xy 342.084908 -283.434218) (xy 342.048289 -283.470832)
			(xy 342.006393 -283.501267) (xy 341.960252 -283.524773) (xy 341.911001 -283.54077) (xy 341.859854 -283.548866)
			(xy 341.833962 -283.549344) (xy 341.808448 -283.548913) (xy 341.75803 -283.541045) (xy 341.709427 -283.525503)
			(xy 341.663798 -283.502658) (xy 341.622234 -283.473056) (xy 341.585727 -283.437404) (xy 341.570056 -283.417264)
			(xy 341.158068 -283.417264) (xy 341.142404 -283.437407) (xy 341.105893 -283.473052) (xy 341.064326 -283.502646)
			(xy 341.018696 -283.525481) (xy 340.970092 -283.541013) (xy 340.919675 -283.548869) (xy 340.894162 -283.549344)
			(xy 340.868277 -283.548822) (xy 340.817145 -283.540718) (xy 340.76791 -283.524715) (xy 340.721785 -283.501208)
			(xy 340.679904 -283.470776) (xy 340.643299 -283.434167) (xy 340.612872 -283.392283) (xy 340.58937 -283.346154)
			(xy 340.573373 -283.296918) (xy 340.565275 -283.245785) (xy 336.524092 -283.245785) (xy 336.524092 -283.245793)
			(xy 336.515993 -283.296931) (xy 336.499994 -283.346171) (xy 336.476488 -283.392303) (xy 336.446056 -283.43419)
			(xy 336.409446 -283.4708) (xy 336.367559 -283.501232) (xy 336.321427 -283.524738) (xy 336.272187 -283.540737)
			(xy 336.221049 -283.548836) (xy 336.169275 -283.548836) (xy 336.118137 -283.540737) (xy 336.068897 -283.524738)
			(xy 336.022765 -283.501232) (xy 335.980878 -283.4708) (xy 335.944268 -283.43419) (xy 335.913836 -283.392303)
			(xy 335.89033 -283.346171) (xy 335.874331 -283.296931) (xy 335.866232 -283.245793) (xy 335.865724 -283.219906)
			(xy 335.866254 -283.192198) (xy 335.875449 -283.137551) (xy 335.884012 -283.111194) (xy 335.891886 -283.089096)
			(xy 335.686654 -282.734004) (xy 335.663794 -282.729686) (xy 335.639001 -282.724454) (xy 335.591266 -282.707468)
			(xy 335.546691 -282.683379) (xy 335.506327 -282.652753) (xy 335.471124 -282.616312) (xy 335.441911 -282.574914)
			(xy 335.419375 -282.529534) (xy 335.404048 -282.48124) (xy 335.396291 -282.43117) (xy 335.395824 -282.405836)
			(xy 106.910632 -282.405836) (xy 106.910124 -282.431723) (xy 106.902025 -282.482861) (xy 106.886026 -282.532101)
			(xy 106.86252 -282.578233) (xy 106.832088 -282.62012) (xy 106.795478 -282.65673) (xy 106.753591 -282.687162)
			(xy 106.707459 -282.710668) (xy 106.658219 -282.726667) (xy 106.607081 -282.734766) (xy 106.555307 -282.734766)
			(xy 106.504169 -282.726667) (xy 106.454929 -282.710668) (xy 106.408797 -282.687162) (xy 106.36691 -282.65673)
			(xy 106.3303 -282.62012) (xy 106.299868 -282.578233) (xy 106.276362 -282.532101) (xy 106.260363 -282.482861)
			(xy 106.252264 -282.431723) (xy 106.251756 -282.405836) (xy 106.252296 -282.378128) (xy 106.261484 -282.323482)
			(xy 106.270044 -282.297124) (xy 106.277918 -282.275026) (xy 106.07294 -281.920188) (xy 106.05008 -281.91587)
			(xy 106.025256 -281.910713) (xy 105.977474 -281.893761) (xy 105.932853 -281.86969) (xy 105.892445 -281.839069)
			(xy 105.857203 -281.802621) (xy 105.827959 -281.761205) (xy 105.805403 -281.715799) (xy 105.790068 -281.667474)
			(xy 105.782315 -281.61737) (xy 105.781856 -281.59202) (xy 104.56164 -281.59202) (xy 104.561132 -281.617927)
			(xy 104.553026 -281.669104) (xy 104.537014 -281.718383) (xy 104.513491 -281.76455) (xy 104.483035 -281.806469)
			(xy 104.446397 -281.843107) (xy 104.404478 -281.873563) (xy 104.358311 -281.897086) (xy 104.309032 -281.913098)
			(xy 104.257855 -281.921204) (xy 104.206041 -281.921204) (xy 104.154864 -281.913098) (xy 104.105585 -281.897086)
			(xy 104.059418 -281.873563) (xy 104.017499 -281.843107) (xy 103.980861 -281.806469) (xy 103.950405 -281.76455)
			(xy 103.926882 -281.718383) (xy 103.91087 -281.669104) (xy 103.902764 -281.617927) (xy 103.902256 -281.59202)
			(xy 103.902852 -281.564303) (xy 103.912174 -281.509656) (xy 103.920798 -281.483308) (xy 103.928672 -281.46121)
			(xy 103.723694 -281.106372) (xy 103.700834 -281.102054) (xy 103.676009 -281.096858) (xy 103.628203 -281.079927)
			(xy 103.583555 -281.055874) (xy 103.543117 -281.025267) (xy 103.507844 -280.988827) (xy 103.478568 -280.947415)
			(xy 103.45598 -280.902007) (xy 103.440613 -280.853676) (xy 103.43283 -280.803562) (xy 103.432356 -280.778204)
			(xy 101.271832 -280.778204) (xy 101.271832 -280.778712) (xy 101.271241 -280.806228) (xy 101.262055 -280.860489)
			(xy 101.253544 -280.886662) (xy 101.245924 -280.908506) (xy 101.451156 -281.263852) (xy 101.474016 -281.26817)
			(xy 101.498826 -281.273386) (xy 101.546603 -281.290334) (xy 101.591222 -281.314398) (xy 101.631628 -281.345012)
			(xy 101.66687 -281.381453) (xy 101.696116 -281.422861) (xy 101.718675 -281.468259) (xy 101.734016 -281.516576)
			(xy 101.741776 -281.566673) (xy 101.74224 -281.59202) (xy 101.741732 -281.617927) (xy 101.733626 -281.669104)
			(xy 101.717614 -281.718383) (xy 101.694091 -281.76455) (xy 101.663635 -281.806469) (xy 101.626997 -281.843107)
			(xy 101.585078 -281.873563) (xy 101.538911 -281.897086) (xy 101.489632 -281.913098) (xy 101.438455 -281.921204)
			(xy 101.386641 -281.921204) (xy 101.335464 -281.913098) (xy 101.286185 -281.897086) (xy 101.240018 -281.873563)
			(xy 101.198099 -281.843107) (xy 101.161461 -281.806469) (xy 101.131005 -281.76455) (xy 101.107482 -281.718383)
			(xy 101.09147 -281.669104) (xy 101.083364 -281.617927) (xy 101.082856 -281.59202) (xy 101.083452 -281.564303)
			(xy 101.092774 -281.509656) (xy 101.101398 -281.483308) (xy 101.109272 -281.46121) (xy 100.904294 -281.106372)
			(xy 100.881434 -281.102054) (xy 100.856609 -281.096858) (xy 100.808803 -281.079927) (xy 100.764155 -281.055874)
			(xy 100.723717 -281.025267) (xy 100.688444 -280.988827) (xy 100.659168 -280.947415) (xy 100.63658 -280.902007)
			(xy 100.621213 -280.853676) (xy 100.61343 -280.803562) (xy 100.612956 -280.778204) (xy 98.452432 -280.778204)
			(xy 98.451927 -280.803537) (xy 98.444175 -280.853607) (xy 98.428854 -280.901902) (xy 98.406324 -280.947284)
			(xy 98.377117 -280.988685) (xy 98.34192 -281.025131) (xy 98.301561 -281.055762) (xy 98.256992 -281.079859)
			(xy 98.20926 -281.096853) (xy 98.184462 -281.102054) (xy 98.161602 -281.106372) (xy 97.956624 -281.46121)
			(xy 97.964498 -281.483308) (xy 97.973138 -281.509652) (xy 97.982453 -281.564301) (xy 97.98304 -281.59202)
			(xy 97.982532 -281.61791) (xy 99.20371 -281.61791) (xy 99.20371 -281.56609) (xy 99.211817 -281.514907)
			(xy 99.227832 -281.465624) (xy 99.25136 -281.419452) (xy 99.281822 -281.37753) (xy 99.318467 -281.34089)
			(xy 99.360393 -281.310435) (xy 99.406568 -281.286913) (xy 99.455854 -281.270906) (xy 99.507038 -281.262806)
			(xy 99.532948 -281.262328) (xy 99.558462 -281.262762) (xy 99.608879 -281.270631) (xy 99.657482 -281.286173)
			(xy 99.70311 -281.309017) (xy 99.744675 -281.338618) (xy 99.781182 -281.374269) (xy 99.796854 -281.394408)
			(xy 100.208842 -281.394408) (xy 100.224493 -281.374254) (xy 100.261007 -281.338611) (xy 100.302577 -281.309019)
			(xy 100.34821 -281.286186) (xy 100.396816 -281.270657) (xy 100.447235 -281.262802) (xy 100.472748 -281.262328)
			(xy 100.498654 -281.2628) (xy 100.549829 -281.270912) (xy 100.599104 -281.286928) (xy 100.645267 -281.310456)
			(xy 100.687182 -281.340914) (xy 100.723817 -281.377554) (xy 100.754269 -281.419474) (xy 100.77779 -281.465641)
			(xy 100.7938 -281.514918) (xy 100.801904 -281.566093) (xy 100.801904 -281.617907) (xy 100.7938 -281.669082)
			(xy 100.77779 -281.718359) (xy 100.754269 -281.764526) (xy 100.723817 -281.806446) (xy 100.687182 -281.843086)
			(xy 100.645267 -281.873544) (xy 100.599104 -281.897072) (xy 100.549829 -281.913088) (xy 100.498654 -281.9212)
			(xy 100.472748 -281.921712) (xy 100.447238 -281.921192) (xy 100.396825 -281.913339) (xy 100.348225 -281.897813)
			(xy 100.302596 -281.874985) (xy 100.26103 -281.8454) (xy 100.224517 -281.809764) (xy 100.208842 -281.789632)
			(xy 99.796854 -281.789632) (xy 99.781158 -281.809749) (xy 99.744652 -281.845392) (xy 99.703091 -281.874987)
			(xy 99.657467 -281.897826) (xy 99.60887 -281.913365) (xy 99.558459 -281.921231) (xy 99.532948 -281.921712)
			(xy 99.507038 -281.921194) (xy 99.455854 -281.913094) (xy 99.406568 -281.897087) (xy 99.360393 -281.873565)
			(xy 99.318467 -281.84311) (xy 99.281822 -281.80647) (xy 99.25136 -281.764548) (xy 99.227832 -281.718376)
			(xy 99.211817 -281.669093) (xy 99.20371 -281.61791) (xy 97.982532 -281.61791) (xy 97.982532 -281.617927)
			(xy 97.974426 -281.669104) (xy 97.958414 -281.718383) (xy 97.934891 -281.76455) (xy 97.904435 -281.806469)
			(xy 97.867797 -281.843107) (xy 97.825878 -281.873563) (xy 97.779711 -281.897086) (xy 97.730432 -281.913098)
			(xy 97.679255 -281.921204) (xy 97.627441 -281.921204) (xy 97.576264 -281.913098) (xy 97.526985 -281.897086)
			(xy 97.480818 -281.873563) (xy 97.438899 -281.843107) (xy 97.402261 -281.806469) (xy 97.371805 -281.76455)
			(xy 97.348282 -281.718383) (xy 97.33227 -281.669104) (xy 97.324164 -281.617927) (xy 97.323656 -281.59202)
			(xy 96.10344 -281.59202) (xy 96.103032 -281.617397) (xy 96.095259 -281.667553) (xy 96.079885 -281.715923)
			(xy 96.057273 -281.761362) (xy 96.027958 -281.802795) (xy 95.992635 -281.839241) (xy 95.95214 -281.869837)
			(xy 95.907431 -281.89386) (xy 95.859566 -281.910741) (xy 95.834708 -281.91587) (xy 95.811848 -281.920188)
			(xy 95.60687 -282.275026) (xy 95.614744 -282.297124) (xy 95.623311 -282.32348) (xy 95.632506 -282.378127)
			(xy 95.633032 -282.405836) (xy 95.913956 -282.405836) (xy 95.914464 -282.379949) (xy 95.922563 -282.328811)
			(xy 95.938562 -282.279571) (xy 95.962068 -282.233439) (xy 95.9925 -282.191552) (xy 96.02911 -282.154942)
			(xy 96.070997 -282.12451) (xy 96.117129 -282.101004) (xy 96.166369 -282.085005) (xy 96.217507 -282.076906)
			(xy 96.269281 -282.076906) (xy 96.320419 -282.085005) (xy 96.369659 -282.101004) (xy 96.415791 -282.12451)
			(xy 96.457678 -282.154942) (xy 96.494288 -282.191552) (xy 96.52472 -282.233439) (xy 96.548226 -282.279571)
			(xy 96.564225 -282.328811) (xy 96.572324 -282.379949) (xy 96.572832 -282.405836) (xy 96.572832 -282.406344)
			(xy 96.572295 -282.431704) (xy 96.854052 -282.431704) (xy 96.854052 -282.379896) (xy 96.862157 -282.328725)
			(xy 96.878166 -282.279453) (xy 96.901687 -282.233291) (xy 96.932138 -282.191377) (xy 96.968772 -282.154742)
			(xy 97.010686 -282.12429) (xy 97.056847 -282.100769) (xy 97.106119 -282.084758) (xy 97.15729 -282.076653)
			(xy 97.183194 -282.076144) (xy 97.208707 -282.076611) (xy 97.259122 -282.084472) (xy 97.307725 -282.100007)
			(xy 97.353354 -282.122845) (xy 97.394919 -282.152441) (xy 97.431427 -282.188087) (xy 97.4471 -282.208224)
			(xy 97.859088 -282.208224) (xy 97.874775 -282.188099) (xy 97.911281 -282.152454) (xy 97.952843 -282.122858)
			(xy 97.998469 -282.10002) (xy 98.047069 -282.084484) (xy 98.097483 -282.076622) (xy 98.122994 -282.076144)
			(xy 98.148907 -282.076553) (xy 98.200094 -282.08466) (xy 98.249383 -282.100674) (xy 98.295559 -282.124201)
			(xy 98.337487 -282.154663) (xy 98.374133 -282.191308) (xy 98.404596 -282.233235) (xy 98.428124 -282.279412)
			(xy 98.444139 -282.3287) (xy 98.452246 -282.379887) (xy 98.452246 -282.431713) (xy 98.444139 -282.4829)
			(xy 98.428124 -282.532188) (xy 98.404596 -282.578365) (xy 98.374133 -282.620292) (xy 98.337487 -282.656937)
			(xy 98.295559 -282.687399) (xy 98.249383 -282.710926) (xy 98.200094 -282.72694) (xy 98.148907 -282.735047)
			(xy 98.122994 -282.735528) (xy 98.097483 -282.735041) (xy 98.047069 -282.72718) (xy 97.998468 -282.711647)
			(xy 97.95284 -282.688813) (xy 97.911274 -282.659222) (xy 97.874762 -282.623582) (xy 97.859088 -282.603448)
			(xy 97.4471 -282.603448) (xy 97.43144 -282.623594) (xy 97.394926 -282.659235) (xy 97.353357 -282.688826)
			(xy 97.307726 -282.71166) (xy 97.259123 -282.727192) (xy 97.208707 -282.735052) (xy 97.183194 -282.735528)
			(xy 97.15729 -282.734947) (xy 97.106119 -282.726842) (xy 97.056847 -282.710831) (xy 97.010686 -282.68731)
			(xy 96.968772 -282.656858) (xy 96.932138 -282.620223) (xy 96.901687 -282.578309) (xy 96.878166 -282.532147)
			(xy 96.862157 -282.482875) (xy 96.854052 -282.431704) (xy 96.572295 -282.431704) (xy 96.572249 -282.43386)
			(xy 96.563058 -282.488121) (xy 96.554544 -282.514294) (xy 96.546924 -282.536392) (xy 96.752156 -282.891738)
			(xy 96.775016 -282.896056) (xy 96.799823 -282.901285) (xy 96.847599 -282.918232) (xy 96.892217 -282.942295)
			(xy 96.932623 -282.972907) (xy 96.967865 -283.009346) (xy 96.997111 -283.050752) (xy 97.019671 -283.096149)
			(xy 97.035013 -283.144464) (xy 97.042775 -283.194559) (xy 97.04324 -283.219906) (xy 99.203256 -283.219906)
			(xy 99.203737 -283.19456) (xy 99.21151 -283.144468) (xy 99.226857 -283.096156) (xy 99.249417 -283.050761)
			(xy 99.278659 -283.009354) (xy 99.313894 -282.97291) (xy 99.354291 -282.942288) (xy 99.398899 -282.918209)
			(xy 99.446666 -282.901241) (xy 99.47148 -282.896056) (xy 99.49434 -282.891738) (xy 99.699318 -282.5369)
			(xy 99.691698 -282.514802) (xy 99.683062 -282.488391) (xy 99.673735 -282.433617) (xy 99.673156 -282.405836)
			(xy 99.673664 -282.379949) (xy 99.681763 -282.328811) (xy 99.697762 -282.279571) (xy 99.721268 -282.233439)
			(xy 99.7517 -282.191552) (xy 99.78831 -282.154942) (xy 99.830197 -282.12451) (xy 99.876329 -282.101004)
			(xy 99.925569 -282.085005) (xy 99.976707 -282.076906) (xy 100.028481 -282.076906) (xy 100.079619 -282.085005)
			(xy 100.128859 -282.101004) (xy 100.174991 -282.12451) (xy 100.216878 -282.154942) (xy 100.253488 -282.191552)
			(xy 100.28392 -282.233439) (xy 100.307426 -282.279571) (xy 100.323425 -282.328811) (xy 100.331524 -282.379949)
			(xy 100.332032 -282.405836) (xy 101.552756 -282.405836) (xy 101.553216 -282.380501) (xy 101.560977 -282.33043)
			(xy 101.576305 -282.282135) (xy 101.598841 -282.236753) (xy 101.628054 -282.195352) (xy 101.663256 -282.158908)
			(xy 101.703619 -282.128277) (xy 101.748192 -282.104181) (xy 101.795927 -282.087187) (xy 101.820726 -282.081986)
			(xy 101.843586 -282.077668) (xy 102.048818 -281.722322) (xy 102.041198 -281.700478) (xy 102.03257 -281.674197)
			(xy 102.023258 -281.619675) (xy 102.022656 -281.59202) (xy 102.023164 -281.566113) (xy 102.03127 -281.514936)
			(xy 102.047282 -281.465657) (xy 102.070805 -281.41949) (xy 102.101261 -281.377571) (xy 102.137899 -281.340933)
			(xy 102.179818 -281.310477) (xy 102.225985 -281.286954) (xy 102.275264 -281.270942) (xy 102.326441 -281.262836)
			(xy 102.378255 -281.262836) (xy 102.429432 -281.270942) (xy 102.478711 -281.286954) (xy 102.524878 -281.310477)
			(xy 102.566797 -281.340933) (xy 102.603435 -281.377571) (xy 102.633891 -281.41949) (xy 102.657414 -281.465657)
			(xy 102.673426 -281.514936) (xy 102.681532 -281.566113) (xy 102.68204 -281.59202) (xy 102.681632 -281.617397)
			(xy 102.673859 -281.667553) (xy 102.658485 -281.715923) (xy 102.635873 -281.761362) (xy 102.606558 -281.802795)
			(xy 102.571235 -281.839241) (xy 102.53074 -281.869837) (xy 102.486031 -281.89386) (xy 102.438166 -281.910741)
			(xy 102.413308 -281.91587) (xy 102.390448 -281.920188) (xy 102.18547 -282.275026) (xy 102.193344 -282.297124)
			(xy 102.201911 -282.32348) (xy 102.211106 -282.378127) (xy 102.211632 -282.405836) (xy 102.211124 -282.431704)
			(xy 103.432652 -282.431704) (xy 103.432652 -282.379896) (xy 103.440757 -282.328725) (xy 103.456766 -282.279453)
			(xy 103.480287 -282.233291) (xy 103.510738 -282.191377) (xy 103.547372 -282.154742) (xy 103.589286 -282.12429)
			(xy 103.635447 -282.100769) (xy 103.684719 -282.084758) (xy 103.73589 -282.076653) (xy 103.761794 -282.076144)
			(xy 103.787307 -282.076611) (xy 103.837722 -282.084472) (xy 103.886325 -282.100007) (xy 103.931954 -282.122845)
			(xy 103.973519 -282.152441) (xy 104.010027 -282.188087) (xy 104.0257 -282.208224) (xy 104.437688 -282.208224)
			(xy 104.453375 -282.188099) (xy 104.489881 -282.152454) (xy 104.531443 -282.122858) (xy 104.577069 -282.10002)
			(xy 104.625669 -282.084484) (xy 104.676083 -282.076622) (xy 104.701594 -282.076144) (xy 104.727507 -282.076553)
			(xy 104.778694 -282.08466) (xy 104.827983 -282.100674) (xy 104.874159 -282.124201) (xy 104.916087 -282.154663)
			(xy 104.952733 -282.191308) (xy 104.983196 -282.233235) (xy 105.006724 -282.279412) (xy 105.022739 -282.3287)
			(xy 105.030846 -282.379887) (xy 105.030846 -282.431713) (xy 105.022739 -282.4829) (xy 105.006724 -282.532188)
			(xy 104.983196 -282.578365) (xy 104.952733 -282.620292) (xy 104.916087 -282.656937) (xy 104.874159 -282.687399)
			(xy 104.827983 -282.710926) (xy 104.778694 -282.72694) (xy 104.727507 -282.735047) (xy 104.701594 -282.735528)
			(xy 104.676083 -282.735041) (xy 104.625669 -282.72718) (xy 104.577068 -282.711647) (xy 104.53144 -282.688813)
			(xy 104.489874 -282.659222) (xy 104.453362 -282.623582) (xy 104.437688 -282.603448) (xy 104.0257 -282.603448)
			(xy 104.01004 -282.623594) (xy 103.973526 -282.659235) (xy 103.931957 -282.688826) (xy 103.886326 -282.71166)
			(xy 103.837723 -282.727192) (xy 103.787307 -282.735052) (xy 103.761794 -282.735528) (xy 103.73589 -282.734947)
			(xy 103.684719 -282.726842) (xy 103.635447 -282.710831) (xy 103.589286 -282.68731) (xy 103.547372 -282.656858)
			(xy 103.510738 -282.620223) (xy 103.480287 -282.578309) (xy 103.456766 -282.532147) (xy 103.440757 -282.482875)
			(xy 103.432652 -282.431704) (xy 102.211124 -282.431704) (xy 102.211124 -282.431723) (xy 102.203025 -282.482861)
			(xy 102.187026 -282.532101) (xy 102.16352 -282.578233) (xy 102.133088 -282.62012) (xy 102.096478 -282.65673)
			(xy 102.054591 -282.687162) (xy 102.008459 -282.710668) (xy 101.959219 -282.726667) (xy 101.908081 -282.734766)
			(xy 101.856307 -282.734766) (xy 101.805169 -282.726667) (xy 101.755929 -282.710668) (xy 101.709797 -282.687162)
			(xy 101.66791 -282.65673) (xy 101.6313 -282.62012) (xy 101.600868 -282.578233) (xy 101.577362 -282.532101)
			(xy 101.561363 -282.482861) (xy 101.553264 -282.431723) (xy 101.552756 -282.405836) (xy 100.332032 -282.405836)
			(xy 100.331594 -282.431161) (xy 100.323857 -282.481217) (xy 100.308554 -282.5295) (xy 100.286046 -282.574874)
			(xy 100.256862 -282.616272) (xy 100.22169 -282.652718) (xy 100.181356 -282.683356) (xy 100.136812 -282.707464)
			(xy 100.089103 -282.724474) (xy 100.064316 -282.729686) (xy 100.041456 -282.734004) (xy 99.836224 -283.089096)
			(xy 99.844098 -283.111194) (xy 99.852735 -283.137539) (xy 99.862052 -283.192188) (xy 99.86264 -283.219906)
			(xy 99.862132 -283.245791) (xy 101.083549 -283.245791) (xy 101.083549 -283.194009) (xy 101.091651 -283.142863)
			(xy 101.107654 -283.093616) (xy 101.131165 -283.047478) (xy 101.161604 -283.005586) (xy 101.198223 -282.968973)
			(xy 101.240119 -282.93854) (xy 101.28626 -282.915036) (xy 101.33551 -282.89904) (xy 101.386657 -282.890946)
			(xy 101.412548 -282.890468) (xy 101.43806 -282.890926) (xy 101.488475 -282.898793) (xy 101.537077 -282.914332)
			(xy 101.582705 -282.937172) (xy 101.62427 -282.966767) (xy 101.66078 -283.002412) (xy 101.676454 -283.022548)
			(xy 102.088442 -283.022548) (xy 102.104077 -283.002381) (xy 102.140596 -282.966741) (xy 102.18217 -282.937153)
			(xy 102.227806 -282.914323) (xy 102.276414 -282.898795) (xy 102.326834 -282.890941) (xy 102.352348 -282.890468)
			(xy 102.378233 -282.890967) (xy 102.429366 -282.899073) (xy 102.478601 -282.915077) (xy 102.524727 -282.938585)
			(xy 102.566608 -282.969019) (xy 102.603213 -283.005629) (xy 102.63364 -283.047514) (xy 102.657142 -283.093643)
			(xy 102.673139 -283.142881) (xy 102.681237 -283.194015) (xy 102.681237 -283.219906) (xy 104.842056 -283.219906)
			(xy 104.842537 -283.19456) (xy 104.85031 -283.144468) (xy 104.865657 -283.096156) (xy 104.888217 -283.050761)
			(xy 104.917459 -283.009354) (xy 104.952694 -282.97291) (xy 104.993091 -282.942288) (xy 105.037699 -282.918209)
			(xy 105.085466 -282.901241) (xy 105.11028 -282.896056) (xy 105.13314 -282.891738) (xy 105.338118 -282.5369)
			(xy 105.330498 -282.514802) (xy 105.321862 -282.488391) (xy 105.312535 -282.433617) (xy 105.311956 -282.405836)
			(xy 105.312464 -282.379949) (xy 105.320563 -282.328811) (xy 105.336562 -282.279571) (xy 105.360068 -282.233439)
			(xy 105.3905 -282.191552) (xy 105.42711 -282.154942) (xy 105.468997 -282.12451) (xy 105.515129 -282.101004)
			(xy 105.564369 -282.085005) (xy 105.615507 -282.076906) (xy 105.667281 -282.076906) (xy 105.718419 -282.085005)
			(xy 105.767659 -282.101004) (xy 105.813791 -282.12451) (xy 105.855678 -282.154942) (xy 105.892288 -282.191552)
			(xy 105.92272 -282.233439) (xy 105.946226 -282.279571) (xy 105.962225 -282.328811) (xy 105.970324 -282.379949)
			(xy 105.970832 -282.405836) (xy 105.970394 -282.431161) (xy 105.962657 -282.481217) (xy 105.947354 -282.5295)
			(xy 105.924846 -282.574874) (xy 105.895662 -282.616272) (xy 105.86049 -282.652718) (xy 105.820156 -282.683356)
			(xy 105.775612 -282.707464) (xy 105.727903 -282.724474) (xy 105.703116 -282.729686) (xy 105.680256 -282.734004)
			(xy 105.475024 -283.089096) (xy 105.482898 -283.111194) (xy 105.491535 -283.137539) (xy 105.500852 -283.192188)
			(xy 105.50144 -283.219906) (xy 105.500932 -283.245813) (xy 105.492826 -283.29699) (xy 105.476814 -283.346269)
			(xy 105.453291 -283.392436) (xy 105.422835 -283.434355) (xy 105.386197 -283.470993) (xy 105.344278 -283.501449)
			(xy 105.298111 -283.524972) (xy 105.248832 -283.540984) (xy 105.197655 -283.54909) (xy 105.145841 -283.54909)
			(xy 105.094664 -283.540984) (xy 105.045385 -283.524972) (xy 104.999218 -283.501449) (xy 104.957299 -283.470993)
			(xy 104.920661 -283.434355) (xy 104.890205 -283.392436) (xy 104.866682 -283.346269) (xy 104.85067 -283.29699)
			(xy 104.842564 -283.245813) (xy 104.842056 -283.219906) (xy 102.681237 -283.219906) (xy 102.681237 -283.245785)
			(xy 102.673139 -283.296919) (xy 102.657142 -283.346157) (xy 102.63364 -283.392286) (xy 102.603213 -283.434171)
			(xy 102.566608 -283.470781) (xy 102.524727 -283.501215) (xy 102.478601 -283.524723) (xy 102.429366 -283.540727)
			(xy 102.378233 -283.548833) (xy 102.352348 -283.549344) (xy 102.326836 -283.548851) (xy 102.276422 -283.540996)
			(xy 102.227819 -283.525467) (xy 102.18219 -283.502633) (xy 102.140624 -283.473042) (xy 102.104115 -283.437399)
			(xy 102.088442 -283.417264) (xy 101.676454 -283.417264) (xy 101.660739 -283.437366) (xy 101.624239 -283.473014)
			(xy 101.582683 -283.502612) (xy 101.537062 -283.525454) (xy 101.488467 -283.540995) (xy 101.438058 -283.548863)
			(xy 101.412548 -283.549344) (xy 101.386657 -283.548854) (xy 101.33551 -283.54076) (xy 101.28626 -283.524764)
			(xy 101.240119 -283.50126) (xy 101.198223 -283.470827) (xy 101.161604 -283.434214) (xy 101.131165 -283.392322)
			(xy 101.107654 -283.346184) (xy 101.091651 -283.296937) (xy 101.083549 -283.245791) (xy 99.862132 -283.245791)
			(xy 99.862132 -283.245813) (xy 99.854026 -283.29699) (xy 99.838014 -283.346269) (xy 99.814491 -283.392436)
			(xy 99.784035 -283.434355) (xy 99.747397 -283.470993) (xy 99.705478 -283.501449) (xy 99.659311 -283.524972)
			(xy 99.610032 -283.540984) (xy 99.558855 -283.54909) (xy 99.507041 -283.54909) (xy 99.455864 -283.540984)
			(xy 99.406585 -283.524972) (xy 99.360418 -283.501449) (xy 99.318499 -283.470993) (xy 99.281861 -283.434355)
			(xy 99.251405 -283.392436) (xy 99.227882 -283.346269) (xy 99.21187 -283.29699) (xy 99.203764 -283.245813)
			(xy 99.203256 -283.219906) (xy 97.04324 -283.219906) (xy 97.042732 -283.245813) (xy 97.034626 -283.29699)
			(xy 97.018614 -283.346269) (xy 96.995091 -283.392436) (xy 96.964635 -283.434355) (xy 96.927997 -283.470993)
			(xy 96.886078 -283.501449) (xy 96.839911 -283.524972) (xy 96.790632 -283.540984) (xy 96.739455 -283.54909)
			(xy 96.687641 -283.54909) (xy 96.636464 -283.540984) (xy 96.587185 -283.524972) (xy 96.541018 -283.501449)
			(xy 96.499099 -283.470993) (xy 96.462461 -283.434355) (xy 96.432005 -283.392436) (xy 96.408482 -283.346269)
			(xy 96.39247 -283.29699) (xy 96.384364 -283.245813) (xy 96.383856 -283.219906) (xy 96.384448 -283.192189)
			(xy 96.393773 -283.137542) (xy 96.402398 -283.111194) (xy 96.410272 -283.089096) (xy 96.205294 -282.734004)
			(xy 96.18218 -282.729686) (xy 96.15736 -282.724514) (xy 96.109579 -282.707563) (xy 96.064958 -282.683494)
			(xy 96.024551 -282.652875) (xy 95.989309 -282.616428) (xy 95.960065 -282.575014) (xy 95.937508 -282.52961)
			(xy 95.922171 -282.481287) (xy 95.914416 -282.431185) (xy 95.913956 -282.405836) (xy 95.633032 -282.405836)
			(xy 95.632524 -282.431723) (xy 95.624425 -282.482861) (xy 95.608426 -282.532101) (xy 95.58492 -282.578233)
			(xy 95.554488 -282.62012) (xy 95.517878 -282.65673) (xy 95.475991 -282.687162) (xy 95.429859 -282.710668)
			(xy 95.380619 -282.726667) (xy 95.329481 -282.734766) (xy 95.277707 -282.734766) (xy 95.226569 -282.726667)
			(xy 95.177329 -282.710668) (xy 95.131197 -282.687162) (xy 95.08931 -282.65673) (xy 95.0527 -282.62012)
			(xy 95.022268 -282.578233) (xy 94.998762 -282.532101) (xy 94.982763 -282.482861) (xy 94.974664 -282.431723)
			(xy 94.974156 -282.405836) (xy 93.75394 -282.405836) (xy 93.753432 -282.431743) (xy 93.745326 -282.48292)
			(xy 93.729314 -282.532199) (xy 93.705791 -282.578366) (xy 93.675335 -282.620285) (xy 93.638697 -282.656923)
			(xy 93.596778 -282.687379) (xy 93.550611 -282.710902) (xy 93.501332 -282.726914) (xy 93.450155 -282.73502)
			(xy 93.398341 -282.73502) (xy 93.347164 -282.726914) (xy 93.297885 -282.710902) (xy 93.251718 -282.687379)
			(xy 93.209799 -282.656923) (xy 93.173161 -282.620285) (xy 93.142705 -282.578366) (xy 93.119182 -282.532199)
			(xy 93.10317 -282.48292) (xy 93.095064 -282.431743) (xy 93.094556 -282.405836) (xy 88.114632 -282.405836)
			(xy 88.11411 -282.433545) (xy 88.10491 -282.488191) (xy 88.096344 -282.514548) (xy 88.08847 -282.536646)
			(xy 88.293702 -282.891738) (xy 88.316562 -282.896056) (xy 88.341357 -282.90128) (xy 88.389096 -282.918263)
			(xy 88.433673 -282.942351) (xy 88.47404 -282.972977) (xy 88.509244 -283.009419) (xy 88.538458 -283.050819)
			(xy 88.560992 -283.096202) (xy 88.576316 -283.144498) (xy 88.584068 -283.194571) (xy 88.584532 -283.219906)
			(xy 88.584024 -283.245787) (xy 92.625176 -283.245787) (xy 92.625176 -283.194013) (xy 92.633275 -283.142878)
			(xy 92.649273 -283.093638) (xy 92.672778 -283.047508) (xy 92.703209 -283.005622) (xy 92.739818 -282.969013)
			(xy 92.781703 -282.938581) (xy 92.827833 -282.915076) (xy 92.877072 -282.899076) (xy 92.928207 -282.890976)
			(xy 92.954094 -282.890468) (xy 92.979605 -282.890965) (xy 93.030018 -282.898824) (xy 93.078619 -282.914355)
			(xy 93.124247 -282.937187) (xy 93.165813 -282.966776) (xy 93.202325 -283.002415) (xy 93.218 -283.022548)
			(xy 93.629988 -283.022548) (xy 93.645654 -283.002407) (xy 93.682167 -282.966766) (xy 93.723734 -282.937174)
			(xy 93.769364 -282.91434) (xy 93.817967 -282.898806) (xy 93.868382 -282.890945) (xy 93.893894 -282.890468)
			(xy 93.919784 -282.890937) (xy 93.970927 -282.899036) (xy 94.020174 -282.915037) (xy 94.066311 -282.938544)
			(xy 94.108202 -282.968979) (xy 94.144817 -283.005593) (xy 94.175253 -283.047484) (xy 94.198761 -283.093621)
			(xy 94.214762 -283.142867) (xy 94.222863 -283.19401) (xy 94.222863 -283.24579) (xy 94.214762 -283.296933)
			(xy 94.198761 -283.346179) (xy 94.175253 -283.392316) (xy 94.144817 -283.434207) (xy 94.108202 -283.470821)
			(xy 94.066311 -283.501256) (xy 94.020174 -283.524763) (xy 93.970927 -283.540764) (xy 93.919784 -283.548863)
			(xy 93.893894 -283.549344) (xy 93.868381 -283.54889) (xy 93.817964 -283.541027) (xy 93.769361 -283.52549)
			(xy 93.723732 -283.502649) (xy 93.682168 -283.473051) (xy 93.64566 -283.437402) (xy 93.629988 -283.417264)
			(xy 93.218 -283.417264) (xy 93.202317 -283.437392) (xy 93.16581 -283.473038) (xy 93.124247 -283.502633)
			(xy 93.078621 -283.525471) (xy 93.03002 -283.541006) (xy 92.979606 -283.548867) (xy 92.954094 -283.549344)
			(xy 92.928207 -283.548824) (xy 92.877072 -283.540724) (xy 92.827833 -283.524724) (xy 92.781703 -283.501219)
			(xy 92.739818 -283.470787) (xy 92.703209 -283.434178) (xy 92.672778 -283.392292) (xy 92.649273 -283.346162)
			(xy 92.633275 -283.296922) (xy 92.625176 -283.245787) (xy 88.584024 -283.245787) (xy 88.584024 -283.245793)
			(xy 88.575925 -283.296931) (xy 88.559926 -283.346171) (xy 88.53642 -283.392303) (xy 88.505988 -283.43419)
			(xy 88.469378 -283.4708) (xy 88.427491 -283.501232) (xy 88.381359 -283.524738) (xy 88.332119 -283.540737)
			(xy 88.280981 -283.548836) (xy 88.229207 -283.548836) (xy 88.178069 -283.540737) (xy 88.128829 -283.524738)
			(xy 88.082697 -283.501232) (xy 88.04081 -283.4708) (xy 88.0042 -283.43419) (xy 87.973768 -283.392303)
			(xy 87.950262 -283.346171) (xy 87.934263 -283.296931) (xy 87.926164 -283.245793) (xy 87.925656 -283.219906)
			(xy 87.926189 -283.192198) (xy 87.935382 -283.137551) (xy 87.943944 -283.111194) (xy 87.951818 -283.089096)
			(xy 87.746586 -282.734004) (xy 87.723726 -282.729686) (xy 87.698938 -282.724431) (xy 87.651203 -282.70745)
			(xy 87.606628 -282.683364) (xy 87.566263 -282.652742) (xy 87.531059 -282.616304) (xy 87.501844 -282.574908)
			(xy 87.479308 -282.52953) (xy 87.463981 -282.481238) (xy 87.456223 -282.431169) (xy 87.455756 -282.405836)
			(xy 2.509012 -282.405836) (xy 2.509012 -284.033722) (xy 86.515956 -284.033722) (xy 86.516464 -284.007815)
			(xy 86.52457 -283.956638) (xy 86.540582 -283.907359) (xy 86.564105 -283.861192) (xy 86.594561 -283.819273)
			(xy 86.631199 -283.782635) (xy 86.673118 -283.752179) (xy 86.719285 -283.728656) (xy 86.768564 -283.712644)
			(xy 86.819741 -283.704538) (xy 86.871555 -283.704538) (xy 86.922732 -283.712644) (xy 86.972011 -283.728656)
			(xy 87.018178 -283.752179) (xy 87.060097 -283.782635) (xy 87.096735 -283.819273) (xy 87.127191 -283.861192)
			(xy 87.150714 -283.907359) (xy 87.166726 -283.956638) (xy 87.174832 -284.007815) (xy 87.17534 -284.033722)
			(xy 334.456024 -284.033722) (xy 334.456532 -284.007815) (xy 334.464638 -283.956638) (xy 334.48065 -283.907359)
			(xy 334.504173 -283.861192) (xy 334.534629 -283.819273) (xy 334.571267 -283.782635) (xy 334.613186 -283.752179)
			(xy 334.659353 -283.728656) (xy 334.708632 -283.712644) (xy 334.759809 -283.704538) (xy 334.811623 -283.704538)
			(xy 334.8628 -283.712644) (xy 334.912079 -283.728656) (xy 334.958246 -283.752179) (xy 335.000165 -283.782635)
			(xy 335.036803 -283.819273) (xy 335.067259 -283.861192) (xy 335.090782 -283.907359) (xy 335.106794 -283.956638)
			(xy 335.1149 -284.007815) (xy 335.115408 -284.033722) (xy 335.114819 -284.06144) (xy 335.105492 -284.116086)
			(xy 335.096866 -284.142434) (xy 335.088992 -284.164532) (xy 335.29397 -284.51937) (xy 335.31683 -284.523688)
			(xy 335.341643 -284.528833) (xy 335.389384 -284.545828) (xy 335.433962 -284.569927) (xy 335.474328 -284.600564)
			(xy 335.50953 -284.637016) (xy 335.538741 -284.678425) (xy 335.561271 -284.723817) (xy 335.576591 -284.772121)
			(xy 335.584339 -284.8222) (xy 335.5848 -284.847538) (xy 335.584292 -284.873425) (xy 335.576193 -284.924563)
			(xy 335.560194 -284.973803) (xy 335.536688 -285.019935) (xy 335.506256 -285.061822) (xy 335.469646 -285.098432)
			(xy 335.427759 -285.128864) (xy 335.381627 -285.15237) (xy 335.332387 -285.168369) (xy 335.281249 -285.176468)
			(xy 335.229475 -285.176468) (xy 335.178337 -285.168369) (xy 335.129097 -285.15237) (xy 335.082965 -285.128864)
			(xy 335.041078 -285.098432) (xy 335.004468 -285.061822) (xy 334.974036 -285.019935) (xy 334.95053 -284.973803)
			(xy 334.934531 -284.924563) (xy 334.926432 -284.873425) (xy 334.925924 -284.847538) (xy 334.926462 -284.81983)
			(xy 334.935651 -284.765183) (xy 334.944212 -284.738826) (xy 334.952086 -284.716728) (xy 334.747108 -284.36189)
			(xy 334.724248 -284.357572) (xy 334.699419 -284.352437) (xy 334.651638 -284.33548) (xy 334.607017 -284.311405)
			(xy 334.56661 -284.280781) (xy 334.531369 -284.24433) (xy 334.502126 -284.202912) (xy 334.479571 -284.157504)
			(xy 334.464236 -284.109178) (xy 334.456483 -284.059073) (xy 334.456024 -284.033722) (xy 87.17534 -284.033722)
			(xy 87.174755 -284.06144) (xy 87.165426 -284.116086) (xy 87.156798 -284.142434) (xy 87.148924 -284.164532)
			(xy 87.353902 -284.51937) (xy 87.376762 -284.523688) (xy 87.401564 -284.528882) (xy 87.449305 -284.545867)
			(xy 87.493884 -284.569958) (xy 87.534252 -284.600587) (xy 87.569457 -284.637033) (xy 87.598669 -284.678438)
			(xy 87.621201 -284.723825) (xy 87.636522 -284.772125) (xy 87.644271 -284.822202) (xy 87.644732 -284.847538)
			(xy 87.644224 -284.873425) (xy 87.636125 -284.924563) (xy 87.620126 -284.973803) (xy 87.59662 -285.019935)
			(xy 87.566188 -285.061822) (xy 87.529578 -285.098432) (xy 87.487691 -285.128864) (xy 87.441559 -285.15237)
			(xy 87.392319 -285.168369) (xy 87.341181 -285.176468) (xy 87.289407 -285.176468) (xy 87.238269 -285.168369)
			(xy 87.189029 -285.15237) (xy 87.142897 -285.128864) (xy 87.10101 -285.098432) (xy 87.0644 -285.061822)
			(xy 87.033968 -285.019935) (xy 87.010462 -284.973803) (xy 86.994463 -284.924563) (xy 86.986364 -284.873425)
			(xy 86.985856 -284.847538) (xy 86.986397 -284.81983) (xy 86.995584 -284.765184) (xy 87.004144 -284.738826)
			(xy 87.012018 -284.716728) (xy 86.80704 -284.36189) (xy 86.78418 -284.357572) (xy 86.759356 -284.352414)
			(xy 86.711575 -284.335461) (xy 86.666954 -284.311391) (xy 86.626545 -284.28077) (xy 86.591303 -284.244322)
			(xy 86.56206 -284.202906) (xy 86.539504 -284.1575) (xy 86.524169 -284.109175) (xy 86.516415 -284.059072)
			(xy 86.515956 -284.033722) (xy 2.509012 -284.033722) (xy 2.509012 -285.661354) (xy 89.335356 -285.661354)
			(xy 89.335864 -285.635467) (xy 89.343963 -285.584329) (xy 89.359962 -285.535089) (xy 89.383468 -285.488957)
			(xy 89.4139 -285.44707) (xy 89.45051 -285.41046) (xy 89.492397 -285.380028) (xy 89.538529 -285.356522)
			(xy 89.587769 -285.340523) (xy 89.638907 -285.332424) (xy 89.690681 -285.332424) (xy 89.741819 -285.340523)
			(xy 89.791059 -285.356522) (xy 89.837191 -285.380028) (xy 89.879078 -285.41046) (xy 89.915688 -285.44707)
			(xy 89.94612 -285.488957) (xy 89.969626 -285.535089) (xy 89.985625 -285.584329) (xy 89.993724 -285.635467)
			(xy 89.994232 -285.661354) (xy 90.275156 -285.661354) (xy 90.27559 -285.636007) (xy 90.28337 -285.585913)
			(xy 90.298725 -285.537599) (xy 90.321292 -285.492204) (xy 90.35054 -285.450798) (xy 90.385779 -285.414354)
			(xy 90.426181 -285.383733) (xy 90.470793 -285.359656) (xy 90.518564 -285.342688) (xy 90.54338 -285.337504)
			(xy 90.56624 -285.333186) (xy 90.771218 -284.978348) (xy 90.763344 -284.956504) (xy 90.754767 -284.930085)
			(xy 90.745569 -284.87531) (xy 90.745056 -284.847538) (xy 90.745564 -284.821651) (xy 90.753663 -284.770513)
			(xy 90.769662 -284.721273) (xy 90.793168 -284.675141) (xy 90.8236 -284.633254) (xy 90.86021 -284.596644)
			(xy 90.902097 -284.566212) (xy 90.948229 -284.542706) (xy 90.997469 -284.526707) (xy 91.048607 -284.518608)
			(xy 91.100381 -284.518608) (xy 91.151519 -284.526707) (xy 91.200759 -284.542706) (xy 91.246891 -284.566212)
			(xy 91.288778 -284.596644) (xy 91.325388 -284.633254) (xy 91.35582 -284.675141) (xy 91.379326 -284.721273)
			(xy 91.395325 -284.770513) (xy 91.403424 -284.821651) (xy 91.403932 -284.847538) (xy 91.403458 -284.872872)
			(xy 91.395701 -284.922944) (xy 91.380375 -284.971239) (xy 91.357841 -285.016622) (xy 91.32863 -285.058022)
			(xy 91.29343 -285.094467) (xy 91.253068 -285.125098) (xy 91.208495 -285.149194) (xy 91.160761 -285.166187)
			(xy 91.135962 -285.171388) (xy 91.113102 -285.175706) (xy 90.908124 -285.530544) (xy 90.915998 -285.552642)
			(xy 90.924622 -285.57899) (xy 90.933948 -285.633636) (xy 90.93454 -285.661354) (xy 91.214956 -285.661354)
			(xy 91.215464 -285.635447) (xy 91.22357 -285.58427) (xy 91.239582 -285.534991) (xy 91.263105 -285.488824)
			(xy 91.293561 -285.446905) (xy 91.330199 -285.410267) (xy 91.372118 -285.379811) (xy 91.418285 -285.356288)
			(xy 91.467564 -285.340276) (xy 91.518741 -285.33217) (xy 91.570555 -285.33217) (xy 91.621732 -285.340276)
			(xy 91.671011 -285.356288) (xy 91.717178 -285.379811) (xy 91.759097 -285.410267) (xy 91.795735 -285.446905)
			(xy 91.826191 -285.488824) (xy 91.849714 -285.534991) (xy 91.865726 -285.58427) (xy 91.873832 -285.635447)
			(xy 91.87434 -285.661354) (xy 92.154756 -285.661354) (xy 92.155232 -285.63602) (xy 92.16299 -285.585949)
			(xy 92.178317 -285.537654) (xy 92.20085 -285.492273) (xy 92.230061 -285.450872) (xy 92.265261 -285.414427)
			(xy 92.305622 -285.383796) (xy 92.350194 -285.3597) (xy 92.397927 -285.342705) (xy 92.422726 -285.337504)
			(xy 92.445586 -285.333186) (xy 92.650818 -284.97784) (xy 92.643198 -284.955996) (xy 92.634574 -284.929714)
			(xy 92.625259 -284.875193) (xy 92.624656 -284.847538) (xy 92.625164 -284.821631) (xy 92.63327 -284.770454)
			(xy 92.649282 -284.721175) (xy 92.672805 -284.675008) (xy 92.703261 -284.633089) (xy 92.739899 -284.596451)
			(xy 92.781818 -284.565995) (xy 92.827985 -284.542472) (xy 92.877264 -284.52646) (xy 92.928441 -284.518354)
			(xy 92.980255 -284.518354) (xy 93.031432 -284.52646) (xy 93.080711 -284.542472) (xy 93.126878 -284.565995)
			(xy 93.168797 -284.596451) (xy 93.205435 -284.633089) (xy 93.235891 -284.675008) (xy 93.259414 -284.721175)
			(xy 93.275426 -284.770454) (xy 93.283532 -284.821631) (xy 93.28404 -284.847538) (xy 93.283648 -284.872916)
			(xy 93.275873 -284.923072) (xy 93.260496 -284.971442) (xy 93.237881 -285.016882) (xy 93.208565 -285.058314)
			(xy 93.17324 -285.09476) (xy 93.132743 -285.125356) (xy 93.088033 -285.149379) (xy 93.040166 -285.166259)
			(xy 93.015308 -285.171388) (xy 92.992448 -285.175706) (xy 92.78747 -285.530544) (xy 92.795344 -285.552642)
			(xy 92.803916 -285.578997) (xy 92.813107 -285.633645) (xy 92.813632 -285.661354) (xy 93.094556 -285.661354)
			(xy 93.095064 -285.635467) (xy 93.103163 -285.584329) (xy 93.119162 -285.535089) (xy 93.142668 -285.488957)
			(xy 93.1731 -285.44707) (xy 93.20971 -285.41046) (xy 93.251597 -285.380028) (xy 93.297729 -285.356522)
			(xy 93.346969 -285.340523) (xy 93.398107 -285.332424) (xy 93.449881 -285.332424) (xy 93.501019 -285.340523)
			(xy 93.550259 -285.356522) (xy 93.596391 -285.380028) (xy 93.638278 -285.41046) (xy 93.674888 -285.44707)
			(xy 93.70532 -285.488957) (xy 93.728826 -285.535089) (xy 93.744825 -285.584329) (xy 93.752924 -285.635467)
			(xy 93.753432 -285.661354) (xy 94.034356 -285.661354) (xy 94.034832 -285.63602) (xy 94.04259 -285.585949)
			(xy 94.057917 -285.537654) (xy 94.08045 -285.492273) (xy 94.109661 -285.450872) (xy 94.144861 -285.414427)
			(xy 94.185222 -285.383796) (xy 94.229794 -285.3597) (xy 94.277527 -285.342705) (xy 94.302326 -285.337504)
			(xy 94.325186 -285.333186) (xy 94.530418 -284.97784) (xy 94.522798 -284.955996) (xy 94.514174 -284.929714)
			(xy 94.504859 -284.875193) (xy 94.504256 -284.847538) (xy 94.504764 -284.821631) (xy 94.51287 -284.770454)
			(xy 94.528882 -284.721175) (xy 94.552405 -284.675008) (xy 94.582861 -284.633089) (xy 94.619499 -284.596451)
			(xy 94.661418 -284.565995) (xy 94.707585 -284.542472) (xy 94.756864 -284.52646) (xy 94.808041 -284.518354)
			(xy 94.859855 -284.518354) (xy 94.911032 -284.52646) (xy 94.960311 -284.542472) (xy 95.006478 -284.565995)
			(xy 95.048397 -284.596451) (xy 95.085035 -284.633089) (xy 95.115491 -284.675008) (xy 95.139014 -284.721175)
			(xy 95.155026 -284.770454) (xy 95.163132 -284.821631) (xy 95.16364 -284.847538) (xy 95.163248 -284.872916)
			(xy 95.155473 -284.923072) (xy 95.140096 -284.971442) (xy 95.117481 -285.016882) (xy 95.088165 -285.058314)
			(xy 95.05284 -285.09476) (xy 95.012343 -285.125356) (xy 94.967633 -285.149379) (xy 94.919766 -285.166259)
			(xy 94.894908 -285.171388) (xy 94.872048 -285.175706) (xy 94.66707 -285.530544) (xy 94.674944 -285.552642)
			(xy 94.683516 -285.578997) (xy 94.692707 -285.633645) (xy 94.693232 -285.661354) (xy 94.974156 -285.661354)
			(xy 94.974664 -285.635467) (xy 94.982763 -285.584329) (xy 94.998762 -285.535089) (xy 95.022268 -285.488957)
			(xy 95.0527 -285.44707) (xy 95.08931 -285.41046) (xy 95.131197 -285.380028) (xy 95.177329 -285.356522)
			(xy 95.226569 -285.340523) (xy 95.277707 -285.332424) (xy 95.329481 -285.332424) (xy 95.380619 -285.340523)
			(xy 95.429859 -285.356522) (xy 95.475991 -285.380028) (xy 95.517878 -285.41046) (xy 95.554488 -285.44707)
			(xy 95.58492 -285.488957) (xy 95.608426 -285.535089) (xy 95.624425 -285.584329) (xy 95.632524 -285.635467)
			(xy 95.633032 -285.661354) (xy 95.913956 -285.661354) (xy 95.914432 -285.63602) (xy 95.92219 -285.585949)
			(xy 95.937517 -285.537654) (xy 95.96005 -285.492273) (xy 95.989261 -285.450872) (xy 96.024461 -285.414427)
			(xy 96.064822 -285.383796) (xy 96.109394 -285.3597) (xy 96.157127 -285.342705) (xy 96.181926 -285.337504)
			(xy 96.204786 -285.333186) (xy 96.410018 -284.97784) (xy 96.402398 -284.955996) (xy 96.393774 -284.929714)
			(xy 96.384459 -284.875193) (xy 96.383856 -284.847538) (xy 96.384364 -284.821631) (xy 96.39247 -284.770454)
			(xy 96.408482 -284.721175) (xy 96.432005 -284.675008) (xy 96.462461 -284.633089) (xy 96.499099 -284.596451)
			(xy 96.541018 -284.565995) (xy 96.587185 -284.542472) (xy 96.636464 -284.52646) (xy 96.687641 -284.518354)
			(xy 96.739455 -284.518354) (xy 96.790632 -284.52646) (xy 96.839911 -284.542472) (xy 96.886078 -284.565995)
			(xy 96.927997 -284.596451) (xy 96.964635 -284.633089) (xy 96.995091 -284.675008) (xy 97.018614 -284.721175)
			(xy 97.034626 -284.770454) (xy 97.042732 -284.821631) (xy 97.04324 -284.847538) (xy 97.042848 -284.872916)
			(xy 97.035073 -284.923072) (xy 97.019696 -284.971442) (xy 96.997081 -285.016882) (xy 96.967765 -285.058314)
			(xy 96.93244 -285.09476) (xy 96.891943 -285.125356) (xy 96.847233 -285.149379) (xy 96.799366 -285.166259)
			(xy 96.774508 -285.171388) (xy 96.751648 -285.175706) (xy 96.54667 -285.530544) (xy 96.554544 -285.552642)
			(xy 96.563116 -285.578997) (xy 96.572307 -285.633645) (xy 96.572832 -285.661354) (xy 96.853756 -285.661354)
			(xy 96.854264 -285.635467) (xy 96.862363 -285.584329) (xy 96.878362 -285.535089) (xy 96.901868 -285.488957)
			(xy 96.9323 -285.44707) (xy 96.96891 -285.41046) (xy 97.010797 -285.380028) (xy 97.056929 -285.356522)
			(xy 97.106169 -285.340523) (xy 97.157307 -285.332424) (xy 97.209081 -285.332424) (xy 97.260219 -285.340523)
			(xy 97.309459 -285.356522) (xy 97.355591 -285.380028) (xy 97.397478 -285.41046) (xy 97.434088 -285.44707)
			(xy 97.46452 -285.488957) (xy 97.488026 -285.535089) (xy 97.504025 -285.584329) (xy 97.512124 -285.635467)
			(xy 97.512632 -285.661354) (xy 97.793556 -285.661354) (xy 97.794032 -285.63602) (xy 97.80179 -285.585949)
			(xy 97.817117 -285.537654) (xy 97.83965 -285.492273) (xy 97.868861 -285.450872) (xy 97.904061 -285.414427)
			(xy 97.944422 -285.383796) (xy 97.988994 -285.3597) (xy 98.036727 -285.342705) (xy 98.061526 -285.337504)
			(xy 98.084386 -285.333186) (xy 98.289618 -284.97784) (xy 98.281998 -284.955996) (xy 98.273374 -284.929714)
			(xy 98.264059 -284.875193) (xy 98.263456 -284.847538) (xy 98.263964 -284.821631) (xy 98.27207 -284.770454)
			(xy 98.288082 -284.721175) (xy 98.311605 -284.675008) (xy 98.342061 -284.633089) (xy 98.378699 -284.596451)
			(xy 98.420618 -284.565995) (xy 98.466785 -284.542472) (xy 98.516064 -284.52646) (xy 98.567241 -284.518354)
			(xy 98.619055 -284.518354) (xy 98.670232 -284.52646) (xy 98.719511 -284.542472) (xy 98.765678 -284.565995)
			(xy 98.807597 -284.596451) (xy 98.844235 -284.633089) (xy 98.874691 -284.675008) (xy 98.898214 -284.721175)
			(xy 98.914226 -284.770454) (xy 98.922332 -284.821631) (xy 98.92284 -284.847538) (xy 98.922448 -284.872916)
			(xy 98.914673 -284.923072) (xy 98.899296 -284.971442) (xy 98.876681 -285.016882) (xy 98.847365 -285.058314)
			(xy 98.81204 -285.09476) (xy 98.771543 -285.125356) (xy 98.726833 -285.149379) (xy 98.678966 -285.166259)
			(xy 98.654108 -285.171388) (xy 98.631248 -285.175706) (xy 98.42627 -285.530544) (xy 98.434144 -285.552642)
			(xy 98.442716 -285.578997) (xy 98.451907 -285.633645) (xy 98.452432 -285.661354) (xy 98.733356 -285.661354)
			(xy 98.733864 -285.635467) (xy 98.741963 -285.584329) (xy 98.757962 -285.535089) (xy 98.781468 -285.488957)
			(xy 98.8119 -285.44707) (xy 98.84851 -285.41046) (xy 98.890397 -285.380028) (xy 98.936529 -285.356522)
			(xy 98.985769 -285.340523) (xy 99.036907 -285.332424) (xy 99.088681 -285.332424) (xy 99.139819 -285.340523)
			(xy 99.189059 -285.356522) (xy 99.235191 -285.380028) (xy 99.277078 -285.41046) (xy 99.313688 -285.44707)
			(xy 99.34412 -285.488957) (xy 99.367626 -285.535089) (xy 99.383625 -285.584329) (xy 99.391724 -285.635467)
			(xy 99.392232 -285.661354) (xy 99.673156 -285.661354) (xy 99.673632 -285.63602) (xy 99.68139 -285.585949)
			(xy 99.696717 -285.537654) (xy 99.71925 -285.492273) (xy 99.748461 -285.450872) (xy 99.783661 -285.414427)
			(xy 99.824022 -285.383796) (xy 99.868594 -285.3597) (xy 99.916327 -285.342705) (xy 99.941126 -285.337504)
			(xy 99.963986 -285.333186) (xy 100.169218 -284.97784) (xy 100.161598 -284.955996) (xy 100.152974 -284.929714)
			(xy 100.143659 -284.875193) (xy 100.143056 -284.847538) (xy 100.143564 -284.821631) (xy 100.15167 -284.770454)
			(xy 100.167682 -284.721175) (xy 100.191205 -284.675008) (xy 100.221661 -284.633089) (xy 100.258299 -284.596451)
			(xy 100.300218 -284.565995) (xy 100.346385 -284.542472) (xy 100.395664 -284.52646) (xy 100.446841 -284.518354)
			(xy 100.498655 -284.518354) (xy 100.549832 -284.52646) (xy 100.599111 -284.542472) (xy 100.645278 -284.565995)
			(xy 100.687197 -284.596451) (xy 100.723835 -284.633089) (xy 100.754291 -284.675008) (xy 100.777814 -284.721175)
			(xy 100.793826 -284.770454) (xy 100.801932 -284.821631) (xy 100.80244 -284.847538) (xy 100.802048 -284.872916)
			(xy 100.794273 -284.923072) (xy 100.778896 -284.971442) (xy 100.756281 -285.016882) (xy 100.726965 -285.058314)
			(xy 100.69164 -285.09476) (xy 100.651143 -285.125356) (xy 100.606433 -285.149379) (xy 100.558566 -285.166259)
			(xy 100.533708 -285.171388) (xy 100.510848 -285.175706) (xy 100.30587 -285.530544) (xy 100.313744 -285.552642)
			(xy 100.322316 -285.578997) (xy 100.331507 -285.633645) (xy 100.332032 -285.661354) (xy 100.612956 -285.661354)
			(xy 100.613464 -285.635467) (xy 100.621563 -285.584329) (xy 100.637562 -285.535089) (xy 100.661068 -285.488957)
			(xy 100.6915 -285.44707) (xy 100.72811 -285.41046) (xy 100.769997 -285.380028) (xy 100.816129 -285.356522)
			(xy 100.865369 -285.340523) (xy 100.916507 -285.332424) (xy 100.968281 -285.332424) (xy 101.019419 -285.340523)
			(xy 101.068659 -285.356522) (xy 101.114791 -285.380028) (xy 101.156678 -285.41046) (xy 101.193288 -285.44707)
			(xy 101.22372 -285.488957) (xy 101.247226 -285.535089) (xy 101.263225 -285.584329) (xy 101.271324 -285.635467)
			(xy 101.271832 -285.661354) (xy 101.552756 -285.661354) (xy 101.553232 -285.63602) (xy 101.56099 -285.585949)
			(xy 101.576317 -285.537654) (xy 101.59885 -285.492273) (xy 101.628061 -285.450872) (xy 101.663261 -285.414427)
			(xy 101.703622 -285.383796) (xy 101.748194 -285.3597) (xy 101.795927 -285.342705) (xy 101.820726 -285.337504)
			(xy 101.843586 -285.333186) (xy 102.048818 -284.97784) (xy 102.041198 -284.955996) (xy 102.032574 -284.929714)
			(xy 102.023259 -284.875193) (xy 102.022656 -284.847538) (xy 102.023164 -284.821631) (xy 102.03127 -284.770454)
			(xy 102.047282 -284.721175) (xy 102.070805 -284.675008) (xy 102.101261 -284.633089) (xy 102.137899 -284.596451)
			(xy 102.179818 -284.565995) (xy 102.225985 -284.542472) (xy 102.275264 -284.52646) (xy 102.326441 -284.518354)
			(xy 102.378255 -284.518354) (xy 102.429432 -284.52646) (xy 102.478711 -284.542472) (xy 102.524878 -284.565995)
			(xy 102.566797 -284.596451) (xy 102.603435 -284.633089) (xy 102.633891 -284.675008) (xy 102.657414 -284.721175)
			(xy 102.673426 -284.770454) (xy 102.681532 -284.821631) (xy 102.68204 -284.847538) (xy 102.681648 -284.872916)
			(xy 102.673873 -284.923072) (xy 102.658496 -284.971442) (xy 102.635881 -285.016882) (xy 102.606565 -285.058314)
			(xy 102.57124 -285.09476) (xy 102.530743 -285.125356) (xy 102.486033 -285.149379) (xy 102.438166 -285.166259)
			(xy 102.413308 -285.171388) (xy 102.390448 -285.175706) (xy 102.18547 -285.530544) (xy 102.193344 -285.552642)
			(xy 102.201916 -285.578997) (xy 102.211107 -285.633645) (xy 102.211632 -285.661354) (xy 102.492556 -285.661354)
			(xy 102.493064 -285.635467) (xy 102.501163 -285.584329) (xy 102.517162 -285.535089) (xy 102.540668 -285.488957)
			(xy 102.5711 -285.44707) (xy 102.60771 -285.41046) (xy 102.649597 -285.380028) (xy 102.695729 -285.356522)
			(xy 102.744969 -285.340523) (xy 102.796107 -285.332424) (xy 102.847881 -285.332424) (xy 102.899019 -285.340523)
			(xy 102.948259 -285.356522) (xy 102.994391 -285.380028) (xy 103.036278 -285.41046) (xy 103.072888 -285.44707)
			(xy 103.10332 -285.488957) (xy 103.126826 -285.535089) (xy 103.142825 -285.584329) (xy 103.150924 -285.635467)
			(xy 103.151432 -285.661354) (xy 103.432356 -285.661354) (xy 103.432832 -285.63602) (xy 103.44059 -285.585949)
			(xy 103.455917 -285.537654) (xy 103.47845 -285.492273) (xy 103.507661 -285.450872) (xy 103.542861 -285.414427)
			(xy 103.583222 -285.383796) (xy 103.627794 -285.3597) (xy 103.675527 -285.342705) (xy 103.700326 -285.337504)
			(xy 103.723186 -285.333186) (xy 103.928418 -284.97784) (xy 103.920798 -284.955996) (xy 103.912174 -284.929714)
			(xy 103.902859 -284.875193) (xy 103.902256 -284.847538) (xy 103.902764 -284.821631) (xy 103.91087 -284.770454)
			(xy 103.926882 -284.721175) (xy 103.950405 -284.675008) (xy 103.980861 -284.633089) (xy 104.017499 -284.596451)
			(xy 104.059418 -284.565995) (xy 104.105585 -284.542472) (xy 104.154864 -284.52646) (xy 104.206041 -284.518354)
			(xy 104.257855 -284.518354) (xy 104.309032 -284.52646) (xy 104.358311 -284.542472) (xy 104.404478 -284.565995)
			(xy 104.446397 -284.596451) (xy 104.483035 -284.633089) (xy 104.513491 -284.675008) (xy 104.537014 -284.721175)
			(xy 104.553026 -284.770454) (xy 104.561132 -284.821631) (xy 104.56164 -284.847538) (xy 118.939056 -284.847538)
			(xy 118.939564 -284.821631) (xy 118.94767 -284.770454) (xy 118.963682 -284.721175) (xy 118.987205 -284.675008)
			(xy 119.017661 -284.633089) (xy 119.054299 -284.596451) (xy 119.096218 -284.565995) (xy 119.142385 -284.542472)
			(xy 119.191664 -284.52646) (xy 119.242841 -284.518354) (xy 119.294655 -284.518354) (xy 119.345832 -284.52646)
			(xy 119.395111 -284.542472) (xy 119.441278 -284.565995) (xy 119.483197 -284.596451) (xy 119.519835 -284.633089)
			(xy 119.550291 -284.675008) (xy 119.573814 -284.721175) (xy 119.589826 -284.770454) (xy 119.597932 -284.821631)
			(xy 119.59844 -284.847538) (xy 120.818656 -284.847538) (xy 120.819164 -284.821631) (xy 120.82727 -284.770454)
			(xy 120.843282 -284.721175) (xy 120.866805 -284.675008) (xy 120.897261 -284.633089) (xy 120.933899 -284.596451)
			(xy 120.975818 -284.565995) (xy 121.021985 -284.542472) (xy 121.071264 -284.52646) (xy 121.122441 -284.518354)
			(xy 121.174255 -284.518354) (xy 121.225432 -284.52646) (xy 121.274711 -284.542472) (xy 121.320878 -284.565995)
			(xy 121.362797 -284.596451) (xy 121.399435 -284.633089) (xy 121.429891 -284.675008) (xy 121.453414 -284.721175)
			(xy 121.469426 -284.770454) (xy 121.477532 -284.821631) (xy 121.47804 -284.847538) (xy 122.698256 -284.847538)
			(xy 122.698764 -284.821631) (xy 122.70687 -284.770454) (xy 122.722882 -284.721175) (xy 122.746405 -284.675008)
			(xy 122.776861 -284.633089) (xy 122.813499 -284.596451) (xy 122.855418 -284.565995) (xy 122.901585 -284.542472)
			(xy 122.950864 -284.52646) (xy 123.002041 -284.518354) (xy 123.053855 -284.518354) (xy 123.105032 -284.52646)
			(xy 123.154311 -284.542472) (xy 123.200478 -284.565995) (xy 123.242397 -284.596451) (xy 123.279035 -284.633089)
			(xy 123.309491 -284.675008) (xy 123.333014 -284.721175) (xy 123.349026 -284.770454) (xy 123.357132 -284.821631)
			(xy 123.35764 -284.847538) (xy 124.577856 -284.847538) (xy 124.578364 -284.821631) (xy 124.58647 -284.770454)
			(xy 124.602482 -284.721175) (xy 124.626005 -284.675008) (xy 124.656461 -284.633089) (xy 124.693099 -284.596451)
			(xy 124.735018 -284.565995) (xy 124.781185 -284.542472) (xy 124.830464 -284.52646) (xy 124.881641 -284.518354)
			(xy 124.933455 -284.518354) (xy 124.984632 -284.52646) (xy 125.033911 -284.542472) (xy 125.080078 -284.565995)
			(xy 125.121997 -284.596451) (xy 125.158635 -284.633089) (xy 125.189091 -284.675008) (xy 125.212614 -284.721175)
			(xy 125.228626 -284.770454) (xy 125.236732 -284.821631) (xy 125.23724 -284.847538) (xy 126.457456 -284.847538)
			(xy 126.457964 -284.821631) (xy 126.46607 -284.770454) (xy 126.482082 -284.721175) (xy 126.505605 -284.675008)
			(xy 126.536061 -284.633089) (xy 126.572699 -284.596451) (xy 126.614618 -284.565995) (xy 126.660785 -284.542472)
			(xy 126.710064 -284.52646) (xy 126.761241 -284.518354) (xy 126.813055 -284.518354) (xy 126.864232 -284.52646)
			(xy 126.913511 -284.542472) (xy 126.959678 -284.565995) (xy 127.001597 -284.596451) (xy 127.038235 -284.633089)
			(xy 127.068691 -284.675008) (xy 127.092214 -284.721175) (xy 127.108226 -284.770454) (xy 127.116332 -284.821631)
			(xy 127.11684 -284.847538) (xy 128.337056 -284.847538) (xy 128.337564 -284.821631) (xy 128.34567 -284.770454)
			(xy 128.361682 -284.721175) (xy 128.385205 -284.675008) (xy 128.415661 -284.633089) (xy 128.452299 -284.596451)
			(xy 128.494218 -284.565995) (xy 128.540385 -284.542472) (xy 128.589664 -284.52646) (xy 128.640841 -284.518354)
			(xy 128.692655 -284.518354) (xy 128.743832 -284.52646) (xy 128.793111 -284.542472) (xy 128.839278 -284.565995)
			(xy 128.881197 -284.596451) (xy 128.917835 -284.633089) (xy 128.948291 -284.675008) (xy 128.971814 -284.721175)
			(xy 128.987826 -284.770454) (xy 128.995932 -284.821631) (xy 128.99644 -284.847538) (xy 130.216656 -284.847538)
			(xy 130.217164 -284.821631) (xy 130.22527 -284.770454) (xy 130.241282 -284.721175) (xy 130.264805 -284.675008)
			(xy 130.295261 -284.633089) (xy 130.331899 -284.596451) (xy 130.373818 -284.565995) (xy 130.419985 -284.542472)
			(xy 130.469264 -284.52646) (xy 130.520441 -284.518354) (xy 130.572255 -284.518354) (xy 130.623432 -284.52646)
			(xy 130.672711 -284.542472) (xy 130.718878 -284.565995) (xy 130.760797 -284.596451) (xy 130.797435 -284.633089)
			(xy 130.827891 -284.675008) (xy 130.851414 -284.721175) (xy 130.867426 -284.770454) (xy 130.875532 -284.821631)
			(xy 130.87604 -284.847538) (xy 132.096256 -284.847538) (xy 132.096764 -284.821631) (xy 132.10487 -284.770454)
			(xy 132.120882 -284.721175) (xy 132.144405 -284.675008) (xy 132.174861 -284.633089) (xy 132.211499 -284.596451)
			(xy 132.253418 -284.565995) (xy 132.299585 -284.542472) (xy 132.348864 -284.52646) (xy 132.400041 -284.518354)
			(xy 132.451855 -284.518354) (xy 132.503032 -284.52646) (xy 132.552311 -284.542472) (xy 132.598478 -284.565995)
			(xy 132.640397 -284.596451) (xy 132.677035 -284.633089) (xy 132.707491 -284.675008) (xy 132.731014 -284.721175)
			(xy 132.747026 -284.770454) (xy 132.755132 -284.821631) (xy 132.75564 -284.847538) (xy 132.755034 -284.875255)
			(xy 132.745719 -284.929901) (xy 132.737098 -284.95625) (xy 132.729224 -284.978348) (xy 132.934202 -285.333186)
			(xy 132.957062 -285.337504) (xy 132.981868 -285.342683) (xy 133.02961 -285.359669) (xy 133.07419 -285.383762)
			(xy 133.114558 -285.414393) (xy 133.149763 -285.450841) (xy 133.178975 -285.492247) (xy 133.201506 -285.537636)
			(xy 133.216825 -285.585939) (xy 133.224572 -285.636017) (xy 133.225032 -285.661354) (xy 133.224524 -285.687241)
			(xy 133.216425 -285.738379) (xy 133.200426 -285.787619) (xy 133.17692 -285.833751) (xy 133.146488 -285.875638)
			(xy 133.109878 -285.912248) (xy 133.067991 -285.94268) (xy 133.021859 -285.966186) (xy 132.972619 -285.982185)
			(xy 132.921481 -285.990284) (xy 132.869707 -285.990284) (xy 132.818569 -285.982185) (xy 132.769329 -285.966186)
			(xy 132.723197 -285.94268) (xy 132.68131 -285.912248) (xy 132.6447 -285.875638) (xy 132.614268 -285.833751)
			(xy 132.590762 -285.787619) (xy 132.574763 -285.738379) (xy 132.566664 -285.687241) (xy 132.566156 -285.661354)
			(xy 132.566701 -285.633647) (xy 132.575886 -285.579) (xy 132.584444 -285.552642) (xy 132.592318 -285.530544)
			(xy 132.38734 -285.175706) (xy 132.36448 -285.171388) (xy 132.33966 -285.166215) (xy 132.29188 -285.149263)
			(xy 132.247259 -285.125194) (xy 132.206851 -285.094575) (xy 132.171609 -285.058129) (xy 132.142365 -285.016715)
			(xy 132.119809 -284.971312) (xy 132.104472 -284.922989) (xy 132.096717 -284.872887) (xy 132.096256 -284.847538)
			(xy 130.87604 -284.847538) (xy 130.875434 -284.875255) (xy 130.866119 -284.929901) (xy 130.857498 -284.95625)
			(xy 130.849624 -284.978348) (xy 131.054602 -285.333186) (xy 131.077462 -285.337504) (xy 131.102268 -285.342683)
			(xy 131.15001 -285.359669) (xy 131.19459 -285.383762) (xy 131.234958 -285.414393) (xy 131.270163 -285.450841)
			(xy 131.299375 -285.492247) (xy 131.321906 -285.537636) (xy 131.337225 -285.585939) (xy 131.344972 -285.636017)
			(xy 131.345432 -285.661354) (xy 131.344924 -285.687241) (xy 131.336825 -285.738379) (xy 131.320826 -285.787619)
			(xy 131.29732 -285.833751) (xy 131.266888 -285.875638) (xy 131.230278 -285.912248) (xy 131.188391 -285.94268)
			(xy 131.142259 -285.966186) (xy 131.093019 -285.982185) (xy 131.041881 -285.990284) (xy 130.990107 -285.990284)
			(xy 130.938969 -285.982185) (xy 130.889729 -285.966186) (xy 130.843597 -285.94268) (xy 130.80171 -285.912248)
			(xy 130.7651 -285.875638) (xy 130.734668 -285.833751) (xy 130.711162 -285.787619) (xy 130.695163 -285.738379)
			(xy 130.687064 -285.687241) (xy 130.686556 -285.661354) (xy 130.687101 -285.633647) (xy 130.696286 -285.579)
			(xy 130.704844 -285.552642) (xy 130.712718 -285.530544) (xy 130.50774 -285.175706) (xy 130.48488 -285.171388)
			(xy 130.46006 -285.166215) (xy 130.41228 -285.149263) (xy 130.367659 -285.125194) (xy 130.327251 -285.094575)
			(xy 130.292009 -285.058129) (xy 130.262765 -285.016715) (xy 130.240209 -284.971312) (xy 130.224872 -284.922989)
			(xy 130.217117 -284.872887) (xy 130.216656 -284.847538) (xy 128.99644 -284.847538) (xy 128.995834 -284.875255)
			(xy 128.986519 -284.929901) (xy 128.977898 -284.95625) (xy 128.970024 -284.978348) (xy 129.175002 -285.333186)
			(xy 129.197862 -285.337504) (xy 129.222668 -285.342683) (xy 129.27041 -285.359669) (xy 129.31499 -285.383762)
			(xy 129.355358 -285.414393) (xy 129.390563 -285.450841) (xy 129.419775 -285.492247) (xy 129.442306 -285.537636)
			(xy 129.457625 -285.585939) (xy 129.465372 -285.636017) (xy 129.465832 -285.661354) (xy 129.465324 -285.687241)
			(xy 129.457225 -285.738379) (xy 129.441226 -285.787619) (xy 129.41772 -285.833751) (xy 129.387288 -285.875638)
			(xy 129.350678 -285.912248) (xy 129.308791 -285.94268) (xy 129.262659 -285.966186) (xy 129.213419 -285.982185)
			(xy 129.162281 -285.990284) (xy 129.110507 -285.990284) (xy 129.059369 -285.982185) (xy 129.010129 -285.966186)
			(xy 128.963997 -285.94268) (xy 128.92211 -285.912248) (xy 128.8855 -285.875638) (xy 128.855068 -285.833751)
			(xy 128.831562 -285.787619) (xy 128.815563 -285.738379) (xy 128.807464 -285.687241) (xy 128.806956 -285.661354)
			(xy 128.807501 -285.633647) (xy 128.816686 -285.579) (xy 128.825244 -285.552642) (xy 128.833118 -285.530544)
			(xy 128.62814 -285.175706) (xy 128.60528 -285.171388) (xy 128.58046 -285.166215) (xy 128.53268 -285.149263)
			(xy 128.488059 -285.125194) (xy 128.447651 -285.094575) (xy 128.412409 -285.058129) (xy 128.383165 -285.016715)
			(xy 128.360609 -284.971312) (xy 128.345272 -284.922989) (xy 128.337517 -284.872887) (xy 128.337056 -284.847538)
			(xy 127.11684 -284.847538) (xy 127.116234 -284.875255) (xy 127.106919 -284.929901) (xy 127.098298 -284.95625)
			(xy 127.090424 -284.978348) (xy 127.295402 -285.333186) (xy 127.318262 -285.337504) (xy 127.343068 -285.342683)
			(xy 127.39081 -285.359669) (xy 127.43539 -285.383762) (xy 127.475758 -285.414393) (xy 127.510963 -285.450841)
			(xy 127.540175 -285.492247) (xy 127.562706 -285.537636) (xy 127.578025 -285.585939) (xy 127.585772 -285.636017)
			(xy 127.586232 -285.661354) (xy 127.585724 -285.687241) (xy 127.577625 -285.738379) (xy 127.561626 -285.787619)
			(xy 127.53812 -285.833751) (xy 127.507688 -285.875638) (xy 127.471078 -285.912248) (xy 127.429191 -285.94268)
			(xy 127.383059 -285.966186) (xy 127.333819 -285.982185) (xy 127.282681 -285.990284) (xy 127.230907 -285.990284)
			(xy 127.179769 -285.982185) (xy 127.130529 -285.966186) (xy 127.084397 -285.94268) (xy 127.04251 -285.912248)
			(xy 127.0059 -285.875638) (xy 126.975468 -285.833751) (xy 126.951962 -285.787619) (xy 126.935963 -285.738379)
			(xy 126.927864 -285.687241) (xy 126.927356 -285.661354) (xy 126.927901 -285.633647) (xy 126.937086 -285.579)
			(xy 126.945644 -285.552642) (xy 126.953518 -285.530544) (xy 126.74854 -285.175706) (xy 126.72568 -285.171388)
			(xy 126.70086 -285.166215) (xy 126.65308 -285.149263) (xy 126.608459 -285.125194) (xy 126.568051 -285.094575)
			(xy 126.532809 -285.058129) (xy 126.503565 -285.016715) (xy 126.481009 -284.971312) (xy 126.465672 -284.922989)
			(xy 126.457917 -284.872887) (xy 126.457456 -284.847538) (xy 125.23724 -284.847538) (xy 125.236634 -284.875255)
			(xy 125.227319 -284.929901) (xy 125.218698 -284.95625) (xy 125.210824 -284.978348) (xy 125.415802 -285.333186)
			(xy 125.438662 -285.337504) (xy 125.463468 -285.342683) (xy 125.51121 -285.359669) (xy 125.55579 -285.383762)
			(xy 125.596158 -285.414393) (xy 125.631363 -285.450841) (xy 125.660575 -285.492247) (xy 125.683106 -285.537636)
			(xy 125.698425 -285.585939) (xy 125.706172 -285.636017) (xy 125.706632 -285.661354) (xy 125.706124 -285.687241)
			(xy 125.698025 -285.738379) (xy 125.682026 -285.787619) (xy 125.65852 -285.833751) (xy 125.628088 -285.875638)
			(xy 125.591478 -285.912248) (xy 125.549591 -285.94268) (xy 125.503459 -285.966186) (xy 125.454219 -285.982185)
			(xy 125.403081 -285.990284) (xy 125.351307 -285.990284) (xy 125.300169 -285.982185) (xy 125.250929 -285.966186)
			(xy 125.204797 -285.94268) (xy 125.16291 -285.912248) (xy 125.1263 -285.875638) (xy 125.095868 -285.833751)
			(xy 125.072362 -285.787619) (xy 125.056363 -285.738379) (xy 125.048264 -285.687241) (xy 125.047756 -285.661354)
			(xy 125.048301 -285.633647) (xy 125.057486 -285.579) (xy 125.066044 -285.552642) (xy 125.073918 -285.530544)
			(xy 124.86894 -285.175706) (xy 124.84608 -285.171388) (xy 124.82126 -285.166215) (xy 124.77348 -285.149263)
			(xy 124.728859 -285.125194) (xy 124.688451 -285.094575) (xy 124.653209 -285.058129) (xy 124.623965 -285.016715)
			(xy 124.601409 -284.971312) (xy 124.586072 -284.922989) (xy 124.578317 -284.872887) (xy 124.577856 -284.847538)
			(xy 123.35764 -284.847538) (xy 123.357034 -284.875255) (xy 123.347719 -284.929901) (xy 123.339098 -284.95625)
			(xy 123.331224 -284.978348) (xy 123.536202 -285.333186) (xy 123.559062 -285.337504) (xy 123.583868 -285.342683)
			(xy 123.63161 -285.359669) (xy 123.67619 -285.383762) (xy 123.716558 -285.414393) (xy 123.751763 -285.450841)
			(xy 123.780975 -285.492247) (xy 123.803506 -285.537636) (xy 123.818825 -285.585939) (xy 123.826572 -285.636017)
			(xy 123.827032 -285.661354) (xy 123.826524 -285.687241) (xy 123.818425 -285.738379) (xy 123.802426 -285.787619)
			(xy 123.77892 -285.833751) (xy 123.748488 -285.875638) (xy 123.711878 -285.912248) (xy 123.669991 -285.94268)
			(xy 123.623859 -285.966186) (xy 123.574619 -285.982185) (xy 123.523481 -285.990284) (xy 123.471707 -285.990284)
			(xy 123.420569 -285.982185) (xy 123.371329 -285.966186) (xy 123.325197 -285.94268) (xy 123.28331 -285.912248)
			(xy 123.2467 -285.875638) (xy 123.216268 -285.833751) (xy 123.192762 -285.787619) (xy 123.176763 -285.738379)
			(xy 123.168664 -285.687241) (xy 123.168156 -285.661354) (xy 123.168701 -285.633647) (xy 123.177886 -285.579)
			(xy 123.186444 -285.552642) (xy 123.194318 -285.530544) (xy 122.98934 -285.175706) (xy 122.96648 -285.171388)
			(xy 122.94166 -285.166215) (xy 122.89388 -285.149263) (xy 122.849259 -285.125194) (xy 122.808851 -285.094575)
			(xy 122.773609 -285.058129) (xy 122.744365 -285.016715) (xy 122.721809 -284.971312) (xy 122.706472 -284.922989)
			(xy 122.698717 -284.872887) (xy 122.698256 -284.847538) (xy 121.47804 -284.847538) (xy 121.477434 -284.875255)
			(xy 121.468119 -284.929901) (xy 121.459498 -284.95625) (xy 121.451624 -284.978348) (xy 121.656602 -285.333186)
			(xy 121.679462 -285.337504) (xy 121.704268 -285.342683) (xy 121.75201 -285.359669) (xy 121.79659 -285.383762)
			(xy 121.836958 -285.414393) (xy 121.872163 -285.450841) (xy 121.901375 -285.492247) (xy 121.923906 -285.537636)
			(xy 121.939225 -285.585939) (xy 121.946972 -285.636017) (xy 121.947432 -285.661354) (xy 121.946924 -285.687241)
			(xy 121.938825 -285.738379) (xy 121.922826 -285.787619) (xy 121.89932 -285.833751) (xy 121.868888 -285.875638)
			(xy 121.832278 -285.912248) (xy 121.790391 -285.94268) (xy 121.744259 -285.966186) (xy 121.695019 -285.982185)
			(xy 121.643881 -285.990284) (xy 121.592107 -285.990284) (xy 121.540969 -285.982185) (xy 121.491729 -285.966186)
			(xy 121.445597 -285.94268) (xy 121.40371 -285.912248) (xy 121.3671 -285.875638) (xy 121.336668 -285.833751)
			(xy 121.313162 -285.787619) (xy 121.297163 -285.738379) (xy 121.289064 -285.687241) (xy 121.288556 -285.661354)
			(xy 121.289101 -285.633647) (xy 121.298286 -285.579) (xy 121.306844 -285.552642) (xy 121.314718 -285.530544)
			(xy 121.10974 -285.175706) (xy 121.08688 -285.171388) (xy 121.06206 -285.166215) (xy 121.01428 -285.149263)
			(xy 120.969659 -285.125194) (xy 120.929251 -285.094575) (xy 120.894009 -285.058129) (xy 120.864765 -285.016715)
			(xy 120.842209 -284.971312) (xy 120.826872 -284.922989) (xy 120.819117 -284.872887) (xy 120.818656 -284.847538)
			(xy 119.59844 -284.847538) (xy 119.597834 -284.875255) (xy 119.588519 -284.929901) (xy 119.579898 -284.95625)
			(xy 119.572024 -284.978348) (xy 119.777002 -285.333186) (xy 119.799862 -285.337504) (xy 119.824668 -285.342683)
			(xy 119.87241 -285.359669) (xy 119.91699 -285.383762) (xy 119.957358 -285.414393) (xy 119.992563 -285.450841)
			(xy 120.021775 -285.492247) (xy 120.044306 -285.537636) (xy 120.059625 -285.585939) (xy 120.067372 -285.636017)
			(xy 120.067832 -285.661354) (xy 120.067324 -285.687241) (xy 120.059225 -285.738379) (xy 120.043226 -285.787619)
			(xy 120.01972 -285.833751) (xy 119.989288 -285.875638) (xy 119.952678 -285.912248) (xy 119.910791 -285.94268)
			(xy 119.864659 -285.966186) (xy 119.815419 -285.982185) (xy 119.764281 -285.990284) (xy 119.712507 -285.990284)
			(xy 119.661369 -285.982185) (xy 119.612129 -285.966186) (xy 119.565997 -285.94268) (xy 119.52411 -285.912248)
			(xy 119.4875 -285.875638) (xy 119.457068 -285.833751) (xy 119.433562 -285.787619) (xy 119.417563 -285.738379)
			(xy 119.409464 -285.687241) (xy 119.408956 -285.661354) (xy 119.409501 -285.633647) (xy 119.418686 -285.579)
			(xy 119.427244 -285.552642) (xy 119.435118 -285.530544) (xy 119.23014 -285.175706) (xy 119.20728 -285.171388)
			(xy 119.18246 -285.166215) (xy 119.13468 -285.149263) (xy 119.090059 -285.125194) (xy 119.049651 -285.094575)
			(xy 119.014409 -285.058129) (xy 118.985165 -285.016715) (xy 118.962609 -284.971312) (xy 118.947272 -284.922989)
			(xy 118.939517 -284.872887) (xy 118.939056 -284.847538) (xy 104.56164 -284.847538) (xy 104.561248 -284.872916)
			(xy 104.553473 -284.923072) (xy 104.538096 -284.971442) (xy 104.515481 -285.016882) (xy 104.486165 -285.058314)
			(xy 104.45084 -285.09476) (xy 104.410343 -285.125356) (xy 104.365633 -285.149379) (xy 104.317766 -285.166259)
			(xy 104.292908 -285.171388) (xy 104.270048 -285.175706) (xy 104.06507 -285.530544) (xy 104.072944 -285.552642)
			(xy 104.081516 -285.578997) (xy 104.090707 -285.633645) (xy 104.091232 -285.661354) (xy 104.090724 -285.687241)
			(xy 104.082625 -285.738379) (xy 104.066626 -285.787619) (xy 104.04312 -285.833751) (xy 104.012688 -285.875638)
			(xy 103.976078 -285.912248) (xy 103.934191 -285.94268) (xy 103.888059 -285.966186) (xy 103.838819 -285.982185)
			(xy 103.787681 -285.990284) (xy 103.735907 -285.990284) (xy 103.684769 -285.982185) (xy 103.635529 -285.966186)
			(xy 103.589397 -285.94268) (xy 103.54751 -285.912248) (xy 103.5109 -285.875638) (xy 103.480468 -285.833751)
			(xy 103.456962 -285.787619) (xy 103.440963 -285.738379) (xy 103.432864 -285.687241) (xy 103.432356 -285.661354)
			(xy 103.151432 -285.661354) (xy 103.151432 -285.661862) (xy 103.150853 -285.689379) (xy 103.141659 -285.74364)
			(xy 103.133144 -285.769812) (xy 103.125524 -285.79191) (xy 103.330756 -286.147256) (xy 103.353616 -286.151574)
			(xy 103.378427 -286.156786) (xy 103.426204 -286.173734) (xy 103.470823 -286.197799) (xy 103.51123 -286.228413)
			(xy 103.546472 -286.264855) (xy 103.575717 -286.306263) (xy 103.598276 -286.351662) (xy 103.613617 -286.399979)
			(xy 103.621377 -286.450077) (xy 103.62184 -286.475424) (xy 119.878856 -286.475424) (xy 119.879354 -286.450079)
			(xy 119.887123 -286.399987) (xy 119.902468 -286.351675) (xy 119.925026 -286.306281) (xy 119.954266 -286.264873)
			(xy 119.989499 -286.228429) (xy 120.029894 -286.197807) (xy 120.0745 -286.173728) (xy 120.122266 -286.156759)
			(xy 120.14708 -286.151574) (xy 120.16994 -286.147256) (xy 120.374918 -285.792164) (xy 120.367044 -285.77032)
			(xy 120.358471 -285.743899) (xy 120.34927 -285.689126) (xy 120.348756 -285.661354) (xy 120.349264 -285.635467)
			(xy 120.357363 -285.584329) (xy 120.373362 -285.535089) (xy 120.396868 -285.488957) (xy 120.4273 -285.44707)
			(xy 120.46391 -285.41046) (xy 120.505797 -285.380028) (xy 120.551929 -285.356522) (xy 120.601169 -285.340523)
			(xy 120.652307 -285.332424) (xy 120.704081 -285.332424) (xy 120.755219 -285.340523) (xy 120.804459 -285.356522)
			(xy 120.850591 -285.380028) (xy 120.892478 -285.41046) (xy 120.929088 -285.44707) (xy 120.95952 -285.488957)
			(xy 120.983026 -285.535089) (xy 120.999025 -285.584329) (xy 121.007124 -285.635467) (xy 121.007632 -285.661354)
			(xy 121.007172 -285.686689) (xy 120.999413 -285.736761) (xy 120.984085 -285.785057) (xy 120.961549 -285.830439)
			(xy 120.932336 -285.87184) (xy 120.897134 -285.908285) (xy 120.856771 -285.938915) (xy 120.812197 -285.963011)
			(xy 120.764462 -285.980004) (xy 120.739662 -285.985204) (xy 120.716802 -285.989522) (xy 120.511824 -286.344614)
			(xy 120.519698 -286.366458) (xy 120.528349 -286.392865) (xy 120.537666 -286.447642) (xy 120.53824 -286.475424)
			(xy 121.758456 -286.475424) (xy 121.758954 -286.450079) (xy 121.766723 -286.399987) (xy 121.782068 -286.351675)
			(xy 121.804626 -286.306281) (xy 121.833866 -286.264873) (xy 121.869099 -286.228429) (xy 121.909494 -286.197807)
			(xy 121.9541 -286.173728) (xy 122.001866 -286.156759) (xy 122.02668 -286.151574) (xy 122.04954 -286.147256)
			(xy 122.254518 -285.792164) (xy 122.246644 -285.77032) (xy 122.238071 -285.743899) (xy 122.22887 -285.689126)
			(xy 122.228356 -285.661354) (xy 122.228864 -285.635467) (xy 122.236963 -285.584329) (xy 122.252962 -285.535089)
			(xy 122.276468 -285.488957) (xy 122.3069 -285.44707) (xy 122.34351 -285.41046) (xy 122.385397 -285.380028)
			(xy 122.431529 -285.356522) (xy 122.480769 -285.340523) (xy 122.531907 -285.332424) (xy 122.583681 -285.332424)
			(xy 122.634819 -285.340523) (xy 122.684059 -285.356522) (xy 122.730191 -285.380028) (xy 122.772078 -285.41046)
			(xy 122.808688 -285.44707) (xy 122.83912 -285.488957) (xy 122.862626 -285.535089) (xy 122.878625 -285.584329)
			(xy 122.886724 -285.635467) (xy 122.887232 -285.661354) (xy 122.886772 -285.686689) (xy 122.879013 -285.736761)
			(xy 122.863685 -285.785057) (xy 122.841149 -285.830439) (xy 122.811936 -285.87184) (xy 122.776734 -285.908285)
			(xy 122.736371 -285.938915) (xy 122.691797 -285.963011) (xy 122.644062 -285.980004) (xy 122.619262 -285.985204)
			(xy 122.596402 -285.989522) (xy 122.391424 -286.344614) (xy 122.399298 -286.366458) (xy 122.407949 -286.392865)
			(xy 122.417266 -286.447642) (xy 122.41784 -286.475424) (xy 123.638056 -286.475424) (xy 123.638554 -286.450079)
			(xy 123.646323 -286.399987) (xy 123.661668 -286.351675) (xy 123.684226 -286.306281) (xy 123.713466 -286.264873)
			(xy 123.748699 -286.228429) (xy 123.789094 -286.197807) (xy 123.8337 -286.173728) (xy 123.881466 -286.156759)
			(xy 123.90628 -286.151574) (xy 123.92914 -286.147256) (xy 124.134118 -285.792164) (xy 124.126244 -285.77032)
			(xy 124.117671 -285.743899) (xy 124.10847 -285.689126) (xy 124.107956 -285.661354) (xy 124.108464 -285.635467)
			(xy 124.116563 -285.584329) (xy 124.132562 -285.535089) (xy 124.156068 -285.488957) (xy 124.1865 -285.44707)
			(xy 124.22311 -285.41046) (xy 124.264997 -285.380028) (xy 124.311129 -285.356522) (xy 124.360369 -285.340523)
			(xy 124.411507 -285.332424) (xy 124.463281 -285.332424) (xy 124.514419 -285.340523) (xy 124.563659 -285.356522)
			(xy 124.609791 -285.380028) (xy 124.651678 -285.41046) (xy 124.688288 -285.44707) (xy 124.71872 -285.488957)
			(xy 124.742226 -285.535089) (xy 124.758225 -285.584329) (xy 124.766324 -285.635467) (xy 124.766832 -285.661354)
			(xy 124.766372 -285.686689) (xy 124.758613 -285.736761) (xy 124.743285 -285.785057) (xy 124.720749 -285.830439)
			(xy 124.691536 -285.87184) (xy 124.656334 -285.908285) (xy 124.615971 -285.938915) (xy 124.571397 -285.963011)
			(xy 124.523662 -285.980004) (xy 124.498862 -285.985204) (xy 124.476002 -285.989522) (xy 124.271024 -286.344614)
			(xy 124.278898 -286.366458) (xy 124.287549 -286.392865) (xy 124.296866 -286.447642) (xy 124.29744 -286.475424)
			(xy 125.517656 -286.475424) (xy 125.518154 -286.450079) (xy 125.525923 -286.399987) (xy 125.541268 -286.351675)
			(xy 125.563826 -286.306281) (xy 125.593066 -286.264873) (xy 125.628299 -286.228429) (xy 125.668694 -286.197807)
			(xy 125.7133 -286.173728) (xy 125.761066 -286.156759) (xy 125.78588 -286.151574) (xy 125.80874 -286.147256)
			(xy 126.013718 -285.792164) (xy 126.005844 -285.77032) (xy 125.997271 -285.743899) (xy 125.98807 -285.689126)
			(xy 125.987556 -285.661354) (xy 125.988064 -285.635467) (xy 125.996163 -285.584329) (xy 126.012162 -285.535089)
			(xy 126.035668 -285.488957) (xy 126.0661 -285.44707) (xy 126.10271 -285.41046) (xy 126.144597 -285.380028)
			(xy 126.190729 -285.356522) (xy 126.239969 -285.340523) (xy 126.291107 -285.332424) (xy 126.342881 -285.332424)
			(xy 126.394019 -285.340523) (xy 126.443259 -285.356522) (xy 126.489391 -285.380028) (xy 126.531278 -285.41046)
			(xy 126.567888 -285.44707) (xy 126.59832 -285.488957) (xy 126.621826 -285.535089) (xy 126.637825 -285.584329)
			(xy 126.645924 -285.635467) (xy 126.646432 -285.661354) (xy 126.645972 -285.686689) (xy 126.638213 -285.736761)
			(xy 126.622885 -285.785057) (xy 126.600349 -285.830439) (xy 126.571136 -285.87184) (xy 126.535934 -285.908285)
			(xy 126.495571 -285.938915) (xy 126.450997 -285.963011) (xy 126.403262 -285.980004) (xy 126.378462 -285.985204)
			(xy 126.355602 -285.989522) (xy 126.150624 -286.344614) (xy 126.158498 -286.366458) (xy 126.167149 -286.392865)
			(xy 126.176466 -286.447642) (xy 126.17704 -286.475424) (xy 127.397256 -286.475424) (xy 127.397754 -286.450079)
			(xy 127.405523 -286.399987) (xy 127.420868 -286.351675) (xy 127.443426 -286.306281) (xy 127.472666 -286.264873)
			(xy 127.507899 -286.228429) (xy 127.548294 -286.197807) (xy 127.5929 -286.173728) (xy 127.640666 -286.156759)
			(xy 127.66548 -286.151574) (xy 127.68834 -286.147256) (xy 127.893318 -285.792164) (xy 127.885444 -285.77032)
			(xy 127.876871 -285.743899) (xy 127.86767 -285.689126) (xy 127.867156 -285.661354) (xy 127.867664 -285.635467)
			(xy 127.875763 -285.584329) (xy 127.891762 -285.535089) (xy 127.915268 -285.488957) (xy 127.9457 -285.44707)
			(xy 127.98231 -285.41046) (xy 128.024197 -285.380028) (xy 128.070329 -285.356522) (xy 128.119569 -285.340523)
			(xy 128.170707 -285.332424) (xy 128.222481 -285.332424) (xy 128.273619 -285.340523) (xy 128.322859 -285.356522)
			(xy 128.368991 -285.380028) (xy 128.410878 -285.41046) (xy 128.447488 -285.44707) (xy 128.47792 -285.488957)
			(xy 128.501426 -285.535089) (xy 128.517425 -285.584329) (xy 128.525524 -285.635467) (xy 128.526032 -285.661354)
			(xy 128.525572 -285.686689) (xy 128.517813 -285.736761) (xy 128.502485 -285.785057) (xy 128.479949 -285.830439)
			(xy 128.450736 -285.87184) (xy 128.415534 -285.908285) (xy 128.375171 -285.938915) (xy 128.330597 -285.963011)
			(xy 128.282862 -285.980004) (xy 128.258062 -285.985204) (xy 128.235202 -285.989522) (xy 128.030224 -286.344614)
			(xy 128.038098 -286.366458) (xy 128.046749 -286.392865) (xy 128.056066 -286.447642) (xy 128.05664 -286.475424)
			(xy 129.276856 -286.475424) (xy 129.277354 -286.450079) (xy 129.285123 -286.399987) (xy 129.300468 -286.351675)
			(xy 129.323026 -286.306281) (xy 129.352266 -286.264873) (xy 129.387499 -286.228429) (xy 129.427894 -286.197807)
			(xy 129.4725 -286.173728) (xy 129.520266 -286.156759) (xy 129.54508 -286.151574) (xy 129.56794 -286.147256)
			(xy 129.772918 -285.792164) (xy 129.765044 -285.77032) (xy 129.756471 -285.743899) (xy 129.74727 -285.689126)
			(xy 129.746756 -285.661354) (xy 129.747264 -285.635467) (xy 129.755363 -285.584329) (xy 129.771362 -285.535089)
			(xy 129.794868 -285.488957) (xy 129.8253 -285.44707) (xy 129.86191 -285.41046) (xy 129.903797 -285.380028)
			(xy 129.949929 -285.356522) (xy 129.999169 -285.340523) (xy 130.050307 -285.332424) (xy 130.102081 -285.332424)
			(xy 130.153219 -285.340523) (xy 130.202459 -285.356522) (xy 130.248591 -285.380028) (xy 130.290478 -285.41046)
			(xy 130.327088 -285.44707) (xy 130.35752 -285.488957) (xy 130.381026 -285.535089) (xy 130.397025 -285.584329)
			(xy 130.405124 -285.635467) (xy 130.405632 -285.661354) (xy 130.405172 -285.686689) (xy 130.397413 -285.736761)
			(xy 130.382085 -285.785057) (xy 130.359549 -285.830439) (xy 130.330336 -285.87184) (xy 130.295134 -285.908285)
			(xy 130.254771 -285.938915) (xy 130.210197 -285.963011) (xy 130.162462 -285.980004) (xy 130.137662 -285.985204)
			(xy 130.114802 -285.989522) (xy 129.909824 -286.344614) (xy 129.917698 -286.366458) (xy 129.926349 -286.392865)
			(xy 129.935666 -286.447642) (xy 129.93624 -286.475424) (xy 131.156456 -286.475424) (xy 131.156954 -286.450079)
			(xy 131.164723 -286.399987) (xy 131.180068 -286.351675) (xy 131.202626 -286.306281) (xy 131.231866 -286.264873)
			(xy 131.267099 -286.228429) (xy 131.307494 -286.197807) (xy 131.3521 -286.173728) (xy 131.399866 -286.156759)
			(xy 131.42468 -286.151574) (xy 131.44754 -286.147256) (xy 131.652518 -285.792164) (xy 131.644644 -285.77032)
			(xy 131.636071 -285.743899) (xy 131.62687 -285.689126) (xy 131.626356 -285.661354) (xy 131.626864 -285.635467)
			(xy 131.634963 -285.584329) (xy 131.650962 -285.535089) (xy 131.674468 -285.488957) (xy 131.7049 -285.44707)
			(xy 131.74151 -285.41046) (xy 131.783397 -285.380028) (xy 131.829529 -285.356522) (xy 131.878769 -285.340523)
			(xy 131.929907 -285.332424) (xy 131.981681 -285.332424) (xy 132.032819 -285.340523) (xy 132.082059 -285.356522)
			(xy 132.128191 -285.380028) (xy 132.170078 -285.41046) (xy 132.206688 -285.44707) (xy 132.23712 -285.488957)
			(xy 132.260626 -285.535089) (xy 132.276625 -285.584329) (xy 132.284724 -285.635467) (xy 132.285232 -285.661354)
			(xy 132.284772 -285.686689) (xy 132.277013 -285.736761) (xy 132.261685 -285.785057) (xy 132.239149 -285.830439)
			(xy 132.209936 -285.87184) (xy 132.174734 -285.908285) (xy 132.134371 -285.938915) (xy 132.089797 -285.963011)
			(xy 132.042062 -285.980004) (xy 132.017262 -285.985204) (xy 131.994402 -285.989522) (xy 131.789424 -286.344614)
			(xy 131.797298 -286.366458) (xy 131.805949 -286.392865) (xy 131.815266 -286.447642) (xy 131.81584 -286.475424)
			(xy 133.036056 -286.475424) (xy 133.036554 -286.450079) (xy 133.044323 -286.399987) (xy 133.059668 -286.351675)
			(xy 133.082226 -286.306281) (xy 133.111466 -286.264873) (xy 133.146699 -286.228429) (xy 133.187094 -286.197807)
			(xy 133.2317 -286.173728) (xy 133.279466 -286.156759) (xy 133.30428 -286.151574) (xy 133.32714 -286.147256)
			(xy 133.532118 -285.792164) (xy 133.524244 -285.77032) (xy 133.515671 -285.743899) (xy 133.50647 -285.689126)
			(xy 133.505956 -285.661354) (xy 133.506464 -285.635467) (xy 133.514563 -285.584329) (xy 133.530562 -285.535089)
			(xy 133.554068 -285.488957) (xy 133.5845 -285.44707) (xy 133.62111 -285.41046) (xy 133.662997 -285.380028)
			(xy 133.709129 -285.356522) (xy 133.758369 -285.340523) (xy 133.809507 -285.332424) (xy 133.861281 -285.332424)
			(xy 133.912419 -285.340523) (xy 133.961659 -285.356522) (xy 134.007791 -285.380028) (xy 134.049678 -285.41046)
			(xy 134.086288 -285.44707) (xy 134.11672 -285.488957) (xy 134.140226 -285.535089) (xy 134.156225 -285.584329)
			(xy 134.164324 -285.635467) (xy 134.164832 -285.661354) (xy 337.275424 -285.661354) (xy 337.275932 -285.635467)
			(xy 337.284031 -285.584329) (xy 337.30003 -285.535089) (xy 337.323536 -285.488957) (xy 337.353968 -285.44707)
			(xy 337.390578 -285.41046) (xy 337.432465 -285.380028) (xy 337.478597 -285.356522) (xy 337.527837 -285.340523)
			(xy 337.578975 -285.332424) (xy 337.630749 -285.332424) (xy 337.681887 -285.340523) (xy 337.731127 -285.356522)
			(xy 337.777259 -285.380028) (xy 337.819146 -285.41046) (xy 337.855756 -285.44707) (xy 337.886188 -285.488957)
			(xy 337.909694 -285.535089) (xy 337.925693 -285.584329) (xy 337.933792 -285.635467) (xy 337.9343 -285.661354)
			(xy 338.215224 -285.661354) (xy 338.215684 -285.636008) (xy 338.223463 -285.585916) (xy 338.238816 -285.537605)
			(xy 338.26138 -285.492212) (xy 338.290625 -285.450806) (xy 338.325861 -285.414363) (xy 338.366259 -285.383741)
			(xy 338.410867 -285.359661) (xy 338.458634 -285.34269) (xy 338.483448 -285.337504) (xy 338.506308 -285.333186)
			(xy 338.711286 -284.978348) (xy 338.703412 -284.956504) (xy 338.694834 -284.930085) (xy 338.685636 -284.87531)
			(xy 338.685124 -284.847538) (xy 338.685632 -284.821651) (xy 338.693731 -284.770513) (xy 338.70973 -284.721273)
			(xy 338.733236 -284.675141) (xy 338.763668 -284.633254) (xy 338.800278 -284.596644) (xy 338.842165 -284.566212)
			(xy 338.888297 -284.542706) (xy 338.937537 -284.526707) (xy 338.988675 -284.518608) (xy 339.040449 -284.518608)
			(xy 339.091587 -284.526707) (xy 339.140827 -284.542706) (xy 339.186959 -284.566212) (xy 339.228846 -284.596644)
			(xy 339.265456 -284.633254) (xy 339.295888 -284.675141) (xy 339.319394 -284.721273) (xy 339.335393 -284.770513)
			(xy 339.343492 -284.821651) (xy 339.344 -284.847538) (xy 339.343552 -284.872874) (xy 339.335794 -284.922948)
			(xy 339.320466 -284.971245) (xy 339.29793 -285.016629) (xy 339.268716 -285.058031) (xy 339.233511 -285.094476)
			(xy 339.193146 -285.125106) (xy 339.148569 -285.149199) (xy 339.100831 -285.16619) (xy 339.07603 -285.171388)
			(xy 339.05317 -285.175706) (xy 338.848192 -285.530544) (xy 338.856066 -285.552642) (xy 338.86469 -285.578991)
			(xy 338.874015 -285.633637) (xy 338.874608 -285.661354) (xy 339.155024 -285.661354) (xy 339.155532 -285.635447)
			(xy 339.163638 -285.58427) (xy 339.17965 -285.534991) (xy 339.203173 -285.488824) (xy 339.233629 -285.446905)
			(xy 339.270267 -285.410267) (xy 339.312186 -285.379811) (xy 339.358353 -285.356288) (xy 339.407632 -285.340276)
			(xy 339.458809 -285.33217) (xy 339.510623 -285.33217) (xy 339.5618 -285.340276) (xy 339.611079 -285.356288)
			(xy 339.657246 -285.379811) (xy 339.699165 -285.410267) (xy 339.735803 -285.446905) (xy 339.766259 -285.488824)
			(xy 339.789782 -285.534991) (xy 339.805794 -285.58427) (xy 339.8139 -285.635447) (xy 339.814408 -285.661354)
			(xy 340.094824 -285.661354) (xy 340.095245 -285.636017) (xy 340.103005 -285.585941) (xy 340.118335 -285.537642)
			(xy 340.140875 -285.492257) (xy 340.170092 -285.450854) (xy 340.2053 -285.41441) (xy 340.24567 -285.383781)
			(xy 340.29025 -285.359689) (xy 340.337992 -285.342701) (xy 340.362794 -285.337504) (xy 340.385654 -285.333186)
			(xy 340.590886 -284.97784) (xy 340.583266 -284.955996) (xy 340.574644 -284.929713) (xy 340.565327 -284.875193)
			(xy 340.564724 -284.847538) (xy 340.565232 -284.821631) (xy 340.573338 -284.770454) (xy 340.58935 -284.721175)
			(xy 340.612873 -284.675008) (xy 340.643329 -284.633089) (xy 340.679967 -284.596451) (xy 340.721886 -284.565995)
			(xy 340.768053 -284.542472) (xy 340.817332 -284.52646) (xy 340.868509 -284.518354) (xy 340.920323 -284.518354)
			(xy 340.9715 -284.52646) (xy 341.020779 -284.542472) (xy 341.066946 -284.565995) (xy 341.108865 -284.596451)
			(xy 341.145503 -284.633089) (xy 341.175959 -284.675008) (xy 341.199482 -284.721175) (xy 341.215494 -284.770454)
			(xy 341.2236 -284.821631) (xy 341.224108 -284.847538) (xy 341.223661 -284.872913) (xy 341.215887 -284.923064)
			(xy 341.200514 -284.97143) (xy 341.177905 -285.016866) (xy 341.148596 -285.058297) (xy 341.113279 -285.094742)
			(xy 341.072791 -285.125341) (xy 341.028089 -285.149367) (xy 340.980231 -285.166254) (xy 340.955376 -285.171388)
			(xy 340.932516 -285.175706) (xy 340.727538 -285.530544) (xy 340.735412 -285.552642) (xy 340.743983 -285.578997)
			(xy 340.753175 -285.633645) (xy 340.7537 -285.661354) (xy 341.034624 -285.661354) (xy 341.035132 -285.635467)
			(xy 341.043231 -285.584329) (xy 341.05923 -285.535089) (xy 341.082736 -285.488957) (xy 341.113168 -285.44707)
			(xy 341.149778 -285.41046) (xy 341.191665 -285.380028) (xy 341.237797 -285.356522) (xy 341.287037 -285.340523)
			(xy 341.338175 -285.332424) (xy 341.389949 -285.332424) (xy 341.441087 -285.340523) (xy 341.490327 -285.356522)
			(xy 341.536459 -285.380028) (xy 341.578346 -285.41046) (xy 341.614956 -285.44707) (xy 341.645388 -285.488957)
			(xy 341.668894 -285.535089) (xy 341.684893 -285.584329) (xy 341.692992 -285.635467) (xy 341.6935 -285.661354)
			(xy 341.974424 -285.661354) (xy 341.974845 -285.636017) (xy 341.982605 -285.585941) (xy 341.997935 -285.537642)
			(xy 342.020475 -285.492257) (xy 342.049692 -285.450854) (xy 342.0849 -285.41441) (xy 342.12527 -285.383781)
			(xy 342.16985 -285.359689) (xy 342.217592 -285.342701) (xy 342.242394 -285.337504) (xy 342.265254 -285.333186)
			(xy 342.470486 -284.97784) (xy 342.462866 -284.955996) (xy 342.454244 -284.929713) (xy 342.444927 -284.875193)
			(xy 342.444324 -284.847538) (xy 342.444832 -284.821631) (xy 342.452938 -284.770454) (xy 342.46895 -284.721175)
			(xy 342.492473 -284.675008) (xy 342.522929 -284.633089) (xy 342.559567 -284.596451) (xy 342.601486 -284.565995)
			(xy 342.647653 -284.542472) (xy 342.696932 -284.52646) (xy 342.748109 -284.518354) (xy 342.799923 -284.518354)
			(xy 342.8511 -284.52646) (xy 342.900379 -284.542472) (xy 342.946546 -284.565995) (xy 342.988465 -284.596451)
			(xy 343.025103 -284.633089) (xy 343.055559 -284.675008) (xy 343.079082 -284.721175) (xy 343.095094 -284.770454)
			(xy 343.1032 -284.821631) (xy 343.103708 -284.847538) (xy 343.103261 -284.872913) (xy 343.095487 -284.923064)
			(xy 343.080114 -284.97143) (xy 343.057505 -285.016866) (xy 343.028196 -285.058297) (xy 342.992879 -285.094742)
			(xy 342.952391 -285.125341) (xy 342.907689 -285.149367) (xy 342.859831 -285.166254) (xy 342.834976 -285.171388)
			(xy 342.812116 -285.175706) (xy 342.607138 -285.530544) (xy 342.615012 -285.552642) (xy 342.623583 -285.578997)
			(xy 342.632775 -285.633645) (xy 342.6333 -285.661354) (xy 342.914224 -285.661354) (xy 342.914732 -285.635467)
			(xy 342.922831 -285.584329) (xy 342.93883 -285.535089) (xy 342.962336 -285.488957) (xy 342.992768 -285.44707)
			(xy 343.029378 -285.41046) (xy 343.071265 -285.380028) (xy 343.117397 -285.356522) (xy 343.166637 -285.340523)
			(xy 343.217775 -285.332424) (xy 343.269549 -285.332424) (xy 343.320687 -285.340523) (xy 343.369927 -285.356522)
			(xy 343.416059 -285.380028) (xy 343.457946 -285.41046) (xy 343.494556 -285.44707) (xy 343.524988 -285.488957)
			(xy 343.548494 -285.535089) (xy 343.564493 -285.584329) (xy 343.572592 -285.635467) (xy 343.5731 -285.661354)
			(xy 343.854024 -285.661354) (xy 343.854445 -285.636017) (xy 343.862205 -285.585941) (xy 343.877535 -285.537642)
			(xy 343.900075 -285.492257) (xy 343.929292 -285.450854) (xy 343.9645 -285.41441) (xy 344.00487 -285.383781)
			(xy 344.04945 -285.359689) (xy 344.097192 -285.342701) (xy 344.121994 -285.337504) (xy 344.144854 -285.333186)
			(xy 344.350086 -284.97784) (xy 344.342466 -284.955996) (xy 344.333844 -284.929713) (xy 344.324527 -284.875193)
			(xy 344.323924 -284.847538) (xy 344.324432 -284.821631) (xy 344.332538 -284.770454) (xy 344.34855 -284.721175)
			(xy 344.372073 -284.675008) (xy 344.402529 -284.633089) (xy 344.439167 -284.596451) (xy 344.481086 -284.565995)
			(xy 344.527253 -284.542472) (xy 344.576532 -284.52646) (xy 344.627709 -284.518354) (xy 344.679523 -284.518354)
			(xy 344.7307 -284.52646) (xy 344.779979 -284.542472) (xy 344.826146 -284.565995) (xy 344.868065 -284.596451)
			(xy 344.904703 -284.633089) (xy 344.935159 -284.675008) (xy 344.958682 -284.721175) (xy 344.974694 -284.770454)
			(xy 344.9828 -284.821631) (xy 344.983308 -284.847538) (xy 344.982861 -284.872913) (xy 344.975087 -284.923064)
			(xy 344.959714 -284.97143) (xy 344.937105 -285.016866) (xy 344.907796 -285.058297) (xy 344.872479 -285.094742)
			(xy 344.831991 -285.125341) (xy 344.787289 -285.149367) (xy 344.739431 -285.166254) (xy 344.714576 -285.171388)
			(xy 344.691716 -285.175706) (xy 344.486738 -285.530544) (xy 344.494612 -285.552642) (xy 344.503183 -285.578997)
			(xy 344.512375 -285.633645) (xy 344.5129 -285.661354) (xy 344.793824 -285.661354) (xy 344.794332 -285.635467)
			(xy 344.802431 -285.584329) (xy 344.81843 -285.535089) (xy 344.841936 -285.488957) (xy 344.872368 -285.44707)
			(xy 344.908978 -285.41046) (xy 344.950865 -285.380028) (xy 344.996997 -285.356522) (xy 345.046237 -285.340523)
			(xy 345.097375 -285.332424) (xy 345.149149 -285.332424) (xy 345.200287 -285.340523) (xy 345.249527 -285.356522)
			(xy 345.295659 -285.380028) (xy 345.337546 -285.41046) (xy 345.374156 -285.44707) (xy 345.404588 -285.488957)
			(xy 345.428094 -285.535089) (xy 345.444093 -285.584329) (xy 345.452192 -285.635467) (xy 345.4527 -285.661354)
			(xy 345.733624 -285.661354) (xy 345.734045 -285.636017) (xy 345.741805 -285.585941) (xy 345.757135 -285.537642)
			(xy 345.779675 -285.492257) (xy 345.808892 -285.450854) (xy 345.8441 -285.41441) (xy 345.88447 -285.383781)
			(xy 345.92905 -285.359689) (xy 345.976792 -285.342701) (xy 346.001594 -285.337504) (xy 346.024454 -285.333186)
			(xy 346.229686 -284.97784) (xy 346.222066 -284.955996) (xy 346.213444 -284.929713) (xy 346.204127 -284.875193)
			(xy 346.203524 -284.847538) (xy 346.204032 -284.821631) (xy 346.212138 -284.770454) (xy 346.22815 -284.721175)
			(xy 346.251673 -284.675008) (xy 346.282129 -284.633089) (xy 346.318767 -284.596451) (xy 346.360686 -284.565995)
			(xy 346.406853 -284.542472) (xy 346.456132 -284.52646) (xy 346.507309 -284.518354) (xy 346.559123 -284.518354)
			(xy 346.6103 -284.52646) (xy 346.659579 -284.542472) (xy 346.705746 -284.565995) (xy 346.747665 -284.596451)
			(xy 346.784303 -284.633089) (xy 346.814759 -284.675008) (xy 346.838282 -284.721175) (xy 346.854294 -284.770454)
			(xy 346.8624 -284.821631) (xy 346.862908 -284.847538) (xy 346.862461 -284.872913) (xy 346.854687 -284.923064)
			(xy 346.839314 -284.97143) (xy 346.816705 -285.016866) (xy 346.787396 -285.058297) (xy 346.752079 -285.094742)
			(xy 346.711591 -285.125341) (xy 346.666889 -285.149367) (xy 346.619031 -285.166254) (xy 346.594176 -285.171388)
			(xy 346.571316 -285.175706) (xy 346.366338 -285.530544) (xy 346.374212 -285.552642) (xy 346.382783 -285.578997)
			(xy 346.391975 -285.633645) (xy 346.3925 -285.661354) (xy 346.673424 -285.661354) (xy 346.673932 -285.635467)
			(xy 346.682031 -285.584329) (xy 346.69803 -285.535089) (xy 346.721536 -285.488957) (xy 346.751968 -285.44707)
			(xy 346.788578 -285.41046) (xy 346.830465 -285.380028) (xy 346.876597 -285.356522) (xy 346.925837 -285.340523)
			(xy 346.976975 -285.332424) (xy 347.028749 -285.332424) (xy 347.079887 -285.340523) (xy 347.129127 -285.356522)
			(xy 347.175259 -285.380028) (xy 347.217146 -285.41046) (xy 347.253756 -285.44707) (xy 347.284188 -285.488957)
			(xy 347.307694 -285.535089) (xy 347.323693 -285.584329) (xy 347.331792 -285.635467) (xy 347.3323 -285.661354)
			(xy 347.613224 -285.661354) (xy 347.613645 -285.636017) (xy 347.621405 -285.585941) (xy 347.636735 -285.537642)
			(xy 347.659275 -285.492257) (xy 347.688492 -285.450854) (xy 347.7237 -285.41441) (xy 347.76407 -285.383781)
			(xy 347.80865 -285.359689) (xy 347.856392 -285.342701) (xy 347.881194 -285.337504) (xy 347.904054 -285.333186)
			(xy 348.109286 -284.97784) (xy 348.101666 -284.955996) (xy 348.093044 -284.929713) (xy 348.083727 -284.875193)
			(xy 348.083124 -284.847538) (xy 348.083632 -284.821631) (xy 348.091738 -284.770454) (xy 348.10775 -284.721175)
			(xy 348.131273 -284.675008) (xy 348.161729 -284.633089) (xy 348.198367 -284.596451) (xy 348.240286 -284.565995)
			(xy 348.286453 -284.542472) (xy 348.335732 -284.52646) (xy 348.386909 -284.518354) (xy 348.438723 -284.518354)
			(xy 348.4899 -284.52646) (xy 348.539179 -284.542472) (xy 348.585346 -284.565995) (xy 348.627265 -284.596451)
			(xy 348.663903 -284.633089) (xy 348.694359 -284.675008) (xy 348.717882 -284.721175) (xy 348.733894 -284.770454)
			(xy 348.742 -284.821631) (xy 348.742508 -284.847538) (xy 348.742061 -284.872913) (xy 348.734287 -284.923064)
			(xy 348.718914 -284.97143) (xy 348.696305 -285.016866) (xy 348.666996 -285.058297) (xy 348.631679 -285.094742)
			(xy 348.591191 -285.125341) (xy 348.546489 -285.149367) (xy 348.498631 -285.166254) (xy 348.473776 -285.171388)
			(xy 348.450916 -285.175706) (xy 348.245938 -285.530544) (xy 348.253812 -285.552642) (xy 348.262383 -285.578997)
			(xy 348.271575 -285.633645) (xy 348.2721 -285.661354) (xy 348.553024 -285.661354) (xy 348.553532 -285.635467)
			(xy 348.561631 -285.584329) (xy 348.57763 -285.535089) (xy 348.601136 -285.488957) (xy 348.631568 -285.44707)
			(xy 348.668178 -285.41046) (xy 348.710065 -285.380028) (xy 348.756197 -285.356522) (xy 348.805437 -285.340523)
			(xy 348.856575 -285.332424) (xy 348.908349 -285.332424) (xy 348.959487 -285.340523) (xy 349.008727 -285.356522)
			(xy 349.054859 -285.380028) (xy 349.096746 -285.41046) (xy 349.133356 -285.44707) (xy 349.163788 -285.488957)
			(xy 349.187294 -285.535089) (xy 349.203293 -285.584329) (xy 349.211392 -285.635467) (xy 349.2119 -285.661354)
			(xy 349.492824 -285.661354) (xy 349.493245 -285.636017) (xy 349.501005 -285.585941) (xy 349.516335 -285.537642)
			(xy 349.538875 -285.492257) (xy 349.568092 -285.450854) (xy 349.6033 -285.41441) (xy 349.64367 -285.383781)
			(xy 349.68825 -285.359689) (xy 349.735992 -285.342701) (xy 349.760794 -285.337504) (xy 349.783654 -285.333186)
			(xy 349.988886 -284.97784) (xy 349.981266 -284.955996) (xy 349.972644 -284.929713) (xy 349.963327 -284.875193)
			(xy 349.962724 -284.847538) (xy 349.963232 -284.821631) (xy 349.971338 -284.770454) (xy 349.98735 -284.721175)
			(xy 350.010873 -284.675008) (xy 350.041329 -284.633089) (xy 350.077967 -284.596451) (xy 350.119886 -284.565995)
			(xy 350.166053 -284.542472) (xy 350.215332 -284.52646) (xy 350.266509 -284.518354) (xy 350.318323 -284.518354)
			(xy 350.3695 -284.52646) (xy 350.418779 -284.542472) (xy 350.464946 -284.565995) (xy 350.506865 -284.596451)
			(xy 350.543503 -284.633089) (xy 350.573959 -284.675008) (xy 350.597482 -284.721175) (xy 350.613494 -284.770454)
			(xy 350.6216 -284.821631) (xy 350.622108 -284.847538) (xy 350.621661 -284.872913) (xy 350.613887 -284.923064)
			(xy 350.598514 -284.97143) (xy 350.575905 -285.016866) (xy 350.546596 -285.058297) (xy 350.511279 -285.094742)
			(xy 350.470791 -285.125341) (xy 350.426089 -285.149367) (xy 350.378231 -285.166254) (xy 350.353376 -285.171388)
			(xy 350.330516 -285.175706) (xy 350.125538 -285.530544) (xy 350.133412 -285.552642) (xy 350.141983 -285.578997)
			(xy 350.151175 -285.633645) (xy 350.1517 -285.661354) (xy 350.432624 -285.661354) (xy 350.433132 -285.635467)
			(xy 350.441231 -285.584329) (xy 350.45723 -285.535089) (xy 350.480736 -285.488957) (xy 350.511168 -285.44707)
			(xy 350.547778 -285.41046) (xy 350.589665 -285.380028) (xy 350.635797 -285.356522) (xy 350.685037 -285.340523)
			(xy 350.736175 -285.332424) (xy 350.787949 -285.332424) (xy 350.839087 -285.340523) (xy 350.888327 -285.356522)
			(xy 350.934459 -285.380028) (xy 350.976346 -285.41046) (xy 351.012956 -285.44707) (xy 351.043388 -285.488957)
			(xy 351.066894 -285.535089) (xy 351.082893 -285.584329) (xy 351.090992 -285.635467) (xy 351.0915 -285.661354)
			(xy 351.372424 -285.661354) (xy 351.372845 -285.636017) (xy 351.380605 -285.585941) (xy 351.395935 -285.537642)
			(xy 351.418475 -285.492257) (xy 351.447692 -285.450854) (xy 351.4829 -285.41441) (xy 351.52327 -285.383781)
			(xy 351.56785 -285.359689) (xy 351.615592 -285.342701) (xy 351.640394 -285.337504) (xy 351.663254 -285.333186)
			(xy 351.868486 -284.97784) (xy 351.860866 -284.955996) (xy 351.852244 -284.929713) (xy 351.842927 -284.875193)
			(xy 351.842324 -284.847538) (xy 351.842832 -284.821631) (xy 351.850938 -284.770454) (xy 351.86695 -284.721175)
			(xy 351.890473 -284.675008) (xy 351.920929 -284.633089) (xy 351.957567 -284.596451) (xy 351.999486 -284.565995)
			(xy 352.045653 -284.542472) (xy 352.094932 -284.52646) (xy 352.146109 -284.518354) (xy 352.197923 -284.518354)
			(xy 352.2491 -284.52646) (xy 352.298379 -284.542472) (xy 352.344546 -284.565995) (xy 352.386465 -284.596451)
			(xy 352.423103 -284.633089) (xy 352.453559 -284.675008) (xy 352.477082 -284.721175) (xy 352.493094 -284.770454)
			(xy 352.5012 -284.821631) (xy 352.501708 -284.847538) (xy 366.879124 -284.847538) (xy 366.879632 -284.821631)
			(xy 366.887738 -284.770454) (xy 366.90375 -284.721175) (xy 366.927273 -284.675008) (xy 366.957729 -284.633089)
			(xy 366.994367 -284.596451) (xy 367.036286 -284.565995) (xy 367.082453 -284.542472) (xy 367.131732 -284.52646)
			(xy 367.182909 -284.518354) (xy 367.234723 -284.518354) (xy 367.2859 -284.52646) (xy 367.335179 -284.542472)
			(xy 367.381346 -284.565995) (xy 367.423265 -284.596451) (xy 367.459903 -284.633089) (xy 367.490359 -284.675008)
			(xy 367.513882 -284.721175) (xy 367.529894 -284.770454) (xy 367.538 -284.821631) (xy 367.538508 -284.847538)
			(xy 368.758724 -284.847538) (xy 368.759232 -284.821631) (xy 368.767338 -284.770454) (xy 368.78335 -284.721175)
			(xy 368.806873 -284.675008) (xy 368.837329 -284.633089) (xy 368.873967 -284.596451) (xy 368.915886 -284.565995)
			(xy 368.962053 -284.542472) (xy 369.011332 -284.52646) (xy 369.062509 -284.518354) (xy 369.114323 -284.518354)
			(xy 369.1655 -284.52646) (xy 369.214779 -284.542472) (xy 369.260946 -284.565995) (xy 369.302865 -284.596451)
			(xy 369.339503 -284.633089) (xy 369.369959 -284.675008) (xy 369.393482 -284.721175) (xy 369.409494 -284.770454)
			(xy 369.4176 -284.821631) (xy 369.418108 -284.847538) (xy 370.638324 -284.847538) (xy 370.638832 -284.821631)
			(xy 370.646938 -284.770454) (xy 370.66295 -284.721175) (xy 370.686473 -284.675008) (xy 370.716929 -284.633089)
			(xy 370.753567 -284.596451) (xy 370.795486 -284.565995) (xy 370.841653 -284.542472) (xy 370.890932 -284.52646)
			(xy 370.942109 -284.518354) (xy 370.993923 -284.518354) (xy 371.0451 -284.52646) (xy 371.094379 -284.542472)
			(xy 371.140546 -284.565995) (xy 371.182465 -284.596451) (xy 371.219103 -284.633089) (xy 371.249559 -284.675008)
			(xy 371.273082 -284.721175) (xy 371.289094 -284.770454) (xy 371.2972 -284.821631) (xy 371.297708 -284.847538)
			(xy 372.517924 -284.847538) (xy 372.518432 -284.821631) (xy 372.526538 -284.770454) (xy 372.54255 -284.721175)
			(xy 372.566073 -284.675008) (xy 372.596529 -284.633089) (xy 372.633167 -284.596451) (xy 372.675086 -284.565995)
			(xy 372.721253 -284.542472) (xy 372.770532 -284.52646) (xy 372.821709 -284.518354) (xy 372.873523 -284.518354)
			(xy 372.9247 -284.52646) (xy 372.973979 -284.542472) (xy 373.020146 -284.565995) (xy 373.062065 -284.596451)
			(xy 373.098703 -284.633089) (xy 373.129159 -284.675008) (xy 373.152682 -284.721175) (xy 373.168694 -284.770454)
			(xy 373.1768 -284.821631) (xy 373.177308 -284.847538) (xy 374.397524 -284.847538) (xy 374.398032 -284.821631)
			(xy 374.406138 -284.770454) (xy 374.42215 -284.721175) (xy 374.445673 -284.675008) (xy 374.476129 -284.633089)
			(xy 374.512767 -284.596451) (xy 374.554686 -284.565995) (xy 374.600853 -284.542472) (xy 374.650132 -284.52646)
			(xy 374.701309 -284.518354) (xy 374.753123 -284.518354) (xy 374.8043 -284.52646) (xy 374.853579 -284.542472)
			(xy 374.899746 -284.565995) (xy 374.941665 -284.596451) (xy 374.978303 -284.633089) (xy 375.008759 -284.675008)
			(xy 375.032282 -284.721175) (xy 375.048294 -284.770454) (xy 375.0564 -284.821631) (xy 375.056908 -284.847538)
			(xy 376.277124 -284.847538) (xy 376.277632 -284.821631) (xy 376.285738 -284.770454) (xy 376.30175 -284.721175)
			(xy 376.325273 -284.675008) (xy 376.355729 -284.633089) (xy 376.392367 -284.596451) (xy 376.434286 -284.565995)
			(xy 376.480453 -284.542472) (xy 376.529732 -284.52646) (xy 376.580909 -284.518354) (xy 376.632723 -284.518354)
			(xy 376.6839 -284.52646) (xy 376.733179 -284.542472) (xy 376.779346 -284.565995) (xy 376.821265 -284.596451)
			(xy 376.857903 -284.633089) (xy 376.888359 -284.675008) (xy 376.911882 -284.721175) (xy 376.927894 -284.770454)
			(xy 376.936 -284.821631) (xy 376.936508 -284.847538) (xy 378.156724 -284.847538) (xy 378.157232 -284.821631)
			(xy 378.165338 -284.770454) (xy 378.18135 -284.721175) (xy 378.204873 -284.675008) (xy 378.235329 -284.633089)
			(xy 378.271967 -284.596451) (xy 378.313886 -284.565995) (xy 378.360053 -284.542472) (xy 378.409332 -284.52646)
			(xy 378.460509 -284.518354) (xy 378.512323 -284.518354) (xy 378.5635 -284.52646) (xy 378.612779 -284.542472)
			(xy 378.658946 -284.565995) (xy 378.700865 -284.596451) (xy 378.737503 -284.633089) (xy 378.767959 -284.675008)
			(xy 378.791482 -284.721175) (xy 378.807494 -284.770454) (xy 378.8156 -284.821631) (xy 378.816108 -284.847538)
			(xy 380.036324 -284.847538) (xy 380.036832 -284.821631) (xy 380.044938 -284.770454) (xy 380.06095 -284.721175)
			(xy 380.084473 -284.675008) (xy 380.114929 -284.633089) (xy 380.151567 -284.596451) (xy 380.193486 -284.565995)
			(xy 380.239653 -284.542472) (xy 380.288932 -284.52646) (xy 380.340109 -284.518354) (xy 380.391923 -284.518354)
			(xy 380.4431 -284.52646) (xy 380.492379 -284.542472) (xy 380.538546 -284.565995) (xy 380.580465 -284.596451)
			(xy 380.617103 -284.633089) (xy 380.647559 -284.675008) (xy 380.671082 -284.721175) (xy 380.687094 -284.770454)
			(xy 380.6952 -284.821631) (xy 380.695708 -284.847538) (xy 380.695098 -284.875255) (xy 380.685785 -284.929901)
			(xy 380.677166 -284.95625) (xy 380.669292 -284.978348) (xy 380.87427 -285.333186) (xy 380.89713 -285.337504)
			(xy 380.921947 -285.342634) (xy 380.969689 -285.35963) (xy 381.014267 -285.383731) (xy 381.054634 -285.414369)
			(xy 381.089836 -285.450823) (xy 381.119046 -285.492235) (xy 381.141576 -285.537628) (xy 381.156894 -285.585934)
			(xy 381.16464 -285.636016) (xy 381.1651 -285.661354) (xy 381.164592 -285.687241) (xy 381.156493 -285.738379)
			(xy 381.140494 -285.787619) (xy 381.116988 -285.833751) (xy 381.086556 -285.875638) (xy 381.049946 -285.912248)
			(xy 381.008059 -285.94268) (xy 380.961927 -285.966186) (xy 380.912687 -285.982185) (xy 380.861549 -285.990284)
			(xy 380.809775 -285.990284) (xy 380.758637 -285.982185) (xy 380.709397 -285.966186) (xy 380.663265 -285.94268)
			(xy 380.621378 -285.912248) (xy 380.584768 -285.875638) (xy 380.554336 -285.833751) (xy 380.53083 -285.787619)
			(xy 380.514831 -285.738379) (xy 380.506732 -285.687241) (xy 380.506224 -285.661354) (xy 380.506766 -285.633646)
			(xy 380.515953 -285.579) (xy 380.524512 -285.552642) (xy 380.532386 -285.530544) (xy 380.327408 -285.175706)
			(xy 380.304548 -285.171388) (xy 380.279723 -285.166238) (xy 380.231943 -285.149282) (xy 380.187323 -285.125209)
			(xy 380.146916 -285.094586) (xy 380.111675 -285.058137) (xy 380.082431 -285.016721) (xy 380.059876 -284.971315)
			(xy 380.044539 -284.922991) (xy 380.036785 -284.872888) (xy 380.036324 -284.847538) (xy 378.816108 -284.847538)
			(xy 378.815498 -284.875255) (xy 378.806185 -284.929901) (xy 378.797566 -284.95625) (xy 378.789692 -284.978348)
			(xy 378.99467 -285.333186) (xy 379.01753 -285.337504) (xy 379.042347 -285.342634) (xy 379.090089 -285.35963)
			(xy 379.134667 -285.383731) (xy 379.175034 -285.414369) (xy 379.210236 -285.450823) (xy 379.239446 -285.492235)
			(xy 379.261976 -285.537628) (xy 379.277294 -285.585934) (xy 379.28504 -285.636016) (xy 379.2855 -285.661354)
			(xy 379.284992 -285.687241) (xy 379.276893 -285.738379) (xy 379.260894 -285.787619) (xy 379.237388 -285.833751)
			(xy 379.206956 -285.875638) (xy 379.170346 -285.912248) (xy 379.128459 -285.94268) (xy 379.082327 -285.966186)
			(xy 379.033087 -285.982185) (xy 378.981949 -285.990284) (xy 378.930175 -285.990284) (xy 378.879037 -285.982185)
			(xy 378.829797 -285.966186) (xy 378.783665 -285.94268) (xy 378.741778 -285.912248) (xy 378.705168 -285.875638)
			(xy 378.674736 -285.833751) (xy 378.65123 -285.787619) (xy 378.635231 -285.738379) (xy 378.627132 -285.687241)
			(xy 378.626624 -285.661354) (xy 378.627166 -285.633646) (xy 378.636353 -285.579) (xy 378.644912 -285.552642)
			(xy 378.652786 -285.530544) (xy 378.447808 -285.175706) (xy 378.424948 -285.171388) (xy 378.400123 -285.166238)
			(xy 378.352343 -285.149282) (xy 378.307723 -285.125209) (xy 378.267316 -285.094586) (xy 378.232075 -285.058137)
			(xy 378.202831 -285.016721) (xy 378.180276 -284.971315) (xy 378.164939 -284.922991) (xy 378.157185 -284.872888)
			(xy 378.156724 -284.847538) (xy 376.936508 -284.847538) (xy 376.935898 -284.875255) (xy 376.926585 -284.929901)
			(xy 376.917966 -284.95625) (xy 376.910092 -284.978348) (xy 377.11507 -285.333186) (xy 377.13793 -285.337504)
			(xy 377.162747 -285.342634) (xy 377.210489 -285.35963) (xy 377.255067 -285.383731) (xy 377.295434 -285.414369)
			(xy 377.330636 -285.450823) (xy 377.359846 -285.492235) (xy 377.382376 -285.537628) (xy 377.397694 -285.585934)
			(xy 377.40544 -285.636016) (xy 377.4059 -285.661354) (xy 377.405392 -285.687241) (xy 377.397293 -285.738379)
			(xy 377.381294 -285.787619) (xy 377.357788 -285.833751) (xy 377.327356 -285.875638) (xy 377.290746 -285.912248)
			(xy 377.248859 -285.94268) (xy 377.202727 -285.966186) (xy 377.153487 -285.982185) (xy 377.102349 -285.990284)
			(xy 377.050575 -285.990284) (xy 376.999437 -285.982185) (xy 376.950197 -285.966186) (xy 376.904065 -285.94268)
			(xy 376.862178 -285.912248) (xy 376.825568 -285.875638) (xy 376.795136 -285.833751) (xy 376.77163 -285.787619)
			(xy 376.755631 -285.738379) (xy 376.747532 -285.687241) (xy 376.747024 -285.661354) (xy 376.747566 -285.633646)
			(xy 376.756753 -285.579) (xy 376.765312 -285.552642) (xy 376.773186 -285.530544) (xy 376.568208 -285.175706)
			(xy 376.545348 -285.171388) (xy 376.520523 -285.166238) (xy 376.472743 -285.149282) (xy 376.428123 -285.125209)
			(xy 376.387716 -285.094586) (xy 376.352475 -285.058137) (xy 376.323231 -285.016721) (xy 376.300676 -284.971315)
			(xy 376.285339 -284.922991) (xy 376.277585 -284.872888) (xy 376.277124 -284.847538) (xy 375.056908 -284.847538)
			(xy 375.056298 -284.875255) (xy 375.046985 -284.929901) (xy 375.038366 -284.95625) (xy 375.030492 -284.978348)
			(xy 375.23547 -285.333186) (xy 375.25833 -285.337504) (xy 375.283147 -285.342634) (xy 375.330889 -285.35963)
			(xy 375.375467 -285.383731) (xy 375.415834 -285.414369) (xy 375.451036 -285.450823) (xy 375.480246 -285.492235)
			(xy 375.502776 -285.537628) (xy 375.518094 -285.585934) (xy 375.52584 -285.636016) (xy 375.5263 -285.661354)
			(xy 375.525792 -285.687241) (xy 375.517693 -285.738379) (xy 375.501694 -285.787619) (xy 375.478188 -285.833751)
			(xy 375.447756 -285.875638) (xy 375.411146 -285.912248) (xy 375.369259 -285.94268) (xy 375.323127 -285.966186)
			(xy 375.273887 -285.982185) (xy 375.222749 -285.990284) (xy 375.170975 -285.990284) (xy 375.119837 -285.982185)
			(xy 375.070597 -285.966186) (xy 375.024465 -285.94268) (xy 374.982578 -285.912248) (xy 374.945968 -285.875638)
			(xy 374.915536 -285.833751) (xy 374.89203 -285.787619) (xy 374.876031 -285.738379) (xy 374.867932 -285.687241)
			(xy 374.867424 -285.661354) (xy 374.867966 -285.633646) (xy 374.877153 -285.579) (xy 374.885712 -285.552642)
			(xy 374.893586 -285.530544) (xy 374.688608 -285.175706) (xy 374.665748 -285.171388) (xy 374.640923 -285.166238)
			(xy 374.593143 -285.149282) (xy 374.548523 -285.125209) (xy 374.508116 -285.094586) (xy 374.472875 -285.058137)
			(xy 374.443631 -285.016721) (xy 374.421076 -284.971315) (xy 374.405739 -284.922991) (xy 374.397985 -284.872888)
			(xy 374.397524 -284.847538) (xy 373.177308 -284.847538) (xy 373.176698 -284.875255) (xy 373.167385 -284.929901)
			(xy 373.158766 -284.95625) (xy 373.150892 -284.978348) (xy 373.35587 -285.333186) (xy 373.37873 -285.337504)
			(xy 373.403547 -285.342634) (xy 373.451289 -285.35963) (xy 373.495867 -285.383731) (xy 373.536234 -285.414369)
			(xy 373.571436 -285.450823) (xy 373.600646 -285.492235) (xy 373.623176 -285.537628) (xy 373.638494 -285.585934)
			(xy 373.64624 -285.636016) (xy 373.6467 -285.661354) (xy 373.646192 -285.687241) (xy 373.638093 -285.738379)
			(xy 373.622094 -285.787619) (xy 373.598588 -285.833751) (xy 373.568156 -285.875638) (xy 373.531546 -285.912248)
			(xy 373.489659 -285.94268) (xy 373.443527 -285.966186) (xy 373.394287 -285.982185) (xy 373.343149 -285.990284)
			(xy 373.291375 -285.990284) (xy 373.240237 -285.982185) (xy 373.190997 -285.966186) (xy 373.144865 -285.94268)
			(xy 373.102978 -285.912248) (xy 373.066368 -285.875638) (xy 373.035936 -285.833751) (xy 373.01243 -285.787619)
			(xy 372.996431 -285.738379) (xy 372.988332 -285.687241) (xy 372.987824 -285.661354) (xy 372.988366 -285.633646)
			(xy 372.997553 -285.579) (xy 373.006112 -285.552642) (xy 373.013986 -285.530544) (xy 372.809008 -285.175706)
			(xy 372.786148 -285.171388) (xy 372.761323 -285.166238) (xy 372.713543 -285.149282) (xy 372.668923 -285.125209)
			(xy 372.628516 -285.094586) (xy 372.593275 -285.058137) (xy 372.564031 -285.016721) (xy 372.541476 -284.971315)
			(xy 372.526139 -284.922991) (xy 372.518385 -284.872888) (xy 372.517924 -284.847538) (xy 371.297708 -284.847538)
			(xy 371.297098 -284.875255) (xy 371.287785 -284.929901) (xy 371.279166 -284.95625) (xy 371.271292 -284.978348)
			(xy 371.47627 -285.333186) (xy 371.49913 -285.337504) (xy 371.523947 -285.342634) (xy 371.571689 -285.35963)
			(xy 371.616267 -285.383731) (xy 371.656634 -285.414369) (xy 371.691836 -285.450823) (xy 371.721046 -285.492235)
			(xy 371.743576 -285.537628) (xy 371.758894 -285.585934) (xy 371.76664 -285.636016) (xy 371.7671 -285.661354)
			(xy 371.766592 -285.687241) (xy 371.758493 -285.738379) (xy 371.742494 -285.787619) (xy 371.718988 -285.833751)
			(xy 371.688556 -285.875638) (xy 371.651946 -285.912248) (xy 371.610059 -285.94268) (xy 371.563927 -285.966186)
			(xy 371.514687 -285.982185) (xy 371.463549 -285.990284) (xy 371.411775 -285.990284) (xy 371.360637 -285.982185)
			(xy 371.311397 -285.966186) (xy 371.265265 -285.94268) (xy 371.223378 -285.912248) (xy 371.186768 -285.875638)
			(xy 371.156336 -285.833751) (xy 371.13283 -285.787619) (xy 371.116831 -285.738379) (xy 371.108732 -285.687241)
			(xy 371.108224 -285.661354) (xy 371.108766 -285.633646) (xy 371.117953 -285.579) (xy 371.126512 -285.552642)
			(xy 371.134386 -285.530544) (xy 370.929408 -285.175706) (xy 370.906548 -285.171388) (xy 370.881723 -285.166238)
			(xy 370.833943 -285.149282) (xy 370.789323 -285.125209) (xy 370.748916 -285.094586) (xy 370.713675 -285.058137)
			(xy 370.684431 -285.016721) (xy 370.661876 -284.971315) (xy 370.646539 -284.922991) (xy 370.638785 -284.872888)
			(xy 370.638324 -284.847538) (xy 369.418108 -284.847538) (xy 369.417498 -284.875255) (xy 369.408185 -284.929901)
			(xy 369.399566 -284.95625) (xy 369.391692 -284.978348) (xy 369.59667 -285.333186) (xy 369.61953 -285.337504)
			(xy 369.644347 -285.342634) (xy 369.692089 -285.35963) (xy 369.736667 -285.383731) (xy 369.777034 -285.414369)
			(xy 369.812236 -285.450823) (xy 369.841446 -285.492235) (xy 369.863976 -285.537628) (xy 369.879294 -285.585934)
			(xy 369.88704 -285.636016) (xy 369.8875 -285.661354) (xy 369.886992 -285.687241) (xy 369.878893 -285.738379)
			(xy 369.862894 -285.787619) (xy 369.839388 -285.833751) (xy 369.808956 -285.875638) (xy 369.772346 -285.912248)
			(xy 369.730459 -285.94268) (xy 369.684327 -285.966186) (xy 369.635087 -285.982185) (xy 369.583949 -285.990284)
			(xy 369.532175 -285.990284) (xy 369.481037 -285.982185) (xy 369.431797 -285.966186) (xy 369.385665 -285.94268)
			(xy 369.343778 -285.912248) (xy 369.307168 -285.875638) (xy 369.276736 -285.833751) (xy 369.25323 -285.787619)
			(xy 369.237231 -285.738379) (xy 369.229132 -285.687241) (xy 369.228624 -285.661354) (xy 369.229166 -285.633646)
			(xy 369.238353 -285.579) (xy 369.246912 -285.552642) (xy 369.254786 -285.530544) (xy 369.049808 -285.175706)
			(xy 369.026948 -285.171388) (xy 369.002123 -285.166238) (xy 368.954343 -285.149282) (xy 368.909723 -285.125209)
			(xy 368.869316 -285.094586) (xy 368.834075 -285.058137) (xy 368.804831 -285.016721) (xy 368.782276 -284.971315)
			(xy 368.766939 -284.922991) (xy 368.759185 -284.872888) (xy 368.758724 -284.847538) (xy 367.538508 -284.847538)
			(xy 367.537898 -284.875255) (xy 367.528585 -284.929901) (xy 367.519966 -284.95625) (xy 367.512092 -284.978348)
			(xy 367.71707 -285.333186) (xy 367.73993 -285.337504) (xy 367.764747 -285.342634) (xy 367.812489 -285.35963)
			(xy 367.857067 -285.383731) (xy 367.897434 -285.414369) (xy 367.932636 -285.450823) (xy 367.961846 -285.492235)
			(xy 367.984376 -285.537628) (xy 367.999694 -285.585934) (xy 368.00744 -285.636016) (xy 368.0079 -285.661354)
			(xy 368.007392 -285.687241) (xy 367.999293 -285.738379) (xy 367.983294 -285.787619) (xy 367.959788 -285.833751)
			(xy 367.929356 -285.875638) (xy 367.892746 -285.912248) (xy 367.850859 -285.94268) (xy 367.804727 -285.966186)
			(xy 367.755487 -285.982185) (xy 367.704349 -285.990284) (xy 367.652575 -285.990284) (xy 367.601437 -285.982185)
			(xy 367.552197 -285.966186) (xy 367.506065 -285.94268) (xy 367.464178 -285.912248) (xy 367.427568 -285.875638)
			(xy 367.397136 -285.833751) (xy 367.37363 -285.787619) (xy 367.357631 -285.738379) (xy 367.349532 -285.687241)
			(xy 367.349024 -285.661354) (xy 367.349566 -285.633646) (xy 367.358753 -285.579) (xy 367.367312 -285.552642)
			(xy 367.375186 -285.530544) (xy 367.170208 -285.175706) (xy 367.147348 -285.171388) (xy 367.122523 -285.166238)
			(xy 367.074743 -285.149282) (xy 367.030123 -285.125209) (xy 366.989716 -285.094586) (xy 366.954475 -285.058137)
			(xy 366.925231 -285.016721) (xy 366.902676 -284.971315) (xy 366.887339 -284.922991) (xy 366.879585 -284.872888)
			(xy 366.879124 -284.847538) (xy 352.501708 -284.847538) (xy 352.501261 -284.872913) (xy 352.493487 -284.923064)
			(xy 352.478114 -284.97143) (xy 352.455505 -285.016866) (xy 352.426196 -285.058297) (xy 352.390879 -285.094742)
			(xy 352.350391 -285.125341) (xy 352.305689 -285.149367) (xy 352.257831 -285.166254) (xy 352.232976 -285.171388)
			(xy 352.210116 -285.175706) (xy 352.005138 -285.530544) (xy 352.013012 -285.552642) (xy 352.021583 -285.578997)
			(xy 352.030775 -285.633645) (xy 352.0313 -285.661354) (xy 352.030792 -285.687241) (xy 352.022693 -285.738379)
			(xy 352.006694 -285.787619) (xy 351.983188 -285.833751) (xy 351.952756 -285.875638) (xy 351.916146 -285.912248)
			(xy 351.874259 -285.94268) (xy 351.828127 -285.966186) (xy 351.778887 -285.982185) (xy 351.727749 -285.990284)
			(xy 351.675975 -285.990284) (xy 351.624837 -285.982185) (xy 351.575597 -285.966186) (xy 351.529465 -285.94268)
			(xy 351.487578 -285.912248) (xy 351.450968 -285.875638) (xy 351.420536 -285.833751) (xy 351.39703 -285.787619)
			(xy 351.381031 -285.738379) (xy 351.372932 -285.687241) (xy 351.372424 -285.661354) (xy 351.0915 -285.661354)
			(xy 351.0915 -285.661862) (xy 351.090923 -285.689379) (xy 351.081728 -285.74364) (xy 351.073212 -285.769812)
			(xy 351.065592 -285.79191) (xy 351.270824 -286.147256) (xy 351.293684 -286.151574) (xy 351.318506 -286.156737)
			(xy 351.366283 -286.173695) (xy 351.410901 -286.197768) (xy 351.451306 -286.22839) (xy 351.486546 -286.264837)
			(xy 351.515789 -286.30625) (xy 351.538346 -286.351653) (xy 351.553685 -286.399975) (xy 351.561445 -286.450075)
			(xy 351.561908 -286.475424) (xy 367.818924 -286.475424) (xy 367.819448 -286.45008) (xy 367.827216 -286.399991)
			(xy 367.842559 -286.351681) (xy 367.865115 -286.306288) (xy 367.894351 -286.264882) (xy 367.92958 -286.228438)
			(xy 367.969972 -286.197814) (xy 368.014574 -286.173733) (xy 368.062336 -286.156761) (xy 368.087148 -286.151574)
			(xy 368.110008 -286.147256) (xy 368.314986 -285.792164) (xy 368.307112 -285.77032) (xy 368.298538 -285.7439)
			(xy 368.289338 -285.689126) (xy 368.288824 -285.661354) (xy 368.289332 -285.635467) (xy 368.297431 -285.584329)
			(xy 368.31343 -285.535089) (xy 368.336936 -285.488957) (xy 368.367368 -285.44707) (xy 368.403978 -285.41046)
			(xy 368.445865 -285.380028) (xy 368.491997 -285.356522) (xy 368.541237 -285.340523) (xy 368.592375 -285.332424)
			(xy 368.644149 -285.332424) (xy 368.695287 -285.340523) (xy 368.744527 -285.356522) (xy 368.790659 -285.380028)
			(xy 368.832546 -285.41046) (xy 368.869156 -285.44707) (xy 368.899588 -285.488957) (xy 368.923094 -285.535089)
			(xy 368.939093 -285.584329) (xy 368.947192 -285.635467) (xy 368.9477 -285.661354) (xy 368.947266 -285.68669)
			(xy 368.939506 -285.736765) (xy 368.924176 -285.785062) (xy 368.901638 -285.830446) (xy 368.872422 -285.871848)
			(xy 368.837216 -285.908293) (xy 368.796849 -285.938922) (xy 368.752271 -285.963016) (xy 368.704531 -285.980006)
			(xy 368.67973 -285.985204) (xy 368.65687 -285.989522) (xy 368.451892 -286.344614) (xy 368.459766 -286.366458)
			(xy 368.468419 -286.392864) (xy 368.477734 -286.447642) (xy 368.478308 -286.475424) (xy 369.698524 -286.475424)
			(xy 369.699048 -286.45008) (xy 369.706816 -286.399991) (xy 369.722159 -286.351681) (xy 369.744715 -286.306288)
			(xy 369.773951 -286.264882) (xy 369.80918 -286.228438) (xy 369.849572 -286.197814) (xy 369.894174 -286.173733)
			(xy 369.941936 -286.156761) (xy 369.966748 -286.151574) (xy 369.989608 -286.147256) (xy 370.194586 -285.792164)
			(xy 370.186712 -285.77032) (xy 370.178138 -285.7439) (xy 370.168938 -285.689126) (xy 370.168424 -285.661354)
			(xy 370.168932 -285.635467) (xy 370.177031 -285.584329) (xy 370.19303 -285.535089) (xy 370.216536 -285.488957)
			(xy 370.246968 -285.44707) (xy 370.283578 -285.41046) (xy 370.325465 -285.380028) (xy 370.371597 -285.356522)
			(xy 370.420837 -285.340523) (xy 370.471975 -285.332424) (xy 370.523749 -285.332424) (xy 370.574887 -285.340523)
			(xy 370.624127 -285.356522) (xy 370.670259 -285.380028) (xy 370.712146 -285.41046) (xy 370.748756 -285.44707)
			(xy 370.779188 -285.488957) (xy 370.802694 -285.535089) (xy 370.818693 -285.584329) (xy 370.826792 -285.635467)
			(xy 370.8273 -285.661354) (xy 370.826866 -285.68669) (xy 370.819106 -285.736765) (xy 370.803776 -285.785062)
			(xy 370.781238 -285.830446) (xy 370.752022 -285.871848) (xy 370.716816 -285.908293) (xy 370.676449 -285.938922)
			(xy 370.631871 -285.963016) (xy 370.584131 -285.980006) (xy 370.55933 -285.985204) (xy 370.53647 -285.989522)
			(xy 370.331492 -286.344614) (xy 370.339366 -286.366458) (xy 370.348019 -286.392864) (xy 370.357334 -286.447642)
			(xy 370.357908 -286.475424) (xy 371.578124 -286.475424) (xy 371.578648 -286.45008) (xy 371.586416 -286.399991)
			(xy 371.601759 -286.351681) (xy 371.624315 -286.306288) (xy 371.653551 -286.264882) (xy 371.68878 -286.228438)
			(xy 371.729172 -286.197814) (xy 371.773774 -286.173733) (xy 371.821536 -286.156761) (xy 371.846348 -286.151574)
			(xy 371.869208 -286.147256) (xy 372.074186 -285.792164) (xy 372.066312 -285.77032) (xy 372.057738 -285.7439)
			(xy 372.048538 -285.689126) (xy 372.048024 -285.661354) (xy 372.048532 -285.635467) (xy 372.056631 -285.584329)
			(xy 372.07263 -285.535089) (xy 372.096136 -285.488957) (xy 372.126568 -285.44707) (xy 372.163178 -285.41046)
			(xy 372.205065 -285.380028) (xy 372.251197 -285.356522) (xy 372.300437 -285.340523) (xy 372.351575 -285.332424)
			(xy 372.403349 -285.332424) (xy 372.454487 -285.340523) (xy 372.503727 -285.356522) (xy 372.549859 -285.380028)
			(xy 372.591746 -285.41046) (xy 372.628356 -285.44707) (xy 372.658788 -285.488957) (xy 372.682294 -285.535089)
			(xy 372.698293 -285.584329) (xy 372.706392 -285.635467) (xy 372.7069 -285.661354) (xy 372.706466 -285.68669)
			(xy 372.698706 -285.736765) (xy 372.683376 -285.785062) (xy 372.660838 -285.830446) (xy 372.631622 -285.871848)
			(xy 372.596416 -285.908293) (xy 372.556049 -285.938922) (xy 372.511471 -285.963016) (xy 372.463731 -285.980006)
			(xy 372.43893 -285.985204) (xy 372.41607 -285.989522) (xy 372.211092 -286.344614) (xy 372.218966 -286.366458)
			(xy 372.227619 -286.392864) (xy 372.236934 -286.447642) (xy 372.237508 -286.475424) (xy 373.457724 -286.475424)
			(xy 373.458248 -286.45008) (xy 373.466016 -286.399991) (xy 373.481359 -286.351681) (xy 373.503915 -286.306288)
			(xy 373.533151 -286.264882) (xy 373.56838 -286.228438) (xy 373.608772 -286.197814) (xy 373.653374 -286.173733)
			(xy 373.701136 -286.156761) (xy 373.725948 -286.151574) (xy 373.748808 -286.147256) (xy 373.953786 -285.792164)
			(xy 373.945912 -285.77032) (xy 373.937338 -285.7439) (xy 373.928138 -285.689126) (xy 373.927624 -285.661354)
			(xy 373.928132 -285.635467) (xy 373.936231 -285.584329) (xy 373.95223 -285.535089) (xy 373.975736 -285.488957)
			(xy 374.006168 -285.44707) (xy 374.042778 -285.41046) (xy 374.084665 -285.380028) (xy 374.130797 -285.356522)
			(xy 374.180037 -285.340523) (xy 374.231175 -285.332424) (xy 374.282949 -285.332424) (xy 374.334087 -285.340523)
			(xy 374.383327 -285.356522) (xy 374.429459 -285.380028) (xy 374.471346 -285.41046) (xy 374.507956 -285.44707)
			(xy 374.538388 -285.488957) (xy 374.561894 -285.535089) (xy 374.577893 -285.584329) (xy 374.585992 -285.635467)
			(xy 374.5865 -285.661354) (xy 374.586066 -285.68669) (xy 374.578306 -285.736765) (xy 374.562976 -285.785062)
			(xy 374.540438 -285.830446) (xy 374.511222 -285.871848) (xy 374.476016 -285.908293) (xy 374.435649 -285.938922)
			(xy 374.391071 -285.963016) (xy 374.343331 -285.980006) (xy 374.31853 -285.985204) (xy 374.29567 -285.989522)
			(xy 374.090692 -286.344614) (xy 374.098566 -286.366458) (xy 374.107219 -286.392864) (xy 374.116534 -286.447642)
			(xy 374.117108 -286.475424) (xy 375.337324 -286.475424) (xy 375.337848 -286.45008) (xy 375.345616 -286.399991)
			(xy 375.360959 -286.351681) (xy 375.383515 -286.306288) (xy 375.412751 -286.264882) (xy 375.44798 -286.228438)
			(xy 375.488372 -286.197814) (xy 375.532974 -286.173733) (xy 375.580736 -286.156761) (xy 375.605548 -286.151574)
			(xy 375.628408 -286.147256) (xy 375.833386 -285.792164) (xy 375.825512 -285.77032) (xy 375.816938 -285.7439)
			(xy 375.807738 -285.689126) (xy 375.807224 -285.661354) (xy 375.807732 -285.635467) (xy 375.815831 -285.584329)
			(xy 375.83183 -285.535089) (xy 375.855336 -285.488957) (xy 375.885768 -285.44707) (xy 375.922378 -285.41046)
			(xy 375.964265 -285.380028) (xy 376.010397 -285.356522) (xy 376.059637 -285.340523) (xy 376.110775 -285.332424)
			(xy 376.162549 -285.332424) (xy 376.213687 -285.340523) (xy 376.262927 -285.356522) (xy 376.309059 -285.380028)
			(xy 376.350946 -285.41046) (xy 376.387556 -285.44707) (xy 376.417988 -285.488957) (xy 376.441494 -285.535089)
			(xy 376.457493 -285.584329) (xy 376.465592 -285.635467) (xy 376.4661 -285.661354) (xy 376.465666 -285.68669)
			(xy 376.457906 -285.736765) (xy 376.442576 -285.785062) (xy 376.420038 -285.830446) (xy 376.390822 -285.871848)
			(xy 376.355616 -285.908293) (xy 376.315249 -285.938922) (xy 376.270671 -285.963016) (xy 376.222931 -285.980006)
			(xy 376.19813 -285.985204) (xy 376.17527 -285.989522) (xy 375.970292 -286.344614) (xy 375.978166 -286.366458)
			(xy 375.986819 -286.392864) (xy 375.996134 -286.447642) (xy 375.996708 -286.475424) (xy 377.216924 -286.475424)
			(xy 377.217448 -286.45008) (xy 377.225216 -286.399991) (xy 377.240559 -286.351681) (xy 377.263115 -286.306288)
			(xy 377.292351 -286.264882) (xy 377.32758 -286.228438) (xy 377.367972 -286.197814) (xy 377.412574 -286.173733)
			(xy 377.460336 -286.156761) (xy 377.485148 -286.151574) (xy 377.508008 -286.147256) (xy 377.712986 -285.792164)
			(xy 377.705112 -285.77032) (xy 377.696538 -285.7439) (xy 377.687338 -285.689126) (xy 377.686824 -285.661354)
			(xy 377.687332 -285.635467) (xy 377.695431 -285.584329) (xy 377.71143 -285.535089) (xy 377.734936 -285.488957)
			(xy 377.765368 -285.44707) (xy 377.801978 -285.41046) (xy 377.843865 -285.380028) (xy 377.889997 -285.356522)
			(xy 377.939237 -285.340523) (xy 377.990375 -285.332424) (xy 378.042149 -285.332424) (xy 378.093287 -285.340523)
			(xy 378.142527 -285.356522) (xy 378.188659 -285.380028) (xy 378.230546 -285.41046) (xy 378.267156 -285.44707)
			(xy 378.297588 -285.488957) (xy 378.321094 -285.535089) (xy 378.337093 -285.584329) (xy 378.345192 -285.635467)
			(xy 378.3457 -285.661354) (xy 378.345266 -285.68669) (xy 378.337506 -285.736765) (xy 378.322176 -285.785062)
			(xy 378.299638 -285.830446) (xy 378.270422 -285.871848) (xy 378.235216 -285.908293) (xy 378.194849 -285.938922)
			(xy 378.150271 -285.963016) (xy 378.102531 -285.980006) (xy 378.07773 -285.985204) (xy 378.05487 -285.989522)
			(xy 377.849892 -286.344614) (xy 377.857766 -286.366458) (xy 377.866419 -286.392864) (xy 377.875734 -286.447642)
			(xy 377.876308 -286.475424) (xy 379.096524 -286.475424) (xy 379.097048 -286.45008) (xy 379.104816 -286.399991)
			(xy 379.120159 -286.351681) (xy 379.142715 -286.306288) (xy 379.171951 -286.264882) (xy 379.20718 -286.228438)
			(xy 379.247572 -286.197814) (xy 379.292174 -286.173733) (xy 379.339936 -286.156761) (xy 379.364748 -286.151574)
			(xy 379.387608 -286.147256) (xy 379.592586 -285.792164) (xy 379.584712 -285.77032) (xy 379.576138 -285.7439)
			(xy 379.566938 -285.689126) (xy 379.566424 -285.661354) (xy 379.566932 -285.635467) (xy 379.575031 -285.584329)
			(xy 379.59103 -285.535089) (xy 379.614536 -285.488957) (xy 379.644968 -285.44707) (xy 379.681578 -285.41046)
			(xy 379.723465 -285.380028) (xy 379.769597 -285.356522) (xy 379.818837 -285.340523) (xy 379.869975 -285.332424)
			(xy 379.921749 -285.332424) (xy 379.972887 -285.340523) (xy 380.022127 -285.356522) (xy 380.068259 -285.380028)
			(xy 380.110146 -285.41046) (xy 380.146756 -285.44707) (xy 380.177188 -285.488957) (xy 380.200694 -285.535089)
			(xy 380.216693 -285.584329) (xy 380.224792 -285.635467) (xy 380.2253 -285.661354) (xy 380.224866 -285.68669)
			(xy 380.217106 -285.736765) (xy 380.201776 -285.785062) (xy 380.179238 -285.830446) (xy 380.150022 -285.871848)
			(xy 380.114816 -285.908293) (xy 380.074449 -285.938922) (xy 380.029871 -285.963016) (xy 379.982131 -285.980006)
			(xy 379.95733 -285.985204) (xy 379.93447 -285.989522) (xy 379.729492 -286.344614) (xy 379.737366 -286.366458)
			(xy 379.746019 -286.392864) (xy 379.755334 -286.447642) (xy 379.755908 -286.475424) (xy 380.976124 -286.475424)
			(xy 380.976648 -286.45008) (xy 380.984416 -286.399991) (xy 380.999759 -286.351681) (xy 381.022315 -286.306288)
			(xy 381.051551 -286.264882) (xy 381.08678 -286.228438) (xy 381.127172 -286.197814) (xy 381.171774 -286.173733)
			(xy 381.219536 -286.156761) (xy 381.244348 -286.151574) (xy 381.267208 -286.147256) (xy 381.472186 -285.792164)
			(xy 381.464312 -285.77032) (xy 381.455738 -285.7439) (xy 381.446538 -285.689126) (xy 381.446024 -285.661354)
			(xy 381.446532 -285.635467) (xy 381.454631 -285.584329) (xy 381.47063 -285.535089) (xy 381.494136 -285.488957)
			(xy 381.524568 -285.44707) (xy 381.561178 -285.41046) (xy 381.603065 -285.380028) (xy 381.649197 -285.356522)
			(xy 381.698437 -285.340523) (xy 381.749575 -285.332424) (xy 381.801349 -285.332424) (xy 381.852487 -285.340523)
			(xy 381.901727 -285.356522) (xy 381.947859 -285.380028) (xy 381.989746 -285.41046) (xy 382.026356 -285.44707)
			(xy 382.056788 -285.488957) (xy 382.080294 -285.535089) (xy 382.096293 -285.584329) (xy 382.104392 -285.635467)
			(xy 382.1049 -285.661354) (xy 382.104466 -285.68669) (xy 382.096706 -285.736765) (xy 382.081376 -285.785062)
			(xy 382.058838 -285.830446) (xy 382.029622 -285.871848) (xy 381.994416 -285.908293) (xy 381.954049 -285.938922)
			(xy 381.909471 -285.963016) (xy 381.861731 -285.980006) (xy 381.83693 -285.985204) (xy 381.81407 -285.989522)
			(xy 381.609092 -286.344614) (xy 381.616966 -286.366458) (xy 381.625619 -286.392864) (xy 381.634934 -286.447642)
			(xy 381.635508 -286.475424) (xy 381.635 -286.501331) (xy 381.626894 -286.552508) (xy 381.610882 -286.601787)
			(xy 381.587359 -286.647954) (xy 381.556903 -286.689873) (xy 381.520265 -286.726511) (xy 381.478346 -286.756967)
			(xy 381.432179 -286.78049) (xy 381.3829 -286.796502) (xy 381.331723 -286.804608) (xy 381.279909 -286.804608)
			(xy 381.228732 -286.796502) (xy 381.179453 -286.78049) (xy 381.133286 -286.756967) (xy 381.091367 -286.726511)
			(xy 381.054729 -286.689873) (xy 381.024273 -286.647954) (xy 381.00075 -286.601787) (xy 380.984738 -286.552508)
			(xy 380.976632 -286.501331) (xy 380.976124 -286.475424) (xy 379.755908 -286.475424) (xy 379.7554 -286.501331)
			(xy 379.747294 -286.552508) (xy 379.731282 -286.601787) (xy 379.707759 -286.647954) (xy 379.677303 -286.689873)
			(xy 379.640665 -286.726511) (xy 379.598746 -286.756967) (xy 379.552579 -286.78049) (xy 379.5033 -286.796502)
			(xy 379.452123 -286.804608) (xy 379.400309 -286.804608) (xy 379.349132 -286.796502) (xy 379.299853 -286.78049)
			(xy 379.253686 -286.756967) (xy 379.211767 -286.726511) (xy 379.175129 -286.689873) (xy 379.144673 -286.647954)
			(xy 379.12115 -286.601787) (xy 379.105138 -286.552508) (xy 379.097032 -286.501331) (xy 379.096524 -286.475424)
			(xy 377.876308 -286.475424) (xy 377.8758 -286.501331) (xy 377.867694 -286.552508) (xy 377.851682 -286.601787)
			(xy 377.828159 -286.647954) (xy 377.797703 -286.689873) (xy 377.761065 -286.726511) (xy 377.719146 -286.756967)
			(xy 377.672979 -286.78049) (xy 377.6237 -286.796502) (xy 377.572523 -286.804608) (xy 377.520709 -286.804608)
			(xy 377.469532 -286.796502) (xy 377.420253 -286.78049) (xy 377.374086 -286.756967) (xy 377.332167 -286.726511)
			(xy 377.295529 -286.689873) (xy 377.265073 -286.647954) (xy 377.24155 -286.601787) (xy 377.225538 -286.552508)
			(xy 377.217432 -286.501331) (xy 377.216924 -286.475424) (xy 375.996708 -286.475424) (xy 375.9962 -286.501331)
			(xy 375.988094 -286.552508) (xy 375.972082 -286.601787) (xy 375.948559 -286.647954) (xy 375.918103 -286.689873)
			(xy 375.881465 -286.726511) (xy 375.839546 -286.756967) (xy 375.793379 -286.78049) (xy 375.7441 -286.796502)
			(xy 375.692923 -286.804608) (xy 375.641109 -286.804608) (xy 375.589932 -286.796502) (xy 375.540653 -286.78049)
			(xy 375.494486 -286.756967) (xy 375.452567 -286.726511) (xy 375.415929 -286.689873) (xy 375.385473 -286.647954)
			(xy 375.36195 -286.601787) (xy 375.345938 -286.552508) (xy 375.337832 -286.501331) (xy 375.337324 -286.475424)
			(xy 374.117108 -286.475424) (xy 374.1166 -286.501331) (xy 374.108494 -286.552508) (xy 374.092482 -286.601787)
			(xy 374.068959 -286.647954) (xy 374.038503 -286.689873) (xy 374.001865 -286.726511) (xy 373.959946 -286.756967)
			(xy 373.913779 -286.78049) (xy 373.8645 -286.796502) (xy 373.813323 -286.804608) (xy 373.761509 -286.804608)
			(xy 373.710332 -286.796502) (xy 373.661053 -286.78049) (xy 373.614886 -286.756967) (xy 373.572967 -286.726511)
			(xy 373.536329 -286.689873) (xy 373.505873 -286.647954) (xy 373.48235 -286.601787) (xy 373.466338 -286.552508)
			(xy 373.458232 -286.501331) (xy 373.457724 -286.475424) (xy 372.237508 -286.475424) (xy 372.237 -286.501331)
			(xy 372.228894 -286.552508) (xy 372.212882 -286.601787) (xy 372.189359 -286.647954) (xy 372.158903 -286.689873)
			(xy 372.122265 -286.726511) (xy 372.080346 -286.756967) (xy 372.034179 -286.78049) (xy 371.9849 -286.796502)
			(xy 371.933723 -286.804608) (xy 371.881909 -286.804608) (xy 371.830732 -286.796502) (xy 371.781453 -286.78049)
			(xy 371.735286 -286.756967) (xy 371.693367 -286.726511) (xy 371.656729 -286.689873) (xy 371.626273 -286.647954)
			(xy 371.60275 -286.601787) (xy 371.586738 -286.552508) (xy 371.578632 -286.501331) (xy 371.578124 -286.475424)
			(xy 370.357908 -286.475424) (xy 370.3574 -286.501331) (xy 370.349294 -286.552508) (xy 370.333282 -286.601787)
			(xy 370.309759 -286.647954) (xy 370.279303 -286.689873) (xy 370.242665 -286.726511) (xy 370.200746 -286.756967)
			(xy 370.154579 -286.78049) (xy 370.1053 -286.796502) (xy 370.054123 -286.804608) (xy 370.002309 -286.804608)
			(xy 369.951132 -286.796502) (xy 369.901853 -286.78049) (xy 369.855686 -286.756967) (xy 369.813767 -286.726511)
			(xy 369.777129 -286.689873) (xy 369.746673 -286.647954) (xy 369.72315 -286.601787) (xy 369.707138 -286.552508)
			(xy 369.699032 -286.501331) (xy 369.698524 -286.475424) (xy 368.478308 -286.475424) (xy 368.4778 -286.501331)
			(xy 368.469694 -286.552508) (xy 368.453682 -286.601787) (xy 368.430159 -286.647954) (xy 368.399703 -286.689873)
			(xy 368.363065 -286.726511) (xy 368.321146 -286.756967) (xy 368.274979 -286.78049) (xy 368.2257 -286.796502)
			(xy 368.174523 -286.804608) (xy 368.122709 -286.804608) (xy 368.071532 -286.796502) (xy 368.022253 -286.78049)
			(xy 367.976086 -286.756967) (xy 367.934167 -286.726511) (xy 367.897529 -286.689873) (xy 367.867073 -286.647954)
			(xy 367.84355 -286.601787) (xy 367.827538 -286.552508) (xy 367.819432 -286.501331) (xy 367.818924 -286.475424)
			(xy 351.561908 -286.475424) (xy 351.5614 -286.501331) (xy 351.553294 -286.552508) (xy 351.537282 -286.601787)
			(xy 351.513759 -286.647954) (xy 351.483303 -286.689873) (xy 351.446665 -286.726511) (xy 351.404746 -286.756967)
			(xy 351.358579 -286.78049) (xy 351.3093 -286.796502) (xy 351.258123 -286.804608) (xy 351.206309 -286.804608)
			(xy 351.155132 -286.796502) (xy 351.105853 -286.78049) (xy 351.059686 -286.756967) (xy 351.017767 -286.726511)
			(xy 350.981129 -286.689873) (xy 350.950673 -286.647954) (xy 350.92715 -286.601787) (xy 350.911138 -286.552508)
			(xy 350.903032 -286.501331) (xy 350.902524 -286.475424) (xy 350.903123 -286.447707) (xy 350.912443 -286.39306)
			(xy 350.921066 -286.366712) (xy 350.92894 -286.344614) (xy 350.723962 -285.989522) (xy 350.700848 -285.985204)
			(xy 350.676027 -285.980039) (xy 350.628247 -285.963084) (xy 350.583628 -285.939012) (xy 350.543222 -285.908392)
			(xy 350.507981 -285.871945) (xy 350.478737 -285.830531) (xy 350.45618 -285.785127) (xy 350.440843 -285.736804)
			(xy 350.433086 -285.686703) (xy 350.432624 -285.661354) (xy 350.1517 -285.661354) (xy 350.151192 -285.687241)
			(xy 350.143093 -285.738379) (xy 350.127094 -285.787619) (xy 350.103588 -285.833751) (xy 350.073156 -285.875638)
			(xy 350.036546 -285.912248) (xy 349.994659 -285.94268) (xy 349.948527 -285.966186) (xy 349.899287 -285.982185)
			(xy 349.848149 -285.990284) (xy 349.796375 -285.990284) (xy 349.745237 -285.982185) (xy 349.695997 -285.966186)
			(xy 349.649865 -285.94268) (xy 349.607978 -285.912248) (xy 349.571368 -285.875638) (xy 349.540936 -285.833751)
			(xy 349.51743 -285.787619) (xy 349.501431 -285.738379) (xy 349.493332 -285.687241) (xy 349.492824 -285.661354)
			(xy 349.2119 -285.661354) (xy 349.2119 -285.661862) (xy 349.211323 -285.689379) (xy 349.202128 -285.74364)
			(xy 349.193612 -285.769812) (xy 349.185992 -285.79191) (xy 349.391224 -286.147256) (xy 349.414084 -286.151574)
			(xy 349.438906 -286.156737) (xy 349.486683 -286.173695) (xy 349.531301 -286.197768) (xy 349.571706 -286.22839)
			(xy 349.606946 -286.264837) (xy 349.636189 -286.30625) (xy 349.658746 -286.351653) (xy 349.674085 -286.399975)
			(xy 349.681845 -286.450075) (xy 349.682308 -286.475424) (xy 349.6818 -286.501331) (xy 349.673694 -286.552508)
			(xy 349.657682 -286.601787) (xy 349.634159 -286.647954) (xy 349.603703 -286.689873) (xy 349.567065 -286.726511)
			(xy 349.525146 -286.756967) (xy 349.478979 -286.78049) (xy 349.4297 -286.796502) (xy 349.378523 -286.804608)
			(xy 349.326709 -286.804608) (xy 349.275532 -286.796502) (xy 349.226253 -286.78049) (xy 349.180086 -286.756967)
			(xy 349.138167 -286.726511) (xy 349.101529 -286.689873) (xy 349.071073 -286.647954) (xy 349.04755 -286.601787)
			(xy 349.031538 -286.552508) (xy 349.023432 -286.501331) (xy 349.022924 -286.475424) (xy 349.023523 -286.447707)
			(xy 349.032843 -286.39306) (xy 349.041466 -286.366712) (xy 349.04934 -286.344614) (xy 348.844362 -285.989522)
			(xy 348.821248 -285.985204) (xy 348.796427 -285.980039) (xy 348.748647 -285.963084) (xy 348.704028 -285.939012)
			(xy 348.663622 -285.908392) (xy 348.628381 -285.871945) (xy 348.599137 -285.830531) (xy 348.57658 -285.785127)
			(xy 348.561243 -285.736804) (xy 348.553486 -285.686703) (xy 348.553024 -285.661354) (xy 348.2721 -285.661354)
			(xy 348.271592 -285.687241) (xy 348.263493 -285.738379) (xy 348.247494 -285.787619) (xy 348.223988 -285.833751)
			(xy 348.193556 -285.875638) (xy 348.156946 -285.912248) (xy 348.115059 -285.94268) (xy 348.068927 -285.966186)
			(xy 348.019687 -285.982185) (xy 347.968549 -285.990284) (xy 347.916775 -285.990284) (xy 347.865637 -285.982185)
			(xy 347.816397 -285.966186) (xy 347.770265 -285.94268) (xy 347.728378 -285.912248) (xy 347.691768 -285.875638)
			(xy 347.661336 -285.833751) (xy 347.63783 -285.787619) (xy 347.621831 -285.738379) (xy 347.613732 -285.687241)
			(xy 347.613224 -285.661354) (xy 347.3323 -285.661354) (xy 347.3323 -285.661862) (xy 347.331723 -285.689379)
			(xy 347.322528 -285.74364) (xy 347.314012 -285.769812) (xy 347.306392 -285.79191) (xy 347.511624 -286.147256)
			(xy 347.534484 -286.151574) (xy 347.559306 -286.156737) (xy 347.607083 -286.173695) (xy 347.651701 -286.197768)
			(xy 347.692106 -286.22839) (xy 347.727346 -286.264837) (xy 347.756589 -286.30625) (xy 347.779146 -286.351653)
			(xy 347.794485 -286.399975) (xy 347.802245 -286.450075) (xy 347.802708 -286.475424) (xy 347.8022 -286.501331)
			(xy 347.794094 -286.552508) (xy 347.778082 -286.601787) (xy 347.754559 -286.647954) (xy 347.724103 -286.689873)
			(xy 347.687465 -286.726511) (xy 347.645546 -286.756967) (xy 347.599379 -286.78049) (xy 347.5501 -286.796502)
			(xy 347.498923 -286.804608) (xy 347.447109 -286.804608) (xy 347.395932 -286.796502) (xy 347.346653 -286.78049)
			(xy 347.300486 -286.756967) (xy 347.258567 -286.726511) (xy 347.221929 -286.689873) (xy 347.191473 -286.647954)
			(xy 347.16795 -286.601787) (xy 347.151938 -286.552508) (xy 347.143832 -286.501331) (xy 347.143324 -286.475424)
			(xy 347.143923 -286.447707) (xy 347.153243 -286.39306) (xy 347.161866 -286.366712) (xy 347.16974 -286.344614)
			(xy 346.964762 -285.989522) (xy 346.941648 -285.985204) (xy 346.916827 -285.980039) (xy 346.869047 -285.963084)
			(xy 346.824428 -285.939012) (xy 346.784022 -285.908392) (xy 346.748781 -285.871945) (xy 346.719537 -285.830531)
			(xy 346.69698 -285.785127) (xy 346.681643 -285.736804) (xy 346.673886 -285.686703) (xy 346.673424 -285.661354)
			(xy 346.3925 -285.661354) (xy 346.391992 -285.687241) (xy 346.383893 -285.738379) (xy 346.367894 -285.787619)
			(xy 346.344388 -285.833751) (xy 346.313956 -285.875638) (xy 346.277346 -285.912248) (xy 346.235459 -285.94268)
			(xy 346.189327 -285.966186) (xy 346.140087 -285.982185) (xy 346.088949 -285.990284) (xy 346.037175 -285.990284)
			(xy 345.986037 -285.982185) (xy 345.936797 -285.966186) (xy 345.890665 -285.94268) (xy 345.848778 -285.912248)
			(xy 345.812168 -285.875638) (xy 345.781736 -285.833751) (xy 345.75823 -285.787619) (xy 345.742231 -285.738379)
			(xy 345.734132 -285.687241) (xy 345.733624 -285.661354) (xy 345.4527 -285.661354) (xy 345.4527 -285.661862)
			(xy 345.452123 -285.689379) (xy 345.442928 -285.74364) (xy 345.434412 -285.769812) (xy 345.426792 -285.79191)
			(xy 345.632024 -286.147256) (xy 345.654884 -286.151574) (xy 345.679706 -286.156737) (xy 345.727483 -286.173695)
			(xy 345.772101 -286.197768) (xy 345.812506 -286.22839) (xy 345.847746 -286.264837) (xy 345.876989 -286.30625)
			(xy 345.899546 -286.351653) (xy 345.914885 -286.399975) (xy 345.922645 -286.450075) (xy 345.923108 -286.475424)
			(xy 345.9226 -286.501331) (xy 345.914494 -286.552508) (xy 345.898482 -286.601787) (xy 345.874959 -286.647954)
			(xy 345.844503 -286.689873) (xy 345.807865 -286.726511) (xy 345.765946 -286.756967) (xy 345.719779 -286.78049)
			(xy 345.6705 -286.796502) (xy 345.619323 -286.804608) (xy 345.567509 -286.804608) (xy 345.516332 -286.796502)
			(xy 345.467053 -286.78049) (xy 345.420886 -286.756967) (xy 345.378967 -286.726511) (xy 345.342329 -286.689873)
			(xy 345.311873 -286.647954) (xy 345.28835 -286.601787) (xy 345.272338 -286.552508) (xy 345.264232 -286.501331)
			(xy 345.263724 -286.475424) (xy 345.264323 -286.447707) (xy 345.273643 -286.39306) (xy 345.282266 -286.366712)
			(xy 345.29014 -286.344614) (xy 345.085162 -285.989522) (xy 345.062048 -285.985204) (xy 345.037227 -285.980039)
			(xy 344.989447 -285.963084) (xy 344.944828 -285.939012) (xy 344.904422 -285.908392) (xy 344.869181 -285.871945)
			(xy 344.839937 -285.830531) (xy 344.81738 -285.785127) (xy 344.802043 -285.736804) (xy 344.794286 -285.686703)
			(xy 344.793824 -285.661354) (xy 344.5129 -285.661354) (xy 344.512392 -285.687241) (xy 344.504293 -285.738379)
			(xy 344.488294 -285.787619) (xy 344.464788 -285.833751) (xy 344.434356 -285.875638) (xy 344.397746 -285.912248)
			(xy 344.355859 -285.94268) (xy 344.309727 -285.966186) (xy 344.260487 -285.982185) (xy 344.209349 -285.990284)
			(xy 344.157575 -285.990284) (xy 344.106437 -285.982185) (xy 344.057197 -285.966186) (xy 344.011065 -285.94268)
			(xy 343.969178 -285.912248) (xy 343.932568 -285.875638) (xy 343.902136 -285.833751) (xy 343.87863 -285.787619)
			(xy 343.862631 -285.738379) (xy 343.854532 -285.687241) (xy 343.854024 -285.661354) (xy 343.5731 -285.661354)
			(xy 343.5731 -285.661862) (xy 343.572523 -285.689379) (xy 343.563328 -285.74364) (xy 343.554812 -285.769812)
			(xy 343.547192 -285.79191) (xy 343.752424 -286.147256) (xy 343.775284 -286.151574) (xy 343.800106 -286.156737)
			(xy 343.847883 -286.173695) (xy 343.892501 -286.197768) (xy 343.932906 -286.22839) (xy 343.968146 -286.264837)
			(xy 343.997389 -286.30625) (xy 344.019946 -286.351653) (xy 344.035285 -286.399975) (xy 344.043045 -286.450075)
			(xy 344.043508 -286.475424) (xy 344.043 -286.501331) (xy 344.034894 -286.552508) (xy 344.018882 -286.601787)
			(xy 343.995359 -286.647954) (xy 343.964903 -286.689873) (xy 343.928265 -286.726511) (xy 343.886346 -286.756967)
			(xy 343.840179 -286.78049) (xy 343.7909 -286.796502) (xy 343.739723 -286.804608) (xy 343.687909 -286.804608)
			(xy 343.636732 -286.796502) (xy 343.587453 -286.78049) (xy 343.541286 -286.756967) (xy 343.499367 -286.726511)
			(xy 343.462729 -286.689873) (xy 343.432273 -286.647954) (xy 343.40875 -286.601787) (xy 343.392738 -286.552508)
			(xy 343.384632 -286.501331) (xy 343.384124 -286.475424) (xy 343.384723 -286.447707) (xy 343.394043 -286.39306)
			(xy 343.402666 -286.366712) (xy 343.41054 -286.344614) (xy 343.205562 -285.989522) (xy 343.182448 -285.985204)
			(xy 343.157627 -285.980039) (xy 343.109847 -285.963084) (xy 343.065228 -285.939012) (xy 343.024822 -285.908392)
			(xy 342.989581 -285.871945) (xy 342.960337 -285.830531) (xy 342.93778 -285.785127) (xy 342.922443 -285.736804)
			(xy 342.914686 -285.686703) (xy 342.914224 -285.661354) (xy 342.6333 -285.661354) (xy 342.632792 -285.687241)
			(xy 342.624693 -285.738379) (xy 342.608694 -285.787619) (xy 342.585188 -285.833751) (xy 342.554756 -285.875638)
			(xy 342.518146 -285.912248) (xy 342.476259 -285.94268) (xy 342.430127 -285.966186) (xy 342.380887 -285.982185)
			(xy 342.329749 -285.990284) (xy 342.277975 -285.990284) (xy 342.226837 -285.982185) (xy 342.177597 -285.966186)
			(xy 342.131465 -285.94268) (xy 342.089578 -285.912248) (xy 342.052968 -285.875638) (xy 342.022536 -285.833751)
			(xy 341.99903 -285.787619) (xy 341.983031 -285.738379) (xy 341.974932 -285.687241) (xy 341.974424 -285.661354)
			(xy 341.6935 -285.661354) (xy 341.6935 -285.661862) (xy 341.692923 -285.689379) (xy 341.683728 -285.74364)
			(xy 341.675212 -285.769812) (xy 341.667592 -285.79191) (xy 341.872824 -286.147256) (xy 341.895684 -286.151574)
			(xy 341.920506 -286.156737) (xy 341.968283 -286.173695) (xy 342.012901 -286.197768) (xy 342.053306 -286.22839)
			(xy 342.088546 -286.264837) (xy 342.117789 -286.30625) (xy 342.140346 -286.351653) (xy 342.155685 -286.399975)
			(xy 342.163445 -286.450075) (xy 342.163908 -286.475424) (xy 342.1634 -286.501331) (xy 342.155294 -286.552508)
			(xy 342.139282 -286.601787) (xy 342.115759 -286.647954) (xy 342.085303 -286.689873) (xy 342.048665 -286.726511)
			(xy 342.006746 -286.756967) (xy 341.960579 -286.78049) (xy 341.9113 -286.796502) (xy 341.860123 -286.804608)
			(xy 341.808309 -286.804608) (xy 341.757132 -286.796502) (xy 341.707853 -286.78049) (xy 341.661686 -286.756967)
			(xy 341.619767 -286.726511) (xy 341.583129 -286.689873) (xy 341.552673 -286.647954) (xy 341.52915 -286.601787)
			(xy 341.513138 -286.552508) (xy 341.505032 -286.501331) (xy 341.504524 -286.475424) (xy 341.505123 -286.447707)
			(xy 341.514443 -286.39306) (xy 341.523066 -286.366712) (xy 341.53094 -286.344614) (xy 341.325962 -285.989522)
			(xy 341.302848 -285.985204) (xy 341.278027 -285.980039) (xy 341.230247 -285.963084) (xy 341.185628 -285.939012)
			(xy 341.145222 -285.908392) (xy 341.109981 -285.871945) (xy 341.080737 -285.830531) (xy 341.05818 -285.785127)
			(xy 341.042843 -285.736804) (xy 341.035086 -285.686703) (xy 341.034624 -285.661354) (xy 340.7537 -285.661354)
			(xy 340.753192 -285.687241) (xy 340.745093 -285.738379) (xy 340.729094 -285.787619) (xy 340.705588 -285.833751)
			(xy 340.675156 -285.875638) (xy 340.638546 -285.912248) (xy 340.596659 -285.94268) (xy 340.550527 -285.966186)
			(xy 340.501287 -285.982185) (xy 340.450149 -285.990284) (xy 340.398375 -285.990284) (xy 340.347237 -285.982185)
			(xy 340.297997 -285.966186) (xy 340.251865 -285.94268) (xy 340.209978 -285.912248) (xy 340.173368 -285.875638)
			(xy 340.142936 -285.833751) (xy 340.11943 -285.787619) (xy 340.103431 -285.738379) (xy 340.095332 -285.687241)
			(xy 340.094824 -285.661354) (xy 339.814408 -285.661354) (xy 339.813802 -285.689071) (xy 339.804487 -285.743717)
			(xy 339.795866 -285.770066) (xy 339.787992 -285.792164) (xy 339.993224 -286.147256) (xy 340.016084 -286.151574)
			(xy 340.040906 -286.156737) (xy 340.088683 -286.173695) (xy 340.133301 -286.197768) (xy 340.173706 -286.22839)
			(xy 340.208946 -286.264837) (xy 340.238189 -286.30625) (xy 340.260746 -286.351653) (xy 340.276085 -286.399975)
			(xy 340.283845 -286.450075) (xy 340.284308 -286.475424) (xy 340.2838 -286.501331) (xy 340.275694 -286.552508)
			(xy 340.259682 -286.601787) (xy 340.236159 -286.647954) (xy 340.205703 -286.689873) (xy 340.169065 -286.726511)
			(xy 340.127146 -286.756967) (xy 340.080979 -286.78049) (xy 340.0317 -286.796502) (xy 339.980523 -286.804608)
			(xy 339.928709 -286.804608) (xy 339.877532 -286.796502) (xy 339.828253 -286.78049) (xy 339.782086 -286.756967)
			(xy 339.740167 -286.726511) (xy 339.703529 -286.689873) (xy 339.673073 -286.647954) (xy 339.64955 -286.601787)
			(xy 339.633538 -286.552508) (xy 339.625432 -286.501331) (xy 339.624924 -286.475424) (xy 339.625523 -286.447707)
			(xy 339.634843 -286.39306) (xy 339.643466 -286.366712) (xy 339.65134 -286.344614) (xy 339.446108 -285.989522)
			(xy 339.423248 -285.985204) (xy 339.398427 -285.980039) (xy 339.350647 -285.963084) (xy 339.306028 -285.939012)
			(xy 339.265622 -285.908392) (xy 339.230381 -285.871945) (xy 339.201137 -285.830531) (xy 339.17858 -285.785127)
			(xy 339.163243 -285.736804) (xy 339.155486 -285.686703) (xy 339.155024 -285.661354) (xy 338.874608 -285.661354)
			(xy 338.8741 -285.687261) (xy 338.865994 -285.738438) (xy 338.849982 -285.787717) (xy 338.826459 -285.833884)
			(xy 338.796003 -285.875803) (xy 338.759365 -285.912441) (xy 338.717446 -285.942897) (xy 338.671279 -285.96642)
			(xy 338.622 -285.982432) (xy 338.570823 -285.990538) (xy 338.519009 -285.990538) (xy 338.467832 -285.982432)
			(xy 338.418553 -285.96642) (xy 338.372386 -285.942897) (xy 338.330467 -285.912441) (xy 338.293829 -285.875803)
			(xy 338.263373 -285.833884) (xy 338.23985 -285.787717) (xy 338.223838 -285.738438) (xy 338.215732 -285.687261)
			(xy 338.215224 -285.661354) (xy 337.9343 -285.661354) (xy 337.933759 -285.689062) (xy 337.924571 -285.743708)
			(xy 337.916012 -285.770066) (xy 337.908138 -285.792164) (xy 338.11337 -286.147256) (xy 338.13623 -286.151574)
			(xy 338.16104 -286.156732) (xy 338.20878 -286.173726) (xy 338.253357 -286.197824) (xy 338.293722 -286.228459)
			(xy 338.328925 -286.264909) (xy 338.358136 -286.306317) (xy 338.380667 -286.351707) (xy 338.395988 -286.400009)
			(xy 338.403738 -286.450087) (xy 338.4042 -286.475424) (xy 338.403692 -286.501311) (xy 338.395593 -286.552449)
			(xy 338.379594 -286.601689) (xy 338.356088 -286.647821) (xy 338.325656 -286.689708) (xy 338.289046 -286.726318)
			(xy 338.247159 -286.75675) (xy 338.201027 -286.780256) (xy 338.151787 -286.796255) (xy 338.100649 -286.804354)
			(xy 338.048875 -286.804354) (xy 337.997737 -286.796255) (xy 337.948497 -286.780256) (xy 337.902365 -286.75675)
			(xy 337.860478 -286.726318) (xy 337.823868 -286.689708) (xy 337.793436 -286.647821) (xy 337.76993 -286.601689)
			(xy 337.753931 -286.552449) (xy 337.745832 -286.501311) (xy 337.745324 -286.475424) (xy 337.745858 -286.447716)
			(xy 337.75505 -286.393069) (xy 337.763612 -286.366712) (xy 337.771486 -286.344614) (xy 337.566254 -285.989522)
			(xy 337.543394 -285.985204) (xy 337.518583 -285.980049) (xy 337.470842 -285.963057) (xy 337.426263 -285.93896)
			(xy 337.385896 -285.908325) (xy 337.350693 -285.871874) (xy 337.321482 -285.830466) (xy 337.298951 -285.785075)
			(xy 337.283632 -285.736771) (xy 337.275885 -285.686692) (xy 337.275424 -285.661354) (xy 134.164832 -285.661354)
			(xy 134.164372 -285.686689) (xy 134.156613 -285.736761) (xy 134.141285 -285.785057) (xy 134.118749 -285.830439)
			(xy 134.089536 -285.87184) (xy 134.054334 -285.908285) (xy 134.013971 -285.938915) (xy 133.969397 -285.963011)
			(xy 133.921662 -285.980004) (xy 133.896862 -285.985204) (xy 133.874002 -285.989522) (xy 133.669024 -286.344614)
			(xy 133.676898 -286.366458) (xy 133.685549 -286.392865) (xy 133.694866 -286.447642) (xy 133.69544 -286.475424)
			(xy 333.986124 -286.475424) (xy 333.986632 -286.449537) (xy 333.994731 -286.398399) (xy 334.01073 -286.349159)
			(xy 334.034236 -286.303027) (xy 334.064668 -286.26114) (xy 334.101278 -286.22453) (xy 334.143165 -286.194098)
			(xy 334.189297 -286.170592) (xy 334.238537 -286.154593) (xy 334.289675 -286.146494) (xy 334.341449 -286.146494)
			(xy 334.392587 -286.154593) (xy 334.441827 -286.170592) (xy 334.487959 -286.194098) (xy 334.529846 -286.22453)
			(xy 334.566456 -286.26114) (xy 334.596888 -286.303027) (xy 334.620394 -286.349159) (xy 334.636393 -286.398399)
			(xy 334.644492 -286.449537) (xy 334.645 -286.475424) (xy 334.644476 -286.503132) (xy 334.635277 -286.557779)
			(xy 334.626712 -286.584136) (xy 334.619092 -286.60598) (xy 334.82407 -286.961072) (xy 334.84693 -286.96539)
			(xy 334.871744 -286.970533) (xy 334.919484 -286.987528) (xy 334.964063 -287.011628) (xy 335.004428 -287.042264)
			(xy 335.039631 -287.078717) (xy 335.068841 -287.120126) (xy 335.091372 -287.165518) (xy 335.106691 -287.213822)
			(xy 335.114439 -287.263902) (xy 335.1149 -287.28924) (xy 335.114392 -287.315127) (xy 335.106293 -287.366265)
			(xy 335.090294 -287.415505) (xy 335.066788 -287.461637) (xy 335.036356 -287.503524) (xy 334.999746 -287.540134)
			(xy 334.957859 -287.570566) (xy 334.911727 -287.594072) (xy 334.862487 -287.610071) (xy 334.811349 -287.61817)
			(xy 334.759575 -287.61817) (xy 334.708437 -287.610071) (xy 334.659197 -287.594072) (xy 334.613065 -287.570566)
			(xy 334.571178 -287.540134) (xy 334.534568 -287.503524) (xy 334.504136 -287.461637) (xy 334.48063 -287.415505)
			(xy 334.464631 -287.366265) (xy 334.456532 -287.315127) (xy 334.456024 -287.28924) (xy 334.456562 -287.261532)
			(xy 334.465751 -287.206885) (xy 334.474312 -287.180528) (xy 334.481932 -287.158684) (xy 334.276954 -286.803592)
			(xy 334.254094 -286.799274) (xy 334.229299 -286.794053) (xy 334.181562 -286.777067) (xy 334.136987 -286.752976)
			(xy 334.096622 -286.722349) (xy 334.061419 -286.685906) (xy 334.032206 -286.644507) (xy 334.009672 -286.599125)
			(xy 333.994346 -286.55083) (xy 333.98659 -286.500758) (xy 333.986124 -286.475424) (xy 133.69544 -286.475424)
			(xy 133.694932 -286.501331) (xy 133.686826 -286.552508) (xy 133.670814 -286.601787) (xy 133.647291 -286.647954)
			(xy 133.616835 -286.689873) (xy 133.580197 -286.726511) (xy 133.538278 -286.756967) (xy 133.492111 -286.78049)
			(xy 133.442832 -286.796502) (xy 133.391655 -286.804608) (xy 133.339841 -286.804608) (xy 133.288664 -286.796502)
			(xy 133.239385 -286.78049) (xy 133.193218 -286.756967) (xy 133.151299 -286.726511) (xy 133.114661 -286.689873)
			(xy 133.084205 -286.647954) (xy 133.060682 -286.601787) (xy 133.04467 -286.552508) (xy 133.036564 -286.501331)
			(xy 133.036056 -286.475424) (xy 131.81584 -286.475424) (xy 131.815332 -286.501331) (xy 131.807226 -286.552508)
			(xy 131.791214 -286.601787) (xy 131.767691 -286.647954) (xy 131.737235 -286.689873) (xy 131.700597 -286.726511)
			(xy 131.658678 -286.756967) (xy 131.612511 -286.78049) (xy 131.563232 -286.796502) (xy 131.512055 -286.804608)
			(xy 131.460241 -286.804608) (xy 131.409064 -286.796502) (xy 131.359785 -286.78049) (xy 131.313618 -286.756967)
			(xy 131.271699 -286.726511) (xy 131.235061 -286.689873) (xy 131.204605 -286.647954) (xy 131.181082 -286.601787)
			(xy 131.16507 -286.552508) (xy 131.156964 -286.501331) (xy 131.156456 -286.475424) (xy 129.93624 -286.475424)
			(xy 129.935732 -286.501331) (xy 129.927626 -286.552508) (xy 129.911614 -286.601787) (xy 129.888091 -286.647954)
			(xy 129.857635 -286.689873) (xy 129.820997 -286.726511) (xy 129.779078 -286.756967) (xy 129.732911 -286.78049)
			(xy 129.683632 -286.796502) (xy 129.632455 -286.804608) (xy 129.580641 -286.804608) (xy 129.529464 -286.796502)
			(xy 129.480185 -286.78049) (xy 129.434018 -286.756967) (xy 129.392099 -286.726511) (xy 129.355461 -286.689873)
			(xy 129.325005 -286.647954) (xy 129.301482 -286.601787) (xy 129.28547 -286.552508) (xy 129.277364 -286.501331)
			(xy 129.276856 -286.475424) (xy 128.05664 -286.475424) (xy 128.056132 -286.501331) (xy 128.048026 -286.552508)
			(xy 128.032014 -286.601787) (xy 128.008491 -286.647954) (xy 127.978035 -286.689873) (xy 127.941397 -286.726511)
			(xy 127.899478 -286.756967) (xy 127.853311 -286.78049) (xy 127.804032 -286.796502) (xy 127.752855 -286.804608)
			(xy 127.701041 -286.804608) (xy 127.649864 -286.796502) (xy 127.600585 -286.78049) (xy 127.554418 -286.756967)
			(xy 127.512499 -286.726511) (xy 127.475861 -286.689873) (xy 127.445405 -286.647954) (xy 127.421882 -286.601787)
			(xy 127.40587 -286.552508) (xy 127.397764 -286.501331) (xy 127.397256 -286.475424) (xy 126.17704 -286.475424)
			(xy 126.176532 -286.501331) (xy 126.168426 -286.552508) (xy 126.152414 -286.601787) (xy 126.128891 -286.647954)
			(xy 126.098435 -286.689873) (xy 126.061797 -286.726511) (xy 126.019878 -286.756967) (xy 125.973711 -286.78049)
			(xy 125.924432 -286.796502) (xy 125.873255 -286.804608) (xy 125.821441 -286.804608) (xy 125.770264 -286.796502)
			(xy 125.720985 -286.78049) (xy 125.674818 -286.756967) (xy 125.632899 -286.726511) (xy 125.596261 -286.689873)
			(xy 125.565805 -286.647954) (xy 125.542282 -286.601787) (xy 125.52627 -286.552508) (xy 125.518164 -286.501331)
			(xy 125.517656 -286.475424) (xy 124.29744 -286.475424) (xy 124.296932 -286.501331) (xy 124.288826 -286.552508)
			(xy 124.272814 -286.601787) (xy 124.249291 -286.647954) (xy 124.218835 -286.689873) (xy 124.182197 -286.726511)
			(xy 124.140278 -286.756967) (xy 124.094111 -286.78049) (xy 124.044832 -286.796502) (xy 123.993655 -286.804608)
			(xy 123.941841 -286.804608) (xy 123.890664 -286.796502) (xy 123.841385 -286.78049) (xy 123.795218 -286.756967)
			(xy 123.753299 -286.726511) (xy 123.716661 -286.689873) (xy 123.686205 -286.647954) (xy 123.662682 -286.601787)
			(xy 123.64667 -286.552508) (xy 123.638564 -286.501331) (xy 123.638056 -286.475424) (xy 122.41784 -286.475424)
			(xy 122.417332 -286.501331) (xy 122.409226 -286.552508) (xy 122.393214 -286.601787) (xy 122.369691 -286.647954)
			(xy 122.339235 -286.689873) (xy 122.302597 -286.726511) (xy 122.260678 -286.756967) (xy 122.214511 -286.78049)
			(xy 122.165232 -286.796502) (xy 122.114055 -286.804608) (xy 122.062241 -286.804608) (xy 122.011064 -286.796502)
			(xy 121.961785 -286.78049) (xy 121.915618 -286.756967) (xy 121.873699 -286.726511) (xy 121.837061 -286.689873)
			(xy 121.806605 -286.647954) (xy 121.783082 -286.601787) (xy 121.76707 -286.552508) (xy 121.758964 -286.501331)
			(xy 121.758456 -286.475424) (xy 120.53824 -286.475424) (xy 120.537732 -286.501331) (xy 120.529626 -286.552508)
			(xy 120.513614 -286.601787) (xy 120.490091 -286.647954) (xy 120.459635 -286.689873) (xy 120.422997 -286.726511)
			(xy 120.381078 -286.756967) (xy 120.334911 -286.78049) (xy 120.285632 -286.796502) (xy 120.234455 -286.804608)
			(xy 120.182641 -286.804608) (xy 120.131464 -286.796502) (xy 120.082185 -286.78049) (xy 120.036018 -286.756967)
			(xy 119.994099 -286.726511) (xy 119.957461 -286.689873) (xy 119.927005 -286.647954) (xy 119.903482 -286.601787)
			(xy 119.88747 -286.552508) (xy 119.879364 -286.501331) (xy 119.878856 -286.475424) (xy 103.62184 -286.475424)
			(xy 103.621332 -286.501331) (xy 103.613226 -286.552508) (xy 103.597214 -286.601787) (xy 103.573691 -286.647954)
			(xy 103.543235 -286.689873) (xy 103.506597 -286.726511) (xy 103.464678 -286.756967) (xy 103.418511 -286.78049)
			(xy 103.369232 -286.796502) (xy 103.318055 -286.804608) (xy 103.266241 -286.804608) (xy 103.215064 -286.796502)
			(xy 103.165785 -286.78049) (xy 103.119618 -286.756967) (xy 103.077699 -286.726511) (xy 103.041061 -286.689873)
			(xy 103.010605 -286.647954) (xy 102.987082 -286.601787) (xy 102.97107 -286.552508) (xy 102.962964 -286.501331)
			(xy 102.962456 -286.475424) (xy 102.963053 -286.447707) (xy 102.972374 -286.39306) (xy 102.980998 -286.366712)
			(xy 102.988872 -286.344614) (xy 102.783894 -285.989522) (xy 102.76078 -285.985204) (xy 102.735964 -285.980016)
			(xy 102.688184 -285.963065) (xy 102.643565 -285.938998) (xy 102.603157 -285.908381) (xy 102.567916 -285.871936)
			(xy 102.538671 -285.830525) (xy 102.516113 -285.785123) (xy 102.500775 -285.736802) (xy 102.493018 -285.686702)
			(xy 102.492556 -285.661354) (xy 102.211632 -285.661354) (xy 102.211124 -285.687241) (xy 102.203025 -285.738379)
			(xy 102.187026 -285.787619) (xy 102.16352 -285.833751) (xy 102.133088 -285.875638) (xy 102.096478 -285.912248)
			(xy 102.054591 -285.94268) (xy 102.008459 -285.966186) (xy 101.959219 -285.982185) (xy 101.908081 -285.990284)
			(xy 101.856307 -285.990284) (xy 101.805169 -285.982185) (xy 101.755929 -285.966186) (xy 101.709797 -285.94268)
			(xy 101.66791 -285.912248) (xy 101.6313 -285.875638) (xy 101.600868 -285.833751) (xy 101.577362 -285.787619)
			(xy 101.561363 -285.738379) (xy 101.553264 -285.687241) (xy 101.552756 -285.661354) (xy 101.271832 -285.661354)
			(xy 101.271832 -285.661862) (xy 101.271253 -285.689379) (xy 101.262059 -285.74364) (xy 101.253544 -285.769812)
			(xy 101.245924 -285.79191) (xy 101.451156 -286.147256) (xy 101.474016 -286.151574) (xy 101.498827 -286.156786)
			(xy 101.546604 -286.173734) (xy 101.591223 -286.197799) (xy 101.63163 -286.228413) (xy 101.666872 -286.264855)
			(xy 101.696117 -286.306263) (xy 101.718676 -286.351662) (xy 101.734017 -286.399979) (xy 101.741777 -286.450077)
			(xy 101.74224 -286.475424) (xy 101.741732 -286.501331) (xy 101.733626 -286.552508) (xy 101.717614 -286.601787)
			(xy 101.694091 -286.647954) (xy 101.663635 -286.689873) (xy 101.626997 -286.726511) (xy 101.585078 -286.756967)
			(xy 101.538911 -286.78049) (xy 101.489632 -286.796502) (xy 101.438455 -286.804608) (xy 101.386641 -286.804608)
			(xy 101.335464 -286.796502) (xy 101.286185 -286.78049) (xy 101.240018 -286.756967) (xy 101.198099 -286.726511)
			(xy 101.161461 -286.689873) (xy 101.131005 -286.647954) (xy 101.107482 -286.601787) (xy 101.09147 -286.552508)
			(xy 101.083364 -286.501331) (xy 101.082856 -286.475424) (xy 101.083453 -286.447707) (xy 101.092774 -286.39306)
			(xy 101.101398 -286.366712) (xy 101.109272 -286.344614) (xy 100.904294 -285.989522) (xy 100.88118 -285.985204)
			(xy 100.856364 -285.980016) (xy 100.808584 -285.963065) (xy 100.763965 -285.938998) (xy 100.723557 -285.908381)
			(xy 100.688316 -285.871936) (xy 100.659071 -285.830525) (xy 100.636513 -285.785123) (xy 100.621175 -285.736802)
			(xy 100.613418 -285.686702) (xy 100.612956 -285.661354) (xy 100.332032 -285.661354) (xy 100.331524 -285.687241)
			(xy 100.323425 -285.738379) (xy 100.307426 -285.787619) (xy 100.28392 -285.833751) (xy 100.253488 -285.875638)
			(xy 100.216878 -285.912248) (xy 100.174991 -285.94268) (xy 100.128859 -285.966186) (xy 100.079619 -285.982185)
			(xy 100.028481 -285.990284) (xy 99.976707 -285.990284) (xy 99.925569 -285.982185) (xy 99.876329 -285.966186)
			(xy 99.830197 -285.94268) (xy 99.78831 -285.912248) (xy 99.7517 -285.875638) (xy 99.721268 -285.833751)
			(xy 99.697762 -285.787619) (xy 99.681763 -285.738379) (xy 99.673664 -285.687241) (xy 99.673156 -285.661354)
			(xy 99.392232 -285.661354) (xy 99.392232 -285.661862) (xy 99.391653 -285.689379) (xy 99.382459 -285.74364)
			(xy 99.373944 -285.769812) (xy 99.366324 -285.79191) (xy 99.571556 -286.147256) (xy 99.594416 -286.151574)
			(xy 99.619227 -286.156786) (xy 99.667004 -286.173734) (xy 99.711623 -286.197799) (xy 99.75203 -286.228413)
			(xy 99.787272 -286.264855) (xy 99.816517 -286.306263) (xy 99.839076 -286.351662) (xy 99.854417 -286.399979)
			(xy 99.862177 -286.450077) (xy 99.86264 -286.475424) (xy 99.862132 -286.501331) (xy 99.854026 -286.552508)
			(xy 99.838014 -286.601787) (xy 99.814491 -286.647954) (xy 99.784035 -286.689873) (xy 99.747397 -286.726511)
			(xy 99.705478 -286.756967) (xy 99.659311 -286.78049) (xy 99.610032 -286.796502) (xy 99.558855 -286.804608)
			(xy 99.507041 -286.804608) (xy 99.455864 -286.796502) (xy 99.406585 -286.78049) (xy 99.360418 -286.756967)
			(xy 99.318499 -286.726511) (xy 99.281861 -286.689873) (xy 99.251405 -286.647954) (xy 99.227882 -286.601787)
			(xy 99.21187 -286.552508) (xy 99.203764 -286.501331) (xy 99.203256 -286.475424) (xy 99.203853 -286.447707)
			(xy 99.213174 -286.39306) (xy 99.221798 -286.366712) (xy 99.229672 -286.344614) (xy 99.024694 -285.989522)
			(xy 99.00158 -285.985204) (xy 98.976764 -285.980016) (xy 98.928984 -285.963065) (xy 98.884365 -285.938998)
			(xy 98.843957 -285.908381) (xy 98.808716 -285.871936) (xy 98.779471 -285.830525) (xy 98.756913 -285.785123)
			(xy 98.741575 -285.736802) (xy 98.733818 -285.686702) (xy 98.733356 -285.661354) (xy 98.452432 -285.661354)
			(xy 98.451924 -285.687241) (xy 98.443825 -285.738379) (xy 98.427826 -285.787619) (xy 98.40432 -285.833751)
			(xy 98.373888 -285.875638) (xy 98.337278 -285.912248) (xy 98.295391 -285.94268) (xy 98.249259 -285.966186)
			(xy 98.200019 -285.982185) (xy 98.148881 -285.990284) (xy 98.097107 -285.990284) (xy 98.045969 -285.982185)
			(xy 97.996729 -285.966186) (xy 97.950597 -285.94268) (xy 97.90871 -285.912248) (xy 97.8721 -285.875638)
			(xy 97.841668 -285.833751) (xy 97.818162 -285.787619) (xy 97.802163 -285.738379) (xy 97.794064 -285.687241)
			(xy 97.793556 -285.661354) (xy 97.512632 -285.661354) (xy 97.512632 -285.661862) (xy 97.512053 -285.689379)
			(xy 97.502859 -285.74364) (xy 97.494344 -285.769812) (xy 97.486724 -285.79191) (xy 97.691956 -286.147256)
			(xy 97.714816 -286.151574) (xy 97.739627 -286.156786) (xy 97.787404 -286.173734) (xy 97.832023 -286.197799)
			(xy 97.87243 -286.228413) (xy 97.907672 -286.264855) (xy 97.936917 -286.306263) (xy 97.959476 -286.351662)
			(xy 97.974817 -286.399979) (xy 97.982577 -286.450077) (xy 97.98304 -286.475424) (xy 97.982532 -286.501331)
			(xy 97.974426 -286.552508) (xy 97.958414 -286.601787) (xy 97.934891 -286.647954) (xy 97.904435 -286.689873)
			(xy 97.867797 -286.726511) (xy 97.825878 -286.756967) (xy 97.779711 -286.78049) (xy 97.730432 -286.796502)
			(xy 97.679255 -286.804608) (xy 97.627441 -286.804608) (xy 97.576264 -286.796502) (xy 97.526985 -286.78049)
			(xy 97.480818 -286.756967) (xy 97.438899 -286.726511) (xy 97.402261 -286.689873) (xy 97.371805 -286.647954)
			(xy 97.348282 -286.601787) (xy 97.33227 -286.552508) (xy 97.324164 -286.501331) (xy 97.323656 -286.475424)
			(xy 97.324253 -286.447707) (xy 97.333574 -286.39306) (xy 97.342198 -286.366712) (xy 97.350072 -286.344614)
			(xy 97.145094 -285.989522) (xy 97.12198 -285.985204) (xy 97.097164 -285.980016) (xy 97.049384 -285.963065)
			(xy 97.004765 -285.938998) (xy 96.964357 -285.908381) (xy 96.929116 -285.871936) (xy 96.899871 -285.830525)
			(xy 96.877313 -285.785123) (xy 96.861975 -285.736802) (xy 96.854218 -285.686702) (xy 96.853756 -285.661354)
			(xy 96.572832 -285.661354) (xy 96.572324 -285.687241) (xy 96.564225 -285.738379) (xy 96.548226 -285.787619)
			(xy 96.52472 -285.833751) (xy 96.494288 -285.875638) (xy 96.457678 -285.912248) (xy 96.415791 -285.94268)
			(xy 96.369659 -285.966186) (xy 96.320419 -285.982185) (xy 96.269281 -285.990284) (xy 96.217507 -285.990284)
			(xy 96.166369 -285.982185) (xy 96.117129 -285.966186) (xy 96.070997 -285.94268) (xy 96.02911 -285.912248)
			(xy 95.9925 -285.875638) (xy 95.962068 -285.833751) (xy 95.938562 -285.787619) (xy 95.922563 -285.738379)
			(xy 95.914464 -285.687241) (xy 95.913956 -285.661354) (xy 95.633032 -285.661354) (xy 95.633032 -285.661862)
			(xy 95.632453 -285.689379) (xy 95.623259 -285.74364) (xy 95.614744 -285.769812) (xy 95.607124 -285.79191)
			(xy 95.812356 -286.147256) (xy 95.835216 -286.151574) (xy 95.860027 -286.156786) (xy 95.907804 -286.173734)
			(xy 95.952423 -286.197799) (xy 95.99283 -286.228413) (xy 96.028072 -286.264855) (xy 96.057317 -286.306263)
			(xy 96.079876 -286.351662) (xy 96.095217 -286.399979) (xy 96.102977 -286.450077) (xy 96.10344 -286.475424)
			(xy 96.102932 -286.501331) (xy 96.094826 -286.552508) (xy 96.078814 -286.601787) (xy 96.055291 -286.647954)
			(xy 96.024835 -286.689873) (xy 95.988197 -286.726511) (xy 95.946278 -286.756967) (xy 95.900111 -286.78049)
			(xy 95.850832 -286.796502) (xy 95.799655 -286.804608) (xy 95.747841 -286.804608) (xy 95.696664 -286.796502)
			(xy 95.647385 -286.78049) (xy 95.601218 -286.756967) (xy 95.559299 -286.726511) (xy 95.522661 -286.689873)
			(xy 95.492205 -286.647954) (xy 95.468682 -286.601787) (xy 95.45267 -286.552508) (xy 95.444564 -286.501331)
			(xy 95.444056 -286.475424) (xy 95.444653 -286.447707) (xy 95.453974 -286.39306) (xy 95.462598 -286.366712)
			(xy 95.470472 -286.344614) (xy 95.265494 -285.989522) (xy 95.24238 -285.985204) (xy 95.217564 -285.980016)
			(xy 95.169784 -285.963065) (xy 95.125165 -285.938998) (xy 95.084757 -285.908381) (xy 95.049516 -285.871936)
			(xy 95.020271 -285.830525) (xy 94.997713 -285.785123) (xy 94.982375 -285.736802) (xy 94.974618 -285.686702)
			(xy 94.974156 -285.661354) (xy 94.693232 -285.661354) (xy 94.692724 -285.687241) (xy 94.684625 -285.738379)
			(xy 94.668626 -285.787619) (xy 94.64512 -285.833751) (xy 94.614688 -285.875638) (xy 94.578078 -285.912248)
			(xy 94.536191 -285.94268) (xy 94.490059 -285.966186) (xy 94.440819 -285.982185) (xy 94.389681 -285.990284)
			(xy 94.337907 -285.990284) (xy 94.286769 -285.982185) (xy 94.237529 -285.966186) (xy 94.191397 -285.94268)
			(xy 94.14951 -285.912248) (xy 94.1129 -285.875638) (xy 94.082468 -285.833751) (xy 94.058962 -285.787619)
			(xy 94.042963 -285.738379) (xy 94.034864 -285.687241) (xy 94.034356 -285.661354) (xy 93.753432 -285.661354)
			(xy 93.753432 -285.661862) (xy 93.752853 -285.689379) (xy 93.743659 -285.74364) (xy 93.735144 -285.769812)
			(xy 93.727524 -285.79191) (xy 93.932756 -286.147256) (xy 93.955616 -286.151574) (xy 93.980427 -286.156786)
			(xy 94.028204 -286.173734) (xy 94.072823 -286.197799) (xy 94.11323 -286.228413) (xy 94.148472 -286.264855)
			(xy 94.177717 -286.306263) (xy 94.200276 -286.351662) (xy 94.215617 -286.399979) (xy 94.223377 -286.450077)
			(xy 94.22384 -286.475424) (xy 94.223332 -286.501331) (xy 94.215226 -286.552508) (xy 94.199214 -286.601787)
			(xy 94.175691 -286.647954) (xy 94.145235 -286.689873) (xy 94.108597 -286.726511) (xy 94.066678 -286.756967)
			(xy 94.020511 -286.78049) (xy 93.971232 -286.796502) (xy 93.920055 -286.804608) (xy 93.868241 -286.804608)
			(xy 93.817064 -286.796502) (xy 93.767785 -286.78049) (xy 93.721618 -286.756967) (xy 93.679699 -286.726511)
			(xy 93.643061 -286.689873) (xy 93.612605 -286.647954) (xy 93.589082 -286.601787) (xy 93.57307 -286.552508)
			(xy 93.564964 -286.501331) (xy 93.564456 -286.475424) (xy 93.565053 -286.447707) (xy 93.574374 -286.39306)
			(xy 93.582998 -286.366712) (xy 93.590872 -286.344614) (xy 93.385894 -285.989522) (xy 93.36278 -285.985204)
			(xy 93.337964 -285.980016) (xy 93.290184 -285.963065) (xy 93.245565 -285.938998) (xy 93.205157 -285.908381)
			(xy 93.169916 -285.871936) (xy 93.140671 -285.830525) (xy 93.118113 -285.785123) (xy 93.102775 -285.736802)
			(xy 93.095018 -285.686702) (xy 93.094556 -285.661354) (xy 92.813632 -285.661354) (xy 92.813124 -285.687241)
			(xy 92.805025 -285.738379) (xy 92.789026 -285.787619) (xy 92.76552 -285.833751) (xy 92.735088 -285.875638)
			(xy 92.698478 -285.912248) (xy 92.656591 -285.94268) (xy 92.610459 -285.966186) (xy 92.561219 -285.982185)
			(xy 92.510081 -285.990284) (xy 92.458307 -285.990284) (xy 92.407169 -285.982185) (xy 92.357929 -285.966186)
			(xy 92.311797 -285.94268) (xy 92.26991 -285.912248) (xy 92.2333 -285.875638) (xy 92.202868 -285.833751)
			(xy 92.179362 -285.787619) (xy 92.163363 -285.738379) (xy 92.155264 -285.687241) (xy 92.154756 -285.661354)
			(xy 91.87434 -285.661354) (xy 91.873738 -285.689071) (xy 91.86442 -285.743718) (xy 91.855798 -285.770066)
			(xy 91.847924 -285.792164) (xy 92.053156 -286.147256) (xy 92.076016 -286.151574) (xy 92.100827 -286.156786)
			(xy 92.148604 -286.173734) (xy 92.193223 -286.197799) (xy 92.23363 -286.228413) (xy 92.268872 -286.264855)
			(xy 92.298117 -286.306263) (xy 92.320676 -286.351662) (xy 92.336017 -286.399979) (xy 92.343777 -286.450077)
			(xy 92.34424 -286.475424) (xy 92.343732 -286.501331) (xy 92.335626 -286.552508) (xy 92.319614 -286.601787)
			(xy 92.296091 -286.647954) (xy 92.265635 -286.689873) (xy 92.228997 -286.726511) (xy 92.187078 -286.756967)
			(xy 92.140911 -286.78049) (xy 92.091632 -286.796502) (xy 92.040455 -286.804608) (xy 91.988641 -286.804608)
			(xy 91.937464 -286.796502) (xy 91.888185 -286.78049) (xy 91.842018 -286.756967) (xy 91.800099 -286.726511)
			(xy 91.763461 -286.689873) (xy 91.733005 -286.647954) (xy 91.709482 -286.601787) (xy 91.69347 -286.552508)
			(xy 91.685364 -286.501331) (xy 91.684856 -286.475424) (xy 91.685453 -286.447707) (xy 91.694774 -286.39306)
			(xy 91.703398 -286.366712) (xy 91.711272 -286.344614) (xy 91.50604 -285.989522) (xy 91.48318 -285.985204)
			(xy 91.458364 -285.980016) (xy 91.410584 -285.963065) (xy 91.365965 -285.938998) (xy 91.325557 -285.908381)
			(xy 91.290316 -285.871936) (xy 91.261071 -285.830525) (xy 91.238513 -285.785123) (xy 91.223175 -285.736802)
			(xy 91.215418 -285.686702) (xy 91.214956 -285.661354) (xy 90.93454 -285.661354) (xy 90.934032 -285.687261)
			(xy 90.925926 -285.738438) (xy 90.909914 -285.787717) (xy 90.886391 -285.833884) (xy 90.855935 -285.875803)
			(xy 90.819297 -285.912441) (xy 90.777378 -285.942897) (xy 90.731211 -285.96642) (xy 90.681932 -285.982432)
			(xy 90.630755 -285.990538) (xy 90.578941 -285.990538) (xy 90.527764 -285.982432) (xy 90.478485 -285.96642)
			(xy 90.432318 -285.942897) (xy 90.390399 -285.912441) (xy 90.353761 -285.875803) (xy 90.323305 -285.833884)
			(xy 90.299782 -285.787717) (xy 90.28377 -285.738438) (xy 90.275664 -285.687261) (xy 90.275156 -285.661354)
			(xy 89.994232 -285.661354) (xy 89.993689 -285.689062) (xy 89.984503 -285.743708) (xy 89.975944 -285.770066)
			(xy 89.96807 -285.792164) (xy 90.173302 -286.147256) (xy 90.196162 -286.151574) (xy 90.220961 -286.156781)
			(xy 90.268701 -286.173765) (xy 90.31328 -286.197855) (xy 90.353647 -286.228483) (xy 90.388851 -286.264927)
			(xy 90.418064 -286.30633) (xy 90.440597 -286.351715) (xy 90.455919 -286.400014) (xy 90.46367 -286.450088)
			(xy 90.464132 -286.475424) (xy 90.463624 -286.501311) (xy 90.455525 -286.552449) (xy 90.439526 -286.601689)
			(xy 90.41602 -286.647821) (xy 90.385588 -286.689708) (xy 90.348978 -286.726318) (xy 90.307091 -286.75675)
			(xy 90.260959 -286.780256) (xy 90.211719 -286.796255) (xy 90.160581 -286.804354) (xy 90.108807 -286.804354)
			(xy 90.057669 -286.796255) (xy 90.008429 -286.780256) (xy 89.962297 -286.75675) (xy 89.92041 -286.726318)
			(xy 89.8838 -286.689708) (xy 89.853368 -286.647821) (xy 89.829862 -286.601689) (xy 89.813863 -286.552449)
			(xy 89.805764 -286.501311) (xy 89.805256 -286.475424) (xy 89.805793 -286.447716) (xy 89.814983 -286.393069)
			(xy 89.823544 -286.366712) (xy 89.831418 -286.344614) (xy 89.626186 -285.989522) (xy 89.603326 -285.985204)
			(xy 89.57852 -285.980026) (xy 89.530779 -285.963039) (xy 89.486199 -285.938946) (xy 89.445832 -285.908314)
			(xy 89.410627 -285.871866) (xy 89.381416 -285.83046) (xy 89.358884 -285.785071) (xy 89.343564 -285.736769)
			(xy 89.335817 -285.686691) (xy 89.335356 -285.661354) (xy 2.509012 -285.661354) (xy 2.509012 -286.475424)
			(xy 86.046056 -286.475424) (xy 86.046564 -286.449537) (xy 86.054663 -286.398399) (xy 86.070662 -286.349159)
			(xy 86.094168 -286.303027) (xy 86.1246 -286.26114) (xy 86.16121 -286.22453) (xy 86.203097 -286.194098)
			(xy 86.249229 -286.170592) (xy 86.298469 -286.154593) (xy 86.349607 -286.146494) (xy 86.401381 -286.146494)
			(xy 86.452519 -286.154593) (xy 86.501759 -286.170592) (xy 86.547891 -286.194098) (xy 86.589778 -286.22453)
			(xy 86.626388 -286.26114) (xy 86.65682 -286.303027) (xy 86.680326 -286.349159) (xy 86.696325 -286.398399)
			(xy 86.704424 -286.449537) (xy 86.704932 -286.475424) (xy 86.704407 -286.503132) (xy 86.695209 -286.557779)
			(xy 86.686644 -286.584136) (xy 86.679024 -286.60598) (xy 86.884002 -286.961072) (xy 86.906862 -286.96539)
			(xy 86.931665 -286.970582) (xy 86.979406 -286.987567) (xy 87.023985 -287.011659) (xy 87.064353 -287.042288)
			(xy 87.099557 -287.078734) (xy 87.12877 -287.120139) (xy 87.151302 -287.165526) (xy 87.166622 -287.213827)
			(xy 87.174371 -287.263904) (xy 87.174832 -287.28924) (xy 87.174324 -287.315127) (xy 87.166225 -287.366265)
			(xy 87.150226 -287.415505) (xy 87.12672 -287.461637) (xy 87.096288 -287.503524) (xy 87.059678 -287.540134)
			(xy 87.017791 -287.570566) (xy 86.971659 -287.594072) (xy 86.922419 -287.610071) (xy 86.871281 -287.61817)
			(xy 86.819507 -287.61817) (xy 86.768369 -287.610071) (xy 86.719129 -287.594072) (xy 86.672997 -287.570566)
			(xy 86.63111 -287.540134) (xy 86.5945 -287.503524) (xy 86.564068 -287.461637) (xy 86.540562 -287.415505)
			(xy 86.524563 -287.366265) (xy 86.516464 -287.315127) (xy 86.515956 -287.28924) (xy 86.516497 -287.261532)
			(xy 86.525685 -287.206886) (xy 86.534244 -287.180528) (xy 86.541864 -287.158684) (xy 86.336886 -286.803592)
			(xy 86.314026 -286.799274) (xy 86.289236 -286.79403) (xy 86.241499 -286.777048) (xy 86.196923 -286.752961)
			(xy 86.156558 -286.722338) (xy 86.121354 -286.685898) (xy 86.09214 -286.644501) (xy 86.069605 -286.599121)
			(xy 86.054278 -286.550828) (xy 86.046522 -286.500758) (xy 86.046056 -286.475424) (xy 2.509012 -286.475424)
			(xy 2.509012 -288.917126) (xy 88.395556 -288.917126) (xy 88.396056 -288.891781) (xy 88.403825 -288.84169)
			(xy 88.419169 -288.793377) (xy 88.441727 -288.747983) (xy 88.470967 -288.706576) (xy 88.506199 -288.670131)
			(xy 88.546595 -288.639509) (xy 88.591201 -288.61543) (xy 88.638966 -288.598461) (xy 88.66378 -288.593276)
			(xy 88.68664 -288.588958) (xy 88.891618 -288.233866) (xy 88.883744 -288.212022) (xy 88.875171 -288.185601)
			(xy 88.86597 -288.130828) (xy 88.865456 -288.103056) (xy 88.865964 -288.077169) (xy 88.874063 -288.026031)
			(xy 88.890062 -287.976791) (xy 88.913568 -287.930659) (xy 88.944 -287.888772) (xy 88.98061 -287.852162)
			(xy 89.022497 -287.82173) (xy 89.068629 -287.798224) (xy 89.117869 -287.782225) (xy 89.169007 -287.774126)
			(xy 89.220781 -287.774126) (xy 89.271919 -287.782225) (xy 89.321159 -287.798224) (xy 89.367291 -287.82173)
			(xy 89.409178 -287.852162) (xy 89.445788 -287.888772) (xy 89.47622 -287.930659) (xy 89.499726 -287.976791)
			(xy 89.515725 -288.026031) (xy 89.523824 -288.077169) (xy 89.524332 -288.103056) (xy 89.523874 -288.128391)
			(xy 89.516115 -288.178463) (xy 89.500786 -288.226759) (xy 89.47825 -288.272141) (xy 89.449037 -288.313542)
			(xy 89.413835 -288.349987) (xy 89.373471 -288.380617) (xy 89.328897 -288.404713) (xy 89.281162 -288.421706)
			(xy 89.256362 -288.426906) (xy 89.233502 -288.431224) (xy 89.028524 -288.786316) (xy 89.036398 -288.80816)
			(xy 89.045049 -288.834567) (xy 89.054366 -288.889344) (xy 89.05494 -288.917126) (xy 90.275156 -288.917126)
			(xy 90.275656 -288.891781) (xy 90.283425 -288.84169) (xy 90.298769 -288.793377) (xy 90.321327 -288.747983)
			(xy 90.350567 -288.706576) (xy 90.385799 -288.670131) (xy 90.426195 -288.639509) (xy 90.470801 -288.61543)
			(xy 90.518566 -288.598461) (xy 90.54338 -288.593276) (xy 90.56624 -288.588958) (xy 90.771218 -288.233866)
			(xy 90.763344 -288.212022) (xy 90.754771 -288.185601) (xy 90.74557 -288.130828) (xy 90.745056 -288.103056)
			(xy 90.745564 -288.077169) (xy 90.753663 -288.026031) (xy 90.769662 -287.976791) (xy 90.793168 -287.930659)
			(xy 90.8236 -287.888772) (xy 90.86021 -287.852162) (xy 90.902097 -287.82173) (xy 90.948229 -287.798224)
			(xy 90.997469 -287.782225) (xy 91.048607 -287.774126) (xy 91.100381 -287.774126) (xy 91.151519 -287.782225)
			(xy 91.200759 -287.798224) (xy 91.246891 -287.82173) (xy 91.288778 -287.852162) (xy 91.325388 -287.888772)
			(xy 91.35582 -287.930659) (xy 91.379326 -287.976791) (xy 91.395325 -288.026031) (xy 91.403424 -288.077169)
			(xy 91.403932 -288.103056) (xy 91.403474 -288.128391) (xy 91.395715 -288.178463) (xy 91.380386 -288.226759)
			(xy 91.35785 -288.272141) (xy 91.328637 -288.313542) (xy 91.293435 -288.349987) (xy 91.253071 -288.380617)
			(xy 91.208497 -288.404713) (xy 91.160762 -288.421706) (xy 91.135962 -288.426906) (xy 91.113102 -288.431224)
			(xy 90.908124 -288.786316) (xy 90.915998 -288.80816) (xy 90.924649 -288.834567) (xy 90.933966 -288.889344)
			(xy 90.93454 -288.917126) (xy 91.214956 -288.917126) (xy 91.215464 -288.891219) (xy 91.22357 -288.840042)
			(xy 91.239582 -288.790763) (xy 91.263105 -288.744596) (xy 91.293561 -288.702677) (xy 91.330199 -288.666039)
			(xy 91.372118 -288.635583) (xy 91.418285 -288.61206) (xy 91.467564 -288.596048) (xy 91.518741 -288.587942)
			(xy 91.570555 -288.587942) (xy 91.621732 -288.596048) (xy 91.671011 -288.61206) (xy 91.717178 -288.635583)
			(xy 91.759097 -288.666039) (xy 91.795735 -288.702677) (xy 91.826191 -288.744596) (xy 91.849714 -288.790763)
			(xy 91.865726 -288.840042) (xy 91.873832 -288.891219) (xy 91.87434 -288.917126) (xy 92.154756 -288.917126)
			(xy 92.155256 -288.891781) (xy 92.163025 -288.84169) (xy 92.178369 -288.793377) (xy 92.200927 -288.747983)
			(xy 92.230167 -288.706576) (xy 92.265399 -288.670131) (xy 92.305795 -288.639509) (xy 92.350401 -288.61543)
			(xy 92.398166 -288.598461) (xy 92.42298 -288.593276) (xy 92.44584 -288.588958) (xy 92.651072 -288.233866)
			(xy 92.643198 -288.211768) (xy 92.634576 -288.185419) (xy 92.625249 -288.130773) (xy 92.624656 -288.103056)
			(xy 92.625164 -288.077149) (xy 92.63327 -288.025972) (xy 92.649282 -287.976693) (xy 92.672805 -287.930526)
			(xy 92.703261 -287.888607) (xy 92.739899 -287.851969) (xy 92.781818 -287.821513) (xy 92.827985 -287.79799)
			(xy 92.877264 -287.781978) (xy 92.928441 -287.773872) (xy 92.980255 -287.773872) (xy 93.031432 -287.781978)
			(xy 93.080711 -287.79799) (xy 93.126878 -287.821513) (xy 93.168797 -287.851969) (xy 93.205435 -287.888607)
			(xy 93.235891 -287.930526) (xy 93.259414 -287.976693) (xy 93.275426 -288.025972) (xy 93.283532 -288.077149)
			(xy 93.28404 -288.103056) (xy 93.283618 -288.128404) (xy 93.275836 -288.178499) (xy 93.26048 -288.226813)
			(xy 93.237912 -288.272208) (xy 93.208662 -288.313614) (xy 93.173421 -288.350057) (xy 93.133018 -288.380678)
			(xy 93.088405 -288.404755) (xy 93.040632 -288.421722) (xy 93.015816 -288.426906) (xy 92.992956 -288.431224)
			(xy 92.787724 -288.786316) (xy 92.795598 -288.808414) (xy 92.80424 -288.834757) (xy 92.813554 -288.889407)
			(xy 92.81414 -288.917126) (xy 93.094556 -288.917126) (xy 93.095064 -288.891219) (xy 93.10317 -288.840042)
			(xy 93.119182 -288.790763) (xy 93.142705 -288.744596) (xy 93.173161 -288.702677) (xy 93.209799 -288.666039)
			(xy 93.251718 -288.635583) (xy 93.297885 -288.61206) (xy 93.347164 -288.596048) (xy 93.398341 -288.587942)
			(xy 93.450155 -288.587942) (xy 93.501332 -288.596048) (xy 93.550611 -288.61206) (xy 93.596778 -288.635583)
			(xy 93.638697 -288.666039) (xy 93.675335 -288.702677) (xy 93.705791 -288.744596) (xy 93.729314 -288.790763)
			(xy 93.745326 -288.840042) (xy 93.753432 -288.891219) (xy 93.75394 -288.917126) (xy 94.034356 -288.917126)
			(xy 94.034856 -288.891781) (xy 94.042625 -288.84169) (xy 94.057969 -288.793377) (xy 94.080527 -288.747983)
			(xy 94.109767 -288.706576) (xy 94.144999 -288.670131) (xy 94.185395 -288.639509) (xy 94.230001 -288.61543)
			(xy 94.277766 -288.598461) (xy 94.30258 -288.593276) (xy 94.32544 -288.588958) (xy 94.530672 -288.233866)
			(xy 94.522798 -288.211768) (xy 94.514176 -288.185419) (xy 94.504849 -288.130773) (xy 94.504256 -288.103056)
			(xy 94.504764 -288.077149) (xy 94.51287 -288.025972) (xy 94.528882 -287.976693) (xy 94.552405 -287.930526)
			(xy 94.582861 -287.888607) (xy 94.619499 -287.851969) (xy 94.661418 -287.821513) (xy 94.707585 -287.79799)
			(xy 94.756864 -287.781978) (xy 94.808041 -287.773872) (xy 94.859855 -287.773872) (xy 94.911032 -287.781978)
			(xy 94.960311 -287.79799) (xy 95.006478 -287.821513) (xy 95.048397 -287.851969) (xy 95.085035 -287.888607)
			(xy 95.115491 -287.930526) (xy 95.139014 -287.976693) (xy 95.155026 -288.025972) (xy 95.163132 -288.077149)
			(xy 95.16364 -288.103056) (xy 95.163218 -288.128404) (xy 95.155436 -288.178499) (xy 95.14008 -288.226813)
			(xy 95.117512 -288.272208) (xy 95.088262 -288.313614) (xy 95.053021 -288.350057) (xy 95.012618 -288.380678)
			(xy 94.968005 -288.404755) (xy 94.920232 -288.421722) (xy 94.895416 -288.426906) (xy 94.872556 -288.431224)
			(xy 94.667324 -288.786316) (xy 94.675198 -288.808414) (xy 94.68384 -288.834757) (xy 94.693154 -288.889407)
			(xy 94.69374 -288.917126) (xy 94.974156 -288.917126) (xy 94.974664 -288.891219) (xy 94.98277 -288.840042)
			(xy 94.998782 -288.790763) (xy 95.022305 -288.744596) (xy 95.052761 -288.702677) (xy 95.089399 -288.666039)
			(xy 95.131318 -288.635583) (xy 95.177485 -288.61206) (xy 95.226764 -288.596048) (xy 95.277941 -288.587942)
			(xy 95.329755 -288.587942) (xy 95.380932 -288.596048) (xy 95.430211 -288.61206) (xy 95.476378 -288.635583)
			(xy 95.518297 -288.666039) (xy 95.554935 -288.702677) (xy 95.585391 -288.744596) (xy 95.608914 -288.790763)
			(xy 95.624926 -288.840042) (xy 95.633032 -288.891219) (xy 95.63354 -288.917126) (xy 95.913956 -288.917126)
			(xy 95.914456 -288.891781) (xy 95.922225 -288.84169) (xy 95.937569 -288.793377) (xy 95.960127 -288.747983)
			(xy 95.989367 -288.706576) (xy 96.024599 -288.670131) (xy 96.064995 -288.639509) (xy 96.109601 -288.61543)
			(xy 96.157366 -288.598461) (xy 96.18218 -288.593276) (xy 96.20504 -288.588958) (xy 96.410272 -288.233866)
			(xy 96.402398 -288.211768) (xy 96.393776 -288.185419) (xy 96.384449 -288.130773) (xy 96.383856 -288.103056)
			(xy 96.384364 -288.077149) (xy 96.39247 -288.025972) (xy 96.408482 -287.976693) (xy 96.432005 -287.930526)
			(xy 96.462461 -287.888607) (xy 96.499099 -287.851969) (xy 96.541018 -287.821513) (xy 96.587185 -287.79799)
			(xy 96.636464 -287.781978) (xy 96.687641 -287.773872) (xy 96.739455 -287.773872) (xy 96.790632 -287.781978)
			(xy 96.839911 -287.79799) (xy 96.886078 -287.821513) (xy 96.927997 -287.851969) (xy 96.964635 -287.888607)
			(xy 96.995091 -287.930526) (xy 97.018614 -287.976693) (xy 97.034626 -288.025972) (xy 97.042732 -288.077149)
			(xy 97.04324 -288.103056) (xy 97.042818 -288.128404) (xy 97.035036 -288.178499) (xy 97.01968 -288.226813)
			(xy 96.997112 -288.272208) (xy 96.967862 -288.313614) (xy 96.932621 -288.350057) (xy 96.892218 -288.380678)
			(xy 96.847605 -288.404755) (xy 96.799832 -288.421722) (xy 96.775016 -288.426906) (xy 96.752156 -288.431224)
			(xy 96.546924 -288.786316) (xy 96.554798 -288.808414) (xy 96.56344 -288.834757) (xy 96.572754 -288.889407)
			(xy 96.57334 -288.917126) (xy 96.853756 -288.917126) (xy 96.854264 -288.891219) (xy 96.86237 -288.840042)
			(xy 96.878382 -288.790763) (xy 96.901905 -288.744596) (xy 96.932361 -288.702677) (xy 96.968999 -288.666039)
			(xy 97.010918 -288.635583) (xy 97.057085 -288.61206) (xy 97.106364 -288.596048) (xy 97.157541 -288.587942)
			(xy 97.209355 -288.587942) (xy 97.260532 -288.596048) (xy 97.309811 -288.61206) (xy 97.355978 -288.635583)
			(xy 97.397897 -288.666039) (xy 97.434535 -288.702677) (xy 97.464991 -288.744596) (xy 97.488514 -288.790763)
			(xy 97.504526 -288.840042) (xy 97.512632 -288.891219) (xy 97.51314 -288.917126) (xy 97.793556 -288.917126)
			(xy 97.794056 -288.891781) (xy 97.801825 -288.84169) (xy 97.817169 -288.793377) (xy 97.839727 -288.747983)
			(xy 97.868967 -288.706576) (xy 97.904199 -288.670131) (xy 97.944595 -288.639509) (xy 97.989201 -288.61543)
			(xy 98.036966 -288.598461) (xy 98.06178 -288.593276) (xy 98.08464 -288.588958) (xy 98.289872 -288.233866)
			(xy 98.281998 -288.211768) (xy 98.273376 -288.185419) (xy 98.264049 -288.130773) (xy 98.263456 -288.103056)
			(xy 98.263964 -288.077149) (xy 98.27207 -288.025972) (xy 98.288082 -287.976693) (xy 98.311605 -287.930526)
			(xy 98.342061 -287.888607) (xy 98.378699 -287.851969) (xy 98.420618 -287.821513) (xy 98.466785 -287.79799)
			(xy 98.516064 -287.781978) (xy 98.567241 -287.773872) (xy 98.619055 -287.773872) (xy 98.670232 -287.781978)
			(xy 98.719511 -287.79799) (xy 98.765678 -287.821513) (xy 98.807597 -287.851969) (xy 98.844235 -287.888607)
			(xy 98.874691 -287.930526) (xy 98.898214 -287.976693) (xy 98.914226 -288.025972) (xy 98.922332 -288.077149)
			(xy 98.92284 -288.103056) (xy 98.922418 -288.128404) (xy 98.914636 -288.178499) (xy 98.89928 -288.226813)
			(xy 98.876712 -288.272208) (xy 98.847462 -288.313614) (xy 98.812221 -288.350057) (xy 98.771818 -288.380678)
			(xy 98.727205 -288.404755) (xy 98.679432 -288.421722) (xy 98.654616 -288.426906) (xy 98.631756 -288.431224)
			(xy 98.426524 -288.786316) (xy 98.434398 -288.808414) (xy 98.44304 -288.834757) (xy 98.452354 -288.889407)
			(xy 98.45294 -288.917126) (xy 98.733356 -288.917126) (xy 98.733864 -288.891219) (xy 98.74197 -288.840042)
			(xy 98.757982 -288.790763) (xy 98.781505 -288.744596) (xy 98.811961 -288.702677) (xy 98.848599 -288.666039)
			(xy 98.890518 -288.635583) (xy 98.936685 -288.61206) (xy 98.985964 -288.596048) (xy 99.037141 -288.587942)
			(xy 99.088955 -288.587942) (xy 99.140132 -288.596048) (xy 99.189411 -288.61206) (xy 99.235578 -288.635583)
			(xy 99.277497 -288.666039) (xy 99.314135 -288.702677) (xy 99.344591 -288.744596) (xy 99.368114 -288.790763)
			(xy 99.384126 -288.840042) (xy 99.392232 -288.891219) (xy 99.39274 -288.917126) (xy 99.673156 -288.917126)
			(xy 99.673656 -288.891781) (xy 99.681425 -288.84169) (xy 99.696769 -288.793377) (xy 99.719327 -288.747983)
			(xy 99.748567 -288.706576) (xy 99.783799 -288.670131) (xy 99.824195 -288.639509) (xy 99.868801 -288.61543)
			(xy 99.916566 -288.598461) (xy 99.94138 -288.593276) (xy 99.96424 -288.588958) (xy 100.169472 -288.233866)
			(xy 100.161598 -288.211768) (xy 100.152976 -288.185419) (xy 100.143649 -288.130773) (xy 100.143056 -288.103056)
			(xy 100.143564 -288.077149) (xy 100.15167 -288.025972) (xy 100.167682 -287.976693) (xy 100.191205 -287.930526)
			(xy 100.221661 -287.888607) (xy 100.258299 -287.851969) (xy 100.300218 -287.821513) (xy 100.346385 -287.79799)
			(xy 100.395664 -287.781978) (xy 100.446841 -287.773872) (xy 100.498655 -287.773872) (xy 100.549832 -287.781978)
			(xy 100.599111 -287.79799) (xy 100.645278 -287.821513) (xy 100.687197 -287.851969) (xy 100.723835 -287.888607)
			(xy 100.754291 -287.930526) (xy 100.777814 -287.976693) (xy 100.793826 -288.025972) (xy 100.801932 -288.077149)
			(xy 100.80244 -288.103056) (xy 100.802018 -288.128404) (xy 100.794236 -288.178499) (xy 100.77888 -288.226813)
			(xy 100.756312 -288.272208) (xy 100.727062 -288.313614) (xy 100.691821 -288.350057) (xy 100.651418 -288.380678)
			(xy 100.606805 -288.404755) (xy 100.559032 -288.421722) (xy 100.534216 -288.426906) (xy 100.511356 -288.431224)
			(xy 100.306124 -288.786316) (xy 100.313998 -288.808414) (xy 100.32264 -288.834757) (xy 100.331954 -288.889407)
			(xy 100.33254 -288.917126) (xy 100.612956 -288.917126) (xy 100.613464 -288.891219) (xy 100.62157 -288.840042)
			(xy 100.637582 -288.790763) (xy 100.661105 -288.744596) (xy 100.691561 -288.702677) (xy 100.728199 -288.666039)
			(xy 100.770118 -288.635583) (xy 100.816285 -288.61206) (xy 100.865564 -288.596048) (xy 100.916741 -288.587942)
			(xy 100.968555 -288.587942) (xy 101.019732 -288.596048) (xy 101.069011 -288.61206) (xy 101.115178 -288.635583)
			(xy 101.157097 -288.666039) (xy 101.193735 -288.702677) (xy 101.224191 -288.744596) (xy 101.247714 -288.790763)
			(xy 101.263726 -288.840042) (xy 101.271832 -288.891219) (xy 101.27234 -288.917126) (xy 101.552756 -288.917126)
			(xy 101.553256 -288.891781) (xy 101.561025 -288.84169) (xy 101.576369 -288.793377) (xy 101.598927 -288.747983)
			(xy 101.628167 -288.706576) (xy 101.663399 -288.670131) (xy 101.703795 -288.639509) (xy 101.748401 -288.61543)
			(xy 101.796166 -288.598461) (xy 101.82098 -288.593276) (xy 101.84384 -288.588958) (xy 102.049072 -288.233866)
			(xy 102.041198 -288.211768) (xy 102.032576 -288.185419) (xy 102.023249 -288.130773) (xy 102.022656 -288.103056)
			(xy 102.023164 -288.077149) (xy 102.03127 -288.025972) (xy 102.047282 -287.976693) (xy 102.070805 -287.930526)
			(xy 102.101261 -287.888607) (xy 102.137899 -287.851969) (xy 102.179818 -287.821513) (xy 102.225985 -287.79799)
			(xy 102.275264 -287.781978) (xy 102.326441 -287.773872) (xy 102.378255 -287.773872) (xy 102.429432 -287.781978)
			(xy 102.478711 -287.79799) (xy 102.524878 -287.821513) (xy 102.566797 -287.851969) (xy 102.603435 -287.888607)
			(xy 102.633891 -287.930526) (xy 102.657414 -287.976693) (xy 102.673426 -288.025972) (xy 102.681532 -288.077149)
			(xy 102.68204 -288.103056) (xy 102.681618 -288.128404) (xy 102.673836 -288.178499) (xy 102.65848 -288.226813)
			(xy 102.635912 -288.272208) (xy 102.606662 -288.313614) (xy 102.571421 -288.350057) (xy 102.531018 -288.380678)
			(xy 102.486405 -288.404755) (xy 102.438632 -288.421722) (xy 102.413816 -288.426906) (xy 102.390956 -288.431224)
			(xy 102.185724 -288.786316) (xy 102.193598 -288.808414) (xy 102.20224 -288.834757) (xy 102.211554 -288.889407)
			(xy 102.21214 -288.917126) (xy 102.492556 -288.917126) (xy 102.493064 -288.891219) (xy 102.50117 -288.840042)
			(xy 102.517182 -288.790763) (xy 102.540705 -288.744596) (xy 102.571161 -288.702677) (xy 102.607799 -288.666039)
			(xy 102.649718 -288.635583) (xy 102.695885 -288.61206) (xy 102.745164 -288.596048) (xy 102.796341 -288.587942)
			(xy 102.848155 -288.587942) (xy 102.899332 -288.596048) (xy 102.948611 -288.61206) (xy 102.994778 -288.635583)
			(xy 103.036697 -288.666039) (xy 103.073335 -288.702677) (xy 103.103791 -288.744596) (xy 103.127314 -288.790763)
			(xy 103.143326 -288.840042) (xy 103.151432 -288.891219) (xy 103.15194 -288.917126) (xy 103.432356 -288.917126)
			(xy 103.432856 -288.891781) (xy 103.440625 -288.84169) (xy 103.455969 -288.793377) (xy 103.478527 -288.747983)
			(xy 103.507767 -288.706576) (xy 103.542999 -288.670131) (xy 103.583395 -288.639509) (xy 103.628001 -288.61543)
			(xy 103.675766 -288.598461) (xy 103.70058 -288.593276) (xy 103.72344 -288.588958) (xy 103.928672 -288.233866)
			(xy 103.920798 -288.211768) (xy 103.912176 -288.185419) (xy 103.902849 -288.130773) (xy 103.902256 -288.103056)
			(xy 103.902764 -288.077149) (xy 103.91087 -288.025972) (xy 103.926882 -287.976693) (xy 103.950405 -287.930526)
			(xy 103.980861 -287.888607) (xy 104.017499 -287.851969) (xy 104.059418 -287.821513) (xy 104.105585 -287.79799)
			(xy 104.154864 -287.781978) (xy 104.206041 -287.773872) (xy 104.257855 -287.773872) (xy 104.309032 -287.781978)
			(xy 104.358311 -287.79799) (xy 104.404478 -287.821513) (xy 104.446397 -287.851969) (xy 104.483035 -287.888607)
			(xy 104.513491 -287.930526) (xy 104.537014 -287.976693) (xy 104.553026 -288.025972) (xy 104.561132 -288.077149)
			(xy 104.56164 -288.103056) (xy 120.818656 -288.103056) (xy 120.819164 -288.077149) (xy 120.82727 -288.025972)
			(xy 120.843282 -287.976693) (xy 120.866805 -287.930526) (xy 120.897261 -287.888607) (xy 120.933899 -287.851969)
			(xy 120.975818 -287.821513) (xy 121.021985 -287.79799) (xy 121.071264 -287.781978) (xy 121.122441 -287.773872)
			(xy 121.174255 -287.773872) (xy 121.225432 -287.781978) (xy 121.274711 -287.79799) (xy 121.320878 -287.821513)
			(xy 121.362797 -287.851969) (xy 121.399435 -287.888607) (xy 121.429891 -287.930526) (xy 121.453414 -287.976693)
			(xy 121.469426 -288.025972) (xy 121.477532 -288.077149) (xy 121.47804 -288.103056) (xy 122.698256 -288.103056)
			(xy 122.698764 -288.077149) (xy 122.70687 -288.025972) (xy 122.722882 -287.976693) (xy 122.746405 -287.930526)
			(xy 122.776861 -287.888607) (xy 122.813499 -287.851969) (xy 122.855418 -287.821513) (xy 122.901585 -287.79799)
			(xy 122.950864 -287.781978) (xy 123.002041 -287.773872) (xy 123.053855 -287.773872) (xy 123.105032 -287.781978)
			(xy 123.154311 -287.79799) (xy 123.200478 -287.821513) (xy 123.242397 -287.851969) (xy 123.279035 -287.888607)
			(xy 123.309491 -287.930526) (xy 123.333014 -287.976693) (xy 123.349026 -288.025972) (xy 123.357132 -288.077149)
			(xy 123.35764 -288.103056) (xy 124.577856 -288.103056) (xy 124.578364 -288.077149) (xy 124.58647 -288.025972)
			(xy 124.602482 -287.976693) (xy 124.626005 -287.930526) (xy 124.656461 -287.888607) (xy 124.693099 -287.851969)
			(xy 124.735018 -287.821513) (xy 124.781185 -287.79799) (xy 124.830464 -287.781978) (xy 124.881641 -287.773872)
			(xy 124.933455 -287.773872) (xy 124.984632 -287.781978) (xy 125.033911 -287.79799) (xy 125.080078 -287.821513)
			(xy 125.121997 -287.851969) (xy 125.158635 -287.888607) (xy 125.189091 -287.930526) (xy 125.212614 -287.976693)
			(xy 125.228626 -288.025972) (xy 125.236732 -288.077149) (xy 125.23724 -288.103056) (xy 126.457456 -288.103056)
			(xy 126.457964 -288.077149) (xy 126.46607 -288.025972) (xy 126.482082 -287.976693) (xy 126.505605 -287.930526)
			(xy 126.536061 -287.888607) (xy 126.572699 -287.851969) (xy 126.614618 -287.821513) (xy 126.660785 -287.79799)
			(xy 126.710064 -287.781978) (xy 126.761241 -287.773872) (xy 126.813055 -287.773872) (xy 126.864232 -287.781978)
			(xy 126.913511 -287.79799) (xy 126.959678 -287.821513) (xy 127.001597 -287.851969) (xy 127.038235 -287.888607)
			(xy 127.068691 -287.930526) (xy 127.092214 -287.976693) (xy 127.108226 -288.025972) (xy 127.116332 -288.077149)
			(xy 127.11684 -288.103056) (xy 128.337056 -288.103056) (xy 128.337564 -288.077149) (xy 128.34567 -288.025972)
			(xy 128.361682 -287.976693) (xy 128.385205 -287.930526) (xy 128.415661 -287.888607) (xy 128.452299 -287.851969)
			(xy 128.494218 -287.821513) (xy 128.540385 -287.79799) (xy 128.589664 -287.781978) (xy 128.640841 -287.773872)
			(xy 128.692655 -287.773872) (xy 128.743832 -287.781978) (xy 128.793111 -287.79799) (xy 128.839278 -287.821513)
			(xy 128.881197 -287.851969) (xy 128.917835 -287.888607) (xy 128.948291 -287.930526) (xy 128.971814 -287.976693)
			(xy 128.987826 -288.025972) (xy 128.995932 -288.077149) (xy 128.99644 -288.103056) (xy 130.216656 -288.103056)
			(xy 130.217164 -288.077149) (xy 130.22527 -288.025972) (xy 130.241282 -287.976693) (xy 130.264805 -287.930526)
			(xy 130.295261 -287.888607) (xy 130.331899 -287.851969) (xy 130.373818 -287.821513) (xy 130.419985 -287.79799)
			(xy 130.469264 -287.781978) (xy 130.520441 -287.773872) (xy 130.572255 -287.773872) (xy 130.623432 -287.781978)
			(xy 130.672711 -287.79799) (xy 130.718878 -287.821513) (xy 130.760797 -287.851969) (xy 130.797435 -287.888607)
			(xy 130.827891 -287.930526) (xy 130.851414 -287.976693) (xy 130.867426 -288.025972) (xy 130.875532 -288.077149)
			(xy 130.87604 -288.103056) (xy 132.096256 -288.103056) (xy 132.096764 -288.077149) (xy 132.10487 -288.025972)
			(xy 132.120882 -287.976693) (xy 132.144405 -287.930526) (xy 132.174861 -287.888607) (xy 132.211499 -287.851969)
			(xy 132.253418 -287.821513) (xy 132.299585 -287.79799) (xy 132.348864 -287.781978) (xy 132.400041 -287.773872)
			(xy 132.451855 -287.773872) (xy 132.503032 -287.781978) (xy 132.552311 -287.79799) (xy 132.598478 -287.821513)
			(xy 132.640397 -287.851969) (xy 132.677035 -287.888607) (xy 132.707491 -287.930526) (xy 132.731014 -287.976693)
			(xy 132.747026 -288.025972) (xy 132.755132 -288.077149) (xy 132.75564 -288.103056) (xy 134.915656 -288.103056)
			(xy 134.916164 -288.077149) (xy 134.92427 -288.025972) (xy 134.940282 -287.976693) (xy 134.963805 -287.930526)
			(xy 134.994261 -287.888607) (xy 135.030899 -287.851969) (xy 135.072818 -287.821513) (xy 135.118985 -287.79799)
			(xy 135.168264 -287.781978) (xy 135.219441 -287.773872) (xy 135.271255 -287.773872) (xy 135.322432 -287.781978)
			(xy 135.371711 -287.79799) (xy 135.417878 -287.821513) (xy 135.459797 -287.851969) (xy 135.496435 -287.888607)
			(xy 135.526891 -287.930526) (xy 135.550414 -287.976693) (xy 135.566426 -288.025972) (xy 135.574532 -288.077149)
			(xy 135.57504 -288.103056) (xy 135.574438 -288.130773) (xy 135.56512 -288.18542) (xy 135.556498 -288.211768)
			(xy 135.548624 -288.233866) (xy 135.753856 -288.588958) (xy 135.776716 -288.593276) (xy 135.801527 -288.598486)
			(xy 135.849305 -288.615434) (xy 135.893924 -288.6395) (xy 135.934331 -288.670114) (xy 135.969573 -288.706556)
			(xy 135.998818 -288.747964) (xy 136.021377 -288.793363) (xy 136.036717 -288.841681) (xy 136.044477 -288.891779)
			(xy 136.04494 -288.917126) (xy 336.335624 -288.917126) (xy 336.336149 -288.891782) (xy 336.343918 -288.841693)
			(xy 336.359261 -288.793383) (xy 336.381816 -288.74799) (xy 336.411052 -288.706584) (xy 336.446281 -288.67014)
			(xy 336.486672 -288.639516) (xy 336.531274 -288.615435) (xy 336.579036 -288.598463) (xy 336.603848 -288.593276)
			(xy 336.626708 -288.588958) (xy 336.831686 -288.233866) (xy 336.823812 -288.212022) (xy 336.815238 -288.185602)
			(xy 336.806038 -288.130828) (xy 336.805524 -288.103056) (xy 336.806032 -288.077169) (xy 336.814131 -288.026031)
			(xy 336.83013 -287.976791) (xy 336.853636 -287.930659) (xy 336.884068 -287.888772) (xy 336.920678 -287.852162)
			(xy 336.962565 -287.82173) (xy 337.008697 -287.798224) (xy 337.057937 -287.782225) (xy 337.109075 -287.774126)
			(xy 337.160849 -287.774126) (xy 337.211987 -287.782225) (xy 337.261227 -287.798224) (xy 337.307359 -287.82173)
			(xy 337.349246 -287.852162) (xy 337.385856 -287.888772) (xy 337.416288 -287.930659) (xy 337.439794 -287.976791)
			(xy 337.455793 -288.026031) (xy 337.463892 -288.077169) (xy 337.4644 -288.103056) (xy 337.463968 -288.128392)
			(xy 337.456207 -288.178467) (xy 337.440877 -288.226765) (xy 337.418339 -288.272149) (xy 337.389123 -288.31355)
			(xy 337.353916 -288.349995) (xy 337.313549 -288.380624) (xy 337.268971 -288.404718) (xy 337.221232 -288.421708)
			(xy 337.19643 -288.426906) (xy 337.17357 -288.431224) (xy 336.968592 -288.786316) (xy 336.976466 -288.80816)
			(xy 336.985119 -288.834566) (xy 336.994435 -288.889344) (xy 336.995008 -288.917126) (xy 338.215224 -288.917126)
			(xy 338.215749 -288.891782) (xy 338.223518 -288.841693) (xy 338.238861 -288.793383) (xy 338.261416 -288.74799)
			(xy 338.290652 -288.706584) (xy 338.325881 -288.67014) (xy 338.366272 -288.639516) (xy 338.410874 -288.615435)
			(xy 338.458636 -288.598463) (xy 338.483448 -288.593276) (xy 338.506308 -288.588958) (xy 338.711286 -288.233866)
			(xy 338.703412 -288.212022) (xy 338.694838 -288.185602) (xy 338.685638 -288.130828) (xy 338.685124 -288.103056)
			(xy 338.685632 -288.077169) (xy 338.693731 -288.026031) (xy 338.70973 -287.976791) (xy 338.733236 -287.930659)
			(xy 338.763668 -287.888772) (xy 338.800278 -287.852162) (xy 338.842165 -287.82173) (xy 338.888297 -287.798224)
			(xy 338.937537 -287.782225) (xy 338.988675 -287.774126) (xy 339.040449 -287.774126) (xy 339.091587 -287.782225)
			(xy 339.140827 -287.798224) (xy 339.186959 -287.82173) (xy 339.228846 -287.852162) (xy 339.265456 -287.888772)
			(xy 339.295888 -287.930659) (xy 339.319394 -287.976791) (xy 339.335393 -288.026031) (xy 339.343492 -288.077169)
			(xy 339.344 -288.103056) (xy 339.343568 -288.128392) (xy 339.335807 -288.178467) (xy 339.320477 -288.226765)
			(xy 339.297939 -288.272149) (xy 339.268723 -288.31355) (xy 339.233516 -288.349995) (xy 339.193149 -288.380624)
			(xy 339.148571 -288.404718) (xy 339.100832 -288.421708) (xy 339.07603 -288.426906) (xy 339.05317 -288.431224)
			(xy 338.848192 -288.786316) (xy 338.856066 -288.80816) (xy 338.864719 -288.834566) (xy 338.874035 -288.889344)
			(xy 338.874608 -288.917126) (xy 339.155024 -288.917126) (xy 339.155532 -288.891219) (xy 339.163638 -288.840042)
			(xy 339.17965 -288.790763) (xy 339.203173 -288.744596) (xy 339.233629 -288.702677) (xy 339.270267 -288.666039)
			(xy 339.312186 -288.635583) (xy 339.358353 -288.61206) (xy 339.407632 -288.596048) (xy 339.458809 -288.587942)
			(xy 339.510623 -288.587942) (xy 339.5618 -288.596048) (xy 339.611079 -288.61206) (xy 339.657246 -288.635583)
			(xy 339.699165 -288.666039) (xy 339.735803 -288.702677) (xy 339.766259 -288.744596) (xy 339.789782 -288.790763)
			(xy 339.805794 -288.840042) (xy 339.8139 -288.891219) (xy 339.814408 -288.917126) (xy 340.094824 -288.917126)
			(xy 340.095349 -288.891782) (xy 340.103118 -288.841693) (xy 340.118461 -288.793383) (xy 340.141016 -288.74799)
			(xy 340.170252 -288.706584) (xy 340.205481 -288.67014) (xy 340.245872 -288.639516) (xy 340.290474 -288.615435)
			(xy 340.338236 -288.598463) (xy 340.363048 -288.593276) (xy 340.385908 -288.588958) (xy 340.59114 -288.233866)
			(xy 340.583266 -288.211768) (xy 340.574642 -288.185419) (xy 340.565317 -288.130773) (xy 340.564724 -288.103056)
			(xy 340.565232 -288.077149) (xy 340.573338 -288.025972) (xy 340.58935 -287.976693) (xy 340.612873 -287.930526)
			(xy 340.643329 -287.888607) (xy 340.679967 -287.851969) (xy 340.721886 -287.821513) (xy 340.768053 -287.79799)
			(xy 340.817332 -287.781978) (xy 340.868509 -287.773872) (xy 340.920323 -287.773872) (xy 340.9715 -287.781978)
			(xy 341.020779 -287.79799) (xy 341.066946 -287.821513) (xy 341.108865 -287.851969) (xy 341.145503 -287.888607)
			(xy 341.175959 -287.930526) (xy 341.199482 -287.976693) (xy 341.215494 -288.025972) (xy 341.2236 -288.077149)
			(xy 341.224108 -288.103056) (xy 341.223631 -288.128401) (xy 341.215851 -288.178491) (xy 341.200499 -288.2268)
			(xy 341.177936 -288.272192) (xy 341.148694 -288.313597) (xy 341.11346 -288.35004) (xy 341.073065 -288.380663)
			(xy 341.028461 -288.404744) (xy 340.980697 -288.421718) (xy 340.955884 -288.426906) (xy 340.933024 -288.431224)
			(xy 340.727792 -288.786316) (xy 340.735666 -288.808414) (xy 340.744307 -288.834758) (xy 340.753621 -288.889407)
			(xy 340.754208 -288.917126) (xy 341.034624 -288.917126) (xy 341.035132 -288.891219) (xy 341.043238 -288.840042)
			(xy 341.05925 -288.790763) (xy 341.082773 -288.744596) (xy 341.113229 -288.702677) (xy 341.149867 -288.666039)
			(xy 341.191786 -288.635583) (xy 341.237953 -288.61206) (xy 341.287232 -288.596048) (xy 341.338409 -288.587942)
			(xy 341.390223 -288.587942) (xy 341.4414 -288.596048) (xy 341.490679 -288.61206) (xy 341.536846 -288.635583)
			(xy 341.578765 -288.666039) (xy 341.615403 -288.702677) (xy 341.645859 -288.744596) (xy 341.669382 -288.790763)
			(xy 341.685394 -288.840042) (xy 341.6935 -288.891219) (xy 341.694008 -288.917126) (xy 341.974424 -288.917126)
			(xy 341.974949 -288.891782) (xy 341.982718 -288.841693) (xy 341.998061 -288.793383) (xy 342.020616 -288.74799)
			(xy 342.049852 -288.706584) (xy 342.085081 -288.67014) (xy 342.125472 -288.639516) (xy 342.170074 -288.615435)
			(xy 342.217836 -288.598463) (xy 342.242648 -288.593276) (xy 342.265508 -288.588958) (xy 342.47074 -288.233866)
			(xy 342.462866 -288.211768) (xy 342.454242 -288.185419) (xy 342.444917 -288.130773) (xy 342.444324 -288.103056)
			(xy 342.444832 -288.077149) (xy 342.452938 -288.025972) (xy 342.46895 -287.976693) (xy 342.492473 -287.930526)
			(xy 342.522929 -287.888607) (xy 342.559567 -287.851969) (xy 342.601486 -287.821513) (xy 342.647653 -287.79799)
			(xy 342.696932 -287.781978) (xy 342.748109 -287.773872) (xy 342.799923 -287.773872) (xy 342.8511 -287.781978)
			(xy 342.900379 -287.79799) (xy 342.946546 -287.821513) (xy 342.988465 -287.851969) (xy 343.025103 -287.888607)
			(xy 343.055559 -287.930526) (xy 343.079082 -287.976693) (xy 343.095094 -288.025972) (xy 343.1032 -288.077149)
			(xy 343.103708 -288.103056) (xy 343.103231 -288.128401) (xy 343.095451 -288.178491) (xy 343.080099 -288.2268)
			(xy 343.057536 -288.272192) (xy 343.028294 -288.313597) (xy 342.99306 -288.35004) (xy 342.952665 -288.380663)
			(xy 342.908061 -288.404744) (xy 342.860297 -288.421718) (xy 342.835484 -288.426906) (xy 342.812624 -288.431224)
			(xy 342.607392 -288.786316) (xy 342.615266 -288.808414) (xy 342.623907 -288.834758) (xy 342.633221 -288.889407)
			(xy 342.633808 -288.917126) (xy 342.914224 -288.917126) (xy 342.914732 -288.891219) (xy 342.922838 -288.840042)
			(xy 342.93885 -288.790763) (xy 342.962373 -288.744596) (xy 342.992829 -288.702677) (xy 343.029467 -288.666039)
			(xy 343.071386 -288.635583) (xy 343.117553 -288.61206) (xy 343.166832 -288.596048) (xy 343.218009 -288.587942)
			(xy 343.269823 -288.587942) (xy 343.321 -288.596048) (xy 343.370279 -288.61206) (xy 343.416446 -288.635583)
			(xy 343.458365 -288.666039) (xy 343.495003 -288.702677) (xy 343.525459 -288.744596) (xy 343.548982 -288.790763)
			(xy 343.564994 -288.840042) (xy 343.5731 -288.891219) (xy 343.573608 -288.917126) (xy 343.854024 -288.917126)
			(xy 343.854549 -288.891782) (xy 343.862318 -288.841693) (xy 343.877661 -288.793383) (xy 343.900216 -288.74799)
			(xy 343.929452 -288.706584) (xy 343.964681 -288.67014) (xy 344.005072 -288.639516) (xy 344.049674 -288.615435)
			(xy 344.097436 -288.598463) (xy 344.122248 -288.593276) (xy 344.145108 -288.588958) (xy 344.35034 -288.233866)
			(xy 344.342466 -288.211768) (xy 344.333842 -288.185419) (xy 344.324517 -288.130773) (xy 344.323924 -288.103056)
			(xy 344.324432 -288.077149) (xy 344.332538 -288.025972) (xy 344.34855 -287.976693) (xy 344.372073 -287.930526)
			(xy 344.402529 -287.888607) (xy 344.439167 -287.851969) (xy 344.481086 -287.821513) (xy 344.527253 -287.79799)
			(xy 344.576532 -287.781978) (xy 344.627709 -287.773872) (xy 344.679523 -287.773872) (xy 344.7307 -287.781978)
			(xy 344.779979 -287.79799) (xy 344.826146 -287.821513) (xy 344.868065 -287.851969) (xy 344.904703 -287.888607)
			(xy 344.935159 -287.930526) (xy 344.958682 -287.976693) (xy 344.974694 -288.025972) (xy 344.9828 -288.077149)
			(xy 344.983308 -288.103056) (xy 344.982831 -288.128401) (xy 344.975051 -288.178491) (xy 344.959699 -288.2268)
			(xy 344.937136 -288.272192) (xy 344.907894 -288.313597) (xy 344.87266 -288.35004) (xy 344.832265 -288.380663)
			(xy 344.787661 -288.404744) (xy 344.739897 -288.421718) (xy 344.715084 -288.426906) (xy 344.692224 -288.431224)
			(xy 344.486992 -288.786316) (xy 344.494866 -288.808414) (xy 344.503507 -288.834758) (xy 344.512821 -288.889407)
			(xy 344.513408 -288.917126) (xy 344.793824 -288.917126) (xy 344.794332 -288.891219) (xy 344.802438 -288.840042)
			(xy 344.81845 -288.790763) (xy 344.841973 -288.744596) (xy 344.872429 -288.702677) (xy 344.909067 -288.666039)
			(xy 344.950986 -288.635583) (xy 344.997153 -288.61206) (xy 345.046432 -288.596048) (xy 345.097609 -288.587942)
			(xy 345.149423 -288.587942) (xy 345.2006 -288.596048) (xy 345.249879 -288.61206) (xy 345.296046 -288.635583)
			(xy 345.337965 -288.666039) (xy 345.374603 -288.702677) (xy 345.405059 -288.744596) (xy 345.428582 -288.790763)
			(xy 345.444594 -288.840042) (xy 345.4527 -288.891219) (xy 345.453208 -288.917126) (xy 345.733624 -288.917126)
			(xy 345.734149 -288.891782) (xy 345.741918 -288.841693) (xy 345.757261 -288.793383) (xy 345.779816 -288.74799)
			(xy 345.809052 -288.706584) (xy 345.844281 -288.67014) (xy 345.884672 -288.639516) (xy 345.929274 -288.615435)
			(xy 345.977036 -288.598463) (xy 346.001848 -288.593276) (xy 346.024708 -288.588958) (xy 346.22994 -288.233866)
			(xy 346.222066 -288.211768) (xy 346.213442 -288.185419) (xy 346.204117 -288.130773) (xy 346.203524 -288.103056)
			(xy 346.204032 -288.077149) (xy 346.212138 -288.025972) (xy 346.22815 -287.976693) (xy 346.251673 -287.930526)
			(xy 346.282129 -287.888607) (xy 346.318767 -287.851969) (xy 346.360686 -287.821513) (xy 346.406853 -287.79799)
			(xy 346.456132 -287.781978) (xy 346.507309 -287.773872) (xy 346.559123 -287.773872) (xy 346.6103 -287.781978)
			(xy 346.659579 -287.79799) (xy 346.705746 -287.821513) (xy 346.747665 -287.851969) (xy 346.784303 -287.888607)
			(xy 346.814759 -287.930526) (xy 346.838282 -287.976693) (xy 346.854294 -288.025972) (xy 346.8624 -288.077149)
			(xy 346.862908 -288.103056) (xy 346.862431 -288.128401) (xy 346.854651 -288.178491) (xy 346.839299 -288.2268)
			(xy 346.816736 -288.272192) (xy 346.787494 -288.313597) (xy 346.75226 -288.35004) (xy 346.711865 -288.380663)
			(xy 346.667261 -288.404744) (xy 346.619497 -288.421718) (xy 346.594684 -288.426906) (xy 346.571824 -288.431224)
			(xy 346.366592 -288.786316) (xy 346.374466 -288.808414) (xy 346.383107 -288.834758) (xy 346.392421 -288.889407)
			(xy 346.393008 -288.917126) (xy 346.673424 -288.917126) (xy 346.673932 -288.891219) (xy 346.682038 -288.840042)
			(xy 346.69805 -288.790763) (xy 346.721573 -288.744596) (xy 346.752029 -288.702677) (xy 346.788667 -288.666039)
			(xy 346.830586 -288.635583) (xy 346.876753 -288.61206) (xy 346.926032 -288.596048) (xy 346.977209 -288.587942)
			(xy 347.029023 -288.587942) (xy 347.0802 -288.596048) (xy 347.129479 -288.61206) (xy 347.175646 -288.635583)
			(xy 347.217565 -288.666039) (xy 347.254203 -288.702677) (xy 347.284659 -288.744596) (xy 347.308182 -288.790763)
			(xy 347.324194 -288.840042) (xy 347.3323 -288.891219) (xy 347.332808 -288.917126) (xy 347.613224 -288.917126)
			(xy 347.613749 -288.891782) (xy 347.621518 -288.841693) (xy 347.636861 -288.793383) (xy 347.659416 -288.74799)
			(xy 347.688652 -288.706584) (xy 347.723881 -288.67014) (xy 347.764272 -288.639516) (xy 347.808874 -288.615435)
			(xy 347.856636 -288.598463) (xy 347.881448 -288.593276) (xy 347.904308 -288.588958) (xy 348.10954 -288.233866)
			(xy 348.101666 -288.211768) (xy 348.093042 -288.185419) (xy 348.083717 -288.130773) (xy 348.083124 -288.103056)
			(xy 348.083632 -288.077149) (xy 348.091738 -288.025972) (xy 348.10775 -287.976693) (xy 348.131273 -287.930526)
			(xy 348.161729 -287.888607) (xy 348.198367 -287.851969) (xy 348.240286 -287.821513) (xy 348.286453 -287.79799)
			(xy 348.335732 -287.781978) (xy 348.386909 -287.773872) (xy 348.438723 -287.773872) (xy 348.4899 -287.781978)
			(xy 348.539179 -287.79799) (xy 348.585346 -287.821513) (xy 348.627265 -287.851969) (xy 348.663903 -287.888607)
			(xy 348.694359 -287.930526) (xy 348.717882 -287.976693) (xy 348.733894 -288.025972) (xy 348.742 -288.077149)
			(xy 348.742508 -288.103056) (xy 348.742031 -288.128401) (xy 348.734251 -288.178491) (xy 348.718899 -288.2268)
			(xy 348.696336 -288.272192) (xy 348.667094 -288.313597) (xy 348.63186 -288.35004) (xy 348.591465 -288.380663)
			(xy 348.546861 -288.404744) (xy 348.499097 -288.421718) (xy 348.474284 -288.426906) (xy 348.451424 -288.431224)
			(xy 348.246192 -288.786316) (xy 348.254066 -288.808414) (xy 348.262707 -288.834758) (xy 348.272021 -288.889407)
			(xy 348.272608 -288.917126) (xy 348.553024 -288.917126) (xy 348.553532 -288.891219) (xy 348.561638 -288.840042)
			(xy 348.57765 -288.790763) (xy 348.601173 -288.744596) (xy 348.631629 -288.702677) (xy 348.668267 -288.666039)
			(xy 348.710186 -288.635583) (xy 348.756353 -288.61206) (xy 348.805632 -288.596048) (xy 348.856809 -288.587942)
			(xy 348.908623 -288.587942) (xy 348.9598 -288.596048) (xy 349.009079 -288.61206) (xy 349.055246 -288.635583)
			(xy 349.097165 -288.666039) (xy 349.133803 -288.702677) (xy 349.164259 -288.744596) (xy 349.187782 -288.790763)
			(xy 349.203794 -288.840042) (xy 349.2119 -288.891219) (xy 349.212408 -288.917126) (xy 349.492824 -288.917126)
			(xy 349.493349 -288.891782) (xy 349.501118 -288.841693) (xy 349.516461 -288.793383) (xy 349.539016 -288.74799)
			(xy 349.568252 -288.706584) (xy 349.603481 -288.67014) (xy 349.643872 -288.639516) (xy 349.688474 -288.615435)
			(xy 349.736236 -288.598463) (xy 349.761048 -288.593276) (xy 349.783908 -288.588958) (xy 349.98914 -288.233866)
			(xy 349.981266 -288.211768) (xy 349.972642 -288.185419) (xy 349.963317 -288.130773) (xy 349.962724 -288.103056)
			(xy 349.963232 -288.077149) (xy 349.971338 -288.025972) (xy 349.98735 -287.976693) (xy 350.010873 -287.930526)
			(xy 350.041329 -287.888607) (xy 350.077967 -287.851969) (xy 350.119886 -287.821513) (xy 350.166053 -287.79799)
			(xy 350.215332 -287.781978) (xy 350.266509 -287.773872) (xy 350.318323 -287.773872) (xy 350.3695 -287.781978)
			(xy 350.418779 -287.79799) (xy 350.464946 -287.821513) (xy 350.506865 -287.851969) (xy 350.543503 -287.888607)
			(xy 350.573959 -287.930526) (xy 350.597482 -287.976693) (xy 350.613494 -288.025972) (xy 350.6216 -288.077149)
			(xy 350.622108 -288.103056) (xy 350.621631 -288.128401) (xy 350.613851 -288.178491) (xy 350.598499 -288.2268)
			(xy 350.575936 -288.272192) (xy 350.546694 -288.313597) (xy 350.51146 -288.35004) (xy 350.471065 -288.380663)
			(xy 350.426461 -288.404744) (xy 350.378697 -288.421718) (xy 350.353884 -288.426906) (xy 350.331024 -288.431224)
			(xy 350.125792 -288.786316) (xy 350.133666 -288.808414) (xy 350.142307 -288.834758) (xy 350.151621 -288.889407)
			(xy 350.152208 -288.917126) (xy 350.432624 -288.917126) (xy 350.433132 -288.891219) (xy 350.441238 -288.840042)
			(xy 350.45725 -288.790763) (xy 350.480773 -288.744596) (xy 350.511229 -288.702677) (xy 350.547867 -288.666039)
			(xy 350.589786 -288.635583) (xy 350.635953 -288.61206) (xy 350.685232 -288.596048) (xy 350.736409 -288.587942)
			(xy 350.788223 -288.587942) (xy 350.8394 -288.596048) (xy 350.888679 -288.61206) (xy 350.934846 -288.635583)
			(xy 350.976765 -288.666039) (xy 351.013403 -288.702677) (xy 351.043859 -288.744596) (xy 351.067382 -288.790763)
			(xy 351.083394 -288.840042) (xy 351.0915 -288.891219) (xy 351.092008 -288.917126) (xy 351.372424 -288.917126)
			(xy 351.372949 -288.891782) (xy 351.380718 -288.841693) (xy 351.396061 -288.793383) (xy 351.418616 -288.74799)
			(xy 351.447852 -288.706584) (xy 351.483081 -288.67014) (xy 351.523472 -288.639516) (xy 351.568074 -288.615435)
			(xy 351.615836 -288.598463) (xy 351.640648 -288.593276) (xy 351.663508 -288.588958) (xy 351.86874 -288.233866)
			(xy 351.860866 -288.211768) (xy 351.852242 -288.185419) (xy 351.842917 -288.130773) (xy 351.842324 -288.103056)
			(xy 351.842832 -288.077149) (xy 351.850938 -288.025972) (xy 351.86695 -287.976693) (xy 351.890473 -287.930526)
			(xy 351.920929 -287.888607) (xy 351.957567 -287.851969) (xy 351.999486 -287.821513) (xy 352.045653 -287.79799)
			(xy 352.094932 -287.781978) (xy 352.146109 -287.773872) (xy 352.197923 -287.773872) (xy 352.2491 -287.781978)
			(xy 352.298379 -287.79799) (xy 352.344546 -287.821513) (xy 352.386465 -287.851969) (xy 352.423103 -287.888607)
			(xy 352.453559 -287.930526) (xy 352.477082 -287.976693) (xy 352.493094 -288.025972) (xy 352.5012 -288.077149)
			(xy 352.501708 -288.103056) (xy 368.758724 -288.103056) (xy 368.759232 -288.077149) (xy 368.767338 -288.025972)
			(xy 368.78335 -287.976693) (xy 368.806873 -287.930526) (xy 368.837329 -287.888607) (xy 368.873967 -287.851969)
			(xy 368.915886 -287.821513) (xy 368.962053 -287.79799) (xy 369.011332 -287.781978) (xy 369.062509 -287.773872)
			(xy 369.114323 -287.773872) (xy 369.1655 -287.781978) (xy 369.214779 -287.79799) (xy 369.260946 -287.821513)
			(xy 369.302865 -287.851969) (xy 369.339503 -287.888607) (xy 369.369959 -287.930526) (xy 369.393482 -287.976693)
			(xy 369.409494 -288.025972) (xy 369.4176 -288.077149) (xy 369.418108 -288.103056) (xy 370.638324 -288.103056)
			(xy 370.638832 -288.077149) (xy 370.646938 -288.025972) (xy 370.66295 -287.976693) (xy 370.686473 -287.930526)
			(xy 370.716929 -287.888607) (xy 370.753567 -287.851969) (xy 370.795486 -287.821513) (xy 370.841653 -287.79799)
			(xy 370.890932 -287.781978) (xy 370.942109 -287.773872) (xy 370.993923 -287.773872) (xy 371.0451 -287.781978)
			(xy 371.094379 -287.79799) (xy 371.140546 -287.821513) (xy 371.182465 -287.851969) (xy 371.219103 -287.888607)
			(xy 371.249559 -287.930526) (xy 371.273082 -287.976693) (xy 371.289094 -288.025972) (xy 371.2972 -288.077149)
			(xy 371.297708 -288.103056) (xy 372.517924 -288.103056) (xy 372.518432 -288.077149) (xy 372.526538 -288.025972)
			(xy 372.54255 -287.976693) (xy 372.566073 -287.930526) (xy 372.596529 -287.888607) (xy 372.633167 -287.851969)
			(xy 372.675086 -287.821513) (xy 372.721253 -287.79799) (xy 372.770532 -287.781978) (xy 372.821709 -287.773872)
			(xy 372.873523 -287.773872) (xy 372.9247 -287.781978) (xy 372.973979 -287.79799) (xy 373.020146 -287.821513)
			(xy 373.062065 -287.851969) (xy 373.098703 -287.888607) (xy 373.129159 -287.930526) (xy 373.152682 -287.976693)
			(xy 373.168694 -288.025972) (xy 373.1768 -288.077149) (xy 373.177308 -288.103056) (xy 374.397524 -288.103056)
			(xy 374.398032 -288.077149) (xy 374.406138 -288.025972) (xy 374.42215 -287.976693) (xy 374.445673 -287.930526)
			(xy 374.476129 -287.888607) (xy 374.512767 -287.851969) (xy 374.554686 -287.821513) (xy 374.600853 -287.79799)
			(xy 374.650132 -287.781978) (xy 374.701309 -287.773872) (xy 374.753123 -287.773872) (xy 374.8043 -287.781978)
			(xy 374.853579 -287.79799) (xy 374.899746 -287.821513) (xy 374.941665 -287.851969) (xy 374.978303 -287.888607)
			(xy 375.008759 -287.930526) (xy 375.032282 -287.976693) (xy 375.048294 -288.025972) (xy 375.0564 -288.077149)
			(xy 375.056908 -288.103056) (xy 376.277124 -288.103056) (xy 376.277632 -288.077149) (xy 376.285738 -288.025972)
			(xy 376.30175 -287.976693) (xy 376.325273 -287.930526) (xy 376.355729 -287.888607) (xy 376.392367 -287.851969)
			(xy 376.434286 -287.821513) (xy 376.480453 -287.79799) (xy 376.529732 -287.781978) (xy 376.580909 -287.773872)
			(xy 376.632723 -287.773872) (xy 376.6839 -287.781978) (xy 376.733179 -287.79799) (xy 376.779346 -287.821513)
			(xy 376.821265 -287.851969) (xy 376.857903 -287.888607) (xy 376.888359 -287.930526) (xy 376.911882 -287.976693)
			(xy 376.927894 -288.025972) (xy 376.936 -288.077149) (xy 376.936508 -288.103056) (xy 378.156724 -288.103056)
			(xy 378.157232 -288.077149) (xy 378.165338 -288.025972) (xy 378.18135 -287.976693) (xy 378.204873 -287.930526)
			(xy 378.235329 -287.888607) (xy 378.271967 -287.851969) (xy 378.313886 -287.821513) (xy 378.360053 -287.79799)
			(xy 378.409332 -287.781978) (xy 378.460509 -287.773872) (xy 378.512323 -287.773872) (xy 378.5635 -287.781978)
			(xy 378.612779 -287.79799) (xy 378.658946 -287.821513) (xy 378.700865 -287.851969) (xy 378.737503 -287.888607)
			(xy 378.767959 -287.930526) (xy 378.791482 -287.976693) (xy 378.807494 -288.025972) (xy 378.8156 -288.077149)
			(xy 378.816108 -288.103056) (xy 380.036324 -288.103056) (xy 380.036832 -288.077149) (xy 380.044938 -288.025972)
			(xy 380.06095 -287.976693) (xy 380.084473 -287.930526) (xy 380.114929 -287.888607) (xy 380.151567 -287.851969)
			(xy 380.193486 -287.821513) (xy 380.239653 -287.79799) (xy 380.288932 -287.781978) (xy 380.340109 -287.773872)
			(xy 380.391923 -287.773872) (xy 380.4431 -287.781978) (xy 380.492379 -287.79799) (xy 380.538546 -287.821513)
			(xy 380.580465 -287.851969) (xy 380.617103 -287.888607) (xy 380.647559 -287.930526) (xy 380.671082 -287.976693)
			(xy 380.687094 -288.025972) (xy 380.6952 -288.077149) (xy 380.695708 -288.103056) (xy 382.855724 -288.103056)
			(xy 382.856232 -288.077149) (xy 382.864338 -288.025972) (xy 382.88035 -287.976693) (xy 382.903873 -287.930526)
			(xy 382.934329 -287.888607) (xy 382.970967 -287.851969) (xy 383.012886 -287.821513) (xy 383.059053 -287.79799)
			(xy 383.108332 -287.781978) (xy 383.159509 -287.773872) (xy 383.211323 -287.773872) (xy 383.2625 -287.781978)
			(xy 383.311779 -287.79799) (xy 383.357946 -287.821513) (xy 383.399865 -287.851969) (xy 383.436503 -287.888607)
			(xy 383.466959 -287.930526) (xy 383.490482 -287.976693) (xy 383.506494 -288.025972) (xy 383.5146 -288.077149)
			(xy 383.515108 -288.103056) (xy 383.514503 -288.130773) (xy 383.505187 -288.185419) (xy 383.496566 -288.211768)
			(xy 383.488692 -288.233866) (xy 383.693924 -288.588958) (xy 383.716784 -288.593276) (xy 383.741606 -288.598437)
			(xy 383.789384 -288.615395) (xy 383.834001 -288.639469) (xy 383.874406 -288.67009) (xy 383.909646 -288.706538)
			(xy 383.93889 -288.747952) (xy 383.961447 -288.793355) (xy 383.976786 -288.841676) (xy 383.984545 -288.891777)
			(xy 383.985008 -288.917126) (xy 383.9845 -288.943033) (xy 383.976394 -288.99421) (xy 383.960382 -289.043489)
			(xy 383.936859 -289.089656) (xy 383.906403 -289.131575) (xy 383.869765 -289.168213) (xy 383.827846 -289.198669)
			(xy 383.781679 -289.222192) (xy 383.7324 -289.238204) (xy 383.681223 -289.24631) (xy 383.629409 -289.24631)
			(xy 383.578232 -289.238204) (xy 383.528953 -289.222192) (xy 383.482786 -289.198669) (xy 383.440867 -289.168213)
			(xy 383.404229 -289.131575) (xy 383.373773 -289.089656) (xy 383.35025 -289.043489) (xy 383.334238 -288.99421)
			(xy 383.326132 -288.943033) (xy 383.325624 -288.917126) (xy 383.326223 -288.889409) (xy 383.335543 -288.834762)
			(xy 383.344166 -288.808414) (xy 383.35204 -288.786316) (xy 383.146808 -288.431224) (xy 383.123948 -288.426906)
			(xy 383.099127 -288.421739) (xy 383.051348 -288.404784) (xy 383.006729 -288.380713) (xy 382.966322 -288.350092)
			(xy 382.931082 -288.313646) (xy 382.901838 -288.272232) (xy 382.879281 -288.226828) (xy 382.863943 -288.178506)
			(xy 382.856186 -288.128405) (xy 382.855724 -288.103056) (xy 380.695708 -288.103056) (xy 380.695103 -288.130773)
			(xy 380.685787 -288.185419) (xy 380.677166 -288.211768) (xy 380.669546 -288.233866) (xy 380.874524 -288.588958)
			(xy 380.897384 -288.593276) (xy 380.922206 -288.598437) (xy 380.969984 -288.615395) (xy 381.014601 -288.639469)
			(xy 381.055006 -288.67009) (xy 381.090246 -288.706538) (xy 381.11949 -288.747952) (xy 381.142047 -288.793355)
			(xy 381.157386 -288.841676) (xy 381.165145 -288.891777) (xy 381.165608 -288.917126) (xy 381.1651 -288.943033)
			(xy 381.156994 -288.99421) (xy 381.140982 -289.043489) (xy 381.117459 -289.089656) (xy 381.087003 -289.131575)
			(xy 381.050365 -289.168213) (xy 381.008446 -289.198669) (xy 380.962279 -289.222192) (xy 380.913 -289.238204)
			(xy 380.861823 -289.24631) (xy 380.810009 -289.24631) (xy 380.758832 -289.238204) (xy 380.709553 -289.222192)
			(xy 380.663386 -289.198669) (xy 380.621467 -289.168213) (xy 380.584829 -289.131575) (xy 380.554373 -289.089656)
			(xy 380.53085 -289.043489) (xy 380.514838 -288.99421) (xy 380.506732 -288.943033) (xy 380.506224 -288.917126)
			(xy 380.506823 -288.889409) (xy 380.516143 -288.834762) (xy 380.524766 -288.808414) (xy 380.53264 -288.786316)
			(xy 380.327662 -288.431224) (xy 380.304802 -288.426906) (xy 380.279961 -288.421779) (xy 380.232152 -288.40484)
			(xy 380.187502 -288.380778) (xy 380.147063 -288.350162) (xy 380.111791 -288.313713) (xy 380.082517 -288.272293)
			(xy 380.059933 -288.226877) (xy 380.044571 -288.178538) (xy 380.036794 -288.128417) (xy 380.036324 -288.103056)
			(xy 378.816108 -288.103056) (xy 378.815503 -288.130773) (xy 378.806187 -288.185419) (xy 378.797566 -288.211768)
			(xy 378.789946 -288.233866) (xy 378.994924 -288.588958) (xy 379.017784 -288.593276) (xy 379.042606 -288.598437)
			(xy 379.090384 -288.615395) (xy 379.135001 -288.639469) (xy 379.175406 -288.67009) (xy 379.210646 -288.706538)
			(xy 379.23989 -288.747952) (xy 379.262447 -288.793355) (xy 379.277786 -288.841676) (xy 379.285545 -288.891777)
			(xy 379.286008 -288.917126) (xy 379.2855 -288.943033) (xy 379.277394 -288.99421) (xy 379.261382 -289.043489)
			(xy 379.237859 -289.089656) (xy 379.207403 -289.131575) (xy 379.170765 -289.168213) (xy 379.128846 -289.198669)
			(xy 379.082679 -289.222192) (xy 379.0334 -289.238204) (xy 378.982223 -289.24631) (xy 378.930409 -289.24631)
			(xy 378.879232 -289.238204) (xy 378.829953 -289.222192) (xy 378.783786 -289.198669) (xy 378.741867 -289.168213)
			(xy 378.705229 -289.131575) (xy 378.674773 -289.089656) (xy 378.65125 -289.043489) (xy 378.635238 -288.99421)
			(xy 378.627132 -288.943033) (xy 378.626624 -288.917126) (xy 378.627223 -288.889409) (xy 378.636543 -288.834762)
			(xy 378.645166 -288.808414) (xy 378.65304 -288.786316) (xy 378.448062 -288.431224) (xy 378.425202 -288.426906)
			(xy 378.400361 -288.421779) (xy 378.352552 -288.40484) (xy 378.307902 -288.380778) (xy 378.267463 -288.350162)
			(xy 378.232191 -288.313713) (xy 378.202917 -288.272293) (xy 378.180333 -288.226877) (xy 378.164971 -288.178538)
			(xy 378.157194 -288.128417) (xy 378.156724 -288.103056) (xy 376.936508 -288.103056) (xy 376.935903 -288.130773)
			(xy 376.926587 -288.185419) (xy 376.917966 -288.211768) (xy 376.910346 -288.233866) (xy 377.115324 -288.588958)
			(xy 377.138184 -288.593276) (xy 377.163006 -288.598437) (xy 377.210784 -288.615395) (xy 377.255401 -288.639469)
			(xy 377.295806 -288.67009) (xy 377.331046 -288.706538) (xy 377.36029 -288.747952) (xy 377.382847 -288.793355)
			(xy 377.398186 -288.841676) (xy 377.405945 -288.891777) (xy 377.406408 -288.917126) (xy 377.4059 -288.943033)
			(xy 377.397794 -288.99421) (xy 377.381782 -289.043489) (xy 377.358259 -289.089656) (xy 377.327803 -289.131575)
			(xy 377.291165 -289.168213) (xy 377.249246 -289.198669) (xy 377.203079 -289.222192) (xy 377.1538 -289.238204)
			(xy 377.102623 -289.24631) (xy 377.050809 -289.24631) (xy 376.999632 -289.238204) (xy 376.950353 -289.222192)
			(xy 376.904186 -289.198669) (xy 376.862267 -289.168213) (xy 376.825629 -289.131575) (xy 376.795173 -289.089656)
			(xy 376.77165 -289.043489) (xy 376.755638 -288.99421) (xy 376.747532 -288.943033) (xy 376.747024 -288.917126)
			(xy 376.747623 -288.889409) (xy 376.756943 -288.834762) (xy 376.765566 -288.808414) (xy 376.77344 -288.786316)
			(xy 376.568462 -288.431224) (xy 376.545602 -288.426906) (xy 376.520761 -288.421779) (xy 376.472952 -288.40484)
			(xy 376.428302 -288.380778) (xy 376.387863 -288.350162) (xy 376.352591 -288.313713) (xy 376.323317 -288.272293)
			(xy 376.300733 -288.226877) (xy 376.285371 -288.178538) (xy 376.277594 -288.128417) (xy 376.277124 -288.103056)
			(xy 375.056908 -288.103056) (xy 375.056303 -288.130773) (xy 375.046987 -288.185419) (xy 375.038366 -288.211768)
			(xy 375.030746 -288.233866) (xy 375.235724 -288.588958) (xy 375.258584 -288.593276) (xy 375.283406 -288.598437)
			(xy 375.331184 -288.615395) (xy 375.375801 -288.639469) (xy 375.416206 -288.67009) (xy 375.451446 -288.706538)
			(xy 375.48069 -288.747952) (xy 375.503247 -288.793355) (xy 375.518586 -288.841676) (xy 375.526345 -288.891777)
			(xy 375.526808 -288.917126) (xy 375.5263 -288.943033) (xy 375.518194 -288.99421) (xy 375.502182 -289.043489)
			(xy 375.478659 -289.089656) (xy 375.448203 -289.131575) (xy 375.411565 -289.168213) (xy 375.369646 -289.198669)
			(xy 375.323479 -289.222192) (xy 375.2742 -289.238204) (xy 375.223023 -289.24631) (xy 375.171209 -289.24631)
			(xy 375.120032 -289.238204) (xy 375.070753 -289.222192) (xy 375.024586 -289.198669) (xy 374.982667 -289.168213)
			(xy 374.946029 -289.131575) (xy 374.915573 -289.089656) (xy 374.89205 -289.043489) (xy 374.876038 -288.99421)
			(xy 374.867932 -288.943033) (xy 374.867424 -288.917126) (xy 374.868023 -288.889409) (xy 374.877343 -288.834762)
			(xy 374.885966 -288.808414) (xy 374.89384 -288.786316) (xy 374.688862 -288.431224) (xy 374.666002 -288.426906)
			(xy 374.641161 -288.421779) (xy 374.593352 -288.40484) (xy 374.548702 -288.380778) (xy 374.508263 -288.350162)
			(xy 374.472991 -288.313713) (xy 374.443717 -288.272293) (xy 374.421133 -288.226877) (xy 374.405771 -288.178538)
			(xy 374.397994 -288.128417) (xy 374.397524 -288.103056) (xy 373.177308 -288.103056) (xy 373.176703 -288.130773)
			(xy 373.167387 -288.185419) (xy 373.158766 -288.211768) (xy 373.151146 -288.233866) (xy 373.356124 -288.588958)
			(xy 373.378984 -288.593276) (xy 373.403806 -288.598437) (xy 373.451584 -288.615395) (xy 373.496201 -288.639469)
			(xy 373.536606 -288.67009) (xy 373.571846 -288.706538) (xy 373.60109 -288.747952) (xy 373.623647 -288.793355)
			(xy 373.638986 -288.841676) (xy 373.646745 -288.891777) (xy 373.647208 -288.917126) (xy 373.6467 -288.943033)
			(xy 373.638594 -288.99421) (xy 373.622582 -289.043489) (xy 373.599059 -289.089656) (xy 373.568603 -289.131575)
			(xy 373.531965 -289.168213) (xy 373.490046 -289.198669) (xy 373.443879 -289.222192) (xy 373.3946 -289.238204)
			(xy 373.343423 -289.24631) (xy 373.291609 -289.24631) (xy 373.240432 -289.238204) (xy 373.191153 -289.222192)
			(xy 373.144986 -289.198669) (xy 373.103067 -289.168213) (xy 373.066429 -289.131575) (xy 373.035973 -289.089656)
			(xy 373.01245 -289.043489) (xy 372.996438 -288.99421) (xy 372.988332 -288.943033) (xy 372.987824 -288.917126)
			(xy 372.988423 -288.889409) (xy 372.997743 -288.834762) (xy 373.006366 -288.808414) (xy 373.01424 -288.786316)
			(xy 372.809262 -288.431224) (xy 372.786402 -288.426906) (xy 372.761561 -288.421779) (xy 372.713752 -288.40484)
			(xy 372.669102 -288.380778) (xy 372.628663 -288.350162) (xy 372.593391 -288.313713) (xy 372.564117 -288.272293)
			(xy 372.541533 -288.226877) (xy 372.526171 -288.178538) (xy 372.518394 -288.128417) (xy 372.517924 -288.103056)
			(xy 371.297708 -288.103056) (xy 371.297103 -288.130773) (xy 371.287787 -288.185419) (xy 371.279166 -288.211768)
			(xy 371.271546 -288.233866) (xy 371.476524 -288.588958) (xy 371.499384 -288.593276) (xy 371.524206 -288.598437)
			(xy 371.571984 -288.615395) (xy 371.616601 -288.639469) (xy 371.657006 -288.67009) (xy 371.692246 -288.706538)
			(xy 371.72149 -288.747952) (xy 371.744047 -288.793355) (xy 371.759386 -288.841676) (xy 371.767145 -288.891777)
			(xy 371.767608 -288.917126) (xy 371.7671 -288.943033) (xy 371.758994 -288.99421) (xy 371.742982 -289.043489)
			(xy 371.719459 -289.089656) (xy 371.689003 -289.131575) (xy 371.652365 -289.168213) (xy 371.610446 -289.198669)
			(xy 371.564279 -289.222192) (xy 371.515 -289.238204) (xy 371.463823 -289.24631) (xy 371.412009 -289.24631)
			(xy 371.360832 -289.238204) (xy 371.311553 -289.222192) (xy 371.265386 -289.198669) (xy 371.223467 -289.168213)
			(xy 371.186829 -289.131575) (xy 371.156373 -289.089656) (xy 371.13285 -289.043489) (xy 371.116838 -288.99421)
			(xy 371.108732 -288.943033) (xy 371.108224 -288.917126) (xy 371.108823 -288.889409) (xy 371.118143 -288.834762)
			(xy 371.126766 -288.808414) (xy 371.13464 -288.786316) (xy 370.929662 -288.431224) (xy 370.906802 -288.426906)
			(xy 370.881961 -288.421779) (xy 370.834152 -288.40484) (xy 370.789502 -288.380778) (xy 370.749063 -288.350162)
			(xy 370.713791 -288.313713) (xy 370.684517 -288.272293) (xy 370.661933 -288.226877) (xy 370.646571 -288.178538)
			(xy 370.638794 -288.128417) (xy 370.638324 -288.103056) (xy 369.418108 -288.103056) (xy 369.417503 -288.130773)
			(xy 369.408187 -288.185419) (xy 369.399566 -288.211768) (xy 369.391692 -288.233866) (xy 369.596924 -288.588958)
			(xy 369.619784 -288.593276) (xy 369.644606 -288.598437) (xy 369.692384 -288.615395) (xy 369.737001 -288.639469)
			(xy 369.777406 -288.67009) (xy 369.812646 -288.706538) (xy 369.84189 -288.747952) (xy 369.864447 -288.793355)
			(xy 369.879786 -288.841676) (xy 369.887545 -288.891777) (xy 369.888008 -288.917126) (xy 369.8875 -288.943033)
			(xy 369.879394 -288.99421) (xy 369.863382 -289.043489) (xy 369.839859 -289.089656) (xy 369.809403 -289.131575)
			(xy 369.772765 -289.168213) (xy 369.730846 -289.198669) (xy 369.684679 -289.222192) (xy 369.6354 -289.238204)
			(xy 369.584223 -289.24631) (xy 369.532409 -289.24631) (xy 369.481232 -289.238204) (xy 369.431953 -289.222192)
			(xy 369.385786 -289.198669) (xy 369.343867 -289.168213) (xy 369.307229 -289.131575) (xy 369.276773 -289.089656)
			(xy 369.25325 -289.043489) (xy 369.237238 -288.99421) (xy 369.229132 -288.943033) (xy 369.228624 -288.917126)
			(xy 369.229223 -288.889409) (xy 369.238543 -288.834762) (xy 369.247166 -288.808414) (xy 369.25504 -288.786316)
			(xy 369.049808 -288.431224) (xy 369.026948 -288.426906) (xy 369.002127 -288.421739) (xy 368.954348 -288.404784)
			(xy 368.909729 -288.380713) (xy 368.869322 -288.350092) (xy 368.834082 -288.313646) (xy 368.804838 -288.272232)
			(xy 368.782281 -288.226828) (xy 368.766943 -288.178506) (xy 368.759186 -288.128405) (xy 368.758724 -288.103056)
			(xy 352.501708 -288.103056) (xy 352.501231 -288.128401) (xy 352.493451 -288.178491) (xy 352.478099 -288.2268)
			(xy 352.455536 -288.272192) (xy 352.426294 -288.313597) (xy 352.39106 -288.35004) (xy 352.350665 -288.380663)
			(xy 352.306061 -288.404744) (xy 352.258297 -288.421718) (xy 352.233484 -288.426906) (xy 352.210624 -288.431224)
			(xy 352.005392 -288.786316) (xy 352.013266 -288.808414) (xy 352.021907 -288.834758) (xy 352.031221 -288.889407)
			(xy 352.031808 -288.917126) (xy 352.0313 -288.943033) (xy 352.023194 -288.99421) (xy 352.007182 -289.043489)
			(xy 351.983659 -289.089656) (xy 351.953203 -289.131575) (xy 351.916565 -289.168213) (xy 351.874646 -289.198669)
			(xy 351.828479 -289.222192) (xy 351.7792 -289.238204) (xy 351.728023 -289.24631) (xy 351.676209 -289.24631)
			(xy 351.625032 -289.238204) (xy 351.575753 -289.222192) (xy 351.529586 -289.198669) (xy 351.487667 -289.168213)
			(xy 351.451029 -289.131575) (xy 351.420573 -289.089656) (xy 351.39705 -289.043489) (xy 351.381038 -288.99421)
			(xy 351.372932 -288.943033) (xy 351.372424 -288.917126) (xy 351.092008 -288.917126) (xy 351.091589 -288.940067)
			(xy 351.08516 -288.985498) (xy 351.072513 -289.029604) (xy 351.06356 -289.05073) (xy 351.053654 -289.073336)
			(xy 351.267522 -289.478466) (xy 351.291652 -289.483038) (xy 351.316573 -289.488138) (xy 351.364584 -289.504939)
			(xy 351.409443 -289.528919) (xy 351.450084 -289.559507) (xy 351.485541 -289.595978) (xy 351.514973 -289.637465)
			(xy 351.537679 -289.682981) (xy 351.553121 -289.731446) (xy 351.560931 -289.781709) (xy 351.5614 -289.807142)
			(xy 367.818924 -289.807142) (xy 367.819411 -289.781712) (xy 367.827244 -289.73146) (xy 367.842699 -289.683005)
			(xy 367.86541 -289.637498) (xy 367.894839 -289.596018) (xy 367.930287 -289.559547) (xy 367.970914 -289.528951)
			(xy 368.015757 -289.504956) (xy 368.063753 -289.48813) (xy 368.088672 -289.483038) (xy 368.112802 -289.478466)
			(xy 368.327178 -289.073082) (xy 368.317272 -289.050476) (xy 368.308309 -289.029398) (xy 368.295664 -288.985377)
			(xy 368.289249 -288.940026) (xy 368.288824 -288.917126) (xy 368.289332 -288.891219) (xy 368.297438 -288.840042)
			(xy 368.31345 -288.790763) (xy 368.336973 -288.744596) (xy 368.367429 -288.702677) (xy 368.404067 -288.666039)
			(xy 368.445986 -288.635583) (xy 368.492153 -288.61206) (xy 368.541432 -288.596048) (xy 368.592609 -288.587942)
			(xy 368.644423 -288.587942) (xy 368.6956 -288.596048) (xy 368.744879 -288.61206) (xy 368.791046 -288.635583)
			(xy 368.832965 -288.666039) (xy 368.869603 -288.702677) (xy 368.900059 -288.744596) (xy 368.923582 -288.790763)
			(xy 368.939594 -288.840042) (xy 368.9477 -288.891219) (xy 368.948208 -288.917126) (xy 368.947753 -288.942575)
			(xy 368.939949 -288.992871) (xy 368.924499 -289.041367) (xy 368.901771 -289.086909) (xy 368.872307 -289.128411)
			(xy 368.836809 -289.164887) (xy 368.796121 -289.195466) (xy 368.751213 -289.21942) (xy 368.703153 -289.23618)
			(xy 368.678206 -289.24123) (xy 368.654076 -289.245802) (xy 368.4397 -289.651186) (xy 368.449606 -289.673792)
			(xy 368.458528 -289.694877) (xy 368.471078 -289.738907) (xy 368.47741 -289.78425) (xy 368.4778 -289.807142)
			(xy 369.698524 -289.807142) (xy 369.699011 -289.781712) (xy 369.706844 -289.73146) (xy 369.722299 -289.683005)
			(xy 369.74501 -289.637498) (xy 369.774439 -289.596018) (xy 369.809887 -289.559547) (xy 369.850514 -289.528951)
			(xy 369.895357 -289.504956) (xy 369.943353 -289.48813) (xy 369.968272 -289.483038) (xy 369.992402 -289.478466)
			(xy 370.206778 -289.073082) (xy 370.196872 -289.050476) (xy 370.187909 -289.029398) (xy 370.175264 -288.985377)
			(xy 370.168849 -288.940026) (xy 370.168424 -288.917126) (xy 370.168932 -288.891219) (xy 370.177038 -288.840042)
			(xy 370.19305 -288.790763) (xy 370.216573 -288.744596) (xy 370.247029 -288.702677) (xy 370.283667 -288.666039)
			(xy 370.325586 -288.635583) (xy 370.371753 -288.61206) (xy 370.421032 -288.596048) (xy 370.472209 -288.587942)
			(xy 370.524023 -288.587942) (xy 370.5752 -288.596048) (xy 370.624479 -288.61206) (xy 370.670646 -288.635583)
			(xy 370.712565 -288.666039) (xy 370.749203 -288.702677) (xy 370.779659 -288.744596) (xy 370.803182 -288.790763)
			(xy 370.819194 -288.840042) (xy 370.8273 -288.891219) (xy 370.827808 -288.917126) (xy 370.827353 -288.942575)
			(xy 370.819549 -288.992871) (xy 370.804099 -289.041367) (xy 370.781371 -289.086909) (xy 370.751907 -289.128411)
			(xy 370.716409 -289.164887) (xy 370.675721 -289.195466) (xy 370.630813 -289.21942) (xy 370.582753 -289.23618)
			(xy 370.557806 -289.24123) (xy 370.533676 -289.245802) (xy 370.3193 -289.651186) (xy 370.329206 -289.673792)
			(xy 370.338128 -289.694877) (xy 370.350678 -289.738907) (xy 370.35701 -289.78425) (xy 370.3574 -289.807142)
			(xy 371.578124 -289.807142) (xy 371.578611 -289.781712) (xy 371.586444 -289.73146) (xy 371.601899 -289.683005)
			(xy 371.62461 -289.637498) (xy 371.654039 -289.596018) (xy 371.689487 -289.559547) (xy 371.730114 -289.528951)
			(xy 371.774957 -289.504956) (xy 371.822953 -289.48813) (xy 371.847872 -289.483038) (xy 371.872002 -289.478466)
			(xy 372.086378 -289.073082) (xy 372.076472 -289.050476) (xy 372.067509 -289.029398) (xy 372.054864 -288.985377)
			(xy 372.048449 -288.940026) (xy 372.048024 -288.917126) (xy 372.048532 -288.891219) (xy 372.056638 -288.840042)
			(xy 372.07265 -288.790763) (xy 372.096173 -288.744596) (xy 372.126629 -288.702677) (xy 372.163267 -288.666039)
			(xy 372.205186 -288.635583) (xy 372.251353 -288.61206) (xy 372.300632 -288.596048) (xy 372.351809 -288.587942)
			(xy 372.403623 -288.587942) (xy 372.4548 -288.596048) (xy 372.504079 -288.61206) (xy 372.550246 -288.635583)
			(xy 372.592165 -288.666039) (xy 372.628803 -288.702677) (xy 372.659259 -288.744596) (xy 372.682782 -288.790763)
			(xy 372.698794 -288.840042) (xy 372.7069 -288.891219) (xy 372.707408 -288.917126) (xy 372.706953 -288.942575)
			(xy 372.699149 -288.992871) (xy 372.683699 -289.041367) (xy 372.660971 -289.086909) (xy 372.631507 -289.128411)
			(xy 372.596009 -289.164887) (xy 372.555321 -289.195466) (xy 372.510413 -289.21942) (xy 372.462353 -289.23618)
			(xy 372.437406 -289.24123) (xy 372.413276 -289.245802) (xy 372.1989 -289.651186) (xy 372.208806 -289.673792)
			(xy 372.217728 -289.694877) (xy 372.230278 -289.738907) (xy 372.23661 -289.78425) (xy 372.237 -289.807142)
			(xy 373.457724 -289.807142) (xy 373.458211 -289.781712) (xy 373.466044 -289.73146) (xy 373.481499 -289.683005)
			(xy 373.50421 -289.637498) (xy 373.533639 -289.596018) (xy 373.569087 -289.559547) (xy 373.609714 -289.528951)
			(xy 373.654557 -289.504956) (xy 373.702553 -289.48813) (xy 373.727472 -289.483038) (xy 373.751602 -289.478466)
			(xy 373.965978 -289.073082) (xy 373.956072 -289.050476) (xy 373.947109 -289.029398) (xy 373.934464 -288.985377)
			(xy 373.928049 -288.940026) (xy 373.927624 -288.917126) (xy 373.928132 -288.891219) (xy 373.936238 -288.840042)
			(xy 373.95225 -288.790763) (xy 373.975773 -288.744596) (xy 374.006229 -288.702677) (xy 374.042867 -288.666039)
			(xy 374.084786 -288.635583) (xy 374.130953 -288.61206) (xy 374.180232 -288.596048) (xy 374.231409 -288.587942)
			(xy 374.283223 -288.587942) (xy 374.3344 -288.596048) (xy 374.383679 -288.61206) (xy 374.429846 -288.635583)
			(xy 374.471765 -288.666039) (xy 374.508403 -288.702677) (xy 374.538859 -288.744596) (xy 374.562382 -288.790763)
			(xy 374.578394 -288.840042) (xy 374.5865 -288.891219) (xy 374.587008 -288.917126) (xy 374.586553 -288.942575)
			(xy 374.578749 -288.992871) (xy 374.563299 -289.041367) (xy 374.540571 -289.086909) (xy 374.511107 -289.128411)
			(xy 374.475609 -289.164887) (xy 374.434921 -289.195466) (xy 374.390013 -289.21942) (xy 374.341953 -289.23618)
			(xy 374.317006 -289.24123) (xy 374.292876 -289.245802) (xy 374.0785 -289.651186) (xy 374.088406 -289.673792)
			(xy 374.097328 -289.694877) (xy 374.109878 -289.738907) (xy 374.11621 -289.78425) (xy 374.1166 -289.807142)
			(xy 375.337324 -289.807142) (xy 375.337811 -289.781712) (xy 375.345644 -289.73146) (xy 375.361099 -289.683005)
			(xy 375.38381 -289.637498) (xy 375.413239 -289.596018) (xy 375.448687 -289.559547) (xy 375.489314 -289.528951)
			(xy 375.534157 -289.504956) (xy 375.582153 -289.48813) (xy 375.607072 -289.483038) (xy 375.631202 -289.478466)
			(xy 375.845578 -289.073082) (xy 375.835672 -289.050476) (xy 375.826709 -289.029398) (xy 375.814064 -288.985377)
			(xy 375.807649 -288.940026) (xy 375.807224 -288.917126) (xy 375.807732 -288.891219) (xy 375.815838 -288.840042)
			(xy 375.83185 -288.790763) (xy 375.855373 -288.744596) (xy 375.885829 -288.702677) (xy 375.922467 -288.666039)
			(xy 375.964386 -288.635583) (xy 376.010553 -288.61206) (xy 376.059832 -288.596048) (xy 376.111009 -288.587942)
			(xy 376.162823 -288.587942) (xy 376.214 -288.596048) (xy 376.263279 -288.61206) (xy 376.309446 -288.635583)
			(xy 376.351365 -288.666039) (xy 376.388003 -288.702677) (xy 376.418459 -288.744596) (xy 376.441982 -288.790763)
			(xy 376.457994 -288.840042) (xy 376.4661 -288.891219) (xy 376.466608 -288.917126) (xy 376.466153 -288.942575)
			(xy 376.458349 -288.992871) (xy 376.442899 -289.041367) (xy 376.420171 -289.086909) (xy 376.390707 -289.128411)
			(xy 376.355209 -289.164887) (xy 376.314521 -289.195466) (xy 376.269613 -289.21942) (xy 376.221553 -289.23618)
			(xy 376.196606 -289.24123) (xy 376.172476 -289.245802) (xy 375.9581 -289.651186) (xy 375.968006 -289.673792)
			(xy 375.976928 -289.694877) (xy 375.989478 -289.738907) (xy 375.99581 -289.78425) (xy 375.9962 -289.807142)
			(xy 377.216924 -289.807142) (xy 377.217411 -289.781712) (xy 377.225244 -289.73146) (xy 377.240699 -289.683005)
			(xy 377.26341 -289.637498) (xy 377.292839 -289.596018) (xy 377.328287 -289.559547) (xy 377.368914 -289.528951)
			(xy 377.413757 -289.504956) (xy 377.461753 -289.48813) (xy 377.486672 -289.483038) (xy 377.510802 -289.478466)
			(xy 377.725178 -289.073082) (xy 377.715272 -289.050476) (xy 377.706309 -289.029398) (xy 377.693664 -288.985377)
			(xy 377.687249 -288.940026) (xy 377.686824 -288.917126) (xy 377.687332 -288.891219) (xy 377.695438 -288.840042)
			(xy 377.71145 -288.790763) (xy 377.734973 -288.744596) (xy 377.765429 -288.702677) (xy 377.802067 -288.666039)
			(xy 377.843986 -288.635583) (xy 377.890153 -288.61206) (xy 377.939432 -288.596048) (xy 377.990609 -288.587942)
			(xy 378.042423 -288.587942) (xy 378.0936 -288.596048) (xy 378.142879 -288.61206) (xy 378.189046 -288.635583)
			(xy 378.230965 -288.666039) (xy 378.267603 -288.702677) (xy 378.298059 -288.744596) (xy 378.321582 -288.790763)
			(xy 378.337594 -288.840042) (xy 378.3457 -288.891219) (xy 378.346208 -288.917126) (xy 378.345753 -288.942575)
			(xy 378.337949 -288.992871) (xy 378.322499 -289.041367) (xy 378.299771 -289.086909) (xy 378.270307 -289.128411)
			(xy 378.234809 -289.164887) (xy 378.194121 -289.195466) (xy 378.149213 -289.21942) (xy 378.101153 -289.23618)
			(xy 378.076206 -289.24123) (xy 378.052076 -289.245802) (xy 377.8377 -289.651186) (xy 377.847606 -289.673792)
			(xy 377.856528 -289.694877) (xy 377.869078 -289.738907) (xy 377.87541 -289.78425) (xy 377.8758 -289.807142)
			(xy 379.096524 -289.807142) (xy 379.097011 -289.781712) (xy 379.104844 -289.73146) (xy 379.120299 -289.683005)
			(xy 379.14301 -289.637498) (xy 379.172439 -289.596018) (xy 379.207887 -289.559547) (xy 379.248514 -289.528951)
			(xy 379.293357 -289.504956) (xy 379.341353 -289.48813) (xy 379.366272 -289.483038) (xy 379.390402 -289.478466)
			(xy 379.604778 -289.073082) (xy 379.594872 -289.050476) (xy 379.585909 -289.029398) (xy 379.573264 -288.985377)
			(xy 379.566849 -288.940026) (xy 379.566424 -288.917126) (xy 379.566932 -288.891219) (xy 379.575038 -288.840042)
			(xy 379.59105 -288.790763) (xy 379.614573 -288.744596) (xy 379.645029 -288.702677) (xy 379.681667 -288.666039)
			(xy 379.723586 -288.635583) (xy 379.769753 -288.61206) (xy 379.819032 -288.596048) (xy 379.870209 -288.587942)
			(xy 379.922023 -288.587942) (xy 379.9732 -288.596048) (xy 380.022479 -288.61206) (xy 380.068646 -288.635583)
			(xy 380.110565 -288.666039) (xy 380.147203 -288.702677) (xy 380.177659 -288.744596) (xy 380.201182 -288.790763)
			(xy 380.217194 -288.840042) (xy 380.2253 -288.891219) (xy 380.225808 -288.917126) (xy 380.225353 -288.942575)
			(xy 380.217549 -288.992871) (xy 380.202099 -289.041367) (xy 380.179371 -289.086909) (xy 380.149907 -289.128411)
			(xy 380.114409 -289.164887) (xy 380.073721 -289.195466) (xy 380.028813 -289.21942) (xy 379.980753 -289.23618)
			(xy 379.955806 -289.24123) (xy 379.931676 -289.245802) (xy 379.7173 -289.651186) (xy 379.727206 -289.673792)
			(xy 379.736128 -289.694877) (xy 379.748678 -289.738907) (xy 379.75501 -289.78425) (xy 379.7554 -289.807142)
			(xy 380.976124 -289.807142) (xy 380.976611 -289.781712) (xy 380.984444 -289.73146) (xy 380.999899 -289.683005)
			(xy 381.02261 -289.637498) (xy 381.052039 -289.596018) (xy 381.087487 -289.559547) (xy 381.128114 -289.528951)
			(xy 381.172957 -289.504956) (xy 381.220953 -289.48813) (xy 381.245872 -289.483038) (xy 381.270002 -289.478466)
			(xy 381.484378 -289.073082) (xy 381.474472 -289.050476) (xy 381.465509 -289.029398) (xy 381.452864 -288.985377)
			(xy 381.446449 -288.940026) (xy 381.446024 -288.917126) (xy 381.446532 -288.891219) (xy 381.454638 -288.840042)
			(xy 381.47065 -288.790763) (xy 381.494173 -288.744596) (xy 381.524629 -288.702677) (xy 381.561267 -288.666039)
			(xy 381.603186 -288.635583) (xy 381.649353 -288.61206) (xy 381.698632 -288.596048) (xy 381.749809 -288.587942)
			(xy 381.801623 -288.587942) (xy 381.8528 -288.596048) (xy 381.902079 -288.61206) (xy 381.948246 -288.635583)
			(xy 381.990165 -288.666039) (xy 382.026803 -288.702677) (xy 382.057259 -288.744596) (xy 382.080782 -288.790763)
			(xy 382.096794 -288.840042) (xy 382.1049 -288.891219) (xy 382.105408 -288.917126) (xy 382.104953 -288.942575)
			(xy 382.097149 -288.992871) (xy 382.081699 -289.041367) (xy 382.058971 -289.086909) (xy 382.029507 -289.128411)
			(xy 381.994009 -289.164887) (xy 381.953321 -289.195466) (xy 381.908413 -289.21942) (xy 381.860353 -289.23618)
			(xy 381.835406 -289.24123) (xy 381.811276 -289.245802) (xy 381.5969 -289.651186) (xy 381.606806 -289.673792)
			(xy 381.615728 -289.694877) (xy 381.628278 -289.738907) (xy 381.63461 -289.78425) (xy 381.635 -289.807142)
			(xy 381.634492 -289.833029) (xy 381.626393 -289.884167) (xy 381.610394 -289.933407) (xy 381.586888 -289.979539)
			(xy 381.556456 -290.021426) (xy 381.519846 -290.058036) (xy 381.477959 -290.088468) (xy 381.431827 -290.111974)
			(xy 381.382587 -290.127973) (xy 381.331449 -290.136072) (xy 381.279675 -290.136072) (xy 381.228537 -290.127973)
			(xy 381.179297 -290.111974) (xy 381.133165 -290.088468) (xy 381.091278 -290.058036) (xy 381.054668 -290.021426)
			(xy 381.024236 -289.979539) (xy 381.00073 -289.933407) (xy 380.984731 -289.884167) (xy 380.976632 -289.833029)
			(xy 380.976124 -289.807142) (xy 379.7554 -289.807142) (xy 379.754892 -289.833029) (xy 379.746793 -289.884167)
			(xy 379.730794 -289.933407) (xy 379.707288 -289.979539) (xy 379.676856 -290.021426) (xy 379.640246 -290.058036)
			(xy 379.598359 -290.088468) (xy 379.552227 -290.111974) (xy 379.502987 -290.127973) (xy 379.451849 -290.136072)
			(xy 379.400075 -290.136072) (xy 379.348937 -290.127973) (xy 379.299697 -290.111974) (xy 379.253565 -290.088468)
			(xy 379.211678 -290.058036) (xy 379.175068 -290.021426) (xy 379.144636 -289.979539) (xy 379.12113 -289.933407)
			(xy 379.105131 -289.884167) (xy 379.097032 -289.833029) (xy 379.096524 -289.807142) (xy 377.8758 -289.807142)
			(xy 377.875292 -289.833029) (xy 377.867193 -289.884167) (xy 377.851194 -289.933407) (xy 377.827688 -289.979539)
			(xy 377.797256 -290.021426) (xy 377.760646 -290.058036) (xy 377.718759 -290.088468) (xy 377.672627 -290.111974)
			(xy 377.623387 -290.127973) (xy 377.572249 -290.136072) (xy 377.520475 -290.136072) (xy 377.469337 -290.127973)
			(xy 377.420097 -290.111974) (xy 377.373965 -290.088468) (xy 377.332078 -290.058036) (xy 377.295468 -290.021426)
			(xy 377.265036 -289.979539) (xy 377.24153 -289.933407) (xy 377.225531 -289.884167) (xy 377.217432 -289.833029)
			(xy 377.216924 -289.807142) (xy 375.9962 -289.807142) (xy 375.995692 -289.833029) (xy 375.987593 -289.884167)
			(xy 375.971594 -289.933407) (xy 375.948088 -289.979539) (xy 375.917656 -290.021426) (xy 375.881046 -290.058036)
			(xy 375.839159 -290.088468) (xy 375.793027 -290.111974) (xy 375.743787 -290.127973) (xy 375.692649 -290.136072)
			(xy 375.640875 -290.136072) (xy 375.589737 -290.127973) (xy 375.540497 -290.111974) (xy 375.494365 -290.088468)
			(xy 375.452478 -290.058036) (xy 375.415868 -290.021426) (xy 375.385436 -289.979539) (xy 375.36193 -289.933407)
			(xy 375.345931 -289.884167) (xy 375.337832 -289.833029) (xy 375.337324 -289.807142) (xy 374.1166 -289.807142)
			(xy 374.116092 -289.833029) (xy 374.107993 -289.884167) (xy 374.091994 -289.933407) (xy 374.068488 -289.979539)
			(xy 374.038056 -290.021426) (xy 374.001446 -290.058036) (xy 373.959559 -290.088468) (xy 373.913427 -290.111974)
			(xy 373.864187 -290.127973) (xy 373.813049 -290.136072) (xy 373.761275 -290.136072) (xy 373.710137 -290.127973)
			(xy 373.660897 -290.111974) (xy 373.614765 -290.088468) (xy 373.572878 -290.058036) (xy 373.536268 -290.021426)
			(xy 373.505836 -289.979539) (xy 373.48233 -289.933407) (xy 373.466331 -289.884167) (xy 373.458232 -289.833029)
			(xy 373.457724 -289.807142) (xy 372.237 -289.807142) (xy 372.236492 -289.833029) (xy 372.228393 -289.884167)
			(xy 372.212394 -289.933407) (xy 372.188888 -289.979539) (xy 372.158456 -290.021426) (xy 372.121846 -290.058036)
			(xy 372.079959 -290.088468) (xy 372.033827 -290.111974) (xy 371.984587 -290.127973) (xy 371.933449 -290.136072)
			(xy 371.881675 -290.136072) (xy 371.830537 -290.127973) (xy 371.781297 -290.111974) (xy 371.735165 -290.088468)
			(xy 371.693278 -290.058036) (xy 371.656668 -290.021426) (xy 371.626236 -289.979539) (xy 371.60273 -289.933407)
			(xy 371.586731 -289.884167) (xy 371.578632 -289.833029) (xy 371.578124 -289.807142) (xy 370.3574 -289.807142)
			(xy 370.356892 -289.833029) (xy 370.348793 -289.884167) (xy 370.332794 -289.933407) (xy 370.309288 -289.979539)
			(xy 370.278856 -290.021426) (xy 370.242246 -290.058036) (xy 370.200359 -290.088468) (xy 370.154227 -290.111974)
			(xy 370.104987 -290.127973) (xy 370.053849 -290.136072) (xy 370.002075 -290.136072) (xy 369.950937 -290.127973)
			(xy 369.901697 -290.111974) (xy 369.855565 -290.088468) (xy 369.813678 -290.058036) (xy 369.777068 -290.021426)
			(xy 369.746636 -289.979539) (xy 369.72313 -289.933407) (xy 369.707131 -289.884167) (xy 369.699032 -289.833029)
			(xy 369.698524 -289.807142) (xy 368.4778 -289.807142) (xy 368.477292 -289.833029) (xy 368.469193 -289.884167)
			(xy 368.453194 -289.933407) (xy 368.429688 -289.979539) (xy 368.399256 -290.021426) (xy 368.362646 -290.058036)
			(xy 368.320759 -290.088468) (xy 368.274627 -290.111974) (xy 368.225387 -290.127973) (xy 368.174249 -290.136072)
			(xy 368.122475 -290.136072) (xy 368.071337 -290.127973) (xy 368.022097 -290.111974) (xy 367.975965 -290.088468)
			(xy 367.934078 -290.058036) (xy 367.897468 -290.021426) (xy 367.867036 -289.979539) (xy 367.84353 -289.933407)
			(xy 367.827531 -289.884167) (xy 367.819432 -289.833029) (xy 367.818924 -289.807142) (xy 351.5614 -289.807142)
			(xy 351.560892 -289.833029) (xy 351.552793 -289.884167) (xy 351.536794 -289.933407) (xy 351.513288 -289.979539)
			(xy 351.482856 -290.021426) (xy 351.446246 -290.058036) (xy 351.404359 -290.088468) (xy 351.358227 -290.111974)
			(xy 351.308987 -290.127973) (xy 351.257849 -290.136072) (xy 351.206075 -290.136072) (xy 351.154937 -290.127973)
			(xy 351.105697 -290.111974) (xy 351.059565 -290.088468) (xy 351.017678 -290.058036) (xy 350.981068 -290.021426)
			(xy 350.950636 -289.979539) (xy 350.92713 -289.933407) (xy 350.911131 -289.884167) (xy 350.903032 -289.833029)
			(xy 350.902524 -289.807142) (xy 350.902524 -289.806634) (xy 350.902922 -289.783785) (xy 350.909275 -289.738531)
			(xy 350.921824 -289.694589) (xy 350.930718 -289.673538) (xy 350.940624 -289.650932) (xy 350.726756 -289.245802)
			(xy 350.702626 -289.24123) (xy 350.677682 -289.236182) (xy 350.629639 -289.219398) (xy 350.584746 -289.195428)
			(xy 350.544072 -289.164843) (xy 350.508582 -289.128369) (xy 350.479121 -289.086873) (xy 350.456389 -289.041341)
			(xy 350.440925 -288.992857) (xy 350.433099 -288.942571) (xy 350.432624 -288.917126) (xy 350.152208 -288.917126)
			(xy 350.1517 -288.943033) (xy 350.143594 -288.99421) (xy 350.127582 -289.043489) (xy 350.104059 -289.089656)
			(xy 350.073603 -289.131575) (xy 350.036965 -289.168213) (xy 349.995046 -289.198669) (xy 349.948879 -289.222192)
			(xy 349.8996 -289.238204) (xy 349.848423 -289.24631) (xy 349.796609 -289.24631) (xy 349.745432 -289.238204)
			(xy 349.696153 -289.222192) (xy 349.649986 -289.198669) (xy 349.608067 -289.168213) (xy 349.571429 -289.131575)
			(xy 349.540973 -289.089656) (xy 349.51745 -289.043489) (xy 349.501438 -288.99421) (xy 349.493332 -288.943033)
			(xy 349.492824 -288.917126) (xy 349.212408 -288.917126) (xy 349.211989 -288.940067) (xy 349.20556 -288.985498)
			(xy 349.192913 -289.029604) (xy 349.18396 -289.05073) (xy 349.174054 -289.073336) (xy 349.387922 -289.478466)
			(xy 349.412052 -289.483038) (xy 349.436973 -289.488138) (xy 349.484984 -289.504939) (xy 349.529843 -289.528919)
			(xy 349.570484 -289.559507) (xy 349.605941 -289.595978) (xy 349.635373 -289.637465) (xy 349.658079 -289.682981)
			(xy 349.673521 -289.731446) (xy 349.681331 -289.781709) (xy 349.6818 -289.807142) (xy 349.681292 -289.833029)
			(xy 349.673193 -289.884167) (xy 349.657194 -289.933407) (xy 349.633688 -289.979539) (xy 349.603256 -290.021426)
			(xy 349.566646 -290.058036) (xy 349.524759 -290.088468) (xy 349.478627 -290.111974) (xy 349.429387 -290.127973)
			(xy 349.378249 -290.136072) (xy 349.326475 -290.136072) (xy 349.275337 -290.127973) (xy 349.226097 -290.111974)
			(xy 349.179965 -290.088468) (xy 349.138078 -290.058036) (xy 349.101468 -290.021426) (xy 349.071036 -289.979539)
			(xy 349.04753 -289.933407) (xy 349.031531 -289.884167) (xy 349.023432 -289.833029) (xy 349.022924 -289.807142)
			(xy 349.022924 -289.806634) (xy 349.023322 -289.783785) (xy 349.029675 -289.738531) (xy 349.042224 -289.694589)
			(xy 349.051118 -289.673538) (xy 349.061024 -289.650932) (xy 348.847156 -289.245802) (xy 348.823026 -289.24123)
			(xy 348.798082 -289.236182) (xy 348.750039 -289.219398) (xy 348.705146 -289.195428) (xy 348.664472 -289.164843)
			(xy 348.628982 -289.128369) (xy 348.599521 -289.086873) (xy 348.576789 -289.041341) (xy 348.561325 -288.992857)
			(xy 348.553499 -288.942571) (xy 348.553024 -288.917126) (xy 348.272608 -288.917126) (xy 348.2721 -288.943033)
			(xy 348.263994 -288.99421) (xy 348.247982 -289.043489) (xy 348.224459 -289.089656) (xy 348.194003 -289.131575)
			(xy 348.157365 -289.168213) (xy 348.115446 -289.198669) (xy 348.069279 -289.222192) (xy 348.02 -289.238204)
			(xy 347.968823 -289.24631) (xy 347.917009 -289.24631) (xy 347.865832 -289.238204) (xy 347.816553 -289.222192)
			(xy 347.770386 -289.198669) (xy 347.728467 -289.168213) (xy 347.691829 -289.131575) (xy 347.661373 -289.089656)
			(xy 347.63785 -289.043489) (xy 347.621838 -288.99421) (xy 347.613732 -288.943033) (xy 347.613224 -288.917126)
			(xy 347.332808 -288.917126) (xy 347.332389 -288.940067) (xy 347.32596 -288.985498) (xy 347.313313 -289.029604)
			(xy 347.30436 -289.05073) (xy 347.294454 -289.073336) (xy 347.508322 -289.478466) (xy 347.532452 -289.483038)
			(xy 347.557373 -289.488138) (xy 347.605384 -289.504939) (xy 347.650243 -289.528919) (xy 347.690884 -289.559507)
			(xy 347.726341 -289.595978) (xy 347.755773 -289.637465) (xy 347.778479 -289.682981) (xy 347.793921 -289.731446)
			(xy 347.801731 -289.781709) (xy 347.8022 -289.807142) (xy 347.801692 -289.833029) (xy 347.793593 -289.884167)
			(xy 347.777594 -289.933407) (xy 347.754088 -289.979539) (xy 347.723656 -290.021426) (xy 347.687046 -290.058036)
			(xy 347.645159 -290.088468) (xy 347.599027 -290.111974) (xy 347.549787 -290.127973) (xy 347.498649 -290.136072)
			(xy 347.446875 -290.136072) (xy 347.395737 -290.127973) (xy 347.346497 -290.111974) (xy 347.300365 -290.088468)
			(xy 347.258478 -290.058036) (xy 347.221868 -290.021426) (xy 347.191436 -289.979539) (xy 347.16793 -289.933407)
			(xy 347.151931 -289.884167) (xy 347.143832 -289.833029) (xy 347.143324 -289.807142) (xy 347.143324 -289.806634)
			(xy 347.143722 -289.783785) (xy 347.150075 -289.738531) (xy 347.162624 -289.694589) (xy 347.171518 -289.673538)
			(xy 347.181424 -289.650932) (xy 346.967556 -289.245802) (xy 346.943426 -289.24123) (xy 346.918482 -289.236182)
			(xy 346.870439 -289.219398) (xy 346.825546 -289.195428) (xy 346.784872 -289.164843) (xy 346.749382 -289.128369)
			(xy 346.719921 -289.086873) (xy 346.697189 -289.041341) (xy 346.681725 -288.992857) (xy 346.673899 -288.942571)
			(xy 346.673424 -288.917126) (xy 346.393008 -288.917126) (xy 346.3925 -288.943033) (xy 346.384394 -288.99421)
			(xy 346.368382 -289.043489) (xy 346.344859 -289.089656) (xy 346.314403 -289.131575) (xy 346.277765 -289.168213)
			(xy 346.235846 -289.198669) (xy 346.189679 -289.222192) (xy 346.1404 -289.238204) (xy 346.089223 -289.24631)
			(xy 346.037409 -289.24631) (xy 345.986232 -289.238204) (xy 345.936953 -289.222192) (xy 345.890786 -289.198669)
			(xy 345.848867 -289.168213) (xy 345.812229 -289.131575) (xy 345.781773 -289.089656) (xy 345.75825 -289.043489)
			(xy 345.742238 -288.99421) (xy 345.734132 -288.943033) (xy 345.733624 -288.917126) (xy 345.453208 -288.917126)
			(xy 345.452789 -288.940067) (xy 345.44636 -288.985498) (xy 345.433713 -289.029604) (xy 345.42476 -289.05073)
			(xy 345.414854 -289.073336) (xy 345.628722 -289.478466) (xy 345.652852 -289.483038) (xy 345.677773 -289.488138)
			(xy 345.725784 -289.504939) (xy 345.770643 -289.528919) (xy 345.811284 -289.559507) (xy 345.846741 -289.595978)
			(xy 345.876173 -289.637465) (xy 345.898879 -289.682981) (xy 345.914321 -289.731446) (xy 345.922131 -289.781709)
			(xy 345.9226 -289.807142) (xy 345.922092 -289.833029) (xy 345.913993 -289.884167) (xy 345.897994 -289.933407)
			(xy 345.874488 -289.979539) (xy 345.844056 -290.021426) (xy 345.807446 -290.058036) (xy 345.765559 -290.088468)
			(xy 345.719427 -290.111974) (xy 345.670187 -290.127973) (xy 345.619049 -290.136072) (xy 345.567275 -290.136072)
			(xy 345.516137 -290.127973) (xy 345.466897 -290.111974) (xy 345.420765 -290.088468) (xy 345.378878 -290.058036)
			(xy 345.342268 -290.021426) (xy 345.311836 -289.979539) (xy 345.28833 -289.933407) (xy 345.272331 -289.884167)
			(xy 345.264232 -289.833029) (xy 345.263724 -289.807142) (xy 345.263724 -289.806634) (xy 345.264122 -289.783785)
			(xy 345.270475 -289.738531) (xy 345.283024 -289.694589) (xy 345.291918 -289.673538) (xy 345.301824 -289.650932)
			(xy 345.087956 -289.245802) (xy 345.063826 -289.24123) (xy 345.038882 -289.236182) (xy 344.990839 -289.219398)
			(xy 344.945946 -289.195428) (xy 344.905272 -289.164843) (xy 344.869782 -289.128369) (xy 344.840321 -289.086873)
			(xy 344.817589 -289.041341) (xy 344.802125 -288.992857) (xy 344.794299 -288.942571) (xy 344.793824 -288.917126)
			(xy 344.513408 -288.917126) (xy 344.5129 -288.943033) (xy 344.504794 -288.99421) (xy 344.488782 -289.043489)
			(xy 344.465259 -289.089656) (xy 344.434803 -289.131575) (xy 344.398165 -289.168213) (xy 344.356246 -289.198669)
			(xy 344.310079 -289.222192) (xy 344.2608 -289.238204) (xy 344.209623 -289.24631) (xy 344.157809 -289.24631)
			(xy 344.106632 -289.238204) (xy 344.057353 -289.222192) (xy 344.011186 -289.198669) (xy 343.969267 -289.168213)
			(xy 343.932629 -289.131575) (xy 343.902173 -289.089656) (xy 343.87865 -289.043489) (xy 343.862638 -288.99421)
			(xy 343.854532 -288.943033) (xy 343.854024 -288.917126) (xy 343.573608 -288.917126) (xy 343.573189 -288.940067)
			(xy 343.56676 -288.985498) (xy 343.554113 -289.029604) (xy 343.54516 -289.05073) (xy 343.535254 -289.073336)
			(xy 343.749122 -289.478466) (xy 343.773252 -289.483038) (xy 343.798173 -289.488138) (xy 343.846184 -289.504939)
			(xy 343.891043 -289.528919) (xy 343.931684 -289.559507) (xy 343.967141 -289.595978) (xy 343.996573 -289.637465)
			(xy 344.019279 -289.682981) (xy 344.034721 -289.731446) (xy 344.042531 -289.781709) (xy 344.043 -289.807142)
			(xy 344.042492 -289.833029) (xy 344.034393 -289.884167) (xy 344.018394 -289.933407) (xy 343.994888 -289.979539)
			(xy 343.964456 -290.021426) (xy 343.927846 -290.058036) (xy 343.885959 -290.088468) (xy 343.839827 -290.111974)
			(xy 343.790587 -290.127973) (xy 343.739449 -290.136072) (xy 343.687675 -290.136072) (xy 343.636537 -290.127973)
			(xy 343.587297 -290.111974) (xy 343.541165 -290.088468) (xy 343.499278 -290.058036) (xy 343.462668 -290.021426)
			(xy 343.432236 -289.979539) (xy 343.40873 -289.933407) (xy 343.392731 -289.884167) (xy 343.384632 -289.833029)
			(xy 343.384124 -289.807142) (xy 343.384124 -289.806634) (xy 343.384522 -289.783785) (xy 343.390875 -289.738531)
			(xy 343.403424 -289.694589) (xy 343.412318 -289.673538) (xy 343.422224 -289.650932) (xy 343.208356 -289.245802)
			(xy 343.184226 -289.24123) (xy 343.159282 -289.236182) (xy 343.111239 -289.219398) (xy 343.066346 -289.195428)
			(xy 343.025672 -289.164843) (xy 342.990182 -289.128369) (xy 342.960721 -289.086873) (xy 342.937989 -289.041341)
			(xy 342.922525 -288.992857) (xy 342.914699 -288.942571) (xy 342.914224 -288.917126) (xy 342.633808 -288.917126)
			(xy 342.6333 -288.943033) (xy 342.625194 -288.99421) (xy 342.609182 -289.043489) (xy 342.585659 -289.089656)
			(xy 342.555203 -289.131575) (xy 342.518565 -289.168213) (xy 342.476646 -289.198669) (xy 342.430479 -289.222192)
			(xy 342.3812 -289.238204) (xy 342.330023 -289.24631) (xy 342.278209 -289.24631) (xy 342.227032 -289.238204)
			(xy 342.177753 -289.222192) (xy 342.131586 -289.198669) (xy 342.089667 -289.168213) (xy 342.053029 -289.131575)
			(xy 342.022573 -289.089656) (xy 341.99905 -289.043489) (xy 341.983038 -288.99421) (xy 341.974932 -288.943033)
			(xy 341.974424 -288.917126) (xy 341.694008 -288.917126) (xy 341.693589 -288.940067) (xy 341.68716 -288.985498)
			(xy 341.674513 -289.029604) (xy 341.66556 -289.05073) (xy 341.655654 -289.073336) (xy 341.869522 -289.478466)
			(xy 341.893652 -289.483038) (xy 341.918573 -289.488138) (xy 341.966584 -289.504939) (xy 342.011443 -289.528919)
			(xy 342.052084 -289.559507) (xy 342.087541 -289.595978) (xy 342.116973 -289.637465) (xy 342.139679 -289.682981)
			(xy 342.155121 -289.731446) (xy 342.162931 -289.781709) (xy 342.1634 -289.807142) (xy 342.162892 -289.833029)
			(xy 342.154793 -289.884167) (xy 342.138794 -289.933407) (xy 342.115288 -289.979539) (xy 342.084856 -290.021426)
			(xy 342.048246 -290.058036) (xy 342.006359 -290.088468) (xy 341.960227 -290.111974) (xy 341.910987 -290.127973)
			(xy 341.859849 -290.136072) (xy 341.808075 -290.136072) (xy 341.756937 -290.127973) (xy 341.707697 -290.111974)
			(xy 341.661565 -290.088468) (xy 341.619678 -290.058036) (xy 341.583068 -290.021426) (xy 341.552636 -289.979539)
			(xy 341.52913 -289.933407) (xy 341.513131 -289.884167) (xy 341.505032 -289.833029) (xy 341.504524 -289.807142)
			(xy 341.504524 -289.806634) (xy 341.504922 -289.783785) (xy 341.511275 -289.738531) (xy 341.523824 -289.694589)
			(xy 341.532718 -289.673538) (xy 341.542624 -289.650932) (xy 341.328756 -289.245802) (xy 341.304626 -289.24123)
			(xy 341.279682 -289.236182) (xy 341.231639 -289.219398) (xy 341.186746 -289.195428) (xy 341.146072 -289.164843)
			(xy 341.110582 -289.128369) (xy 341.081121 -289.086873) (xy 341.058389 -289.041341) (xy 341.042925 -288.992857)
			(xy 341.035099 -288.942571) (xy 341.034624 -288.917126) (xy 340.754208 -288.917126) (xy 340.7537 -288.943033)
			(xy 340.745594 -288.99421) (xy 340.729582 -289.043489) (xy 340.706059 -289.089656) (xy 340.675603 -289.131575)
			(xy 340.638965 -289.168213) (xy 340.597046 -289.198669) (xy 340.550879 -289.222192) (xy 340.5016 -289.238204)
			(xy 340.450423 -289.24631) (xy 340.398609 -289.24631) (xy 340.347432 -289.238204) (xy 340.298153 -289.222192)
			(xy 340.251986 -289.198669) (xy 340.210067 -289.168213) (xy 340.173429 -289.131575) (xy 340.142973 -289.089656)
			(xy 340.11945 -289.043489) (xy 340.103438 -288.99421) (xy 340.095332 -288.943033) (xy 340.094824 -288.917126)
			(xy 339.814408 -288.917126) (xy 339.813989 -288.940067) (xy 339.80756 -288.985498) (xy 339.794913 -289.029604)
			(xy 339.78596 -289.05073) (xy 339.776054 -289.073336) (xy 339.989922 -289.478466) (xy 340.014052 -289.483038)
			(xy 340.038973 -289.488138) (xy 340.086984 -289.504939) (xy 340.131843 -289.528919) (xy 340.172484 -289.559507)
			(xy 340.207941 -289.595978) (xy 340.237373 -289.637465) (xy 340.260079 -289.682981) (xy 340.275521 -289.731446)
			(xy 340.283331 -289.781709) (xy 340.2838 -289.807142) (xy 340.283292 -289.833029) (xy 340.275193 -289.884167)
			(xy 340.259194 -289.933407) (xy 340.235688 -289.979539) (xy 340.205256 -290.021426) (xy 340.168646 -290.058036)
			(xy 340.126759 -290.088468) (xy 340.080627 -290.111974) (xy 340.031387 -290.127973) (xy 339.980249 -290.136072)
			(xy 339.928475 -290.136072) (xy 339.877337 -290.127973) (xy 339.828097 -290.111974) (xy 339.781965 -290.088468)
			(xy 339.740078 -290.058036) (xy 339.703468 -290.021426) (xy 339.673036 -289.979539) (xy 339.64953 -289.933407)
			(xy 339.633531 -289.884167) (xy 339.625432 -289.833029) (xy 339.624924 -289.807142) (xy 339.624924 -289.806634)
			(xy 339.625322 -289.783785) (xy 339.631675 -289.738531) (xy 339.644224 -289.694589) (xy 339.653118 -289.673538)
			(xy 339.663024 -289.650932) (xy 339.449156 -289.245802) (xy 339.425026 -289.24123) (xy 339.400082 -289.236182)
			(xy 339.352039 -289.219398) (xy 339.307146 -289.195428) (xy 339.266472 -289.164843) (xy 339.230982 -289.128369)
			(xy 339.201521 -289.086873) (xy 339.178789 -289.041341) (xy 339.163325 -288.992857) (xy 339.155499 -288.942571)
			(xy 339.155024 -288.917126) (xy 338.874608 -288.917126) (xy 338.8741 -288.943033) (xy 338.865994 -288.99421)
			(xy 338.849982 -289.043489) (xy 338.826459 -289.089656) (xy 338.796003 -289.131575) (xy 338.759365 -289.168213)
			(xy 338.717446 -289.198669) (xy 338.671279 -289.222192) (xy 338.622 -289.238204) (xy 338.570823 -289.24631)
			(xy 338.519009 -289.24631) (xy 338.467832 -289.238204) (xy 338.418553 -289.222192) (xy 338.372386 -289.198669)
			(xy 338.330467 -289.168213) (xy 338.293829 -289.131575) (xy 338.263373 -289.089656) (xy 338.23985 -289.043489)
			(xy 338.223838 -288.99421) (xy 338.215732 -288.943033) (xy 338.215224 -288.917126) (xy 336.995008 -288.917126)
			(xy 336.9945 -288.943033) (xy 336.986394 -288.99421) (xy 336.970382 -289.043489) (xy 336.946859 -289.089656)
			(xy 336.916403 -289.131575) (xy 336.879765 -289.168213) (xy 336.837846 -289.198669) (xy 336.791679 -289.222192)
			(xy 336.7424 -289.238204) (xy 336.691223 -289.24631) (xy 336.639409 -289.24631) (xy 336.588232 -289.238204)
			(xy 336.538953 -289.222192) (xy 336.492786 -289.198669) (xy 336.450867 -289.168213) (xy 336.414229 -289.131575)
			(xy 336.383773 -289.089656) (xy 336.36025 -289.043489) (xy 336.344238 -288.99421) (xy 336.336132 -288.943033)
			(xy 336.335624 -288.917126) (xy 136.04494 -288.917126) (xy 136.044432 -288.943033) (xy 136.036326 -288.99421)
			(xy 136.020314 -289.043489) (xy 135.996791 -289.089656) (xy 135.966335 -289.131575) (xy 135.929697 -289.168213)
			(xy 135.887778 -289.198669) (xy 135.841611 -289.222192) (xy 135.792332 -289.238204) (xy 135.741155 -289.24631)
			(xy 135.689341 -289.24631) (xy 135.638164 -289.238204) (xy 135.588885 -289.222192) (xy 135.542718 -289.198669)
			(xy 135.500799 -289.168213) (xy 135.464161 -289.131575) (xy 135.433705 -289.089656) (xy 135.410182 -289.043489)
			(xy 135.39417 -288.99421) (xy 135.386064 -288.943033) (xy 135.385556 -288.917126) (xy 135.386153 -288.889409)
			(xy 135.395474 -288.834762) (xy 135.404098 -288.808414) (xy 135.411972 -288.786316) (xy 135.20674 -288.431224)
			(xy 135.18388 -288.426906) (xy 135.159064 -288.421716) (xy 135.111285 -288.404766) (xy 135.066665 -288.380698)
			(xy 135.026258 -288.350081) (xy 134.991016 -288.313637) (xy 134.961772 -288.272226) (xy 134.939214 -288.226825)
			(xy 134.923875 -288.178504) (xy 134.916118 -288.128404) (xy 134.915656 -288.103056) (xy 132.75564 -288.103056)
			(xy 132.755038 -288.130773) (xy 132.74572 -288.18542) (xy 132.737098 -288.211768) (xy 132.729478 -288.233866)
			(xy 132.934456 -288.588958) (xy 132.957316 -288.593276) (xy 132.982127 -288.598486) (xy 133.029905 -288.615434)
			(xy 133.074524 -288.6395) (xy 133.114931 -288.670114) (xy 133.150173 -288.706556) (xy 133.179418 -288.747964)
			(xy 133.201977 -288.793363) (xy 133.217317 -288.841681) (xy 133.225077 -288.891779) (xy 133.22554 -288.917126)
			(xy 133.225032 -288.943033) (xy 133.216926 -288.99421) (xy 133.200914 -289.043489) (xy 133.177391 -289.089656)
			(xy 133.146935 -289.131575) (xy 133.110297 -289.168213) (xy 133.068378 -289.198669) (xy 133.022211 -289.222192)
			(xy 132.972932 -289.238204) (xy 132.921755 -289.24631) (xy 132.869941 -289.24631) (xy 132.818764 -289.238204)
			(xy 132.769485 -289.222192) (xy 132.723318 -289.198669) (xy 132.681399 -289.168213) (xy 132.644761 -289.131575)
			(xy 132.614305 -289.089656) (xy 132.590782 -289.043489) (xy 132.57477 -288.99421) (xy 132.566664 -288.943033)
			(xy 132.566156 -288.917126) (xy 132.566753 -288.889409) (xy 132.576074 -288.834762) (xy 132.584698 -288.808414)
			(xy 132.592572 -288.786316) (xy 132.387594 -288.431224) (xy 132.364734 -288.426906) (xy 132.339899 -288.421756)
			(xy 132.292089 -288.404821) (xy 132.247438 -288.380764) (xy 132.206999 -288.350151) (xy 132.171726 -288.313705)
			(xy 132.142451 -288.272287) (xy 132.119866 -288.226873) (xy 132.104504 -288.178536) (xy 132.096726 -288.128416)
			(xy 132.096256 -288.103056) (xy 130.87604 -288.103056) (xy 130.875438 -288.130773) (xy 130.86612 -288.18542)
			(xy 130.857498 -288.211768) (xy 130.849878 -288.233866) (xy 131.054856 -288.588958) (xy 131.077716 -288.593276)
			(xy 131.102527 -288.598486) (xy 131.150305 -288.615434) (xy 131.194924 -288.6395) (xy 131.235331 -288.670114)
			(xy 131.270573 -288.706556) (xy 131.299818 -288.747964) (xy 131.322377 -288.793363) (xy 131.337717 -288.841681)
			(xy 131.345477 -288.891779) (xy 131.34594 -288.917126) (xy 131.345432 -288.943033) (xy 131.337326 -288.99421)
			(xy 131.321314 -289.043489) (xy 131.297791 -289.089656) (xy 131.267335 -289.131575) (xy 131.230697 -289.168213)
			(xy 131.188778 -289.198669) (xy 131.142611 -289.222192) (xy 131.093332 -289.238204) (xy 131.042155 -289.24631)
			(xy 130.990341 -289.24631) (xy 130.939164 -289.238204) (xy 130.889885 -289.222192) (xy 130.843718 -289.198669)
			(xy 130.801799 -289.168213) (xy 130.765161 -289.131575) (xy 130.734705 -289.089656) (xy 130.711182 -289.043489)
			(xy 130.69517 -288.99421) (xy 130.687064 -288.943033) (xy 130.686556 -288.917126) (xy 130.687153 -288.889409)
			(xy 130.696474 -288.834762) (xy 130.705098 -288.808414) (xy 130.712972 -288.786316) (xy 130.507994 -288.431224)
			(xy 130.485134 -288.426906) (xy 130.460299 -288.421756) (xy 130.412489 -288.404821) (xy 130.367838 -288.380764)
			(xy 130.327399 -288.350151) (xy 130.292126 -288.313705) (xy 130.262851 -288.272287) (xy 130.240266 -288.226873)
			(xy 130.224904 -288.178536) (xy 130.217126 -288.128416) (xy 130.216656 -288.103056) (xy 128.99644 -288.103056)
			(xy 128.995838 -288.130773) (xy 128.98652 -288.18542) (xy 128.977898 -288.211768) (xy 128.970278 -288.233866)
			(xy 129.175256 -288.588958) (xy 129.198116 -288.593276) (xy 129.222927 -288.598486) (xy 129.270705 -288.615434)
			(xy 129.315324 -288.6395) (xy 129.355731 -288.670114) (xy 129.390973 -288.706556) (xy 129.420218 -288.747964)
			(xy 129.442777 -288.793363) (xy 129.458117 -288.841681) (xy 129.465877 -288.891779) (xy 129.46634 -288.917126)
			(xy 129.465832 -288.943033) (xy 129.457726 -288.99421) (xy 129.441714 -289.043489) (xy 129.418191 -289.089656)
			(xy 129.387735 -289.131575) (xy 129.351097 -289.168213) (xy 129.309178 -289.198669) (xy 129.263011 -289.222192)
			(xy 129.213732 -289.238204) (xy 129.162555 -289.24631) (xy 129.110741 -289.24631) (xy 129.059564 -289.238204)
			(xy 129.010285 -289.222192) (xy 128.964118 -289.198669) (xy 128.922199 -289.168213) (xy 128.885561 -289.131575)
			(xy 128.855105 -289.089656) (xy 128.831582 -289.043489) (xy 128.81557 -288.99421) (xy 128.807464 -288.943033)
			(xy 128.806956 -288.917126) (xy 128.807553 -288.889409) (xy 128.816874 -288.834762) (xy 128.825498 -288.808414)
			(xy 128.833372 -288.786316) (xy 128.628394 -288.431224) (xy 128.605534 -288.426906) (xy 128.580699 -288.421756)
			(xy 128.532889 -288.404821) (xy 128.488238 -288.380764) (xy 128.447799 -288.350151) (xy 128.412526 -288.313705)
			(xy 128.383251 -288.272287) (xy 128.360666 -288.226873) (xy 128.345304 -288.178536) (xy 128.337526 -288.128416)
			(xy 128.337056 -288.103056) (xy 127.11684 -288.103056) (xy 127.116238 -288.130773) (xy 127.10692 -288.18542)
			(xy 127.098298 -288.211768) (xy 127.090678 -288.233866) (xy 127.295656 -288.588958) (xy 127.318516 -288.593276)
			(xy 127.343327 -288.598486) (xy 127.391105 -288.615434) (xy 127.435724 -288.6395) (xy 127.476131 -288.670114)
			(xy 127.511373 -288.706556) (xy 127.540618 -288.747964) (xy 127.563177 -288.793363) (xy 127.578517 -288.841681)
			(xy 127.586277 -288.891779) (xy 127.58674 -288.917126) (xy 127.586232 -288.943033) (xy 127.578126 -288.99421)
			(xy 127.562114 -289.043489) (xy 127.538591 -289.089656) (xy 127.508135 -289.131575) (xy 127.471497 -289.168213)
			(xy 127.429578 -289.198669) (xy 127.383411 -289.222192) (xy 127.334132 -289.238204) (xy 127.282955 -289.24631)
			(xy 127.231141 -289.24631) (xy 127.179964 -289.238204) (xy 127.130685 -289.222192) (xy 127.084518 -289.198669)
			(xy 127.042599 -289.168213) (xy 127.005961 -289.131575) (xy 126.975505 -289.089656) (xy 126.951982 -289.043489)
			(xy 126.93597 -288.99421) (xy 126.927864 -288.943033) (xy 126.927356 -288.917126) (xy 126.927953 -288.889409)
			(xy 126.937274 -288.834762) (xy 126.945898 -288.808414) (xy 126.953772 -288.786316) (xy 126.748794 -288.431224)
			(xy 126.725934 -288.426906) (xy 126.701099 -288.421756) (xy 126.653289 -288.404821) (xy 126.608638 -288.380764)
			(xy 126.568199 -288.350151) (xy 126.532926 -288.313705) (xy 126.503651 -288.272287) (xy 126.481066 -288.226873)
			(xy 126.465704 -288.178536) (xy 126.457926 -288.128416) (xy 126.457456 -288.103056) (xy 125.23724 -288.103056)
			(xy 125.236638 -288.130773) (xy 125.22732 -288.18542) (xy 125.218698 -288.211768) (xy 125.211078 -288.233866)
			(xy 125.416056 -288.588958) (xy 125.438916 -288.593276) (xy 125.463727 -288.598486) (xy 125.511505 -288.615434)
			(xy 125.556124 -288.6395) (xy 125.596531 -288.670114) (xy 125.631773 -288.706556) (xy 125.661018 -288.747964)
			(xy 125.683577 -288.793363) (xy 125.698917 -288.841681) (xy 125.706677 -288.891779) (xy 125.70714 -288.917126)
			(xy 125.706632 -288.943033) (xy 125.698526 -288.99421) (xy 125.682514 -289.043489) (xy 125.658991 -289.089656)
			(xy 125.628535 -289.131575) (xy 125.591897 -289.168213) (xy 125.549978 -289.198669) (xy 125.503811 -289.222192)
			(xy 125.454532 -289.238204) (xy 125.403355 -289.24631) (xy 125.351541 -289.24631) (xy 125.300364 -289.238204)
			(xy 125.251085 -289.222192) (xy 125.204918 -289.198669) (xy 125.162999 -289.168213) (xy 125.126361 -289.131575)
			(xy 125.095905 -289.089656) (xy 125.072382 -289.043489) (xy 125.05637 -288.99421) (xy 125.048264 -288.943033)
			(xy 125.047756 -288.917126) (xy 125.048353 -288.889409) (xy 125.057674 -288.834762) (xy 125.066298 -288.808414)
			(xy 125.074172 -288.786316) (xy 124.869194 -288.431224) (xy 124.846334 -288.426906) (xy 124.821499 -288.421756)
			(xy 124.773689 -288.404821) (xy 124.729038 -288.380764) (xy 124.688599 -288.350151) (xy 124.653326 -288.313705)
			(xy 124.624051 -288.272287) (xy 124.601466 -288.226873) (xy 124.586104 -288.178536) (xy 124.578326 -288.128416)
			(xy 124.577856 -288.103056) (xy 123.35764 -288.103056) (xy 123.357038 -288.130773) (xy 123.34772 -288.18542)
			(xy 123.339098 -288.211768) (xy 123.331478 -288.233866) (xy 123.536456 -288.588958) (xy 123.559316 -288.593276)
			(xy 123.584127 -288.598486) (xy 123.631905 -288.615434) (xy 123.676524 -288.6395) (xy 123.716931 -288.670114)
			(xy 123.752173 -288.706556) (xy 123.781418 -288.747964) (xy 123.803977 -288.793363) (xy 123.819317 -288.841681)
			(xy 123.827077 -288.891779) (xy 123.82754 -288.917126) (xy 123.827032 -288.943033) (xy 123.818926 -288.99421)
			(xy 123.802914 -289.043489) (xy 123.779391 -289.089656) (xy 123.748935 -289.131575) (xy 123.712297 -289.168213)
			(xy 123.670378 -289.198669) (xy 123.624211 -289.222192) (xy 123.574932 -289.238204) (xy 123.523755 -289.24631)
			(xy 123.471941 -289.24631) (xy 123.420764 -289.238204) (xy 123.371485 -289.222192) (xy 123.325318 -289.198669)
			(xy 123.283399 -289.168213) (xy 123.246761 -289.131575) (xy 123.216305 -289.089656) (xy 123.192782 -289.043489)
			(xy 123.17677 -288.99421) (xy 123.168664 -288.943033) (xy 123.168156 -288.917126) (xy 123.168753 -288.889409)
			(xy 123.178074 -288.834762) (xy 123.186698 -288.808414) (xy 123.194572 -288.786316) (xy 122.989594 -288.431224)
			(xy 122.966734 -288.426906) (xy 122.941899 -288.421756) (xy 122.894089 -288.404821) (xy 122.849438 -288.380764)
			(xy 122.808999 -288.350151) (xy 122.773726 -288.313705) (xy 122.744451 -288.272287) (xy 122.721866 -288.226873)
			(xy 122.706504 -288.178536) (xy 122.698726 -288.128416) (xy 122.698256 -288.103056) (xy 121.47804 -288.103056)
			(xy 121.477438 -288.130773) (xy 121.46812 -288.18542) (xy 121.459498 -288.211768) (xy 121.451624 -288.233866)
			(xy 121.656856 -288.588958) (xy 121.679716 -288.593276) (xy 121.704527 -288.598486) (xy 121.752305 -288.615434)
			(xy 121.796924 -288.6395) (xy 121.837331 -288.670114) (xy 121.872573 -288.706556) (xy 121.901818 -288.747964)
			(xy 121.924377 -288.793363) (xy 121.939717 -288.841681) (xy 121.947477 -288.891779) (xy 121.94794 -288.917126)
			(xy 121.947432 -288.943033) (xy 121.939326 -288.99421) (xy 121.923314 -289.043489) (xy 121.899791 -289.089656)
			(xy 121.869335 -289.131575) (xy 121.832697 -289.168213) (xy 121.790778 -289.198669) (xy 121.744611 -289.222192)
			(xy 121.695332 -289.238204) (xy 121.644155 -289.24631) (xy 121.592341 -289.24631) (xy 121.541164 -289.238204)
			(xy 121.491885 -289.222192) (xy 121.445718 -289.198669) (xy 121.403799 -289.168213) (xy 121.367161 -289.131575)
			(xy 121.336705 -289.089656) (xy 121.313182 -289.043489) (xy 121.29717 -288.99421) (xy 121.289064 -288.943033)
			(xy 121.288556 -288.917126) (xy 121.289153 -288.889409) (xy 121.298474 -288.834762) (xy 121.307098 -288.808414)
			(xy 121.314972 -288.786316) (xy 121.10974 -288.431224) (xy 121.08688 -288.426906) (xy 121.062064 -288.421716)
			(xy 121.014285 -288.404766) (xy 120.969665 -288.380698) (xy 120.929258 -288.350081) (xy 120.894016 -288.313637)
			(xy 120.864772 -288.272226) (xy 120.842214 -288.226825) (xy 120.826875 -288.178504) (xy 120.819118 -288.128404)
			(xy 120.818656 -288.103056) (xy 104.56164 -288.103056) (xy 104.561218 -288.128404) (xy 104.553436 -288.178499)
			(xy 104.53808 -288.226813) (xy 104.515512 -288.272208) (xy 104.486262 -288.313614) (xy 104.451021 -288.350057)
			(xy 104.410618 -288.380678) (xy 104.366005 -288.404755) (xy 104.318232 -288.421722) (xy 104.293416 -288.426906)
			(xy 104.270556 -288.431224) (xy 104.065324 -288.786316) (xy 104.073198 -288.808414) (xy 104.08184 -288.834757)
			(xy 104.091154 -288.889407) (xy 104.09174 -288.917126) (xy 104.091232 -288.943033) (xy 104.083126 -288.99421)
			(xy 104.067114 -289.043489) (xy 104.043591 -289.089656) (xy 104.013135 -289.131575) (xy 103.976497 -289.168213)
			(xy 103.934578 -289.198669) (xy 103.888411 -289.222192) (xy 103.839132 -289.238204) (xy 103.787955 -289.24631)
			(xy 103.736141 -289.24631) (xy 103.684964 -289.238204) (xy 103.635685 -289.222192) (xy 103.589518 -289.198669)
			(xy 103.547599 -289.168213) (xy 103.510961 -289.131575) (xy 103.480505 -289.089656) (xy 103.456982 -289.043489)
			(xy 103.44097 -288.99421) (xy 103.432864 -288.943033) (xy 103.432356 -288.917126) (xy 103.15194 -288.917126)
			(xy 103.151518 -288.940067) (xy 103.14509 -288.985498) (xy 103.132444 -289.029604) (xy 103.123492 -289.05073)
			(xy 103.113586 -289.073336) (xy 103.327454 -289.478466) (xy 103.351584 -289.483038) (xy 103.37651 -289.488115)
			(xy 103.424521 -289.50492) (xy 103.469379 -289.528904) (xy 103.510019 -289.559496) (xy 103.545476 -289.59597)
			(xy 103.574906 -289.637459) (xy 103.597612 -289.682977) (xy 103.613053 -289.731444) (xy 103.620863 -289.781708)
			(xy 103.621332 -289.807142) (xy 119.878856 -289.807142) (xy 119.879399 -289.781715) (xy 119.887229 -289.731468)
			(xy 119.90268 -289.683018) (xy 119.925386 -289.637514) (xy 119.954808 -289.596036) (xy 119.990248 -289.559565)
			(xy 120.030867 -289.528967) (xy 120.075701 -289.504967) (xy 120.123688 -289.488134) (xy 120.148604 -289.483038)
			(xy 120.172734 -289.478466) (xy 120.38711 -289.073082) (xy 120.377204 -289.050476) (xy 120.368243 -289.029398)
			(xy 120.355596 -288.985377) (xy 120.349182 -288.940026) (xy 120.348756 -288.917126) (xy 120.349264 -288.891219)
			(xy 120.35737 -288.840042) (xy 120.373382 -288.790763) (xy 120.396905 -288.744596) (xy 120.427361 -288.702677)
			(xy 120.463999 -288.666039) (xy 120.505918 -288.635583) (xy 120.552085 -288.61206) (xy 120.601364 -288.596048)
			(xy 120.652541 -288.587942) (xy 120.704355 -288.587942) (xy 120.755532 -288.596048) (xy 120.804811 -288.61206)
			(xy 120.850978 -288.635583) (xy 120.892897 -288.666039) (xy 120.929535 -288.702677) (xy 120.959991 -288.744596)
			(xy 120.983514 -288.790763) (xy 120.999526 -288.840042) (xy 121.007632 -288.891219) (xy 121.00814 -288.917126)
			(xy 121.007659 -288.942574) (xy 120.999856 -288.992867) (xy 120.984408 -289.041361) (xy 120.961683 -289.086901)
			(xy 120.932222 -289.128403) (xy 120.896727 -289.164878) (xy 120.856043 -289.195458) (xy 120.811139 -289.219415)
			(xy 120.763084 -289.236178) (xy 120.738138 -289.24123) (xy 120.714008 -289.245802) (xy 120.499632 -289.651186)
			(xy 120.509538 -289.673792) (xy 120.518456 -289.694878) (xy 120.531008 -289.738907) (xy 120.537342 -289.78425)
			(xy 120.537732 -289.807142) (xy 121.758456 -289.807142) (xy 121.758999 -289.781715) (xy 121.766829 -289.731468)
			(xy 121.78228 -289.683018) (xy 121.804986 -289.637514) (xy 121.834408 -289.596036) (xy 121.869848 -289.559565)
			(xy 121.910467 -289.528967) (xy 121.955301 -289.504967) (xy 122.003288 -289.488134) (xy 122.028204 -289.483038)
			(xy 122.052334 -289.478466) (xy 122.26671 -289.073082) (xy 122.256804 -289.050476) (xy 122.247843 -289.029398)
			(xy 122.235196 -288.985377) (xy 122.228782 -288.940026) (xy 122.228356 -288.917126) (xy 122.228864 -288.891219)
			(xy 122.23697 -288.840042) (xy 122.252982 -288.790763) (xy 122.276505 -288.744596) (xy 122.306961 -288.702677)
			(xy 122.343599 -288.666039) (xy 122.385518 -288.635583) (xy 122.431685 -288.61206) (xy 122.480964 -288.596048)
			(xy 122.532141 -288.587942) (xy 122.583955 -288.587942) (xy 122.635132 -288.596048) (xy 122.684411 -288.61206)
			(xy 122.730578 -288.635583) (xy 122.772497 -288.666039) (xy 122.809135 -288.702677) (xy 122.839591 -288.744596)
			(xy 122.863114 -288.790763) (xy 122.879126 -288.840042) (xy 122.887232 -288.891219) (xy 122.88774 -288.917126)
			(xy 122.887259 -288.942574) (xy 122.879456 -288.992867) (xy 122.864008 -289.041361) (xy 122.841283 -289.086901)
			(xy 122.811822 -289.128403) (xy 122.776327 -289.164878) (xy 122.735643 -289.195458) (xy 122.690739 -289.219415)
			(xy 122.642684 -289.236178) (xy 122.617738 -289.24123) (xy 122.593608 -289.245802) (xy 122.379232 -289.651186)
			(xy 122.389138 -289.673792) (xy 122.398056 -289.694878) (xy 122.410608 -289.738907) (xy 122.416942 -289.78425)
			(xy 122.417332 -289.807142) (xy 123.638056 -289.807142) (xy 123.638599 -289.781715) (xy 123.646429 -289.731468)
			(xy 123.66188 -289.683018) (xy 123.684586 -289.637514) (xy 123.714008 -289.596036) (xy 123.749448 -289.559565)
			(xy 123.790067 -289.528967) (xy 123.834901 -289.504967) (xy 123.882888 -289.488134) (xy 123.907804 -289.483038)
			(xy 123.931934 -289.478466) (xy 124.14631 -289.073082) (xy 124.136404 -289.050476) (xy 124.127443 -289.029398)
			(xy 124.114796 -288.985377) (xy 124.108382 -288.940026) (xy 124.107956 -288.917126) (xy 124.108464 -288.891219)
			(xy 124.11657 -288.840042) (xy 124.132582 -288.790763) (xy 124.156105 -288.744596) (xy 124.186561 -288.702677)
			(xy 124.223199 -288.666039) (xy 124.265118 -288.635583) (xy 124.311285 -288.61206) (xy 124.360564 -288.596048)
			(xy 124.411741 -288.587942) (xy 124.463555 -288.587942) (xy 124.514732 -288.596048) (xy 124.564011 -288.61206)
			(xy 124.610178 -288.635583) (xy 124.652097 -288.666039) (xy 124.688735 -288.702677) (xy 124.719191 -288.744596)
			(xy 124.742714 -288.790763) (xy 124.758726 -288.840042) (xy 124.766832 -288.891219) (xy 124.76734 -288.917126)
			(xy 124.766859 -288.942574) (xy 124.759056 -288.992867) (xy 124.743608 -289.041361) (xy 124.720883 -289.086901)
			(xy 124.691422 -289.128403) (xy 124.655927 -289.164878) (xy 124.615243 -289.195458) (xy 124.570339 -289.219415)
			(xy 124.522284 -289.236178) (xy 124.497338 -289.24123) (xy 124.473208 -289.245802) (xy 124.258832 -289.651186)
			(xy 124.268738 -289.673792) (xy 124.277656 -289.694878) (xy 124.290208 -289.738907) (xy 124.296542 -289.78425)
			(xy 124.296932 -289.807142) (xy 125.517656 -289.807142) (xy 125.518199 -289.781715) (xy 125.526029 -289.731468)
			(xy 125.54148 -289.683018) (xy 125.564186 -289.637514) (xy 125.593608 -289.596036) (xy 125.629048 -289.559565)
			(xy 125.669667 -289.528967) (xy 125.714501 -289.504967) (xy 125.762488 -289.488134) (xy 125.787404 -289.483038)
			(xy 125.811534 -289.478466) (xy 126.02591 -289.073082) (xy 126.016004 -289.050476) (xy 126.007043 -289.029398)
			(xy 125.994396 -288.985377) (xy 125.987982 -288.940026) (xy 125.987556 -288.917126) (xy 125.988064 -288.891219)
			(xy 125.99617 -288.840042) (xy 126.012182 -288.790763) (xy 126.035705 -288.744596) (xy 126.066161 -288.702677)
			(xy 126.102799 -288.666039) (xy 126.144718 -288.635583) (xy 126.190885 -288.61206) (xy 126.240164 -288.596048)
			(xy 126.291341 -288.587942) (xy 126.343155 -288.587942) (xy 126.394332 -288.596048) (xy 126.443611 -288.61206)
			(xy 126.489778 -288.635583) (xy 126.531697 -288.666039) (xy 126.568335 -288.702677) (xy 126.598791 -288.744596)
			(xy 126.622314 -288.790763) (xy 126.638326 -288.840042) (xy 126.646432 -288.891219) (xy 126.64694 -288.917126)
			(xy 126.646459 -288.942574) (xy 126.638656 -288.992867) (xy 126.623208 -289.041361) (xy 126.600483 -289.086901)
			(xy 126.571022 -289.128403) (xy 126.535527 -289.164878) (xy 126.494843 -289.195458) (xy 126.449939 -289.219415)
			(xy 126.401884 -289.236178) (xy 126.376938 -289.24123) (xy 126.352808 -289.245802) (xy 126.138432 -289.651186)
			(xy 126.148338 -289.673792) (xy 126.157256 -289.694878) (xy 126.169808 -289.738907) (xy 126.176142 -289.78425)
			(xy 126.176532 -289.807142) (xy 127.397256 -289.807142) (xy 127.397799 -289.781715) (xy 127.405629 -289.731468)
			(xy 127.42108 -289.683018) (xy 127.443786 -289.637514) (xy 127.473208 -289.596036) (xy 127.508648 -289.559565)
			(xy 127.549267 -289.528967) (xy 127.594101 -289.504967) (xy 127.642088 -289.488134) (xy 127.667004 -289.483038)
			(xy 127.691134 -289.478466) (xy 127.90551 -289.073082) (xy 127.895604 -289.050476) (xy 127.886643 -289.029398)
			(xy 127.873996 -288.985377) (xy 127.867582 -288.940026) (xy 127.867156 -288.917126) (xy 127.867664 -288.891219)
			(xy 127.87577 -288.840042) (xy 127.891782 -288.790763) (xy 127.915305 -288.744596) (xy 127.945761 -288.702677)
			(xy 127.982399 -288.666039) (xy 128.024318 -288.635583) (xy 128.070485 -288.61206) (xy 128.119764 -288.596048)
			(xy 128.170941 -288.587942) (xy 128.222755 -288.587942) (xy 128.273932 -288.596048) (xy 128.323211 -288.61206)
			(xy 128.369378 -288.635583) (xy 128.411297 -288.666039) (xy 128.447935 -288.702677) (xy 128.478391 -288.744596)
			(xy 128.501914 -288.790763) (xy 128.517926 -288.840042) (xy 128.526032 -288.891219) (xy 128.52654 -288.917126)
			(xy 128.526059 -288.942574) (xy 128.518256 -288.992867) (xy 128.502808 -289.041361) (xy 128.480083 -289.086901)
			(xy 128.450622 -289.128403) (xy 128.415127 -289.164878) (xy 128.374443 -289.195458) (xy 128.329539 -289.219415)
			(xy 128.281484 -289.236178) (xy 128.256538 -289.24123) (xy 128.232408 -289.245802) (xy 128.018032 -289.651186)
			(xy 128.027938 -289.673792) (xy 128.036856 -289.694878) (xy 128.049408 -289.738907) (xy 128.055742 -289.78425)
			(xy 128.056132 -289.807142) (xy 129.276856 -289.807142) (xy 129.277399 -289.781715) (xy 129.285229 -289.731468)
			(xy 129.30068 -289.683018) (xy 129.323386 -289.637514) (xy 129.352808 -289.596036) (xy 129.388248 -289.559565)
			(xy 129.428867 -289.528967) (xy 129.473701 -289.504967) (xy 129.521688 -289.488134) (xy 129.546604 -289.483038)
			(xy 129.570734 -289.478466) (xy 129.78511 -289.073082) (xy 129.775204 -289.050476) (xy 129.766243 -289.029398)
			(xy 129.753596 -288.985377) (xy 129.747182 -288.940026) (xy 129.746756 -288.917126) (xy 129.747264 -288.891219)
			(xy 129.75537 -288.840042) (xy 129.771382 -288.790763) (xy 129.794905 -288.744596) (xy 129.825361 -288.702677)
			(xy 129.861999 -288.666039) (xy 129.903918 -288.635583) (xy 129.950085 -288.61206) (xy 129.999364 -288.596048)
			(xy 130.050541 -288.587942) (xy 130.102355 -288.587942) (xy 130.153532 -288.596048) (xy 130.202811 -288.61206)
			(xy 130.248978 -288.635583) (xy 130.290897 -288.666039) (xy 130.327535 -288.702677) (xy 130.357991 -288.744596)
			(xy 130.381514 -288.790763) (xy 130.397526 -288.840042) (xy 130.405632 -288.891219) (xy 130.40614 -288.917126)
			(xy 130.405659 -288.942574) (xy 130.397856 -288.992867) (xy 130.382408 -289.041361) (xy 130.359683 -289.086901)
			(xy 130.330222 -289.128403) (xy 130.294727 -289.164878) (xy 130.254043 -289.195458) (xy 130.209139 -289.219415)
			(xy 130.161084 -289.236178) (xy 130.136138 -289.24123) (xy 130.112008 -289.245802) (xy 129.897632 -289.651186)
			(xy 129.907538 -289.673792) (xy 129.916456 -289.694878) (xy 129.929008 -289.738907) (xy 129.935342 -289.78425)
			(xy 129.935732 -289.807142) (xy 131.156456 -289.807142) (xy 131.156999 -289.781715) (xy 131.164829 -289.731468)
			(xy 131.18028 -289.683018) (xy 131.202986 -289.637514) (xy 131.232408 -289.596036) (xy 131.267848 -289.559565)
			(xy 131.308467 -289.528967) (xy 131.353301 -289.504967) (xy 131.401288 -289.488134) (xy 131.426204 -289.483038)
			(xy 131.450334 -289.478466) (xy 131.66471 -289.073082) (xy 131.654804 -289.050476) (xy 131.645843 -289.029398)
			(xy 131.633196 -288.985377) (xy 131.626782 -288.940026) (xy 131.626356 -288.917126) (xy 131.626864 -288.891219)
			(xy 131.63497 -288.840042) (xy 131.650982 -288.790763) (xy 131.674505 -288.744596) (xy 131.704961 -288.702677)
			(xy 131.741599 -288.666039) (xy 131.783518 -288.635583) (xy 131.829685 -288.61206) (xy 131.878964 -288.596048)
			(xy 131.930141 -288.587942) (xy 131.981955 -288.587942) (xy 132.033132 -288.596048) (xy 132.082411 -288.61206)
			(xy 132.128578 -288.635583) (xy 132.170497 -288.666039) (xy 132.207135 -288.702677) (xy 132.237591 -288.744596)
			(xy 132.261114 -288.790763) (xy 132.277126 -288.840042) (xy 132.285232 -288.891219) (xy 132.28574 -288.917126)
			(xy 132.285259 -288.942574) (xy 132.277456 -288.992867) (xy 132.262008 -289.041361) (xy 132.239283 -289.086901)
			(xy 132.209822 -289.128403) (xy 132.174327 -289.164878) (xy 132.133643 -289.195458) (xy 132.088739 -289.219415)
			(xy 132.040684 -289.236178) (xy 132.015738 -289.24123) (xy 131.991608 -289.245802) (xy 131.777232 -289.651186)
			(xy 131.787138 -289.673792) (xy 131.796056 -289.694878) (xy 131.808608 -289.738907) (xy 131.814942 -289.78425)
			(xy 131.815332 -289.807142) (xy 133.036056 -289.807142) (xy 133.036599 -289.781715) (xy 133.044429 -289.731468)
			(xy 133.05988 -289.683018) (xy 133.082586 -289.637514) (xy 133.112008 -289.596036) (xy 133.147448 -289.559565)
			(xy 133.188067 -289.528967) (xy 133.232901 -289.504967) (xy 133.280888 -289.488134) (xy 133.305804 -289.483038)
			(xy 133.329934 -289.478466) (xy 133.54431 -289.073082) (xy 133.534404 -289.050476) (xy 133.525443 -289.029398)
			(xy 133.512796 -288.985377) (xy 133.506382 -288.940026) (xy 133.505956 -288.917126) (xy 133.506464 -288.891219)
			(xy 133.51457 -288.840042) (xy 133.530582 -288.790763) (xy 133.554105 -288.744596) (xy 133.584561 -288.702677)
			(xy 133.621199 -288.666039) (xy 133.663118 -288.635583) (xy 133.709285 -288.61206) (xy 133.758564 -288.596048)
			(xy 133.809741 -288.587942) (xy 133.861555 -288.587942) (xy 133.912732 -288.596048) (xy 133.962011 -288.61206)
			(xy 134.008178 -288.635583) (xy 134.050097 -288.666039) (xy 134.086735 -288.702677) (xy 134.117191 -288.744596)
			(xy 134.140714 -288.790763) (xy 134.156726 -288.840042) (xy 134.164832 -288.891219) (xy 134.16534 -288.917126)
			(xy 134.164859 -288.942574) (xy 134.157056 -288.992867) (xy 134.141608 -289.041361) (xy 134.118883 -289.086901)
			(xy 134.089422 -289.128403) (xy 134.053927 -289.164878) (xy 134.013243 -289.195458) (xy 133.968339 -289.219415)
			(xy 133.920284 -289.236178) (xy 133.895338 -289.24123) (xy 133.871208 -289.245802) (xy 133.656832 -289.651186)
			(xy 133.666738 -289.673792) (xy 133.675656 -289.694878) (xy 133.688208 -289.738907) (xy 133.694542 -289.78425)
			(xy 133.694932 -289.807142) (xy 133.694424 -289.833029) (xy 133.686325 -289.884167) (xy 133.670326 -289.933407)
			(xy 133.64682 -289.979539) (xy 133.616388 -290.021426) (xy 133.579778 -290.058036) (xy 133.537891 -290.088468)
			(xy 133.491759 -290.111974) (xy 133.442519 -290.127973) (xy 133.391381 -290.136072) (xy 133.339607 -290.136072)
			(xy 133.288469 -290.127973) (xy 133.239229 -290.111974) (xy 133.193097 -290.088468) (xy 133.15121 -290.058036)
			(xy 133.1146 -290.021426) (xy 133.084168 -289.979539) (xy 133.060662 -289.933407) (xy 133.044663 -289.884167)
			(xy 133.036564 -289.833029) (xy 133.036056 -289.807142) (xy 131.815332 -289.807142) (xy 131.814824 -289.833029)
			(xy 131.806725 -289.884167) (xy 131.790726 -289.933407) (xy 131.76722 -289.979539) (xy 131.736788 -290.021426)
			(xy 131.700178 -290.058036) (xy 131.658291 -290.088468) (xy 131.612159 -290.111974) (xy 131.562919 -290.127973)
			(xy 131.511781 -290.136072) (xy 131.460007 -290.136072) (xy 131.408869 -290.127973) (xy 131.359629 -290.111974)
			(xy 131.313497 -290.088468) (xy 131.27161 -290.058036) (xy 131.235 -290.021426) (xy 131.204568 -289.979539)
			(xy 131.181062 -289.933407) (xy 131.165063 -289.884167) (xy 131.156964 -289.833029) (xy 131.156456 -289.807142)
			(xy 129.935732 -289.807142) (xy 129.935224 -289.833029) (xy 129.927125 -289.884167) (xy 129.911126 -289.933407)
			(xy 129.88762 -289.979539) (xy 129.857188 -290.021426) (xy 129.820578 -290.058036) (xy 129.778691 -290.088468)
			(xy 129.732559 -290.111974) (xy 129.683319 -290.127973) (xy 129.632181 -290.136072) (xy 129.580407 -290.136072)
			(xy 129.529269 -290.127973) (xy 129.480029 -290.111974) (xy 129.433897 -290.088468) (xy 129.39201 -290.058036)
			(xy 129.3554 -290.021426) (xy 129.324968 -289.979539) (xy 129.301462 -289.933407) (xy 129.285463 -289.884167)
			(xy 129.277364 -289.833029) (xy 129.276856 -289.807142) (xy 128.056132 -289.807142) (xy 128.055624 -289.833029)
			(xy 128.047525 -289.884167) (xy 128.031526 -289.933407) (xy 128.00802 -289.979539) (xy 127.977588 -290.021426)
			(xy 127.940978 -290.058036) (xy 127.899091 -290.088468) (xy 127.852959 -290.111974) (xy 127.803719 -290.127973)
			(xy 127.752581 -290.136072) (xy 127.700807 -290.136072) (xy 127.649669 -290.127973) (xy 127.600429 -290.111974)
			(xy 127.554297 -290.088468) (xy 127.51241 -290.058036) (xy 127.4758 -290.021426) (xy 127.445368 -289.979539)
			(xy 127.421862 -289.933407) (xy 127.405863 -289.884167) (xy 127.397764 -289.833029) (xy 127.397256 -289.807142)
			(xy 126.176532 -289.807142) (xy 126.176024 -289.833029) (xy 126.167925 -289.884167) (xy 126.151926 -289.933407)
			(xy 126.12842 -289.979539) (xy 126.097988 -290.021426) (xy 126.061378 -290.058036) (xy 126.019491 -290.088468)
			(xy 125.973359 -290.111974) (xy 125.924119 -290.127973) (xy 125.872981 -290.136072) (xy 125.821207 -290.136072)
			(xy 125.770069 -290.127973) (xy 125.720829 -290.111974) (xy 125.674697 -290.088468) (xy 125.63281 -290.058036)
			(xy 125.5962 -290.021426) (xy 125.565768 -289.979539) (xy 125.542262 -289.933407) (xy 125.526263 -289.884167)
			(xy 125.518164 -289.833029) (xy 125.517656 -289.807142) (xy 124.296932 -289.807142) (xy 124.296424 -289.833029)
			(xy 124.288325 -289.884167) (xy 124.272326 -289.933407) (xy 124.24882 -289.979539) (xy 124.218388 -290.021426)
			(xy 124.181778 -290.058036) (xy 124.139891 -290.088468) (xy 124.093759 -290.111974) (xy 124.044519 -290.127973)
			(xy 123.993381 -290.136072) (xy 123.941607 -290.136072) (xy 123.890469 -290.127973) (xy 123.841229 -290.111974)
			(xy 123.795097 -290.088468) (xy 123.75321 -290.058036) (xy 123.7166 -290.021426) (xy 123.686168 -289.979539)
			(xy 123.662662 -289.933407) (xy 123.646663 -289.884167) (xy 123.638564 -289.833029) (xy 123.638056 -289.807142)
			(xy 122.417332 -289.807142) (xy 122.416824 -289.833029) (xy 122.408725 -289.884167) (xy 122.392726 -289.933407)
			(xy 122.36922 -289.979539) (xy 122.338788 -290.021426) (xy 122.302178 -290.058036) (xy 122.260291 -290.088468)
			(xy 122.214159 -290.111974) (xy 122.164919 -290.127973) (xy 122.113781 -290.136072) (xy 122.062007 -290.136072)
			(xy 122.010869 -290.127973) (xy 121.961629 -290.111974) (xy 121.915497 -290.088468) (xy 121.87361 -290.058036)
			(xy 121.837 -290.021426) (xy 121.806568 -289.979539) (xy 121.783062 -289.933407) (xy 121.767063 -289.884167)
			(xy 121.758964 -289.833029) (xy 121.758456 -289.807142) (xy 120.537732 -289.807142) (xy 120.537224 -289.833029)
			(xy 120.529125 -289.884167) (xy 120.513126 -289.933407) (xy 120.48962 -289.979539) (xy 120.459188 -290.021426)
			(xy 120.422578 -290.058036) (xy 120.380691 -290.088468) (xy 120.334559 -290.111974) (xy 120.285319 -290.127973)
			(xy 120.234181 -290.136072) (xy 120.182407 -290.136072) (xy 120.131269 -290.127973) (xy 120.082029 -290.111974)
			(xy 120.035897 -290.088468) (xy 119.99401 -290.058036) (xy 119.9574 -290.021426) (xy 119.926968 -289.979539)
			(xy 119.903462 -289.933407) (xy 119.887463 -289.884167) (xy 119.879364 -289.833029) (xy 119.878856 -289.807142)
			(xy 103.621332 -289.807142) (xy 103.620824 -289.833029) (xy 103.612725 -289.884167) (xy 103.596726 -289.933407)
			(xy 103.57322 -289.979539) (xy 103.542788 -290.021426) (xy 103.506178 -290.058036) (xy 103.464291 -290.088468)
			(xy 103.418159 -290.111974) (xy 103.368919 -290.127973) (xy 103.317781 -290.136072) (xy 103.266007 -290.136072)
			(xy 103.214869 -290.127973) (xy 103.165629 -290.111974) (xy 103.119497 -290.088468) (xy 103.07761 -290.058036)
			(xy 103.041 -290.021426) (xy 103.010568 -289.979539) (xy 102.987062 -289.933407) (xy 102.971063 -289.884167)
			(xy 102.962964 -289.833029) (xy 102.962456 -289.807142) (xy 102.962456 -289.806634) (xy 102.962859 -289.783785)
			(xy 102.969212 -289.738531) (xy 102.981758 -289.694589) (xy 102.99065 -289.673538) (xy 103.000556 -289.650932)
			(xy 102.786688 -289.245802) (xy 102.762558 -289.24123) (xy 102.737619 -289.236158) (xy 102.689576 -289.219379)
			(xy 102.644683 -289.195414) (xy 102.604007 -289.164832) (xy 102.568517 -289.12836) (xy 102.539055 -289.086867)
			(xy 102.516322 -289.041337) (xy 102.500858 -288.992854) (xy 102.493031 -288.942571) (xy 102.492556 -288.917126)
			(xy 102.21214 -288.917126) (xy 102.211632 -288.943033) (xy 102.203526 -288.99421) (xy 102.187514 -289.043489)
			(xy 102.163991 -289.089656) (xy 102.133535 -289.131575) (xy 102.096897 -289.168213) (xy 102.054978 -289.198669)
			(xy 102.008811 -289.222192) (xy 101.959532 -289.238204) (xy 101.908355 -289.24631) (xy 101.856541 -289.24631)
			(xy 101.805364 -289.238204) (xy 101.756085 -289.222192) (xy 101.709918 -289.198669) (xy 101.667999 -289.168213)
			(xy 101.631361 -289.131575) (xy 101.600905 -289.089656) (xy 101.577382 -289.043489) (xy 101.56137 -288.99421)
			(xy 101.553264 -288.943033) (xy 101.552756 -288.917126) (xy 101.27234 -288.917126) (xy 101.271918 -288.940067)
			(xy 101.26549 -288.985498) (xy 101.252844 -289.029604) (xy 101.243892 -289.05073) (xy 101.233986 -289.073336)
			(xy 101.447854 -289.478466) (xy 101.471984 -289.483038) (xy 101.49691 -289.488115) (xy 101.544921 -289.50492)
			(xy 101.589779 -289.528904) (xy 101.630419 -289.559496) (xy 101.665876 -289.59597) (xy 101.695306 -289.637459)
			(xy 101.718012 -289.682977) (xy 101.733453 -289.731444) (xy 101.741263 -289.781708) (xy 101.741732 -289.807142)
			(xy 101.741224 -289.833029) (xy 101.733125 -289.884167) (xy 101.717126 -289.933407) (xy 101.69362 -289.979539)
			(xy 101.663188 -290.021426) (xy 101.626578 -290.058036) (xy 101.584691 -290.088468) (xy 101.538559 -290.111974)
			(xy 101.489319 -290.127973) (xy 101.438181 -290.136072) (xy 101.386407 -290.136072) (xy 101.335269 -290.127973)
			(xy 101.286029 -290.111974) (xy 101.239897 -290.088468) (xy 101.19801 -290.058036) (xy 101.1614 -290.021426)
			(xy 101.130968 -289.979539) (xy 101.107462 -289.933407) (xy 101.091463 -289.884167) (xy 101.083364 -289.833029)
			(xy 101.082856 -289.807142) (xy 101.082856 -289.806634) (xy 101.083259 -289.783785) (xy 101.089612 -289.738531)
			(xy 101.102158 -289.694589) (xy 101.11105 -289.673538) (xy 101.120956 -289.650932) (xy 100.907088 -289.245802)
			(xy 100.882958 -289.24123) (xy 100.858019 -289.236158) (xy 100.809976 -289.219379) (xy 100.765083 -289.195414)
			(xy 100.724407 -289.164832) (xy 100.688917 -289.12836) (xy 100.659455 -289.086867) (xy 100.636722 -289.041337)
			(xy 100.621258 -288.992854) (xy 100.613431 -288.942571) (xy 100.612956 -288.917126) (xy 100.33254 -288.917126)
			(xy 100.332032 -288.943033) (xy 100.323926 -288.99421) (xy 100.307914 -289.043489) (xy 100.284391 -289.089656)
			(xy 100.253935 -289.131575) (xy 100.217297 -289.168213) (xy 100.175378 -289.198669) (xy 100.129211 -289.222192)
			(xy 100.079932 -289.238204) (xy 100.028755 -289.24631) (xy 99.976941 -289.24631) (xy 99.925764 -289.238204)
			(xy 99.876485 -289.222192) (xy 99.830318 -289.198669) (xy 99.788399 -289.168213) (xy 99.751761 -289.131575)
			(xy 99.721305 -289.089656) (xy 99.697782 -289.043489) (xy 99.68177 -288.99421) (xy 99.673664 -288.943033)
			(xy 99.673156 -288.917126) (xy 99.39274 -288.917126) (xy 99.392318 -288.940067) (xy 99.38589 -288.985498)
			(xy 99.373244 -289.029604) (xy 99.364292 -289.05073) (xy 99.354386 -289.073336) (xy 99.568254 -289.478466)
			(xy 99.592384 -289.483038) (xy 99.61731 -289.488115) (xy 99.665321 -289.50492) (xy 99.710179 -289.528904)
			(xy 99.750819 -289.559496) (xy 99.786276 -289.59597) (xy 99.815706 -289.637459) (xy 99.838412 -289.682977)
			(xy 99.853853 -289.731444) (xy 99.861663 -289.781708) (xy 99.862132 -289.807142) (xy 99.861624 -289.833029)
			(xy 99.853525 -289.884167) (xy 99.837526 -289.933407) (xy 99.81402 -289.979539) (xy 99.783588 -290.021426)
			(xy 99.746978 -290.058036) (xy 99.705091 -290.088468) (xy 99.658959 -290.111974) (xy 99.609719 -290.127973)
			(xy 99.558581 -290.136072) (xy 99.506807 -290.136072) (xy 99.455669 -290.127973) (xy 99.406429 -290.111974)
			(xy 99.360297 -290.088468) (xy 99.31841 -290.058036) (xy 99.2818 -290.021426) (xy 99.251368 -289.979539)
			(xy 99.227862 -289.933407) (xy 99.211863 -289.884167) (xy 99.203764 -289.833029) (xy 99.203256 -289.807142)
			(xy 99.203256 -289.806634) (xy 99.203659 -289.783785) (xy 99.210012 -289.738531) (xy 99.222558 -289.694589)
			(xy 99.23145 -289.673538) (xy 99.241356 -289.650932) (xy 99.027488 -289.245802) (xy 99.003358 -289.24123)
			(xy 98.978419 -289.236158) (xy 98.930376 -289.219379) (xy 98.885483 -289.195414) (xy 98.844807 -289.164832)
			(xy 98.809317 -289.12836) (xy 98.779855 -289.086867) (xy 98.757122 -289.041337) (xy 98.741658 -288.992854)
			(xy 98.733831 -288.942571) (xy 98.733356 -288.917126) (xy 98.45294 -288.917126) (xy 98.452432 -288.943033)
			(xy 98.444326 -288.99421) (xy 98.428314 -289.043489) (xy 98.404791 -289.089656) (xy 98.374335 -289.131575)
			(xy 98.337697 -289.168213) (xy 98.295778 -289.198669) (xy 98.249611 -289.222192) (xy 98.200332 -289.238204)
			(xy 98.149155 -289.24631) (xy 98.097341 -289.24631) (xy 98.046164 -289.238204) (xy 97.996885 -289.222192)
			(xy 97.950718 -289.198669) (xy 97.908799 -289.168213) (xy 97.872161 -289.131575) (xy 97.841705 -289.089656)
			(xy 97.818182 -289.043489) (xy 97.80217 -288.99421) (xy 97.794064 -288.943033) (xy 97.793556 -288.917126)
			(xy 97.51314 -288.917126) (xy 97.512718 -288.940067) (xy 97.50629 -288.985498) (xy 97.493644 -289.029604)
			(xy 97.484692 -289.05073) (xy 97.474786 -289.073336) (xy 97.688654 -289.478466) (xy 97.712784 -289.483038)
			(xy 97.73771 -289.488115) (xy 97.785721 -289.50492) (xy 97.830579 -289.528904) (xy 97.871219 -289.559496)
			(xy 97.906676 -289.59597) (xy 97.936106 -289.637459) (xy 97.958812 -289.682977) (xy 97.974253 -289.731444)
			(xy 97.982063 -289.781708) (xy 97.982532 -289.807142) (xy 97.982024 -289.833029) (xy 97.973925 -289.884167)
			(xy 97.957926 -289.933407) (xy 97.93442 -289.979539) (xy 97.903988 -290.021426) (xy 97.867378 -290.058036)
			(xy 97.825491 -290.088468) (xy 97.779359 -290.111974) (xy 97.730119 -290.127973) (xy 97.678981 -290.136072)
			(xy 97.627207 -290.136072) (xy 97.576069 -290.127973) (xy 97.526829 -290.111974) (xy 97.480697 -290.088468)
			(xy 97.43881 -290.058036) (xy 97.4022 -290.021426) (xy 97.371768 -289.979539) (xy 97.348262 -289.933407)
			(xy 97.332263 -289.884167) (xy 97.324164 -289.833029) (xy 97.323656 -289.807142) (xy 97.323656 -289.806634)
			(xy 97.324059 -289.783785) (xy 97.330412 -289.738531) (xy 97.342958 -289.694589) (xy 97.35185 -289.673538)
			(xy 97.361756 -289.650932) (xy 97.147888 -289.245802) (xy 97.123758 -289.24123) (xy 97.098819 -289.236158)
			(xy 97.050776 -289.219379) (xy 97.005883 -289.195414) (xy 96.965207 -289.164832) (xy 96.929717 -289.12836)
			(xy 96.900255 -289.086867) (xy 96.877522 -289.041337) (xy 96.862058 -288.992854) (xy 96.854231 -288.942571)
			(xy 96.853756 -288.917126) (xy 96.57334 -288.917126) (xy 96.572832 -288.943033) (xy 96.564726 -288.99421)
			(xy 96.548714 -289.043489) (xy 96.525191 -289.089656) (xy 96.494735 -289.131575) (xy 96.458097 -289.168213)
			(xy 96.416178 -289.198669) (xy 96.370011 -289.222192) (xy 96.320732 -289.238204) (xy 96.269555 -289.24631)
			(xy 96.217741 -289.24631) (xy 96.166564 -289.238204) (xy 96.117285 -289.222192) (xy 96.071118 -289.198669)
			(xy 96.029199 -289.168213) (xy 95.992561 -289.131575) (xy 95.962105 -289.089656) (xy 95.938582 -289.043489)
			(xy 95.92257 -288.99421) (xy 95.914464 -288.943033) (xy 95.913956 -288.917126) (xy 95.63354 -288.917126)
			(xy 95.633118 -288.940067) (xy 95.62669 -288.985498) (xy 95.614044 -289.029604) (xy 95.605092 -289.05073)
			(xy 95.595186 -289.073336) (xy 95.809054 -289.478466) (xy 95.833184 -289.483038) (xy 95.85811 -289.488115)
			(xy 95.906121 -289.50492) (xy 95.950979 -289.528904) (xy 95.991619 -289.559496) (xy 96.027076 -289.59597)
			(xy 96.056506 -289.637459) (xy 96.079212 -289.682977) (xy 96.094653 -289.731444) (xy 96.102463 -289.781708)
			(xy 96.102932 -289.807142) (xy 96.102424 -289.833029) (xy 96.094325 -289.884167) (xy 96.078326 -289.933407)
			(xy 96.05482 -289.979539) (xy 96.024388 -290.021426) (xy 95.987778 -290.058036) (xy 95.945891 -290.088468)
			(xy 95.899759 -290.111974) (xy 95.850519 -290.127973) (xy 95.799381 -290.136072) (xy 95.747607 -290.136072)
			(xy 95.696469 -290.127973) (xy 95.647229 -290.111974) (xy 95.601097 -290.088468) (xy 95.55921 -290.058036)
			(xy 95.5226 -290.021426) (xy 95.492168 -289.979539) (xy 95.468662 -289.933407) (xy 95.452663 -289.884167)
			(xy 95.444564 -289.833029) (xy 95.444056 -289.807142) (xy 95.444056 -289.806634) (xy 95.444459 -289.783785)
			(xy 95.450812 -289.738531) (xy 95.463358 -289.694589) (xy 95.47225 -289.673538) (xy 95.482156 -289.650932)
			(xy 95.268288 -289.245802) (xy 95.244158 -289.24123) (xy 95.219219 -289.236158) (xy 95.171176 -289.219379)
			(xy 95.126283 -289.195414) (xy 95.085607 -289.164832) (xy 95.050117 -289.12836) (xy 95.020655 -289.086867)
			(xy 94.997922 -289.041337) (xy 94.982458 -288.992854) (xy 94.974631 -288.942571) (xy 94.974156 -288.917126)
			(xy 94.69374 -288.917126) (xy 94.693232 -288.943033) (xy 94.685126 -288.99421) (xy 94.669114 -289.043489)
			(xy 94.645591 -289.089656) (xy 94.615135 -289.131575) (xy 94.578497 -289.168213) (xy 94.536578 -289.198669)
			(xy 94.490411 -289.222192) (xy 94.441132 -289.238204) (xy 94.389955 -289.24631) (xy 94.338141 -289.24631)
			(xy 94.286964 -289.238204) (xy 94.237685 -289.222192) (xy 94.191518 -289.198669) (xy 94.149599 -289.168213)
			(xy 94.112961 -289.131575) (xy 94.082505 -289.089656) (xy 94.058982 -289.043489) (xy 94.04297 -288.99421)
			(xy 94.034864 -288.943033) (xy 94.034356 -288.917126) (xy 93.75394 -288.917126) (xy 93.753518 -288.940067)
			(xy 93.74709 -288.985498) (xy 93.734444 -289.029604) (xy 93.725492 -289.05073) (xy 93.715586 -289.073336)
			(xy 93.929454 -289.478466) (xy 93.953584 -289.483038) (xy 93.97851 -289.488115) (xy 94.026521 -289.50492)
			(xy 94.071379 -289.528904) (xy 94.112019 -289.559496) (xy 94.147476 -289.59597) (xy 94.176906 -289.637459)
			(xy 94.199612 -289.682977) (xy 94.215053 -289.731444) (xy 94.222863 -289.781708) (xy 94.223332 -289.807142)
			(xy 94.222824 -289.833029) (xy 94.214725 -289.884167) (xy 94.198726 -289.933407) (xy 94.17522 -289.979539)
			(xy 94.144788 -290.021426) (xy 94.108178 -290.058036) (xy 94.066291 -290.088468) (xy 94.020159 -290.111974)
			(xy 93.970919 -290.127973) (xy 93.919781 -290.136072) (xy 93.868007 -290.136072) (xy 93.816869 -290.127973)
			(xy 93.767629 -290.111974) (xy 93.721497 -290.088468) (xy 93.67961 -290.058036) (xy 93.643 -290.021426)
			(xy 93.612568 -289.979539) (xy 93.589062 -289.933407) (xy 93.573063 -289.884167) (xy 93.564964 -289.833029)
			(xy 93.564456 -289.807142) (xy 93.564456 -289.806634) (xy 93.564859 -289.783785) (xy 93.571212 -289.738531)
			(xy 93.583758 -289.694589) (xy 93.59265 -289.673538) (xy 93.602556 -289.650932) (xy 93.388688 -289.245802)
			(xy 93.364558 -289.24123) (xy 93.339619 -289.236158) (xy 93.291576 -289.219379) (xy 93.246683 -289.195414)
			(xy 93.206007 -289.164832) (xy 93.170517 -289.12836) (xy 93.141055 -289.086867) (xy 93.118322 -289.041337)
			(xy 93.102858 -288.992854) (xy 93.095031 -288.942571) (xy 93.094556 -288.917126) (xy 92.81414 -288.917126)
			(xy 92.813632 -288.943033) (xy 92.805526 -288.99421) (xy 92.789514 -289.043489) (xy 92.765991 -289.089656)
			(xy 92.735535 -289.131575) (xy 92.698897 -289.168213) (xy 92.656978 -289.198669) (xy 92.610811 -289.222192)
			(xy 92.561532 -289.238204) (xy 92.510355 -289.24631) (xy 92.458541 -289.24631) (xy 92.407364 -289.238204)
			(xy 92.358085 -289.222192) (xy 92.311918 -289.198669) (xy 92.269999 -289.168213) (xy 92.233361 -289.131575)
			(xy 92.202905 -289.089656) (xy 92.179382 -289.043489) (xy 92.16337 -288.99421) (xy 92.155264 -288.943033)
			(xy 92.154756 -288.917126) (xy 91.87434 -288.917126) (xy 91.873918 -288.940067) (xy 91.86749 -288.985498)
			(xy 91.854844 -289.029604) (xy 91.845892 -289.05073) (xy 91.835986 -289.073336) (xy 92.049854 -289.478466)
			(xy 92.073984 -289.483038) (xy 92.09891 -289.488115) (xy 92.146921 -289.50492) (xy 92.191779 -289.528904)
			(xy 92.232419 -289.559496) (xy 92.267876 -289.59597) (xy 92.297306 -289.637459) (xy 92.320012 -289.682977)
			(xy 92.335453 -289.731444) (xy 92.343263 -289.781708) (xy 92.343732 -289.807142) (xy 92.343224 -289.833029)
			(xy 92.335125 -289.884167) (xy 92.319126 -289.933407) (xy 92.29562 -289.979539) (xy 92.265188 -290.021426)
			(xy 92.228578 -290.058036) (xy 92.186691 -290.088468) (xy 92.140559 -290.111974) (xy 92.091319 -290.127973)
			(xy 92.040181 -290.136072) (xy 91.988407 -290.136072) (xy 91.937269 -290.127973) (xy 91.888029 -290.111974)
			(xy 91.841897 -290.088468) (xy 91.80001 -290.058036) (xy 91.7634 -290.021426) (xy 91.732968 -289.979539)
			(xy 91.709462 -289.933407) (xy 91.693463 -289.884167) (xy 91.685364 -289.833029) (xy 91.684856 -289.807142)
			(xy 91.684856 -289.806634) (xy 91.685259 -289.783785) (xy 91.691612 -289.738531) (xy 91.704158 -289.694589)
			(xy 91.71305 -289.673538) (xy 91.722956 -289.650932) (xy 91.509088 -289.245802) (xy 91.484958 -289.24123)
			(xy 91.460019 -289.236158) (xy 91.411976 -289.219379) (xy 91.367083 -289.195414) (xy 91.326407 -289.164832)
			(xy 91.290917 -289.12836) (xy 91.261455 -289.086867) (xy 91.238722 -289.041337) (xy 91.223258 -288.992854)
			(xy 91.215431 -288.942571) (xy 91.214956 -288.917126) (xy 90.93454 -288.917126) (xy 90.934032 -288.943033)
			(xy 90.925926 -288.99421) (xy 90.909914 -289.043489) (xy 90.886391 -289.089656) (xy 90.855935 -289.131575)
			(xy 90.819297 -289.168213) (xy 90.777378 -289.198669) (xy 90.731211 -289.222192) (xy 90.681932 -289.238204)
			(xy 90.630755 -289.24631) (xy 90.578941 -289.24631) (xy 90.527764 -289.238204) (xy 90.478485 -289.222192)
			(xy 90.432318 -289.198669) (xy 90.390399 -289.168213) (xy 90.353761 -289.131575) (xy 90.323305 -289.089656)
			(xy 90.299782 -289.043489) (xy 90.28377 -288.99421) (xy 90.275664 -288.943033) (xy 90.275156 -288.917126)
			(xy 89.05494 -288.917126) (xy 89.054432 -288.943033) (xy 89.046326 -288.99421) (xy 89.030314 -289.043489)
			(xy 89.006791 -289.089656) (xy 88.976335 -289.131575) (xy 88.939697 -289.168213) (xy 88.897778 -289.198669)
			(xy 88.851611 -289.222192) (xy 88.802332 -289.238204) (xy 88.751155 -289.24631) (xy 88.699341 -289.24631)
			(xy 88.648164 -289.238204) (xy 88.598885 -289.222192) (xy 88.552718 -289.198669) (xy 88.510799 -289.168213)
			(xy 88.474161 -289.131575) (xy 88.443705 -289.089656) (xy 88.420182 -289.043489) (xy 88.40417 -288.99421)
			(xy 88.396064 -288.943033) (xy 88.395556 -288.917126) (xy 2.509012 -288.917126) (xy 2.509012 -297.515026)
			(xy 88.21548 -297.515026) (xy 88.219461 -297.382006) (xy 88.23139 -297.249461) (xy 88.251225 -297.117868)
			(xy 88.278894 -296.987696) (xy 88.314298 -296.859411) (xy 88.357311 -296.733474) (xy 88.407778 -296.610335)
			(xy 88.465519 -296.490434) (xy 88.530328 -296.374201) (xy 88.601972 -296.262051) (xy 88.680194 -296.154387)
			(xy 88.764715 -296.051594) (xy 88.855233 -295.954039) (xy 88.951422 -295.862073) (xy 89.05294 -295.776023)
			(xy 89.159421 -295.696199) (xy 89.270486 -295.622886) (xy 89.385737 -295.556346) (xy 89.504761 -295.496817)
			(xy 89.627132 -295.444513) (xy 89.752411 -295.399621) (xy 89.880152 -295.362302) (xy 90.009895 -295.332689)
			(xy 90.141177 -295.310888) (xy 90.273528 -295.296978) (xy 90.406474 -295.291007) (xy 90.539539 -295.292998)
			(xy 90.672247 -295.302943) (xy 90.804123 -295.320807) (xy 90.934694 -295.346525) (xy 91.063494 -295.380006)
			(xy 91.19006 -295.42113) (xy 91.313941 -295.46975) (xy 91.434692 -295.525691) (xy 91.551882 -295.588753)
			(xy 91.665091 -295.658711) (xy 91.773913 -295.735315) (xy 91.877959 -295.818289) (xy 91.976857 -295.907337)
			(xy 92.070252 -296.00214) (xy 92.15781 -296.102358) (xy 92.239219 -296.207634) (xy 92.314185 -296.31759)
			(xy 92.382442 -296.431832) (xy 92.443744 -296.549952) (xy 92.497873 -296.671527) (xy 92.544634 -296.796121)
			(xy 92.58386 -296.923289) (xy 92.61541 -297.052575) (xy 92.639173 -297.183516) (xy 92.655062 -297.315644)
			(xy 92.66302 -297.448486) (xy 92.663518 -297.515026) (xy 131.195582 -297.515026) (xy 131.199563 -297.382006)
			(xy 131.211492 -297.249461) (xy 131.231327 -297.117868) (xy 131.258996 -296.987696) (xy 131.2944 -296.859411)
			(xy 131.337413 -296.733474) (xy 131.38788 -296.610335) (xy 131.445621 -296.490434) (xy 131.51043 -296.374201)
			(xy 131.582074 -296.262051) (xy 131.660296 -296.154387) (xy 131.744817 -296.051594) (xy 131.835335 -295.954039)
			(xy 131.931524 -295.862073) (xy 132.033042 -295.776023) (xy 132.139523 -295.696199) (xy 132.250588 -295.622886)
			(xy 132.365839 -295.556346) (xy 132.484863 -295.496817) (xy 132.607234 -295.444513) (xy 132.732513 -295.399621)
			(xy 132.860254 -295.362302) (xy 132.989997 -295.332689) (xy 133.121279 -295.310888) (xy 133.25363 -295.296978)
			(xy 133.386576 -295.291007) (xy 133.519641 -295.292998) (xy 133.652349 -295.302943) (xy 133.784225 -295.320807)
			(xy 133.914796 -295.346525) (xy 134.043596 -295.380006) (xy 134.170162 -295.42113) (xy 134.294043 -295.46975)
			(xy 134.414794 -295.525691) (xy 134.531984 -295.588753) (xy 134.645193 -295.658711) (xy 134.754015 -295.735315)
			(xy 134.858061 -295.818289) (xy 134.956959 -295.907337) (xy 135.050354 -296.00214) (xy 135.137912 -296.102358)
			(xy 135.219321 -296.207634) (xy 135.294287 -296.31759) (xy 135.362544 -296.431832) (xy 135.423846 -296.549952)
			(xy 135.477975 -296.671527) (xy 135.524736 -296.796121) (xy 135.563962 -296.923289) (xy 135.595512 -297.052575)
			(xy 135.619275 -297.183516) (xy 135.635164 -297.315644) (xy 135.643122 -297.448486) (xy 135.64362 -297.515026)
			(xy 336.155548 -297.515026) (xy 336.159529 -297.382006) (xy 336.171458 -297.249461) (xy 336.191293 -297.117868)
			(xy 336.218962 -296.987696) (xy 336.254366 -296.859411) (xy 336.297379 -296.733474) (xy 336.347846 -296.610335)
			(xy 336.405587 -296.490434) (xy 336.470396 -296.374201) (xy 336.54204 -296.262051) (xy 336.620262 -296.154387)
			(xy 336.704783 -296.051594) (xy 336.795301 -295.954039) (xy 336.89149 -295.862073) (xy 336.993008 -295.776023)
			(xy 337.099489 -295.696199) (xy 337.210554 -295.622886) (xy 337.325805 -295.556346) (xy 337.444829 -295.496817)
			(xy 337.5672 -295.444513) (xy 337.692479 -295.399621) (xy 337.82022 -295.362302) (xy 337.949963 -295.332689)
			(xy 338.081245 -295.310888) (xy 338.213596 -295.296978) (xy 338.346542 -295.291007) (xy 338.479607 -295.292998)
			(xy 338.612315 -295.302943) (xy 338.744191 -295.320807) (xy 338.874762 -295.346525) (xy 339.003562 -295.380006)
			(xy 339.130128 -295.42113) (xy 339.254009 -295.46975) (xy 339.37476 -295.525691) (xy 339.49195 -295.588753)
			(xy 339.605159 -295.658711) (xy 339.713981 -295.735315) (xy 339.818027 -295.818289) (xy 339.916925 -295.907337)
			(xy 340.01032 -296.00214) (xy 340.097878 -296.102358) (xy 340.179287 -296.207634) (xy 340.254253 -296.31759)
			(xy 340.32251 -296.431832) (xy 340.383812 -296.549952) (xy 340.437941 -296.671527) (xy 340.484702 -296.796121)
			(xy 340.523928 -296.923289) (xy 340.555478 -297.052575) (xy 340.579241 -297.183516) (xy 340.59513 -297.315644)
			(xy 340.603088 -297.448486) (xy 340.603586 -297.515026) (xy 379.13565 -297.515026) (xy 379.139631 -297.382006)
			(xy 379.15156 -297.249461) (xy 379.171395 -297.117868) (xy 379.199064 -296.987696) (xy 379.234468 -296.859411)
			(xy 379.277481 -296.733474) (xy 379.327948 -296.610335) (xy 379.385689 -296.490434) (xy 379.450498 -296.374201)
			(xy 379.522142 -296.262051) (xy 379.600364 -296.154387) (xy 379.684885 -296.051594) (xy 379.775403 -295.954039)
			(xy 379.871592 -295.862073) (xy 379.97311 -295.776023) (xy 380.079591 -295.696199) (xy 380.190656 -295.622886)
			(xy 380.305907 -295.556346) (xy 380.424931 -295.496817) (xy 380.547302 -295.444513) (xy 380.672581 -295.399621)
			(xy 380.800322 -295.362302) (xy 380.930065 -295.332689) (xy 381.061347 -295.310888) (xy 381.193698 -295.296978)
			(xy 381.326644 -295.291007) (xy 381.459709 -295.292998) (xy 381.592417 -295.302943) (xy 381.724293 -295.320807)
			(xy 381.854864 -295.346525) (xy 381.983664 -295.380006) (xy 382.11023 -295.42113) (xy 382.234111 -295.46975)
			(xy 382.354862 -295.525691) (xy 382.472052 -295.588753) (xy 382.585261 -295.658711) (xy 382.694083 -295.735315)
			(xy 382.798129 -295.818289) (xy 382.897027 -295.907337) (xy 382.990422 -296.00214) (xy 383.07798 -296.102358)
			(xy 383.159389 -296.207634) (xy 383.234355 -296.31759) (xy 383.302612 -296.431832) (xy 383.363914 -296.549952)
			(xy 383.418043 -296.671527) (xy 383.464804 -296.796121) (xy 383.50403 -296.923289) (xy 383.53558 -297.052575)
			(xy 383.559343 -297.183516) (xy 383.575232 -297.315644) (xy 383.58319 -297.448486) (xy 383.583688 -297.515026)
			(xy 383.58319 -297.581566) (xy 383.575232 -297.714408) (xy 383.559343 -297.846536) (xy 383.53558 -297.977477)
			(xy 383.50403 -298.106763) (xy 383.464804 -298.233931) (xy 383.418043 -298.358525) (xy 383.363914 -298.4801)
			(xy 383.302612 -298.59822) (xy 383.234355 -298.712462) (xy 383.159389 -298.822418) (xy 383.07798 -298.927694)
			(xy 382.990422 -299.027912) (xy 382.897027 -299.122715) (xy 382.798129 -299.211763) (xy 382.694083 -299.294737)
			(xy 382.585261 -299.371341) (xy 382.472052 -299.441299) (xy 382.354862 -299.504361) (xy 382.234111 -299.560302)
			(xy 382.11023 -299.608922) (xy 381.983664 -299.650046) (xy 381.854864 -299.683527) (xy 381.724293 -299.709245)
			(xy 381.592417 -299.727109) (xy 381.459709 -299.737054) (xy 381.326644 -299.739045) (xy 381.193698 -299.733074)
			(xy 381.061347 -299.719164) (xy 380.930065 -299.697363) (xy 380.800322 -299.66775) (xy 380.672581 -299.630431)
			(xy 380.547302 -299.585539) (xy 380.424931 -299.533235) (xy 380.305907 -299.473706) (xy 380.190656 -299.407166)
			(xy 380.079591 -299.333853) (xy 379.97311 -299.254029) (xy 379.871592 -299.167979) (xy 379.775403 -299.076013)
			(xy 379.684885 -298.978458) (xy 379.600364 -298.875665) (xy 379.522142 -298.768001) (xy 379.450498 -298.655851)
			(xy 379.385689 -298.539618) (xy 379.327948 -298.419717) (xy 379.277481 -298.296578) (xy 379.234468 -298.170641)
			(xy 379.199064 -298.042356) (xy 379.171395 -297.912184) (xy 379.15156 -297.780591) (xy 379.139631 -297.648046)
			(xy 379.13565 -297.515026) (xy 340.603586 -297.515026) (xy 340.603088 -297.581566) (xy 340.59513 -297.714408)
			(xy 340.579241 -297.846536) (xy 340.555478 -297.977477) (xy 340.523928 -298.106763) (xy 340.484702 -298.233931)
			(xy 340.437941 -298.358525) (xy 340.383812 -298.4801) (xy 340.32251 -298.59822) (xy 340.254253 -298.712462)
			(xy 340.179287 -298.822418) (xy 340.097878 -298.927694) (xy 340.01032 -299.027912) (xy 339.916925 -299.122715)
			(xy 339.818027 -299.211763) (xy 339.713981 -299.294737) (xy 339.605159 -299.371341) (xy 339.49195 -299.441299)
			(xy 339.37476 -299.504361) (xy 339.254009 -299.560302) (xy 339.130128 -299.608922) (xy 339.003562 -299.650046)
			(xy 338.874762 -299.683527) (xy 338.744191 -299.709245) (xy 338.612315 -299.727109) (xy 338.479607 -299.737054)
			(xy 338.346542 -299.739045) (xy 338.213596 -299.733074) (xy 338.081245 -299.719164) (xy 337.949963 -299.697363)
			(xy 337.82022 -299.66775) (xy 337.692479 -299.630431) (xy 337.5672 -299.585539) (xy 337.444829 -299.533235)
			(xy 337.325805 -299.473706) (xy 337.210554 -299.407166) (xy 337.099489 -299.333853) (xy 336.993008 -299.254029)
			(xy 336.89149 -299.167979) (xy 336.795301 -299.076013) (xy 336.704783 -298.978458) (xy 336.620262 -298.875665)
			(xy 336.54204 -298.768001) (xy 336.470396 -298.655851) (xy 336.405587 -298.539618) (xy 336.347846 -298.419717)
			(xy 336.297379 -298.296578) (xy 336.254366 -298.170641) (xy 336.218962 -298.042356) (xy 336.191293 -297.912184)
			(xy 336.171458 -297.780591) (xy 336.159529 -297.648046) (xy 336.155548 -297.515026) (xy 135.64362 -297.515026)
			(xy 135.643122 -297.581566) (xy 135.635164 -297.714408) (xy 135.619275 -297.846536) (xy 135.595512 -297.977477)
			(xy 135.563962 -298.106763) (xy 135.524736 -298.233931) (xy 135.477975 -298.358525) (xy 135.423846 -298.4801)
			(xy 135.362544 -298.59822) (xy 135.294287 -298.712462) (xy 135.219321 -298.822418) (xy 135.137912 -298.927694)
			(xy 135.050354 -299.027912) (xy 134.956959 -299.122715) (xy 134.858061 -299.211763) (xy 134.754015 -299.294737)
			(xy 134.645193 -299.371341) (xy 134.531984 -299.441299) (xy 134.414794 -299.504361) (xy 134.294043 -299.560302)
			(xy 134.170162 -299.608922) (xy 134.043596 -299.650046) (xy 133.914796 -299.683527) (xy 133.784225 -299.709245)
			(xy 133.652349 -299.727109) (xy 133.519641 -299.737054) (xy 133.386576 -299.739045) (xy 133.25363 -299.733074)
			(xy 133.121279 -299.719164) (xy 132.989997 -299.697363) (xy 132.860254 -299.66775) (xy 132.732513 -299.630431)
			(xy 132.607234 -299.585539) (xy 132.484863 -299.533235) (xy 132.365839 -299.473706) (xy 132.250588 -299.407166)
			(xy 132.139523 -299.333853) (xy 132.033042 -299.254029) (xy 131.931524 -299.167979) (xy 131.835335 -299.076013)
			(xy 131.744817 -298.978458) (xy 131.660296 -298.875665) (xy 131.582074 -298.768001) (xy 131.51043 -298.655851)
			(xy 131.445621 -298.539618) (xy 131.38788 -298.419717) (xy 131.337413 -298.296578) (xy 131.2944 -298.170641)
			(xy 131.258996 -298.042356) (xy 131.231327 -297.912184) (xy 131.211492 -297.780591) (xy 131.199563 -297.648046)
			(xy 131.195582 -297.515026) (xy 92.663518 -297.515026) (xy 92.66302 -297.581566) (xy 92.655062 -297.714408)
			(xy 92.639173 -297.846536) (xy 92.61541 -297.977477) (xy 92.58386 -298.106763) (xy 92.544634 -298.233931)
			(xy 92.497873 -298.358525) (xy 92.443744 -298.4801) (xy 92.382442 -298.59822) (xy 92.314185 -298.712462)
			(xy 92.239219 -298.822418) (xy 92.15781 -298.927694) (xy 92.070252 -299.027912) (xy 91.976857 -299.122715)
			(xy 91.877959 -299.211763) (xy 91.773913 -299.294737) (xy 91.665091 -299.371341) (xy 91.551882 -299.441299)
			(xy 91.434692 -299.504361) (xy 91.313941 -299.560302) (xy 91.19006 -299.608922) (xy 91.063494 -299.650046)
			(xy 90.934694 -299.683527) (xy 90.804123 -299.709245) (xy 90.672247 -299.727109) (xy 90.539539 -299.737054)
			(xy 90.406474 -299.739045) (xy 90.273528 -299.733074) (xy 90.141177 -299.719164) (xy 90.009895 -299.697363)
			(xy 89.880152 -299.66775) (xy 89.752411 -299.630431) (xy 89.627132 -299.585539) (xy 89.504761 -299.533235)
			(xy 89.385737 -299.473706) (xy 89.270486 -299.407166) (xy 89.159421 -299.333853) (xy 89.05294 -299.254029)
			(xy 88.951422 -299.167979) (xy 88.855233 -299.076013) (xy 88.764715 -298.978458) (xy 88.680194 -298.875665)
			(xy 88.601972 -298.768001) (xy 88.530328 -298.655851) (xy 88.465519 -298.539618) (xy 88.407778 -298.419717)
			(xy 88.357311 -298.296578) (xy 88.314298 -298.170641) (xy 88.278894 -298.042356) (xy 88.251225 -297.912184)
			(xy 88.23139 -297.780591) (xy 88.219461 -297.648046) (xy 88.21548 -297.515026) (xy 2.509012 -297.515026)
			(xy 2.509012 -360.76382) (xy 4.226823 -360.76382) (xy 4.230819 -360.553934) (xy 4.242804 -360.344352)
			(xy 4.262758 -360.135378) (xy 4.290654 -359.927316) (xy 4.326451 -359.720466) (xy 4.370096 -359.515129)
			(xy 4.421528 -359.311603) (xy 4.48067 -359.110182) (xy 4.547438 -358.911159) (xy 4.621734 -358.714822)
			(xy 4.703452 -358.521456) (xy 4.792471 -358.331341) (xy 4.888664 -358.144753) (xy 4.991891 -357.961962)
			(xy 5.102002 -357.783234) (xy 5.218837 -357.608827) (xy 5.342227 -357.438995) (xy 5.471994 -357.273983)
			(xy 5.607948 -357.114032) (xy 5.749894 -356.959372) (xy 5.897624 -356.810228) (xy 6.050926 -356.666817)
			(xy 6.209576 -356.529346) (xy 6.373345 -356.398014) (xy 6.541995 -356.273013) (xy 6.715281 -356.154522)
			(xy 6.892953 -356.042715) (xy 7.074753 -355.937753) (xy 7.260417 -355.839788) (xy 7.449675 -355.748963)
			(xy 7.642255 -355.665409) (xy 7.837876 -355.589246) (xy 8.036254 -355.520587) (xy 8.237103 -355.45953)
			(xy 8.44013 -355.406163) (xy 8.645043 -355.360565) (xy 8.851542 -355.3228) (xy 9.059329 -355.292925)
			(xy 9.268104 -355.270982) (xy 9.477562 -355.257003) (xy 9.687401 -355.251008) (xy 9.897315 -355.253007)
			(xy 10.107002 -355.262995) (xy 10.316156 -355.28096) (xy 10.524474 -355.306874) (xy 10.731655 -355.340699)
			(xy 10.937399 -355.382388) (xy 11.141405 -355.43188) (xy 11.34338 -355.489102) (xy 11.54303 -355.553972)
			(xy 11.740065 -355.626396) (xy 11.934201 -355.706269) (xy 12.125154 -355.793475) (xy 12.31265 -355.887887)
			(xy 12.496415 -355.989369) (xy 12.676183 -356.097773) (xy 12.851694 -356.212943) (xy 13.022693 -356.334711)
			(xy 13.188933 -356.4629) (xy 13.350172 -356.597326) (xy 13.506176 -356.737793) (xy 13.656719 -356.884097)
			(xy 13.801583 -357.036026) (xy 13.940558 -357.19336) (xy 14.073443 -357.355871) (xy 14.200044 -357.523324)
			(xy 14.320179 -357.695474) (xy 14.433673 -357.872074) (xy 14.540361 -358.052866) (xy 14.640088 -358.237589)
			(xy 14.732711 -358.425975) (xy 14.818095 -358.61775) (xy 14.896116 -358.812637) (xy 14.966661 -359.010353)
			(xy 15.029628 -359.210611) (xy 15.084925 -359.413121) (xy 15.132472 -359.61759) (xy 15.1722 -359.823721)
			(xy 15.204052 -360.031214) (xy 15.227982 -360.23977) (xy 15.243954 -360.449086) (xy 15.251946 -360.658858)
			(xy 15.252446 -360.76382) (xy 15.251946 -360.868782) (xy 15.243954 -361.078554) (xy 15.239789 -361.133136)
			(xy 121.446286 -361.133136) (xy 121.450375 -361.077254) (xy 121.462558 -361.022564) (xy 121.482574 -360.97023)
			(xy 121.509997 -360.921368) (xy 121.544242 -360.87702) (xy 121.584578 -360.83813) (xy 121.630148 -360.805528)
			(xy 121.679979 -360.779909) (xy 121.733009 -360.761817) (xy 121.788107 -360.75164) (xy 121.844101 -360.749594)
			(xy 121.899796 -360.755722) (xy 121.930771 -360.76382) (xy 211.161635 -360.76382) (xy 211.16566 -360.621628)
			(xy 211.177723 -360.479892) (xy 211.197786 -360.339066) (xy 211.225784 -360.1996) (xy 211.261628 -360.061941)
			(xy 211.305202 -359.926531) (xy 211.356367 -359.793803) (xy 211.41496 -359.664182) (xy 211.480791 -359.538084)
			(xy 211.553652 -359.415912) (xy 211.633307 -359.298058) (xy 211.719503 -359.184899) (xy 211.811962 -359.076797)
			(xy 211.91039 -358.9741) (xy 212.014469 -358.877136) (xy 212.123868 -358.786216) (xy 212.238236 -358.70163)
			(xy 212.357205 -358.62365) (xy 212.480396 -358.552526) (xy 212.607413 -358.488485) (xy 212.73785 -358.431733)
			(xy 212.871289 -358.382451) (xy 213.007302 -358.340797) (xy 213.145454 -358.306905) (xy 213.285303 -358.280884)
			(xy 213.426399 -358.262816) (xy 213.568291 -358.252759) (xy 213.710526 -358.250746) (xy 213.852646 -358.256783)
			(xy 213.994197 -358.270851) (xy 214.134726 -358.292905) (xy 214.273781 -358.322874) (xy 214.410919 -358.360662)
			(xy 214.545699 -358.406148) (xy 214.67769 -358.459186) (xy 214.806469 -358.519607) (xy 214.931623 -358.587216)
			(xy 215.052751 -358.661798) (xy 215.169467 -358.743114) (xy 215.281395 -358.830902) (xy 215.388177 -358.924882)
			(xy 215.489471 -359.024752) (xy 215.584952 -359.130194) (xy 215.674316 -359.240868) (xy 215.757274 -359.356421)
			(xy 215.833563 -359.476482) (xy 215.902937 -359.600667) (xy 215.965174 -359.728578) (xy 216.020075 -359.859805)
			(xy 216.067463 -359.993928) (xy 216.107188 -360.130517) (xy 216.139121 -360.269135) (xy 216.163162 -360.409337)
			(xy 216.179231 -360.550675) (xy 216.187279 -360.692696) (xy 216.187782 -360.76382) (xy 255.611635 -360.76382)
			(xy 255.61566 -360.621628) (xy 255.627723 -360.479892) (xy 255.647786 -360.339066) (xy 255.675784 -360.1996)
			(xy 255.711628 -360.061941) (xy 255.755202 -359.926531) (xy 255.806367 -359.793803) (xy 255.86496 -359.664182)
			(xy 255.930791 -359.538084) (xy 256.003652 -359.415912) (xy 256.083307 -359.298058) (xy 256.169503 -359.184899)
			(xy 256.261962 -359.076797) (xy 256.36039 -358.9741) (xy 256.464469 -358.877136) (xy 256.573868 -358.786216)
			(xy 256.688236 -358.70163) (xy 256.807205 -358.62365) (xy 256.930396 -358.552526) (xy 257.057413 -358.488485)
			(xy 257.18785 -358.431733) (xy 257.321289 -358.382451) (xy 257.457302 -358.340797) (xy 257.595454 -358.306905)
			(xy 257.735303 -358.280884) (xy 257.876399 -358.262816) (xy 258.018291 -358.252759) (xy 258.160526 -358.250746)
			(xy 258.302646 -358.256783) (xy 258.444197 -358.270851) (xy 258.584726 -358.292905) (xy 258.723781 -358.322874)
			(xy 258.860919 -358.360662) (xy 258.995699 -358.406148) (xy 259.12769 -358.459186) (xy 259.256469 -358.519607)
			(xy 259.381623 -358.587216) (xy 259.502751 -358.661798) (xy 259.619467 -358.743114) (xy 259.731395 -358.830902)
			(xy 259.838177 -358.924882) (xy 259.939471 -359.024752) (xy 260.034952 -359.130194) (xy 260.124316 -359.240868)
			(xy 260.207274 -359.356421) (xy 260.283563 -359.476482) (xy 260.352937 -359.600667) (xy 260.415174 -359.728578)
			(xy 260.470075 -359.859805) (xy 260.517463 -359.993928) (xy 260.557188 -360.130517) (xy 260.589121 -360.269135)
			(xy 260.613162 -360.409337) (xy 260.629231 -360.550675) (xy 260.637279 -360.692696) (xy 260.637782 -360.76382)
			(xy 260.637279 -360.834944) (xy 260.629231 -360.976965) (xy 260.613162 -361.118303) (xy 260.610619 -361.133136)
			(xy 369.3861 -361.133136) (xy 369.390189 -361.077254) (xy 369.402372 -361.022564) (xy 369.422388 -360.97023)
			(xy 369.449811 -360.921368) (xy 369.484056 -360.87702) (xy 369.524392 -360.83813) (xy 369.569962 -360.805528)
			(xy 369.619793 -360.779909) (xy 369.672823 -360.761817) (xy 369.727921 -360.75164) (xy 369.783915 -360.749594)
			(xy 369.83961 -360.755722) (xy 369.870585 -360.76382) (xy 456.565771 -360.76382) (xy 456.569767 -360.553934)
			(xy 456.581752 -360.344352) (xy 456.601706 -360.135378) (xy 456.629602 -359.927316) (xy 456.665399 -359.720466)
			(xy 456.709044 -359.515129) (xy 456.760476 -359.311603) (xy 456.819618 -359.110182) (xy 456.886386 -358.911159)
			(xy 456.960682 -358.714822) (xy 457.0424 -358.521456) (xy 457.131419 -358.331341) (xy 457.227612 -358.144753)
			(xy 457.330839 -357.961962) (xy 457.44095 -357.783234) (xy 457.557785 -357.608827) (xy 457.681175 -357.438995)
			(xy 457.810942 -357.273983) (xy 457.946896 -357.114032) (xy 458.088842 -356.959372) (xy 458.236572 -356.810228)
			(xy 458.389874 -356.666817) (xy 458.548524 -356.529346) (xy 458.712293 -356.398014) (xy 458.880943 -356.273013)
			(xy 459.054229 -356.154522) (xy 459.231901 -356.042715) (xy 459.413701 -355.937753) (xy 459.599365 -355.839788)
			(xy 459.788623 -355.748963) (xy 459.981203 -355.665409) (xy 460.176824 -355.589246) (xy 460.375202 -355.520587)
			(xy 460.576051 -355.45953) (xy 460.779078 -355.406163) (xy 460.983991 -355.360565) (xy 461.19049 -355.3228)
			(xy 461.398277 -355.292925) (xy 461.607052 -355.270982) (xy 461.81651 -355.257003) (xy 462.026349 -355.251008)
			(xy 462.236263 -355.253007) (xy 462.44595 -355.262995) (xy 462.655104 -355.28096) (xy 462.863422 -355.306874)
			(xy 463.070603 -355.340699) (xy 463.276347 -355.382388) (xy 463.480353 -355.43188) (xy 463.682328 -355.489102)
			(xy 463.881978 -355.553972) (xy 464.079013 -355.626396) (xy 464.273149 -355.706269) (xy 464.464102 -355.793475)
			(xy 464.651598 -355.887887) (xy 464.835363 -355.989369) (xy 465.015131 -356.097773) (xy 465.190642 -356.212943)
			(xy 465.361641 -356.334711) (xy 465.527881 -356.4629) (xy 465.68912 -356.597326) (xy 465.845124 -356.737793)
			(xy 465.995667 -356.884097) (xy 466.140531 -357.036026) (xy 466.279506 -357.19336) (xy 466.412391 -357.355871)
			(xy 466.538992 -357.523324) (xy 466.659127 -357.695474) (xy 466.772621 -357.872074) (xy 466.879309 -358.052866)
			(xy 466.979036 -358.237589) (xy 467.071659 -358.425975) (xy 467.157043 -358.61775) (xy 467.235064 -358.812637)
			(xy 467.305609 -359.010353) (xy 467.368576 -359.210611) (xy 467.423873 -359.413121) (xy 467.47142 -359.61759)
			(xy 467.511148 -359.823721) (xy 467.543 -360.031214) (xy 467.56693 -360.23977) (xy 467.582902 -360.449086)
			(xy 467.590894 -360.658858) (xy 467.591394 -360.76382) (xy 467.590894 -360.868782) (xy 467.582902 -361.078554)
			(xy 467.56693 -361.28787) (xy 467.543 -361.496426) (xy 467.511148 -361.703919) (xy 467.47142 -361.91005)
			(xy 467.423873 -362.114519) (xy 467.368576 -362.317029) (xy 467.305609 -362.517287) (xy 467.235064 -362.715003)
			(xy 467.157043 -362.90989) (xy 467.071659 -363.101665) (xy 466.979036 -363.290051) (xy 466.879309 -363.474774)
			(xy 466.772621 -363.655566) (xy 466.659127 -363.832166) (xy 466.538992 -364.004316) (xy 466.412391 -364.171769)
			(xy 466.279506 -364.33428) (xy 466.140531 -364.491614) (xy 465.995667 -364.643543) (xy 465.845124 -364.789847)
			(xy 465.68912 -364.930314) (xy 465.527881 -365.06474) (xy 465.361641 -365.192929) (xy 465.190642 -365.314697)
			(xy 465.015131 -365.429867) (xy 464.835363 -365.538271) (xy 464.651598 -365.639753) (xy 464.464102 -365.734165)
			(xy 464.273149 -365.821371) (xy 464.079013 -365.901244) (xy 463.881978 -365.973668) (xy 463.682328 -366.038538)
			(xy 463.480353 -366.09576) (xy 463.276347 -366.145252) (xy 463.070603 -366.186941) (xy 462.863422 -366.220766)
			(xy 462.655104 -366.24668) (xy 462.44595 -366.264645) (xy 462.236263 -366.274633) (xy 462.026349 -366.276632)
			(xy 461.81651 -366.270637) (xy 461.607052 -366.256658) (xy 461.398277 -366.234715) (xy 461.19049 -366.20484)
			(xy 460.983991 -366.167075) (xy 460.779078 -366.121477) (xy 460.576051 -366.06811) (xy 460.375202 -366.007053)
			(xy 460.176824 -365.938394) (xy 459.981203 -365.862231) (xy 459.788623 -365.778677) (xy 459.599365 -365.687852)
			(xy 459.413701 -365.589887) (xy 459.231901 -365.484925) (xy 459.054229 -365.373118) (xy 458.880943 -365.254627)
			(xy 458.712293 -365.129626) (xy 458.548524 -364.998294) (xy 458.389874 -364.860823) (xy 458.236572 -364.717412)
			(xy 458.088842 -364.568268) (xy 457.946896 -364.413608) (xy 457.810942 -364.253657) (xy 457.681175 -364.088645)
			(xy 457.557785 -363.918813) (xy 457.44095 -363.744406) (xy 457.330839 -363.565678) (xy 457.227612 -363.382887)
			(xy 457.131419 -363.196299) (xy 457.0424 -363.006184) (xy 456.960682 -362.812818) (xy 456.886386 -362.616481)
			(xy 456.819618 -362.417458) (xy 456.760476 -362.216037) (xy 456.709044 -362.012511) (xy 456.665399 -361.807174)
			(xy 456.629602 -361.600324) (xy 456.601706 -361.392262) (xy 456.581752 -361.183288) (xy 456.569767 -360.973706)
			(xy 456.565771 -360.76382) (xy 369.870585 -360.76382) (xy 369.893819 -360.769894) (xy 369.945387 -360.791808)
			(xy 369.993215 -360.820997) (xy 370.036283 -360.856838) (xy 370.073673 -360.898568) (xy 370.104589 -360.945298)
			(xy 370.128372 -360.996031) (xy 370.144514 -361.049687) (xy 370.152673 -361.105121) (xy 370.153184 -361.133136)
			(xy 370.152673 -361.161151) (xy 370.144514 -361.216585) (xy 370.128372 -361.270241) (xy 370.104589 -361.320974)
			(xy 370.073673 -361.367704) (xy 370.036283 -361.409434) (xy 369.993215 -361.445275) (xy 369.945387 -361.474464)
			(xy 369.893819 -361.496378) (xy 369.83961 -361.51055) (xy 369.783915 -361.516678) (xy 369.727921 -361.514632)
			(xy 369.672823 -361.504455) (xy 369.619793 -361.486363) (xy 369.569962 -361.460744) (xy 369.524392 -361.428142)
			(xy 369.484056 -361.389252) (xy 369.449811 -361.344904) (xy 369.422388 -361.296042) (xy 369.402372 -361.243708)
			(xy 369.390189 -361.189018) (xy 369.3861 -361.133136) (xy 260.610619 -361.133136) (xy 260.589121 -361.258505)
			(xy 260.557188 -361.397123) (xy 260.517463 -361.533712) (xy 260.470075 -361.667835) (xy 260.415174 -361.799062)
			(xy 260.352937 -361.926973) (xy 260.283563 -362.051158) (xy 260.207274 -362.171219) (xy 260.124316 -362.286772)
			(xy 260.034952 -362.397446) (xy 259.939471 -362.502888) (xy 259.838177 -362.602758) (xy 259.731395 -362.696738)
			(xy 259.619467 -362.784526) (xy 259.502751 -362.865842) (xy 259.381623 -362.940424) (xy 259.256469 -363.008033)
			(xy 259.12769 -363.068454) (xy 258.995699 -363.121492) (xy 258.860919 -363.166978) (xy 258.723781 -363.204766)
			(xy 258.584726 -363.234735) (xy 258.444197 -363.256789) (xy 258.302646 -363.270857) (xy 258.160526 -363.276894)
			(xy 258.018291 -363.274881) (xy 257.876399 -363.264824) (xy 257.735303 -363.246756) (xy 257.595454 -363.220735)
			(xy 257.457302 -363.186843) (xy 257.321289 -363.145189) (xy 257.18785 -363.095907) (xy 257.057413 -363.039155)
			(xy 256.930396 -362.975114) (xy 256.807205 -362.90399) (xy 256.688236 -362.82601) (xy 256.573868 -362.741424)
			(xy 256.464469 -362.650504) (xy 256.36039 -362.55354) (xy 256.261962 -362.450843) (xy 256.169503 -362.342741)
			(xy 256.083307 -362.229582) (xy 256.003652 -362.111728) (xy 255.930791 -361.989556) (xy 255.86496 -361.863458)
			(xy 255.806367 -361.733837) (xy 255.755202 -361.601109) (xy 255.711628 -361.465699) (xy 255.675784 -361.32804)
			(xy 255.647786 -361.188574) (xy 255.627723 -361.047748) (xy 255.61566 -360.906012) (xy 255.611635 -360.76382)
			(xy 216.187782 -360.76382) (xy 216.187279 -360.834944) (xy 216.179231 -360.976965) (xy 216.163162 -361.118303)
			(xy 216.139121 -361.258505) (xy 216.107188 -361.397123) (xy 216.067463 -361.533712) (xy 216.020075 -361.667835)
			(xy 215.965174 -361.799062) (xy 215.902937 -361.926973) (xy 215.833563 -362.051158) (xy 215.757274 -362.171219)
			(xy 215.674316 -362.286772) (xy 215.584952 -362.397446) (xy 215.489471 -362.502888) (xy 215.388177 -362.602758)
			(xy 215.281395 -362.696738) (xy 215.169467 -362.784526) (xy 215.052751 -362.865842) (xy 214.931623 -362.940424)
			(xy 214.806469 -363.008033) (xy 214.67769 -363.068454) (xy 214.545699 -363.121492) (xy 214.410919 -363.166978)
			(xy 214.273781 -363.204766) (xy 214.134726 -363.234735) (xy 213.994197 -363.256789) (xy 213.852646 -363.270857)
			(xy 213.710526 -363.276894) (xy 213.568291 -363.274881) (xy 213.426399 -363.264824) (xy 213.285303 -363.246756)
			(xy 213.145454 -363.220735) (xy 213.007302 -363.186843) (xy 212.871289 -363.145189) (xy 212.73785 -363.095907)
			(xy 212.607413 -363.039155) (xy 212.480396 -362.975114) (xy 212.357205 -362.90399) (xy 212.238236 -362.82601)
			(xy 212.123868 -362.741424) (xy 212.014469 -362.650504) (xy 211.91039 -362.55354) (xy 211.811962 -362.450843)
			(xy 211.719503 -362.342741) (xy 211.633307 -362.229582) (xy 211.553652 -362.111728) (xy 211.480791 -361.989556)
			(xy 211.41496 -361.863458) (xy 211.356367 -361.733837) (xy 211.305202 -361.601109) (xy 211.261628 -361.465699)
			(xy 211.225784 -361.32804) (xy 211.197786 -361.188574) (xy 211.177723 -361.047748) (xy 211.16566 -360.906012)
			(xy 211.161635 -360.76382) (xy 121.930771 -360.76382) (xy 121.954005 -360.769894) (xy 122.005573 -360.791808)
			(xy 122.053401 -360.820997) (xy 122.096469 -360.856838) (xy 122.133859 -360.898568) (xy 122.164775 -360.945298)
			(xy 122.188558 -360.996031) (xy 122.2047 -361.049687) (xy 122.212859 -361.105121) (xy 122.21337 -361.133136)
			(xy 122.212859 -361.161151) (xy 122.2047 -361.216585) (xy 122.188558 -361.270241) (xy 122.164775 -361.320974)
			(xy 122.133859 -361.367704) (xy 122.096469 -361.409434) (xy 122.053401 -361.445275) (xy 122.005573 -361.474464)
			(xy 121.954005 -361.496378) (xy 121.899796 -361.51055) (xy 121.844101 -361.516678) (xy 121.788107 -361.514632)
			(xy 121.733009 -361.504455) (xy 121.679979 -361.486363) (xy 121.630148 -361.460744) (xy 121.584578 -361.428142)
			(xy 121.544242 -361.389252) (xy 121.509997 -361.344904) (xy 121.482574 -361.296042) (xy 121.462558 -361.243708)
			(xy 121.450375 -361.189018) (xy 121.446286 -361.133136) (xy 15.239789 -361.133136) (xy 15.227982 -361.28787)
			(xy 15.204052 -361.496426) (xy 15.1722 -361.703919) (xy 15.132472 -361.91005) (xy 15.084925 -362.114519)
			(xy 15.029628 -362.317029) (xy 14.966661 -362.517287) (xy 14.896116 -362.715003) (xy 14.818095 -362.90989)
			(xy 14.732711 -363.101665) (xy 14.640088 -363.290051) (xy 14.540361 -363.474774) (xy 14.433673 -363.655566)
			(xy 14.320179 -363.832166) (xy 14.200044 -364.004316) (xy 14.073443 -364.171769) (xy 13.940558 -364.33428)
			(xy 13.801583 -364.491614) (xy 13.656719 -364.643543) (xy 13.506176 -364.789847) (xy 13.350172 -364.930314)
			(xy 13.188933 -365.06474) (xy 13.022693 -365.192929) (xy 12.851694 -365.314697) (xy 12.676183 -365.429867)
			(xy 12.496415 -365.538271) (xy 12.31265 -365.639753) (xy 12.125154 -365.734165) (xy 11.934201 -365.821371)
			(xy 11.740065 -365.901244) (xy 11.54303 -365.973668) (xy 11.34338 -366.038538) (xy 11.141405 -366.09576)
			(xy 10.937399 -366.145252) (xy 10.731655 -366.186941) (xy 10.524474 -366.220766) (xy 10.316156 -366.24668)
			(xy 10.107002 -366.264645) (xy 9.897315 -366.274633) (xy 9.687401 -366.276632) (xy 9.477562 -366.270637)
			(xy 9.268104 -366.256658) (xy 9.059329 -366.234715) (xy 8.851542 -366.20484) (xy 8.645043 -366.167075)
			(xy 8.44013 -366.121477) (xy 8.237103 -366.06811) (xy 8.036254 -366.007053) (xy 7.837876 -365.938394)
			(xy 7.642255 -365.862231) (xy 7.449675 -365.778677) (xy 7.260417 -365.687852) (xy 7.074753 -365.589887)
			(xy 6.892953 -365.484925) (xy 6.715281 -365.373118) (xy 6.541995 -365.254627) (xy 6.373345 -365.129626)
			(xy 6.209576 -364.998294) (xy 6.050926 -364.860823) (xy 5.897624 -364.717412) (xy 5.749894 -364.568268)
			(xy 5.607948 -364.413608) (xy 5.471994 -364.253657) (xy 5.342227 -364.088645) (xy 5.218837 -363.918813)
			(xy 5.102002 -363.744406) (xy 4.991891 -363.565678) (xy 4.888664 -363.382887) (xy 4.792471 -363.196299)
			(xy 4.703452 -363.006184) (xy 4.621734 -362.812818) (xy 4.547438 -362.616481) (xy 4.48067 -362.417458)
			(xy 4.421528 -362.216037) (xy 4.370096 -362.012511) (xy 4.326451 -361.807174) (xy 4.290654 -361.600324)
			(xy 4.262758 -361.392262) (xy 4.242804 -361.183288) (xy 4.230819 -360.973706) (xy 4.226823 -360.76382)
			(xy 2.509012 -360.76382) (xy 2.509012 -383.932484) (xy 8.539215 -383.932484) (xy 8.539215 -383.803344)
			(xy 8.547165 -383.674449) (xy 8.563035 -383.546289) (xy 8.586764 -383.419348) (xy 8.618263 -383.294109)
			(xy 8.657412 -383.171046) (xy 8.704063 -383.050627) (xy 8.758038 -382.933308) (xy 8.819133 -382.819534)
			(xy 8.887116 -382.709737) (xy 8.96173 -382.604334) (xy 9.042691 -382.503724) (xy 9.129691 -382.408289)
			(xy 9.222402 -382.31839) (xy 9.320472 -382.234369) (xy 9.423527 -382.156545) (xy 9.531178 -382.085213)
			(xy 9.643017 -382.020643) (xy 9.758618 -381.963081) (xy 9.877543 -381.912744) (xy 9.999342 -381.869824)
			(xy 10.123552 -381.834483) (xy 10.249701 -381.806856) (xy 10.377313 -381.787047) (xy 10.505902 -381.775131)
			(xy 10.63498 -381.771155) (xy 10.764058 -381.775131) (xy 10.892647 -381.787047) (xy 11.020259 -381.806856)
			(xy 11.146408 -381.834483) (xy 11.270618 -381.869824) (xy 11.392417 -381.912744) (xy 11.511342 -381.963081)
			(xy 11.626943 -382.020643) (xy 11.738782 -382.085213) (xy 11.846433 -382.156545) (xy 11.949488 -382.234369)
			(xy 12.047558 -382.31839) (xy 12.140269 -382.408289) (xy 12.227269 -382.503724) (xy 12.30823 -382.604334)
			(xy 12.382844 -382.709737) (xy 12.450827 -382.819534) (xy 12.505341 -382.921052) (xy 19.016679 -382.921052)
			(xy 19.016679 -382.866548) (xy 19.024437 -382.812598) (xy 19.039793 -382.760301) (xy 19.062436 -382.710722)
			(xy 19.091904 -382.664871) (xy 19.127599 -382.62368) (xy 19.168792 -382.587989) (xy 19.214645 -382.558523)
			(xy 19.264226 -382.535884) (xy 19.316523 -382.520531) (xy 19.370474 -382.512778) (xy 19.397726 -382.512316)
			(xy 20.261326 -382.512316) (xy 20.288578 -382.512756) (xy 20.342526 -382.520516) (xy 20.394821 -382.535874)
			(xy 20.444398 -382.558518) (xy 20.490248 -382.587987) (xy 20.531438 -382.623681) (xy 20.567129 -382.664873)
			(xy 20.596594 -382.710725) (xy 20.619235 -382.760303) (xy 20.63459 -382.812599) (xy 20.642346 -382.866548)
			(xy 20.642346 -382.921052) (xy 20.636681 -382.960459) (xy 22.291788 -382.960459) (xy 22.291788 -382.905921)
			(xy 22.29955 -382.851938) (xy 22.314915 -382.79961) (xy 22.337571 -382.75) (xy 22.367056 -382.70412)
			(xy 22.40277 -382.662903) (xy 22.443987 -382.627188) (xy 22.489867 -382.597702) (xy 22.539476 -382.575046)
			(xy 22.591804 -382.559681) (xy 22.645787 -382.551919) (xy 22.673056 -382.551432) (xy 23.536656 -382.551432)
			(xy 23.563927 -382.551887) (xy 23.617915 -382.559649) (xy 23.670249 -382.575015) (xy 23.719863 -382.597673)
			(xy 23.765748 -382.62716) (xy 23.806969 -382.662878) (xy 23.842687 -382.704099) (xy 23.872175 -382.749983)
			(xy 23.894834 -382.799597) (xy 23.9102 -382.851931) (xy 23.917962 -382.905919) (xy 23.917962 -382.960461)
			(xy 23.9102 -383.014449) (xy 23.894834 -383.066783) (xy 23.872175 -383.116397) (xy 23.842687 -383.162281)
			(xy 23.806969 -383.203502) (xy 23.765748 -383.23922) (xy 23.719863 -383.268707) (xy 23.670249 -383.291365)
			(xy 23.617915 -383.306731) (xy 23.563927 -383.314493) (xy 23.536656 -383.314956) (xy 22.673056 -383.314956)
			(xy 22.645787 -383.314461) (xy 22.591804 -383.306699) (xy 22.539476 -383.291334) (xy 22.489867 -383.268678)
			(xy 22.443987 -383.239192) (xy 22.40277 -383.203477) (xy 22.367056 -383.16226) (xy 22.337571 -383.11638)
			(xy 22.314915 -383.06677) (xy 22.29955 -383.014442) (xy 22.291788 -382.960459) (xy 20.636681 -382.960459)
			(xy 20.63459 -382.975001) (xy 20.619235 -383.027297) (xy 20.596594 -383.076875) (xy 20.567129 -383.122727)
			(xy 20.531438 -383.163919) (xy 20.490248 -383.199613) (xy 20.444398 -383.229082) (xy 20.394821 -383.251726)
			(xy 20.342526 -383.267084) (xy 20.288578 -383.274844) (xy 20.261326 -383.275332) (xy 19.397726 -383.275332)
			(xy 19.370474 -383.274822) (xy 19.316523 -383.267069) (xy 19.264226 -383.251716) (xy 19.214645 -383.229077)
			(xy 19.168792 -383.199611) (xy 19.127599 -383.16392) (xy 19.091904 -383.122729) (xy 19.062436 -383.076878)
			(xy 19.039793 -383.027299) (xy 19.024437 -382.975002) (xy 19.016679 -382.921052) (xy 12.505341 -382.921052)
			(xy 12.511922 -382.933308) (xy 12.565897 -383.050627) (xy 12.612548 -383.171046) (xy 12.651697 -383.294109)
			(xy 12.683196 -383.419348) (xy 12.706925 -383.546289) (xy 12.722795 -383.674449) (xy 12.730745 -383.803344)
			(xy 12.731242 -383.867914) (xy 12.730745 -383.932484) (xy 12.722795 -384.061379) (xy 12.706925 -384.189539)
			(xy 12.683196 -384.31648) (xy 12.651697 -384.441719) (xy 12.612548 -384.564782) (xy 12.565897 -384.685201)
			(xy 12.511922 -384.80252) (xy 12.450827 -384.916294) (xy 12.382844 -385.026091) (xy 12.30823 -385.131494)
			(xy 12.227269 -385.232104) (xy 12.140269 -385.327539) (xy 12.047558 -385.417438) (xy 11.949488 -385.501459)
			(xy 11.846433 -385.579283) (xy 11.738782 -385.650615) (xy 11.626943 -385.715185) (xy 11.511342 -385.772747)
			(xy 11.483943 -385.784344) (xy 19.460972 -385.784344) (xy 19.460972 -384.920744) (xy 19.461458 -384.893493)
			(xy 19.469214 -384.839545) (xy 19.484569 -384.78725) (xy 19.507211 -384.737673) (xy 19.536677 -384.691823)
			(xy 19.572368 -384.650632) (xy 19.613559 -384.614941) (xy 19.659409 -384.585475) (xy 19.708986 -384.562833)
			(xy 19.761281 -384.547478) (xy 19.815229 -384.539722) (xy 19.869731 -384.539722) (xy 19.923679 -384.547478)
			(xy 19.975974 -384.562833) (xy 20.025551 -384.585475) (xy 20.071401 -384.614941) (xy 20.112592 -384.650632)
			(xy 20.148283 -384.691823) (xy 20.177749 -384.737673) (xy 20.200391 -384.78725) (xy 20.215746 -384.839545)
			(xy 20.223502 -384.893493) (xy 20.223988 -384.920744) (xy 20.223988 -385.784344) (xy 20.22353 -385.809998)
			(xy 22.731984 -385.809998) (xy 22.731984 -384.946398) (xy 22.73247 -384.919147) (xy 22.740226 -384.865199)
			(xy 22.755581 -384.812904) (xy 22.778223 -384.763327) (xy 22.807689 -384.717477) (xy 22.84338 -384.676286)
			(xy 22.884571 -384.640595) (xy 22.930421 -384.611129) (xy 22.979998 -384.588487) (xy 23.032293 -384.573132)
			(xy 23.086241 -384.565376) (xy 23.140743 -384.565376) (xy 23.194691 -384.573132) (xy 23.246986 -384.588487)
			(xy 23.296563 -384.611129) (xy 23.342413 -384.640595) (xy 23.383604 -384.676286) (xy 23.419295 -384.717477)
			(xy 23.448761 -384.763327) (xy 23.471403 -384.812904) (xy 23.486758 -384.865199) (xy 23.494514 -384.919147)
			(xy 23.495 -384.946398) (xy 23.495 -385.440249) (xy 36.585674 -385.440249) (xy 36.585674 -385.385751)
			(xy 36.593429 -385.331807) (xy 36.608782 -385.279515) (xy 36.63142 -385.229941) (xy 36.660882 -385.184092)
			(xy 36.696569 -385.142903) (xy 36.737753 -385.107211) (xy 36.783598 -385.077743) (xy 36.83317 -385.055099)
			(xy 36.88546 -385.039739) (xy 36.939403 -385.031977) (xy 36.966652 -385.031488) (xy 37.830252 -385.031488)
			(xy 37.857507 -385.031956) (xy 37.911462 -385.039707) (xy 37.963765 -385.055059) (xy 38.013351 -385.077699)
			(xy 38.05921 -385.107165) (xy 38.100408 -385.142858) (xy 38.136106 -385.184052) (xy 38.165578 -385.229907)
			(xy 38.188224 -385.27949) (xy 38.203582 -385.331791) (xy 38.211341 -385.385745) (xy 38.211341 -385.440255)
			(xy 38.203582 -385.494209) (xy 38.188224 -385.54651) (xy 38.165578 -385.596093) (xy 38.16123 -385.602858)
			(xy 41.455211 -385.602858) (xy 41.455211 -385.548342) (xy 41.46297 -385.494381) (xy 41.47833 -385.442074)
			(xy 41.500978 -385.392486) (xy 41.530453 -385.346625) (xy 41.566155 -385.305427) (xy 41.607357 -385.269729)
			(xy 41.653221 -385.240259) (xy 41.702812 -385.217616) (xy 41.755121 -385.202261) (xy 41.809082 -385.194508)
			(xy 41.83634 -385.194048) (xy 42.69994 -385.194048) (xy 42.727186 -385.194625) (xy 42.781123 -385.202385)
			(xy 42.833407 -385.217742) (xy 42.882974 -385.240383) (xy 42.928814 -385.269847) (xy 42.969994 -385.305534)
			(xy 43.005677 -385.346718) (xy 43.035136 -385.392562) (xy 43.057772 -385.44213) (xy 43.073123 -385.494416)
			(xy 43.080878 -385.548354) (xy 43.080878 -385.602846) (xy 43.073123 -385.656784) (xy 43.057772 -385.70907)
			(xy 43.035136 -385.758638) (xy 43.005677 -385.804482) (xy 42.969994 -385.845666) (xy 42.928814 -385.881353)
			(xy 42.882974 -385.910817) (xy 42.833407 -385.933458) (xy 42.781123 -385.948815) (xy 42.727186 -385.956575)
			(xy 42.69994 -385.957064) (xy 41.83634 -385.957064) (xy 41.809082 -385.956692) (xy 41.755121 -385.948939)
			(xy 41.702812 -385.933584) (xy 41.653221 -385.910941) (xy 41.607357 -385.881471) (xy 41.566155 -385.845773)
			(xy 41.530453 -385.804575) (xy 41.500978 -385.758714) (xy 41.47833 -385.709126) (xy 41.46297 -385.656819)
			(xy 41.455211 -385.602858) (xy 38.16123 -385.602858) (xy 38.136106 -385.641948) (xy 38.100408 -385.683142)
			(xy 38.05921 -385.718835) (xy 38.013351 -385.748301) (xy 37.963765 -385.770941) (xy 37.911462 -385.786293)
			(xy 37.857507 -385.794044) (xy 37.830252 -385.794504) (xy 36.966652 -385.794504) (xy 36.939403 -385.794023)
			(xy 36.88546 -385.786261) (xy 36.83317 -385.770901) (xy 36.783598 -385.748257) (xy 36.737753 -385.718789)
			(xy 36.696569 -385.683097) (xy 36.660882 -385.641908) (xy 36.63142 -385.596059) (xy 36.608782 -385.546485)
			(xy 36.593429 -385.494193) (xy 36.585674 -385.440249) (xy 23.495 -385.440249) (xy 23.495 -385.809998)
			(xy 23.494514 -385.837249) (xy 23.486758 -385.891197) (xy 23.471403 -385.943492) (xy 23.448761 -385.993069)
			(xy 23.419295 -386.038919) (xy 23.383604 -386.08011) (xy 23.342413 -386.115801) (xy 23.296563 -386.145267)
			(xy 23.246986 -386.167909) (xy 23.194691 -386.183264) (xy 23.140743 -386.19102) (xy 23.086241 -386.19102)
			(xy 23.032293 -386.183264) (xy 22.979998 -386.167909) (xy 22.930421 -386.145267) (xy 22.884571 -386.115801)
			(xy 22.84338 -386.08011) (xy 22.807689 -386.038919) (xy 22.778223 -385.993069) (xy 22.755581 -385.943492)
			(xy 22.740226 -385.891197) (xy 22.73247 -385.837249) (xy 22.731984 -385.809998) (xy 20.22353 -385.809998)
			(xy 20.223502 -385.811595) (xy 20.215746 -385.865543) (xy 20.200391 -385.917838) (xy 20.177749 -385.967415)
			(xy 20.148283 -386.013265) (xy 20.112592 -386.054456) (xy 20.071401 -386.090147) (xy 20.025551 -386.119613)
			(xy 19.975974 -386.142255) (xy 19.923679 -386.15761) (xy 19.869731 -386.165366) (xy 19.815229 -386.165366)
			(xy 19.761281 -386.15761) (xy 19.708986 -386.142255) (xy 19.659409 -386.119613) (xy 19.613559 -386.090147)
			(xy 19.572368 -386.054456) (xy 19.536677 -386.013265) (xy 19.507211 -385.967415) (xy 19.484569 -385.917838)
			(xy 19.469214 -385.865543) (xy 19.461458 -385.811595) (xy 19.460972 -385.784344) (xy 11.483943 -385.784344)
			(xy 11.392417 -385.823084) (xy 11.270618 -385.866004) (xy 11.146408 -385.901345) (xy 11.020259 -385.928972)
			(xy 10.892647 -385.948781) (xy 10.764058 -385.960697) (xy 10.63498 -385.964674) (xy 10.505902 -385.960697)
			(xy 10.377313 -385.948781) (xy 10.249701 -385.928972) (xy 10.123552 -385.901345) (xy 9.999342 -385.866004)
			(xy 9.877543 -385.823084) (xy 9.758618 -385.772747) (xy 9.643017 -385.715185) (xy 9.531178 -385.650615)
			(xy 9.423527 -385.579283) (xy 9.320472 -385.501459) (xy 9.222402 -385.417438) (xy 9.129691 -385.327539)
			(xy 9.042691 -385.232104) (xy 8.96173 -385.131494) (xy 8.887116 -385.026091) (xy 8.819133 -384.916294)
			(xy 8.758038 -384.80252) (xy 8.704063 -384.685201) (xy 8.657412 -384.564782) (xy 8.618263 -384.441719)
			(xy 8.586764 -384.31648) (xy 8.563035 -384.189539) (xy 8.547165 -384.061379) (xy 8.539215 -383.932484)
			(xy 2.509012 -383.932484) (xy 2.509012 -389.402275) (xy 286.566098 -389.402275) (xy 286.566098 -389.317529)
			(xy 286.574154 -389.233168) (xy 286.590192 -389.149954) (xy 286.614067 -389.068641) (xy 286.645564 -388.989966)
			(xy 286.684397 -388.914642) (xy 286.730213 -388.843349) (xy 286.7826 -388.776735) (xy 286.84108 -388.715402)
			(xy 286.905127 -388.659906) (xy 286.974158 -388.610748) (xy 287.04755 -388.568376) (xy 287.124637 -388.533171)
			(xy 287.204721 -388.505454) (xy 287.287078 -388.485474) (xy 287.370961 -388.473414) (xy 287.45561 -388.469382)
			(xy 287.540259 -388.473414) (xy 287.624142 -388.485474) (xy 287.706499 -388.505454) (xy 287.786583 -388.533171)
			(xy 287.86367 -388.568376) (xy 287.937062 -388.610748) (xy 288.006093 -388.659906) (xy 288.07014 -388.715402)
			(xy 288.12862 -388.776735) (xy 288.181007 -388.843349) (xy 288.226823 -388.914642) (xy 288.265656 -388.989966)
			(xy 288.297153 -389.068641) (xy 288.321028 -389.149954) (xy 288.337066 -389.233168) (xy 288.345122 -389.317529)
			(xy 288.345626 -389.359902) (xy 288.345122 -389.402275) (xy 297.615098 -389.402275) (xy 297.615098 -389.317529)
			(xy 297.623154 -389.233168) (xy 297.639192 -389.149954) (xy 297.663067 -389.068641) (xy 297.694564 -388.989966)
			(xy 297.733397 -388.914642) (xy 297.779213 -388.843349) (xy 297.8316 -388.776735) (xy 297.89008 -388.715402)
			(xy 297.954127 -388.659906) (xy 298.023158 -388.610748) (xy 298.09655 -388.568376) (xy 298.173637 -388.533171)
			(xy 298.253721 -388.505454) (xy 298.336078 -388.485474) (xy 298.419961 -388.473414) (xy 298.50461 -388.469382)
			(xy 298.589259 -388.473414) (xy 298.673142 -388.485474) (xy 298.755499 -388.505454) (xy 298.835583 -388.533171)
			(xy 298.91267 -388.568376) (xy 298.986062 -388.610748) (xy 299.055093 -388.659906) (xy 299.11914 -388.715402)
			(xy 299.17762 -388.776735) (xy 299.230007 -388.843349) (xy 299.275823 -388.914642) (xy 299.314656 -388.989966)
			(xy 299.346153 -389.068641) (xy 299.370028 -389.149954) (xy 299.386066 -389.233168) (xy 299.394122 -389.317529)
			(xy 299.394626 -389.359902) (xy 299.394122 -389.402275) (xy 299.386066 -389.486636) (xy 299.370028 -389.56985)
			(xy 299.346153 -389.651163) (xy 299.314656 -389.729838) (xy 299.275823 -389.805162) (xy 299.230007 -389.876455)
			(xy 299.17762 -389.943069) (xy 299.11914 -390.004402) (xy 299.055093 -390.059898) (xy 298.986062 -390.109056)
			(xy 298.91267 -390.151428) (xy 298.835583 -390.186633) (xy 298.755499 -390.21435) (xy 298.673142 -390.23433)
			(xy 298.589259 -390.24639) (xy 298.50461 -390.250423) (xy 298.419961 -390.24639) (xy 298.336078 -390.23433)
			(xy 298.253721 -390.21435) (xy 298.173637 -390.186633) (xy 298.09655 -390.151428) (xy 298.023158 -390.109056)
			(xy 297.954127 -390.059898) (xy 297.89008 -390.004402) (xy 297.8316 -389.943069) (xy 297.779213 -389.876455)
			(xy 297.733397 -389.805162) (xy 297.694564 -389.729838) (xy 297.663067 -389.651163) (xy 297.639192 -389.56985)
			(xy 297.623154 -389.486636) (xy 297.615098 -389.402275) (xy 288.345122 -389.402275) (xy 288.337066 -389.486636)
			(xy 288.321028 -389.56985) (xy 288.297153 -389.651163) (xy 288.265656 -389.729838) (xy 288.226823 -389.805162)
			(xy 288.181007 -389.876455) (xy 288.12862 -389.943069) (xy 288.07014 -390.004402) (xy 288.006093 -390.059898)
			(xy 287.937062 -390.109056) (xy 287.86367 -390.151428) (xy 287.786583 -390.186633) (xy 287.706499 -390.21435)
			(xy 287.624142 -390.23433) (xy 287.540259 -390.24639) (xy 287.45561 -390.250423) (xy 287.370961 -390.24639)
			(xy 287.287078 -390.23433) (xy 287.204721 -390.21435) (xy 287.124637 -390.186633) (xy 287.04755 -390.151428)
			(xy 286.974158 -390.109056) (xy 286.905127 -390.059898) (xy 286.84108 -390.004402) (xy 286.7826 -389.943069)
			(xy 286.730213 -389.876455) (xy 286.684397 -389.805162) (xy 286.645564 -389.729838) (xy 286.614067 -389.651163)
			(xy 286.590192 -389.56985) (xy 286.574154 -389.486636) (xy 286.566098 -389.402275) (xy 2.509012 -389.402275)
			(xy 2.509012 -390.74852) (xy 289.828732 -390.74852) (xy 289.829157 -390.717787) (xy 289.836564 -390.656768)
			(xy 289.851272 -390.597088) (xy 289.873068 -390.539615) (xy 289.901633 -390.485189) (xy 289.93655 -390.434604)
			(xy 289.97731 -390.388596) (xy 290.023319 -390.347837) (xy 290.073907 -390.312922) (xy 290.128334 -390.28436)
			(xy 290.185807 -390.262566) (xy 290.245488 -390.24786) (xy 290.306507 -390.240455) (xy 290.33724 -390.240012)
			(xy 290.369283 -390.240508) (xy 290.432859 -390.248584) (xy 290.494917 -390.264579) (xy 290.554476 -390.288239)
			(xy 290.610594 -390.31919) (xy 290.662381 -390.356941) (xy 290.709019 -390.400896) (xy 290.749768 -390.450359)
			(xy 290.783985 -390.504546) (xy 290.811128 -390.562601) (xy 290.830767 -390.623604) (xy 290.842591 -390.686591)
			(xy 290.844986 -390.718548) (xy 290.846452 -390.733661) (xy 290.857061 -390.762093) (xy 290.875562 -390.786147)
			(xy 290.900318 -390.803698) (xy 290.929141 -390.813192) (xy 290.9443 -390.814052) (xy 290.977155 -390.815239)
			(xy 291.042167 -390.825028) (xy 291.105376 -390.843112) (xy 291.165728 -390.86919) (xy 291.222216 -390.902827)
			(xy 291.2739 -390.943462) (xy 291.319917 -390.990417) (xy 291.359501 -391.04291) (xy 291.391992 -391.100065)
			(xy 291.416847 -391.160931) (xy 291.433653 -391.224491) (xy 291.442129 -391.289688) (xy 291.442648 -391.32256)
			(xy 291.442106 -391.353289) (xy 291.434703 -391.414298) (xy 291.42 -391.473971) (xy 291.398212 -391.531436)
			(xy 291.369656 -391.585856) (xy 291.334748 -391.636437) (xy 291.293998 -391.682441) (xy 291.248 -391.723199)
			(xy 291.197424 -391.758114) (xy 291.143009 -391.786679) (xy 291.085547 -391.808477) (xy 291.025877 -391.823189)
			(xy 290.964869 -391.830602) (xy 290.93414 -391.831068) (xy 290.902098 -391.830516) (xy 290.838523 -391.822449)
			(xy 290.776465 -391.806463) (xy 290.716905 -391.78281) (xy 290.660787 -391.751866) (xy 290.608999 -391.71412)
			(xy 290.56236 -391.670169) (xy 290.521609 -391.620711) (xy 290.487392 -391.566526) (xy 290.460249 -391.508474)
			(xy 290.440611 -391.447473) (xy 290.428788 -391.384488) (xy 290.426394 -391.352532) (xy 290.424962 -391.337414)
			(xy 290.414346 -391.308979) (xy 290.395837 -391.284924) (xy 290.371072 -391.267376) (xy 290.342242 -391.257886)
			(xy 290.32708 -391.257028) (xy 290.294229 -391.25578) (xy 290.229223 -391.24599) (xy 290.166019 -391.227907)
			(xy 290.105673 -391.201832) (xy 290.049188 -391.1682) (xy 289.997507 -391.127571) (xy 289.95149 -391.080623)
			(xy 289.911906 -391.028137) (xy 289.879413 -390.97099) (xy 289.854553 -390.910132) (xy 289.837741 -390.846579)
			(xy 289.829256 -390.78139) (xy 289.828732 -390.74852) (xy 2.509012 -390.74852) (xy 2.509012 -394.8085)
			(xy 243.179528 -394.8085) (xy 243.183558 -394.723892) (xy 243.195613 -394.640051) (xy 243.215583 -394.557735)
			(xy 243.243287 -394.47769) (xy 243.278475 -394.400641) (xy 243.320827 -394.327286) (xy 243.36996 -394.258289)
			(xy 243.42543 -394.194274) (xy 243.486733 -394.135823) (xy 243.553315 -394.083463) (xy 243.624573 -394.03767)
			(xy 243.699861 -393.998857) (xy 243.778498 -393.967377) (xy 243.859771 -393.943515) (xy 243.942944 -393.927486)
			(xy 244.027264 -393.919435) (xy 244.069616 -393.918948) (xy 244.11084 -393.919417) (xy 244.192933 -393.927053)
			(xy 244.273968 -393.94225) (xy 244.35325 -393.964876) (xy 244.430099 -393.994739) (xy 244.503857 -394.031582)
			(xy 244.573891 -394.075088) (xy 244.639601 -394.124886) (xy 244.670326 -394.152374) (xy 244.677558 -394.158461)
			(xy 244.695171 -394.165287) (xy 244.714061 -394.165287) (xy 244.731674 -394.158461) (xy 244.738906 -394.152374)
			(xy 244.769639 -394.124894) (xy 244.835341 -394.075085) (xy 244.905371 -394.03157) (xy 244.979128 -393.994723)
			(xy 245.055977 -393.964858) (xy 245.13526 -393.942233) (xy 245.216297 -393.927041) (xy 245.298392 -393.919413)
			(xy 245.339616 -393.918948) (xy 245.380184 -393.919416) (xy 245.460981 -393.926807) (xy 245.54077 -393.941524)
			(xy 245.618888 -393.963447) (xy 245.694684 -393.992392) (xy 245.767529 -394.02812) (xy 245.836818 -394.070333)
			(xy 245.901975 -394.118681) (xy 245.962458 -394.172761) (xy 246.017765 -394.232125) (xy 246.067436 -394.296278)
			(xy 246.111059 -394.364689) (xy 246.130064 -394.400532) (xy 246.157157 -394.401367) (xy 246.21073 -394.409598)
			(xy 246.262601 -394.42532) (xy 246.31173 -394.448214) (xy 246.357129 -394.477824) (xy 246.397887 -394.513553)
			(xy 246.433186 -394.554684) (xy 246.462317 -394.600391) (xy 246.484695 -394.649758) (xy 246.499871 -394.701791)
			(xy 246.507539 -394.755447) (xy 246.508016 -394.782548) (xy 246.507582 -394.8085) (xy 249.114543 -394.8085)
			(xy 249.118574 -394.723896) (xy 249.130628 -394.640058) (xy 249.150596 -394.557746) (xy 249.178298 -394.477704)
			(xy 249.213483 -394.400658) (xy 249.255833 -394.327305) (xy 249.304963 -394.25831) (xy 249.360429 -394.194298)
			(xy 249.421729 -394.135847) (xy 249.488307 -394.083488) (xy 249.55956 -394.037695) (xy 249.634844 -393.998882)
			(xy 249.713476 -393.967401) (xy 249.794745 -393.943537) (xy 249.877914 -393.927506) (xy 249.96223 -393.919453)
			(xy 250.00458 -393.918948) (xy 250.045803 -393.919439) (xy 250.127896 -393.927072) (xy 250.20893 -393.942266)
			(xy 250.288212 -393.964889) (xy 250.365061 -393.994749) (xy 250.438819 -394.031588) (xy 250.508854 -394.075092)
			(xy 250.574564 -394.124887) (xy 250.60529 -394.152374) (xy 250.612522 -394.158461) (xy 250.630135 -394.165287)
			(xy 250.649025 -394.165287) (xy 250.666638 -394.158461) (xy 250.67387 -394.152374) (xy 250.704576 -394.124863)
			(xy 250.770283 -394.075057) (xy 250.840317 -394.031545) (xy 250.914078 -393.994701) (xy 250.990931 -393.96484)
			(xy 251.070218 -393.942219) (xy 251.151257 -393.927032) (xy 251.233355 -393.91941) (xy 251.27458 -393.918948)
			(xy 251.315219 -393.919386) (xy 251.396157 -393.926808) (xy 251.47608 -393.941582) (xy 251.554323 -393.963585)
			(xy 251.630232 -393.992634) (xy 251.703174 -394.028487) (xy 251.772542 -394.070844) (xy 251.837756 -394.119353)
			(xy 251.898274 -394.173608) (xy 251.95359 -394.233158) (xy 252.003243 -394.297505) (xy 252.046819 -394.366114)
			(xy 252.06579 -394.402056) (xy 252.086364 -394.401548) (xy 252.113582 -394.401996) (xy 252.167464 -394.409739)
			(xy 252.219695 -394.425073) (xy 252.269213 -394.447684) (xy 252.315007 -394.477114) (xy 252.356147 -394.512762)
			(xy 252.391793 -394.553902) (xy 252.421221 -394.599698) (xy 252.443832 -394.649216) (xy 252.459163 -394.701448)
			(xy 252.466905 -394.75533) (xy 252.467364 -394.782548) (xy 252.466916 -394.8085) (xy 255.049428 -394.8085)
			(xy 255.053459 -394.723891) (xy 255.065514 -394.640048) (xy 255.085484 -394.55773) (xy 255.11319 -394.477684)
			(xy 255.148379 -394.400634) (xy 255.190732 -394.327277) (xy 255.239868 -394.258279) (xy 255.295339 -394.194265)
			(xy 255.356645 -394.135813) (xy 255.423229 -394.083453) (xy 255.494489 -394.03766) (xy 255.56978 -393.998849)
			(xy 255.648419 -393.96737) (xy 255.729694 -393.943509) (xy 255.812869 -393.927482) (xy 255.897191 -393.919434)
			(xy 255.939544 -393.918948) (xy 255.980768 -393.919399) (xy 256.062862 -393.927038) (xy 256.143897 -393.942237)
			(xy 256.223179 -393.964866) (xy 256.300029 -393.994731) (xy 256.373786 -394.031576) (xy 256.44382 -394.075085)
			(xy 256.509529 -394.124885) (xy 256.540254 -394.152374) (xy 256.547486 -394.158461) (xy 256.565099 -394.165287)
			(xy 256.583989 -394.165287) (xy 256.601602 -394.158461) (xy 256.608834 -394.152374) (xy 256.639555 -394.12488)
			(xy 256.70526 -394.075073) (xy 256.775292 -394.031559) (xy 256.849049 -393.994713) (xy 256.925901 -393.96485)
			(xy 257.005185 -393.942227) (xy 257.086223 -393.927037) (xy 257.168319 -393.919412) (xy 257.209544 -393.918948)
			(xy 257.250365 -393.919407) (xy 257.331665 -393.926876) (xy 257.411938 -393.941765) (xy 257.490509 -393.963948)
			(xy 257.566715 -393.993239) (xy 257.639917 -394.029392) (xy 257.709496 -394.072102) (xy 257.774868 -394.121009)
			(xy 257.835483 -394.175702) (xy 257.890829 -394.235721) (xy 257.940442 -394.300559) (xy 257.983902 -394.369672)
			(xy 258.002786 -394.405866) (xy 258.01873 -394.403337) (xy 258.050905 -394.400664) (xy 258.067048 -394.400532)
			(xy 258.094337 -394.400926) (xy 258.148358 -394.408699) (xy 258.200723 -394.424081) (xy 258.250366 -394.446758)
			(xy 258.296278 -394.476268) (xy 258.337522 -394.512012) (xy 258.37326 -394.553261) (xy 258.402765 -394.599176)
			(xy 258.425436 -394.648822) (xy 258.440811 -394.701189) (xy 258.448577 -394.755211) (xy 258.448577 -394.8085)
			(xy 260.984428 -394.8085) (xy 260.988458 -394.723893) (xy 261.000513 -394.640052) (xy 261.020483 -394.557736)
			(xy 261.048186 -394.477692) (xy 261.083374 -394.400643) (xy 261.125725 -394.327288) (xy 261.174858 -394.258291)
			(xy 261.230327 -394.194277) (xy 261.29163 -394.135826) (xy 261.358212 -394.083466) (xy 261.429469 -394.037672)
			(xy 261.504756 -393.99886) (xy 261.583392 -393.967379) (xy 261.664664 -393.943516) (xy 261.747837 -393.927487)
			(xy 261.832156 -393.919436) (xy 261.874508 -393.918948) (xy 261.915732 -393.919422) (xy 261.997825 -393.927057)
			(xy 262.078859 -393.942253) (xy 262.158141 -393.964879) (xy 262.234991 -393.994741) (xy 262.308749 -394.031583)
			(xy 262.378783 -394.075089) (xy 262.444493 -394.124886) (xy 262.475218 -394.152374) (xy 262.48245 -394.158461)
			(xy 262.500063 -394.165287) (xy 262.518953 -394.165287) (xy 262.536566 -394.158461) (xy 262.543798 -394.152374)
			(xy 262.574534 -394.124897) (xy 262.640236 -394.075089) (xy 262.710266 -394.031574) (xy 262.784021 -393.994725)
			(xy 262.86087 -393.96486) (xy 262.940153 -393.942234) (xy 263.021189 -393.927042) (xy 263.103284 -393.919413)
			(xy 263.144508 -393.918948) (xy 263.185239 -393.919443) (xy 263.26636 -393.9269) (xy 263.346458 -393.941743)
			(xy 263.424865 -393.963847) (xy 263.500922 -393.993026) (xy 263.573993 -394.029037) (xy 263.643465 -394.071577)
			(xy 263.708758 -394.120291) (xy 263.769323 -394.174771) (xy 263.824654 -394.234559) (xy 263.874287 -394.299155)
			(xy 263.917806 -394.368019) (xy 263.936734 -394.404088) (xy 263.947933 -394.402872) (xy 263.970427 -394.401601)
			(xy 263.981692 -394.401548) (xy 264.008912 -394.401914) (xy 264.062799 -394.409661) (xy 264.115035 -394.424998)
			(xy 264.164556 -394.447612) (xy 264.210355 -394.477045) (xy 264.251499 -394.512695) (xy 264.287151 -394.553838)
			(xy 264.316584 -394.599637) (xy 264.3392 -394.649158) (xy 264.354537 -394.701393) (xy 264.362285 -394.75528)
			(xy 264.362285 -394.8085) (xy 266.919443 -394.8085) (xy 266.923474 -394.723896) (xy 266.935527 -394.640059)
			(xy 266.955496 -394.557747) (xy 266.983198 -394.477706) (xy 267.018382 -394.40066) (xy 267.060731 -394.327308)
			(xy 267.109861 -394.258313) (xy 267.165326 -394.194301) (xy 267.226625 -394.13585) (xy 267.293203 -394.083491)
			(xy 267.364456 -394.037698) (xy 267.439739 -393.998885) (xy 267.51837 -393.967403) (xy 267.599638 -393.943538)
			(xy 267.682807 -393.927507) (xy 267.767122 -393.919453) (xy 267.809472 -393.918948) (xy 267.850695 -393.919444)
			(xy 267.932787 -393.927077) (xy 268.013822 -393.942269) (xy 268.093103 -393.964892) (xy 268.169953 -393.994751)
			(xy 268.243711 -394.03159) (xy 268.313746 -394.075093) (xy 268.379456 -394.124888) (xy 268.410182 -394.152374)
			(xy 268.417414 -394.158461) (xy 268.435027 -394.165287) (xy 268.453917 -394.165287) (xy 268.47153 -394.158461)
			(xy 268.478762 -394.152374) (xy 268.509471 -394.124866) (xy 268.575178 -394.07506) (xy 268.645212 -394.031548)
			(xy 268.718971 -393.994703) (xy 268.795824 -393.964842) (xy 268.87511 -393.942221) (xy 268.95615 -393.927033)
			(xy 269.038247 -393.91941) (xy 269.079472 -393.918948) (xy 269.120039 -393.919454) (xy 269.200835 -393.92684)
			(xy 269.280624 -393.941554) (xy 269.35874 -393.963472) (xy 269.434536 -393.992414) (xy 269.507381 -394.028138)
			(xy 269.576671 -394.070348) (xy 269.641828 -394.118693) (xy 269.702312 -394.17277) (xy 269.757619 -394.232131)
			(xy 269.807291 -394.296282) (xy 269.850914 -394.36469) (xy 269.86992 -394.400532) (xy 269.897015 -394.401316)
			(xy 269.95059 -394.409555) (xy 270.002462 -394.425283) (xy 270.051591 -394.448184) (xy 270.096989 -394.477799)
			(xy 270.137747 -394.513533) (xy 270.173045 -394.554669) (xy 270.202175 -394.60038) (xy 270.224552 -394.64975)
			(xy 270.239727 -394.701787) (xy 270.247395 -394.755446) (xy 270.247872 -394.782548) (xy 270.24739 -394.8085)
			(xy 272.854328 -394.8085) (xy 272.858359 -394.723891) (xy 272.870414 -394.640048) (xy 272.890384 -394.557731)
			(xy 272.918089 -394.477686) (xy 272.953277 -394.400636) (xy 272.995631 -394.32728) (xy 273.044766 -394.258282)
			(xy 273.100237 -394.194267) (xy 273.161542 -394.135816) (xy 273.228125 -394.083456) (xy 273.299385 -394.037663)
			(xy 273.374675 -393.998851) (xy 273.453313 -393.967372) (xy 273.534587 -393.943511) (xy 273.617762 -393.927483)
			(xy 273.702084 -393.919434) (xy 273.744436 -393.918948) (xy 273.78566 -393.919404) (xy 273.867754 -393.927042)
			(xy 273.948789 -393.942241) (xy 274.028071 -393.964869) (xy 274.10492 -393.994734) (xy 274.178678 -394.031578)
			(xy 274.248712 -394.075086) (xy 274.314421 -394.124886) (xy 274.345146 -394.152374) (xy 274.352378 -394.158461)
			(xy 274.369991 -394.165287) (xy 274.388881 -394.165287) (xy 274.406494 -394.158461) (xy 274.413726 -394.152374)
			(xy 274.44445 -394.124884) (xy 274.510154 -394.075076) (xy 274.580186 -394.031562) (xy 274.653943 -393.994716)
			(xy 274.730794 -393.964852) (xy 274.810078 -393.942228) (xy 274.891116 -393.927038) (xy 274.973211 -393.919412)
			(xy 275.014436 -393.918948) (xy 275.055004 -393.9194) (xy 275.135802 -393.926792) (xy 275.215592 -393.941511)
			(xy 275.293709 -393.963435) (xy 275.369506 -393.992382) (xy 275.442351 -394.028112) (xy 275.51164 -394.070326)
			(xy 275.576797 -394.118675) (xy 275.63728 -394.172757) (xy 275.692586 -394.232122) (xy 275.742257 -394.296277)
			(xy 275.785879 -394.364688) (xy 275.804884 -394.400532) (xy 275.831978 -394.401349) (xy 275.885551 -394.409583)
			(xy 275.937423 -394.425306) (xy 275.986552 -394.448204) (xy 276.031951 -394.477815) (xy 276.072709 -394.513546)
			(xy 276.108007 -394.554678) (xy 276.137138 -394.600387) (xy 276.159515 -394.649755) (xy 276.174691 -394.70179)
			(xy 276.182359 -394.755447) (xy 276.182836 -394.782548) (xy 276.182385 -394.808456) (xy 278.916892 -394.808456)
			(xy 278.917356 -394.766262) (xy 278.925335 -394.682252) (xy 278.941234 -394.599376) (xy 278.964912 -394.518378)
			(xy 278.996156 -394.439987) (xy 279.034684 -394.364908) (xy 279.08015 -394.293815) (xy 279.132146 -394.227349)
			(xy 279.190203 -394.166106) (xy 279.2538 -394.110638) (xy 279.322365 -394.061443) (xy 279.395282 -394.018964)
			(xy 279.471894 -393.983582) (xy 279.551513 -393.955615) (xy 279.633423 -393.935316) (xy 279.675082 -393.9286)
			(xy 279.689459 -393.925944) (xy 279.715949 -393.913606) (xy 279.737852 -393.894262) (xy 279.753368 -393.869499)
			(xy 279.761223 -393.841352) (xy 279.760772 -393.812133) (xy 279.75687 -393.798044) (xy 279.744165 -393.755179)
			(xy 279.726399 -393.667554) (xy 279.717507 -393.578589) (xy 279.716992 -393.533884) (xy 279.717496 -393.491536)
			(xy 279.725547 -393.407222) (xy 279.741576 -393.324056) (xy 279.765437 -393.242789) (xy 279.796916 -393.164159)
			(xy 279.835727 -393.088878) (xy 279.881517 -393.017626) (xy 279.933873 -392.95105) (xy 279.992321 -392.889752)
			(xy 280.056331 -392.834287) (xy 280.125323 -392.785158) (xy 280.198673 -392.742809) (xy 280.275716 -392.707625)
			(xy 280.355755 -392.679923) (xy 280.438064 -392.659955) (xy 280.521899 -392.647902) (xy 280.6065 -392.643872)
			(xy 280.691101 -392.647902) (xy 280.774936 -392.659955) (xy 280.857245 -392.679923) (xy 280.937284 -392.707625)
			(xy 281.014327 -392.742809) (xy 281.087677 -392.785158) (xy 281.156669 -392.834287) (xy 281.220679 -392.889752)
			(xy 281.279127 -392.95105) (xy 281.331483 -393.017626) (xy 281.377273 -393.088878) (xy 281.416084 -393.164159)
			(xy 281.447563 -393.242789) (xy 281.471424 -393.324056) (xy 281.487453 -393.407222) (xy 281.495504 -393.491536)
			(xy 281.496008 -393.533884) (xy 281.495487 -393.576077) (xy 281.487514 -393.660085) (xy 281.47162 -393.74296)
			(xy 281.461756 -393.776708) (xy 289.471608 -393.776708) (xy 289.471608 -393.776454) (xy 289.47211 -393.744493)
			(xy 289.480121 -393.681075) (xy 289.496018 -393.619161) (xy 289.51955 -393.559728) (xy 289.550344 -393.503713)
			(xy 289.587917 -393.451998) (xy 289.631674 -393.405401) (xy 289.680927 -393.364656) (xy 289.734898 -393.330405)
			(xy 289.792737 -393.303188) (xy 289.85353 -393.283435) (xy 289.91632 -393.271457) (xy 289.980116 -393.267444)
			(xy 290.043912 -393.271457) (xy 290.106702 -393.283435) (xy 290.167495 -393.303188) (xy 290.225334 -393.330405)
			(xy 290.279305 -393.364656) (xy 290.328558 -393.405401) (xy 290.372315 -393.451998) (xy 290.409888 -393.503713)
			(xy 290.440682 -393.559728) (xy 290.464214 -393.619161) (xy 290.480111 -393.681075) (xy 290.488122 -393.744493)
			(xy 290.488624 -393.776454) (xy 290.488624 -393.7765) (xy 291.470768 -393.7765) (xy 291.474784 -393.712663)
			(xy 291.48677 -393.649832) (xy 291.506536 -393.589) (xy 291.533771 -393.531124) (xy 291.568045 -393.477118)
			(xy 291.608817 -393.427834) (xy 291.655445 -393.384049) (xy 291.707193 -393.346453) (xy 291.763245 -393.315639)
			(xy 291.822717 -393.292094) (xy 291.884671 -393.276188) (xy 291.94813 -393.268172) (xy 291.980112 -393.267692)
			(xy 292.010658 -393.268138) (xy 292.071311 -393.275449) (xy 292.13065 -393.289975) (xy 292.187822 -393.311508)
			(xy 292.242001 -393.339737) (xy 292.292406 -393.374254) (xy 292.338312 -393.414564) (xy 292.379057 -393.460084)
			(xy 292.396926 -393.484862) (xy 292.405296 -393.496027) (xy 292.426903 -393.51367) (xy 292.452477 -393.52481)
			(xy 292.480111 -393.528618) (xy 292.507745 -393.52481) (xy 292.533319 -393.51367) (xy 292.554926 -393.496027)
			(xy 292.563296 -393.484862) (xy 292.582389 -393.458454) (xy 292.626241 -393.410247) (xy 292.675892 -393.368039)
			(xy 292.730528 -393.332518) (xy 292.789254 -393.304269) (xy 292.851108 -393.283754) (xy 292.915076 -393.271309)
			(xy 292.98011 -393.267138) (xy 293.045144 -393.271309) (xy 293.109112 -393.283754) (xy 293.170966 -393.304269)
			(xy 293.229692 -393.332518) (xy 293.284328 -393.368039) (xy 293.333979 -393.410247) (xy 293.377831 -393.458454)
			(xy 293.396924 -393.484862) (xy 293.405294 -393.496027) (xy 293.426901 -393.51367) (xy 293.452475 -393.52481)
			(xy 293.480109 -393.528618) (xy 293.507743 -393.52481) (xy 293.533317 -393.51367) (xy 293.554924 -393.496027)
			(xy 293.563294 -393.484862) (xy 293.582387 -393.458454) (xy 293.626239 -393.410247) (xy 293.67589 -393.368039)
			(xy 293.730526 -393.332518) (xy 293.789252 -393.304269) (xy 293.851106 -393.283754) (xy 293.915074 -393.271309)
			(xy 293.980108 -393.267138) (xy 294.045142 -393.271309) (xy 294.10911 -393.283754) (xy 294.170964 -393.304269)
			(xy 294.22969 -393.332518) (xy 294.284326 -393.368039) (xy 294.333977 -393.410247) (xy 294.377829 -393.458454)
			(xy 294.396922 -393.484862) (xy 294.405292 -393.496027) (xy 294.426899 -393.51367) (xy 294.452473 -393.52481)
			(xy 294.480107 -393.528618) (xy 294.507741 -393.52481) (xy 294.533315 -393.51367) (xy 294.554922 -393.496027)
			(xy 294.563292 -393.484862) (xy 294.582385 -393.458454) (xy 294.626237 -393.410247) (xy 294.675888 -393.368039)
			(xy 294.730524 -393.332518) (xy 294.78925 -393.304269) (xy 294.851104 -393.283754) (xy 294.915072 -393.271309)
			(xy 294.980106 -393.267138) (xy 295.04514 -393.271309) (xy 295.109108 -393.283754) (xy 295.170962 -393.304269)
			(xy 295.229688 -393.332518) (xy 295.284324 -393.368039) (xy 295.333975 -393.410247) (xy 295.377827 -393.458454)
			(xy 295.39692 -393.484862) (xy 295.40529 -393.496027) (xy 295.426897 -393.51367) (xy 295.452471 -393.52481)
			(xy 295.480105 -393.528618) (xy 295.507739 -393.52481) (xy 295.533313 -393.51367) (xy 295.55492 -393.496027)
			(xy 295.56329 -393.484862) (xy 295.582383 -393.458454) (xy 295.626235 -393.410247) (xy 295.675886 -393.368039)
			(xy 295.730522 -393.332518) (xy 295.789248 -393.304269) (xy 295.851102 -393.283754) (xy 295.91507 -393.271309)
			(xy 295.980104 -393.267138) (xy 296.045138 -393.271309) (xy 296.109106 -393.283754) (xy 296.17096 -393.304269)
			(xy 296.229686 -393.332518) (xy 296.284322 -393.368039) (xy 296.333973 -393.410247) (xy 296.377825 -393.458454)
			(xy 296.396918 -393.484862) (xy 296.405288 -393.496027) (xy 296.426895 -393.51367) (xy 296.452469 -393.52481)
			(xy 296.480103 -393.528618) (xy 296.507737 -393.52481) (xy 296.533311 -393.51367) (xy 296.554918 -393.496027)
			(xy 296.563288 -393.484862) (xy 296.581151 -393.46008) (xy 296.621903 -393.414568) (xy 296.667813 -393.374265)
			(xy 296.71822 -393.339752) (xy 296.772399 -393.311525) (xy 296.829568 -393.289992) (xy 296.888906 -393.275462)
			(xy 296.949557 -393.268144) (xy 296.980102 -393.267692) (xy 297.012076 -393.268286) (xy 297.07552 -393.276301)
			(xy 297.137459 -393.292204) (xy 297.196916 -393.315745) (xy 297.252954 -393.346553) (xy 297.304689 -393.384141)
			(xy 297.351305 -393.427916) (xy 297.392067 -393.477189) (xy 297.426332 -393.531182) (xy 297.45356 -393.589044)
			(xy 297.473321 -393.649863) (xy 297.485304 -393.712678) (xy 297.489319 -393.7765) (xy 297.485304 -393.840322)
			(xy 297.473321 -393.903137) (xy 297.45356 -393.963956) (xy 297.426332 -394.021818) (xy 297.392067 -394.075811)
			(xy 297.351305 -394.125084) (xy 297.304689 -394.168859) (xy 297.252954 -394.206447) (xy 297.196916 -394.237255)
			(xy 297.137459 -394.260796) (xy 297.07552 -394.276699) (xy 297.012076 -394.284714) (xy 296.980102 -394.285216)
			(xy 296.949556 -394.284756) (xy 296.888904 -394.277447) (xy 296.829565 -394.262922) (xy 296.772394 -394.241392)
			(xy 296.718215 -394.213165) (xy 296.667809 -394.178649) (xy 296.621903 -394.138341) (xy 296.581158 -394.092823)
			(xy 296.563288 -394.068046) (xy 296.554946 -394.056837) (xy 296.53336 -394.03911) (xy 296.507771 -394.027912)
			(xy 296.480103 -394.024083) (xy 296.452435 -394.027912) (xy 296.426846 -394.03911) (xy 296.40526 -394.056837)
			(xy 296.396918 -394.068046) (xy 296.377825 -394.094454) (xy 296.333973 -394.142661) (xy 296.284322 -394.184869)
			(xy 296.229686 -394.22039) (xy 296.17096 -394.248639) (xy 296.109106 -394.269154) (xy 296.045138 -394.281599)
			(xy 295.980104 -394.28577) (xy 295.91507 -394.281599) (xy 295.851102 -394.269154) (xy 295.789248 -394.248639)
			(xy 295.730522 -394.22039) (xy 295.675886 -394.184869) (xy 295.626235 -394.142661) (xy 295.582383 -394.094454)
			(xy 295.56329 -394.068046) (xy 295.554948 -394.056837) (xy 295.533362 -394.03911) (xy 295.507773 -394.027912)
			(xy 295.480105 -394.024083) (xy 295.452437 -394.027912) (xy 295.426848 -394.03911) (xy 295.405262 -394.056837)
			(xy 295.39692 -394.068046) (xy 295.377827 -394.094454) (xy 295.333975 -394.142661) (xy 295.284324 -394.184869)
			(xy 295.229688 -394.22039) (xy 295.170962 -394.248639) (xy 295.109108 -394.269154) (xy 295.04514 -394.281599)
			(xy 294.980106 -394.28577) (xy 294.915072 -394.281599) (xy 294.851104 -394.269154) (xy 294.78925 -394.248639)
			(xy 294.730524 -394.22039) (xy 294.675888 -394.184869) (xy 294.626237 -394.142661) (xy 294.582385 -394.094454)
			(xy 294.563292 -394.068046) (xy 294.55495 -394.056837) (xy 294.533364 -394.03911) (xy 294.507775 -394.027912)
			(xy 294.480107 -394.024083) (xy 294.452439 -394.027912) (xy 294.42685 -394.03911) (xy 294.405264 -394.056837)
			(xy 294.396922 -394.068046) (xy 294.377829 -394.094454) (xy 294.333977 -394.142661) (xy 294.284326 -394.184869)
			(xy 294.22969 -394.22039) (xy 294.170964 -394.248639) (xy 294.10911 -394.269154) (xy 294.045142 -394.281599)
			(xy 293.980108 -394.28577) (xy 293.915074 -394.281599) (xy 293.851106 -394.269154) (xy 293.789252 -394.248639)
			(xy 293.730526 -394.22039) (xy 293.67589 -394.184869) (xy 293.626239 -394.142661) (xy 293.582387 -394.094454)
			(xy 293.563294 -394.068046) (xy 293.554952 -394.056837) (xy 293.533366 -394.03911) (xy 293.507777 -394.027912)
			(xy 293.480109 -394.024083) (xy 293.452441 -394.027912) (xy 293.426852 -394.03911) (xy 293.405266 -394.056837)
			(xy 293.396924 -394.068046) (xy 293.377831 -394.094454) (xy 293.333979 -394.142661) (xy 293.284328 -394.184869)
			(xy 293.229692 -394.22039) (xy 293.170966 -394.248639) (xy 293.109112 -394.269154) (xy 293.045144 -394.281599)
			(xy 292.98011 -394.28577) (xy 292.915076 -394.281599) (xy 292.851108 -394.269154) (xy 292.789254 -394.248639)
			(xy 292.730528 -394.22039) (xy 292.675892 -394.184869) (xy 292.626241 -394.142661) (xy 292.582389 -394.094454)
			(xy 292.563296 -394.068046) (xy 292.554954 -394.056837) (xy 292.533368 -394.03911) (xy 292.507779 -394.027912)
			(xy 292.480111 -394.024083) (xy 292.452443 -394.027912) (xy 292.426854 -394.03911) (xy 292.405268 -394.056837)
			(xy 292.396926 -394.068046) (xy 292.379057 -394.092823) (xy 292.338306 -394.138335) (xy 292.292396 -394.178638)
			(xy 292.24199 -394.213151) (xy 292.187812 -394.241378) (xy 292.130644 -394.262913) (xy 292.071307 -394.277444)
			(xy 292.010657 -394.284763) (xy 291.980112 -394.285216) (xy 291.94813 -394.284828) (xy 291.884671 -394.276812)
			(xy 291.822717 -394.260906) (xy 291.763245 -394.237361) (xy 291.707193 -394.206547) (xy 291.655445 -394.168951)
			(xy 291.608817 -394.125166) (xy 291.568045 -394.075882) (xy 291.533771 -394.021876) (xy 291.506536 -393.964)
			(xy 291.48677 -393.903168) (xy 291.474784 -393.840337) (xy 291.470768 -393.7765) (xy 290.488624 -393.7765)
			(xy 290.488624 -393.776962) (xy 290.488202 -393.806564) (xy 290.481324 -393.865367) (xy 290.467658 -393.922971)
			(xy 290.447389 -393.978597) (xy 290.420792 -394.03149) (xy 290.388226 -394.080932) (xy 290.369498 -394.10386)
			(xy 290.389588 -394.127178) (xy 290.424612 -394.17779) (xy 290.453267 -394.232263) (xy 290.475133 -394.289797)
			(xy 290.48989 -394.349552) (xy 290.497321 -394.410651) (xy 290.497768 -394.441426) (xy 290.497768 -394.44168)
			(xy 290.497266 -394.473641) (xy 290.489255 -394.537059) (xy 290.473358 -394.598973) (xy 290.449826 -394.658406)
			(xy 290.419032 -394.714421) (xy 290.381459 -394.766136) (xy 290.337702 -394.812733) (xy 290.288449 -394.853478)
			(xy 290.234478 -394.887729) (xy 290.176639 -394.914946) (xy 290.115846 -394.934699) (xy 290.053056 -394.946677)
			(xy 289.98926 -394.950691) (xy 289.925464 -394.946677) (xy 289.862674 -394.934699) (xy 289.801881 -394.914946)
			(xy 289.744042 -394.887729) (xy 289.690071 -394.853478) (xy 289.640818 -394.812733) (xy 289.597061 -394.766136)
			(xy 289.559488 -394.714421) (xy 289.528694 -394.658406) (xy 289.505162 -394.598973) (xy 289.489265 -394.537059)
			(xy 289.481254 -394.473641) (xy 289.480752 -394.44168) (xy 289.480752 -394.441172) (xy 289.481141 -394.411569)
			(xy 289.488026 -394.352765) (xy 289.501699 -394.29516) (xy 289.521974 -394.239535) (xy 289.548577 -394.186643)
			(xy 289.581148 -394.137202) (xy 289.599878 -394.114274) (xy 289.579769 -394.090972) (xy 289.544745 -394.040357)
			(xy 289.516091 -393.985882) (xy 289.494228 -393.928344) (xy 289.479476 -393.868586) (xy 289.472051 -393.807484)
			(xy 289.471608 -393.776708) (xy 281.461756 -393.776708) (xy 281.447947 -393.823957) (xy 281.416708 -393.902348)
			(xy 281.378185 -393.977427) (xy 281.332723 -394.04852) (xy 281.280732 -394.114986) (xy 281.222678 -394.176229)
			(xy 281.159084 -394.231698) (xy 281.090523 -394.280894) (xy 281.017609 -394.323374) (xy 280.941 -394.358757)
			(xy 280.861383 -394.386724) (xy 280.779476 -394.407024) (xy 280.737818 -394.41374) (xy 280.72343 -394.416347)
			(xy 280.696933 -394.428691) (xy 280.675026 -394.448046) (xy 280.659511 -394.472819) (xy 280.651661 -394.500977)
			(xy 280.652122 -394.530204) (xy 280.65603 -394.544296) (xy 280.668744 -394.587158) (xy 280.686507 -394.674785)
			(xy 280.695395 -394.763751) (xy 280.695908 -394.808456) (xy 280.695404 -394.850804) (xy 280.687353 -394.935118)
			(xy 280.671324 -395.018284) (xy 280.647463 -395.099551) (xy 280.615984 -395.178181) (xy 280.577173 -395.253462)
			(xy 280.531383 -395.324714) (xy 280.479027 -395.39129) (xy 280.420579 -395.452588) (xy 280.356569 -395.508053)
			(xy 280.287577 -395.557182) (xy 280.214227 -395.599531) (xy 280.137184 -395.634715) (xy 280.057145 -395.662417)
			(xy 279.974836 -395.682385) (xy 279.891001 -395.694438) (xy 279.8064 -395.698469) (xy 279.721799 -395.694438)
			(xy 279.637964 -395.682385) (xy 279.555655 -395.662417) (xy 279.475616 -395.634715) (xy 279.398573 -395.599531)
			(xy 279.325223 -395.557182) (xy 279.256231 -395.508053) (xy 279.192221 -395.452588) (xy 279.133773 -395.39129)
			(xy 279.081417 -395.324714) (xy 279.035627 -395.253462) (xy 278.996816 -395.178181) (xy 278.965337 -395.099551)
			(xy 278.941476 -395.018284) (xy 278.925447 -394.935118) (xy 278.917396 -394.850804) (xy 278.916892 -394.808456)
			(xy 276.182385 -394.808456) (xy 276.182339 -394.81111) (xy 276.173854 -394.867601) (xy 276.157051 -394.922198)
			(xy 276.132304 -394.973684) (xy 276.100165 -395.02091) (xy 276.061351 -395.062822) (xy 276.016728 -395.098487)
			(xy 275.967291 -395.127109) (xy 275.914142 -395.148048) (xy 275.858468 -395.160839) (xy 275.83003 -395.163548)
			(xy 275.812369 -395.202766) (xy 275.770577 -395.277947) (xy 275.721724 -395.348744) (xy 275.666266 -395.414494)
			(xy 275.60472 -395.474584) (xy 275.537661 -395.528453) (xy 275.465716 -395.575598) (xy 275.389556 -395.615578)
			(xy 275.309893 -395.648021) (xy 275.22747 -395.672622) (xy 275.143058 -395.689153) (xy 275.057444 -395.697459)
			(xy 275.014436 -395.697964) (xy 274.973213 -395.69746) (xy 274.891121 -395.689828) (xy 274.810087 -395.674636)
			(xy 274.730806 -395.652015) (xy 274.653956 -395.622157) (xy 274.580198 -395.585319) (xy 274.510163 -395.541817)
			(xy 274.444452 -395.492024) (xy 274.413726 -395.464538) (xy 274.406494 -395.458451) (xy 274.388881 -395.451625)
			(xy 274.369991 -395.451625) (xy 274.352378 -395.458451) (xy 274.345146 -395.464538) (xy 274.314435 -395.492044)
			(xy 274.248729 -395.54185) (xy 274.178695 -395.585362) (xy 274.104936 -395.622207) (xy 274.028083 -395.652068)
			(xy 273.948797 -395.67469) (xy 273.867758 -395.689878) (xy 273.785661 -395.697501) (xy 273.744436 -395.697964)
			(xy 273.702084 -395.697566) (xy 273.617762 -395.689517) (xy 273.534587 -395.673489) (xy 273.453313 -395.649628)
			(xy 273.374675 -395.618149) (xy 273.299385 -395.579337) (xy 273.228125 -395.533544) (xy 273.161542 -395.481184)
			(xy 273.100237 -395.422733) (xy 273.044766 -395.358718) (xy 272.995631 -395.28972) (xy 272.953277 -395.216364)
			(xy 272.918089 -395.139314) (xy 272.890384 -395.059269) (xy 272.870414 -394.976952) (xy 272.858359 -394.893109)
			(xy 272.854328 -394.8085) (xy 270.24739 -394.8085) (xy 270.247342 -394.811109) (xy 270.238858 -394.867596)
			(xy 270.222057 -394.922191) (xy 270.197312 -394.973674) (xy 270.165177 -395.020899) (xy 270.126367 -395.062811)
			(xy 270.081748 -395.098476) (xy 270.032316 -395.127099) (xy 269.979172 -395.148042) (xy 269.923503 -395.160836)
			(xy 269.895066 -395.163548) (xy 269.877376 -395.202752) (xy 269.835586 -395.277933) (xy 269.786736 -395.348729)
			(xy 269.73128 -395.414479) (xy 269.669737 -395.474569) (xy 269.602681 -395.528439) (xy 269.530739 -395.575585)
			(xy 269.454582 -395.615566) (xy 269.374921 -395.648011) (xy 269.292501 -395.672615) (xy 269.208091 -395.689148)
			(xy 269.122479 -395.697457) (xy 269.079472 -395.697964) (xy 269.038248 -395.6975) (xy 268.956155 -395.689862)
			(xy 268.87512 -395.674665) (xy 268.795838 -395.652037) (xy 268.718989 -395.622174) (xy 268.645231 -395.585331)
			(xy 268.575197 -395.541824) (xy 268.509487 -395.492026) (xy 268.478762 -395.464538) (xy 268.47153 -395.458451)
			(xy 268.453917 -395.451625) (xy 268.435027 -395.451625) (xy 268.417414 -395.458451) (xy 268.410182 -395.464538)
			(xy 268.379456 -395.492026) (xy 268.313752 -395.541834) (xy 268.243721 -395.585348) (xy 268.169964 -395.622194)
			(xy 268.093113 -395.652058) (xy 268.013829 -395.674682) (xy 267.932792 -395.689873) (xy 267.850696 -395.6975)
			(xy 267.809472 -395.697964) (xy 267.767122 -395.697547) (xy 267.682807 -395.689493) (xy 267.599638 -395.673462)
			(xy 267.51837 -395.649597) (xy 267.439739 -395.618115) (xy 267.364456 -395.579302) (xy 267.293203 -395.533509)
			(xy 267.226625 -395.48115) (xy 267.165326 -395.422699) (xy 267.109861 -395.358687) (xy 267.060731 -395.289692)
			(xy 267.018382 -395.21634) (xy 266.983198 -395.139294) (xy 266.955496 -395.059253) (xy 266.935527 -394.976941)
			(xy 266.923474 -394.893104) (xy 266.919443 -394.8085) (xy 264.362285 -394.8085) (xy 264.362285 -394.80972)
			(xy 264.354537 -394.863607) (xy 264.3392 -394.915842) (xy 264.316584 -394.965363) (xy 264.287151 -395.011162)
			(xy 264.251499 -395.052305) (xy 264.210355 -395.087955) (xy 264.164556 -395.117388) (xy 264.115035 -395.140002)
			(xy 264.062799 -395.155339) (xy 264.008912 -395.163086) (xy 263.981692 -395.163548) (xy 263.960356 -395.16304)
			(xy 263.942674 -395.202274) (xy 263.9009 -395.277517) (xy 263.852055 -395.348375) (xy 263.796597 -395.414185)
			(xy 263.735042 -395.474332) (xy 263.667968 -395.528254) (xy 263.596 -395.575447) (xy 263.519811 -395.61547)
			(xy 263.440113 -395.647949) (xy 263.357652 -395.67258) (xy 263.273197 -395.689134) (xy 263.187539 -395.697455)
			(xy 263.144508 -395.697964) (xy 263.103285 -395.697477) (xy 263.021192 -395.689843) (xy 262.940158 -395.674649)
			(xy 262.860876 -395.652025) (xy 262.784027 -395.622164) (xy 262.710269 -395.585324) (xy 262.640234 -395.54182)
			(xy 262.574524 -395.492025) (xy 262.543798 -395.464538) (xy 262.536566 -395.458451) (xy 262.518953 -395.451625)
			(xy 262.500063 -395.451625) (xy 262.48245 -395.458451) (xy 262.475218 -395.464538) (xy 262.444477 -395.492009)
			(xy 262.378775 -395.541818) (xy 262.308747 -395.585333) (xy 262.234992 -395.622182) (xy 262.158144 -395.652048)
			(xy 262.078861 -395.674675) (xy 261.997826 -395.689868) (xy 261.915732 -395.697498) (xy 261.874508 -395.697964)
			(xy 261.832156 -395.697564) (xy 261.747837 -395.689513) (xy 261.664664 -395.673484) (xy 261.583392 -395.649621)
			(xy 261.504756 -395.61814) (xy 261.429469 -395.579328) (xy 261.358212 -395.533534) (xy 261.29163 -395.481174)
			(xy 261.230327 -395.422723) (xy 261.174858 -395.358709) (xy 261.125725 -395.289712) (xy 261.083374 -395.216357)
			(xy 261.048186 -395.139308) (xy 261.020483 -395.059264) (xy 261.000513 -394.976948) (xy 260.988458 -394.893107)
			(xy 260.984428 -394.8085) (xy 258.448577 -394.8085) (xy 258.448577 -394.809789) (xy 258.440811 -394.863811)
			(xy 258.425436 -394.916178) (xy 258.402765 -394.965824) (xy 258.37326 -395.011739) (xy 258.337522 -395.052988)
			(xy 258.296278 -395.088732) (xy 258.250366 -395.118242) (xy 258.200723 -395.140919) (xy 258.148358 -395.156301)
			(xy 258.094337 -395.164074) (xy 258.067048 -395.164564) (xy 258.056676 -395.164479) (xy 258.035964 -395.163337)
			(xy 258.025646 -395.162278) (xy 258.008 -395.201564) (xy 257.966267 -395.276906) (xy 257.917448 -395.347861)
			(xy 257.861999 -395.413765) (xy 257.80044 -395.474001) (xy 257.733346 -395.528004) (xy 257.661347 -395.575269)
			(xy 257.585116 -395.615354) (xy 257.505368 -395.647883) (xy 257.422848 -395.672551) (xy 257.338331 -395.689127)
			(xy 257.252608 -395.697456) (xy 257.209544 -395.697964) (xy 257.168321 -395.697455) (xy 257.08623 -395.689824)
			(xy 257.005196 -395.674633) (xy 256.925914 -395.652012) (xy 256.849065 -395.622155) (xy 256.775306 -395.585317)
			(xy 256.705271 -395.541816) (xy 256.63956 -395.492023) (xy 256.608834 -395.464538) (xy 256.601602 -395.458451)
			(xy 256.583989 -395.451625) (xy 256.565099 -395.451625) (xy 256.547486 -395.458451) (xy 256.540254 -395.464538)
			(xy 256.50954 -395.49204) (xy 256.443834 -395.541846) (xy 256.373801 -395.585359) (xy 256.300042 -395.622204)
			(xy 256.22319 -395.652066) (xy 256.143904 -395.674688) (xy 256.062865 -395.689877) (xy 255.980769 -395.697501)
			(xy 255.939544 -395.697964) (xy 255.897191 -395.697566) (xy 255.812869 -395.689518) (xy 255.729694 -395.673491)
			(xy 255.648419 -395.64963) (xy 255.56978 -395.618151) (xy 255.494489 -395.57934) (xy 255.423229 -395.533547)
			(xy 255.356645 -395.481187) (xy 255.295339 -395.422735) (xy 255.239868 -395.358721) (xy 255.190732 -395.289723)
			(xy 255.148379 -395.216366) (xy 255.11319 -395.139316) (xy 255.085484 -395.05927) (xy 255.065514 -394.976952)
			(xy 255.053459 -394.893109) (xy 255.049428 -394.8085) (xy 252.466916 -394.8085) (xy 252.466897 -394.809592)
			(xy 252.459254 -394.863136) (xy 252.444116 -394.915061) (xy 252.421785 -394.964324) (xy 252.392711 -395.009932)
			(xy 252.357479 -395.05097) (xy 252.316797 -395.086613) (xy 252.271483 -395.116143) (xy 252.222447 -395.138967)
			(xy 252.170677 -395.154627) (xy 252.117212 -395.162807) (xy 252.090174 -395.163548) (xy 252.072477 -395.202749)
			(xy 252.030688 -395.27793) (xy 251.981838 -395.348725) (xy 251.926383 -395.414475) (xy 251.864841 -395.474566)
			(xy 251.797785 -395.528436) (xy 251.725844 -395.575582) (xy 251.649687 -395.615564) (xy 251.570027 -395.648009)
			(xy 251.487608 -395.672613) (xy 251.403198 -395.689147) (xy 251.317587 -395.697457) (xy 251.27458 -395.697964)
			(xy 251.233356 -395.697495) (xy 251.151263 -395.689858) (xy 251.070228 -395.674661) (xy 250.990947 -395.652035)
			(xy 250.914097 -395.622172) (xy 250.840339 -395.58533) (xy 250.770305 -395.541823) (xy 250.704595 -395.492026)
			(xy 250.67387 -395.464538) (xy 250.666638 -395.458451) (xy 250.649025 -395.451625) (xy 250.630135 -395.451625)
			(xy 250.612522 -395.458451) (xy 250.60529 -395.464538) (xy 250.574561 -395.492023) (xy 250.508857 -395.54183)
			(xy 250.438827 -395.585344) (xy 250.36507 -395.622192) (xy 250.28822 -395.652056) (xy 250.208936 -395.67468)
			(xy 250.127899 -395.689872) (xy 250.045804 -395.697499) (xy 250.00458 -395.697964) (xy 249.96223 -395.697547)
			(xy 249.877914 -395.689494) (xy 249.794745 -395.673463) (xy 249.713476 -395.649599) (xy 249.634844 -395.618118)
			(xy 249.55956 -395.579305) (xy 249.488307 -395.533512) (xy 249.421729 -395.481153) (xy 249.360429 -395.422702)
			(xy 249.304963 -395.35869) (xy 249.255833 -395.289695) (xy 249.213483 -395.216342) (xy 249.178298 -395.139296)
			(xy 249.150596 -395.059254) (xy 249.130628 -394.976942) (xy 249.118574 -394.893104) (xy 249.114543 -394.8085)
			(xy 246.507582 -394.8085) (xy 246.507538 -394.811111) (xy 246.499052 -394.867604) (xy 246.482248 -394.922202)
			(xy 246.457499 -394.973689) (xy 246.425358 -395.020916) (xy 246.386542 -395.062829) (xy 246.341916 -395.098493)
			(xy 246.292476 -395.127114) (xy 246.239326 -395.148052) (xy 246.183649 -395.16084) (xy 246.15521 -395.163548)
			(xy 246.137565 -395.202774) (xy 246.095772 -395.277955) (xy 246.046918 -395.348752) (xy 245.991458 -395.414502)
			(xy 245.929911 -395.474592) (xy 245.86285 -395.528461) (xy 245.790904 -395.575605) (xy 245.714742 -395.615585)
			(xy 245.635078 -395.648026) (xy 245.552653 -395.672626) (xy 245.46824 -395.689156) (xy 245.382624 -395.69746)
			(xy 245.339616 -395.697964) (xy 245.298393 -395.697472) (xy 245.216301 -395.689839) (xy 245.135266 -395.674645)
			(xy 245.055985 -395.652022) (xy 244.979135 -395.622162) (xy 244.905377 -395.585323) (xy 244.835342 -395.541819)
			(xy 244.769632 -395.492024) (xy 244.738906 -395.464538) (xy 244.731674 -395.458451) (xy 244.714061 -395.451625)
			(xy 244.695171 -395.451625) (xy 244.677558 -395.458451) (xy 244.670326 -395.464538) (xy 244.639624 -395.492053)
			(xy 244.573916 -395.541859) (xy 244.503881 -395.58537) (xy 244.43012 -395.622214) (xy 244.353266 -395.652074)
			(xy 244.273979 -395.674694) (xy 244.192939 -395.68988) (xy 244.110841 -395.697502) (xy 244.069616 -395.697964)
			(xy 244.027264 -395.697565) (xy 243.942944 -395.689514) (xy 243.859771 -395.673485) (xy 243.778498 -395.649623)
			(xy 243.699861 -395.618143) (xy 243.624573 -395.57933) (xy 243.553315 -395.533537) (xy 243.486733 -395.481177)
			(xy 243.42543 -395.422726) (xy 243.36996 -395.358711) (xy 243.320827 -395.289714) (xy 243.278475 -395.216359)
			(xy 243.243287 -395.13931) (xy 243.215583 -395.059265) (xy 243.195613 -394.976949) (xy 243.183558 -394.893108)
			(xy 243.179528 -394.8085) (xy 2.509012 -394.8085) (xy 2.509012 -396.842996) (xy 18.90268 -396.842996)
			(xy 18.90268 -395.979396) (xy 18.903166 -395.952145) (xy 18.910922 -395.898197) (xy 18.926277 -395.845902)
			(xy 18.948919 -395.796325) (xy 18.978385 -395.750475) (xy 19.014076 -395.709284) (xy 19.055267 -395.673593)
			(xy 19.101117 -395.644127) (xy 19.150694 -395.621485) (xy 19.202989 -395.60613) (xy 19.256937 -395.598374)
			(xy 19.311439 -395.598374) (xy 19.365387 -395.60613) (xy 19.417682 -395.621485) (xy 19.467259 -395.644127)
			(xy 19.513109 -395.673593) (xy 19.5543 -395.709284) (xy 19.589991 -395.750475) (xy 19.601933 -395.769057)
			(xy 288.471858 -395.769057) (xy 288.471858 -395.705103) (xy 288.479873 -395.641653) (xy 288.495778 -395.579708)
			(xy 288.519321 -395.520246) (xy 288.550131 -395.464202) (xy 288.587723 -395.412462) (xy 288.631502 -395.365842)
			(xy 288.68078 -395.325076) (xy 288.734778 -395.290808) (xy 288.792645 -395.263577) (xy 288.853469 -395.243814)
			(xy 288.91629 -395.231831) (xy 288.980118 -395.227815) (xy 289.043946 -395.231831) (xy 289.106767 -395.243814)
			(xy 289.167591 -395.263577) (xy 289.225458 -395.290808) (xy 289.279456 -395.325076) (xy 289.328734 -395.365842)
			(xy 289.372513 -395.412462) (xy 289.410105 -395.464202) (xy 289.440915 -395.520246) (xy 289.464458 -395.579708)
			(xy 289.480363 -395.641653) (xy 289.488378 -395.705103) (xy 289.48888 -395.73708) (xy 289.488378 -395.769057)
			(xy 289.480363 -395.832507) (xy 289.464458 -395.894452) (xy 289.440915 -395.953914) (xy 289.410105 -396.009958)
			(xy 289.372513 -396.061698) (xy 289.328734 -396.108318) (xy 289.279456 -396.149084) (xy 289.225458 -396.183352)
			(xy 289.167591 -396.210583) (xy 289.106767 -396.230346) (xy 289.043946 -396.242329) (xy 288.980118 -396.246345)
			(xy 288.91629 -396.242329) (xy 288.853469 -396.230346) (xy 288.792645 -396.210583) (xy 288.734778 -396.183352)
			(xy 288.68078 -396.149084) (xy 288.631502 -396.108318) (xy 288.587723 -396.061698) (xy 288.550131 -396.009958)
			(xy 288.519321 -395.953914) (xy 288.495778 -395.894452) (xy 288.479873 -395.832507) (xy 288.471858 -395.769057)
			(xy 19.601933 -395.769057) (xy 19.619457 -395.796325) (xy 19.642099 -395.845902) (xy 19.657454 -395.898197)
			(xy 19.66521 -395.952145) (xy 19.665696 -395.979396) (xy 19.665696 -396.842996) (xy 19.66521 -396.870247)
			(xy 19.657454 -396.924195) (xy 19.642099 -396.97649) (xy 19.619457 -397.026067) (xy 19.589991 -397.071917)
			(xy 19.5543 -397.113108) (xy 19.513109 -397.148799) (xy 19.467259 -397.178265) (xy 19.417682 -397.200907)
			(xy 19.365387 -397.216262) (xy 19.311439 -397.224018) (xy 19.256937 -397.224018) (xy 19.202989 -397.216262)
			(xy 19.150694 -397.200907) (xy 19.101117 -397.178265) (xy 19.055267 -397.148799) (xy 19.014076 -397.113108)
			(xy 18.978385 -397.071917) (xy 18.948919 -397.026067) (xy 18.926277 -396.97649) (xy 18.910922 -396.924195)
			(xy 18.903166 -396.870247) (xy 18.90268 -396.842996) (xy 2.509012 -396.842996) (xy 2.509012 -397.606012)
			(xy 24.954992 -397.606012) (xy 24.954992 -396.742412) (xy 24.955478 -396.715161) (xy 24.963234 -396.661213)
			(xy 24.978589 -396.608918) (xy 25.001231 -396.559341) (xy 25.030697 -396.513491) (xy 25.066388 -396.4723)
			(xy 25.107579 -396.436609) (xy 25.153429 -396.407143) (xy 25.203006 -396.384501) (xy 25.255301 -396.369146)
			(xy 25.309249 -396.36139) (xy 25.363751 -396.36139) (xy 25.417699 -396.369146) (xy 25.469994 -396.384501)
			(xy 25.519571 -396.407143) (xy 25.565421 -396.436609) (xy 25.606612 -396.4723) (xy 25.642303 -396.513491)
			(xy 25.671769 -396.559341) (xy 25.694411 -396.608918) (xy 25.709766 -396.661213) (xy 25.717522 -396.715161)
			(xy 25.718008 -396.742412) (xy 25.718008 -397.606012) (xy 25.717522 -397.633263) (xy 25.709766 -397.687211)
			(xy 25.694411 -397.739506) (xy 25.671769 -397.789083) (xy 25.642303 -397.834933) (xy 25.606612 -397.876124)
			(xy 25.565421 -397.911815) (xy 25.519571 -397.941281) (xy 25.469994 -397.963923) (xy 25.417699 -397.979278)
			(xy 25.363751 -397.987034) (xy 25.309249 -397.987034) (xy 25.255301 -397.979278) (xy 25.203006 -397.963923)
			(xy 25.153429 -397.941281) (xy 25.107579 -397.911815) (xy 25.066388 -397.876124) (xy 25.030697 -397.834933)
			(xy 25.001231 -397.789083) (xy 24.978589 -397.739506) (xy 24.963234 -397.687211) (xy 24.955478 -397.633263)
			(xy 24.954992 -397.606012) (xy 2.509012 -397.606012) (xy 2.509012 -398.68657) (xy 36.781952 -398.68657)
			(xy 36.781952 -398.63203) (xy 36.789714 -398.578046) (xy 36.805081 -398.525717) (xy 36.827739 -398.476107)
			(xy 36.857227 -398.430227) (xy 36.892945 -398.389011) (xy 36.934165 -398.353298) (xy 36.980049 -398.323816)
			(xy 37.029662 -398.301164) (xy 37.081993 -398.285804) (xy 37.135978 -398.278048) (xy 37.163248 -398.277588)
			(xy 38.026848 -398.277588) (xy 38.054119 -398.277978) (xy 38.108104 -398.285746) (xy 38.160435 -398.301118)
			(xy 38.210045 -398.323779) (xy 38.255926 -398.353271) (xy 38.297144 -398.38899) (xy 38.332858 -398.430212)
			(xy 38.362344 -398.476097) (xy 38.384999 -398.52571) (xy 38.400364 -398.578043) (xy 38.408126 -398.632029)
			(xy 38.408126 -398.686571) (xy 38.400364 -398.740557) (xy 38.384999 -398.79289) (xy 38.38214 -398.799152)
			(xy 42.10455 -398.799152) (xy 42.10455 -398.744648) (xy 42.112306 -398.6907) (xy 42.12766 -398.638404)
			(xy 42.150301 -398.588826) (xy 42.179766 -398.542974) (xy 42.215456 -398.501781) (xy 42.256645 -398.466087)
			(xy 42.302494 -398.436618) (xy 42.35207 -398.413973) (xy 42.404365 -398.398614) (xy 42.458312 -398.390852)
			(xy 42.485564 -398.390364) (xy 43.349164 -398.390364) (xy 43.376417 -398.390881) (xy 43.430367 -398.398633)
			(xy 43.482666 -398.413985) (xy 43.532247 -398.436624) (xy 43.578101 -398.466088) (xy 43.619295 -398.50178)
			(xy 43.65499 -398.54297) (xy 43.684459 -398.588822) (xy 43.707103 -398.638401) (xy 43.722459 -398.690697)
			(xy 43.730217 -398.744648) (xy 43.730217 -398.799152) (xy 43.722459 -398.853103) (xy 43.707103 -398.9054)
			(xy 43.684459 -398.954978) (xy 43.65499 -399.00083) (xy 43.619295 -399.04202) (xy 43.578101 -399.077712)
			(xy 43.532247 -399.107176) (xy 43.482666 -399.129815) (xy 43.430367 -399.145167) (xy 43.376417 -399.152919)
			(xy 43.349164 -399.15338) (xy 42.485564 -399.15338) (xy 42.458312 -399.152948) (xy 42.404365 -399.145186)
			(xy 42.35207 -399.129827) (xy 42.302494 -399.107182) (xy 42.256645 -399.077713) (xy 42.215456 -399.042019)
			(xy 42.179766 -399.000826) (xy 42.150301 -398.954974) (xy 42.12766 -398.905396) (xy 42.112306 -398.8531)
			(xy 42.10455 -398.799152) (xy 38.38214 -398.799152) (xy 38.362344 -398.842503) (xy 38.332858 -398.888388)
			(xy 38.297144 -398.92961) (xy 38.255926 -398.965329) (xy 38.210045 -398.994821) (xy 38.160435 -399.017482)
			(xy 38.108104 -399.032854) (xy 38.054119 -399.040622) (xy 38.026848 -399.041112) (xy 37.163248 -399.041112)
			(xy 37.135978 -399.040552) (xy 37.081993 -399.032796) (xy 37.029662 -399.017436) (xy 36.980049 -398.994784)
			(xy 36.934165 -398.965302) (xy 36.892945 -398.929589) (xy 36.857227 -398.888373) (xy 36.827739 -398.842493)
			(xy 36.805081 -398.792883) (xy 36.789714 -398.740554) (xy 36.781952 -398.68657) (xy 2.509012 -398.68657)
			(xy 2.509012 -399.443249) (xy 18.470394 -399.443249) (xy 18.470394 -399.388751) (xy 18.47815 -399.334808)
			(xy 18.493503 -399.282518) (xy 18.516141 -399.232945) (xy 18.545603 -399.187098) (xy 18.58129 -399.14591)
			(xy 18.622475 -399.11022) (xy 18.66832 -399.080754) (xy 18.717892 -399.058112) (xy 18.770181 -399.042756)
			(xy 18.824123 -399.034996) (xy 18.851372 -399.034508) (xy 19.714972 -399.034508) (xy 19.742227 -399.034937)
			(xy 19.796184 -399.042691) (xy 19.848487 -399.058045) (xy 19.898073 -399.080687) (xy 19.943931 -399.110156)
			(xy 19.985129 -399.145851) (xy 20.020827 -399.187046) (xy 20.050299 -399.232903) (xy 20.072945 -399.282487)
			(xy 20.088303 -399.334789) (xy 20.096061 -399.388745) (xy 20.096061 -399.443255) (xy 20.088303 -399.497211)
			(xy 20.072945 -399.549513) (xy 20.050299 -399.599097) (xy 20.020828 -399.644954) (xy 19.985129 -399.686149)
			(xy 19.943931 -399.721844) (xy 19.898073 -399.751313) (xy 19.848487 -399.773955) (xy 19.796184 -399.789309)
			(xy 19.742227 -399.797063) (xy 19.714972 -399.797524) (xy 18.851372 -399.797524) (xy 18.824123 -399.797004)
			(xy 18.770181 -399.789244) (xy 18.717892 -399.773888) (xy 18.66832 -399.751246) (xy 18.622475 -399.72178)
			(xy 18.58129 -399.68609) (xy 18.545603 -399.644902) (xy 18.516141 -399.599055) (xy 18.493503 -399.549482)
			(xy 18.47815 -399.497192) (xy 18.470394 -399.443249) (xy 2.509012 -399.443249) (xy 2.509012 -400.459248)
			(xy 25.590794 -400.459248) (xy 25.590794 -400.404752) (xy 25.598549 -400.350811) (xy 25.613901 -400.298522)
			(xy 25.636538 -400.24895) (xy 25.665999 -400.203104) (xy 25.701684 -400.161916) (xy 25.742867 -400.126226)
			(xy 25.788709 -400.09676) (xy 25.838279 -400.074117) (xy 25.890566 -400.058759) (xy 25.944506 -400.050997)
			(xy 25.971754 -400.050508) (xy 26.835354 -400.050508) (xy 26.86261 -400.050936) (xy 26.916568 -400.058688)
			(xy 26.968874 -400.07404) (xy 27.018462 -400.096681) (xy 27.064323 -400.126149) (xy 27.105523 -400.161845)
			(xy 27.141223 -400.20304) (xy 27.170697 -400.248897) (xy 27.193343 -400.298483) (xy 27.208702 -400.350787)
			(xy 27.216461 -400.404744) (xy 27.216461 -400.459256) (xy 27.208702 -400.513213) (xy 27.193343 -400.565517)
			(xy 27.170697 -400.615103) (xy 27.141223 -400.66096) (xy 27.105523 -400.702155) (xy 27.064323 -400.737851)
			(xy 27.018462 -400.767319) (xy 26.968874 -400.78996) (xy 26.916568 -400.805312) (xy 26.86261 -400.813064)
			(xy 26.835354 -400.813524) (xy 25.971754 -400.813524) (xy 25.944506 -400.813003) (xy 25.890566 -400.805241)
			(xy 25.838279 -400.789883) (xy 25.788709 -400.76724) (xy 25.742867 -400.737774) (xy 25.701684 -400.702084)
			(xy 25.665999 -400.660896) (xy 25.636538 -400.61505) (xy 25.613901 -400.565478) (xy 25.598549 -400.513189)
			(xy 25.590794 -400.459248) (xy 2.509012 -400.459248) (xy 2.509012 -400.885453) (xy 47.598783 -400.885453)
			(xy 47.598783 -400.830947) (xy 47.606541 -400.776997) (xy 47.621898 -400.7247) (xy 47.644541 -400.675121)
			(xy 47.674011 -400.629269) (xy 47.709706 -400.588079) (xy 47.7509 -400.552388) (xy 47.796754 -400.522923)
			(xy 47.846336 -400.500284) (xy 47.898634 -400.484933) (xy 47.952585 -400.477181) (xy 47.979838 -400.47672)
			(xy 48.843438 -400.47672) (xy 48.870689 -400.477152) (xy 48.924637 -400.484914) (xy 48.976931 -400.500273)
			(xy 49.026507 -400.522918) (xy 49.072356 -400.552388) (xy 49.113545 -400.588082) (xy 49.149235 -400.629274)
			(xy 49.1787 -400.675126) (xy 49.20134 -400.724705) (xy 49.216694 -400.777) (xy 49.22445 -400.830948)
			(xy 49.22445 -400.885448) (xy 50.662106 -400.885448) (xy 50.662106 -400.830952) (xy 50.669862 -400.77701)
			(xy 50.685214 -400.724721) (xy 50.707852 -400.675149) (xy 50.737314 -400.629303) (xy 50.773001 -400.588116)
			(xy 50.814185 -400.552427) (xy 50.86003 -400.522963) (xy 50.9096 -400.500322) (xy 50.961888 -400.484966)
			(xy 51.01583 -400.477208) (xy 51.043078 -400.47672) (xy 51.906678 -400.47672) (xy 51.933934 -400.477125)
			(xy 51.987891 -400.48488) (xy 52.040196 -400.500236) (xy 52.089782 -400.522879) (xy 52.135642 -400.552348)
			(xy 52.17684 -400.588045) (xy 52.212539 -400.629241) (xy 52.242011 -400.675098) (xy 52.264657 -400.724684)
			(xy 52.280015 -400.776987) (xy 52.287773 -400.830944) (xy 52.287773 -400.885452) (xy 53.725283 -400.885452)
			(xy 53.725283 -400.830948) (xy 53.73304 -400.777) (xy 53.748396 -400.724704) (xy 53.771038 -400.675127)
			(xy 53.800506 -400.629276) (xy 53.836199 -400.588086) (xy 53.87739 -400.552395) (xy 53.923242 -400.52293)
			(xy 53.972821 -400.50029) (xy 54.025117 -400.484936) (xy 54.079066 -400.477182) (xy 54.106318 -400.47672)
			(xy 54.969918 -400.47672) (xy 54.99717 -400.477151) (xy 55.05112 -400.48491) (xy 55.103417 -400.500268)
			(xy 55.152995 -400.522912) (xy 55.198847 -400.552381) (xy 55.240038 -400.588075) (xy 55.27573 -400.629268)
			(xy 55.305197 -400.675121) (xy 55.327838 -400.7247) (xy 55.343194 -400.776997) (xy 55.35095 -400.830948)
			(xy 55.35095 -400.885447) (xy 56.788606 -400.885447) (xy 56.788606 -400.830953) (xy 56.796361 -400.777013)
			(xy 56.811713 -400.724725) (xy 56.834349 -400.675154) (xy 56.863809 -400.629309) (xy 56.899494 -400.588123)
			(xy 56.940676 -400.552435) (xy 56.986518 -400.522969) (xy 57.036086 -400.500327) (xy 57.088372 -400.48497)
			(xy 57.142311 -400.477209) (xy 57.169558 -400.47672) (xy 58.033158 -400.47672) (xy 58.060415 -400.477124)
			(xy 58.114374 -400.484877) (xy 58.166681 -400.50023) (xy 58.21627 -400.522872) (xy 58.262132 -400.552341)
			(xy 58.303333 -400.588037) (xy 58.339034 -400.629234) (xy 58.368508 -400.675093) (xy 58.391155 -400.724679)
			(xy 58.406514 -400.776985) (xy 58.414273 -400.830943) (xy 58.414273 -400.885449) (xy 59.851806 -400.885449)
			(xy 59.851806 -400.830951) (xy 59.859562 -400.777007) (xy 59.874916 -400.724717) (xy 59.897555 -400.675143)
			(xy 59.927019 -400.629296) (xy 59.962708 -400.588109) (xy 60.003895 -400.55242) (xy 60.049742 -400.522956)
			(xy 60.099315 -400.500317) (xy 60.151605 -400.484963) (xy 60.205549 -400.477206) (xy 60.232798 -400.47672)
			(xy 61.096398 -400.47672) (xy 61.123653 -400.477127) (xy 61.177608 -400.484884) (xy 61.22991 -400.500241)
			(xy 61.279494 -400.522885) (xy 61.325351 -400.552355) (xy 61.366547 -400.588052) (xy 61.402243 -400.629247)
			(xy 61.431714 -400.675104) (xy 61.454358 -400.724688) (xy 61.469715 -400.77699) (xy 61.477473 -400.830945)
			(xy 61.477473 -400.885453) (xy 62.914983 -400.885453) (xy 62.914983 -400.830947) (xy 62.922741 -400.776997)
			(xy 62.938098 -400.7247) (xy 62.960741 -400.675121) (xy 62.990211 -400.629269) (xy 63.025906 -400.588079)
			(xy 63.0671 -400.552388) (xy 63.112954 -400.522923) (xy 63.162536 -400.500284) (xy 63.214834 -400.484933)
			(xy 63.268785 -400.477181) (xy 63.296038 -400.47672) (xy 64.159638 -400.47672) (xy 64.186889 -400.477152)
			(xy 64.240837 -400.484914) (xy 64.293131 -400.500273) (xy 64.342707 -400.522918) (xy 64.388556 -400.552388)
			(xy 64.429745 -400.588082) (xy 64.465435 -400.629274) (xy 64.4949 -400.675126) (xy 64.51754 -400.724705)
			(xy 64.532894 -400.777) (xy 64.54065 -400.830948) (xy 64.54065 -400.885448) (xy 65.978306 -400.885448)
			(xy 65.978306 -400.830952) (xy 65.986062 -400.77701) (xy 66.001414 -400.724721) (xy 66.024052 -400.675149)
			(xy 66.053514 -400.629303) (xy 66.089201 -400.588116) (xy 66.130385 -400.552427) (xy 66.17623 -400.522963)
			(xy 66.2258 -400.500322) (xy 66.278088 -400.484966) (xy 66.33203 -400.477208) (xy 66.359278 -400.47672)
			(xy 67.222878 -400.47672) (xy 67.250134 -400.477125) (xy 67.304091 -400.48488) (xy 67.356396 -400.500236)
			(xy 67.405982 -400.522879) (xy 67.451842 -400.552348) (xy 67.49304 -400.588045) (xy 67.528739 -400.629241)
			(xy 67.558211 -400.675098) (xy 67.580857 -400.724684) (xy 67.596215 -400.776987) (xy 67.603973 -400.830944)
			(xy 67.603973 -400.885452) (xy 69.041483 -400.885452) (xy 69.041483 -400.830948) (xy 69.04924 -400.777)
			(xy 69.064596 -400.724704) (xy 69.087238 -400.675127) (xy 69.116706 -400.629276) (xy 69.152399 -400.588086)
			(xy 69.19359 -400.552395) (xy 69.239442 -400.52293) (xy 69.289021 -400.50029) (xy 69.341317 -400.484936)
			(xy 69.395266 -400.477182) (xy 69.422518 -400.47672) (xy 70.286118 -400.47672) (xy 70.31337 -400.477151)
			(xy 70.36732 -400.48491) (xy 70.419617 -400.500268) (xy 70.469195 -400.522912) (xy 70.515047 -400.552381)
			(xy 70.556238 -400.588075) (xy 70.59193 -400.629268) (xy 70.621397 -400.675121) (xy 70.644038 -400.7247)
			(xy 70.659394 -400.776997) (xy 70.66715 -400.830948) (xy 70.66715 -400.885447) (xy 72.104806 -400.885447)
			(xy 72.104806 -400.830953) (xy 72.112561 -400.777013) (xy 72.127913 -400.724725) (xy 72.150549 -400.675154)
			(xy 72.180009 -400.629309) (xy 72.215694 -400.588123) (xy 72.256876 -400.552435) (xy 72.302718 -400.522969)
			(xy 72.352286 -400.500327) (xy 72.404572 -400.48497) (xy 72.458511 -400.477209) (xy 72.485758 -400.47672)
			(xy 73.349358 -400.47672) (xy 73.376615 -400.477124) (xy 73.430574 -400.484877) (xy 73.482881 -400.50023)
			(xy 73.53247 -400.522872) (xy 73.578332 -400.552341) (xy 73.619533 -400.588037) (xy 73.655234 -400.629234)
			(xy 73.684708 -400.675093) (xy 73.707355 -400.724679) (xy 73.722714 -400.776985) (xy 73.730473 -400.830943)
			(xy 73.730473 -400.885449) (xy 75.168006 -400.885449) (xy 75.168006 -400.830951) (xy 75.175762 -400.777007)
			(xy 75.191116 -400.724717) (xy 75.213755 -400.675143) (xy 75.243219 -400.629296) (xy 75.278908 -400.588109)
			(xy 75.320095 -400.55242) (xy 75.365942 -400.522956) (xy 75.415515 -400.500317) (xy 75.467805 -400.484963)
			(xy 75.521749 -400.477206) (xy 75.548998 -400.47672) (xy 76.412598 -400.47672) (xy 76.439853 -400.477127)
			(xy 76.493808 -400.484884) (xy 76.54611 -400.500241) (xy 76.595694 -400.522885) (xy 76.641551 -400.552355)
			(xy 76.682747 -400.588052) (xy 76.718443 -400.629247) (xy 76.747914 -400.675104) (xy 76.770558 -400.724688)
			(xy 76.785915 -400.77699) (xy 76.793673 -400.830945) (xy 76.793673 -400.885453) (xy 78.231183 -400.885453)
			(xy 78.231183 -400.830947) (xy 78.238941 -400.776997) (xy 78.254298 -400.7247) (xy 78.276941 -400.675121)
			(xy 78.306411 -400.629269) (xy 78.342106 -400.588079) (xy 78.3833 -400.552388) (xy 78.429154 -400.522923)
			(xy 78.478736 -400.500284) (xy 78.531034 -400.484933) (xy 78.584985 -400.477181) (xy 78.612238 -400.47672)
			(xy 79.475838 -400.47672) (xy 79.503089 -400.477152) (xy 79.557037 -400.484914) (xy 79.609331 -400.500273)
			(xy 79.658907 -400.522918) (xy 79.704756 -400.552388) (xy 79.745945 -400.588082) (xy 79.781635 -400.629274)
			(xy 79.8111 -400.675126) (xy 79.83374 -400.724705) (xy 79.849094 -400.777) (xy 79.85685 -400.830948)
			(xy 79.85685 -400.885448) (xy 81.294506 -400.885448) (xy 81.294506 -400.830952) (xy 81.302262 -400.77701)
			(xy 81.317614 -400.724721) (xy 81.340252 -400.675149) (xy 81.369714 -400.629303) (xy 81.405401 -400.588116)
			(xy 81.446585 -400.552427) (xy 81.49243 -400.522963) (xy 81.542 -400.500322) (xy 81.594288 -400.484966)
			(xy 81.64823 -400.477208) (xy 81.675478 -400.47672) (xy 82.539078 -400.47672) (xy 82.566334 -400.477125)
			(xy 82.620291 -400.48488) (xy 82.672596 -400.500236) (xy 82.722182 -400.522879) (xy 82.768042 -400.552348)
			(xy 82.80924 -400.588045) (xy 82.844939 -400.629241) (xy 82.874411 -400.675098) (xy 82.897057 -400.724684)
			(xy 82.912415 -400.776987) (xy 82.920173 -400.830944) (xy 82.920173 -400.885452) (xy 84.357683 -400.885452)
			(xy 84.357683 -400.830948) (xy 84.36544 -400.777) (xy 84.380796 -400.724704) (xy 84.403438 -400.675127)
			(xy 84.432906 -400.629276) (xy 84.468599 -400.588086) (xy 84.50979 -400.552395) (xy 84.555642 -400.52293)
			(xy 84.605221 -400.50029) (xy 84.657517 -400.484936) (xy 84.711466 -400.477182) (xy 84.738718 -400.47672)
			(xy 85.602318 -400.47672) (xy 85.62957 -400.477151) (xy 85.68352 -400.48491) (xy 85.735817 -400.500268)
			(xy 85.785395 -400.522912) (xy 85.831247 -400.552381) (xy 85.872438 -400.588075) (xy 85.90813 -400.629268)
			(xy 85.937597 -400.675121) (xy 85.960238 -400.7247) (xy 85.975594 -400.776997) (xy 85.98335 -400.830948)
			(xy 85.98335 -400.885447) (xy 87.421006 -400.885447) (xy 87.421006 -400.830953) (xy 87.428761 -400.777013)
			(xy 87.444113 -400.724725) (xy 87.466749 -400.675154) (xy 87.496209 -400.629309) (xy 87.531894 -400.588123)
			(xy 87.573076 -400.552435) (xy 87.618918 -400.522969) (xy 87.668486 -400.500327) (xy 87.720772 -400.48497)
			(xy 87.774711 -400.477209) (xy 87.801958 -400.47672) (xy 88.665558 -400.47672) (xy 88.692815 -400.477124)
			(xy 88.746774 -400.484877) (xy 88.799081 -400.50023) (xy 88.84867 -400.522872) (xy 88.894532 -400.552341)
			(xy 88.935733 -400.588037) (xy 88.971434 -400.629234) (xy 89.000908 -400.675093) (xy 89.023555 -400.724679)
			(xy 89.038914 -400.776985) (xy 89.046673 -400.830943) (xy 89.046673 -400.885449) (xy 90.484206 -400.885449)
			(xy 90.484206 -400.830951) (xy 90.491962 -400.777007) (xy 90.507316 -400.724717) (xy 90.529955 -400.675143)
			(xy 90.559419 -400.629296) (xy 90.595108 -400.588109) (xy 90.636295 -400.55242) (xy 90.682142 -400.522956)
			(xy 90.731715 -400.500317) (xy 90.784005 -400.484963) (xy 90.837949 -400.477206) (xy 90.865198 -400.47672)
			(xy 91.728798 -400.47672) (xy 91.756053 -400.477127) (xy 91.810008 -400.484884) (xy 91.86231 -400.500241)
			(xy 91.911894 -400.522885) (xy 91.957751 -400.552355) (xy 91.998947 -400.588052) (xy 92.034643 -400.629247)
			(xy 92.064114 -400.675104) (xy 92.086758 -400.724688) (xy 92.102115 -400.77699) (xy 92.109873 -400.830945)
			(xy 92.109873 -400.885453) (xy 93.547383 -400.885453) (xy 93.547383 -400.830947) (xy 93.555141 -400.776997)
			(xy 93.570498 -400.7247) (xy 93.593141 -400.675121) (xy 93.622611 -400.629269) (xy 93.658306 -400.588079)
			(xy 93.6995 -400.552388) (xy 93.745354 -400.522923) (xy 93.794936 -400.500284) (xy 93.847234 -400.484933)
			(xy 93.901185 -400.477181) (xy 93.928438 -400.47672) (xy 94.792038 -400.47672) (xy 94.819289 -400.477152)
			(xy 94.873237 -400.484914) (xy 94.925531 -400.500273) (xy 94.975107 -400.522918) (xy 95.020956 -400.552388)
			(xy 95.062145 -400.588082) (xy 95.097835 -400.629274) (xy 95.1273 -400.675126) (xy 95.14994 -400.724705)
			(xy 95.165294 -400.777) (xy 95.17305 -400.830948) (xy 95.17305 -400.885447) (xy 119.774006 -400.885447)
			(xy 119.774006 -400.830953) (xy 119.781761 -400.777013) (xy 119.797112 -400.724726) (xy 119.819749 -400.675156)
			(xy 119.849208 -400.629311) (xy 119.884892 -400.588125) (xy 119.926074 -400.552436) (xy 119.971915 -400.522971)
			(xy 120.021483 -400.500329) (xy 120.073768 -400.484971) (xy 120.127707 -400.477209) (xy 120.154954 -400.47672)
			(xy 121.018554 -400.47672) (xy 121.045811 -400.477124) (xy 121.099771 -400.484876) (xy 121.152078 -400.500229)
			(xy 121.201668 -400.522871) (xy 121.24753 -400.55234) (xy 121.288731 -400.588036) (xy 121.324433 -400.629233)
			(xy 121.353907 -400.675092) (xy 121.376555 -400.724679) (xy 121.391914 -400.776984) (xy 121.399673 -400.830943)
			(xy 121.399673 -400.885449) (xy 122.837206 -400.885449) (xy 122.837206 -400.830951) (xy 122.844962 -400.777008)
			(xy 122.860316 -400.724717) (xy 122.882955 -400.675144) (xy 122.912418 -400.629298) (xy 122.948106 -400.588111)
			(xy 122.989293 -400.552422) (xy 123.035139 -400.522958) (xy 123.084712 -400.500318) (xy 123.137002 -400.484963)
			(xy 123.190945 -400.477207) (xy 123.218194 -400.47672) (xy 124.081794 -400.47672) (xy 124.109049 -400.477127)
			(xy 124.163005 -400.484883) (xy 124.215307 -400.50024) (xy 124.264892 -400.522884) (xy 124.310749 -400.552354)
			(xy 124.351946 -400.58805) (xy 124.387643 -400.629246) (xy 124.417113 -400.675103) (xy 124.439758 -400.724687)
			(xy 124.455115 -400.776989) (xy 124.462873 -400.830945) (xy 124.462873 -400.885452) (xy 125.900383 -400.885452)
			(xy 125.900383 -400.830948) (xy 125.908141 -400.776998) (xy 125.923497 -400.724701) (xy 125.946141 -400.675122)
			(xy 125.97561 -400.629271) (xy 126.011304 -400.58808) (xy 126.052498 -400.552389) (xy 126.098352 -400.522924)
			(xy 126.147933 -400.500285) (xy 126.200231 -400.484933) (xy 126.254182 -400.477181) (xy 126.281434 -400.47672)
			(xy 127.145034 -400.47672) (xy 127.172286 -400.477152) (xy 127.226234 -400.484913) (xy 127.278528 -400.500272)
			(xy 127.328105 -400.522917) (xy 127.373954 -400.552386) (xy 127.415143 -400.588081) (xy 127.450834 -400.629273)
			(xy 127.480299 -400.675125) (xy 127.50294 -400.724704) (xy 127.518294 -400.777) (xy 127.52605 -400.830948)
			(xy 127.52605 -400.885448) (xy 128.963706 -400.885448) (xy 128.963706 -400.830952) (xy 128.971461 -400.777011)
			(xy 128.986814 -400.724722) (xy 129.009452 -400.67515) (xy 129.038913 -400.629304) (xy 129.074599 -400.588118)
			(xy 129.115783 -400.552429) (xy 129.161627 -400.522964) (xy 129.211197 -400.500323) (xy 129.263485 -400.484967)
			(xy 129.317426 -400.477208) (xy 129.344674 -400.47672) (xy 130.208274 -400.47672) (xy 130.23553 -400.477125)
			(xy 130.289488 -400.48488) (xy 130.341793 -400.500235) (xy 130.39138 -400.522877) (xy 130.43724 -400.552347)
			(xy 130.478438 -400.588043) (xy 130.514138 -400.62924) (xy 130.54361 -400.675097) (xy 130.566256 -400.724683)
			(xy 130.581615 -400.776987) (xy 130.589373 -400.830944) (xy 130.589373 -400.885451) (xy 132.026883 -400.885451)
			(xy 132.026883 -400.830949) (xy 132.03464 -400.777) (xy 132.049996 -400.724705) (xy 132.072638 -400.675128)
			(xy 132.102105 -400.629277) (xy 132.137797 -400.588087) (xy 132.178989 -400.552396) (xy 132.22484 -400.522931)
			(xy 132.274418 -400.500291) (xy 132.326714 -400.484937) (xy 132.380662 -400.477182) (xy 132.407914 -400.47672)
			(xy 133.271514 -400.47672) (xy 133.298767 -400.477151) (xy 133.352717 -400.48491) (xy 133.405014 -400.500267)
			(xy 133.454593 -400.522911) (xy 133.500445 -400.552379) (xy 133.541636 -400.588074) (xy 133.577329 -400.629266)
			(xy 133.606796 -400.67512) (xy 133.629438 -400.724699) (xy 133.644793 -400.776997) (xy 133.65255 -400.830947)
			(xy 133.65255 -400.885447) (xy 135.090206 -400.885447) (xy 135.090206 -400.830953) (xy 135.097961 -400.777013)
			(xy 135.113312 -400.724726) (xy 135.135949 -400.675156) (xy 135.165408 -400.629311) (xy 135.201092 -400.588125)
			(xy 135.242274 -400.552436) (xy 135.288115 -400.522971) (xy 135.337683 -400.500329) (xy 135.389968 -400.484971)
			(xy 135.443907 -400.477209) (xy 135.471154 -400.47672) (xy 136.334754 -400.47672) (xy 136.362011 -400.477124)
			(xy 136.415971 -400.484876) (xy 136.468278 -400.500229) (xy 136.517868 -400.522871) (xy 136.56373 -400.55234)
			(xy 136.604931 -400.588036) (xy 136.640633 -400.629233) (xy 136.670107 -400.675092) (xy 136.692755 -400.724679)
			(xy 136.708114 -400.776984) (xy 136.715873 -400.830943) (xy 136.715873 -400.885449) (xy 138.153406 -400.885449)
			(xy 138.153406 -400.830951) (xy 138.161162 -400.777008) (xy 138.176516 -400.724717) (xy 138.199155 -400.675144)
			(xy 138.228618 -400.629298) (xy 138.264306 -400.588111) (xy 138.305493 -400.552422) (xy 138.351339 -400.522958)
			(xy 138.400912 -400.500318) (xy 138.453202 -400.484963) (xy 138.507145 -400.477207) (xy 138.534394 -400.47672)
			(xy 139.397994 -400.47672) (xy 139.425249 -400.477127) (xy 139.479205 -400.484883) (xy 139.531507 -400.50024)
			(xy 139.581092 -400.522884) (xy 139.626949 -400.552354) (xy 139.668146 -400.58805) (xy 139.703843 -400.629246)
			(xy 139.733313 -400.675103) (xy 139.755958 -400.724687) (xy 139.771315 -400.776989) (xy 139.779073 -400.830945)
			(xy 139.779073 -400.885452) (xy 141.216583 -400.885452) (xy 141.216583 -400.830948) (xy 141.224341 -400.776998)
			(xy 141.239697 -400.724701) (xy 141.262341 -400.675122) (xy 141.29181 -400.629271) (xy 141.327504 -400.58808)
			(xy 141.368698 -400.552389) (xy 141.414552 -400.522924) (xy 141.464133 -400.500285) (xy 141.516431 -400.484933)
			(xy 141.570382 -400.477181) (xy 141.597634 -400.47672) (xy 142.461234 -400.47672) (xy 142.488486 -400.477152)
			(xy 142.542434 -400.484913) (xy 142.594728 -400.500272) (xy 142.644305 -400.522917) (xy 142.690154 -400.552386)
			(xy 142.731343 -400.588081) (xy 142.767034 -400.629273) (xy 142.796499 -400.675125) (xy 142.81914 -400.724704)
			(xy 142.834494 -400.777) (xy 142.84225 -400.830948) (xy 142.84225 -400.885448) (xy 144.279906 -400.885448)
			(xy 144.279906 -400.830952) (xy 144.287661 -400.777011) (xy 144.303014 -400.724722) (xy 144.325652 -400.67515)
			(xy 144.355113 -400.629304) (xy 144.390799 -400.588118) (xy 144.431983 -400.552429) (xy 144.477827 -400.522964)
			(xy 144.527397 -400.500323) (xy 144.579685 -400.484967) (xy 144.633626 -400.477208) (xy 144.660874 -400.47672)
			(xy 145.524474 -400.47672) (xy 145.55173 -400.477125) (xy 145.605688 -400.48488) (xy 145.657993 -400.500235)
			(xy 145.70758 -400.522877) (xy 145.75344 -400.552347) (xy 145.794638 -400.588043) (xy 145.830338 -400.62924)
			(xy 145.85981 -400.675097) (xy 145.882456 -400.724683) (xy 145.897815 -400.776987) (xy 145.905573 -400.830944)
			(xy 145.905573 -400.885451) (xy 147.343083 -400.885451) (xy 147.343083 -400.830949) (xy 147.35084 -400.777)
			(xy 147.366196 -400.724705) (xy 147.388838 -400.675128) (xy 147.418305 -400.629277) (xy 147.453997 -400.588087)
			(xy 147.495189 -400.552396) (xy 147.54104 -400.522931) (xy 147.590618 -400.500291) (xy 147.642914 -400.484937)
			(xy 147.696862 -400.477182) (xy 147.724114 -400.47672) (xy 148.587714 -400.47672) (xy 148.614967 -400.477151)
			(xy 148.668917 -400.48491) (xy 148.721214 -400.500267) (xy 148.770793 -400.522911) (xy 148.816645 -400.552379)
			(xy 148.857836 -400.588074) (xy 148.893529 -400.629266) (xy 148.922996 -400.67512) (xy 148.945638 -400.724699)
			(xy 148.960993 -400.776997) (xy 148.96875 -400.830947) (xy 148.96875 -400.885447) (xy 150.406406 -400.885447)
			(xy 150.406406 -400.830953) (xy 150.414161 -400.777013) (xy 150.429512 -400.724726) (xy 150.452149 -400.675156)
			(xy 150.481608 -400.629311) (xy 150.517292 -400.588125) (xy 150.558474 -400.552436) (xy 150.604315 -400.522971)
			(xy 150.653883 -400.500329) (xy 150.706168 -400.484971) (xy 150.760107 -400.477209) (xy 150.787354 -400.47672)
			(xy 151.650954 -400.47672) (xy 151.678211 -400.477124) (xy 151.732171 -400.484876) (xy 151.784478 -400.500229)
			(xy 151.834068 -400.522871) (xy 151.87993 -400.55234) (xy 151.921131 -400.588036) (xy 151.956833 -400.629233)
			(xy 151.986307 -400.675092) (xy 152.008955 -400.724679) (xy 152.024314 -400.776984) (xy 152.032073 -400.830943)
			(xy 152.032073 -400.885449) (xy 153.469606 -400.885449) (xy 153.469606 -400.830951) (xy 153.477362 -400.777008)
			(xy 153.492716 -400.724717) (xy 153.515355 -400.675144) (xy 153.544818 -400.629298) (xy 153.580506 -400.588111)
			(xy 153.621693 -400.552422) (xy 153.667539 -400.522958) (xy 153.717112 -400.500318) (xy 153.769402 -400.484963)
			(xy 153.823345 -400.477207) (xy 153.850594 -400.47672) (xy 154.714194 -400.47672) (xy 154.741449 -400.477127)
			(xy 154.795405 -400.484883) (xy 154.847707 -400.50024) (xy 154.897292 -400.522884) (xy 154.943149 -400.552354)
			(xy 154.984346 -400.58805) (xy 155.020043 -400.629246) (xy 155.049513 -400.675103) (xy 155.072158 -400.724687)
			(xy 155.087515 -400.776989) (xy 155.095273 -400.830945) (xy 155.095273 -400.885452) (xy 156.532783 -400.885452)
			(xy 156.532783 -400.830948) (xy 156.540541 -400.776998) (xy 156.555897 -400.724701) (xy 156.578541 -400.675122)
			(xy 156.60801 -400.629271) (xy 156.643704 -400.58808) (xy 156.684898 -400.552389) (xy 156.730752 -400.522924)
			(xy 156.780333 -400.500285) (xy 156.832631 -400.484933) (xy 156.886582 -400.477181) (xy 156.913834 -400.47672)
			(xy 157.777434 -400.47672) (xy 157.804686 -400.477152) (xy 157.858634 -400.484913) (xy 157.910928 -400.500272)
			(xy 157.960505 -400.522917) (xy 158.006354 -400.552386) (xy 158.047543 -400.588081) (xy 158.083234 -400.629273)
			(xy 158.112699 -400.675125) (xy 158.13534 -400.724704) (xy 158.150694 -400.777) (xy 158.15845 -400.830948)
			(xy 158.15845 -400.885448) (xy 159.596106 -400.885448) (xy 159.596106 -400.830952) (xy 159.603861 -400.777011)
			(xy 159.619214 -400.724722) (xy 159.641852 -400.67515) (xy 159.671313 -400.629304) (xy 159.706999 -400.588118)
			(xy 159.748183 -400.552429) (xy 159.794027 -400.522964) (xy 159.843597 -400.500323) (xy 159.895885 -400.484967)
			(xy 159.949826 -400.477208) (xy 159.977074 -400.47672) (xy 160.840674 -400.47672) (xy 160.86793 -400.477125)
			(xy 160.921888 -400.48488) (xy 160.974193 -400.500235) (xy 161.02378 -400.522877) (xy 161.06964 -400.552347)
			(xy 161.110838 -400.588043) (xy 161.146538 -400.62924) (xy 161.17601 -400.675097) (xy 161.198656 -400.724683)
			(xy 161.214015 -400.776987) (xy 161.221773 -400.830944) (xy 161.221773 -400.885451) (xy 162.659283 -400.885451)
			(xy 162.659283 -400.830949) (xy 162.66704 -400.777) (xy 162.682396 -400.724705) (xy 162.705038 -400.675128)
			(xy 162.734505 -400.629277) (xy 162.770197 -400.588087) (xy 162.811389 -400.552396) (xy 162.85724 -400.522931)
			(xy 162.906818 -400.500291) (xy 162.959114 -400.484937) (xy 163.013062 -400.477182) (xy 163.040314 -400.47672)
			(xy 163.903914 -400.47672) (xy 163.931167 -400.477151) (xy 163.985117 -400.48491) (xy 164.037414 -400.500267)
			(xy 164.086993 -400.522911) (xy 164.132845 -400.552379) (xy 164.174036 -400.588074) (xy 164.209729 -400.629266)
			(xy 164.239196 -400.67512) (xy 164.261838 -400.724699) (xy 164.277193 -400.776997) (xy 164.28495 -400.830947)
			(xy 164.28495 -400.885447) (xy 165.722606 -400.885447) (xy 165.722606 -400.830953) (xy 165.730361 -400.777013)
			(xy 165.745712 -400.724726) (xy 165.768349 -400.675156) (xy 165.797808 -400.629311) (xy 165.833492 -400.588125)
			(xy 165.874674 -400.552436) (xy 165.920515 -400.522971) (xy 165.970083 -400.500329) (xy 166.022368 -400.484971)
			(xy 166.076307 -400.477209) (xy 166.103554 -400.47672) (xy 166.967154 -400.47672) (xy 166.994411 -400.477124)
			(xy 167.048371 -400.484876) (xy 167.100678 -400.500229) (xy 167.150268 -400.522871) (xy 167.19613 -400.55234)
			(xy 167.237331 -400.588036) (xy 167.273033 -400.629233) (xy 167.302507 -400.675092) (xy 167.325155 -400.724679)
			(xy 167.340514 -400.776984) (xy 167.348273 -400.830943) (xy 167.348273 -400.885457) (xy 167.340514 -400.939416)
			(xy 167.325155 -400.991721) (xy 167.302507 -401.041308) (xy 167.273033 -401.087167) (xy 167.237331 -401.128364)
			(xy 167.19613 -401.16406) (xy 167.150268 -401.193529) (xy 167.100678 -401.216171) (xy 167.048371 -401.231524)
			(xy 166.994411 -401.239276) (xy 166.967154 -401.239736) (xy 166.103554 -401.239736) (xy 166.076307 -401.239191)
			(xy 166.022368 -401.231429) (xy 165.970083 -401.216071) (xy 165.920515 -401.193429) (xy 165.874674 -401.163964)
			(xy 165.833492 -401.128275) (xy 165.797808 -401.087089) (xy 165.768349 -401.041244) (xy 165.745712 -400.991674)
			(xy 165.730361 -400.939387) (xy 165.722606 -400.885447) (xy 164.28495 -400.885447) (xy 164.28495 -400.885453)
			(xy 164.277193 -400.939403) (xy 164.261838 -400.991701) (xy 164.239196 -401.04128) (xy 164.209729 -401.087134)
			(xy 164.174036 -401.128326) (xy 164.132845 -401.164021) (xy 164.086993 -401.193489) (xy 164.037414 -401.216133)
			(xy 163.985117 -401.23149) (xy 163.931167 -401.239249) (xy 163.903914 -401.239736) (xy 163.040314 -401.239736)
			(xy 163.013062 -401.239218) (xy 162.959114 -401.231463) (xy 162.906818 -401.216109) (xy 162.85724 -401.193469)
			(xy 162.811389 -401.164004) (xy 162.770197 -401.128313) (xy 162.734505 -401.087123) (xy 162.705038 -401.041272)
			(xy 162.682396 -400.991695) (xy 162.66704 -400.9394) (xy 162.659283 -400.885451) (xy 161.221773 -400.885451)
			(xy 161.221773 -400.885456) (xy 161.214015 -400.939413) (xy 161.198656 -400.991717) (xy 161.17601 -401.041303)
			(xy 161.146538 -401.08716) (xy 161.110838 -401.128357) (xy 161.06964 -401.164053) (xy 161.02378 -401.193523)
			(xy 160.974193 -401.216165) (xy 160.921888 -401.23152) (xy 160.86793 -401.239275) (xy 160.840674 -401.239736)
			(xy 159.977074 -401.239736) (xy 159.949826 -401.239192) (xy 159.895885 -401.231433) (xy 159.843597 -401.216077)
			(xy 159.794027 -401.193436) (xy 159.748183 -401.163971) (xy 159.706999 -401.128282) (xy 159.671313 -401.087096)
			(xy 159.641852 -401.04125) (xy 159.619214 -400.991678) (xy 159.603861 -400.939389) (xy 159.596106 -400.885448)
			(xy 158.15845 -400.885448) (xy 158.15845 -400.885452) (xy 158.150694 -400.9394) (xy 158.13534 -400.991696)
			(xy 158.112699 -401.041275) (xy 158.083234 -401.087127) (xy 158.047543 -401.128319) (xy 158.006354 -401.164014)
			(xy 157.960505 -401.193483) (xy 157.910928 -401.216128) (xy 157.858634 -401.231487) (xy 157.804686 -401.239248)
			(xy 157.777434 -401.239736) (xy 156.913834 -401.239736) (xy 156.886582 -401.239219) (xy 156.832631 -401.231467)
			(xy 156.780333 -401.216115) (xy 156.730752 -401.193476) (xy 156.684898 -401.164011) (xy 156.643704 -401.12832)
			(xy 156.60801 -401.087129) (xy 156.578541 -401.041278) (xy 156.555897 -400.991699) (xy 156.540541 -400.939402)
			(xy 156.532783 -400.885452) (xy 155.095273 -400.885452) (xy 155.095273 -400.885455) (xy 155.087515 -400.939411)
			(xy 155.072158 -400.991713) (xy 155.049513 -401.041297) (xy 155.020043 -401.087154) (xy 154.984346 -401.12835)
			(xy 154.943149 -401.164046) (xy 154.897292 -401.193516) (xy 154.847707 -401.21616) (xy 154.795405 -401.231517)
			(xy 154.741449 -401.239273) (xy 154.714194 -401.239736) (xy 153.850594 -401.239736) (xy 153.823345 -401.239193)
			(xy 153.769402 -401.231437) (xy 153.717112 -401.216082) (xy 153.667539 -401.193442) (xy 153.621693 -401.163978)
			(xy 153.580506 -401.128289) (xy 153.544818 -401.087102) (xy 153.515355 -401.041256) (xy 153.492716 -400.991683)
			(xy 153.477362 -400.939392) (xy 153.469606 -400.885449) (xy 152.032073 -400.885449) (xy 152.032073 -400.885457)
			(xy 152.024314 -400.939416) (xy 152.008955 -400.991721) (xy 151.986307 -401.041308) (xy 151.956833 -401.087167)
			(xy 151.921131 -401.128364) (xy 151.87993 -401.16406) (xy 151.834068 -401.193529) (xy 151.784478 -401.216171)
			(xy 151.732171 -401.231524) (xy 151.678211 -401.239276) (xy 151.650954 -401.239736) (xy 150.787354 -401.239736)
			(xy 150.760107 -401.239191) (xy 150.706168 -401.231429) (xy 150.653883 -401.216071) (xy 150.604315 -401.193429)
			(xy 150.558474 -401.163964) (xy 150.517292 -401.128275) (xy 150.481608 -401.087089) (xy 150.452149 -401.041244)
			(xy 150.429512 -400.991674) (xy 150.414161 -400.939387) (xy 150.406406 -400.885447) (xy 148.96875 -400.885447)
			(xy 148.96875 -400.885453) (xy 148.960993 -400.939403) (xy 148.945638 -400.991701) (xy 148.922996 -401.04128)
			(xy 148.893529 -401.087134) (xy 148.857836 -401.128326) (xy 148.816645 -401.164021) (xy 148.770793 -401.193489)
			(xy 148.721214 -401.216133) (xy 148.668917 -401.23149) (xy 148.614967 -401.239249) (xy 148.587714 -401.239736)
			(xy 147.724114 -401.239736) (xy 147.696862 -401.239218) (xy 147.642914 -401.231463) (xy 147.590618 -401.216109)
			(xy 147.54104 -401.193469) (xy 147.495189 -401.164004) (xy 147.453997 -401.128313) (xy 147.418305 -401.087123)
			(xy 147.388838 -401.041272) (xy 147.366196 -400.991695) (xy 147.35084 -400.9394) (xy 147.343083 -400.885451)
			(xy 145.905573 -400.885451) (xy 145.905573 -400.885456) (xy 145.897815 -400.939413) (xy 145.882456 -400.991717)
			(xy 145.85981 -401.041303) (xy 145.830338 -401.08716) (xy 145.794638 -401.128357) (xy 145.75344 -401.164053)
			(xy 145.70758 -401.193523) (xy 145.657993 -401.216165) (xy 145.605688 -401.23152) (xy 145.55173 -401.239275)
			(xy 145.524474 -401.239736) (xy 144.660874 -401.239736) (xy 144.633626 -401.239192) (xy 144.579685 -401.231433)
			(xy 144.527397 -401.216077) (xy 144.477827 -401.193436) (xy 144.431983 -401.163971) (xy 144.390799 -401.128282)
			(xy 144.355113 -401.087096) (xy 144.325652 -401.04125) (xy 144.303014 -400.991678) (xy 144.287661 -400.939389)
			(xy 144.279906 -400.885448) (xy 142.84225 -400.885448) (xy 142.84225 -400.885452) (xy 142.834494 -400.9394)
			(xy 142.81914 -400.991696) (xy 142.796499 -401.041275) (xy 142.767034 -401.087127) (xy 142.731343 -401.128319)
			(xy 142.690154 -401.164014) (xy 142.644305 -401.193483) (xy 142.594728 -401.216128) (xy 142.542434 -401.231487)
			(xy 142.488486 -401.239248) (xy 142.461234 -401.239736) (xy 141.597634 -401.239736) (xy 141.570382 -401.239219)
			(xy 141.516431 -401.231467) (xy 141.464133 -401.216115) (xy 141.414552 -401.193476) (xy 141.368698 -401.164011)
			(xy 141.327504 -401.12832) (xy 141.29181 -401.087129) (xy 141.262341 -401.041278) (xy 141.239697 -400.991699)
			(xy 141.224341 -400.939402) (xy 141.216583 -400.885452) (xy 139.779073 -400.885452) (xy 139.779073 -400.885455)
			(xy 139.771315 -400.939411) (xy 139.755958 -400.991713) (xy 139.733313 -401.041297) (xy 139.703843 -401.087154)
			(xy 139.668146 -401.12835) (xy 139.626949 -401.164046) (xy 139.581092 -401.193516) (xy 139.531507 -401.21616)
			(xy 139.479205 -401.231517) (xy 139.425249 -401.239273) (xy 139.397994 -401.239736) (xy 138.534394 -401.239736)
			(xy 138.507145 -401.239193) (xy 138.453202 -401.231437) (xy 138.400912 -401.216082) (xy 138.351339 -401.193442)
			(xy 138.305493 -401.163978) (xy 138.264306 -401.128289) (xy 138.228618 -401.087102) (xy 138.199155 -401.041256)
			(xy 138.176516 -400.991683) (xy 138.161162 -400.939392) (xy 138.153406 -400.885449) (xy 136.715873 -400.885449)
			(xy 136.715873 -400.885457) (xy 136.708114 -400.939416) (xy 136.692755 -400.991721) (xy 136.670107 -401.041308)
			(xy 136.640633 -401.087167) (xy 136.604931 -401.128364) (xy 136.56373 -401.16406) (xy 136.517868 -401.193529)
			(xy 136.468278 -401.216171) (xy 136.415971 -401.231524) (xy 136.362011 -401.239276) (xy 136.334754 -401.239736)
			(xy 135.471154 -401.239736) (xy 135.443907 -401.239191) (xy 135.389968 -401.231429) (xy 135.337683 -401.216071)
			(xy 135.288115 -401.193429) (xy 135.242274 -401.163964) (xy 135.201092 -401.128275) (xy 135.165408 -401.087089)
			(xy 135.135949 -401.041244) (xy 135.113312 -400.991674) (xy 135.097961 -400.939387) (xy 135.090206 -400.885447)
			(xy 133.65255 -400.885447) (xy 133.65255 -400.885453) (xy 133.644793 -400.939403) (xy 133.629438 -400.991701)
			(xy 133.606796 -401.04128) (xy 133.577329 -401.087134) (xy 133.541636 -401.128326) (xy 133.500445 -401.164021)
			(xy 133.454593 -401.193489) (xy 133.405014 -401.216133) (xy 133.352717 -401.23149) (xy 133.298767 -401.239249)
			(xy 133.271514 -401.239736) (xy 132.407914 -401.239736) (xy 132.380662 -401.239218) (xy 132.326714 -401.231463)
			(xy 132.274418 -401.216109) (xy 132.22484 -401.193469) (xy 132.178989 -401.164004) (xy 132.137797 -401.128313)
			(xy 132.102105 -401.087123) (xy 132.072638 -401.041272) (xy 132.049996 -400.991695) (xy 132.03464 -400.9394)
			(xy 132.026883 -400.885451) (xy 130.589373 -400.885451) (xy 130.589373 -400.885456) (xy 130.581615 -400.939413)
			(xy 130.566256 -400.991717) (xy 130.54361 -401.041303) (xy 130.514138 -401.08716) (xy 130.478438 -401.128357)
			(xy 130.43724 -401.164053) (xy 130.39138 -401.193523) (xy 130.341793 -401.216165) (xy 130.289488 -401.23152)
			(xy 130.23553 -401.239275) (xy 130.208274 -401.239736) (xy 129.344674 -401.239736) (xy 129.317426 -401.239192)
			(xy 129.263485 -401.231433) (xy 129.211197 -401.216077) (xy 129.161627 -401.193436) (xy 129.115783 -401.163971)
			(xy 129.074599 -401.128282) (xy 129.038913 -401.087096) (xy 129.009452 -401.04125) (xy 128.986814 -400.991678)
			(xy 128.971461 -400.939389) (xy 128.963706 -400.885448) (xy 127.52605 -400.885448) (xy 127.52605 -400.885452)
			(xy 127.518294 -400.9394) (xy 127.50294 -400.991696) (xy 127.480299 -401.041275) (xy 127.450834 -401.087127)
			(xy 127.415143 -401.128319) (xy 127.373954 -401.164014) (xy 127.328105 -401.193483) (xy 127.278528 -401.216128)
			(xy 127.226234 -401.231487) (xy 127.172286 -401.239248) (xy 127.145034 -401.239736) (xy 126.281434 -401.239736)
			(xy 126.254182 -401.239219) (xy 126.200231 -401.231467) (xy 126.147933 -401.216115) (xy 126.098352 -401.193476)
			(xy 126.052498 -401.164011) (xy 126.011304 -401.12832) (xy 125.97561 -401.087129) (xy 125.946141 -401.041278)
			(xy 125.923497 -400.991699) (xy 125.908141 -400.939402) (xy 125.900383 -400.885452) (xy 124.462873 -400.885452)
			(xy 124.462873 -400.885455) (xy 124.455115 -400.939411) (xy 124.439758 -400.991713) (xy 124.417113 -401.041297)
			(xy 124.387643 -401.087154) (xy 124.351946 -401.12835) (xy 124.310749 -401.164046) (xy 124.264892 -401.193516)
			(xy 124.215307 -401.21616) (xy 124.163005 -401.231517) (xy 124.109049 -401.239273) (xy 124.081794 -401.239736)
			(xy 123.218194 -401.239736) (xy 123.190945 -401.239193) (xy 123.137002 -401.231437) (xy 123.084712 -401.216082)
			(xy 123.035139 -401.193442) (xy 122.989293 -401.163978) (xy 122.948106 -401.128289) (xy 122.912418 -401.087102)
			(xy 122.882955 -401.041256) (xy 122.860316 -400.991683) (xy 122.844962 -400.939392) (xy 122.837206 -400.885449)
			(xy 121.399673 -400.885449) (xy 121.399673 -400.885457) (xy 121.391914 -400.939416) (xy 121.376555 -400.991721)
			(xy 121.353907 -401.041308) (xy 121.324433 -401.087167) (xy 121.288731 -401.128364) (xy 121.24753 -401.16406)
			(xy 121.201668 -401.193529) (xy 121.152078 -401.216171) (xy 121.099771 -401.231524) (xy 121.045811 -401.239276)
			(xy 121.018554 -401.239736) (xy 120.154954 -401.239736) (xy 120.127707 -401.239191) (xy 120.073768 -401.231429)
			(xy 120.021483 -401.216071) (xy 119.971915 -401.193429) (xy 119.926074 -401.163964) (xy 119.884892 -401.128275)
			(xy 119.849208 -401.087089) (xy 119.819749 -401.041244) (xy 119.797112 -400.991674) (xy 119.781761 -400.939387)
			(xy 119.774006 -400.885447) (xy 95.17305 -400.885447) (xy 95.17305 -400.885452) (xy 95.165294 -400.9394)
			(xy 95.14994 -400.991695) (xy 95.1273 -401.041274) (xy 95.097835 -401.087126) (xy 95.062145 -401.128318)
			(xy 95.020956 -401.164012) (xy 94.975107 -401.193482) (xy 94.925531 -401.216127) (xy 94.873237 -401.231486)
			(xy 94.819289 -401.239248) (xy 94.792038 -401.239736) (xy 93.928438 -401.239736) (xy 93.901185 -401.239219)
			(xy 93.847234 -401.231467) (xy 93.794936 -401.216116) (xy 93.745354 -401.193477) (xy 93.6995 -401.164012)
			(xy 93.658306 -401.128321) (xy 93.622611 -401.087131) (xy 93.593141 -401.041279) (xy 93.570498 -400.9917)
			(xy 93.555141 -400.939403) (xy 93.547383 -400.885453) (xy 92.109873 -400.885453) (xy 92.109873 -400.885455)
			(xy 92.102115 -400.93941) (xy 92.086758 -400.991712) (xy 92.064114 -401.041296) (xy 92.034643 -401.087153)
			(xy 91.998947 -401.128348) (xy 91.957751 -401.164045) (xy 91.911894 -401.193515) (xy 91.86231 -401.216159)
			(xy 91.810008 -401.231516) (xy 91.756053 -401.239273) (xy 91.728798 -401.239736) (xy 90.865198 -401.239736)
			(xy 90.837949 -401.239194) (xy 90.784005 -401.231437) (xy 90.731715 -401.216083) (xy 90.682142 -401.193444)
			(xy 90.636295 -401.16398) (xy 90.595108 -401.128291) (xy 90.559419 -401.087104) (xy 90.529955 -401.041257)
			(xy 90.507316 -400.991683) (xy 90.491962 -400.939393) (xy 90.484206 -400.885449) (xy 89.046673 -400.885449)
			(xy 89.046673 -400.885457) (xy 89.038914 -400.939415) (xy 89.023555 -400.991721) (xy 89.000908 -401.041307)
			(xy 88.971434 -401.087166) (xy 88.935733 -401.128363) (xy 88.894532 -401.164059) (xy 88.84867 -401.193528)
			(xy 88.799081 -401.21617) (xy 88.746774 -401.231523) (xy 88.692815 -401.239276) (xy 88.665558 -401.239736)
			(xy 87.801958 -401.239736) (xy 87.774711 -401.239191) (xy 87.720772 -401.23143) (xy 87.668486 -401.216073)
			(xy 87.618918 -401.193431) (xy 87.573076 -401.163965) (xy 87.531894 -401.128277) (xy 87.496209 -401.087091)
			(xy 87.466749 -401.041246) (xy 87.444113 -400.991675) (xy 87.428761 -400.939387) (xy 87.421006 -400.885447)
			(xy 85.98335 -400.885447) (xy 85.98335 -400.885452) (xy 85.975594 -400.939403) (xy 85.960238 -400.9917)
			(xy 85.937597 -401.041279) (xy 85.90813 -401.087132) (xy 85.872438 -401.128325) (xy 85.831247 -401.164019)
			(xy 85.785395 -401.193488) (xy 85.735817 -401.216132) (xy 85.68352 -401.23149) (xy 85.62957 -401.239249)
			(xy 85.602318 -401.239736) (xy 84.738718 -401.239736) (xy 84.711466 -401.239218) (xy 84.657517 -401.231464)
			(xy 84.605221 -401.21611) (xy 84.555642 -401.19347) (xy 84.50979 -401.164005) (xy 84.468599 -401.128314)
			(xy 84.432906 -401.087124) (xy 84.403438 -401.041273) (xy 84.380796 -400.991696) (xy 84.36544 -400.9394)
			(xy 84.357683 -400.885452) (xy 82.920173 -400.885452) (xy 82.920173 -400.885456) (xy 82.912415 -400.939413)
			(xy 82.897057 -400.991716) (xy 82.874411 -401.041302) (xy 82.844939 -401.087159) (xy 82.80924 -401.128355)
			(xy 82.768042 -401.164052) (xy 82.722182 -401.193521) (xy 82.672596 -401.216164) (xy 82.620291 -401.23152)
			(xy 82.566334 -401.239275) (xy 82.539078 -401.239736) (xy 81.675478 -401.239736) (xy 81.64823 -401.239192)
			(xy 81.594288 -401.231434) (xy 81.542 -401.216078) (xy 81.49243 -401.193437) (xy 81.446585 -401.163973)
			(xy 81.405401 -401.128284) (xy 81.369714 -401.087097) (xy 81.340252 -401.041251) (xy 81.317614 -400.991679)
			(xy 81.302262 -400.93939) (xy 81.294506 -400.885448) (xy 79.85685 -400.885448) (xy 79.85685 -400.885452)
			(xy 79.849094 -400.9394) (xy 79.83374 -400.991695) (xy 79.8111 -401.041274) (xy 79.781635 -401.087126)
			(xy 79.745945 -401.128318) (xy 79.704756 -401.164012) (xy 79.658907 -401.193482) (xy 79.609331 -401.216127)
			(xy 79.557037 -401.231486) (xy 79.503089 -401.239248) (xy 79.475838 -401.239736) (xy 78.612238 -401.239736)
			(xy 78.584985 -401.239219) (xy 78.531034 -401.231467) (xy 78.478736 -401.216116) (xy 78.429154 -401.193477)
			(xy 78.3833 -401.164012) (xy 78.342106 -401.128321) (xy 78.306411 -401.087131) (xy 78.276941 -401.041279)
			(xy 78.254298 -400.9917) (xy 78.238941 -400.939403) (xy 78.231183 -400.885453) (xy 76.793673 -400.885453)
			(xy 76.793673 -400.885455) (xy 76.785915 -400.93941) (xy 76.770558 -400.991712) (xy 76.747914 -401.041296)
			(xy 76.718443 -401.087153) (xy 76.682747 -401.128348) (xy 76.641551 -401.164045) (xy 76.595694 -401.193515)
			(xy 76.54611 -401.216159) (xy 76.493808 -401.231516) (xy 76.439853 -401.239273) (xy 76.412598 -401.239736)
			(xy 75.548998 -401.239736) (xy 75.521749 -401.239194) (xy 75.467805 -401.231437) (xy 75.415515 -401.216083)
			(xy 75.365942 -401.193444) (xy 75.320095 -401.16398) (xy 75.278908 -401.128291) (xy 75.243219 -401.087104)
			(xy 75.213755 -401.041257) (xy 75.191116 -400.991683) (xy 75.175762 -400.939393) (xy 75.168006 -400.885449)
			(xy 73.730473 -400.885449) (xy 73.730473 -400.885457) (xy 73.722714 -400.939415) (xy 73.707355 -400.991721)
			(xy 73.684708 -401.041307) (xy 73.655234 -401.087166) (xy 73.619533 -401.128363) (xy 73.578332 -401.164059)
			(xy 73.53247 -401.193528) (xy 73.482881 -401.21617) (xy 73.430574 -401.231523) (xy 73.376615 -401.239276)
			(xy 73.349358 -401.239736) (xy 72.485758 -401.239736) (xy 72.458511 -401.239191) (xy 72.404572 -401.23143)
			(xy 72.352286 -401.216073) (xy 72.302718 -401.193431) (xy 72.256876 -401.163965) (xy 72.215694 -401.128277)
			(xy 72.180009 -401.087091) (xy 72.150549 -401.041246) (xy 72.127913 -400.991675) (xy 72.112561 -400.939387)
			(xy 72.104806 -400.885447) (xy 70.66715 -400.885447) (xy 70.66715 -400.885452) (xy 70.659394 -400.939403)
			(xy 70.644038 -400.9917) (xy 70.621397 -401.041279) (xy 70.59193 -401.087132) (xy 70.556238 -401.128325)
			(xy 70.515047 -401.164019) (xy 70.469195 -401.193488) (xy 70.419617 -401.216132) (xy 70.36732 -401.23149)
			(xy 70.31337 -401.239249) (xy 70.286118 -401.239736) (xy 69.422518 -401.239736) (xy 69.395266 -401.239218)
			(xy 69.341317 -401.231464) (xy 69.289021 -401.21611) (xy 69.239442 -401.19347) (xy 69.19359 -401.164005)
			(xy 69.152399 -401.128314) (xy 69.116706 -401.087124) (xy 69.087238 -401.041273) (xy 69.064596 -400.991696)
			(xy 69.04924 -400.9394) (xy 69.041483 -400.885452) (xy 67.603973 -400.885452) (xy 67.603973 -400.885456)
			(xy 67.596215 -400.939413) (xy 67.580857 -400.991716) (xy 67.558211 -401.041302) (xy 67.528739 -401.087159)
			(xy 67.49304 -401.128355) (xy 67.451842 -401.164052) (xy 67.405982 -401.193521) (xy 67.356396 -401.216164)
			(xy 67.304091 -401.23152) (xy 67.250134 -401.239275) (xy 67.222878 -401.239736) (xy 66.359278 -401.239736)
			(xy 66.33203 -401.239192) (xy 66.278088 -401.231434) (xy 66.2258 -401.216078) (xy 66.17623 -401.193437)
			(xy 66.130385 -401.163973) (xy 66.089201 -401.128284) (xy 66.053514 -401.087097) (xy 66.024052 -401.041251)
			(xy 66.001414 -400.991679) (xy 65.986062 -400.93939) (xy 65.978306 -400.885448) (xy 64.54065 -400.885448)
			(xy 64.54065 -400.885452) (xy 64.532894 -400.9394) (xy 64.51754 -400.991695) (xy 64.4949 -401.041274)
			(xy 64.465435 -401.087126) (xy 64.429745 -401.128318) (xy 64.388556 -401.164012) (xy 64.342707 -401.193482)
			(xy 64.293131 -401.216127) (xy 64.240837 -401.231486) (xy 64.186889 -401.239248) (xy 64.159638 -401.239736)
			(xy 63.296038 -401.239736) (xy 63.268785 -401.239219) (xy 63.214834 -401.231467) (xy 63.162536 -401.216116)
			(xy 63.112954 -401.193477) (xy 63.0671 -401.164012) (xy 63.025906 -401.128321) (xy 62.990211 -401.087131)
			(xy 62.960741 -401.041279) (xy 62.938098 -400.9917) (xy 62.922741 -400.939403) (xy 62.914983 -400.885453)
			(xy 61.477473 -400.885453) (xy 61.477473 -400.885455) (xy 61.469715 -400.93941) (xy 61.454358 -400.991712)
			(xy 61.431714 -401.041296) (xy 61.402243 -401.087153) (xy 61.366547 -401.128348) (xy 61.325351 -401.164045)
			(xy 61.279494 -401.193515) (xy 61.22991 -401.216159) (xy 61.177608 -401.231516) (xy 61.123653 -401.239273)
			(xy 61.096398 -401.239736) (xy 60.232798 -401.239736) (xy 60.205549 -401.239194) (xy 60.151605 -401.231437)
			(xy 60.099315 -401.216083) (xy 60.049742 -401.193444) (xy 60.003895 -401.16398) (xy 59.962708 -401.128291)
			(xy 59.927019 -401.087104) (xy 59.897555 -401.041257) (xy 59.874916 -400.991683) (xy 59.859562 -400.939393)
			(xy 59.851806 -400.885449) (xy 58.414273 -400.885449) (xy 58.414273 -400.885457) (xy 58.406514 -400.939415)
			(xy 58.391155 -400.991721) (xy 58.368508 -401.041307) (xy 58.339034 -401.087166) (xy 58.303333 -401.128363)
			(xy 58.262132 -401.164059) (xy 58.21627 -401.193528) (xy 58.166681 -401.21617) (xy 58.114374 -401.231523)
			(xy 58.060415 -401.239276) (xy 58.033158 -401.239736) (xy 57.169558 -401.239736) (xy 57.142311 -401.239191)
			(xy 57.088372 -401.23143) (xy 57.036086 -401.216073) (xy 56.986518 -401.193431) (xy 56.940676 -401.163965)
			(xy 56.899494 -401.128277) (xy 56.863809 -401.087091) (xy 56.834349 -401.041246) (xy 56.811713 -400.991675)
			(xy 56.796361 -400.939387) (xy 56.788606 -400.885447) (xy 55.35095 -400.885447) (xy 55.35095 -400.885452)
			(xy 55.343194 -400.939403) (xy 55.327838 -400.9917) (xy 55.305197 -401.041279) (xy 55.27573 -401.087132)
			(xy 55.240038 -401.128325) (xy 55.198847 -401.164019) (xy 55.152995 -401.193488) (xy 55.103417 -401.216132)
			(xy 55.05112 -401.23149) (xy 54.99717 -401.239249) (xy 54.969918 -401.239736) (xy 54.106318 -401.239736)
			(xy 54.079066 -401.239218) (xy 54.025117 -401.231464) (xy 53.972821 -401.21611) (xy 53.923242 -401.19347)
			(xy 53.87739 -401.164005) (xy 53.836199 -401.128314) (xy 53.800506 -401.087124) (xy 53.771038 -401.041273)
			(xy 53.748396 -400.991696) (xy 53.73304 -400.9394) (xy 53.725283 -400.885452) (xy 52.287773 -400.885452)
			(xy 52.287773 -400.885456) (xy 52.280015 -400.939413) (xy 52.264657 -400.991716) (xy 52.242011 -401.041302)
			(xy 52.212539 -401.087159) (xy 52.17684 -401.128355) (xy 52.135642 -401.164052) (xy 52.089782 -401.193521)
			(xy 52.040196 -401.216164) (xy 51.987891 -401.23152) (xy 51.933934 -401.239275) (xy 51.906678 -401.239736)
			(xy 51.043078 -401.239736) (xy 51.01583 -401.239192) (xy 50.961888 -401.231434) (xy 50.9096 -401.216078)
			(xy 50.86003 -401.193437) (xy 50.814185 -401.163973) (xy 50.773001 -401.128284) (xy 50.737314 -401.087097)
			(xy 50.707852 -401.041251) (xy 50.685214 -400.991679) (xy 50.669862 -400.93939) (xy 50.662106 -400.885448)
			(xy 49.22445 -400.885448) (xy 49.22445 -400.885452) (xy 49.216694 -400.9394) (xy 49.20134 -400.991695)
			(xy 49.1787 -401.041274) (xy 49.149235 -401.087126) (xy 49.113545 -401.128318) (xy 49.072356 -401.164012)
			(xy 49.026507 -401.193482) (xy 48.976931 -401.216127) (xy 48.924637 -401.231486) (xy 48.870689 -401.239248)
			(xy 48.843438 -401.239736) (xy 47.979838 -401.239736) (xy 47.952585 -401.239219) (xy 47.898634 -401.231467)
			(xy 47.846336 -401.216116) (xy 47.796754 -401.193477) (xy 47.7509 -401.164012) (xy 47.709706 -401.128321)
			(xy 47.674011 -401.087131) (xy 47.644541 -401.041279) (xy 47.621898 -400.9917) (xy 47.606541 -400.939403)
			(xy 47.598783 -400.885453) (xy 2.509012 -400.885453) (xy 2.509012 -402.10994) (xy 239.42294 -402.10994)
			(xy 239.42294 -397.53286) (xy 239.423521 -397.5079) (xy 239.433246 -397.458937) (xy 239.452353 -397.412819)
			(xy 239.480105 -397.371324) (xy 239.497362 -397.353282) (xy 239.885982 -396.964662) (xy 239.904032 -396.947415)
			(xy 239.945531 -396.919673) (xy 239.991645 -396.900562) (xy 240.040601 -396.890815) (xy 240.06556 -396.89024)
			(xy 280.24074 -396.89024) (xy 280.2657 -396.890821) (xy 280.314663 -396.900546) (xy 280.360781 -396.919653)
			(xy 280.402276 -396.947405) (xy 280.420318 -396.964662) (xy 280.689558 -397.233902) (xy 280.706818 -397.25194)
			(xy 280.734556 -397.293444) (xy 280.753664 -397.339561) (xy 280.763407 -397.38852) (xy 280.76398 -397.41348)
			(xy 280.76398 -398.65534) (xy 457.185003 -398.65534) (xy 457.185003 -398.5262) (xy 457.192953 -398.397305)
			(xy 457.208823 -398.269145) (xy 457.232552 -398.142204) (xy 457.264051 -398.016965) (xy 457.3032 -397.893902)
			(xy 457.349851 -397.773483) (xy 457.403826 -397.656164) (xy 457.464921 -397.54239) (xy 457.532904 -397.432593)
			(xy 457.607518 -397.32719) (xy 457.688479 -397.22658) (xy 457.775479 -397.131145) (xy 457.86819 -397.041246)
			(xy 457.96626 -396.957225) (xy 458.069315 -396.879401) (xy 458.176966 -396.808069) (xy 458.288805 -396.743499)
			(xy 458.404406 -396.685937) (xy 458.523331 -396.6356) (xy 458.64513 -396.59268) (xy 458.76934 -396.557339)
			(xy 458.895489 -396.529712) (xy 459.023101 -396.509903) (xy 459.15169 -396.497987) (xy 459.280768 -396.494011)
			(xy 459.409846 -396.497987) (xy 459.538435 -396.509903) (xy 459.666047 -396.529712) (xy 459.792196 -396.557339)
			(xy 459.916406 -396.59268) (xy 460.038205 -396.6356) (xy 460.15713 -396.685937) (xy 460.272731 -396.743499)
			(xy 460.38457 -396.808069) (xy 460.492221 -396.879401) (xy 460.595276 -396.957225) (xy 460.693346 -397.041246)
			(xy 460.786057 -397.131145) (xy 460.873057 -397.22658) (xy 460.954018 -397.32719) (xy 461.028632 -397.432593)
			(xy 461.096615 -397.54239) (xy 461.15771 -397.656164) (xy 461.211685 -397.773483) (xy 461.258336 -397.893902)
			(xy 461.297485 -398.016965) (xy 461.328984 -398.142204) (xy 461.352713 -398.269145) (xy 461.368583 -398.397305)
			(xy 461.376533 -398.5262) (xy 461.37703 -398.59077) (xy 461.376533 -398.65534) (xy 461.368583 -398.784235)
			(xy 461.352713 -398.912395) (xy 461.328984 -399.039336) (xy 461.297485 -399.164575) (xy 461.258336 -399.287638)
			(xy 461.211685 -399.408057) (xy 461.15771 -399.525376) (xy 461.096615 -399.63915) (xy 461.028632 -399.748947)
			(xy 460.954018 -399.85435) (xy 460.873057 -399.95496) (xy 460.786057 -400.050395) (xy 460.693346 -400.140294)
			(xy 460.595276 -400.224315) (xy 460.492221 -400.302139) (xy 460.38457 -400.373471) (xy 460.272731 -400.438041)
			(xy 460.15713 -400.495603) (xy 460.038205 -400.54594) (xy 459.916406 -400.58886) (xy 459.792196 -400.624201)
			(xy 459.666047 -400.651828) (xy 459.538435 -400.671637) (xy 459.409846 -400.683553) (xy 459.280768 -400.68753)
			(xy 459.15169 -400.683553) (xy 459.023101 -400.671637) (xy 458.895489 -400.651828) (xy 458.76934 -400.624201)
			(xy 458.64513 -400.58886) (xy 458.523331 -400.54594) (xy 458.404406 -400.495603) (xy 458.288805 -400.438041)
			(xy 458.176966 -400.373471) (xy 458.069315 -400.302139) (xy 457.96626 -400.224315) (xy 457.86819 -400.140294)
			(xy 457.775479 -400.050395) (xy 457.688479 -399.95496) (xy 457.607518 -399.85435) (xy 457.532904 -399.748947)
			(xy 457.464921 -399.63915) (xy 457.403826 -399.525376) (xy 457.349851 -399.408057) (xy 457.3032 -399.287638)
			(xy 457.264051 -399.164575) (xy 457.232552 -399.039336) (xy 457.208823 -398.912395) (xy 457.192953 -398.784235)
			(xy 457.185003 -398.65534) (xy 280.76398 -398.65534) (xy 280.76398 -399.9835) (xy 289.606441 -399.9835)
			(xy 289.610455 -399.919698) (xy 289.622434 -399.856902) (xy 289.642189 -399.796103) (xy 289.669408 -399.73826)
			(xy 289.703662 -399.684283) (xy 289.744411 -399.635026) (xy 289.791013 -399.591264) (xy 289.842731 -399.553688)
			(xy 289.898752 -399.52289) (xy 289.958191 -399.499357) (xy 290.02011 -399.483458) (xy 290.083534 -399.475446)
			(xy 290.115498 -399.474944) (xy 290.115752 -399.474944) (xy 290.147498 -399.475464) (xy 290.210494 -399.483393)
			(xy 290.272014 -399.499096) (xy 290.331102 -399.52233) (xy 290.386842 -399.552733) (xy 290.438367 -399.589834)
			(xy 290.461954 -399.611088) (xy 290.469217 -399.617272) (xy 290.486967 -399.624223) (xy 290.506029 -399.624223)
			(xy 290.523779 -399.617272) (xy 290.531042 -399.611088) (xy 290.554631 -399.589832) (xy 290.60614 -399.5527)
			(xy 290.661874 -399.522276) (xy 290.720965 -399.499035) (xy 290.782492 -399.483338) (xy 290.845495 -399.475431)
			(xy 290.877244 -399.474944) (xy 290.877498 -399.474944) (xy 290.909457 -399.475521) (xy 290.972872 -399.483532)
			(xy 291.034783 -399.499427) (xy 291.094213 -399.522957) (xy 291.150226 -399.55375) (xy 291.201937 -399.591321)
			(xy 291.248532 -399.635076) (xy 291.289276 -399.684326) (xy 291.323525 -399.738295) (xy 291.350741 -399.79613)
			(xy 291.370493 -399.856921) (xy 291.38247 -399.919707) (xy 291.386484 -399.9835) (xy 292.146441 -399.9835)
			(xy 292.150455 -399.919698) (xy 292.162434 -399.856902) (xy 292.182189 -399.796103) (xy 292.209408 -399.73826)
			(xy 292.243662 -399.684283) (xy 292.284411 -399.635026) (xy 292.331013 -399.591264) (xy 292.382731 -399.553688)
			(xy 292.438752 -399.52289) (xy 292.498191 -399.499357) (xy 292.56011 -399.483458) (xy 292.623534 -399.475446)
			(xy 292.655498 -399.474944) (xy 292.655752 -399.474944) (xy 292.687498 -399.475464) (xy 292.750494 -399.483393)
			(xy 292.812014 -399.499096) (xy 292.871102 -399.52233) (xy 292.926842 -399.552733) (xy 292.978367 -399.589834)
			(xy 293.001954 -399.611088) (xy 293.009217 -399.617272) (xy 293.026967 -399.624223) (xy 293.046029 -399.624223)
			(xy 293.063779 -399.617272) (xy 293.071042 -399.611088) (xy 293.094631 -399.589832) (xy 293.14614 -399.5527)
			(xy 293.201874 -399.522276) (xy 293.260965 -399.499035) (xy 293.322492 -399.483338) (xy 293.385495 -399.475431)
			(xy 293.417244 -399.474944) (xy 293.417498 -399.474944) (xy 293.449457 -399.475521) (xy 293.512872 -399.483532)
			(xy 293.574783 -399.499427) (xy 293.634213 -399.522957) (xy 293.690226 -399.55375) (xy 293.741937 -399.591321)
			(xy 293.788532 -399.635076) (xy 293.829276 -399.684326) (xy 293.863525 -399.738295) (xy 293.890741 -399.79613)
			(xy 293.910493 -399.856921) (xy 293.92247 -399.919707) (xy 293.926484 -399.9835) (xy 294.53602 -399.9835)
			(xy 294.540035 -399.919693) (xy 294.552015 -399.856892) (xy 294.571773 -399.796089) (xy 294.598995 -399.738241)
			(xy 294.633253 -399.684261) (xy 294.674007 -399.635001) (xy 294.720613 -399.591237) (xy 294.772338 -399.55366)
			(xy 294.828364 -399.522862) (xy 294.887809 -399.499329) (xy 294.949734 -399.483433) (xy 295.013163 -399.475423)
			(xy 295.04513 -399.474944) (xy 295.045384 -399.474944) (xy 295.077131 -399.475444) (xy 295.140127 -399.483377)
			(xy 295.201647 -399.499084) (xy 295.260736 -399.522322) (xy 295.316476 -399.552728) (xy 295.368 -399.589832)
			(xy 295.391586 -399.611088) (xy 295.398849 -399.617272) (xy 295.416599 -399.624223) (xy 295.435661 -399.624223)
			(xy 295.453411 -399.617272) (xy 295.460674 -399.611088) (xy 295.48425 -399.589817) (xy 295.535761 -399.552686)
			(xy 295.591498 -399.522265) (xy 295.650592 -399.499026) (xy 295.712121 -399.483332) (xy 295.775126 -399.475429)
			(xy 295.806876 -399.474944) (xy 295.80713 -399.474944) (xy 295.839087 -399.475544) (xy 295.902496 -399.483558)
			(xy 295.964401 -399.499455) (xy 296.023825 -399.522986) (xy 296.079832 -399.553779) (xy 296.131538 -399.591348)
			(xy 296.178128 -399.635102) (xy 296.218866 -399.684349) (xy 296.253112 -399.738314) (xy 296.280324 -399.796145)
			(xy 296.300074 -399.856931) (xy 296.312049 -399.919712) (xy 296.316063 -399.9835) (xy 297.07602 -399.9835)
			(xy 297.080035 -399.919693) (xy 297.092015 -399.856892) (xy 297.111773 -399.796089) (xy 297.138995 -399.738241)
			(xy 297.173253 -399.684261) (xy 297.214007 -399.635001) (xy 297.260613 -399.591237) (xy 297.312338 -399.55366)
			(xy 297.368364 -399.522862) (xy 297.427809 -399.499329) (xy 297.489734 -399.483433) (xy 297.553163 -399.475423)
			(xy 297.58513 -399.474944) (xy 297.585384 -399.474944) (xy 297.617131 -399.475444) (xy 297.680127 -399.483377)
			(xy 297.741647 -399.499084) (xy 297.800736 -399.522322) (xy 297.856476 -399.552728) (xy 297.908 -399.589832)
			(xy 297.931586 -399.611088) (xy 297.938849 -399.617272) (xy 297.956599 -399.624223) (xy 297.975661 -399.624223)
			(xy 297.993411 -399.617272) (xy 298.000674 -399.611088) (xy 298.02425 -399.589817) (xy 298.075761 -399.552686)
			(xy 298.131498 -399.522265) (xy 298.190592 -399.499026) (xy 298.252121 -399.483332) (xy 298.315126 -399.475429)
			(xy 298.346876 -399.474944) (xy 298.34713 -399.474944) (xy 298.379087 -399.475544) (xy 298.442496 -399.483558)
			(xy 298.504401 -399.499455) (xy 298.563825 -399.522986) (xy 298.619832 -399.553779) (xy 298.671538 -399.591348)
			(xy 298.718128 -399.635102) (xy 298.758866 -399.684349) (xy 298.793112 -399.738314) (xy 298.820324 -399.796145)
			(xy 298.840074 -399.856931) (xy 298.852049 -399.919712) (xy 298.856063 -399.9835) (xy 298.852049 -400.047288)
			(xy 298.840074 -400.110069) (xy 298.820324 -400.170855) (xy 298.793112 -400.228686) (xy 298.758866 -400.282651)
			(xy 298.718128 -400.331898) (xy 298.671538 -400.375652) (xy 298.619832 -400.413221) (xy 298.563825 -400.444014)
			(xy 298.504401 -400.467545) (xy 298.442496 -400.483442) (xy 298.379087 -400.491456) (xy 298.34713 -400.49196)
			(xy 298.346876 -400.49196) (xy 298.315131 -400.491422) (xy 298.252136 -400.483497) (xy 298.190616 -400.467797)
			(xy 298.131527 -400.444566) (xy 298.075787 -400.414166) (xy 298.024261 -400.377069) (xy 298.000674 -400.355816)
			(xy 297.993411 -400.349632) (xy 297.975661 -400.342681) (xy 297.956599 -400.342681) (xy 297.938849 -400.349632)
			(xy 297.931586 -400.355816) (xy 297.908028 -400.377107) (xy 297.856512 -400.414235) (xy 297.800771 -400.444654)
			(xy 297.741674 -400.467889) (xy 297.680142 -400.483579) (xy 297.617135 -400.491478) (xy 297.585384 -400.49196)
			(xy 297.58513 -400.49196) (xy 297.553163 -400.491577) (xy 297.489734 -400.483567) (xy 297.427809 -400.467671)
			(xy 297.368364 -400.444138) (xy 297.312338 -400.41334) (xy 297.260613 -400.375763) (xy 297.214007 -400.331999)
			(xy 297.173253 -400.282739) (xy 297.138995 -400.228759) (xy 297.111773 -400.170911) (xy 297.092015 -400.110108)
			(xy 297.080035 -400.047307) (xy 297.07602 -399.9835) (xy 296.316063 -399.9835) (xy 296.312049 -400.047288)
			(xy 296.300074 -400.110069) (xy 296.280324 -400.170855) (xy 296.253112 -400.228686) (xy 296.218866 -400.282651)
			(xy 296.178128 -400.331898) (xy 296.131538 -400.375652) (xy 296.079832 -400.413221) (xy 296.023825 -400.444014)
			(xy 295.964401 -400.467545) (xy 295.902496 -400.483442) (xy 295.839087 -400.491456) (xy 295.80713 -400.49196)
			(xy 295.806876 -400.49196) (xy 295.775131 -400.491422) (xy 295.712136 -400.483497) (xy 295.650616 -400.467797)
			(xy 295.591527 -400.444566) (xy 295.535787 -400.414166) (xy 295.484261 -400.377069) (xy 295.460674 -400.355816)
			(xy 295.453411 -400.349632) (xy 295.435661 -400.342681) (xy 295.416599 -400.342681) (xy 295.398849 -400.349632)
			(xy 295.391586 -400.355816) (xy 295.368028 -400.377107) (xy 295.316512 -400.414235) (xy 295.260771 -400.444654)
			(xy 295.201674 -400.467889) (xy 295.140142 -400.483579) (xy 295.077135 -400.491478) (xy 295.045384 -400.49196)
			(xy 295.04513 -400.49196) (xy 295.013163 -400.491577) (xy 294.949734 -400.483567) (xy 294.887809 -400.467671)
			(xy 294.828364 -400.444138) (xy 294.772338 -400.41334) (xy 294.720613 -400.375763) (xy 294.674007 -400.331999)
			(xy 294.633253 -400.282739) (xy 294.598995 -400.228759) (xy 294.571773 -400.170911) (xy 294.552015 -400.110108)
			(xy 294.540035 -400.047307) (xy 294.53602 -399.9835) (xy 293.926484 -399.9835) (xy 293.92247 -400.047293)
			(xy 293.910493 -400.110079) (xy 293.890741 -400.17087) (xy 293.863525 -400.228705) (xy 293.829276 -400.282674)
			(xy 293.788532 -400.331924) (xy 293.741937 -400.375679) (xy 293.690226 -400.41325) (xy 293.634213 -400.444043)
			(xy 293.574783 -400.467573) (xy 293.512872 -400.483468) (xy 293.449457 -400.491479) (xy 293.417498 -400.49196)
			(xy 293.417244 -400.49196) (xy 293.385498 -400.491442) (xy 293.322502 -400.483512) (xy 293.260982 -400.467809)
			(xy 293.201894 -400.444575) (xy 293.146154 -400.414171) (xy 293.094629 -400.37707) (xy 293.071042 -400.355816)
			(xy 293.063779 -400.349632) (xy 293.046029 -400.342681) (xy 293.026967 -400.342681) (xy 293.009217 -400.349632)
			(xy 293.001954 -400.355816) (xy 292.978367 -400.377074) (xy 292.926858 -400.414206) (xy 292.871123 -400.44463)
			(xy 292.812032 -400.467871) (xy 292.750504 -400.483567) (xy 292.687501 -400.491474) (xy 292.655752 -400.49196)
			(xy 292.655498 -400.49196) (xy 292.623534 -400.491554) (xy 292.56011 -400.483542) (xy 292.498191 -400.467643)
			(xy 292.438752 -400.44411) (xy 292.382731 -400.413312) (xy 292.331013 -400.375736) (xy 292.284411 -400.331974)
			(xy 292.243662 -400.282717) (xy 292.209408 -400.22874) (xy 292.182189 -400.170897) (xy 292.162434 -400.110098)
			(xy 292.150455 -400.047302) (xy 292.146441 -399.9835) (xy 291.386484 -399.9835) (xy 291.38247 -400.047293)
			(xy 291.370493 -400.110079) (xy 291.350741 -400.17087) (xy 291.323525 -400.228705) (xy 291.289276 -400.282674)
			(xy 291.248532 -400.331924) (xy 291.201937 -400.375679) (xy 291.150226 -400.41325) (xy 291.094213 -400.444043)
			(xy 291.034783 -400.467573) (xy 290.972872 -400.483468) (xy 290.909457 -400.491479) (xy 290.877498 -400.49196)
			(xy 290.877244 -400.49196) (xy 290.845498 -400.491442) (xy 290.782502 -400.483512) (xy 290.720982 -400.467809)
			(xy 290.661894 -400.444575) (xy 290.606154 -400.414171) (xy 290.554629 -400.37707) (xy 290.531042 -400.355816)
			(xy 290.523779 -400.349632) (xy 290.506029 -400.342681) (xy 290.486967 -400.342681) (xy 290.469217 -400.349632)
			(xy 290.461954 -400.355816) (xy 290.438367 -400.377074) (xy 290.386858 -400.414206) (xy 290.331123 -400.44463)
			(xy 290.272032 -400.467871) (xy 290.210504 -400.483567) (xy 290.147501 -400.491474) (xy 290.115752 -400.49196)
			(xy 290.115498 -400.49196) (xy 290.083534 -400.491554) (xy 290.02011 -400.483542) (xy 289.958191 -400.467643)
			(xy 289.898752 -400.44411) (xy 289.842731 -400.413312) (xy 289.791013 -400.375736) (xy 289.744411 -400.331974)
			(xy 289.703662 -400.282717) (xy 289.669408 -400.22874) (xy 289.642189 -400.170897) (xy 289.622434 -400.110098)
			(xy 289.610455 -400.047302) (xy 289.606441 -399.9835) (xy 280.76398 -399.9835) (xy 280.76398 -400.885449)
			(xy 303.599106 -400.885449) (xy 303.599106 -400.830951) (xy 303.606862 -400.777009) (xy 303.622215 -400.724719)
			(xy 303.644854 -400.675146) (xy 303.674317 -400.6293) (xy 303.710004 -400.588113) (xy 303.75119 -400.552424)
			(xy 303.797036 -400.52296) (xy 303.846608 -400.500319) (xy 303.898897 -400.484964) (xy 303.952839 -400.477207)
			(xy 303.980088 -400.47672) (xy 304.843688 -400.47672) (xy 304.870943 -400.477126) (xy 304.9249 -400.484882)
			(xy 304.977203 -400.500238) (xy 305.026788 -400.522882) (xy 305.072646 -400.552352) (xy 305.113843 -400.588048)
			(xy 305.149541 -400.629244) (xy 305.179012 -400.675101) (xy 305.201657 -400.724686) (xy 305.217015 -400.776989)
			(xy 305.224773 -400.830945) (xy 305.224773 -400.885452) (xy 306.662283 -400.885452) (xy 306.662283 -400.830948)
			(xy 306.67004 -400.776998) (xy 306.685397 -400.724702) (xy 306.70804 -400.675124) (xy 306.737508 -400.629273)
			(xy 306.773202 -400.588082) (xy 306.814395 -400.552391) (xy 306.860248 -400.522926) (xy 306.909828 -400.500287)
			(xy 306.962126 -400.484935) (xy 307.016076 -400.477181) (xy 307.043328 -400.47672) (xy 307.906928 -400.47672)
			(xy 307.93418 -400.477152) (xy 307.988129 -400.484912) (xy 308.040424 -400.500271) (xy 308.090001 -400.522915)
			(xy 308.135851 -400.552384) (xy 308.177041 -400.588079) (xy 308.212732 -400.629271) (xy 308.242198 -400.675123)
			(xy 308.264839 -400.724702) (xy 308.280194 -400.776999) (xy 308.28795 -400.830948) (xy 308.28795 -400.885448)
			(xy 309.725606 -400.885448) (xy 309.725606 -400.830952) (xy 309.733361 -400.777011) (xy 309.748714 -400.724723)
			(xy 309.771351 -400.675152) (xy 309.800812 -400.629306) (xy 309.836497 -400.58812) (xy 309.877681 -400.552431)
			(xy 309.923524 -400.522966) (xy 309.973093 -400.500325) (xy 310.02538 -400.484968) (xy 310.07932 -400.477208)
			(xy 310.106568 -400.47672) (xy 310.970168 -400.47672) (xy 310.997424 -400.477125) (xy 311.051383 -400.484879)
			(xy 311.103688 -400.500233) (xy 311.153276 -400.522875) (xy 311.199137 -400.552345) (xy 311.240336 -400.588041)
			(xy 311.276036 -400.629238) (xy 311.305509 -400.675096) (xy 311.328156 -400.724682) (xy 311.343515 -400.776986)
			(xy 311.351273 -400.830944) (xy 311.351273 -400.885451) (xy 312.788783 -400.885451) (xy 312.788783 -400.830949)
			(xy 312.79654 -400.777001) (xy 312.811895 -400.724706) (xy 312.834537 -400.675129) (xy 312.864003 -400.629279)
			(xy 312.899695 -400.588089) (xy 312.940886 -400.552398) (xy 312.986736 -400.522933) (xy 313.036314 -400.500292)
			(xy 313.088609 -400.484938) (xy 313.142557 -400.477183) (xy 313.169808 -400.47672) (xy 314.033408 -400.47672)
			(xy 314.060661 -400.47715) (xy 314.114612 -400.484908) (xy 314.166909 -400.500265) (xy 314.216489 -400.522909)
			(xy 314.262342 -400.552377) (xy 314.303534 -400.588071) (xy 314.339228 -400.629264) (xy 314.368695 -400.675118)
			(xy 314.391337 -400.724698) (xy 314.406693 -400.776996) (xy 314.41445 -400.830947) (xy 314.41445 -400.885453)
			(xy 315.851983 -400.885453) (xy 315.851983 -400.830947) (xy 315.859741 -400.776996) (xy 315.875098 -400.724698)
			(xy 315.897743 -400.675118) (xy 315.927213 -400.629266) (xy 315.962909 -400.588075) (xy 316.004105 -400.552384)
			(xy 316.04996 -400.52292) (xy 316.099543 -400.500282) (xy 316.151843 -400.484931) (xy 316.205795 -400.47718)
			(xy 316.233048 -400.47672) (xy 317.096648 -400.47672) (xy 317.123899 -400.477153) (xy 317.177846 -400.484916)
			(xy 317.230138 -400.500276) (xy 317.279713 -400.522922) (xy 317.325561 -400.552391) (xy 317.366748 -400.588086)
			(xy 317.402437 -400.629278) (xy 317.431901 -400.675129) (xy 317.454541 -400.724707) (xy 317.469894 -400.777001)
			(xy 317.47765 -400.830949) (xy 317.47765 -400.885449) (xy 318.915306 -400.885449) (xy 318.915306 -400.830951)
			(xy 318.923062 -400.777009) (xy 318.938415 -400.724719) (xy 318.961054 -400.675146) (xy 318.990517 -400.6293)
			(xy 319.026204 -400.588113) (xy 319.06739 -400.552424) (xy 319.113236 -400.52296) (xy 319.162808 -400.500319)
			(xy 319.215097 -400.484964) (xy 319.269039 -400.477207) (xy 319.296288 -400.47672) (xy 320.159888 -400.47672)
			(xy 320.187143 -400.477126) (xy 320.2411 -400.484882) (xy 320.293403 -400.500238) (xy 320.342988 -400.522882)
			(xy 320.388846 -400.552352) (xy 320.430043 -400.588048) (xy 320.465741 -400.629244) (xy 320.495212 -400.675101)
			(xy 320.517857 -400.724686) (xy 320.533215 -400.776989) (xy 320.540973 -400.830945) (xy 320.540973 -400.885452)
			(xy 321.978483 -400.885452) (xy 321.978483 -400.830948) (xy 321.98624 -400.776998) (xy 322.001597 -400.724702)
			(xy 322.02424 -400.675124) (xy 322.053708 -400.629273) (xy 322.089402 -400.588082) (xy 322.130595 -400.552391)
			(xy 322.176448 -400.522926) (xy 322.226028 -400.500287) (xy 322.278326 -400.484935) (xy 322.332276 -400.477181)
			(xy 322.359528 -400.47672) (xy 323.223128 -400.47672) (xy 323.25038 -400.477152) (xy 323.304329 -400.484912)
			(xy 323.356624 -400.500271) (xy 323.406201 -400.522915) (xy 323.452051 -400.552384) (xy 323.493241 -400.588079)
			(xy 323.528932 -400.629271) (xy 323.558398 -400.675123) (xy 323.581039 -400.724702) (xy 323.596394 -400.776999)
			(xy 323.60415 -400.830948) (xy 323.60415 -400.885448) (xy 325.041806 -400.885448) (xy 325.041806 -400.830952)
			(xy 325.049561 -400.777011) (xy 325.064914 -400.724723) (xy 325.087551 -400.675152) (xy 325.117012 -400.629306)
			(xy 325.152697 -400.58812) (xy 325.193881 -400.552431) (xy 325.239724 -400.522966) (xy 325.289293 -400.500325)
			(xy 325.34158 -400.484968) (xy 325.39552 -400.477208) (xy 325.422768 -400.47672) (xy 326.286368 -400.47672)
			(xy 326.313624 -400.477125) (xy 326.367583 -400.484879) (xy 326.419888 -400.500233) (xy 326.469476 -400.522875)
			(xy 326.515337 -400.552345) (xy 326.556536 -400.588041) (xy 326.592236 -400.629238) (xy 326.621709 -400.675096)
			(xy 326.644356 -400.724682) (xy 326.659715 -400.776986) (xy 326.667473 -400.830944) (xy 326.667473 -400.885451)
			(xy 328.104983 -400.885451) (xy 328.104983 -400.830949) (xy 328.11274 -400.777001) (xy 328.128095 -400.724706)
			(xy 328.150737 -400.675129) (xy 328.180203 -400.629279) (xy 328.215895 -400.588089) (xy 328.257086 -400.552398)
			(xy 328.302936 -400.522933) (xy 328.352514 -400.500292) (xy 328.404809 -400.484938) (xy 328.458757 -400.477183)
			(xy 328.486008 -400.47672) (xy 329.349608 -400.47672) (xy 329.376861 -400.47715) (xy 329.430812 -400.484908)
			(xy 329.483109 -400.500265) (xy 329.532689 -400.522909) (xy 329.578542 -400.552377) (xy 329.619734 -400.588071)
			(xy 329.655428 -400.629264) (xy 329.684895 -400.675118) (xy 329.707537 -400.724698) (xy 329.722893 -400.776996)
			(xy 329.73065 -400.830947) (xy 329.73065 -400.885453) (xy 331.168183 -400.885453) (xy 331.168183 -400.830947)
			(xy 331.175941 -400.776996) (xy 331.191298 -400.724698) (xy 331.213943 -400.675118) (xy 331.243413 -400.629266)
			(xy 331.279109 -400.588075) (xy 331.320305 -400.552384) (xy 331.36616 -400.52292) (xy 331.415743 -400.500282)
			(xy 331.468043 -400.484931) (xy 331.521995 -400.47718) (xy 331.549248 -400.47672) (xy 332.412848 -400.47672)
			(xy 332.440099 -400.477153) (xy 332.494046 -400.484916) (xy 332.546338 -400.500276) (xy 332.595913 -400.522922)
			(xy 332.641761 -400.552391) (xy 332.682948 -400.588086) (xy 332.718637 -400.629278) (xy 332.748101 -400.675129)
			(xy 332.770741 -400.724707) (xy 332.786094 -400.777001) (xy 332.79385 -400.830949) (xy 332.79385 -400.885449)
			(xy 334.231506 -400.885449) (xy 334.231506 -400.830951) (xy 334.239262 -400.777009) (xy 334.254615 -400.724719)
			(xy 334.277254 -400.675146) (xy 334.306717 -400.6293) (xy 334.342404 -400.588113) (xy 334.38359 -400.552424)
			(xy 334.429436 -400.52296) (xy 334.479008 -400.500319) (xy 334.531297 -400.484964) (xy 334.585239 -400.477207)
			(xy 334.612488 -400.47672) (xy 335.476088 -400.47672) (xy 335.503343 -400.477126) (xy 335.5573 -400.484882)
			(xy 335.609603 -400.500238) (xy 335.659188 -400.522882) (xy 335.705046 -400.552352) (xy 335.746243 -400.588048)
			(xy 335.781941 -400.629244) (xy 335.811412 -400.675101) (xy 335.834057 -400.724686) (xy 335.849415 -400.776989)
			(xy 335.857173 -400.830945) (xy 335.857173 -400.885452) (xy 337.294683 -400.885452) (xy 337.294683 -400.830948)
			(xy 337.30244 -400.776998) (xy 337.317797 -400.724702) (xy 337.34044 -400.675124) (xy 337.369908 -400.629273)
			(xy 337.405602 -400.588082) (xy 337.446795 -400.552391) (xy 337.492648 -400.522926) (xy 337.542228 -400.500287)
			(xy 337.594526 -400.484935) (xy 337.648476 -400.477181) (xy 337.675728 -400.47672) (xy 338.539328 -400.47672)
			(xy 338.56658 -400.477152) (xy 338.620529 -400.484912) (xy 338.672824 -400.500271) (xy 338.722401 -400.522915)
			(xy 338.768251 -400.552384) (xy 338.809441 -400.588079) (xy 338.845132 -400.629271) (xy 338.874598 -400.675123)
			(xy 338.897239 -400.724702) (xy 338.912594 -400.776999) (xy 338.92035 -400.830948) (xy 338.92035 -400.885448)
			(xy 340.358006 -400.885448) (xy 340.358006 -400.830952) (xy 340.365761 -400.777011) (xy 340.381114 -400.724723)
			(xy 340.403751 -400.675152) (xy 340.433212 -400.629306) (xy 340.468897 -400.58812) (xy 340.510081 -400.552431)
			(xy 340.555924 -400.522966) (xy 340.605493 -400.500325) (xy 340.65778 -400.484968) (xy 340.71172 -400.477208)
			(xy 340.738968 -400.47672) (xy 341.602568 -400.47672) (xy 341.629824 -400.477125) (xy 341.683783 -400.484879)
			(xy 341.736088 -400.500233) (xy 341.785676 -400.522875) (xy 341.831537 -400.552345) (xy 341.872736 -400.588041)
			(xy 341.908436 -400.629238) (xy 341.937909 -400.675096) (xy 341.960556 -400.724682) (xy 341.975915 -400.776986)
			(xy 341.983673 -400.830944) (xy 341.983673 -400.885451) (xy 343.421183 -400.885451) (xy 343.421183 -400.830949)
			(xy 343.42894 -400.777001) (xy 343.444295 -400.724706) (xy 343.466937 -400.675129) (xy 343.496403 -400.629279)
			(xy 343.532095 -400.588089) (xy 343.573286 -400.552398) (xy 343.619136 -400.522933) (xy 343.668714 -400.500292)
			(xy 343.721009 -400.484938) (xy 343.774957 -400.477183) (xy 343.802208 -400.47672) (xy 344.665808 -400.47672)
			(xy 344.693061 -400.47715) (xy 344.747012 -400.484908) (xy 344.799309 -400.500265) (xy 344.848889 -400.522909)
			(xy 344.894742 -400.552377) (xy 344.935934 -400.588071) (xy 344.971628 -400.629264) (xy 345.001095 -400.675118)
			(xy 345.023737 -400.724698) (xy 345.039093 -400.776996) (xy 345.04685 -400.830947) (xy 345.04685 -400.885453)
			(xy 346.484383 -400.885453) (xy 346.484383 -400.830947) (xy 346.492141 -400.776996) (xy 346.507498 -400.724698)
			(xy 346.530143 -400.675118) (xy 346.559613 -400.629266) (xy 346.595309 -400.588075) (xy 346.636505 -400.552384)
			(xy 346.68236 -400.52292) (xy 346.731943 -400.500282) (xy 346.784243 -400.484931) (xy 346.838195 -400.47718)
			(xy 346.865448 -400.47672) (xy 347.729048 -400.47672) (xy 347.756299 -400.477153) (xy 347.810246 -400.484916)
			(xy 347.862538 -400.500276) (xy 347.912113 -400.522922) (xy 347.957961 -400.552391) (xy 347.999148 -400.588086)
			(xy 348.034837 -400.629278) (xy 348.064301 -400.675129) (xy 348.086941 -400.724707) (xy 348.102294 -400.777001)
			(xy 348.11005 -400.830949) (xy 348.11005 -400.885449) (xy 349.547706 -400.885449) (xy 349.547706 -400.830951)
			(xy 349.555462 -400.777009) (xy 349.570815 -400.724719) (xy 349.593454 -400.675146) (xy 349.622917 -400.6293)
			(xy 349.658604 -400.588113) (xy 349.69979 -400.552424) (xy 349.745636 -400.52296) (xy 349.795208 -400.500319)
			(xy 349.847497 -400.484964) (xy 349.901439 -400.477207) (xy 349.928688 -400.47672) (xy 350.792288 -400.47672)
			(xy 350.819543 -400.477126) (xy 350.8735 -400.484882) (xy 350.925803 -400.500238) (xy 350.975388 -400.522882)
			(xy 351.021246 -400.552352) (xy 351.062443 -400.588048) (xy 351.098141 -400.629244) (xy 351.127612 -400.675101)
			(xy 351.150257 -400.724686) (xy 351.165615 -400.776989) (xy 351.173373 -400.830945) (xy 351.173373 -400.885452)
			(xy 371.041883 -400.885452) (xy 371.041883 -400.830948) (xy 371.049641 -400.776998) (xy 371.064997 -400.724702)
			(xy 371.08764 -400.675123) (xy 371.117109 -400.629272) (xy 371.152803 -400.588082) (xy 371.193996 -400.552391)
			(xy 371.23985 -400.522926) (xy 371.28943 -400.500286) (xy 371.341728 -400.484934) (xy 371.395678 -400.477181)
			(xy 371.42293 -400.47672) (xy 372.28653 -400.47672) (xy 372.313782 -400.477152) (xy 372.36773 -400.484912)
			(xy 372.420025 -400.500271) (xy 372.469602 -400.522916) (xy 372.515452 -400.552385) (xy 372.556642 -400.588079)
			(xy 372.592333 -400.629272) (xy 372.621799 -400.675124) (xy 372.644439 -400.724703) (xy 372.659794 -400.776999)
			(xy 372.66755 -400.830948) (xy 372.66755 -400.885448) (xy 374.105206 -400.885448) (xy 374.105206 -400.830952)
			(xy 374.112961 -400.777011) (xy 374.128314 -400.724723) (xy 374.150951 -400.675151) (xy 374.180412 -400.629306)
			(xy 374.216098 -400.588119) (xy 374.257281 -400.55243) (xy 374.303125 -400.522965) (xy 374.352694 -400.500324)
			(xy 374.404982 -400.484968) (xy 374.458922 -400.477208) (xy 374.48617 -400.47672) (xy 375.34977 -400.47672)
			(xy 375.377026 -400.477125) (xy 375.430984 -400.484879) (xy 375.48329 -400.500234) (xy 375.532877 -400.522876)
			(xy 375.578738 -400.552345) (xy 375.619937 -400.588042) (xy 375.655637 -400.629238) (xy 375.68511 -400.675096)
			(xy 375.707756 -400.724682) (xy 375.723115 -400.776986) (xy 375.730873 -400.830944) (xy 375.730873 -400.885451)
			(xy 377.168383 -400.885451) (xy 377.168383 -400.830949) (xy 377.17614 -400.777001) (xy 377.191495 -400.724706)
			(xy 377.214137 -400.675129) (xy 377.243604 -400.629279) (xy 377.279296 -400.588089) (xy 377.320487 -400.552398)
			(xy 377.366338 -400.522932) (xy 377.415915 -400.500292) (xy 377.468211 -400.484938) (xy 377.522159 -400.477183)
			(xy 377.54941 -400.47672) (xy 378.41301 -400.47672) (xy 378.440263 -400.477151) (xy 378.494213 -400.484909)
			(xy 378.546511 -400.500266) (xy 378.59609 -400.522909) (xy 378.641943 -400.552378) (xy 378.683135 -400.588072)
			(xy 378.718828 -400.629265) (xy 378.748296 -400.675118) (xy 378.770938 -400.724699) (xy 378.786293 -400.776996)
			(xy 378.79405 -400.830947) (xy 378.79405 -400.885447) (xy 380.231706 -400.885447) (xy 380.231706 -400.830953)
			(xy 380.239461 -400.777014) (xy 380.254812 -400.724727) (xy 380.277448 -400.675157) (xy 380.306907 -400.629312)
			(xy 380.342591 -400.588126) (xy 380.383772 -400.552437) (xy 380.429613 -400.522972) (xy 380.47918 -400.50033)
			(xy 380.531465 -400.484971) (xy 380.585403 -400.47721) (xy 380.61265 -400.47672) (xy 381.47625 -400.47672)
			(xy 381.503507 -400.477124) (xy 381.557468 -400.484875) (xy 381.609775 -400.500228) (xy 381.659365 -400.522869)
			(xy 381.705228 -400.552338) (xy 381.74643 -400.588035) (xy 381.782132 -400.629232) (xy 381.811607 -400.675091)
			(xy 381.834254 -400.724678) (xy 381.849614 -400.776983) (xy 381.857373 -400.830943) (xy 381.857373 -400.885449)
			(xy 383.294906 -400.885449) (xy 383.294906 -400.830951) (xy 383.302662 -400.777008) (xy 383.318015 -400.724718)
			(xy 383.340654 -400.675145) (xy 383.370117 -400.629299) (xy 383.405805 -400.588112) (xy 383.446991 -400.552423)
			(xy 383.492837 -400.522959) (xy 383.542409 -400.500319) (xy 383.594699 -400.484964) (xy 383.648641 -400.477207)
			(xy 383.67589 -400.47672) (xy 384.53949 -400.47672) (xy 384.566745 -400.477126) (xy 384.620701 -400.484883)
			(xy 384.673004 -400.500239) (xy 384.722589 -400.522883) (xy 384.768447 -400.552352) (xy 384.809644 -400.588049)
			(xy 384.845342 -400.629245) (xy 384.874813 -400.675102) (xy 384.897458 -400.724686) (xy 384.912815 -400.776989)
			(xy 384.920573 -400.830945) (xy 384.920573 -400.885452) (xy 386.358083 -400.885452) (xy 386.358083 -400.830948)
			(xy 386.365841 -400.776998) (xy 386.381197 -400.724702) (xy 386.40384 -400.675123) (xy 386.433309 -400.629272)
			(xy 386.469003 -400.588082) (xy 386.510196 -400.552391) (xy 386.55605 -400.522926) (xy 386.60563 -400.500286)
			(xy 386.657928 -400.484934) (xy 386.711878 -400.477181) (xy 386.73913 -400.47672) (xy 387.60273 -400.47672)
			(xy 387.629982 -400.477152) (xy 387.68393 -400.484912) (xy 387.736225 -400.500271) (xy 387.785802 -400.522916)
			(xy 387.831652 -400.552385) (xy 387.872842 -400.588079) (xy 387.908533 -400.629272) (xy 387.937999 -400.675124)
			(xy 387.960639 -400.724703) (xy 387.975994 -400.776999) (xy 387.98375 -400.830948) (xy 387.98375 -400.885448)
			(xy 389.421406 -400.885448) (xy 389.421406 -400.830952) (xy 389.429161 -400.777011) (xy 389.444514 -400.724723)
			(xy 389.467151 -400.675151) (xy 389.496612 -400.629306) (xy 389.532298 -400.588119) (xy 389.573481 -400.55243)
			(xy 389.619325 -400.522965) (xy 389.668894 -400.500324) (xy 389.721182 -400.484968) (xy 389.775122 -400.477208)
			(xy 389.80237 -400.47672) (xy 390.66597 -400.47672) (xy 390.693226 -400.477125) (xy 390.747184 -400.484879)
			(xy 390.79949 -400.500234) (xy 390.849077 -400.522876) (xy 390.894938 -400.552345) (xy 390.936137 -400.588042)
			(xy 390.971837 -400.629238) (xy 391.00131 -400.675096) (xy 391.023956 -400.724682) (xy 391.039315 -400.776986)
			(xy 391.047073 -400.830944) (xy 391.047073 -400.885451) (xy 392.484583 -400.885451) (xy 392.484583 -400.830949)
			(xy 392.49234 -400.777001) (xy 392.507695 -400.724706) (xy 392.530337 -400.675129) (xy 392.559804 -400.629279)
			(xy 392.595496 -400.588089) (xy 392.636687 -400.552398) (xy 392.682538 -400.522932) (xy 392.732115 -400.500292)
			(xy 392.784411 -400.484938) (xy 392.838359 -400.477183) (xy 392.86561 -400.47672) (xy 393.72921 -400.47672)
			(xy 393.756463 -400.477151) (xy 393.810413 -400.484909) (xy 393.862711 -400.500266) (xy 393.91229 -400.522909)
			(xy 393.958143 -400.552378) (xy 393.999335 -400.588072) (xy 394.035028 -400.629265) (xy 394.064496 -400.675118)
			(xy 394.087138 -400.724699) (xy 394.102493 -400.776996) (xy 394.11025 -400.830947) (xy 394.11025 -400.885447)
			(xy 395.547906 -400.885447) (xy 395.547906 -400.830953) (xy 395.555661 -400.777014) (xy 395.571012 -400.724727)
			(xy 395.593648 -400.675157) (xy 395.623107 -400.629312) (xy 395.658791 -400.588126) (xy 395.699972 -400.552437)
			(xy 395.745813 -400.522972) (xy 395.79538 -400.50033) (xy 395.847665 -400.484971) (xy 395.901603 -400.47721)
			(xy 395.92885 -400.47672) (xy 396.79245 -400.47672) (xy 396.819707 -400.477124) (xy 396.873668 -400.484875)
			(xy 396.925975 -400.500228) (xy 396.975565 -400.522869) (xy 397.021428 -400.552338) (xy 397.06263 -400.588035)
			(xy 397.098332 -400.629232) (xy 397.127807 -400.675091) (xy 397.150454 -400.724678) (xy 397.165814 -400.776983)
			(xy 397.173573 -400.830943) (xy 397.173573 -400.885449) (xy 398.611106 -400.885449) (xy 398.611106 -400.830951)
			(xy 398.618862 -400.777008) (xy 398.634215 -400.724718) (xy 398.656854 -400.675145) (xy 398.686317 -400.629299)
			(xy 398.722005 -400.588112) (xy 398.763191 -400.552423) (xy 398.809037 -400.522959) (xy 398.858609 -400.500319)
			(xy 398.910899 -400.484964) (xy 398.964841 -400.477207) (xy 398.99209 -400.47672) (xy 399.85569 -400.47672)
			(xy 399.882945 -400.477126) (xy 399.936901 -400.484883) (xy 399.989204 -400.500239) (xy 400.038789 -400.522883)
			(xy 400.084647 -400.552352) (xy 400.125844 -400.588049) (xy 400.161542 -400.629245) (xy 400.191013 -400.675102)
			(xy 400.213658 -400.724686) (xy 400.229015 -400.776989) (xy 400.236773 -400.830945) (xy 400.236773 -400.885452)
			(xy 401.674283 -400.885452) (xy 401.674283 -400.830948) (xy 401.682041 -400.776998) (xy 401.697397 -400.724702)
			(xy 401.72004 -400.675123) (xy 401.749509 -400.629272) (xy 401.785203 -400.588082) (xy 401.826396 -400.552391)
			(xy 401.87225 -400.522926) (xy 401.92183 -400.500286) (xy 401.974128 -400.484934) (xy 402.028078 -400.477181)
			(xy 402.05533 -400.47672) (xy 402.91893 -400.47672) (xy 402.946182 -400.477152) (xy 403.00013 -400.484912)
			(xy 403.052425 -400.500271) (xy 403.102002 -400.522916) (xy 403.147852 -400.552385) (xy 403.189042 -400.588079)
			(xy 403.224733 -400.629272) (xy 403.254199 -400.675124) (xy 403.276839 -400.724703) (xy 403.292194 -400.776999)
			(xy 403.29995 -400.830948) (xy 403.29995 -400.885448) (xy 404.737606 -400.885448) (xy 404.737606 -400.830952)
			(xy 404.745361 -400.777011) (xy 404.760714 -400.724723) (xy 404.783351 -400.675151) (xy 404.812812 -400.629306)
			(xy 404.848498 -400.588119) (xy 404.889681 -400.55243) (xy 404.935525 -400.522965) (xy 404.985094 -400.500324)
			(xy 405.037382 -400.484968) (xy 405.091322 -400.477208) (xy 405.11857 -400.47672) (xy 405.98217 -400.47672)
			(xy 406.009426 -400.477125) (xy 406.063384 -400.484879) (xy 406.11569 -400.500234) (xy 406.165277 -400.522876)
			(xy 406.211138 -400.552345) (xy 406.252337 -400.588042) (xy 406.288037 -400.629238) (xy 406.31751 -400.675096)
			(xy 406.340156 -400.724682) (xy 406.355515 -400.776986) (xy 406.363273 -400.830944) (xy 406.363273 -400.885451)
			(xy 407.800783 -400.885451) (xy 407.800783 -400.830949) (xy 407.80854 -400.777001) (xy 407.823895 -400.724706)
			(xy 407.846537 -400.675129) (xy 407.876004 -400.629279) (xy 407.911696 -400.588089) (xy 407.952887 -400.552398)
			(xy 407.998738 -400.522932) (xy 408.048315 -400.500292) (xy 408.100611 -400.484938) (xy 408.154559 -400.477183)
			(xy 408.18181 -400.47672) (xy 409.04541 -400.47672) (xy 409.072663 -400.477151) (xy 409.126613 -400.484909)
			(xy 409.178911 -400.500266) (xy 409.22849 -400.522909) (xy 409.274343 -400.552378) (xy 409.315535 -400.588072)
			(xy 409.351228 -400.629265) (xy 409.380696 -400.675118) (xy 409.403338 -400.724699) (xy 409.418693 -400.776996)
			(xy 409.42645 -400.830947) (xy 409.42645 -400.885447) (xy 410.864106 -400.885447) (xy 410.864106 -400.830953)
			(xy 410.871861 -400.777014) (xy 410.887212 -400.724727) (xy 410.909848 -400.675157) (xy 410.939307 -400.629312)
			(xy 410.974991 -400.588126) (xy 411.016172 -400.552437) (xy 411.062013 -400.522972) (xy 411.11158 -400.50033)
			(xy 411.163865 -400.484971) (xy 411.217803 -400.47721) (xy 411.24505 -400.47672) (xy 412.10865 -400.47672)
			(xy 412.135907 -400.477124) (xy 412.189868 -400.484875) (xy 412.242175 -400.500228) (xy 412.291765 -400.522869)
			(xy 412.337628 -400.552338) (xy 412.37883 -400.588035) (xy 412.414532 -400.629232) (xy 412.444007 -400.675091)
			(xy 412.466654 -400.724678) (xy 412.482014 -400.776983) (xy 412.489773 -400.830943) (xy 412.489773 -400.885449)
			(xy 413.927306 -400.885449) (xy 413.927306 -400.830951) (xy 413.935062 -400.777008) (xy 413.950415 -400.724718)
			(xy 413.973054 -400.675145) (xy 414.002517 -400.629299) (xy 414.038205 -400.588112) (xy 414.079391 -400.552423)
			(xy 414.125237 -400.522959) (xy 414.174809 -400.500319) (xy 414.227099 -400.484964) (xy 414.281041 -400.477207)
			(xy 414.30829 -400.47672) (xy 415.17189 -400.47672) (xy 415.199145 -400.477126) (xy 415.253101 -400.484883)
			(xy 415.305404 -400.500239) (xy 415.354989 -400.522883) (xy 415.400847 -400.552352) (xy 415.442044 -400.588049)
			(xy 415.477742 -400.629245) (xy 415.507213 -400.675102) (xy 415.529858 -400.724686) (xy 415.545215 -400.776989)
			(xy 415.552973 -400.830945) (xy 415.552973 -400.885452) (xy 416.990483 -400.885452) (xy 416.990483 -400.830948)
			(xy 416.998241 -400.776998) (xy 417.013597 -400.724702) (xy 417.03624 -400.675123) (xy 417.065709 -400.629272)
			(xy 417.101403 -400.588082) (xy 417.142596 -400.552391) (xy 417.18845 -400.522926) (xy 417.23803 -400.500286)
			(xy 417.290328 -400.484934) (xy 417.344278 -400.477181) (xy 417.37153 -400.47672) (xy 418.23513 -400.47672)
			(xy 418.262382 -400.477152) (xy 418.31633 -400.484912) (xy 418.368625 -400.500271) (xy 418.418202 -400.522916)
			(xy 418.464052 -400.552385) (xy 418.505242 -400.588079) (xy 418.540933 -400.629272) (xy 418.570399 -400.675124)
			(xy 418.593039 -400.724703) (xy 418.608394 -400.776999) (xy 418.61615 -400.830948) (xy 418.61615 -400.885452)
			(xy 418.608394 -400.939401) (xy 418.593039 -400.991697) (xy 418.570399 -401.041276) (xy 418.540933 -401.087128)
			(xy 418.505242 -401.128321) (xy 418.464052 -401.164015) (xy 418.418202 -401.193484) (xy 418.368625 -401.216129)
			(xy 418.31633 -401.231488) (xy 418.262382 -401.239248) (xy 418.23513 -401.239736) (xy 417.37153 -401.239736)
			(xy 417.344278 -401.239219) (xy 417.290328 -401.231466) (xy 417.23803 -401.216114) (xy 417.18845 -401.193474)
			(xy 417.142596 -401.164009) (xy 417.101403 -401.128318) (xy 417.065709 -401.087128) (xy 417.03624 -401.041277)
			(xy 417.013597 -400.991698) (xy 416.998241 -400.939402) (xy 416.990483 -400.885452) (xy 415.552973 -400.885452)
			(xy 415.552973 -400.885455) (xy 415.545215 -400.939411) (xy 415.529858 -400.991714) (xy 415.507213 -401.041298)
			(xy 415.477742 -401.087155) (xy 415.442044 -401.128351) (xy 415.400847 -401.164048) (xy 415.354989 -401.193517)
			(xy 415.305404 -401.216161) (xy 415.253101 -401.231517) (xy 415.199145 -401.239274) (xy 415.17189 -401.239736)
			(xy 414.30829 -401.239736) (xy 414.281041 -401.239193) (xy 414.227099 -401.231436) (xy 414.174809 -401.216081)
			(xy 414.125237 -401.193441) (xy 414.079391 -401.163977) (xy 414.038205 -401.128288) (xy 414.002517 -401.087101)
			(xy 413.973054 -401.041255) (xy 413.950415 -400.991682) (xy 413.935062 -400.939392) (xy 413.927306 -400.885449)
			(xy 412.489773 -400.885449) (xy 412.489773 -400.885457) (xy 412.482014 -400.939416) (xy 412.466654 -400.991722)
			(xy 412.444007 -401.041309) (xy 412.414532 -401.087168) (xy 412.37883 -401.128365) (xy 412.337628 -401.164062)
			(xy 412.291765 -401.193531) (xy 412.242175 -401.216172) (xy 412.189868 -401.231525) (xy 412.135907 -401.239276)
			(xy 412.10865 -401.239736) (xy 411.24505 -401.239736) (xy 411.217803 -401.23919) (xy 411.163865 -401.231429)
			(xy 411.11158 -401.21607) (xy 411.062013 -401.193428) (xy 411.016172 -401.163963) (xy 410.974991 -401.128274)
			(xy 410.939307 -401.087088) (xy 410.909848 -401.041243) (xy 410.887212 -400.991673) (xy 410.871861 -400.939386)
			(xy 410.864106 -400.885447) (xy 409.42645 -400.885447) (xy 409.42645 -400.885453) (xy 409.418693 -400.939404)
			(xy 409.403338 -400.991701) (xy 409.380696 -401.041282) (xy 409.351228 -401.087135) (xy 409.315535 -401.128328)
			(xy 409.274343 -401.164022) (xy 409.22849 -401.193491) (xy 409.178911 -401.216134) (xy 409.126613 -401.231491)
			(xy 409.072663 -401.239249) (xy 409.04541 -401.239736) (xy 408.18181 -401.239736) (xy 408.154559 -401.239217)
			(xy 408.100611 -401.231462) (xy 408.048315 -401.216108) (xy 407.998738 -401.193468) (xy 407.952887 -401.164002)
			(xy 407.911696 -401.128311) (xy 407.876004 -401.087121) (xy 407.846537 -401.041271) (xy 407.823895 -400.991694)
			(xy 407.80854 -400.939399) (xy 407.800783 -400.885451) (xy 406.363273 -400.885451) (xy 406.363273 -400.885456)
			(xy 406.355515 -400.939414) (xy 406.340156 -400.991718) (xy 406.31751 -401.041304) (xy 406.288037 -401.087162)
			(xy 406.252337 -401.128358) (xy 406.211138 -401.164055) (xy 406.165277 -401.193524) (xy 406.11569 -401.216166)
			(xy 406.063384 -401.231521) (xy 406.009426 -401.239275) (xy 405.98217 -401.239736) (xy 405.11857 -401.239736)
			(xy 405.091322 -401.239192) (xy 405.037382 -401.231432) (xy 404.985094 -401.216076) (xy 404.935525 -401.193435)
			(xy 404.889682 -401.16397) (xy 404.848498 -401.128281) (xy 404.812812 -401.087094) (xy 404.783351 -401.041249)
			(xy 404.760714 -400.991677) (xy 404.745361 -400.939389) (xy 404.737606 -400.885448) (xy 403.29995 -400.885448)
			(xy 403.29995 -400.885452) (xy 403.292194 -400.939401) (xy 403.276839 -400.991697) (xy 403.254199 -401.041276)
			(xy 403.224733 -401.087128) (xy 403.189042 -401.128321) (xy 403.147852 -401.164015) (xy 403.102002 -401.193484)
			(xy 403.052425 -401.216129) (xy 403.00013 -401.231488) (xy 402.946182 -401.239248) (xy 402.91893 -401.239736)
			(xy 402.05533 -401.239736) (xy 402.028078 -401.239219) (xy 401.974128 -401.231466) (xy 401.92183 -401.216114)
			(xy 401.87225 -401.193474) (xy 401.826396 -401.164009) (xy 401.785203 -401.128318) (xy 401.749509 -401.087128)
			(xy 401.72004 -401.041277) (xy 401.697397 -400.991698) (xy 401.682041 -400.939402) (xy 401.674283 -400.885452)
			(xy 400.236773 -400.885452) (xy 400.236773 -400.885455) (xy 400.229015 -400.939411) (xy 400.213658 -400.991714)
			(xy 400.191013 -401.041298) (xy 400.161542 -401.087155) (xy 400.125844 -401.128351) (xy 400.084647 -401.164048)
			(xy 400.038789 -401.193517) (xy 399.989204 -401.216161) (xy 399.936901 -401.231517) (xy 399.882945 -401.239274)
			(xy 399.85569 -401.239736) (xy 398.99209 -401.239736) (xy 398.964841 -401.239193) (xy 398.910899 -401.231436)
			(xy 398.858609 -401.216081) (xy 398.809037 -401.193441) (xy 398.763191 -401.163977) (xy 398.722005 -401.128288)
			(xy 398.686317 -401.087101) (xy 398.656854 -401.041255) (xy 398.634215 -400.991682) (xy 398.618862 -400.939392)
			(xy 398.611106 -400.885449) (xy 397.173573 -400.885449) (xy 397.173573 -400.885457) (xy 397.165814 -400.939416)
			(xy 397.150454 -400.991722) (xy 397.127807 -401.041309) (xy 397.098332 -401.087168) (xy 397.06263 -401.128365)
			(xy 397.021428 -401.164062) (xy 396.975565 -401.193531) (xy 396.925975 -401.216172) (xy 396.873668 -401.231525)
			(xy 396.819707 -401.239276) (xy 396.79245 -401.239736) (xy 395.92885 -401.239736) (xy 395.901603 -401.23919)
			(xy 395.847665 -401.231429) (xy 395.79538 -401.21607) (xy 395.745813 -401.193428) (xy 395.699972 -401.163963)
			(xy 395.658791 -401.128274) (xy 395.623107 -401.087088) (xy 395.593648 -401.041243) (xy 395.571012 -400.991673)
			(xy 395.555661 -400.939386) (xy 395.547906 -400.885447) (xy 394.11025 -400.885447) (xy 394.11025 -400.885453)
			(xy 394.102493 -400.939404) (xy 394.087138 -400.991701) (xy 394.064496 -401.041282) (xy 394.035028 -401.087135)
			(xy 393.999335 -401.128328) (xy 393.958143 -401.164022) (xy 393.91229 -401.193491) (xy 393.862711 -401.216134)
			(xy 393.810413 -401.231491) (xy 393.756463 -401.239249) (xy 393.72921 -401.239736) (xy 392.86561 -401.239736)
			(xy 392.838359 -401.239217) (xy 392.784411 -401.231462) (xy 392.732115 -401.216108) (xy 392.682538 -401.193468)
			(xy 392.636687 -401.164002) (xy 392.595496 -401.128311) (xy 392.559804 -401.087121) (xy 392.530337 -401.041271)
			(xy 392.507695 -400.991694) (xy 392.49234 -400.939399) (xy 392.484583 -400.885451) (xy 391.047073 -400.885451)
			(xy 391.047073 -400.885456) (xy 391.039315 -400.939414) (xy 391.023956 -400.991718) (xy 391.00131 -401.041304)
			(xy 390.971837 -401.087162) (xy 390.936137 -401.128358) (xy 390.894938 -401.164055) (xy 390.849077 -401.193524)
			(xy 390.79949 -401.216166) (xy 390.747184 -401.231521) (xy 390.693226 -401.239275) (xy 390.66597 -401.239736)
			(xy 389.80237 -401.239736) (xy 389.775122 -401.239192) (xy 389.721182 -401.231432) (xy 389.668894 -401.216076)
			(xy 389.619325 -401.193435) (xy 389.573482 -401.16397) (xy 389.532298 -401.128281) (xy 389.496612 -401.087094)
			(xy 389.467151 -401.041249) (xy 389.444514 -400.991677) (xy 389.429161 -400.939389) (xy 389.421406 -400.885448)
			(xy 387.98375 -400.885448) (xy 387.98375 -400.885452) (xy 387.975994 -400.939401) (xy 387.960639 -400.991697)
			(xy 387.937999 -401.041276) (xy 387.908533 -401.087128) (xy 387.872842 -401.128321) (xy 387.831652 -401.164015)
			(xy 387.785802 -401.193484) (xy 387.736225 -401.216129) (xy 387.68393 -401.231488) (xy 387.629982 -401.239248)
			(xy 387.60273 -401.239736) (xy 386.73913 -401.239736) (xy 386.711878 -401.239219) (xy 386.657928 -401.231466)
			(xy 386.60563 -401.216114) (xy 386.55605 -401.193474) (xy 386.510196 -401.164009) (xy 386.469003 -401.128318)
			(xy 386.433309 -401.087128) (xy 386.40384 -401.041277) (xy 386.381197 -400.991698) (xy 386.365841 -400.939402)
			(xy 386.358083 -400.885452) (xy 384.920573 -400.885452) (xy 384.920573 -400.885455) (xy 384.912815 -400.939411)
			(xy 384.897458 -400.991714) (xy 384.874813 -401.041298) (xy 384.845342 -401.087155) (xy 384.809644 -401.128351)
			(xy 384.768447 -401.164048) (xy 384.722589 -401.193517) (xy 384.673004 -401.216161) (xy 384.620701 -401.231517)
			(xy 384.566745 -401.239274) (xy 384.53949 -401.239736) (xy 383.67589 -401.239736) (xy 383.648641 -401.239193)
			(xy 383.594699 -401.231436) (xy 383.542409 -401.216081) (xy 383.492837 -401.193441) (xy 383.446991 -401.163977)
			(xy 383.405805 -401.128288) (xy 383.370117 -401.087101) (xy 383.340654 -401.041255) (xy 383.318015 -400.991682)
			(xy 383.302662 -400.939392) (xy 383.294906 -400.885449) (xy 381.857373 -400.885449) (xy 381.857373 -400.885457)
			(xy 381.849614 -400.939416) (xy 381.834254 -400.991722) (xy 381.811607 -401.041309) (xy 381.782132 -401.087168)
			(xy 381.74643 -401.128365) (xy 381.705228 -401.164062) (xy 381.659365 -401.193531) (xy 381.609775 -401.216172)
			(xy 381.557468 -401.231525) (xy 381.503507 -401.239276) (xy 381.47625 -401.239736) (xy 380.61265 -401.239736)
			(xy 380.585403 -401.23919) (xy 380.531465 -401.231429) (xy 380.47918 -401.21607) (xy 380.429613 -401.193428)
			(xy 380.383772 -401.163963) (xy 380.342591 -401.128274) (xy 380.306907 -401.087088) (xy 380.277448 -401.041243)
			(xy 380.254812 -400.991673) (xy 380.239461 -400.939386) (xy 380.231706 -400.885447) (xy 378.79405 -400.885447)
			(xy 378.79405 -400.885453) (xy 378.786293 -400.939404) (xy 378.770938 -400.991701) (xy 378.748296 -401.041282)
			(xy 378.718828 -401.087135) (xy 378.683135 -401.128328) (xy 378.641943 -401.164022) (xy 378.59609 -401.193491)
			(xy 378.546511 -401.216134) (xy 378.494213 -401.231491) (xy 378.440263 -401.239249) (xy 378.41301 -401.239736)
			(xy 377.54941 -401.239736) (xy 377.522159 -401.239217) (xy 377.468211 -401.231462) (xy 377.415915 -401.216108)
			(xy 377.366338 -401.193468) (xy 377.320487 -401.164002) (xy 377.279296 -401.128311) (xy 377.243604 -401.087121)
			(xy 377.214137 -401.041271) (xy 377.191495 -400.991694) (xy 377.17614 -400.939399) (xy 377.168383 -400.885451)
			(xy 375.730873 -400.885451) (xy 375.730873 -400.885456) (xy 375.723115 -400.939414) (xy 375.707756 -400.991718)
			(xy 375.68511 -401.041304) (xy 375.655637 -401.087162) (xy 375.619937 -401.128358) (xy 375.578738 -401.164055)
			(xy 375.532877 -401.193524) (xy 375.48329 -401.216166) (xy 375.430984 -401.231521) (xy 375.377026 -401.239275)
			(xy 375.34977 -401.239736) (xy 374.48617 -401.239736) (xy 374.458922 -401.239192) (xy 374.404982 -401.231432)
			(xy 374.352694 -401.216076) (xy 374.303125 -401.193435) (xy 374.257282 -401.16397) (xy 374.216098 -401.128281)
			(xy 374.180412 -401.087094) (xy 374.150951 -401.041249) (xy 374.128314 -400.991677) (xy 374.112961 -400.939389)
			(xy 374.105206 -400.885448) (xy 372.66755 -400.885448) (xy 372.66755 -400.885452) (xy 372.659794 -400.939401)
			(xy 372.644439 -400.991697) (xy 372.621799 -401.041276) (xy 372.592333 -401.087128) (xy 372.556642 -401.128321)
			(xy 372.515452 -401.164015) (xy 372.469602 -401.193484) (xy 372.420025 -401.216129) (xy 372.36773 -401.231488)
			(xy 372.313782 -401.239248) (xy 372.28653 -401.239736) (xy 371.42293 -401.239736) (xy 371.395678 -401.239219)
			(xy 371.341728 -401.231466) (xy 371.28943 -401.216114) (xy 371.23985 -401.193474) (xy 371.193996 -401.164009)
			(xy 371.152803 -401.128318) (xy 371.117109 -401.087128) (xy 371.08764 -401.041277) (xy 371.064997 -400.991698)
			(xy 371.049641 -400.939402) (xy 371.041883 -400.885452) (xy 351.173373 -400.885452) (xy 351.173373 -400.885455)
			(xy 351.165615 -400.939411) (xy 351.150257 -400.991714) (xy 351.127612 -401.041299) (xy 351.098141 -401.087156)
			(xy 351.062443 -401.128352) (xy 351.021246 -401.164048) (xy 350.975388 -401.193518) (xy 350.925803 -401.216162)
			(xy 350.8735 -401.231518) (xy 350.819543 -401.239274) (xy 350.792288 -401.239736) (xy 349.928688 -401.239736)
			(xy 349.901439 -401.239193) (xy 349.847497 -401.231436) (xy 349.795208 -401.216081) (xy 349.745636 -401.19344)
			(xy 349.69979 -401.163976) (xy 349.658604 -401.128287) (xy 349.622917 -401.0871) (xy 349.593454 -401.041254)
			(xy 349.570815 -400.991681) (xy 349.555462 -400.939391) (xy 349.547706 -400.885449) (xy 348.11005 -400.885449)
			(xy 348.11005 -400.885451) (xy 348.102294 -400.939399) (xy 348.086941 -400.991693) (xy 348.064301 -401.041271)
			(xy 348.034837 -401.087122) (xy 347.999148 -401.128314) (xy 347.957961 -401.164009) (xy 347.912113 -401.193478)
			(xy 347.862538 -401.216124) (xy 347.810245 -401.231484) (xy 347.756299 -401.239247) (xy 347.729048 -401.239736)
			(xy 346.865448 -401.239736) (xy 346.838195 -401.23922) (xy 346.784243 -401.231469) (xy 346.731943 -401.216118)
			(xy 346.68236 -401.19348) (xy 346.636505 -401.164016) (xy 346.595309 -401.128325) (xy 346.559613 -401.087134)
			(xy 346.530143 -401.041282) (xy 346.507498 -400.991702) (xy 346.492141 -400.939404) (xy 346.484383 -400.885453)
			(xy 345.04685 -400.885453) (xy 345.039093 -400.939404) (xy 345.023737 -400.991702) (xy 345.001095 -401.041282)
			(xy 344.971628 -401.087136) (xy 344.935934 -401.128329) (xy 344.894742 -401.164023) (xy 344.848889 -401.193491)
			(xy 344.799309 -401.216135) (xy 344.747012 -401.231492) (xy 344.693061 -401.23925) (xy 344.665808 -401.239736)
			(xy 343.802208 -401.239736) (xy 343.774957 -401.239217) (xy 343.721009 -401.231462) (xy 343.668714 -401.216108)
			(xy 343.619136 -401.193467) (xy 343.573286 -401.164002) (xy 343.532095 -401.128311) (xy 343.496403 -401.087121)
			(xy 343.466937 -401.041271) (xy 343.444295 -400.991694) (xy 343.42894 -400.939399) (xy 343.421183 -400.885451)
			(xy 341.983673 -400.885451) (xy 341.983673 -400.885456) (xy 341.975915 -400.939414) (xy 341.960556 -400.991718)
			(xy 341.937909 -401.041304) (xy 341.908436 -401.087162) (xy 341.872736 -401.128359) (xy 341.831537 -401.164055)
			(xy 341.785676 -401.193525) (xy 341.736088 -401.216167) (xy 341.683783 -401.231521) (xy 341.629824 -401.239275)
			(xy 341.602568 -401.239736) (xy 340.738968 -401.239736) (xy 340.71172 -401.239192) (xy 340.65778 -401.231432)
			(xy 340.605493 -401.216075) (xy 340.555924 -401.193434) (xy 340.510081 -401.163969) (xy 340.468897 -401.12828)
			(xy 340.433212 -401.087094) (xy 340.403751 -401.041248) (xy 340.381114 -400.991677) (xy 340.365761 -400.939389)
			(xy 340.358006 -400.885448) (xy 338.92035 -400.885448) (xy 338.92035 -400.885452) (xy 338.912594 -400.939401)
			(xy 338.897239 -400.991698) (xy 338.874598 -401.041277) (xy 338.845132 -401.087129) (xy 338.809441 -401.128321)
			(xy 338.768251 -401.164016) (xy 338.722401 -401.193485) (xy 338.672824 -401.216129) (xy 338.620529 -401.231488)
			(xy 338.56658 -401.239248) (xy 338.539328 -401.239736) (xy 337.675728 -401.239736) (xy 337.648476 -401.239219)
			(xy 337.594526 -401.231465) (xy 337.542228 -401.216113) (xy 337.492648 -401.193474) (xy 337.446795 -401.164009)
			(xy 337.405602 -401.128318) (xy 337.369908 -401.087127) (xy 337.34044 -401.041276) (xy 337.317797 -400.991698)
			(xy 337.30244 -400.939402) (xy 337.294683 -400.885452) (xy 335.857173 -400.885452) (xy 335.857173 -400.885455)
			(xy 335.849415 -400.939411) (xy 335.834057 -400.991714) (xy 335.811412 -401.041299) (xy 335.781941 -401.087156)
			(xy 335.746243 -401.128352) (xy 335.705046 -401.164048) (xy 335.659188 -401.193518) (xy 335.609603 -401.216162)
			(xy 335.5573 -401.231518) (xy 335.503343 -401.239274) (xy 335.476088 -401.239736) (xy 334.612488 -401.239736)
			(xy 334.585239 -401.239193) (xy 334.531297 -401.231436) (xy 334.479008 -401.216081) (xy 334.429436 -401.19344)
			(xy 334.38359 -401.163976) (xy 334.342404 -401.128287) (xy 334.306717 -401.0871) (xy 334.277254 -401.041254)
			(xy 334.254615 -400.991681) (xy 334.239262 -400.939391) (xy 334.231506 -400.885449) (xy 332.79385 -400.885449)
			(xy 332.79385 -400.885451) (xy 332.786094 -400.939399) (xy 332.770741 -400.991693) (xy 332.748101 -401.041271)
			(xy 332.718637 -401.087122) (xy 332.682948 -401.128314) (xy 332.641761 -401.164009) (xy 332.595913 -401.193478)
			(xy 332.546338 -401.216124) (xy 332.494045 -401.231484) (xy 332.440099 -401.239247) (xy 332.412848 -401.239736)
			(xy 331.549248 -401.239736) (xy 331.521995 -401.23922) (xy 331.468043 -401.231469) (xy 331.415743 -401.216118)
			(xy 331.36616 -401.19348) (xy 331.320305 -401.164016) (xy 331.279109 -401.128325) (xy 331.243413 -401.087134)
			(xy 331.213943 -401.041282) (xy 331.191298 -400.991702) (xy 331.175941 -400.939404) (xy 331.168183 -400.885453)
			(xy 329.73065 -400.885453) (xy 329.722893 -400.939404) (xy 329.707537 -400.991702) (xy 329.684895 -401.041282)
			(xy 329.655428 -401.087136) (xy 329.619734 -401.128329) (xy 329.578542 -401.164023) (xy 329.532689 -401.193491)
			(xy 329.483109 -401.216135) (xy 329.430812 -401.231492) (xy 329.376861 -401.23925) (xy 329.349608 -401.239736)
			(xy 328.486008 -401.239736) (xy 328.458757 -401.239217) (xy 328.404809 -401.231462) (xy 328.352514 -401.216108)
			(xy 328.302936 -401.193467) (xy 328.257086 -401.164002) (xy 328.215895 -401.128311) (xy 328.180203 -401.087121)
			(xy 328.150737 -401.041271) (xy 328.128095 -400.991694) (xy 328.11274 -400.939399) (xy 328.104983 -400.885451)
			(xy 326.667473 -400.885451) (xy 326.667473 -400.885456) (xy 326.659715 -400.939414) (xy 326.644356 -400.991718)
			(xy 326.621709 -401.041304) (xy 326.592236 -401.087162) (xy 326.556536 -401.128359) (xy 326.515337 -401.164055)
			(xy 326.469476 -401.193525) (xy 326.419888 -401.216167) (xy 326.367583 -401.231521) (xy 326.313624 -401.239275)
			(xy 326.286368 -401.239736) (xy 325.422768 -401.239736) (xy 325.39552 -401.239192) (xy 325.34158 -401.231432)
			(xy 325.289293 -401.216075) (xy 325.239724 -401.193434) (xy 325.193881 -401.163969) (xy 325.152697 -401.12828)
			(xy 325.117012 -401.087094) (xy 325.087551 -401.041248) (xy 325.064914 -400.991677) (xy 325.049561 -400.939389)
			(xy 325.041806 -400.885448) (xy 323.60415 -400.885448) (xy 323.60415 -400.885452) (xy 323.596394 -400.939401)
			(xy 323.581039 -400.991698) (xy 323.558398 -401.041277) (xy 323.528932 -401.087129) (xy 323.493241 -401.128321)
			(xy 323.452051 -401.164016) (xy 323.406201 -401.193485) (xy 323.356624 -401.216129) (xy 323.304329 -401.231488)
			(xy 323.25038 -401.239248) (xy 323.223128 -401.239736) (xy 322.359528 -401.239736) (xy 322.332276 -401.239219)
			(xy 322.278326 -401.231465) (xy 322.226028 -401.216113) (xy 322.176448 -401.193474) (xy 322.130595 -401.164009)
			(xy 322.089402 -401.128318) (xy 322.053708 -401.087127) (xy 322.02424 -401.041276) (xy 322.001597 -400.991698)
			(xy 321.98624 -400.939402) (xy 321.978483 -400.885452) (xy 320.540973 -400.885452) (xy 320.540973 -400.885455)
			(xy 320.533215 -400.939411) (xy 320.517857 -400.991714) (xy 320.495212 -401.041299) (xy 320.465741 -401.087156)
			(xy 320.430043 -401.128352) (xy 320.388846 -401.164048) (xy 320.342988 -401.193518) (xy 320.293403 -401.216162)
			(xy 320.2411 -401.231518) (xy 320.187143 -401.239274) (xy 320.159888 -401.239736) (xy 319.296288 -401.239736)
			(xy 319.269039 -401.239193) (xy 319.215097 -401.231436) (xy 319.162808 -401.216081) (xy 319.113236 -401.19344)
			(xy 319.06739 -401.163976) (xy 319.026204 -401.128287) (xy 318.990517 -401.0871) (xy 318.961054 -401.041254)
			(xy 318.938415 -400.991681) (xy 318.923062 -400.939391) (xy 318.915306 -400.885449) (xy 317.47765 -400.885449)
			(xy 317.47765 -400.885451) (xy 317.469894 -400.939399) (xy 317.454541 -400.991693) (xy 317.431901 -401.041271)
			(xy 317.402437 -401.087122) (xy 317.366748 -401.128314) (xy 317.325561 -401.164009) (xy 317.279713 -401.193478)
			(xy 317.230138 -401.216124) (xy 317.177845 -401.231484) (xy 317.123899 -401.239247) (xy 317.096648 -401.239736)
			(xy 316.233048 -401.239736) (xy 316.205795 -401.23922) (xy 316.151843 -401.231469) (xy 316.099543 -401.216118)
			(xy 316.04996 -401.19348) (xy 316.004105 -401.164016) (xy 315.962909 -401.128325) (xy 315.927213 -401.087134)
			(xy 315.897743 -401.041282) (xy 315.875098 -400.991702) (xy 315.859741 -400.939404) (xy 315.851983 -400.885453)
			(xy 314.41445 -400.885453) (xy 314.406693 -400.939404) (xy 314.391337 -400.991702) (xy 314.368695 -401.041282)
			(xy 314.339228 -401.087136) (xy 314.303534 -401.128329) (xy 314.262342 -401.164023) (xy 314.216489 -401.193491)
			(xy 314.166909 -401.216135) (xy 314.114612 -401.231492) (xy 314.060661 -401.23925) (xy 314.033408 -401.239736)
			(xy 313.169808 -401.239736) (xy 313.142557 -401.239217) (xy 313.088609 -401.231462) (xy 313.036314 -401.216108)
			(xy 312.986736 -401.193467) (xy 312.940886 -401.164002) (xy 312.899695 -401.128311) (xy 312.864003 -401.087121)
			(xy 312.834537 -401.041271) (xy 312.811895 -400.991694) (xy 312.79654 -400.939399) (xy 312.788783 -400.885451)
			(xy 311.351273 -400.885451) (xy 311.351273 -400.885456) (xy 311.343515 -400.939414) (xy 311.328156 -400.991718)
			(xy 311.305509 -401.041304) (xy 311.276036 -401.087162) (xy 311.240336 -401.128359) (xy 311.199137 -401.164055)
			(xy 311.153276 -401.193525) (xy 311.103688 -401.216167) (xy 311.051383 -401.231521) (xy 310.997424 -401.239275)
			(xy 310.970168 -401.239736) (xy 310.106568 -401.239736) (xy 310.07932 -401.239192) (xy 310.02538 -401.231432)
			(xy 309.973093 -401.216075) (xy 309.923524 -401.193434) (xy 309.877681 -401.163969) (xy 309.836497 -401.12828)
			(xy 309.800812 -401.087094) (xy 309.771351 -401.041248) (xy 309.748714 -400.991677) (xy 309.733361 -400.939389)
			(xy 309.725606 -400.885448) (xy 308.28795 -400.885448) (xy 308.28795 -400.885452) (xy 308.280194 -400.939401)
			(xy 308.264839 -400.991698) (xy 308.242198 -401.041277) (xy 308.212732 -401.087129) (xy 308.177041 -401.128321)
			(xy 308.135851 -401.164016) (xy 308.090001 -401.193485) (xy 308.040424 -401.216129) (xy 307.988129 -401.231488)
			(xy 307.93418 -401.239248) (xy 307.906928 -401.239736) (xy 307.043328 -401.239736) (xy 307.016076 -401.239219)
			(xy 306.962126 -401.231465) (xy 306.909828 -401.216113) (xy 306.860248 -401.193474) (xy 306.814395 -401.164009)
			(xy 306.773202 -401.128318) (xy 306.737508 -401.087127) (xy 306.70804 -401.041276) (xy 306.685397 -400.991698)
			(xy 306.67004 -400.939402) (xy 306.662283 -400.885452) (xy 305.224773 -400.885452) (xy 305.224773 -400.885455)
			(xy 305.217015 -400.939411) (xy 305.201657 -400.991714) (xy 305.179012 -401.041299) (xy 305.149541 -401.087156)
			(xy 305.113843 -401.128352) (xy 305.072646 -401.164048) (xy 305.026788 -401.193518) (xy 304.977203 -401.216162)
			(xy 304.9249 -401.231518) (xy 304.870943 -401.239274) (xy 304.843688 -401.239736) (xy 303.980088 -401.239736)
			(xy 303.952839 -401.239193) (xy 303.898897 -401.231436) (xy 303.846608 -401.216081) (xy 303.797036 -401.19344)
			(xy 303.75119 -401.163976) (xy 303.710004 -401.128287) (xy 303.674317 -401.0871) (xy 303.644854 -401.041254)
			(xy 303.622215 -400.991681) (xy 303.606862 -400.939391) (xy 303.599106 -400.885449) (xy 280.76398 -400.885449)
			(xy 280.76398 -402.0155) (xy 287.066441 -402.0155) (xy 287.070455 -401.951698) (xy 287.082434 -401.888902)
			(xy 287.102189 -401.828103) (xy 287.129408 -401.77026) (xy 287.163662 -401.716283) (xy 287.204411 -401.667026)
			(xy 287.251013 -401.623264) (xy 287.302731 -401.585688) (xy 287.358752 -401.55489) (xy 287.418191 -401.531357)
			(xy 287.48011 -401.515458) (xy 287.543534 -401.507446) (xy 287.575498 -401.506944) (xy 287.575752 -401.506944)
			(xy 287.607498 -401.507464) (xy 287.670494 -401.515393) (xy 287.732014 -401.531096) (xy 287.791102 -401.55433)
			(xy 287.846842 -401.584733) (xy 287.898367 -401.621834) (xy 287.921954 -401.643088) (xy 287.929217 -401.649272)
			(xy 287.946967 -401.656223) (xy 287.966029 -401.656223) (xy 287.983779 -401.649272) (xy 287.991042 -401.643088)
			(xy 288.014631 -401.621832) (xy 288.06614 -401.5847) (xy 288.121874 -401.554276) (xy 288.180965 -401.531035)
			(xy 288.242492 -401.515338) (xy 288.305495 -401.507431) (xy 288.337244 -401.506944) (xy 288.337498 -401.506944)
			(xy 288.369457 -401.507521) (xy 288.432872 -401.515532) (xy 288.494783 -401.531427) (xy 288.554213 -401.554957)
			(xy 288.610226 -401.58575) (xy 288.661937 -401.623321) (xy 288.708532 -401.667076) (xy 288.749276 -401.716326)
			(xy 288.783525 -401.770295) (xy 288.810741 -401.82813) (xy 288.830493 -401.888921) (xy 288.84247 -401.951707)
			(xy 288.846484 -402.0155) (xy 289.606441 -402.0155) (xy 289.610455 -401.951698) (xy 289.622434 -401.888902)
			(xy 289.642189 -401.828103) (xy 289.669408 -401.77026) (xy 289.703662 -401.716283) (xy 289.744411 -401.667026)
			(xy 289.791013 -401.623264) (xy 289.842731 -401.585688) (xy 289.898752 -401.55489) (xy 289.958191 -401.531357)
			(xy 290.02011 -401.515458) (xy 290.083534 -401.507446) (xy 290.115498 -401.506944) (xy 290.115752 -401.506944)
			(xy 290.147498 -401.507464) (xy 290.210494 -401.515393) (xy 290.272014 -401.531096) (xy 290.331102 -401.55433)
			(xy 290.386842 -401.584733) (xy 290.438367 -401.621834) (xy 290.461954 -401.643088) (xy 290.469217 -401.649272)
			(xy 290.486967 -401.656223) (xy 290.506029 -401.656223) (xy 290.523779 -401.649272) (xy 290.531042 -401.643088)
			(xy 290.554631 -401.621832) (xy 290.60614 -401.5847) (xy 290.661874 -401.554276) (xy 290.720965 -401.531035)
			(xy 290.782492 -401.515338) (xy 290.845495 -401.507431) (xy 290.877244 -401.506944) (xy 290.877498 -401.506944)
			(xy 290.909457 -401.507521) (xy 290.972872 -401.515532) (xy 291.034783 -401.531427) (xy 291.094213 -401.554957)
			(xy 291.150226 -401.58575) (xy 291.201937 -401.623321) (xy 291.248532 -401.667076) (xy 291.289276 -401.716326)
			(xy 291.323525 -401.770295) (xy 291.350741 -401.82813) (xy 291.370493 -401.888921) (xy 291.38247 -401.951707)
			(xy 291.386484 -402.0155) (xy 292.146441 -402.0155) (xy 292.150455 -401.951698) (xy 292.162434 -401.888902)
			(xy 292.182189 -401.828103) (xy 292.209408 -401.77026) (xy 292.243662 -401.716283) (xy 292.284411 -401.667026)
			(xy 292.331013 -401.623264) (xy 292.382731 -401.585688) (xy 292.438752 -401.55489) (xy 292.498191 -401.531357)
			(xy 292.56011 -401.515458) (xy 292.623534 -401.507446) (xy 292.655498 -401.506944) (xy 292.655752 -401.506944)
			(xy 292.687498 -401.507464) (xy 292.750494 -401.515393) (xy 292.812014 -401.531096) (xy 292.871102 -401.55433)
			(xy 292.926842 -401.584733) (xy 292.978367 -401.621834) (xy 293.001954 -401.643088) (xy 293.009217 -401.649272)
			(xy 293.026967 -401.656223) (xy 293.046029 -401.656223) (xy 293.063779 -401.649272) (xy 293.071042 -401.643088)
			(xy 293.094631 -401.621832) (xy 293.14614 -401.5847) (xy 293.201874 -401.554276) (xy 293.260965 -401.531035)
			(xy 293.322492 -401.515338) (xy 293.385495 -401.507431) (xy 293.417244 -401.506944) (xy 293.417498 -401.506944)
			(xy 293.449457 -401.507521) (xy 293.512872 -401.515532) (xy 293.574783 -401.531427) (xy 293.634213 -401.554957)
			(xy 293.690226 -401.58575) (xy 293.741937 -401.623321) (xy 293.788532 -401.667076) (xy 293.829276 -401.716326)
			(xy 293.863525 -401.770295) (xy 293.890741 -401.82813) (xy 293.910493 -401.888921) (xy 293.92247 -401.951707)
			(xy 293.926484 -402.0155) (xy 294.53602 -402.0155) (xy 294.540035 -401.951693) (xy 294.552015 -401.888892)
			(xy 294.571773 -401.828089) (xy 294.598995 -401.770241) (xy 294.633253 -401.716261) (xy 294.674007 -401.667001)
			(xy 294.720613 -401.623237) (xy 294.772338 -401.58566) (xy 294.828364 -401.554862) (xy 294.887809 -401.531329)
			(xy 294.949734 -401.515433) (xy 295.013163 -401.507423) (xy 295.04513 -401.506944) (xy 295.045384 -401.506944)
			(xy 295.077131 -401.507444) (xy 295.140127 -401.515377) (xy 295.201647 -401.531084) (xy 295.260736 -401.554322)
			(xy 295.316476 -401.584728) (xy 295.368 -401.621832) (xy 295.391586 -401.643088) (xy 295.398849 -401.649272)
			(xy 295.416599 -401.656223) (xy 295.435661 -401.656223) (xy 295.453411 -401.649272) (xy 295.460674 -401.643088)
			(xy 295.48425 -401.621817) (xy 295.535761 -401.584686) (xy 295.591498 -401.554265) (xy 295.650592 -401.531026)
			(xy 295.712121 -401.515332) (xy 295.775126 -401.507429) (xy 295.806876 -401.506944) (xy 295.80713 -401.506944)
			(xy 295.839087 -401.507544) (xy 295.902496 -401.515558) (xy 295.964401 -401.531455) (xy 296.023825 -401.554986)
			(xy 296.079832 -401.585779) (xy 296.131538 -401.623348) (xy 296.178128 -401.667102) (xy 296.218866 -401.716349)
			(xy 296.253112 -401.770314) (xy 296.280324 -401.828145) (xy 296.300074 -401.888931) (xy 296.312049 -401.951712)
			(xy 296.316063 -402.0155) (xy 297.07602 -402.0155) (xy 297.080035 -401.951693) (xy 297.092015 -401.888892)
			(xy 297.111773 -401.828089) (xy 297.138995 -401.770241) (xy 297.173253 -401.716261) (xy 297.214007 -401.667001)
			(xy 297.260613 -401.623237) (xy 297.312338 -401.58566) (xy 297.368364 -401.554862) (xy 297.427809 -401.531329)
			(xy 297.489734 -401.515433) (xy 297.553163 -401.507423) (xy 297.58513 -401.506944) (xy 297.585384 -401.506944)
			(xy 297.617131 -401.507444) (xy 297.680127 -401.515377) (xy 297.741647 -401.531084) (xy 297.800736 -401.554322)
			(xy 297.856476 -401.584728) (xy 297.908 -401.621832) (xy 297.931586 -401.643088) (xy 297.938849 -401.649272)
			(xy 297.956599 -401.656223) (xy 297.975661 -401.656223) (xy 297.993411 -401.649272) (xy 298.000674 -401.643088)
			(xy 298.02425 -401.621817) (xy 298.075761 -401.584686) (xy 298.131498 -401.554265) (xy 298.190592 -401.531026)
			(xy 298.252121 -401.515332) (xy 298.315126 -401.507429) (xy 298.346876 -401.506944) (xy 298.34713 -401.506944)
			(xy 298.379087 -401.507544) (xy 298.442496 -401.515558) (xy 298.504401 -401.531455) (xy 298.563825 -401.554986)
			(xy 298.619832 -401.585779) (xy 298.671538 -401.623348) (xy 298.718128 -401.667102) (xy 298.758866 -401.716349)
			(xy 298.793112 -401.770314) (xy 298.820324 -401.828145) (xy 298.840074 -401.888931) (xy 298.852049 -401.951712)
			(xy 298.856063 -402.0155) (xy 298.852049 -402.079288) (xy 298.840074 -402.142069) (xy 298.820324 -402.202855)
			(xy 298.793112 -402.260686) (xy 298.758866 -402.314651) (xy 298.718128 -402.363898) (xy 298.671538 -402.407652)
			(xy 298.619832 -402.445221) (xy 298.563825 -402.476014) (xy 298.504401 -402.499545) (xy 298.442496 -402.515442)
			(xy 298.379087 -402.523456) (xy 298.34713 -402.52396) (xy 298.346876 -402.52396) (xy 298.315131 -402.523422)
			(xy 298.252136 -402.515497) (xy 298.190616 -402.499797) (xy 298.131527 -402.476566) (xy 298.075787 -402.446166)
			(xy 298.024261 -402.409069) (xy 298.000674 -402.387816) (xy 297.993411 -402.381632) (xy 297.975661 -402.374681)
			(xy 297.956599 -402.374681) (xy 297.938849 -402.381632) (xy 297.931586 -402.387816) (xy 297.908028 -402.409107)
			(xy 297.856512 -402.446235) (xy 297.800771 -402.476654) (xy 297.741674 -402.499889) (xy 297.680142 -402.515579)
			(xy 297.617135 -402.523478) (xy 297.585384 -402.52396) (xy 297.58513 -402.52396) (xy 297.553163 -402.523577)
			(xy 297.489734 -402.515567) (xy 297.427809 -402.499671) (xy 297.368364 -402.476138) (xy 297.312338 -402.44534)
			(xy 297.260613 -402.407763) (xy 297.214007 -402.363999) (xy 297.173253 -402.314739) (xy 297.138995 -402.260759)
			(xy 297.111773 -402.202911) (xy 297.092015 -402.142108) (xy 297.080035 -402.079307) (xy 297.07602 -402.0155)
			(xy 296.316063 -402.0155) (xy 296.312049 -402.079288) (xy 296.300074 -402.142069) (xy 296.280324 -402.202855)
			(xy 296.253112 -402.260686) (xy 296.218866 -402.314651) (xy 296.178128 -402.363898) (xy 296.131538 -402.407652)
			(xy 296.079832 -402.445221) (xy 296.023825 -402.476014) (xy 295.964401 -402.499545) (xy 295.902496 -402.515442)
			(xy 295.839087 -402.523456) (xy 295.80713 -402.52396) (xy 295.806876 -402.52396) (xy 295.775131 -402.523422)
			(xy 295.712136 -402.515497) (xy 295.650616 -402.499797) (xy 295.591527 -402.476566) (xy 295.535787 -402.446166)
			(xy 295.484261 -402.409069) (xy 295.460674 -402.387816) (xy 295.453411 -402.381632) (xy 295.435661 -402.374681)
			(xy 295.416599 -402.374681) (xy 295.398849 -402.381632) (xy 295.391586 -402.387816) (xy 295.368028 -402.409107)
			(xy 295.316512 -402.446235) (xy 295.260771 -402.476654) (xy 295.201674 -402.499889) (xy 295.140142 -402.515579)
			(xy 295.077135 -402.523478) (xy 295.045384 -402.52396) (xy 295.04513 -402.52396) (xy 295.013163 -402.523577)
			(xy 294.949734 -402.515567) (xy 294.887809 -402.499671) (xy 294.828364 -402.476138) (xy 294.772338 -402.44534)
			(xy 294.720613 -402.407763) (xy 294.674007 -402.363999) (xy 294.633253 -402.314739) (xy 294.598995 -402.260759)
			(xy 294.571773 -402.202911) (xy 294.552015 -402.142108) (xy 294.540035 -402.079307) (xy 294.53602 -402.0155)
			(xy 293.926484 -402.0155) (xy 293.92247 -402.079293) (xy 293.910493 -402.142079) (xy 293.890741 -402.20287)
			(xy 293.863525 -402.260705) (xy 293.829276 -402.314674) (xy 293.788532 -402.363924) (xy 293.741937 -402.407679)
			(xy 293.690226 -402.44525) (xy 293.634213 -402.476043) (xy 293.574783 -402.499573) (xy 293.512872 -402.515468)
			(xy 293.449457 -402.523479) (xy 293.417498 -402.52396) (xy 293.417244 -402.52396) (xy 293.385498 -402.523442)
			(xy 293.322502 -402.515512) (xy 293.260982 -402.499809) (xy 293.201894 -402.476575) (xy 293.146154 -402.446171)
			(xy 293.094629 -402.40907) (xy 293.071042 -402.387816) (xy 293.063779 -402.381632) (xy 293.046029 -402.374681)
			(xy 293.026967 -402.374681) (xy 293.009217 -402.381632) (xy 293.001954 -402.387816) (xy 292.978367 -402.409074)
			(xy 292.926858 -402.446206) (xy 292.871123 -402.47663) (xy 292.812032 -402.499871) (xy 292.750504 -402.515567)
			(xy 292.687501 -402.523474) (xy 292.655752 -402.52396) (xy 292.655498 -402.52396) (xy 292.623534 -402.523554)
			(xy 292.56011 -402.515542) (xy 292.498191 -402.499643) (xy 292.438752 -402.47611) (xy 292.382731 -402.445312)
			(xy 292.331013 -402.407736) (xy 292.284411 -402.363974) (xy 292.243662 -402.314717) (xy 292.209408 -402.26074)
			(xy 292.182189 -402.202897) (xy 292.162434 -402.142098) (xy 292.150455 -402.079302) (xy 292.146441 -402.0155)
			(xy 291.386484 -402.0155) (xy 291.38247 -402.079293) (xy 291.370493 -402.142079) (xy 291.350741 -402.20287)
			(xy 291.323525 -402.260705) (xy 291.289276 -402.314674) (xy 291.248532 -402.363924) (xy 291.201937 -402.407679)
			(xy 291.150226 -402.44525) (xy 291.094213 -402.476043) (xy 291.034783 -402.499573) (xy 290.972872 -402.515468)
			(xy 290.909457 -402.523479) (xy 290.877498 -402.52396) (xy 290.877244 -402.52396) (xy 290.845498 -402.523442)
			(xy 290.782502 -402.515512) (xy 290.720982 -402.499809) (xy 290.661894 -402.476575) (xy 290.606154 -402.446171)
			(xy 290.554629 -402.40907) (xy 290.531042 -402.387816) (xy 290.523779 -402.381632) (xy 290.506029 -402.374681)
			(xy 290.486967 -402.374681) (xy 290.469217 -402.381632) (xy 290.461954 -402.387816) (xy 290.438367 -402.409074)
			(xy 290.386858 -402.446206) (xy 290.331123 -402.47663) (xy 290.272032 -402.499871) (xy 290.210504 -402.515567)
			(xy 290.147501 -402.523474) (xy 290.115752 -402.52396) (xy 290.115498 -402.52396) (xy 290.083534 -402.523554)
			(xy 290.02011 -402.515542) (xy 289.958191 -402.499643) (xy 289.898752 -402.47611) (xy 289.842731 -402.445312)
			(xy 289.791013 -402.407736) (xy 289.744411 -402.363974) (xy 289.703662 -402.314717) (xy 289.669408 -402.26074)
			(xy 289.642189 -402.202897) (xy 289.622434 -402.142098) (xy 289.610455 -402.079302) (xy 289.606441 -402.0155)
			(xy 288.846484 -402.0155) (xy 288.84247 -402.079293) (xy 288.830493 -402.142079) (xy 288.810741 -402.20287)
			(xy 288.783525 -402.260705) (xy 288.749276 -402.314674) (xy 288.708532 -402.363924) (xy 288.661937 -402.407679)
			(xy 288.610226 -402.44525) (xy 288.554213 -402.476043) (xy 288.494783 -402.499573) (xy 288.432872 -402.515468)
			(xy 288.369457 -402.523479) (xy 288.337498 -402.52396) (xy 288.337244 -402.52396) (xy 288.305498 -402.523442)
			(xy 288.242502 -402.515512) (xy 288.180982 -402.499809) (xy 288.121894 -402.476575) (xy 288.066154 -402.446171)
			(xy 288.014629 -402.40907) (xy 287.991042 -402.387816) (xy 287.983779 -402.381632) (xy 287.966029 -402.374681)
			(xy 287.946967 -402.374681) (xy 287.929217 -402.381632) (xy 287.921954 -402.387816) (xy 287.898367 -402.409074)
			(xy 287.846858 -402.446206) (xy 287.791123 -402.47663) (xy 287.732032 -402.499871) (xy 287.670504 -402.515567)
			(xy 287.607501 -402.523474) (xy 287.575752 -402.52396) (xy 287.575498 -402.52396) (xy 287.543534 -402.523554)
			(xy 287.48011 -402.515542) (xy 287.418191 -402.499643) (xy 287.358752 -402.47611) (xy 287.302731 -402.445312)
			(xy 287.251013 -402.407736) (xy 287.204411 -402.363974) (xy 287.163662 -402.314717) (xy 287.129408 -402.26074)
			(xy 287.102189 -402.202897) (xy 287.082434 -402.142098) (xy 287.070455 -402.079302) (xy 287.066441 -402.0155)
			(xy 280.76398 -402.0155) (xy 280.76398 -402.1074) (xy 280.76343 -402.132362) (xy 280.753694 -402.181326)
			(xy 280.734578 -402.227444) (xy 280.706818 -402.268937) (xy 280.689558 -402.286978) (xy 280.501598 -402.474938)
			(xy 280.483557 -402.492195) (xy 280.442055 -402.519934) (xy 280.395938 -402.539043) (xy 280.346979 -402.548787)
			(xy 280.32202 -402.54936) (xy 239.86236 -402.54936) (xy 239.8374 -402.548779) (xy 239.788437 -402.539054)
			(xy 239.742319 -402.519947) (xy 239.700824 -402.492195) (xy 239.682782 -402.474938) (xy 239.497362 -402.289518)
			(xy 239.480115 -402.271468) (xy 239.452373 -402.229969) (xy 239.433262 -402.183855) (xy 239.423515 -402.134899)
			(xy 239.42294 -402.10994) (xy 2.509012 -402.10994) (xy 2.509012 -402.656674) (xy 98.152872 -402.656674)
			(xy 98.152872 -402.602126) (xy 98.160635 -402.548133) (xy 98.176003 -402.495795) (xy 98.198664 -402.446176)
			(xy 98.228156 -402.400288) (xy 98.263878 -402.359064) (xy 98.305104 -402.323344) (xy 98.350994 -402.293855)
			(xy 98.400613 -402.271196) (xy 98.452953 -402.255831) (xy 98.506946 -402.24807) (xy 98.53422 -402.247608)
			(xy 99.39782 -402.247608) (xy 99.425086 -402.248156) (xy 99.479063 -402.255919) (xy 99.531387 -402.271285)
			(xy 99.58099 -402.293941) (xy 99.626865 -402.323425) (xy 99.668077 -402.359137) (xy 99.703787 -402.400351)
			(xy 99.733269 -402.446227) (xy 99.755922 -402.495832) (xy 99.771285 -402.548156) (xy 99.779046 -402.602134)
			(xy 99.779046 -402.656666) (xy 99.771285 -402.710644) (xy 99.755922 -402.762968) (xy 99.733269 -402.812573)
			(xy 99.703787 -402.858449) (xy 99.668077 -402.899663) (xy 99.626865 -402.935375) (xy 99.58099 -402.964859)
			(xy 99.531387 -402.987515) (xy 99.479063 -403.002881) (xy 99.425086 -403.010644) (xy 99.39782 -403.011132)
			(xy 98.53422 -403.011132) (xy 98.506946 -403.01073) (xy 98.452953 -403.002969) (xy 98.400613 -402.987604)
			(xy 98.350994 -402.964945) (xy 98.305104 -402.935456) (xy 98.263878 -402.899736) (xy 98.228156 -402.858512)
			(xy 98.198664 -402.812624) (xy 98.176003 -402.763005) (xy 98.160635 -402.710667) (xy 98.152872 -402.656674)
			(xy 2.509012 -402.656674) (xy 2.509012 -403.371812) (xy 2.5095 -403.425034) (xy 2.517117 -403.531207)
			(xy 2.532283 -403.636566) (xy 2.554922 -403.740575) (xy 2.584919 -403.842706) (xy 2.610452 -403.911156)
			(xy 47.598731 -403.911156) (xy 47.598731 -403.856644) (xy 47.606489 -403.802686) (xy 47.621848 -403.750382)
			(xy 47.644495 -403.700796) (xy 47.673969 -403.654938) (xy 47.709669 -403.613742) (xy 47.750868 -403.578046)
			(xy 47.796729 -403.548577) (xy 47.846317 -403.525935) (xy 47.898623 -403.510581) (xy 47.952582 -403.502828)
			(xy 47.979838 -403.502368) (xy 48.843438 -403.502368) (xy 48.870686 -403.502905) (xy 48.924626 -403.510665)
			(xy 48.976913 -403.526023) (xy 49.026482 -403.548665) (xy 49.072325 -403.57813) (xy 49.113508 -403.613819)
			(xy 49.149193 -403.655006) (xy 49.178654 -403.700851) (xy 49.201291 -403.750423) (xy 49.216643 -403.802711)
			(xy 49.224398 -403.856652) (xy 49.224398 -403.911148) (xy 49.224397 -403.911152) (xy 50.662054 -403.911152)
			(xy 50.662054 -403.856648) (xy 50.66981 -403.802699) (xy 50.685165 -403.750403) (xy 50.707806 -403.700824)
			(xy 50.737272 -403.654971) (xy 50.772964 -403.613779) (xy 50.814154 -403.578085) (xy 50.860004 -403.548617)
			(xy 50.909582 -403.525973) (xy 50.961877 -403.510615) (xy 51.015826 -403.502855) (xy 51.043078 -403.502368)
			(xy 51.906678 -403.502368) (xy 51.93393 -403.502878) (xy 51.98788 -403.510632) (xy 52.040177 -403.525985)
			(xy 52.089757 -403.548625) (xy 52.13561 -403.57809) (xy 52.176803 -403.613782) (xy 52.212497 -403.654972)
			(xy 52.241965 -403.700824) (xy 52.264607 -403.750402) (xy 52.279964 -403.802698) (xy 52.287721 -403.856648)
			(xy 52.287721 -403.911152) (xy 52.287721 -403.911155) (xy 53.725231 -403.911155) (xy 53.725231 -403.856645)
			(xy 53.732989 -403.802689) (xy 53.748347 -403.750386) (xy 53.770992 -403.700801) (xy 53.800464 -403.654945)
			(xy 53.836162 -403.613749) (xy 53.877359 -403.578053) (xy 53.923217 -403.548583) (xy 53.972803 -403.525941)
			(xy 54.025106 -403.510585) (xy 54.079063 -403.50283) (xy 54.106318 -403.502368) (xy 54.969918 -403.502368)
			(xy 54.997167 -403.502903) (xy 55.051109 -403.510662) (xy 55.103398 -403.526017) (xy 55.15297 -403.548658)
			(xy 55.198815 -403.578123) (xy 55.240001 -403.613812) (xy 55.275688 -403.654999) (xy 55.305151 -403.700846)
			(xy 55.327789 -403.750419) (xy 55.343142 -403.802709) (xy 55.350898 -403.856651) (xy 55.350898 -403.911149)
			(xy 55.350898 -403.911151) (xy 56.788554 -403.911151) (xy 56.788554 -403.856649) (xy 56.79631 -403.802702)
			(xy 56.811664 -403.750407) (xy 56.834303 -403.700829) (xy 56.863767 -403.654978) (xy 56.899457 -403.613786)
			(xy 56.940644 -403.578093) (xy 56.986492 -403.548623) (xy 57.036067 -403.525978) (xy 57.08836 -403.510619)
			(xy 57.142307 -403.502857) (xy 57.169558 -403.502368) (xy 58.033158 -403.502368) (xy 58.060411 -403.502876)
			(xy 58.114363 -403.510628) (xy 58.166663 -403.525979) (xy 58.216245 -403.548618) (xy 58.262101 -403.578083)
			(xy 58.303296 -403.613775) (xy 58.338992 -403.654966) (xy 58.368462 -403.700818) (xy 58.391106 -403.750398)
			(xy 58.406463 -403.802696) (xy 58.414221 -403.856647) (xy 58.414221 -403.911153) (xy 59.851754 -403.911153)
			(xy 59.851754 -403.856647) (xy 59.859511 -403.802696) (xy 59.874867 -403.750398) (xy 59.897509 -403.700818)
			(xy 59.926977 -403.654965) (xy 59.962671 -403.613772) (xy 60.003863 -403.578078) (xy 60.049716 -403.54861)
			(xy 60.099296 -403.525967) (xy 60.151594 -403.510611) (xy 60.205545 -403.502854) (xy 60.232798 -403.502368)
			(xy 61.096398 -403.502368) (xy 61.123649 -403.502879) (xy 61.177597 -403.510635) (xy 61.229892 -403.52599)
			(xy 61.279469 -403.548631) (xy 61.32532 -403.578097) (xy 61.36651 -403.613789) (xy 61.402201 -403.654979)
			(xy 61.431668 -403.700829) (xy 61.454309 -403.750406) (xy 61.469664 -403.802701) (xy 61.477421 -403.856649)
			(xy 61.477421 -403.911151) (xy 61.47742 -403.911156) (xy 62.914931 -403.911156) (xy 62.914931 -403.856644)
			(xy 62.922689 -403.802686) (xy 62.938048 -403.750382) (xy 62.960695 -403.700796) (xy 62.990169 -403.654938)
			(xy 63.025869 -403.613742) (xy 63.067068 -403.578046) (xy 63.112929 -403.548577) (xy 63.162517 -403.525935)
			(xy 63.214823 -403.510581) (xy 63.268782 -403.502828) (xy 63.296038 -403.502368) (xy 64.159638 -403.502368)
			(xy 64.186886 -403.502905) (xy 64.240826 -403.510665) (xy 64.293113 -403.526023) (xy 64.342682 -403.548665)
			(xy 64.388525 -403.57813) (xy 64.429708 -403.613819) (xy 64.465393 -403.655006) (xy 64.494854 -403.700851)
			(xy 64.517491 -403.750423) (xy 64.532843 -403.802711) (xy 64.540598 -403.856652) (xy 64.540598 -403.911148)
			(xy 64.540597 -403.911152) (xy 65.978254 -403.911152) (xy 65.978254 -403.856648) (xy 65.98601 -403.802699)
			(xy 66.001365 -403.750403) (xy 66.024006 -403.700824) (xy 66.053472 -403.654971) (xy 66.089164 -403.613779)
			(xy 66.130354 -403.578085) (xy 66.176204 -403.548617) (xy 66.225782 -403.525973) (xy 66.278077 -403.510615)
			(xy 66.332026 -403.502855) (xy 66.359278 -403.502368) (xy 67.222878 -403.502368) (xy 67.25013 -403.502878)
			(xy 67.30408 -403.510632) (xy 67.356377 -403.525985) (xy 67.405957 -403.548625) (xy 67.45181 -403.57809)
			(xy 67.493003 -403.613782) (xy 67.528697 -403.654972) (xy 67.558165 -403.700824) (xy 67.580807 -403.750402)
			(xy 67.596164 -403.802698) (xy 67.603921 -403.856648) (xy 67.603921 -403.911152) (xy 67.603921 -403.911155)
			(xy 69.041431 -403.911155) (xy 69.041431 -403.856645) (xy 69.049189 -403.802689) (xy 69.064547 -403.750386)
			(xy 69.087192 -403.700801) (xy 69.116664 -403.654945) (xy 69.152362 -403.613749) (xy 69.193559 -403.578053)
			(xy 69.239417 -403.548583) (xy 69.289003 -403.525941) (xy 69.341306 -403.510585) (xy 69.395263 -403.50283)
			(xy 69.422518 -403.502368) (xy 70.286118 -403.502368) (xy 70.313367 -403.502903) (xy 70.367309 -403.510662)
			(xy 70.419598 -403.526017) (xy 70.46917 -403.548658) (xy 70.515015 -403.578123) (xy 70.556201 -403.613812)
			(xy 70.591888 -403.654999) (xy 70.621351 -403.700846) (xy 70.643989 -403.750419) (xy 70.659342 -403.802709)
			(xy 70.667098 -403.856651) (xy 70.667098 -403.911149) (xy 70.667098 -403.911151) (xy 72.104754 -403.911151)
			(xy 72.104754 -403.856649) (xy 72.11251 -403.802702) (xy 72.127864 -403.750407) (xy 72.150503 -403.700829)
			(xy 72.179967 -403.654978) (xy 72.215657 -403.613786) (xy 72.256844 -403.578093) (xy 72.302692 -403.548623)
			(xy 72.352267 -403.525978) (xy 72.40456 -403.510619) (xy 72.458507 -403.502857) (xy 72.485758 -403.502368)
			(xy 73.349358 -403.502368) (xy 73.376611 -403.502876) (xy 73.430563 -403.510628) (xy 73.482863 -403.525979)
			(xy 73.532445 -403.548618) (xy 73.578301 -403.578083) (xy 73.619496 -403.613775) (xy 73.655192 -403.654966)
			(xy 73.684662 -403.700818) (xy 73.707306 -403.750398) (xy 73.722663 -403.802696) (xy 73.730421 -403.856647)
			(xy 73.730421 -403.911153) (xy 75.167954 -403.911153) (xy 75.167954 -403.856647) (xy 75.175711 -403.802696)
			(xy 75.191067 -403.750398) (xy 75.213709 -403.700818) (xy 75.243177 -403.654965) (xy 75.278871 -403.613772)
			(xy 75.320063 -403.578078) (xy 75.365916 -403.54861) (xy 75.415496 -403.525967) (xy 75.467794 -403.510611)
			(xy 75.521745 -403.502854) (xy 75.548998 -403.502368) (xy 76.412598 -403.502368) (xy 76.439849 -403.502879)
			(xy 76.493797 -403.510635) (xy 76.546092 -403.52599) (xy 76.595669 -403.548631) (xy 76.64152 -403.578097)
			(xy 76.68271 -403.613789) (xy 76.718401 -403.654979) (xy 76.747868 -403.700829) (xy 76.770509 -403.750406)
			(xy 76.785864 -403.802701) (xy 76.793621 -403.856649) (xy 76.793621 -403.911151) (xy 76.79362 -403.911156)
			(xy 78.231131 -403.911156) (xy 78.231131 -403.856644) (xy 78.238889 -403.802686) (xy 78.254248 -403.750382)
			(xy 78.276895 -403.700796) (xy 78.306369 -403.654938) (xy 78.342069 -403.613742) (xy 78.383268 -403.578046)
			(xy 78.429129 -403.548577) (xy 78.478717 -403.525935) (xy 78.531023 -403.510581) (xy 78.584982 -403.502828)
			(xy 78.612238 -403.502368) (xy 79.475838 -403.502368) (xy 79.503086 -403.502905) (xy 79.557026 -403.510665)
			(xy 79.609313 -403.526023) (xy 79.658882 -403.548665) (xy 79.704725 -403.57813) (xy 79.745908 -403.613819)
			(xy 79.781593 -403.655006) (xy 79.811054 -403.700851) (xy 79.833691 -403.750423) (xy 79.849043 -403.802711)
			(xy 79.856798 -403.856652) (xy 79.856798 -403.911148) (xy 79.856797 -403.911152) (xy 81.294454 -403.911152)
			(xy 81.294454 -403.856648) (xy 81.30221 -403.802699) (xy 81.317565 -403.750403) (xy 81.340206 -403.700824)
			(xy 81.369672 -403.654971) (xy 81.405364 -403.613779) (xy 81.446554 -403.578085) (xy 81.492404 -403.548617)
			(xy 81.541982 -403.525973) (xy 81.594277 -403.510615) (xy 81.648226 -403.502855) (xy 81.675478 -403.502368)
			(xy 82.539078 -403.502368) (xy 82.56633 -403.502878) (xy 82.62028 -403.510632) (xy 82.672577 -403.525985)
			(xy 82.722157 -403.548625) (xy 82.76801 -403.57809) (xy 82.809203 -403.613782) (xy 82.844897 -403.654972)
			(xy 82.874365 -403.700824) (xy 82.897007 -403.750402) (xy 82.912364 -403.802698) (xy 82.920121 -403.856648)
			(xy 82.920121 -403.911152) (xy 82.920121 -403.911155) (xy 84.357631 -403.911155) (xy 84.357631 -403.856645)
			(xy 84.365389 -403.802689) (xy 84.380747 -403.750386) (xy 84.403392 -403.700801) (xy 84.432864 -403.654945)
			(xy 84.468562 -403.613749) (xy 84.509759 -403.578053) (xy 84.555617 -403.548583) (xy 84.605203 -403.525941)
			(xy 84.657506 -403.510585) (xy 84.711463 -403.50283) (xy 84.738718 -403.502368) (xy 85.602318 -403.502368)
			(xy 85.629567 -403.502903) (xy 85.683509 -403.510662) (xy 85.735798 -403.526017) (xy 85.78537 -403.548658)
			(xy 85.831215 -403.578123) (xy 85.872401 -403.613812) (xy 85.908088 -403.654999) (xy 85.937551 -403.700846)
			(xy 85.960189 -403.750419) (xy 85.975542 -403.802709) (xy 85.983298 -403.856651) (xy 85.983298 -403.911149)
			(xy 85.983298 -403.911151) (xy 87.420954 -403.911151) (xy 87.420954 -403.856649) (xy 87.42871 -403.802702)
			(xy 87.444064 -403.750407) (xy 87.466703 -403.700829) (xy 87.496167 -403.654978) (xy 87.531857 -403.613786)
			(xy 87.573044 -403.578093) (xy 87.618892 -403.548623) (xy 87.668467 -403.525978) (xy 87.72076 -403.510619)
			(xy 87.774707 -403.502857) (xy 87.801958 -403.502368) (xy 88.665558 -403.502368) (xy 88.692811 -403.502876)
			(xy 88.746763 -403.510628) (xy 88.799063 -403.525979) (xy 88.848645 -403.548618) (xy 88.894501 -403.578083)
			(xy 88.935696 -403.613775) (xy 88.971392 -403.654966) (xy 89.000862 -403.700818) (xy 89.023506 -403.750398)
			(xy 89.038863 -403.802696) (xy 89.046621 -403.856647) (xy 89.046621 -403.911153) (xy 90.484154 -403.911153)
			(xy 90.484154 -403.856647) (xy 90.491911 -403.802696) (xy 90.507267 -403.750398) (xy 90.529909 -403.700818)
			(xy 90.559377 -403.654965) (xy 90.595071 -403.613772) (xy 90.636263 -403.578078) (xy 90.682116 -403.54861)
			(xy 90.731696 -403.525967) (xy 90.783994 -403.510611) (xy 90.837945 -403.502854) (xy 90.865198 -403.502368)
			(xy 91.728798 -403.502368) (xy 91.756049 -403.502879) (xy 91.809997 -403.510635) (xy 91.862292 -403.52599)
			(xy 91.911869 -403.548631) (xy 91.95772 -403.578097) (xy 91.99891 -403.613789) (xy 92.034601 -403.654979)
			(xy 92.064068 -403.700829) (xy 92.086709 -403.750406) (xy 92.102064 -403.802701) (xy 92.109821 -403.856649)
			(xy 92.109821 -403.911151) (xy 92.10982 -403.911156) (xy 93.547331 -403.911156) (xy 93.547331 -403.856644)
			(xy 93.555089 -403.802686) (xy 93.570448 -403.750382) (xy 93.593095 -403.700796) (xy 93.622569 -403.654938)
			(xy 93.658269 -403.613742) (xy 93.699468 -403.578046) (xy 93.745329 -403.548577) (xy 93.794917 -403.525935)
			(xy 93.847223 -403.510581) (xy 93.901182 -403.502828) (xy 93.928438 -403.502368) (xy 94.792038 -403.502368)
			(xy 94.819286 -403.502905) (xy 94.873226 -403.510665) (xy 94.925513 -403.526023) (xy 94.975082 -403.548665)
			(xy 95.020925 -403.57813) (xy 95.062108 -403.613819) (xy 95.097793 -403.655006) (xy 95.127254 -403.700851)
			(xy 95.149891 -403.750423) (xy 95.165243 -403.802711) (xy 95.172998 -403.856652) (xy 95.172998 -403.911148)
			(xy 95.172998 -403.911151) (xy 119.773954 -403.911151) (xy 119.773954 -403.856649) (xy 119.78171 -403.802702)
			(xy 119.797063 -403.750408) (xy 119.819702 -403.70083) (xy 119.849166 -403.654979) (xy 119.884855 -403.613788)
			(xy 119.926042 -403.578094) (xy 119.97189 -403.548625) (xy 120.021465 -403.525979) (xy 120.073757 -403.510619)
			(xy 120.127703 -403.502857) (xy 120.154954 -403.502368) (xy 121.018554 -403.502368) (xy 121.045807 -403.502876)
			(xy 121.09976 -403.510627) (xy 121.15206 -403.525978) (xy 121.201643 -403.548617) (xy 121.247499 -403.578082)
			(xy 121.288694 -403.613773) (xy 121.324391 -403.654964) (xy 121.353861 -403.700817) (xy 121.376506 -403.750397)
			(xy 121.391863 -403.802695) (xy 121.399621 -403.856647) (xy 121.399621 -403.911153) (xy 122.837154 -403.911153)
			(xy 122.837154 -403.856647) (xy 122.844911 -403.802697) (xy 122.860266 -403.750399) (xy 122.882909 -403.700819)
			(xy 122.912376 -403.654966) (xy 122.948069 -403.613774) (xy 122.989261 -403.57808) (xy 123.035114 -403.548611)
			(xy 123.084694 -403.525969) (xy 123.136991 -403.510612) (xy 123.190941 -403.502854) (xy 123.218194 -403.502368)
			(xy 124.081794 -403.502368) (xy 124.109045 -403.502879) (xy 124.162994 -403.510635) (xy 124.215289 -403.525989)
			(xy 124.264867 -403.54863) (xy 124.310718 -403.578096) (xy 124.351908 -403.613787) (xy 124.3876 -403.654978)
			(xy 124.417067 -403.700828) (xy 124.439709 -403.750406) (xy 124.455064 -403.802701) (xy 124.462821 -403.856649)
			(xy 124.462821 -403.911151) (xy 124.46282 -403.911156) (xy 125.900331 -403.911156) (xy 125.900331 -403.856644)
			(xy 125.908089 -403.802686) (xy 125.923448 -403.750383) (xy 125.946095 -403.700797) (xy 125.975568 -403.654939)
			(xy 126.011267 -403.613743) (xy 126.052467 -403.578047) (xy 126.098327 -403.548578) (xy 126.147914 -403.525936)
			(xy 126.20022 -403.510582) (xy 126.254178 -403.502829) (xy 126.281434 -403.502368) (xy 127.145034 -403.502368)
			(xy 127.172282 -403.502905) (xy 127.226223 -403.510664) (xy 127.27851 -403.526022) (xy 127.32808 -403.548663)
			(xy 127.373923 -403.578129) (xy 127.415106 -403.613818) (xy 127.450792 -403.655004) (xy 127.480253 -403.70085)
			(xy 127.50289 -403.750422) (xy 127.518243 -403.802711) (xy 127.525998 -403.856652) (xy 127.525998 -403.911148)
			(xy 127.525997 -403.911152) (xy 128.963654 -403.911152) (xy 128.963654 -403.856648) (xy 128.97141 -403.802699)
			(xy 128.986765 -403.750403) (xy 129.009406 -403.700825) (xy 129.038871 -403.654973) (xy 129.074562 -403.613781)
			(xy 129.115752 -403.578087) (xy 129.161602 -403.548618) (xy 129.211179 -403.525974) (xy 129.263474 -403.510616)
			(xy 129.317422 -403.502856) (xy 129.344674 -403.502368) (xy 130.208274 -403.502368) (xy 130.235526 -403.502878)
			(xy 130.289477 -403.510631) (xy 130.341774 -403.525984) (xy 130.391355 -403.548623) (xy 130.437208 -403.578089)
			(xy 130.478401 -403.61378) (xy 130.514096 -403.654971) (xy 130.543564 -403.700822) (xy 130.566207 -403.750401)
			(xy 130.581563 -403.802698) (xy 130.589321 -403.856648) (xy 130.589321 -403.911152) (xy 130.589321 -403.911155)
			(xy 132.026831 -403.911155) (xy 132.026831 -403.856645) (xy 132.034589 -403.802689) (xy 132.049946 -403.750387)
			(xy 132.072591 -403.700803) (xy 132.102063 -403.654946) (xy 132.13776 -403.61375) (xy 132.178957 -403.578054)
			(xy 132.224815 -403.548585) (xy 132.2744 -403.525942) (xy 132.326703 -403.510586) (xy 132.380659 -403.50283)
			(xy 132.407914 -403.502368) (xy 133.271514 -403.502368) (xy 133.298763 -403.502903) (xy 133.352706 -403.510661)
			(xy 133.404995 -403.526016) (xy 133.454568 -403.548657) (xy 133.500413 -403.578121) (xy 133.541599 -403.613811)
			(xy 133.577287 -403.654998) (xy 133.60675 -403.700845) (xy 133.629389 -403.750418) (xy 133.644742 -403.802708)
			(xy 133.652498 -403.856651) (xy 133.652498 -403.911149) (xy 133.652498 -403.911151) (xy 135.090154 -403.911151)
			(xy 135.090154 -403.856649) (xy 135.09791 -403.802702) (xy 135.113263 -403.750408) (xy 135.135902 -403.70083)
			(xy 135.165366 -403.654979) (xy 135.201055 -403.613788) (xy 135.242242 -403.578094) (xy 135.28809 -403.548625)
			(xy 135.337665 -403.525979) (xy 135.389957 -403.510619) (xy 135.443903 -403.502857) (xy 135.471154 -403.502368)
			(xy 136.334754 -403.502368) (xy 136.362007 -403.502876) (xy 136.41596 -403.510627) (xy 136.46826 -403.525978)
			(xy 136.517843 -403.548617) (xy 136.563699 -403.578082) (xy 136.604894 -403.613773) (xy 136.640591 -403.654964)
			(xy 136.670061 -403.700817) (xy 136.692706 -403.750397) (xy 136.708063 -403.802695) (xy 136.715821 -403.856647)
			(xy 136.715821 -403.911153) (xy 138.153354 -403.911153) (xy 138.153354 -403.856647) (xy 138.161111 -403.802697)
			(xy 138.176466 -403.750399) (xy 138.199109 -403.700819) (xy 138.228576 -403.654966) (xy 138.264269 -403.613774)
			(xy 138.305461 -403.57808) (xy 138.351314 -403.548611) (xy 138.400894 -403.525969) (xy 138.453191 -403.510612)
			(xy 138.507141 -403.502854) (xy 138.534394 -403.502368) (xy 139.397994 -403.502368) (xy 139.425245 -403.502879)
			(xy 139.479194 -403.510635) (xy 139.531489 -403.525989) (xy 139.581067 -403.54863) (xy 139.626918 -403.578096)
			(xy 139.668108 -403.613787) (xy 139.7038 -403.654978) (xy 139.733267 -403.700828) (xy 139.755909 -403.750406)
			(xy 139.771264 -403.802701) (xy 139.779021 -403.856649) (xy 139.779021 -403.911151) (xy 139.77902 -403.911156)
			(xy 141.216531 -403.911156) (xy 141.216531 -403.856644) (xy 141.224289 -403.802686) (xy 141.239648 -403.750383)
			(xy 141.262295 -403.700797) (xy 141.291768 -403.654939) (xy 141.327467 -403.613743) (xy 141.368667 -403.578047)
			(xy 141.414527 -403.548578) (xy 141.464114 -403.525936) (xy 141.51642 -403.510582) (xy 141.570378 -403.502829)
			(xy 141.597634 -403.502368) (xy 142.461234 -403.502368) (xy 142.488482 -403.502905) (xy 142.542423 -403.510664)
			(xy 142.59471 -403.526022) (xy 142.64428 -403.548663) (xy 142.690123 -403.578129) (xy 142.731306 -403.613818)
			(xy 142.766992 -403.655004) (xy 142.796453 -403.70085) (xy 142.81909 -403.750422) (xy 142.834443 -403.802711)
			(xy 142.842198 -403.856652) (xy 142.842198 -403.911148) (xy 142.842197 -403.911152) (xy 144.279854 -403.911152)
			(xy 144.279854 -403.856648) (xy 144.28761 -403.802699) (xy 144.302965 -403.750403) (xy 144.325606 -403.700825)
			(xy 144.355071 -403.654973) (xy 144.390762 -403.613781) (xy 144.431952 -403.578087) (xy 144.477802 -403.548618)
			(xy 144.527379 -403.525974) (xy 144.579674 -403.510616) (xy 144.633622 -403.502856) (xy 144.660874 -403.502368)
			(xy 145.524474 -403.502368) (xy 145.551726 -403.502878) (xy 145.605677 -403.510631) (xy 145.657974 -403.525984)
			(xy 145.707555 -403.548623) (xy 145.753408 -403.578089) (xy 145.794601 -403.61378) (xy 145.830296 -403.654971)
			(xy 145.859764 -403.700822) (xy 145.882407 -403.750401) (xy 145.897763 -403.802698) (xy 145.905521 -403.856648)
			(xy 145.905521 -403.911152) (xy 145.905521 -403.911155) (xy 147.343031 -403.911155) (xy 147.343031 -403.856645)
			(xy 147.350789 -403.802689) (xy 147.366146 -403.750387) (xy 147.388791 -403.700803) (xy 147.418263 -403.654946)
			(xy 147.45396 -403.61375) (xy 147.495157 -403.578054) (xy 147.541015 -403.548585) (xy 147.5906 -403.525942)
			(xy 147.642903 -403.510586) (xy 147.696859 -403.50283) (xy 147.724114 -403.502368) (xy 148.587714 -403.502368)
			(xy 148.614963 -403.502903) (xy 148.668906 -403.510661) (xy 148.721195 -403.526016) (xy 148.770768 -403.548657)
			(xy 148.816613 -403.578121) (xy 148.857799 -403.613811) (xy 148.893487 -403.654998) (xy 148.92295 -403.700845)
			(xy 148.945589 -403.750418) (xy 148.960942 -403.802708) (xy 148.968698 -403.856651) (xy 148.968698 -403.911149)
			(xy 148.968698 -403.911151) (xy 150.406354 -403.911151) (xy 150.406354 -403.856649) (xy 150.41411 -403.802702)
			(xy 150.429463 -403.750408) (xy 150.452102 -403.70083) (xy 150.481566 -403.654979) (xy 150.517255 -403.613788)
			(xy 150.558442 -403.578094) (xy 150.60429 -403.548625) (xy 150.653865 -403.525979) (xy 150.706157 -403.510619)
			(xy 150.760103 -403.502857) (xy 150.787354 -403.502368) (xy 151.650954 -403.502368) (xy 151.678207 -403.502876)
			(xy 151.73216 -403.510627) (xy 151.78446 -403.525978) (xy 151.834043 -403.548617) (xy 151.879899 -403.578082)
			(xy 151.921094 -403.613773) (xy 151.956791 -403.654964) (xy 151.986261 -403.700817) (xy 152.008906 -403.750397)
			(xy 152.024263 -403.802695) (xy 152.032021 -403.856647) (xy 152.032021 -403.911153) (xy 153.469554 -403.911153)
			(xy 153.469554 -403.856647) (xy 153.477311 -403.802697) (xy 153.492666 -403.750399) (xy 153.515309 -403.700819)
			(xy 153.544776 -403.654966) (xy 153.580469 -403.613774) (xy 153.621661 -403.57808) (xy 153.667514 -403.548611)
			(xy 153.717094 -403.525969) (xy 153.769391 -403.510612) (xy 153.823341 -403.502854) (xy 153.850594 -403.502368)
			(xy 154.714194 -403.502368) (xy 154.741445 -403.502879) (xy 154.795394 -403.510635) (xy 154.847689 -403.525989)
			(xy 154.897267 -403.54863) (xy 154.943118 -403.578096) (xy 154.984308 -403.613787) (xy 155.02 -403.654978)
			(xy 155.049467 -403.700828) (xy 155.072109 -403.750406) (xy 155.087464 -403.802701) (xy 155.095221 -403.856649)
			(xy 155.095221 -403.911151) (xy 155.09522 -403.911156) (xy 156.532731 -403.911156) (xy 156.532731 -403.856644)
			(xy 156.540489 -403.802686) (xy 156.555848 -403.750383) (xy 156.578495 -403.700797) (xy 156.607968 -403.654939)
			(xy 156.643667 -403.613743) (xy 156.684867 -403.578047) (xy 156.730727 -403.548578) (xy 156.780314 -403.525936)
			(xy 156.83262 -403.510582) (xy 156.886578 -403.502829) (xy 156.913834 -403.502368) (xy 157.777434 -403.502368)
			(xy 157.804682 -403.502905) (xy 157.858623 -403.510664) (xy 157.91091 -403.526022) (xy 157.96048 -403.548663)
			(xy 158.006323 -403.578129) (xy 158.047506 -403.613818) (xy 158.083192 -403.655004) (xy 158.112653 -403.70085)
			(xy 158.13529 -403.750422) (xy 158.150643 -403.802711) (xy 158.158398 -403.856652) (xy 158.158398 -403.911148)
			(xy 158.158397 -403.911152) (xy 159.596054 -403.911152) (xy 159.596054 -403.856648) (xy 159.60381 -403.802699)
			(xy 159.619165 -403.750403) (xy 159.641806 -403.700825) (xy 159.671271 -403.654973) (xy 159.706962 -403.613781)
			(xy 159.748152 -403.578087) (xy 159.794002 -403.548618) (xy 159.843579 -403.525974) (xy 159.895874 -403.510616)
			(xy 159.949822 -403.502856) (xy 159.977074 -403.502368) (xy 160.840674 -403.502368) (xy 160.867926 -403.502878)
			(xy 160.921877 -403.510631) (xy 160.974174 -403.525984) (xy 161.023755 -403.548623) (xy 161.069608 -403.578089)
			(xy 161.110801 -403.61378) (xy 161.146496 -403.654971) (xy 161.175964 -403.700822) (xy 161.198607 -403.750401)
			(xy 161.213963 -403.802698) (xy 161.221721 -403.856648) (xy 161.221721 -403.911152) (xy 161.221721 -403.911155)
			(xy 162.659231 -403.911155) (xy 162.659231 -403.856645) (xy 162.666989 -403.802689) (xy 162.682346 -403.750387)
			(xy 162.704991 -403.700803) (xy 162.734463 -403.654946) (xy 162.77016 -403.61375) (xy 162.811357 -403.578054)
			(xy 162.857215 -403.548585) (xy 162.9068 -403.525942) (xy 162.959103 -403.510586) (xy 163.013059 -403.50283)
			(xy 163.040314 -403.502368) (xy 163.903914 -403.502368) (xy 163.931163 -403.502903) (xy 163.985106 -403.510661)
			(xy 164.037395 -403.526016) (xy 164.086968 -403.548657) (xy 164.132813 -403.578121) (xy 164.173999 -403.613811)
			(xy 164.209687 -403.654998) (xy 164.23915 -403.700845) (xy 164.261789 -403.750418) (xy 164.277142 -403.802708)
			(xy 164.284898 -403.856651) (xy 164.284898 -403.911149) (xy 164.284898 -403.911151) (xy 165.722554 -403.911151)
			(xy 165.722554 -403.856649) (xy 165.73031 -403.802702) (xy 165.745663 -403.750408) (xy 165.768302 -403.70083)
			(xy 165.797766 -403.654979) (xy 165.833455 -403.613788) (xy 165.874642 -403.578094) (xy 165.92049 -403.548625)
			(xy 165.970065 -403.525979) (xy 166.022357 -403.510619) (xy 166.076303 -403.502857) (xy 166.103554 -403.502368)
			(xy 166.967154 -403.502368) (xy 166.994407 -403.502876) (xy 167.04836 -403.510627) (xy 167.10066 -403.525978)
			(xy 167.150243 -403.548617) (xy 167.196099 -403.578082) (xy 167.237294 -403.613773) (xy 167.272991 -403.654964)
			(xy 167.302461 -403.700817) (xy 167.325106 -403.750397) (xy 167.340463 -403.802695) (xy 167.348221 -403.856647)
			(xy 167.348221 -403.911153) (xy 167.340463 -403.965105) (xy 167.325106 -404.017403) (xy 167.31136 -404.0475)
			(xy 287.066441 -404.0475) (xy 287.070455 -403.983698) (xy 287.082434 -403.920902) (xy 287.102189 -403.860103)
			(xy 287.129408 -403.80226) (xy 287.163662 -403.748283) (xy 287.204411 -403.699026) (xy 287.251013 -403.655264)
			(xy 287.302731 -403.617688) (xy 287.358752 -403.58689) (xy 287.418191 -403.563357) (xy 287.48011 -403.547458)
			(xy 287.543534 -403.539446) (xy 287.575498 -403.538944) (xy 287.575752 -403.538944) (xy 287.607498 -403.539464)
			(xy 287.670494 -403.547393) (xy 287.732014 -403.563096) (xy 287.791102 -403.58633) (xy 287.846842 -403.616733)
			(xy 287.898367 -403.653834) (xy 287.921954 -403.675088) (xy 287.929217 -403.681272) (xy 287.946967 -403.688223)
			(xy 287.966029 -403.688223) (xy 287.983779 -403.681272) (xy 287.991042 -403.675088) (xy 288.014631 -403.653832)
			(xy 288.06614 -403.6167) (xy 288.121874 -403.586276) (xy 288.180965 -403.563035) (xy 288.242492 -403.547338)
			(xy 288.305495 -403.539431) (xy 288.337244 -403.538944) (xy 288.337498 -403.538944) (xy 288.369457 -403.539521)
			(xy 288.432872 -403.547532) (xy 288.494783 -403.563427) (xy 288.554213 -403.586957) (xy 288.610226 -403.61775)
			(xy 288.661937 -403.655321) (xy 288.708532 -403.699076) (xy 288.749276 -403.748326) (xy 288.783525 -403.802295)
			(xy 288.810741 -403.86013) (xy 288.830493 -403.920921) (xy 288.84247 -403.983707) (xy 288.846484 -404.0475)
			(xy 289.606441 -404.0475) (xy 289.610455 -403.983698) (xy 289.622434 -403.920902) (xy 289.642189 -403.860103)
			(xy 289.669408 -403.80226) (xy 289.703662 -403.748283) (xy 289.744411 -403.699026) (xy 289.791013 -403.655264)
			(xy 289.842731 -403.617688) (xy 289.898752 -403.58689) (xy 289.958191 -403.563357) (xy 290.02011 -403.547458)
			(xy 290.083534 -403.539446) (xy 290.115498 -403.538944) (xy 290.115752 -403.538944) (xy 290.147498 -403.539464)
			(xy 290.210494 -403.547393) (xy 290.272014 -403.563096) (xy 290.331102 -403.58633) (xy 290.386842 -403.616733)
			(xy 290.438367 -403.653834) (xy 290.461954 -403.675088) (xy 290.469217 -403.681272) (xy 290.486967 -403.688223)
			(xy 290.506029 -403.688223) (xy 290.523779 -403.681272) (xy 290.531042 -403.675088) (xy 290.554631 -403.653832)
			(xy 290.60614 -403.6167) (xy 290.661874 -403.586276) (xy 290.720965 -403.563035) (xy 290.782492 -403.547338)
			(xy 290.845495 -403.539431) (xy 290.877244 -403.538944) (xy 290.877498 -403.538944) (xy 290.909457 -403.539521)
			(xy 290.972872 -403.547532) (xy 291.034783 -403.563427) (xy 291.094213 -403.586957) (xy 291.150226 -403.61775)
			(xy 291.201937 -403.655321) (xy 291.248532 -403.699076) (xy 291.289276 -403.748326) (xy 291.323525 -403.802295)
			(xy 291.350741 -403.86013) (xy 291.370493 -403.920921) (xy 291.38247 -403.983707) (xy 291.386484 -404.0475)
			(xy 292.146441 -404.0475) (xy 292.150455 -403.983698) (xy 292.162434 -403.920902) (xy 292.182189 -403.860103)
			(xy 292.209408 -403.80226) (xy 292.243662 -403.748283) (xy 292.284411 -403.699026) (xy 292.331013 -403.655264)
			(xy 292.382731 -403.617688) (xy 292.438752 -403.58689) (xy 292.498191 -403.563357) (xy 292.56011 -403.547458)
			(xy 292.623534 -403.539446) (xy 292.655498 -403.538944) (xy 292.655752 -403.538944) (xy 292.687498 -403.539464)
			(xy 292.750494 -403.547393) (xy 292.812014 -403.563096) (xy 292.871102 -403.58633) (xy 292.926842 -403.616733)
			(xy 292.978367 -403.653834) (xy 293.001954 -403.675088) (xy 293.009217 -403.681272) (xy 293.026967 -403.688223)
			(xy 293.046029 -403.688223) (xy 293.063779 -403.681272) (xy 293.071042 -403.675088) (xy 293.094631 -403.653832)
			(xy 293.14614 -403.6167) (xy 293.201874 -403.586276) (xy 293.260965 -403.563035) (xy 293.322492 -403.547338)
			(xy 293.385495 -403.539431) (xy 293.417244 -403.538944) (xy 293.417498 -403.538944) (xy 293.449457 -403.539521)
			(xy 293.512872 -403.547532) (xy 293.574783 -403.563427) (xy 293.634213 -403.586957) (xy 293.690226 -403.61775)
			(xy 293.741937 -403.655321) (xy 293.788532 -403.699076) (xy 293.829276 -403.748326) (xy 293.863525 -403.802295)
			(xy 293.890741 -403.86013) (xy 293.910493 -403.920921) (xy 293.92247 -403.983707) (xy 293.926484 -404.0475)
			(xy 294.53602 -404.0475) (xy 294.540035 -403.983693) (xy 294.552015 -403.920892) (xy 294.571773 -403.860089)
			(xy 294.598995 -403.802241) (xy 294.633253 -403.748261) (xy 294.674007 -403.699001) (xy 294.720613 -403.655237)
			(xy 294.772338 -403.61766) (xy 294.828364 -403.586862) (xy 294.887809 -403.563329) (xy 294.949734 -403.547433)
			(xy 295.013163 -403.539423) (xy 295.04513 -403.538944) (xy 295.045384 -403.538944) (xy 295.077131 -403.539444)
			(xy 295.140127 -403.547377) (xy 295.201647 -403.563084) (xy 295.260736 -403.586322) (xy 295.316476 -403.616728)
			(xy 295.368 -403.653832) (xy 295.391586 -403.675088) (xy 295.398849 -403.681272) (xy 295.416599 -403.688223)
			(xy 295.435661 -403.688223) (xy 295.453411 -403.681272) (xy 295.460674 -403.675088) (xy 295.48425 -403.653817)
			(xy 295.535761 -403.616686) (xy 295.591498 -403.586265) (xy 295.650592 -403.563026) (xy 295.712121 -403.547332)
			(xy 295.775126 -403.539429) (xy 295.806876 -403.538944) (xy 295.80713 -403.538944) (xy 295.839087 -403.539544)
			(xy 295.902496 -403.547558) (xy 295.964401 -403.563455) (xy 296.023825 -403.586986) (xy 296.079832 -403.617779)
			(xy 296.131538 -403.655348) (xy 296.178128 -403.699102) (xy 296.218866 -403.748349) (xy 296.253112 -403.802314)
			(xy 296.280324 -403.860145) (xy 296.300074 -403.920931) (xy 296.312049 -403.983712) (xy 296.316063 -404.0475)
			(xy 297.07602 -404.0475) (xy 297.080035 -403.983693) (xy 297.092015 -403.920892) (xy 297.111773 -403.860089)
			(xy 297.138995 -403.802241) (xy 297.173253 -403.748261) (xy 297.214007 -403.699001) (xy 297.260613 -403.655237)
			(xy 297.312338 -403.61766) (xy 297.368364 -403.586862) (xy 297.427809 -403.563329) (xy 297.489734 -403.547433)
			(xy 297.553163 -403.539423) (xy 297.58513 -403.538944) (xy 297.585384 -403.538944) (xy 297.617131 -403.539444)
			(xy 297.680127 -403.547377) (xy 297.741647 -403.563084) (xy 297.800736 -403.586322) (xy 297.856476 -403.616728)
			(xy 297.908 -403.653832) (xy 297.931586 -403.675088) (xy 297.938849 -403.681272) (xy 297.956599 -403.688223)
			(xy 297.975661 -403.688223) (xy 297.993411 -403.681272) (xy 298.000674 -403.675088) (xy 298.02425 -403.653817)
			(xy 298.075761 -403.616686) (xy 298.131498 -403.586265) (xy 298.190592 -403.563026) (xy 298.252121 -403.547332)
			(xy 298.315126 -403.539429) (xy 298.346876 -403.538944) (xy 298.34713 -403.538944) (xy 298.379087 -403.539544)
			(xy 298.442496 -403.547558) (xy 298.504401 -403.563455) (xy 298.563825 -403.586986) (xy 298.619832 -403.617779)
			(xy 298.671538 -403.655348) (xy 298.718128 -403.699102) (xy 298.758866 -403.748349) (xy 298.793112 -403.802314)
			(xy 298.820324 -403.860145) (xy 298.836897 -403.911152) (xy 303.599054 -403.911152) (xy 303.599054 -403.856648)
			(xy 303.60681 -403.802698) (xy 303.622166 -403.7504) (xy 303.644808 -403.700821) (xy 303.674275 -403.654968)
			(xy 303.709967 -403.613776) (xy 303.751159 -403.578082) (xy 303.79701 -403.548613) (xy 303.846589 -403.52597)
			(xy 303.898886 -403.510613) (xy 303.952836 -403.502855) (xy 303.980088 -403.502368) (xy 304.843688 -403.502368)
			(xy 304.87094 -403.502878) (xy 304.924889 -403.510634) (xy 304.977185 -403.525988) (xy 305.026763 -403.548628)
			(xy 305.072615 -403.578094) (xy 305.113806 -403.613785) (xy 305.149499 -403.654976) (xy 305.178966 -403.700826)
			(xy 305.201608 -403.750404) (xy 305.216964 -403.8027) (xy 305.224721 -403.856648) (xy 305.224721 -403.911152)
			(xy 305.22472 -403.911156) (xy 306.662231 -403.911156) (xy 306.662231 -403.856644) (xy 306.669989 -403.802687)
			(xy 306.685348 -403.750384) (xy 306.707994 -403.700799) (xy 306.737466 -403.654941) (xy 306.773165 -403.613745)
			(xy 306.814364 -403.578049) (xy 306.860223 -403.54858) (xy 306.90981 -403.525938) (xy 306.962115 -403.510583)
			(xy 307.016072 -403.502829) (xy 307.043328 -403.502368) (xy 307.906928 -403.502368) (xy 307.934176 -403.502904)
			(xy 307.988117 -403.510663) (xy 308.040405 -403.52602) (xy 308.089976 -403.548661) (xy 308.13582 -403.578126)
			(xy 308.177004 -403.613816) (xy 308.21269 -403.655002) (xy 308.242152 -403.700849) (xy 308.26479 -403.750421)
			(xy 308.280143 -403.80271) (xy 308.287898 -403.856652) (xy 308.287898 -403.911148) (xy 308.287897 -403.911152)
			(xy 309.725554 -403.911152) (xy 309.725554 -403.856648) (xy 309.73331 -403.8027) (xy 309.748664 -403.750405)
			(xy 309.771305 -403.700826) (xy 309.80077 -403.654975) (xy 309.83646 -403.613783) (xy 309.877649 -403.578089)
			(xy 309.923498 -403.54862) (xy 309.973075 -403.525976) (xy 310.025369 -403.510617) (xy 310.079317 -403.502856)
			(xy 310.106568 -403.502368) (xy 310.970168 -403.502368) (xy 310.997421 -403.502877) (xy 311.051372 -403.51063)
			(xy 311.10367 -403.525982) (xy 311.153251 -403.548621) (xy 311.199105 -403.578087) (xy 311.240299 -403.613778)
			(xy 311.275994 -403.654969) (xy 311.305463 -403.700821) (xy 311.328107 -403.7504) (xy 311.343463 -403.802697)
			(xy 311.351221 -403.856647) (xy 311.351221 -403.911153) (xy 311.351221 -403.911155) (xy 312.788731 -403.911155)
			(xy 312.788731 -403.856645) (xy 312.796489 -403.80269) (xy 312.811846 -403.750388) (xy 312.834491 -403.700804)
			(xy 312.863961 -403.654948) (xy 312.899658 -403.613752) (xy 312.940854 -403.578056) (xy 312.986711 -403.548587)
			(xy 313.036296 -403.525943) (xy 313.088598 -403.510587) (xy 313.142553 -403.50283) (xy 313.169808 -403.502368)
			(xy 314.033408 -403.502368) (xy 314.060657 -403.502903) (xy 314.114601 -403.51066) (xy 314.166891 -403.526015)
			(xy 314.216464 -403.548655) (xy 314.26231 -403.578119) (xy 314.303497 -403.613809) (xy 314.339186 -403.654996)
			(xy 314.368649 -403.700843) (xy 314.391288 -403.750417) (xy 314.406642 -403.802707) (xy 314.414398 -403.856651)
			(xy 314.414398 -403.911149) (xy 314.414397 -403.911157) (xy 315.851931 -403.911157) (xy 315.851931 -403.856643)
			(xy 315.85969 -403.802685) (xy 315.875049 -403.75038) (xy 315.897697 -403.700793) (xy 315.927171 -403.654935)
			(xy 315.962872 -403.613738) (xy 316.004073 -403.578042) (xy 316.049935 -403.548574) (xy 316.099525 -403.525932)
			(xy 316.151832 -403.51058) (xy 316.205791 -403.502828) (xy 316.233048 -403.502368) (xy 317.096648 -403.502368)
			(xy 317.123895 -403.502905) (xy 317.177834 -403.510667) (xy 317.23012 -403.526025) (xy 317.279688 -403.548668)
			(xy 317.325529 -403.578133) (xy 317.366711 -403.613823) (xy 317.402395 -403.655009) (xy 317.431855 -403.700854)
			(xy 317.454491 -403.750425) (xy 317.469843 -403.802713) (xy 317.477598 -403.856653) (xy 317.477598 -403.911147)
			(xy 317.477597 -403.911152) (xy 318.915254 -403.911152) (xy 318.915254 -403.856648) (xy 318.92301 -403.802698)
			(xy 318.938366 -403.7504) (xy 318.961008 -403.700821) (xy 318.990475 -403.654968) (xy 319.026167 -403.613776)
			(xy 319.067359 -403.578082) (xy 319.11321 -403.548613) (xy 319.162789 -403.52597) (xy 319.215086 -403.510613)
			(xy 319.269036 -403.502855) (xy 319.296288 -403.502368) (xy 320.159888 -403.502368) (xy 320.18714 -403.502878)
			(xy 320.241089 -403.510634) (xy 320.293385 -403.525988) (xy 320.342963 -403.548628) (xy 320.388815 -403.578094)
			(xy 320.430006 -403.613785) (xy 320.465699 -403.654976) (xy 320.495166 -403.700826) (xy 320.517808 -403.750404)
			(xy 320.533164 -403.8027) (xy 320.540921 -403.856648) (xy 320.540921 -403.911152) (xy 320.54092 -403.911156)
			(xy 321.978431 -403.911156) (xy 321.978431 -403.856644) (xy 321.986189 -403.802687) (xy 322.001548 -403.750384)
			(xy 322.024194 -403.700799) (xy 322.053666 -403.654941) (xy 322.089365 -403.613745) (xy 322.130564 -403.578049)
			(xy 322.176423 -403.54858) (xy 322.22601 -403.525938) (xy 322.278315 -403.510583) (xy 322.332272 -403.502829)
			(xy 322.359528 -403.502368) (xy 323.223128 -403.502368) (xy 323.250376 -403.502904) (xy 323.304317 -403.510663)
			(xy 323.356605 -403.52602) (xy 323.406176 -403.548661) (xy 323.45202 -403.578126) (xy 323.493204 -403.613816)
			(xy 323.52889 -403.655002) (xy 323.558352 -403.700849) (xy 323.58099 -403.750421) (xy 323.596343 -403.80271)
			(xy 323.604098 -403.856652) (xy 323.604098 -403.911148) (xy 323.604097 -403.911152) (xy 325.041754 -403.911152)
			(xy 325.041754 -403.856648) (xy 325.04951 -403.8027) (xy 325.064864 -403.750405) (xy 325.087505 -403.700826)
			(xy 325.11697 -403.654975) (xy 325.15266 -403.613783) (xy 325.193849 -403.578089) (xy 325.239698 -403.54862)
			(xy 325.289275 -403.525976) (xy 325.341569 -403.510617) (xy 325.395517 -403.502856) (xy 325.422768 -403.502368)
			(xy 326.286368 -403.502368) (xy 326.313621 -403.502877) (xy 326.367572 -403.51063) (xy 326.41987 -403.525982)
			(xy 326.469451 -403.548621) (xy 326.515305 -403.578087) (xy 326.556499 -403.613778) (xy 326.592194 -403.654969)
			(xy 326.621663 -403.700821) (xy 326.644307 -403.7504) (xy 326.659663 -403.802697) (xy 326.667421 -403.856647)
			(xy 326.667421 -403.911153) (xy 326.667421 -403.911155) (xy 328.104931 -403.911155) (xy 328.104931 -403.856645)
			(xy 328.112689 -403.80269) (xy 328.128046 -403.750388) (xy 328.150691 -403.700804) (xy 328.180161 -403.654948)
			(xy 328.215858 -403.613752) (xy 328.257054 -403.578056) (xy 328.302911 -403.548587) (xy 328.352496 -403.525943)
			(xy 328.404798 -403.510587) (xy 328.458753 -403.50283) (xy 328.486008 -403.502368) (xy 329.349608 -403.502368)
			(xy 329.376857 -403.502903) (xy 329.430801 -403.51066) (xy 329.483091 -403.526015) (xy 329.532664 -403.548655)
			(xy 329.57851 -403.578119) (xy 329.619697 -403.613809) (xy 329.655386 -403.654996) (xy 329.684849 -403.700843)
			(xy 329.707488 -403.750417) (xy 329.722842 -403.802707) (xy 329.730598 -403.856651) (xy 329.730598 -403.911149)
			(xy 329.730597 -403.911157) (xy 331.168131 -403.911157) (xy 331.168131 -403.856643) (xy 331.17589 -403.802685)
			(xy 331.191249 -403.75038) (xy 331.213897 -403.700793) (xy 331.243371 -403.654935) (xy 331.279072 -403.613738)
			(xy 331.320273 -403.578042) (xy 331.366135 -403.548574) (xy 331.415725 -403.525932) (xy 331.468032 -403.51058)
			(xy 331.521991 -403.502828) (xy 331.549248 -403.502368) (xy 332.412848 -403.502368) (xy 332.440095 -403.502905)
			(xy 332.494034 -403.510667) (xy 332.54632 -403.526025) (xy 332.595888 -403.548668) (xy 332.641729 -403.578133)
			(xy 332.682911 -403.613823) (xy 332.718595 -403.655009) (xy 332.748055 -403.700854) (xy 332.770691 -403.750425)
			(xy 332.786043 -403.802713) (xy 332.793798 -403.856653) (xy 332.793798 -403.911147) (xy 332.793797 -403.911152)
			(xy 334.231454 -403.911152) (xy 334.231454 -403.856648) (xy 334.23921 -403.802698) (xy 334.254566 -403.7504)
			(xy 334.277208 -403.700821) (xy 334.306675 -403.654968) (xy 334.342367 -403.613776) (xy 334.383559 -403.578082)
			(xy 334.42941 -403.548613) (xy 334.478989 -403.52597) (xy 334.531286 -403.510613) (xy 334.585236 -403.502855)
			(xy 334.612488 -403.502368) (xy 335.476088 -403.502368) (xy 335.50334 -403.502878) (xy 335.557289 -403.510634)
			(xy 335.609585 -403.525988) (xy 335.659163 -403.548628) (xy 335.705015 -403.578094) (xy 335.746206 -403.613785)
			(xy 335.781899 -403.654976) (xy 335.811366 -403.700826) (xy 335.834008 -403.750404) (xy 335.849364 -403.8027)
			(xy 335.857121 -403.856648) (xy 335.857121 -403.911152) (xy 335.85712 -403.911156) (xy 337.294631 -403.911156)
			(xy 337.294631 -403.856644) (xy 337.302389 -403.802687) (xy 337.317748 -403.750384) (xy 337.340394 -403.700799)
			(xy 337.369866 -403.654941) (xy 337.405565 -403.613745) (xy 337.446764 -403.578049) (xy 337.492623 -403.54858)
			(xy 337.54221 -403.525938) (xy 337.594515 -403.510583) (xy 337.648472 -403.502829) (xy 337.675728 -403.502368)
			(xy 338.539328 -403.502368) (xy 338.566576 -403.502904) (xy 338.620517 -403.510663) (xy 338.672805 -403.52602)
			(xy 338.722376 -403.548661) (xy 338.76822 -403.578126) (xy 338.809404 -403.613816) (xy 338.84509 -403.655002)
			(xy 338.874552 -403.700849) (xy 338.89719 -403.750421) (xy 338.912543 -403.80271) (xy 338.920298 -403.856652)
			(xy 338.920298 -403.911148) (xy 338.920297 -403.911152) (xy 340.357954 -403.911152) (xy 340.357954 -403.856648)
			(xy 340.36571 -403.8027) (xy 340.381064 -403.750405) (xy 340.403705 -403.700826) (xy 340.43317 -403.654975)
			(xy 340.46886 -403.613783) (xy 340.510049 -403.578089) (xy 340.555898 -403.54862) (xy 340.605475 -403.525976)
			(xy 340.657769 -403.510617) (xy 340.711717 -403.502856) (xy 340.738968 -403.502368) (xy 341.602568 -403.502368)
			(xy 341.629821 -403.502877) (xy 341.683772 -403.51063) (xy 341.73607 -403.525982) (xy 341.785651 -403.548621)
			(xy 341.831505 -403.578087) (xy 341.872699 -403.613778) (xy 341.908394 -403.654969) (xy 341.937863 -403.700821)
			(xy 341.960507 -403.7504) (xy 341.975863 -403.802697) (xy 341.983621 -403.856647) (xy 341.983621 -403.911153)
			(xy 341.983621 -403.911155) (xy 343.421131 -403.911155) (xy 343.421131 -403.856645) (xy 343.428889 -403.80269)
			(xy 343.444246 -403.750388) (xy 343.466891 -403.700804) (xy 343.496361 -403.654948) (xy 343.532058 -403.613752)
			(xy 343.573254 -403.578056) (xy 343.619111 -403.548587) (xy 343.668696 -403.525943) (xy 343.720998 -403.510587)
			(xy 343.774953 -403.50283) (xy 343.802208 -403.502368) (xy 344.665808 -403.502368) (xy 344.693057 -403.502903)
			(xy 344.747001 -403.51066) (xy 344.799291 -403.526015) (xy 344.848864 -403.548655) (xy 344.89471 -403.578119)
			(xy 344.935897 -403.613809) (xy 344.971586 -403.654996) (xy 345.001049 -403.700843) (xy 345.023688 -403.750417)
			(xy 345.039042 -403.802707) (xy 345.046798 -403.856651) (xy 345.046798 -403.911149) (xy 345.046797 -403.911157)
			(xy 346.484331 -403.911157) (xy 346.484331 -403.856643) (xy 346.49209 -403.802685) (xy 346.507449 -403.75038)
			(xy 346.530097 -403.700793) (xy 346.559571 -403.654935) (xy 346.595272 -403.613738) (xy 346.636473 -403.578042)
			(xy 346.682335 -403.548574) (xy 346.731925 -403.525932) (xy 346.784232 -403.51058) (xy 346.838191 -403.502828)
			(xy 346.865448 -403.502368) (xy 347.729048 -403.502368) (xy 347.756295 -403.502905) (xy 347.810234 -403.510667)
			(xy 347.86252 -403.526025) (xy 347.912088 -403.548668) (xy 347.957929 -403.578133) (xy 347.999111 -403.613823)
			(xy 348.034795 -403.655009) (xy 348.064255 -403.700854) (xy 348.086891 -403.750425) (xy 348.102243 -403.802713)
			(xy 348.109998 -403.856653) (xy 348.109998 -403.911147) (xy 348.109997 -403.911152) (xy 349.547654 -403.911152)
			(xy 349.547654 -403.856648) (xy 349.55541 -403.802698) (xy 349.570766 -403.7504) (xy 349.593408 -403.700821)
			(xy 349.622875 -403.654968) (xy 349.658567 -403.613776) (xy 349.699759 -403.578082) (xy 349.74561 -403.548613)
			(xy 349.795189 -403.52597) (xy 349.847486 -403.510613) (xy 349.901436 -403.502855) (xy 349.928688 -403.502368)
			(xy 350.792288 -403.502368) (xy 350.81954 -403.502878) (xy 350.873489 -403.510634) (xy 350.925785 -403.525988)
			(xy 350.975363 -403.548628) (xy 351.021215 -403.578094) (xy 351.062406 -403.613785) (xy 351.098099 -403.654976)
			(xy 351.127566 -403.700826) (xy 351.150208 -403.750404) (xy 351.165564 -403.8027) (xy 351.173321 -403.856648)
			(xy 351.173321 -403.911152) (xy 351.17332 -403.911156) (xy 371.041831 -403.911156) (xy 371.041831 -403.856644)
			(xy 371.049589 -403.802687) (xy 371.064948 -403.750383) (xy 371.087594 -403.700798) (xy 371.117067 -403.654941)
			(xy 371.152766 -403.613745) (xy 371.193965 -403.578049) (xy 371.239824 -403.54858) (xy 371.289412 -403.525937)
			(xy 371.341716 -403.510583) (xy 371.395674 -403.502829) (xy 371.42293 -403.502368) (xy 372.28653 -403.502368)
			(xy 372.313778 -403.502904) (xy 372.367719 -403.510664) (xy 372.420007 -403.52602) (xy 372.469577 -403.548662)
			(xy 372.515421 -403.578127) (xy 372.556605 -403.613816) (xy 372.592291 -403.655003) (xy 372.621753 -403.700849)
			(xy 372.64439 -403.750421) (xy 372.659743 -403.80271) (xy 372.667498 -403.856652) (xy 372.667498 -403.911148)
			(xy 372.667497 -403.911152) (xy 374.105154 -403.911152) (xy 374.105154 -403.856648) (xy 374.11291 -403.8027)
			(xy 374.128265 -403.750404) (xy 374.150905 -403.700826) (xy 374.18037 -403.654974) (xy 374.216061 -403.613782)
			(xy 374.25725 -403.578088) (xy 374.3031 -403.548619) (xy 374.352676 -403.525975) (xy 374.404971 -403.510616)
			(xy 374.458918 -403.502856) (xy 374.48617 -403.502368) (xy 375.34977 -403.502368) (xy 375.377023 -403.502877)
			(xy 375.430973 -403.51063) (xy 375.483271 -403.525983) (xy 375.532852 -403.548622) (xy 375.578706 -403.578087)
			(xy 375.6199 -403.613779) (xy 375.655595 -403.65497) (xy 375.685064 -403.700821) (xy 375.707707 -403.7504)
			(xy 375.723063 -403.802697) (xy 375.730821 -403.856647) (xy 375.730821 -403.911153) (xy 375.730821 -403.911155)
			(xy 377.168331 -403.911155) (xy 377.168331 -403.856645) (xy 377.176089 -403.80269) (xy 377.191446 -403.750388)
			(xy 377.214091 -403.700804) (xy 377.243562 -403.654947) (xy 377.279259 -403.613752) (xy 377.320455 -403.578056)
			(xy 377.366313 -403.548586) (xy 377.415897 -403.525943) (xy 377.468199 -403.510587) (xy 377.522155 -403.50283)
			(xy 377.54941 -403.502368) (xy 378.41301 -403.502368) (xy 378.440259 -403.502903) (xy 378.494202 -403.51066)
			(xy 378.546492 -403.526015) (xy 378.596065 -403.548655) (xy 378.641911 -403.57812) (xy 378.683098 -403.613809)
			(xy 378.718786 -403.654997) (xy 378.748249 -403.700844) (xy 378.770888 -403.750417) (xy 378.786242 -403.802708)
			(xy 378.793998 -403.856651) (xy 378.793998 -403.911149) (xy 378.793998 -403.911151) (xy 380.231654 -403.911151)
			(xy 380.231654 -403.856649) (xy 380.239409 -403.802703) (xy 380.254763 -403.750409) (xy 380.277402 -403.700832)
			(xy 380.306865 -403.654981) (xy 380.342554 -403.613789) (xy 380.383741 -403.578095) (xy 380.429588 -403.548626)
			(xy 380.479162 -403.52598) (xy 380.531454 -403.51062) (xy 380.585399 -403.502857) (xy 380.61265 -403.502368)
			(xy 381.47625 -403.502368) (xy 381.503503 -403.502876) (xy 381.557456 -403.510627) (xy 381.609757 -403.525977)
			(xy 381.65934 -403.548616) (xy 381.705197 -403.57808) (xy 381.746393 -403.613772) (xy 381.78209 -403.654963)
			(xy 381.81156 -403.700816) (xy 381.834205 -403.750396) (xy 381.849563 -403.802695) (xy 381.857321 -403.856647)
			(xy 381.857321 -403.911153) (xy 383.294854 -403.911153) (xy 383.294854 -403.856647) (xy 383.302611 -403.802697)
			(xy 383.317966 -403.7504) (xy 383.340608 -403.70082) (xy 383.370075 -403.654968) (xy 383.405768 -403.613775)
			(xy 383.44696 -403.578081) (xy 383.492812 -403.548613) (xy 383.542391 -403.52597) (xy 383.594687 -403.510613)
			(xy 383.648638 -403.502855) (xy 383.67589 -403.502368) (xy 384.53949 -403.502368) (xy 384.566742 -403.502879)
			(xy 384.62069 -403.510634) (xy 384.672986 -403.525988) (xy 384.722564 -403.548629) (xy 384.768416 -403.578095)
			(xy 384.809607 -403.613786) (xy 384.845299 -403.654976) (xy 384.874767 -403.700827) (xy 384.897408 -403.750405)
			(xy 384.912764 -403.8027) (xy 384.920521 -403.856648) (xy 384.920521 -403.911152) (xy 384.92052 -403.911156)
			(xy 386.358031 -403.911156) (xy 386.358031 -403.856644) (xy 386.365789 -403.802687) (xy 386.381148 -403.750383)
			(xy 386.403794 -403.700798) (xy 386.433267 -403.654941) (xy 386.468966 -403.613745) (xy 386.510165 -403.578049)
			(xy 386.556024 -403.54858) (xy 386.605612 -403.525937) (xy 386.657916 -403.510583) (xy 386.711874 -403.502829)
			(xy 386.73913 -403.502368) (xy 387.60273 -403.502368) (xy 387.629978 -403.502904) (xy 387.683919 -403.510664)
			(xy 387.736207 -403.52602) (xy 387.785777 -403.548662) (xy 387.831621 -403.578127) (xy 387.872805 -403.613816)
			(xy 387.908491 -403.655003) (xy 387.937953 -403.700849) (xy 387.96059 -403.750421) (xy 387.975943 -403.80271)
			(xy 387.983698 -403.856652) (xy 387.983698 -403.911148) (xy 387.983697 -403.911152) (xy 389.421354 -403.911152)
			(xy 389.421354 -403.856648) (xy 389.42911 -403.8027) (xy 389.444465 -403.750404) (xy 389.467105 -403.700826)
			(xy 389.49657 -403.654974) (xy 389.532261 -403.613782) (xy 389.57345 -403.578088) (xy 389.6193 -403.548619)
			(xy 389.668876 -403.525975) (xy 389.721171 -403.510616) (xy 389.775118 -403.502856) (xy 389.80237 -403.502368)
			(xy 390.66597 -403.502368) (xy 390.693223 -403.502877) (xy 390.747173 -403.51063) (xy 390.799471 -403.525983)
			(xy 390.849052 -403.548622) (xy 390.894906 -403.578087) (xy 390.9361 -403.613779) (xy 390.971795 -403.65497)
			(xy 391.001264 -403.700821) (xy 391.023907 -403.7504) (xy 391.039263 -403.802697) (xy 391.047021 -403.856647)
			(xy 391.047021 -403.911153) (xy 391.047021 -403.911155) (xy 392.484531 -403.911155) (xy 392.484531 -403.856645)
			(xy 392.492289 -403.80269) (xy 392.507646 -403.750388) (xy 392.530291 -403.700804) (xy 392.559762 -403.654947)
			(xy 392.595459 -403.613752) (xy 392.636655 -403.578056) (xy 392.682513 -403.548586) (xy 392.732097 -403.525943)
			(xy 392.784399 -403.510587) (xy 392.838355 -403.50283) (xy 392.86561 -403.502368) (xy 393.72921 -403.502368)
			(xy 393.756459 -403.502903) (xy 393.810402 -403.51066) (xy 393.862692 -403.526015) (xy 393.912265 -403.548655)
			(xy 393.958111 -403.57812) (xy 393.999298 -403.613809) (xy 394.034986 -403.654997) (xy 394.064449 -403.700844)
			(xy 394.087088 -403.750417) (xy 394.102442 -403.802708) (xy 394.110198 -403.856651) (xy 394.110198 -403.911149)
			(xy 394.110198 -403.911151) (xy 395.547854 -403.911151) (xy 395.547854 -403.856649) (xy 395.555609 -403.802703)
			(xy 395.570963 -403.750409) (xy 395.593602 -403.700832) (xy 395.623065 -403.654981) (xy 395.658754 -403.613789)
			(xy 395.699941 -403.578095) (xy 395.745788 -403.548626) (xy 395.795362 -403.52598) (xy 395.847654 -403.51062)
			(xy 395.901599 -403.502857) (xy 395.92885 -403.502368) (xy 396.79245 -403.502368) (xy 396.819703 -403.502876)
			(xy 396.873656 -403.510627) (xy 396.925957 -403.525977) (xy 396.97554 -403.548616) (xy 397.021397 -403.57808)
			(xy 397.062593 -403.613772) (xy 397.09829 -403.654963) (xy 397.12776 -403.700816) (xy 397.150405 -403.750396)
			(xy 397.165763 -403.802695) (xy 397.173521 -403.856647) (xy 397.173521 -403.911153) (xy 398.611054 -403.911153)
			(xy 398.611054 -403.856647) (xy 398.618811 -403.802697) (xy 398.634166 -403.7504) (xy 398.656808 -403.70082)
			(xy 398.686275 -403.654968) (xy 398.721968 -403.613775) (xy 398.76316 -403.578081) (xy 398.809012 -403.548613)
			(xy 398.858591 -403.52597) (xy 398.910887 -403.510613) (xy 398.964838 -403.502855) (xy 398.99209 -403.502368)
			(xy 399.85569 -403.502368) (xy 399.882942 -403.502879) (xy 399.93689 -403.510634) (xy 399.989186 -403.525988)
			(xy 400.038764 -403.548629) (xy 400.084616 -403.578095) (xy 400.125807 -403.613786) (xy 400.161499 -403.654976)
			(xy 400.190967 -403.700827) (xy 400.213608 -403.750405) (xy 400.228964 -403.8027) (xy 400.236721 -403.856648)
			(xy 400.236721 -403.911152) (xy 400.23672 -403.911156) (xy 401.674231 -403.911156) (xy 401.674231 -403.856644)
			(xy 401.681989 -403.802687) (xy 401.697348 -403.750383) (xy 401.719994 -403.700798) (xy 401.749467 -403.654941)
			(xy 401.785166 -403.613745) (xy 401.826365 -403.578049) (xy 401.872224 -403.54858) (xy 401.921812 -403.525937)
			(xy 401.974116 -403.510583) (xy 402.028074 -403.502829) (xy 402.05533 -403.502368) (xy 402.91893 -403.502368)
			(xy 402.946178 -403.502904) (xy 403.000119 -403.510664) (xy 403.052407 -403.52602) (xy 403.101977 -403.548662)
			(xy 403.147821 -403.578127) (xy 403.189005 -403.613816) (xy 403.224691 -403.655003) (xy 403.254153 -403.700849)
			(xy 403.27679 -403.750421) (xy 403.292143 -403.80271) (xy 403.299898 -403.856652) (xy 403.299898 -403.911148)
			(xy 403.299897 -403.911152) (xy 404.737554 -403.911152) (xy 404.737554 -403.856648) (xy 404.74531 -403.8027)
			(xy 404.760665 -403.750404) (xy 404.783305 -403.700826) (xy 404.81277 -403.654974) (xy 404.848461 -403.613782)
			(xy 404.88965 -403.578088) (xy 404.9355 -403.548619) (xy 404.985076 -403.525975) (xy 405.037371 -403.510616)
			(xy 405.091318 -403.502856) (xy 405.11857 -403.502368) (xy 405.98217 -403.502368) (xy 406.009423 -403.502877)
			(xy 406.063373 -403.51063) (xy 406.115671 -403.525983) (xy 406.165252 -403.548622) (xy 406.211106 -403.578087)
			(xy 406.2523 -403.613779) (xy 406.287995 -403.65497) (xy 406.317464 -403.700821) (xy 406.340107 -403.7504)
			(xy 406.355463 -403.802697) (xy 406.363221 -403.856647) (xy 406.363221 -403.911153) (xy 406.363221 -403.911155)
			(xy 407.800731 -403.911155) (xy 407.800731 -403.856645) (xy 407.808489 -403.80269) (xy 407.823846 -403.750388)
			(xy 407.846491 -403.700804) (xy 407.875962 -403.654947) (xy 407.911659 -403.613752) (xy 407.952855 -403.578056)
			(xy 407.998713 -403.548586) (xy 408.048297 -403.525943) (xy 408.100599 -403.510587) (xy 408.154555 -403.50283)
			(xy 408.18181 -403.502368) (xy 409.04541 -403.502368) (xy 409.072659 -403.502903) (xy 409.126602 -403.51066)
			(xy 409.178892 -403.526015) (xy 409.228465 -403.548655) (xy 409.274311 -403.57812) (xy 409.315498 -403.613809)
			(xy 409.351186 -403.654997) (xy 409.380649 -403.700844) (xy 409.403288 -403.750417) (xy 409.418642 -403.802708)
			(xy 409.426398 -403.856651) (xy 409.426398 -403.911149) (xy 409.426398 -403.911151) (xy 410.864054 -403.911151)
			(xy 410.864054 -403.856649) (xy 410.871809 -403.802703) (xy 410.887163 -403.750409) (xy 410.909802 -403.700832)
			(xy 410.939265 -403.654981) (xy 410.974954 -403.613789) (xy 411.016141 -403.578095) (xy 411.061988 -403.548626)
			(xy 411.111562 -403.52598) (xy 411.163854 -403.51062) (xy 411.217799 -403.502857) (xy 411.24505 -403.502368)
			(xy 412.10865 -403.502368) (xy 412.135903 -403.502876) (xy 412.189856 -403.510627) (xy 412.242157 -403.525977)
			(xy 412.29174 -403.548616) (xy 412.337597 -403.57808) (xy 412.378793 -403.613772) (xy 412.41449 -403.654963)
			(xy 412.44396 -403.700816) (xy 412.466605 -403.750396) (xy 412.481963 -403.802695) (xy 412.489721 -403.856647)
			(xy 412.489721 -403.911153) (xy 413.927254 -403.911153) (xy 413.927254 -403.856647) (xy 413.935011 -403.802697)
			(xy 413.950366 -403.7504) (xy 413.973008 -403.70082) (xy 414.002475 -403.654968) (xy 414.038168 -403.613775)
			(xy 414.07936 -403.578081) (xy 414.125212 -403.548613) (xy 414.174791 -403.52597) (xy 414.227087 -403.510613)
			(xy 414.281038 -403.502855) (xy 414.30829 -403.502368) (xy 415.17189 -403.502368) (xy 415.199142 -403.502879)
			(xy 415.25309 -403.510634) (xy 415.305386 -403.525988) (xy 415.354964 -403.548629) (xy 415.400816 -403.578095)
			(xy 415.442007 -403.613786) (xy 415.477699 -403.654976) (xy 415.507167 -403.700827) (xy 415.529808 -403.750405)
			(xy 415.545164 -403.8027) (xy 415.552921 -403.856648) (xy 415.552921 -403.911152) (xy 415.55292 -403.911156)
			(xy 416.990431 -403.911156) (xy 416.990431 -403.856644) (xy 416.998189 -403.802687) (xy 417.013548 -403.750383)
			(xy 417.036194 -403.700798) (xy 417.065667 -403.654941) (xy 417.101366 -403.613745) (xy 417.142565 -403.578049)
			(xy 417.188424 -403.54858) (xy 417.238012 -403.525937) (xy 417.290316 -403.510583) (xy 417.344274 -403.502829)
			(xy 417.37153 -403.502368) (xy 418.23513 -403.502368) (xy 418.262378 -403.502904) (xy 418.316319 -403.510664)
			(xy 418.368607 -403.52602) (xy 418.418177 -403.548662) (xy 418.464021 -403.578127) (xy 418.505205 -403.613816)
			(xy 418.540891 -403.655003) (xy 418.570353 -403.700849) (xy 418.59299 -403.750421) (xy 418.608343 -403.80271)
			(xy 418.616098 -403.856652) (xy 418.616098 -403.911148) (xy 418.608343 -403.96509) (xy 418.59299 -404.017379)
			(xy 418.570353 -404.066951) (xy 418.540891 -404.112797) (xy 418.505205 -404.153984) (xy 418.464021 -404.189673)
			(xy 418.418177 -404.219138) (xy 418.368607 -404.24178) (xy 418.316319 -404.257136) (xy 418.262378 -404.264896)
			(xy 418.23513 -404.265384) (xy 417.37153 -404.265384) (xy 417.344274 -404.264971) (xy 417.290316 -404.257217)
			(xy 417.238012 -404.241863) (xy 417.188424 -404.21922) (xy 417.142565 -404.189751) (xy 417.101366 -404.154055)
			(xy 417.065667 -404.112859) (xy 417.036194 -404.067002) (xy 417.013548 -404.017417) (xy 416.998189 -403.965113)
			(xy 416.990431 -403.911156) (xy 415.55292 -403.911156) (xy 415.545164 -403.9651) (xy 415.529808 -404.017395)
			(xy 415.507167 -404.066973) (xy 415.477699 -404.112824) (xy 415.442007 -404.154014) (xy 415.400816 -404.189705)
			(xy 415.354964 -404.219171) (xy 415.305386 -404.241812) (xy 415.25309 -404.257166) (xy 415.199142 -404.264921)
			(xy 415.17189 -404.265384) (xy 414.30829 -404.265384) (xy 414.281038 -404.264945) (xy 414.227087 -404.257187)
			(xy 414.174791 -404.24183) (xy 414.125212 -404.219187) (xy 414.07936 -404.189719) (xy 414.038168 -404.154025)
			(xy 414.002475 -404.112832) (xy 413.973008 -404.06698) (xy 413.950366 -404.0174) (xy 413.935011 -403.965103)
			(xy 413.927254 -403.911153) (xy 412.489721 -403.911153) (xy 412.481963 -403.965105) (xy 412.466605 -404.017404)
			(xy 412.44396 -404.066984) (xy 412.41449 -404.112837) (xy 412.378793 -404.154028) (xy 412.337597 -404.18972)
			(xy 412.29174 -404.219184) (xy 412.242157 -404.241823) (xy 412.189856 -404.257173) (xy 412.135903 -404.264924)
			(xy 412.10865 -404.265384) (xy 411.24505 -404.265384) (xy 411.217799 -404.264943) (xy 411.163854 -404.25718)
			(xy 411.111562 -404.24182) (xy 411.061988 -404.219174) (xy 411.016141 -404.189705) (xy 410.974954 -404.154011)
			(xy 410.939265 -404.112819) (xy 410.909802 -404.066968) (xy 410.887163 -404.017391) (xy 410.871809 -403.965097)
			(xy 410.864054 -403.911151) (xy 409.426398 -403.911151) (xy 409.418642 -403.965092) (xy 409.403288 -404.017383)
			(xy 409.380649 -404.066956) (xy 409.351186 -404.112803) (xy 409.315498 -404.153991) (xy 409.274311 -404.18968)
			(xy 409.228465 -404.219145) (xy 409.178892 -404.241785) (xy 409.126602 -404.25714) (xy 409.072659 -404.264897)
			(xy 409.04541 -404.265384) (xy 408.18181 -404.265384) (xy 408.154555 -404.26497) (xy 408.100599 -404.257213)
			(xy 408.048297 -404.241857) (xy 407.998713 -404.219214) (xy 407.952855 -404.189744) (xy 407.911659 -404.154048)
			(xy 407.875962 -404.112853) (xy 407.846491 -404.066996) (xy 407.823846 -404.017412) (xy 407.808489 -403.96511)
			(xy 407.800731 -403.911155) (xy 406.363221 -403.911155) (xy 406.355463 -403.965103) (xy 406.340107 -404.0174)
			(xy 406.317464 -404.066979) (xy 406.287995 -404.11283) (xy 406.2523 -404.154021) (xy 406.211106 -404.189713)
			(xy 406.165252 -404.219178) (xy 406.115671 -404.241817) (xy 406.063373 -404.25717) (xy 406.009423 -404.264923)
			(xy 405.98217 -404.265384) (xy 405.11857 -404.265384) (xy 405.091318 -404.264944) (xy 405.037371 -404.257184)
			(xy 404.985076 -404.241825) (xy 404.9355 -404.219181) (xy 404.88965 -404.189712) (xy 404.848461 -404.154018)
			(xy 404.81277 -404.112826) (xy 404.783305 -404.066974) (xy 404.760665 -404.017396) (xy 404.74531 -403.9651)
			(xy 404.737554 -403.911152) (xy 403.299897 -403.911152) (xy 403.292143 -403.96509) (xy 403.27679 -404.017379)
			(xy 403.254153 -404.066951) (xy 403.224691 -404.112797) (xy 403.189005 -404.153984) (xy 403.147821 -404.189673)
			(xy 403.101977 -404.219138) (xy 403.052407 -404.24178) (xy 403.000119 -404.257136) (xy 402.946178 -404.264896)
			(xy 402.91893 -404.265384) (xy 402.05533 -404.265384) (xy 402.028074 -404.264971) (xy 401.974116 -404.257217)
			(xy 401.921812 -404.241863) (xy 401.872224 -404.21922) (xy 401.826365 -404.189751) (xy 401.785166 -404.154055)
			(xy 401.749467 -404.112859) (xy 401.719994 -404.067002) (xy 401.697348 -404.017417) (xy 401.681989 -403.965113)
			(xy 401.674231 -403.911156) (xy 400.23672 -403.911156) (xy 400.228964 -403.9651) (xy 400.213608 -404.017395)
			(xy 400.190967 -404.066973) (xy 400.161499 -404.112824) (xy 400.125807 -404.154014) (xy 400.084616 -404.189705)
			(xy 400.038764 -404.219171) (xy 399.989186 -404.241812) (xy 399.93689 -404.257166) (xy 399.882942 -404.264921)
			(xy 399.85569 -404.265384) (xy 398.99209 -404.265384) (xy 398.964838 -404.264945) (xy 398.910887 -404.257187)
			(xy 398.858591 -404.24183) (xy 398.809012 -404.219187) (xy 398.76316 -404.189719) (xy 398.721968 -404.154025)
			(xy 398.686275 -404.112832) (xy 398.656808 -404.06698) (xy 398.634166 -404.0174) (xy 398.618811 -403.965103)
			(xy 398.611054 -403.911153) (xy 397.173521 -403.911153) (xy 397.165763 -403.965105) (xy 397.150405 -404.017404)
			(xy 397.12776 -404.066984) (xy 397.09829 -404.112837) (xy 397.062593 -404.154028) (xy 397.021397 -404.18972)
			(xy 396.97554 -404.219184) (xy 396.925957 -404.241823) (xy 396.873656 -404.257173) (xy 396.819703 -404.264924)
			(xy 396.79245 -404.265384) (xy 395.92885 -404.265384) (xy 395.901599 -404.264943) (xy 395.847654 -404.25718)
			(xy 395.795362 -404.24182) (xy 395.745788 -404.219174) (xy 395.699941 -404.189705) (xy 395.658754 -404.154011)
			(xy 395.623065 -404.112819) (xy 395.593602 -404.066968) (xy 395.570963 -404.017391) (xy 395.555609 -403.965097)
			(xy 395.547854 -403.911151) (xy 394.110198 -403.911151) (xy 394.102442 -403.965092) (xy 394.087088 -404.017383)
			(xy 394.064449 -404.066956) (xy 394.034986 -404.112803) (xy 393.999298 -404.153991) (xy 393.958111 -404.18968)
			(xy 393.912265 -404.219145) (xy 393.862692 -404.241785) (xy 393.810402 -404.25714) (xy 393.756459 -404.264897)
			(xy 393.72921 -404.265384) (xy 392.86561 -404.265384) (xy 392.838355 -404.26497) (xy 392.784399 -404.257213)
			(xy 392.732097 -404.241857) (xy 392.682513 -404.219214) (xy 392.636655 -404.189744) (xy 392.595459 -404.154048)
			(xy 392.559762 -404.112853) (xy 392.530291 -404.066996) (xy 392.507646 -404.017412) (xy 392.492289 -403.96511)
			(xy 392.484531 -403.911155) (xy 391.047021 -403.911155) (xy 391.039263 -403.965103) (xy 391.023907 -404.0174)
			(xy 391.001264 -404.066979) (xy 390.971795 -404.11283) (xy 390.9361 -404.154021) (xy 390.894906 -404.189713)
			(xy 390.849052 -404.219178) (xy 390.799471 -404.241817) (xy 390.747173 -404.25717) (xy 390.693223 -404.264923)
			(xy 390.66597 -404.265384) (xy 389.80237 -404.265384) (xy 389.775118 -404.264944) (xy 389.721171 -404.257184)
			(xy 389.668876 -404.241825) (xy 389.6193 -404.219181) (xy 389.57345 -404.189712) (xy 389.532261 -404.154018)
			(xy 389.49657 -404.112826) (xy 389.467105 -404.066974) (xy 389.444465 -404.017396) (xy 389.42911 -403.9651)
			(xy 389.421354 -403.911152) (xy 387.983697 -403.911152) (xy 387.975943 -403.96509) (xy 387.96059 -404.017379)
			(xy 387.937953 -404.066951) (xy 387.908491 -404.112797) (xy 387.872805 -404.153984) (xy 387.831621 -404.189673)
			(xy 387.785777 -404.219138) (xy 387.736207 -404.24178) (xy 387.683919 -404.257136) (xy 387.629978 -404.264896)
			(xy 387.60273 -404.265384) (xy 386.73913 -404.265384) (xy 386.711874 -404.264971) (xy 386.657916 -404.257217)
			(xy 386.605612 -404.241863) (xy 386.556024 -404.21922) (xy 386.510165 -404.189751) (xy 386.468966 -404.154055)
			(xy 386.433267 -404.112859) (xy 386.403794 -404.067002) (xy 386.381148 -404.017417) (xy 386.365789 -403.965113)
			(xy 386.358031 -403.911156) (xy 384.92052 -403.911156) (xy 384.912764 -403.9651) (xy 384.897408 -404.017395)
			(xy 384.874767 -404.066973) (xy 384.845299 -404.112824) (xy 384.809607 -404.154014) (xy 384.768416 -404.189705)
			(xy 384.722564 -404.219171) (xy 384.672986 -404.241812) (xy 384.62069 -404.257166) (xy 384.566742 -404.264921)
			(xy 384.53949 -404.265384) (xy 383.67589 -404.265384) (xy 383.648638 -404.264945) (xy 383.594687 -404.257187)
			(xy 383.542391 -404.24183) (xy 383.492812 -404.219187) (xy 383.44696 -404.189719) (xy 383.405768 -404.154025)
			(xy 383.370075 -404.112832) (xy 383.340608 -404.06698) (xy 383.317966 -404.0174) (xy 383.302611 -403.965103)
			(xy 383.294854 -403.911153) (xy 381.857321 -403.911153) (xy 381.849563 -403.965105) (xy 381.834205 -404.017404)
			(xy 381.81156 -404.066984) (xy 381.78209 -404.112837) (xy 381.746393 -404.154028) (xy 381.705197 -404.18972)
			(xy 381.65934 -404.219184) (xy 381.609757 -404.241823) (xy 381.557456 -404.257173) (xy 381.503503 -404.264924)
			(xy 381.47625 -404.265384) (xy 380.61265 -404.265384) (xy 380.585399 -404.264943) (xy 380.531454 -404.25718)
			(xy 380.479162 -404.24182) (xy 380.429588 -404.219174) (xy 380.383741 -404.189705) (xy 380.342554 -404.154011)
			(xy 380.306865 -404.112819) (xy 380.277402 -404.066968) (xy 380.254763 -404.017391) (xy 380.239409 -403.965097)
			(xy 380.231654 -403.911151) (xy 378.793998 -403.911151) (xy 378.786242 -403.965092) (xy 378.770888 -404.017383)
			(xy 378.748249 -404.066956) (xy 378.718786 -404.112803) (xy 378.683098 -404.153991) (xy 378.641911 -404.18968)
			(xy 378.596065 -404.219145) (xy 378.546492 -404.241785) (xy 378.494202 -404.25714) (xy 378.440259 -404.264897)
			(xy 378.41301 -404.265384) (xy 377.54941 -404.265384) (xy 377.522155 -404.26497) (xy 377.468199 -404.257213)
			(xy 377.415897 -404.241857) (xy 377.366313 -404.219214) (xy 377.320455 -404.189744) (xy 377.279259 -404.154048)
			(xy 377.243562 -404.112853) (xy 377.214091 -404.066996) (xy 377.191446 -404.017412) (xy 377.176089 -403.96511)
			(xy 377.168331 -403.911155) (xy 375.730821 -403.911155) (xy 375.723063 -403.965103) (xy 375.707707 -404.0174)
			(xy 375.685064 -404.066979) (xy 375.655595 -404.11283) (xy 375.6199 -404.154021) (xy 375.578706 -404.189713)
			(xy 375.532852 -404.219178) (xy 375.483271 -404.241817) (xy 375.430973 -404.25717) (xy 375.377023 -404.264923)
			(xy 375.34977 -404.265384) (xy 374.48617 -404.265384) (xy 374.458918 -404.264944) (xy 374.404971 -404.257184)
			(xy 374.352676 -404.241825) (xy 374.3031 -404.219181) (xy 374.25725 -404.189712) (xy 374.216061 -404.154018)
			(xy 374.18037 -404.112826) (xy 374.150905 -404.066974) (xy 374.128265 -404.017396) (xy 374.11291 -403.9651)
			(xy 374.105154 -403.911152) (xy 372.667497 -403.911152) (xy 372.659743 -403.96509) (xy 372.64439 -404.017379)
			(xy 372.621753 -404.066951) (xy 372.592291 -404.112797) (xy 372.556605 -404.153984) (xy 372.515421 -404.189673)
			(xy 372.469577 -404.219138) (xy 372.420007 -404.24178) (xy 372.367719 -404.257136) (xy 372.313778 -404.264896)
			(xy 372.28653 -404.265384) (xy 371.42293 -404.265384) (xy 371.395674 -404.264971) (xy 371.341716 -404.257217)
			(xy 371.289412 -404.241863) (xy 371.239824 -404.21922) (xy 371.193965 -404.189751) (xy 371.152766 -404.154055)
			(xy 371.117067 -404.112859) (xy 371.087594 -404.067002) (xy 371.064948 -404.017417) (xy 371.049589 -403.965113)
			(xy 371.041831 -403.911156) (xy 351.17332 -403.911156) (xy 351.165564 -403.9651) (xy 351.150208 -404.017396)
			(xy 351.127566 -404.066974) (xy 351.098099 -404.112824) (xy 351.062406 -404.154015) (xy 351.021215 -404.189706)
			(xy 350.975363 -404.219172) (xy 350.925785 -404.241812) (xy 350.873489 -404.257166) (xy 350.81954 -404.264922)
			(xy 350.792288 -404.265384) (xy 349.928688 -404.265384) (xy 349.901436 -404.264945) (xy 349.847486 -404.257187)
			(xy 349.795189 -404.24183) (xy 349.74561 -404.219187) (xy 349.699759 -404.189718) (xy 349.658567 -404.154024)
			(xy 349.622875 -404.112832) (xy 349.593408 -404.066979) (xy 349.570766 -404.0174) (xy 349.55541 -403.965102)
			(xy 349.547654 -403.911152) (xy 348.109997 -403.911152) (xy 348.102243 -403.965087) (xy 348.086891 -404.017375)
			(xy 348.064255 -404.066946) (xy 348.034795 -404.112791) (xy 347.999111 -404.153977) (xy 347.957929 -404.189667)
			(xy 347.912088 -404.219132) (xy 347.86252 -404.241775) (xy 347.810234 -404.257133) (xy 347.756295 -404.264895)
			(xy 347.729048 -404.265384) (xy 346.865448 -404.265384) (xy 346.838191 -404.264972) (xy 346.784232 -404.25722)
			(xy 346.731925 -404.241868) (xy 346.682335 -404.219226) (xy 346.636473 -404.189758) (xy 346.595272 -404.154062)
			(xy 346.559571 -404.112865) (xy 346.530097 -404.067007) (xy 346.507449 -404.01742) (xy 346.49209 -403.965115)
			(xy 346.484331 -403.911157) (xy 345.046797 -403.911157) (xy 345.039042 -403.965093) (xy 345.023688 -404.017383)
			(xy 345.001049 -404.066957) (xy 344.971586 -404.112804) (xy 344.935897 -404.153991) (xy 344.89471 -404.189681)
			(xy 344.848864 -404.219145) (xy 344.799291 -404.241785) (xy 344.747001 -404.25714) (xy 344.693057 -404.264897)
			(xy 344.665808 -404.265384) (xy 343.802208 -404.265384) (xy 343.774953 -404.26497) (xy 343.720998 -404.257213)
			(xy 343.668696 -404.241857) (xy 343.619111 -404.219213) (xy 343.573254 -404.189744) (xy 343.532058 -404.154048)
			(xy 343.496361 -404.112852) (xy 343.466891 -404.066996) (xy 343.444246 -404.017412) (xy 343.428889 -403.96511)
			(xy 343.421131 -403.911155) (xy 341.983621 -403.911155) (xy 341.975863 -403.965103) (xy 341.960507 -404.0174)
			(xy 341.937863 -404.066979) (xy 341.908394 -404.112831) (xy 341.872699 -404.154022) (xy 341.831505 -404.189713)
			(xy 341.785651 -404.219179) (xy 341.73607 -404.241818) (xy 341.683772 -404.25717) (xy 341.629821 -404.264923)
			(xy 341.602568 -404.265384) (xy 340.738968 -404.265384) (xy 340.711717 -404.264944) (xy 340.657769 -404.257183)
			(xy 340.605475 -404.241824) (xy 340.555898 -404.21918) (xy 340.510049 -404.189711) (xy 340.46886 -404.154017)
			(xy 340.43317 -404.112825) (xy 340.403705 -404.066974) (xy 340.381064 -404.017395) (xy 340.36571 -403.9651)
			(xy 340.357954 -403.911152) (xy 338.920297 -403.911152) (xy 338.912543 -403.96509) (xy 338.89719 -404.017379)
			(xy 338.874552 -404.066951) (xy 338.84509 -404.112798) (xy 338.809404 -404.153984) (xy 338.76822 -404.189674)
			(xy 338.722376 -404.219139) (xy 338.672805 -404.24178) (xy 338.620517 -404.257137) (xy 338.566576 -404.264896)
			(xy 338.539328 -404.265384) (xy 337.675728 -404.265384) (xy 337.648472 -404.264971) (xy 337.594515 -404.257217)
			(xy 337.54221 -404.241862) (xy 337.492623 -404.21922) (xy 337.446764 -404.189751) (xy 337.405565 -404.154055)
			(xy 337.369866 -404.112859) (xy 337.340394 -404.067001) (xy 337.317748 -404.017416) (xy 337.302389 -403.965113)
			(xy 337.294631 -403.911156) (xy 335.85712 -403.911156) (xy 335.849364 -403.9651) (xy 335.834008 -404.017396)
			(xy 335.811366 -404.066974) (xy 335.781899 -404.112824) (xy 335.746206 -404.154015) (xy 335.705015 -404.189706)
			(xy 335.659163 -404.219172) (xy 335.609585 -404.241812) (xy 335.557289 -404.257166) (xy 335.50334 -404.264922)
			(xy 335.476088 -404.265384) (xy 334.612488 -404.265384) (xy 334.585236 -404.264945) (xy 334.531286 -404.257187)
			(xy 334.478989 -404.24183) (xy 334.42941 -404.219187) (xy 334.383559 -404.189718) (xy 334.342367 -404.154024)
			(xy 334.306675 -404.112832) (xy 334.277208 -404.066979) (xy 334.254566 -404.0174) (xy 334.23921 -403.965102)
			(xy 334.231454 -403.911152) (xy 332.793797 -403.911152) (xy 332.786043 -403.965087) (xy 332.770691 -404.017375)
			(xy 332.748055 -404.066946) (xy 332.718595 -404.112791) (xy 332.682911 -404.153977) (xy 332.641729 -404.189667)
			(xy 332.595888 -404.219132) (xy 332.54632 -404.241775) (xy 332.494034 -404.257133) (xy 332.440095 -404.264895)
			(xy 332.412848 -404.265384) (xy 331.549248 -404.265384) (xy 331.521991 -404.264972) (xy 331.468032 -404.25722)
			(xy 331.415725 -404.241868) (xy 331.366135 -404.219226) (xy 331.320273 -404.189758) (xy 331.279072 -404.154062)
			(xy 331.243371 -404.112865) (xy 331.213897 -404.067007) (xy 331.191249 -404.01742) (xy 331.17589 -403.965115)
			(xy 331.168131 -403.911157) (xy 329.730597 -403.911157) (xy 329.722842 -403.965093) (xy 329.707488 -404.017383)
			(xy 329.684849 -404.066957) (xy 329.655386 -404.112804) (xy 329.619697 -404.153991) (xy 329.57851 -404.189681)
			(xy 329.532664 -404.219145) (xy 329.483091 -404.241785) (xy 329.430801 -404.25714) (xy 329.376857 -404.264897)
			(xy 329.349608 -404.265384) (xy 328.486008 -404.265384) (xy 328.458753 -404.26497) (xy 328.404798 -404.257213)
			(xy 328.352496 -404.241857) (xy 328.302911 -404.219213) (xy 328.257054 -404.189744) (xy 328.215858 -404.154048)
			(xy 328.180161 -404.112852) (xy 328.150691 -404.066996) (xy 328.128046 -404.017412) (xy 328.112689 -403.96511)
			(xy 328.104931 -403.911155) (xy 326.667421 -403.911155) (xy 326.659663 -403.965103) (xy 326.644307 -404.0174)
			(xy 326.621663 -404.066979) (xy 326.592194 -404.112831) (xy 326.556499 -404.154022) (xy 326.515305 -404.189713)
			(xy 326.469451 -404.219179) (xy 326.41987 -404.241818) (xy 326.367572 -404.25717) (xy 326.313621 -404.264923)
			(xy 326.286368 -404.265384) (xy 325.422768 -404.265384) (xy 325.395517 -404.264944) (xy 325.341569 -404.257183)
			(xy 325.289275 -404.241824) (xy 325.239698 -404.21918) (xy 325.193849 -404.189711) (xy 325.15266 -404.154017)
			(xy 325.11697 -404.112825) (xy 325.087505 -404.066974) (xy 325.064864 -404.017395) (xy 325.04951 -403.9651)
			(xy 325.041754 -403.911152) (xy 323.604097 -403.911152) (xy 323.596343 -403.96509) (xy 323.58099 -404.017379)
			(xy 323.558352 -404.066951) (xy 323.52889 -404.112798) (xy 323.493204 -404.153984) (xy 323.45202 -404.189674)
			(xy 323.406176 -404.219139) (xy 323.356605 -404.24178) (xy 323.304317 -404.257137) (xy 323.250376 -404.264896)
			(xy 323.223128 -404.265384) (xy 322.359528 -404.265384) (xy 322.332272 -404.264971) (xy 322.278315 -404.257217)
			(xy 322.22601 -404.241862) (xy 322.176423 -404.21922) (xy 322.130564 -404.189751) (xy 322.089365 -404.154055)
			(xy 322.053666 -404.112859) (xy 322.024194 -404.067001) (xy 322.001548 -404.017416) (xy 321.986189 -403.965113)
			(xy 321.978431 -403.911156) (xy 320.54092 -403.911156) (xy 320.533164 -403.9651) (xy 320.517808 -404.017396)
			(xy 320.495166 -404.066974) (xy 320.465699 -404.112824) (xy 320.430006 -404.154015) (xy 320.388815 -404.189706)
			(xy 320.342963 -404.219172) (xy 320.293385 -404.241812) (xy 320.241089 -404.257166) (xy 320.18714 -404.264922)
			(xy 320.159888 -404.265384) (xy 319.296288 -404.265384) (xy 319.269036 -404.264945) (xy 319.215086 -404.257187)
			(xy 319.162789 -404.24183) (xy 319.11321 -404.219187) (xy 319.067359 -404.189718) (xy 319.026167 -404.154024)
			(xy 318.990475 -404.112832) (xy 318.961008 -404.066979) (xy 318.938366 -404.0174) (xy 318.92301 -403.965102)
			(xy 318.915254 -403.911152) (xy 317.477597 -403.911152) (xy 317.469843 -403.965087) (xy 317.454491 -404.017375)
			(xy 317.431855 -404.066946) (xy 317.402395 -404.112791) (xy 317.366711 -404.153977) (xy 317.325529 -404.189667)
			(xy 317.279688 -404.219132) (xy 317.23012 -404.241775) (xy 317.177834 -404.257133) (xy 317.123895 -404.264895)
			(xy 317.096648 -404.265384) (xy 316.233048 -404.265384) (xy 316.205791 -404.264972) (xy 316.151832 -404.25722)
			(xy 316.099525 -404.241868) (xy 316.049935 -404.219226) (xy 316.004073 -404.189758) (xy 315.962872 -404.154062)
			(xy 315.927171 -404.112865) (xy 315.897697 -404.067007) (xy 315.875049 -404.01742) (xy 315.85969 -403.965115)
			(xy 315.851931 -403.911157) (xy 314.414397 -403.911157) (xy 314.406642 -403.965093) (xy 314.391288 -404.017383)
			(xy 314.368649 -404.066957) (xy 314.339186 -404.112804) (xy 314.303497 -404.153991) (xy 314.26231 -404.189681)
			(xy 314.216464 -404.219145) (xy 314.166891 -404.241785) (xy 314.114601 -404.25714) (xy 314.060657 -404.264897)
			(xy 314.033408 -404.265384) (xy 313.169808 -404.265384) (xy 313.142553 -404.26497) (xy 313.088598 -404.257213)
			(xy 313.036296 -404.241857) (xy 312.986711 -404.219213) (xy 312.940854 -404.189744) (xy 312.899658 -404.154048)
			(xy 312.863961 -404.112852) (xy 312.834491 -404.066996) (xy 312.811846 -404.017412) (xy 312.796489 -403.96511)
			(xy 312.788731 -403.911155) (xy 311.351221 -403.911155) (xy 311.343463 -403.965103) (xy 311.328107 -404.0174)
			(xy 311.305463 -404.066979) (xy 311.275994 -404.112831) (xy 311.240299 -404.154022) (xy 311.199105 -404.189713)
			(xy 311.153251 -404.219179) (xy 311.10367 -404.241818) (xy 311.051372 -404.25717) (xy 310.997421 -404.264923)
			(xy 310.970168 -404.265384) (xy 310.106568 -404.265384) (xy 310.079317 -404.264944) (xy 310.025369 -404.257183)
			(xy 309.973075 -404.241824) (xy 309.923498 -404.21918) (xy 309.877649 -404.189711) (xy 309.83646 -404.154017)
			(xy 309.80077 -404.112825) (xy 309.771305 -404.066974) (xy 309.748664 -404.017395) (xy 309.73331 -403.9651)
			(xy 309.725554 -403.911152) (xy 308.287897 -403.911152) (xy 308.280143 -403.96509) (xy 308.26479 -404.017379)
			(xy 308.242152 -404.066951) (xy 308.21269 -404.112798) (xy 308.177004 -404.153984) (xy 308.13582 -404.189674)
			(xy 308.089976 -404.219139) (xy 308.040405 -404.24178) (xy 307.988117 -404.257137) (xy 307.934176 -404.264896)
			(xy 307.906928 -404.265384) (xy 307.043328 -404.265384) (xy 307.016072 -404.264971) (xy 306.962115 -404.257217)
			(xy 306.90981 -404.241862) (xy 306.860223 -404.21922) (xy 306.814364 -404.189751) (xy 306.773165 -404.154055)
			(xy 306.737466 -404.112859) (xy 306.707994 -404.067001) (xy 306.685348 -404.017416) (xy 306.669989 -403.965113)
			(xy 306.662231 -403.911156) (xy 305.22472 -403.911156) (xy 305.216964 -403.9651) (xy 305.201608 -404.017396)
			(xy 305.178966 -404.066974) (xy 305.149499 -404.112824) (xy 305.113806 -404.154015) (xy 305.072615 -404.189706)
			(xy 305.026763 -404.219172) (xy 304.977185 -404.241812) (xy 304.924889 -404.257166) (xy 304.87094 -404.264922)
			(xy 304.843688 -404.265384) (xy 303.980088 -404.265384) (xy 303.952836 -404.264945) (xy 303.898886 -404.257187)
			(xy 303.846589 -404.24183) (xy 303.79701 -404.219187) (xy 303.751159 -404.189718) (xy 303.709967 -404.154024)
			(xy 303.674275 -404.112832) (xy 303.644808 -404.066979) (xy 303.622166 -404.0174) (xy 303.60681 -403.965102)
			(xy 303.599054 -403.911152) (xy 298.836897 -403.911152) (xy 298.840074 -403.920931) (xy 298.852049 -403.983712)
			(xy 298.856063 -404.0475) (xy 298.852049 -404.111288) (xy 298.840074 -404.174069) (xy 298.820324 -404.234855)
			(xy 298.793112 -404.292686) (xy 298.758866 -404.346651) (xy 298.718128 -404.395898) (xy 298.671538 -404.439652)
			(xy 298.619832 -404.477221) (xy 298.563825 -404.508014) (xy 298.504401 -404.531545) (xy 298.442496 -404.547442)
			(xy 298.379087 -404.555456) (xy 298.34713 -404.55596) (xy 298.346876 -404.55596) (xy 298.315131 -404.555422)
			(xy 298.252136 -404.547497) (xy 298.190616 -404.531797) (xy 298.131527 -404.508566) (xy 298.075787 -404.478166)
			(xy 298.024261 -404.441069) (xy 298.000674 -404.419816) (xy 297.993411 -404.413632) (xy 297.975661 -404.406681)
			(xy 297.956599 -404.406681) (xy 297.938849 -404.413632) (xy 297.931586 -404.419816) (xy 297.908028 -404.441107)
			(xy 297.856512 -404.478235) (xy 297.800771 -404.508654) (xy 297.741674 -404.531889) (xy 297.680142 -404.547579)
			(xy 297.617135 -404.555478) (xy 297.585384 -404.55596) (xy 297.58513 -404.55596) (xy 297.553163 -404.555577)
			(xy 297.489734 -404.547567) (xy 297.427809 -404.531671) (xy 297.368364 -404.508138) (xy 297.312338 -404.47734)
			(xy 297.260613 -404.439763) (xy 297.214007 -404.395999) (xy 297.173253 -404.346739) (xy 297.138995 -404.292759)
			(xy 297.111773 -404.234911) (xy 297.092015 -404.174108) (xy 297.080035 -404.111307) (xy 297.07602 -404.0475)
			(xy 296.316063 -404.0475) (xy 296.312049 -404.111288) (xy 296.300074 -404.174069) (xy 296.280324 -404.234855)
			(xy 296.253112 -404.292686) (xy 296.218866 -404.346651) (xy 296.178128 -404.395898) (xy 296.131538 -404.439652)
			(xy 296.079832 -404.477221) (xy 296.023825 -404.508014) (xy 295.964401 -404.531545) (xy 295.902496 -404.547442)
			(xy 295.839087 -404.555456) (xy 295.80713 -404.55596) (xy 295.806876 -404.55596) (xy 295.775131 -404.555422)
			(xy 295.712136 -404.547497) (xy 295.650616 -404.531797) (xy 295.591527 -404.508566) (xy 295.535787 -404.478166)
			(xy 295.484261 -404.441069) (xy 295.460674 -404.419816) (xy 295.453411 -404.413632) (xy 295.435661 -404.406681)
			(xy 295.416599 -404.406681) (xy 295.398849 -404.413632) (xy 295.391586 -404.419816) (xy 295.368028 -404.441107)
			(xy 295.316512 -404.478235) (xy 295.260771 -404.508654) (xy 295.201674 -404.531889) (xy 295.140142 -404.547579)
			(xy 295.077135 -404.555478) (xy 295.045384 -404.55596) (xy 295.04513 -404.55596) (xy 295.013163 -404.555577)
			(xy 294.949734 -404.547567) (xy 294.887809 -404.531671) (xy 294.828364 -404.508138) (xy 294.772338 -404.47734)
			(xy 294.720613 -404.439763) (xy 294.674007 -404.395999) (xy 294.633253 -404.346739) (xy 294.598995 -404.292759)
			(xy 294.571773 -404.234911) (xy 294.552015 -404.174108) (xy 294.540035 -404.111307) (xy 294.53602 -404.0475)
			(xy 293.926484 -404.0475) (xy 293.92247 -404.111293) (xy 293.910493 -404.174079) (xy 293.890741 -404.23487)
			(xy 293.863525 -404.292705) (xy 293.829276 -404.346674) (xy 293.788532 -404.395924) (xy 293.741937 -404.439679)
			(xy 293.690226 -404.47725) (xy 293.634213 -404.508043) (xy 293.574783 -404.531573) (xy 293.512872 -404.547468)
			(xy 293.449457 -404.555479) (xy 293.417498 -404.55596) (xy 293.417244 -404.55596) (xy 293.385498 -404.555442)
			(xy 293.322502 -404.547512) (xy 293.260982 -404.531809) (xy 293.201894 -404.508575) (xy 293.146154 -404.478171)
			(xy 293.094629 -404.44107) (xy 293.071042 -404.419816) (xy 293.063779 -404.413632) (xy 293.046029 -404.406681)
			(xy 293.026967 -404.406681) (xy 293.009217 -404.413632) (xy 293.001954 -404.419816) (xy 292.978367 -404.441074)
			(xy 292.926858 -404.478206) (xy 292.871123 -404.50863) (xy 292.812032 -404.531871) (xy 292.750504 -404.547567)
			(xy 292.687501 -404.555474) (xy 292.655752 -404.55596) (xy 292.655498 -404.55596) (xy 292.623534 -404.555554)
			(xy 292.56011 -404.547542) (xy 292.498191 -404.531643) (xy 292.438752 -404.50811) (xy 292.382731 -404.477312)
			(xy 292.331013 -404.439736) (xy 292.284411 -404.395974) (xy 292.243662 -404.346717) (xy 292.209408 -404.29274)
			(xy 292.182189 -404.234897) (xy 292.162434 -404.174098) (xy 292.150455 -404.111302) (xy 292.146441 -404.0475)
			(xy 291.386484 -404.0475) (xy 291.38247 -404.111293) (xy 291.370493 -404.174079) (xy 291.350741 -404.23487)
			(xy 291.323525 -404.292705) (xy 291.289276 -404.346674) (xy 291.248532 -404.395924) (xy 291.201937 -404.439679)
			(xy 291.150226 -404.47725) (xy 291.094213 -404.508043) (xy 291.034783 -404.531573) (xy 290.972872 -404.547468)
			(xy 290.909457 -404.555479) (xy 290.877498 -404.55596) (xy 290.877244 -404.55596) (xy 290.845498 -404.555442)
			(xy 290.782502 -404.547512) (xy 290.720982 -404.531809) (xy 290.661894 -404.508575) (xy 290.606154 -404.478171)
			(xy 290.554629 -404.44107) (xy 290.531042 -404.419816) (xy 290.523779 -404.413632) (xy 290.506029 -404.406681)
			(xy 290.486967 -404.406681) (xy 290.469217 -404.413632) (xy 290.461954 -404.419816) (xy 290.438367 -404.441074)
			(xy 290.386858 -404.478206) (xy 290.331123 -404.50863) (xy 290.272032 -404.531871) (xy 290.210504 -404.547567)
			(xy 290.147501 -404.555474) (xy 290.115752 -404.55596) (xy 290.115498 -404.55596) (xy 290.083534 -404.555554)
			(xy 290.02011 -404.547542) (xy 289.958191 -404.531643) (xy 289.898752 -404.50811) (xy 289.842731 -404.477312)
			(xy 289.791013 -404.439736) (xy 289.744411 -404.395974) (xy 289.703662 -404.346717) (xy 289.669408 -404.29274)
			(xy 289.642189 -404.234897) (xy 289.622434 -404.174098) (xy 289.610455 -404.111302) (xy 289.606441 -404.0475)
			(xy 288.846484 -404.0475) (xy 288.84247 -404.111293) (xy 288.830493 -404.174079) (xy 288.810741 -404.23487)
			(xy 288.783525 -404.292705) (xy 288.749276 -404.346674) (xy 288.708532 -404.395924) (xy 288.661937 -404.439679)
			(xy 288.610226 -404.47725) (xy 288.554213 -404.508043) (xy 288.494783 -404.531573) (xy 288.432872 -404.547468)
			(xy 288.369457 -404.555479) (xy 288.337498 -404.55596) (xy 288.337244 -404.55596) (xy 288.305498 -404.555442)
			(xy 288.242502 -404.547512) (xy 288.180982 -404.531809) (xy 288.121894 -404.508575) (xy 288.066154 -404.478171)
			(xy 288.014629 -404.44107) (xy 287.991042 -404.419816) (xy 287.983779 -404.413632) (xy 287.966029 -404.406681)
			(xy 287.946967 -404.406681) (xy 287.929217 -404.413632) (xy 287.921954 -404.419816) (xy 287.898367 -404.441074)
			(xy 287.846858 -404.478206) (xy 287.791123 -404.50863) (xy 287.732032 -404.531871) (xy 287.670504 -404.547567)
			(xy 287.607501 -404.555474) (xy 287.575752 -404.55596) (xy 287.575498 -404.55596) (xy 287.543534 -404.555554)
			(xy 287.48011 -404.547542) (xy 287.418191 -404.531643) (xy 287.358752 -404.50811) (xy 287.302731 -404.477312)
			(xy 287.251013 -404.439736) (xy 287.204411 -404.395974) (xy 287.163662 -404.346717) (xy 287.129408 -404.29274)
			(xy 287.102189 -404.234897) (xy 287.082434 -404.174098) (xy 287.070455 -404.111302) (xy 287.066441 -404.0475)
			(xy 167.31136 -404.0475) (xy 167.302461 -404.066983) (xy 167.272991 -404.112836) (xy 167.237294 -404.154027)
			(xy 167.196099 -404.189718) (xy 167.150243 -404.219183) (xy 167.10066 -404.241822) (xy 167.04836 -404.257173)
			(xy 166.994407 -404.264924) (xy 166.967154 -404.265384) (xy 166.103554 -404.265384) (xy 166.076303 -404.264943)
			(xy 166.022357 -404.257181) (xy 165.970065 -404.241821) (xy 165.92049 -404.219175) (xy 165.874642 -404.189706)
			(xy 165.833455 -404.154012) (xy 165.797766 -404.112821) (xy 165.768302 -404.06697) (xy 165.745663 -404.017392)
			(xy 165.73031 -403.965098) (xy 165.722554 -403.911151) (xy 164.284898 -403.911151) (xy 164.277142 -403.965092)
			(xy 164.261789 -404.017382) (xy 164.23915 -404.066955) (xy 164.209687 -404.112802) (xy 164.173999 -404.153989)
			(xy 164.132813 -404.189679) (xy 164.086968 -404.219143) (xy 164.037395 -404.241784) (xy 163.985106 -404.257139)
			(xy 163.931163 -404.264897) (xy 163.903914 -404.265384) (xy 163.040314 -404.265384) (xy 163.013059 -404.26497)
			(xy 162.959103 -404.257214) (xy 162.9068 -404.241858) (xy 162.857215 -404.219215) (xy 162.811357 -404.189746)
			(xy 162.77016 -404.15405) (xy 162.734463 -404.112854) (xy 162.704991 -404.066997) (xy 162.682346 -404.017413)
			(xy 162.666989 -403.965111) (xy 162.659231 -403.911155) (xy 161.221721 -403.911155) (xy 161.213963 -403.965102)
			(xy 161.198607 -404.017399) (xy 161.175964 -404.066978) (xy 161.146496 -404.112829) (xy 161.110801 -404.15402)
			(xy 161.069608 -404.189711) (xy 161.023755 -404.219177) (xy 160.974174 -404.241816) (xy 160.921877 -404.257169)
			(xy 160.867926 -404.264922) (xy 160.840674 -404.265384) (xy 159.977074 -404.265384) (xy 159.949822 -404.264944)
			(xy 159.895874 -404.257184) (xy 159.843579 -404.241826) (xy 159.794002 -404.219182) (xy 159.748152 -404.189713)
			(xy 159.706962 -404.154019) (xy 159.671271 -404.112827) (xy 159.641806 -404.066975) (xy 159.619165 -404.017397)
			(xy 159.60381 -403.965101) (xy 159.596054 -403.911152) (xy 158.158397 -403.911152) (xy 158.150643 -403.965089)
			(xy 158.13529 -404.017378) (xy 158.112653 -404.06695) (xy 158.083192 -404.112796) (xy 158.047506 -404.153982)
			(xy 158.006323 -404.189671) (xy 157.96048 -404.219137) (xy 157.91091 -404.241778) (xy 157.858623 -404.257136)
			(xy 157.804682 -404.264895) (xy 157.777434 -404.265384) (xy 156.913834 -404.265384) (xy 156.886578 -404.264971)
			(xy 156.83262 -404.257218) (xy 156.780314 -404.241864) (xy 156.730727 -404.219222) (xy 156.684867 -404.189753)
			(xy 156.643667 -404.154057) (xy 156.607968 -404.112861) (xy 156.578495 -404.067003) (xy 156.555848 -404.017417)
			(xy 156.540489 -403.965114) (xy 156.532731 -403.911156) (xy 155.09522 -403.911156) (xy 155.087464 -403.965099)
			(xy 155.072109 -404.017394) (xy 155.049467 -404.066972) (xy 155.02 -404.112822) (xy 154.984308 -404.154013)
			(xy 154.943118 -404.189704) (xy 154.897267 -404.21917) (xy 154.847689 -404.241811) (xy 154.795394 -404.257165)
			(xy 154.741445 -404.264921) (xy 154.714194 -404.265384) (xy 153.850594 -404.265384) (xy 153.823341 -404.264946)
			(xy 153.769391 -404.257188) (xy 153.717094 -404.241831) (xy 153.667514 -404.219189) (xy 153.621661 -404.18972)
			(xy 153.580469 -404.154026) (xy 153.544776 -404.112834) (xy 153.515309 -404.066981) (xy 153.492666 -404.017401)
			(xy 153.477311 -403.965103) (xy 153.469554 -403.911153) (xy 152.032021 -403.911153) (xy 152.024263 -403.965105)
			(xy 152.008906 -404.017403) (xy 151.986261 -404.066983) (xy 151.956791 -404.112836) (xy 151.921094 -404.154027)
			(xy 151.879899 -404.189718) (xy 151.834043 -404.219183) (xy 151.78446 -404.241822) (xy 151.73216 -404.257173)
			(xy 151.678207 -404.264924) (xy 151.650954 -404.265384) (xy 150.787354 -404.265384) (xy 150.760103 -404.264943)
			(xy 150.706157 -404.257181) (xy 150.653865 -404.241821) (xy 150.60429 -404.219175) (xy 150.558442 -404.189706)
			(xy 150.517255 -404.154012) (xy 150.481566 -404.112821) (xy 150.452102 -404.06697) (xy 150.429463 -404.017392)
			(xy 150.41411 -403.965098) (xy 150.406354 -403.911151) (xy 148.968698 -403.911151) (xy 148.960942 -403.965092)
			(xy 148.945589 -404.017382) (xy 148.92295 -404.066955) (xy 148.893487 -404.112802) (xy 148.857799 -404.153989)
			(xy 148.816613 -404.189679) (xy 148.770768 -404.219143) (xy 148.721195 -404.241784) (xy 148.668906 -404.257139)
			(xy 148.614963 -404.264897) (xy 148.587714 -404.265384) (xy 147.724114 -404.265384) (xy 147.696859 -404.26497)
			(xy 147.642903 -404.257214) (xy 147.5906 -404.241858) (xy 147.541015 -404.219215) (xy 147.495157 -404.189746)
			(xy 147.45396 -404.15405) (xy 147.418263 -404.112854) (xy 147.388791 -404.066997) (xy 147.366146 -404.017413)
			(xy 147.350789 -403.965111) (xy 147.343031 -403.911155) (xy 145.905521 -403.911155) (xy 145.897763 -403.965102)
			(xy 145.882407 -404.017399) (xy 145.859764 -404.066978) (xy 145.830296 -404.112829) (xy 145.794601 -404.15402)
			(xy 145.753408 -404.189711) (xy 145.707555 -404.219177) (xy 145.657974 -404.241816) (xy 145.605677 -404.257169)
			(xy 145.551726 -404.264922) (xy 145.524474 -404.265384) (xy 144.660874 -404.265384) (xy 144.633622 -404.264944)
			(xy 144.579674 -404.257184) (xy 144.527379 -404.241826) (xy 144.477802 -404.219182) (xy 144.431952 -404.189713)
			(xy 144.390762 -404.154019) (xy 144.355071 -404.112827) (xy 144.325606 -404.066975) (xy 144.302965 -404.017397)
			(xy 144.28761 -403.965101) (xy 144.279854 -403.911152) (xy 142.842197 -403.911152) (xy 142.834443 -403.965089)
			(xy 142.81909 -404.017378) (xy 142.796453 -404.06695) (xy 142.766992 -404.112796) (xy 142.731306 -404.153982)
			(xy 142.690123 -404.189671) (xy 142.64428 -404.219137) (xy 142.59471 -404.241778) (xy 142.542423 -404.257136)
			(xy 142.488482 -404.264895) (xy 142.461234 -404.265384) (xy 141.597634 -404.265384) (xy 141.570378 -404.264971)
			(xy 141.51642 -404.257218) (xy 141.464114 -404.241864) (xy 141.414527 -404.219222) (xy 141.368667 -404.189753)
			(xy 141.327467 -404.154057) (xy 141.291768 -404.112861) (xy 141.262295 -404.067003) (xy 141.239648 -404.017417)
			(xy 141.224289 -403.965114) (xy 141.216531 -403.911156) (xy 139.77902 -403.911156) (xy 139.771264 -403.965099)
			(xy 139.755909 -404.017394) (xy 139.733267 -404.066972) (xy 139.7038 -404.112822) (xy 139.668108 -404.154013)
			(xy 139.626918 -404.189704) (xy 139.581067 -404.21917) (xy 139.531489 -404.241811) (xy 139.479194 -404.257165)
			(xy 139.425245 -404.264921) (xy 139.397994 -404.265384) (xy 138.534394 -404.265384) (xy 138.507141 -404.264946)
			(xy 138.453191 -404.257188) (xy 138.400894 -404.241831) (xy 138.351314 -404.219189) (xy 138.305461 -404.18972)
			(xy 138.264269 -404.154026) (xy 138.228576 -404.112834) (xy 138.199109 -404.066981) (xy 138.176466 -404.017401)
			(xy 138.161111 -403.965103) (xy 138.153354 -403.911153) (xy 136.715821 -403.911153) (xy 136.708063 -403.965105)
			(xy 136.692706 -404.017403) (xy 136.670061 -404.066983) (xy 136.640591 -404.112836) (xy 136.604894 -404.154027)
			(xy 136.563699 -404.189718) (xy 136.517843 -404.219183) (xy 136.46826 -404.241822) (xy 136.41596 -404.257173)
			(xy 136.362007 -404.264924) (xy 136.334754 -404.265384) (xy 135.471154 -404.265384) (xy 135.443903 -404.264943)
			(xy 135.389957 -404.257181) (xy 135.337665 -404.241821) (xy 135.28809 -404.219175) (xy 135.242242 -404.189706)
			(xy 135.201055 -404.154012) (xy 135.165366 -404.112821) (xy 135.135902 -404.06697) (xy 135.113263 -404.017392)
			(xy 135.09791 -403.965098) (xy 135.090154 -403.911151) (xy 133.652498 -403.911151) (xy 133.644742 -403.965092)
			(xy 133.629389 -404.017382) (xy 133.60675 -404.066955) (xy 133.577287 -404.112802) (xy 133.541599 -404.153989)
			(xy 133.500413 -404.189679) (xy 133.454568 -404.219143) (xy 133.404995 -404.241784) (xy 133.352706 -404.257139)
			(xy 133.298763 -404.264897) (xy 133.271514 -404.265384) (xy 132.407914 -404.265384) (xy 132.380659 -404.26497)
			(xy 132.326703 -404.257214) (xy 132.2744 -404.241858) (xy 132.224815 -404.219215) (xy 132.178957 -404.189746)
			(xy 132.13776 -404.15405) (xy 132.102063 -404.112854) (xy 132.072591 -404.066997) (xy 132.049946 -404.017413)
			(xy 132.034589 -403.965111) (xy 132.026831 -403.911155) (xy 130.589321 -403.911155) (xy 130.581563 -403.965102)
			(xy 130.566207 -404.017399) (xy 130.543564 -404.066978) (xy 130.514096 -404.112829) (xy 130.478401 -404.15402)
			(xy 130.437208 -404.189711) (xy 130.391355 -404.219177) (xy 130.341774 -404.241816) (xy 130.289477 -404.257169)
			(xy 130.235526 -404.264922) (xy 130.208274 -404.265384) (xy 129.344674 -404.265384) (xy 129.317422 -404.264944)
			(xy 129.263474 -404.257184) (xy 129.211179 -404.241826) (xy 129.161602 -404.219182) (xy 129.115752 -404.189713)
			(xy 129.074562 -404.154019) (xy 129.038871 -404.112827) (xy 129.009406 -404.066975) (xy 128.986765 -404.017397)
			(xy 128.97141 -403.965101) (xy 128.963654 -403.911152) (xy 127.525997 -403.911152) (xy 127.518243 -403.965089)
			(xy 127.50289 -404.017378) (xy 127.480253 -404.06695) (xy 127.450792 -404.112796) (xy 127.415106 -404.153982)
			(xy 127.373923 -404.189671) (xy 127.32808 -404.219137) (xy 127.27851 -404.241778) (xy 127.226223 -404.257136)
			(xy 127.172282 -404.264895) (xy 127.145034 -404.265384) (xy 126.281434 -404.265384) (xy 126.254178 -404.264971)
			(xy 126.20022 -404.257218) (xy 126.147914 -404.241864) (xy 126.098327 -404.219222) (xy 126.052467 -404.189753)
			(xy 126.011267 -404.154057) (xy 125.975568 -404.112861) (xy 125.946095 -404.067003) (xy 125.923448 -404.017417)
			(xy 125.908089 -403.965114) (xy 125.900331 -403.911156) (xy 124.46282 -403.911156) (xy 124.455064 -403.965099)
			(xy 124.439709 -404.017394) (xy 124.417067 -404.066972) (xy 124.3876 -404.112822) (xy 124.351908 -404.154013)
			(xy 124.310718 -404.189704) (xy 124.264867 -404.21917) (xy 124.215289 -404.241811) (xy 124.162994 -404.257165)
			(xy 124.109045 -404.264921) (xy 124.081794 -404.265384) (xy 123.218194 -404.265384) (xy 123.190941 -404.264946)
			(xy 123.136991 -404.257188) (xy 123.084694 -404.241831) (xy 123.035114 -404.219189) (xy 122.989261 -404.18972)
			(xy 122.948069 -404.154026) (xy 122.912376 -404.112834) (xy 122.882909 -404.066981) (xy 122.860266 -404.017401)
			(xy 122.844911 -403.965103) (xy 122.837154 -403.911153) (xy 121.399621 -403.911153) (xy 121.391863 -403.965105)
			(xy 121.376506 -404.017403) (xy 121.353861 -404.066983) (xy 121.324391 -404.112836) (xy 121.288694 -404.154027)
			(xy 121.247499 -404.189718) (xy 121.201643 -404.219183) (xy 121.15206 -404.241822) (xy 121.09976 -404.257173)
			(xy 121.045807 -404.264924) (xy 121.018554 -404.265384) (xy 120.154954 -404.265384) (xy 120.127703 -404.264943)
			(xy 120.073757 -404.257181) (xy 120.021465 -404.241821) (xy 119.97189 -404.219175) (xy 119.926042 -404.189706)
			(xy 119.884855 -404.154012) (xy 119.849166 -404.112821) (xy 119.819702 -404.06697) (xy 119.797063 -404.017392)
			(xy 119.78171 -403.965098) (xy 119.773954 -403.911151) (xy 95.172998 -403.911151) (xy 95.165243 -403.965089)
			(xy 95.149891 -404.017377) (xy 95.127254 -404.066949) (xy 95.097793 -404.112794) (xy 95.062108 -404.153981)
			(xy 95.020925 -404.18967) (xy 94.975082 -404.219135) (xy 94.925513 -404.241777) (xy 94.873226 -404.257135)
			(xy 94.819286 -404.264895) (xy 94.792038 -404.265384) (xy 93.928438 -404.265384) (xy 93.901182 -404.264972)
			(xy 93.847223 -404.257219) (xy 93.794917 -404.241865) (xy 93.745329 -404.219223) (xy 93.699468 -404.189754)
			(xy 93.658269 -404.154058) (xy 93.622569 -404.112862) (xy 93.593095 -404.067004) (xy 93.570448 -404.017418)
			(xy 93.555089 -403.965114) (xy 93.547331 -403.911156) (xy 92.10982 -403.911156) (xy 92.102064 -403.965099)
			(xy 92.086709 -404.017394) (xy 92.064068 -404.066971) (xy 92.034601 -404.112821) (xy 91.99891 -404.154011)
			(xy 91.95772 -404.189703) (xy 91.911869 -404.219169) (xy 91.862292 -404.24181) (xy 91.809997 -404.257165)
			(xy 91.756049 -404.264921) (xy 91.728798 -404.265384) (xy 90.865198 -404.265384) (xy 90.837945 -404.264946)
			(xy 90.783994 -404.257189) (xy 90.731696 -404.241833) (xy 90.682116 -404.21919) (xy 90.636263 -404.189722)
			(xy 90.595071 -404.154028) (xy 90.559377 -404.112835) (xy 90.529909 -404.066982) (xy 90.507267 -404.017402)
			(xy 90.491911 -403.965104) (xy 90.484154 -403.911153) (xy 89.046621 -403.911153) (xy 89.038863 -403.965104)
			(xy 89.023506 -404.017402) (xy 89.000862 -404.066982) (xy 88.971392 -404.112834) (xy 88.935696 -404.154025)
			(xy 88.894501 -404.189717) (xy 88.848645 -404.219182) (xy 88.799063 -404.241821) (xy 88.746763 -404.257172)
			(xy 88.692811 -404.264924) (xy 88.665558 -404.265384) (xy 87.801958 -404.265384) (xy 87.774707 -404.264943)
			(xy 87.72076 -404.257181) (xy 87.668467 -404.241822) (xy 87.618892 -404.219177) (xy 87.573044 -404.189707)
			(xy 87.531857 -404.154014) (xy 87.496167 -404.112822) (xy 87.466703 -404.066971) (xy 87.444064 -404.017393)
			(xy 87.42871 -403.965098) (xy 87.420954 -403.911151) (xy 85.983298 -403.911151) (xy 85.975542 -403.965091)
			(xy 85.960189 -404.017381) (xy 85.937551 -404.066954) (xy 85.908088 -404.112801) (xy 85.872401 -404.153988)
			(xy 85.831215 -404.189677) (xy 85.78537 -404.219142) (xy 85.735798 -404.241783) (xy 85.683509 -404.257138)
			(xy 85.629567 -404.264897) (xy 85.602318 -404.265384) (xy 84.738718 -404.265384) (xy 84.711463 -404.26497)
			(xy 84.657506 -404.257215) (xy 84.605203 -404.241859) (xy 84.555617 -404.219217) (xy 84.509759 -404.189747)
			(xy 84.468562 -404.154051) (xy 84.432864 -404.112855) (xy 84.403392 -404.066999) (xy 84.380747 -404.017414)
			(xy 84.365389 -403.965111) (xy 84.357631 -403.911155) (xy 82.920121 -403.911155) (xy 82.912364 -403.965102)
			(xy 82.897007 -404.017398) (xy 82.874365 -404.066976) (xy 82.844897 -404.112828) (xy 82.809203 -404.154018)
			(xy 82.76801 -404.18971) (xy 82.722157 -404.219175) (xy 82.672577 -404.241815) (xy 82.62028 -404.257168)
			(xy 82.56633 -404.264922) (xy 82.539078 -404.265384) (xy 81.675478 -404.265384) (xy 81.648226 -404.264945)
			(xy 81.594277 -404.257185) (xy 81.541982 -404.241827) (xy 81.492404 -404.219183) (xy 81.446554 -404.189715)
			(xy 81.405364 -404.154021) (xy 81.369672 -404.112829) (xy 81.340206 -404.066976) (xy 81.317565 -404.017397)
			(xy 81.30221 -403.965101) (xy 81.294454 -403.911152) (xy 79.856797 -403.911152) (xy 79.849043 -403.965089)
			(xy 79.833691 -404.017377) (xy 79.811054 -404.066949) (xy 79.781593 -404.112794) (xy 79.745908 -404.153981)
			(xy 79.704725 -404.18967) (xy 79.658882 -404.219135) (xy 79.609313 -404.241777) (xy 79.557026 -404.257135)
			(xy 79.503086 -404.264895) (xy 79.475838 -404.265384) (xy 78.612238 -404.265384) (xy 78.584982 -404.264972)
			(xy 78.531023 -404.257219) (xy 78.478717 -404.241865) (xy 78.429129 -404.219223) (xy 78.383268 -404.189754)
			(xy 78.342069 -404.154058) (xy 78.306369 -404.112862) (xy 78.276895 -404.067004) (xy 78.254248 -404.017418)
			(xy 78.238889 -403.965114) (xy 78.231131 -403.911156) (xy 76.79362 -403.911156) (xy 76.785864 -403.965099)
			(xy 76.770509 -404.017394) (xy 76.747868 -404.066971) (xy 76.718401 -404.112821) (xy 76.68271 -404.154011)
			(xy 76.64152 -404.189703) (xy 76.595669 -404.219169) (xy 76.546092 -404.24181) (xy 76.493797 -404.257165)
			(xy 76.439849 -404.264921) (xy 76.412598 -404.265384) (xy 75.548998 -404.265384) (xy 75.521745 -404.264946)
			(xy 75.467794 -404.257189) (xy 75.415496 -404.241833) (xy 75.365916 -404.21919) (xy 75.320063 -404.189722)
			(xy 75.278871 -404.154028) (xy 75.243177 -404.112835) (xy 75.213709 -404.066982) (xy 75.191067 -404.017402)
			(xy 75.175711 -403.965104) (xy 75.167954 -403.911153) (xy 73.730421 -403.911153) (xy 73.722663 -403.965104)
			(xy 73.707306 -404.017402) (xy 73.684662 -404.066982) (xy 73.655192 -404.112834) (xy 73.619496 -404.154025)
			(xy 73.578301 -404.189717) (xy 73.532445 -404.219182) (xy 73.482863 -404.241821) (xy 73.430563 -404.257172)
			(xy 73.376611 -404.264924) (xy 73.349358 -404.265384) (xy 72.485758 -404.265384) (xy 72.458507 -404.264943)
			(xy 72.40456 -404.257181) (xy 72.352267 -404.241822) (xy 72.302692 -404.219177) (xy 72.256844 -404.189707)
			(xy 72.215657 -404.154014) (xy 72.179967 -404.112822) (xy 72.150503 -404.066971) (xy 72.127864 -404.017393)
			(xy 72.11251 -403.965098) (xy 72.104754 -403.911151) (xy 70.667098 -403.911151) (xy 70.659342 -403.965091)
			(xy 70.643989 -404.017381) (xy 70.621351 -404.066954) (xy 70.591888 -404.112801) (xy 70.556201 -404.153988)
			(xy 70.515015 -404.189677) (xy 70.46917 -404.219142) (xy 70.419598 -404.241783) (xy 70.367309 -404.257138)
			(xy 70.313367 -404.264897) (xy 70.286118 -404.265384) (xy 69.422518 -404.265384) (xy 69.395263 -404.26497)
			(xy 69.341306 -404.257215) (xy 69.289003 -404.241859) (xy 69.239417 -404.219217) (xy 69.193559 -404.189747)
			(xy 69.152362 -404.154051) (xy 69.116664 -404.112855) (xy 69.087192 -404.066999) (xy 69.064547 -404.017414)
			(xy 69.049189 -403.965111) (xy 69.041431 -403.911155) (xy 67.603921 -403.911155) (xy 67.596164 -403.965102)
			(xy 67.580807 -404.017398) (xy 67.558165 -404.066976) (xy 67.528697 -404.112828) (xy 67.493003 -404.154018)
			(xy 67.45181 -404.18971) (xy 67.405957 -404.219175) (xy 67.356377 -404.241815) (xy 67.30408 -404.257168)
			(xy 67.25013 -404.264922) (xy 67.222878 -404.265384) (xy 66.359278 -404.265384) (xy 66.332026 -404.264945)
			(xy 66.278077 -404.257185) (xy 66.225782 -404.241827) (xy 66.176204 -404.219183) (xy 66.130354 -404.189715)
			(xy 66.089164 -404.154021) (xy 66.053472 -404.112829) (xy 66.024006 -404.066976) (xy 66.001365 -404.017397)
			(xy 65.98601 -403.965101) (xy 65.978254 -403.911152) (xy 64.540597 -403.911152) (xy 64.532843 -403.965089)
			(xy 64.517491 -404.017377) (xy 64.494854 -404.066949) (xy 64.465393 -404.112794) (xy 64.429708 -404.153981)
			(xy 64.388525 -404.18967) (xy 64.342682 -404.219135) (xy 64.293113 -404.241777) (xy 64.240826 -404.257135)
			(xy 64.186886 -404.264895) (xy 64.159638 -404.265384) (xy 63.296038 -404.265384) (xy 63.268782 -404.264972)
			(xy 63.214823 -404.257219) (xy 63.162517 -404.241865) (xy 63.112929 -404.219223) (xy 63.067068 -404.189754)
			(xy 63.025869 -404.154058) (xy 62.990169 -404.112862) (xy 62.960695 -404.067004) (xy 62.938048 -404.017418)
			(xy 62.922689 -403.965114) (xy 62.914931 -403.911156) (xy 61.47742 -403.911156) (xy 61.469664 -403.965099)
			(xy 61.454309 -404.017394) (xy 61.431668 -404.066971) (xy 61.402201 -404.112821) (xy 61.36651 -404.154011)
			(xy 61.32532 -404.189703) (xy 61.279469 -404.219169) (xy 61.229892 -404.24181) (xy 61.177597 -404.257165)
			(xy 61.123649 -404.264921) (xy 61.096398 -404.265384) (xy 60.232798 -404.265384) (xy 60.205545 -404.264946)
			(xy 60.151594 -404.257189) (xy 60.099296 -404.241833) (xy 60.049716 -404.21919) (xy 60.003863 -404.189722)
			(xy 59.962671 -404.154028) (xy 59.926977 -404.112835) (xy 59.897509 -404.066982) (xy 59.874867 -404.017402)
			(xy 59.859511 -403.965104) (xy 59.851754 -403.911153) (xy 58.414221 -403.911153) (xy 58.406463 -403.965104)
			(xy 58.391106 -404.017402) (xy 58.368462 -404.066982) (xy 58.338992 -404.112834) (xy 58.303296 -404.154025)
			(xy 58.262101 -404.189717) (xy 58.216245 -404.219182) (xy 58.166663 -404.241821) (xy 58.114363 -404.257172)
			(xy 58.060411 -404.264924) (xy 58.033158 -404.265384) (xy 57.169558 -404.265384) (xy 57.142307 -404.264943)
			(xy 57.08836 -404.257181) (xy 57.036067 -404.241822) (xy 56.986492 -404.219177) (xy 56.940644 -404.189707)
			(xy 56.899457 -404.154014) (xy 56.863767 -404.112822) (xy 56.834303 -404.066971) (xy 56.811664 -404.017393)
			(xy 56.79631 -403.965098) (xy 56.788554 -403.911151) (xy 55.350898 -403.911151) (xy 55.343142 -403.965091)
			(xy 55.327789 -404.017381) (xy 55.305151 -404.066954) (xy 55.275688 -404.112801) (xy 55.240001 -404.153988)
			(xy 55.198815 -404.189677) (xy 55.15297 -404.219142) (xy 55.103398 -404.241783) (xy 55.051109 -404.257138)
			(xy 54.997167 -404.264897) (xy 54.969918 -404.265384) (xy 54.106318 -404.265384) (xy 54.079063 -404.26497)
			(xy 54.025106 -404.257215) (xy 53.972803 -404.241859) (xy 53.923217 -404.219217) (xy 53.877359 -404.189747)
			(xy 53.836162 -404.154051) (xy 53.800464 -404.112855) (xy 53.770992 -404.066999) (xy 53.748347 -404.017414)
			(xy 53.732989 -403.965111) (xy 53.725231 -403.911155) (xy 52.287721 -403.911155) (xy 52.279964 -403.965102)
			(xy 52.264607 -404.017398) (xy 52.241965 -404.066976) (xy 52.212497 -404.112828) (xy 52.176803 -404.154018)
			(xy 52.13561 -404.18971) (xy 52.089757 -404.219175) (xy 52.040177 -404.241815) (xy 51.98788 -404.257168)
			(xy 51.93393 -404.264922) (xy 51.906678 -404.265384) (xy 51.043078 -404.265384) (xy 51.015826 -404.264945)
			(xy 50.961877 -404.257185) (xy 50.909582 -404.241827) (xy 50.860004 -404.219183) (xy 50.814154 -404.189715)
			(xy 50.772964 -404.154021) (xy 50.737272 -404.112829) (xy 50.707806 -404.066976) (xy 50.685165 -404.017397)
			(xy 50.66981 -403.965101) (xy 50.662054 -403.911152) (xy 49.224397 -403.911152) (xy 49.216643 -403.965089)
			(xy 49.201291 -404.017377) (xy 49.178654 -404.066949) (xy 49.149193 -404.112794) (xy 49.113508 -404.153981)
			(xy 49.072325 -404.18967) (xy 49.026482 -404.219135) (xy 48.976913 -404.241777) (xy 48.924626 -404.257135)
			(xy 48.870686 -404.264895) (xy 48.843438 -404.265384) (xy 47.979838 -404.265384) (xy 47.952582 -404.264972)
			(xy 47.898623 -404.257219) (xy 47.846317 -404.241865) (xy 47.796729 -404.219223) (xy 47.750868 -404.189754)
			(xy 47.709669 -404.154058) (xy 47.673969 -404.112862) (xy 47.644495 -404.067004) (xy 47.621848 -404.017418)
			(xy 47.606489 -403.965114) (xy 47.598731 -403.911156) (xy 2.610452 -403.911156) (xy 2.622121 -403.942439)
			(xy 2.666338 -404.039266) (xy 2.717346 -404.132693) (xy 2.774884 -404.222247) (xy 2.838661 -404.307471)
			(xy 2.908351 -404.387931) (xy 2.945638 -404.425912) (xy 3.748786 -405.22906) (xy 102.242112 -405.22906)
			(xy 102.242112 -404.36546) (xy 102.242598 -404.338209) (xy 102.250354 -404.284261) (xy 102.265709 -404.231966)
			(xy 102.288351 -404.182389) (xy 102.317817 -404.136539) (xy 102.353508 -404.095348) (xy 102.394699 -404.059657)
			(xy 102.440549 -404.030191) (xy 102.490126 -404.007549) (xy 102.542421 -403.992194) (xy 102.596369 -403.984438)
			(xy 102.650871 -403.984438) (xy 102.704819 -403.992194) (xy 102.757114 -404.007549) (xy 102.806691 -404.030191)
			(xy 102.852541 -404.059657) (xy 102.893732 -404.095348) (xy 102.929423 -404.136539) (xy 102.958889 -404.182389)
			(xy 102.981531 -404.231966) (xy 102.996886 -404.284261) (xy 103.004642 -404.338209) (xy 103.005128 -404.36546)
			(xy 103.005128 -405.22906) (xy 103.004642 -405.256311) (xy 102.996886 -405.310259) (xy 102.981531 -405.362554)
			(xy 102.958889 -405.412131) (xy 102.929423 -405.457981) (xy 102.893732 -405.499172) (xy 102.852541 -405.534863)
			(xy 102.806691 -405.564329) (xy 102.757114 -405.586971) (xy 102.704819 -405.602326) (xy 102.650871 -405.610082)
			(xy 102.596369 -405.610082) (xy 102.542421 -405.602326) (xy 102.490126 -405.586971) (xy 102.440549 -405.564329)
			(xy 102.394699 -405.534863) (xy 102.353508 -405.499172) (xy 102.317817 -405.457981) (xy 102.288351 -405.412131)
			(xy 102.265709 -405.362554) (xy 102.250354 -405.310259) (xy 102.242598 -405.256311) (xy 102.242112 -405.22906)
			(xy 3.748786 -405.22906) (xy 5.555234 -407.035508) (xy 15.978632 -407.035508) (xy 15.978632 -406.171908)
			(xy 15.979118 -406.144657) (xy 15.986874 -406.090709) (xy 16.002229 -406.038414) (xy 16.024871 -405.988837)
			(xy 16.054337 -405.942987) (xy 16.090028 -405.901796) (xy 16.131219 -405.866105) (xy 16.177069 -405.836639)
			(xy 16.226646 -405.813997) (xy 16.278941 -405.798642) (xy 16.332889 -405.790886) (xy 16.387391 -405.790886)
			(xy 16.441339 -405.798642) (xy 16.493634 -405.813997) (xy 16.543211 -405.836639) (xy 16.589061 -405.866105)
			(xy 16.630252 -405.901796) (xy 16.665943 -405.942987) (xy 16.695409 -405.988837) (xy 16.718051 -406.038414)
			(xy 16.733406 -406.090709) (xy 16.741162 -406.144657) (xy 16.741648 -406.171908) (xy 16.741648 -407.031753)
			(xy 48.944975 -407.031753) (xy 48.944975 -406.977247) (xy 48.952733 -406.923295) (xy 48.96809 -406.870997)
			(xy 48.990734 -406.821417) (xy 49.020204 -406.775565) (xy 49.0559 -406.734373) (xy 49.097095 -406.698681)
			(xy 49.142951 -406.669216) (xy 49.192533 -406.646577) (xy 49.244833 -406.631225) (xy 49.298785 -406.623473)
			(xy 49.326038 -406.623012) (xy 50.189638 -406.623012) (xy 50.216889 -406.62346) (xy 50.270835 -406.631222)
			(xy 50.323128 -406.646581) (xy 50.372703 -406.669225) (xy 50.418551 -406.698694) (xy 50.459739 -406.734388)
			(xy 50.495428 -406.775579) (xy 50.524893 -406.82143) (xy 50.547532 -406.871007) (xy 50.562886 -406.923302)
			(xy 50.570642 -406.977249) (xy 50.570642 -407.031749) (xy 52.008298 -407.031749) (xy 52.008298 -406.977251)
			(xy 52.016054 -406.923308) (xy 52.031407 -406.871018) (xy 52.054045 -406.821445) (xy 52.083508 -406.775598)
			(xy 52.119195 -406.734411) (xy 52.16038 -406.698721) (xy 52.206226 -406.669256) (xy 52.255797 -406.646615)
			(xy 52.308087 -406.631258) (xy 52.362029 -406.6235) (xy 52.389278 -406.623012) (xy 53.252878 -406.623012)
			(xy 53.280133 -406.623433) (xy 53.33409 -406.631188) (xy 53.386393 -406.646543) (xy 53.435978 -406.669186)
			(xy 53.481837 -406.698655) (xy 53.523034 -406.73435) (xy 53.558732 -406.775546) (xy 53.588204 -406.821402)
			(xy 53.610849 -406.870987) (xy 53.626207 -406.923289) (xy 53.633965 -406.977245) (xy 53.633965 -407.031752)
			(xy 55.071475 -407.031752) (xy 55.071475 -406.977248) (xy 55.079232 -406.923298) (xy 55.094589 -406.871002)
			(xy 55.117231 -406.821423) (xy 55.146699 -406.775571) (xy 55.182393 -406.73438) (xy 55.223586 -406.698688)
			(xy 55.269439 -406.669222) (xy 55.319018 -406.646582) (xy 55.371316 -406.631229) (xy 55.425266 -406.623474)
			(xy 55.452518 -406.623012) (xy 56.316118 -406.623012) (xy 56.34337 -406.623459) (xy 56.397318 -406.631218)
			(xy 56.449614 -406.646576) (xy 56.499191 -406.669219) (xy 56.545042 -406.698687) (xy 56.586232 -406.734381)
			(xy 56.621924 -406.775573) (xy 56.65139 -406.821424) (xy 56.674031 -406.871003) (xy 56.689386 -406.923299)
			(xy 56.697142 -406.977248) (xy 56.697142 -407.031748) (xy 58.134798 -407.031748) (xy 58.134798 -406.977252)
			(xy 58.142553 -406.923311) (xy 58.157905 -406.871022) (xy 58.180542 -406.821451) (xy 58.210003 -406.775605)
			(xy 58.245688 -406.734418) (xy 58.286871 -406.698728) (xy 58.332714 -406.669262) (xy 58.382283 -406.64662)
			(xy 58.43457 -406.631262) (xy 58.48851 -406.623501) (xy 58.515758 -406.623012) (xy 59.379358 -406.623012)
			(xy 59.406614 -406.623432) (xy 59.460573 -406.631185) (xy 59.512878 -406.646538) (xy 59.562466 -406.669179)
			(xy 59.608327 -406.698648) (xy 59.649527 -406.734343) (xy 59.685227 -406.775539) (xy 59.714701 -406.821397)
			(xy 59.737348 -406.870982) (xy 59.752707 -406.923286) (xy 59.760465 -406.977244) (xy 59.760465 -407.03175)
			(xy 61.197998 -407.03175) (xy 61.197998 -406.97725) (xy 61.205754 -406.923306) (xy 61.221108 -406.871014)
			(xy 61.243748 -406.821439) (xy 61.273213 -406.775592) (xy 61.308902 -406.734404) (xy 61.35009 -406.698714)
			(xy 61.395938 -406.669249) (xy 61.445512 -406.646609) (xy 61.497804 -406.631255) (xy 61.551748 -406.623498)
			(xy 61.578998 -406.623012) (xy 62.442598 -406.623012) (xy 62.469852 -406.623435) (xy 62.523806 -406.631192)
			(xy 62.576107 -406.646549) (xy 62.62569 -406.669192) (xy 62.671546 -406.698662) (xy 62.712741 -406.734357)
			(xy 62.748437 -406.775552) (xy 62.777907 -406.821408) (xy 62.800551 -406.870991) (xy 62.815908 -406.923292)
			(xy 62.823665 -406.977246) (xy 62.823665 -407.031753) (xy 64.261175 -407.031753) (xy 64.261175 -406.977247)
			(xy 64.268933 -406.923295) (xy 64.28429 -406.870997) (xy 64.306934 -406.821417) (xy 64.336404 -406.775565)
			(xy 64.3721 -406.734373) (xy 64.413295 -406.698681) (xy 64.459151 -406.669216) (xy 64.508733 -406.646577)
			(xy 64.561033 -406.631225) (xy 64.614985 -406.623473) (xy 64.642238 -406.623012) (xy 65.505838 -406.623012)
			(xy 65.533089 -406.62346) (xy 65.587035 -406.631222) (xy 65.639328 -406.646581) (xy 65.688903 -406.669225)
			(xy 65.734751 -406.698694) (xy 65.775939 -406.734388) (xy 65.811628 -406.775579) (xy 65.841093 -406.82143)
			(xy 65.863732 -406.871007) (xy 65.879086 -406.923302) (xy 65.886842 -406.977249) (xy 65.886842 -407.031749)
			(xy 67.324498 -407.031749) (xy 67.324498 -406.977251) (xy 67.332254 -406.923308) (xy 67.347607 -406.871018)
			(xy 67.370245 -406.821445) (xy 67.399708 -406.775598) (xy 67.435395 -406.734411) (xy 67.47658 -406.698721)
			(xy 67.522426 -406.669256) (xy 67.571997 -406.646615) (xy 67.624287 -406.631258) (xy 67.678229 -406.6235)
			(xy 67.705478 -406.623012) (xy 68.569078 -406.623012) (xy 68.596333 -406.623433) (xy 68.65029 -406.631188)
			(xy 68.702593 -406.646543) (xy 68.752178 -406.669186) (xy 68.798037 -406.698655) (xy 68.839234 -406.73435)
			(xy 68.874932 -406.775546) (xy 68.904404 -406.821402) (xy 68.927049 -406.870987) (xy 68.942407 -406.923289)
			(xy 68.950165 -406.977245) (xy 68.950165 -407.031752) (xy 70.387675 -407.031752) (xy 70.387675 -406.977248)
			(xy 70.395432 -406.923298) (xy 70.410789 -406.871002) (xy 70.433431 -406.821423) (xy 70.462899 -406.775571)
			(xy 70.498593 -406.73438) (xy 70.539786 -406.698688) (xy 70.585639 -406.669222) (xy 70.635218 -406.646582)
			(xy 70.687516 -406.631229) (xy 70.741466 -406.623474) (xy 70.768718 -406.623012) (xy 71.632318 -406.623012)
			(xy 71.65957 -406.623459) (xy 71.713518 -406.631218) (xy 71.765814 -406.646576) (xy 71.815391 -406.669219)
			(xy 71.861242 -406.698687) (xy 71.902432 -406.734381) (xy 71.938124 -406.775573) (xy 71.96759 -406.821424)
			(xy 71.990231 -406.871003) (xy 72.005586 -406.923299) (xy 72.013342 -406.977248) (xy 72.013342 -407.031748)
			(xy 73.450998 -407.031748) (xy 73.450998 -406.977252) (xy 73.458753 -406.923311) (xy 73.474105 -406.871022)
			(xy 73.496742 -406.821451) (xy 73.526203 -406.775605) (xy 73.561888 -406.734418) (xy 73.603071 -406.698728)
			(xy 73.648914 -406.669262) (xy 73.698483 -406.64662) (xy 73.75077 -406.631262) (xy 73.80471 -406.623501)
			(xy 73.831958 -406.623012) (xy 74.695558 -406.623012) (xy 74.722814 -406.623432) (xy 74.776773 -406.631185)
			(xy 74.829078 -406.646538) (xy 74.878666 -406.669179) (xy 74.924527 -406.698648) (xy 74.965727 -406.734343)
			(xy 75.001427 -406.775539) (xy 75.030901 -406.821397) (xy 75.053548 -406.870982) (xy 75.068907 -406.923286)
			(xy 75.076665 -406.977244) (xy 75.076665 -407.03175) (xy 76.514198 -407.03175) (xy 76.514198 -406.97725)
			(xy 76.521954 -406.923306) (xy 76.537308 -406.871014) (xy 76.559948 -406.821439) (xy 76.589413 -406.775592)
			(xy 76.625102 -406.734404) (xy 76.66629 -406.698714) (xy 76.712138 -406.669249) (xy 76.761712 -406.646609)
			(xy 76.814004 -406.631255) (xy 76.867948 -406.623498) (xy 76.895198 -406.623012) (xy 77.758798 -406.623012)
			(xy 77.786052 -406.623435) (xy 77.840006 -406.631192) (xy 77.892307 -406.646549) (xy 77.94189 -406.669192)
			(xy 77.987746 -406.698662) (xy 78.028941 -406.734357) (xy 78.064637 -406.775552) (xy 78.094107 -406.821408)
			(xy 78.116751 -406.870991) (xy 78.132108 -406.923292) (xy 78.139865 -406.977246) (xy 78.139865 -407.031753)
			(xy 79.577375 -407.031753) (xy 79.577375 -406.977247) (xy 79.585133 -406.923295) (xy 79.60049 -406.870997)
			(xy 79.623134 -406.821417) (xy 79.652604 -406.775565) (xy 79.6883 -406.734373) (xy 79.729495 -406.698681)
			(xy 79.775351 -406.669216) (xy 79.824933 -406.646577) (xy 79.877233 -406.631225) (xy 79.931185 -406.623473)
			(xy 79.958438 -406.623012) (xy 80.822038 -406.623012) (xy 80.849289 -406.62346) (xy 80.903235 -406.631222)
			(xy 80.955528 -406.646581) (xy 81.005103 -406.669225) (xy 81.050951 -406.698694) (xy 81.092139 -406.734388)
			(xy 81.127828 -406.775579) (xy 81.157293 -406.82143) (xy 81.179932 -406.871007) (xy 81.195286 -406.923302)
			(xy 81.203042 -406.977249) (xy 81.203042 -407.031749) (xy 82.640698 -407.031749) (xy 82.640698 -406.977251)
			(xy 82.648454 -406.923308) (xy 82.663807 -406.871018) (xy 82.686445 -406.821445) (xy 82.715908 -406.775598)
			(xy 82.751595 -406.734411) (xy 82.79278 -406.698721) (xy 82.838626 -406.669256) (xy 82.888197 -406.646615)
			(xy 82.940487 -406.631258) (xy 82.994429 -406.6235) (xy 83.021678 -406.623012) (xy 83.885278 -406.623012)
			(xy 83.912533 -406.623433) (xy 83.96649 -406.631188) (xy 84.018793 -406.646543) (xy 84.068378 -406.669186)
			(xy 84.114237 -406.698655) (xy 84.155434 -406.73435) (xy 84.191132 -406.775546) (xy 84.220604 -406.821402)
			(xy 84.243249 -406.870987) (xy 84.258607 -406.923289) (xy 84.266365 -406.977245) (xy 84.266365 -407.031752)
			(xy 85.703875 -407.031752) (xy 85.703875 -406.977248) (xy 85.711632 -406.923298) (xy 85.726989 -406.871002)
			(xy 85.749631 -406.821423) (xy 85.779099 -406.775571) (xy 85.814793 -406.73438) (xy 85.855986 -406.698688)
			(xy 85.901839 -406.669222) (xy 85.951418 -406.646582) (xy 86.003716 -406.631229) (xy 86.057666 -406.623474)
			(xy 86.084918 -406.623012) (xy 86.948518 -406.623012) (xy 86.97577 -406.623459) (xy 87.029718 -406.631218)
			(xy 87.082014 -406.646576) (xy 87.131591 -406.669219) (xy 87.177442 -406.698687) (xy 87.218632 -406.734381)
			(xy 87.254324 -406.775573) (xy 87.28379 -406.821424) (xy 87.306431 -406.871003) (xy 87.321786 -406.923299)
			(xy 87.329542 -406.977248) (xy 87.329542 -407.031748) (xy 88.767198 -407.031748) (xy 88.767198 -406.977252)
			(xy 88.774953 -406.923311) (xy 88.790305 -406.871022) (xy 88.812942 -406.821451) (xy 88.842403 -406.775605)
			(xy 88.878088 -406.734418) (xy 88.919271 -406.698728) (xy 88.965114 -406.669262) (xy 89.014683 -406.64662)
			(xy 89.06697 -406.631262) (xy 89.12091 -406.623501) (xy 89.148158 -406.623012) (xy 90.011758 -406.623012)
			(xy 90.039014 -406.623432) (xy 90.092973 -406.631185) (xy 90.145278 -406.646538) (xy 90.194866 -406.669179)
			(xy 90.240727 -406.698648) (xy 90.281927 -406.734343) (xy 90.317627 -406.775539) (xy 90.347101 -406.821397)
			(xy 90.369748 -406.870982) (xy 90.385107 -406.923286) (xy 90.392865 -406.977244) (xy 90.392865 -407.03175)
			(xy 91.830398 -407.03175) (xy 91.830398 -406.97725) (xy 91.838154 -406.923306) (xy 91.853508 -406.871014)
			(xy 91.876148 -406.821439) (xy 91.905613 -406.775592) (xy 91.941302 -406.734404) (xy 91.98249 -406.698714)
			(xy 92.028338 -406.669249) (xy 92.077912 -406.646609) (xy 92.130204 -406.631255) (xy 92.184148 -406.623498)
			(xy 92.211398 -406.623012) (xy 93.074998 -406.623012) (xy 93.102252 -406.623435) (xy 93.156206 -406.631192)
			(xy 93.208507 -406.646549) (xy 93.25809 -406.669192) (xy 93.303946 -406.698662) (xy 93.345141 -406.734357)
			(xy 93.380837 -406.775552) (xy 93.410307 -406.821408) (xy 93.432951 -406.870991) (xy 93.448308 -406.923292)
			(xy 93.456065 -406.977246) (xy 93.456065 -407.031753) (xy 94.893575 -407.031753) (xy 94.893575 -406.977247)
			(xy 94.901333 -406.923295) (xy 94.91669 -406.870997) (xy 94.939334 -406.821417) (xy 94.968804 -406.775565)
			(xy 95.0045 -406.734373) (xy 95.045695 -406.698681) (xy 95.091551 -406.669216) (xy 95.141133 -406.646577)
			(xy 95.193433 -406.631225) (xy 95.247385 -406.623473) (xy 95.274638 -406.623012) (xy 96.138238 -406.623012)
			(xy 96.165489 -406.62346) (xy 96.219435 -406.631222) (xy 96.271728 -406.646581) (xy 96.321303 -406.669225)
			(xy 96.367151 -406.698694) (xy 96.408339 -406.734388) (xy 96.444028 -406.775579) (xy 96.473493 -406.82143)
			(xy 96.496132 -406.871007) (xy 96.511486 -406.923302) (xy 96.519242 -406.977249) (xy 96.519242 -407.031751)
			(xy 96.511486 -407.085698) (xy 96.496132 -407.137993) (xy 96.495694 -407.138953) (xy 106.243063 -407.138953)
			(xy 106.243063 -407.084447) (xy 106.250821 -407.030495) (xy 106.266177 -406.978197) (xy 106.288821 -406.928617)
			(xy 106.31829 -406.882763) (xy 106.353985 -406.841571) (xy 106.395179 -406.805878) (xy 106.441034 -406.776411)
			(xy 106.490616 -406.75377) (xy 106.542915 -406.738416) (xy 106.596867 -406.730662) (xy 106.62412 -406.7302)
			(xy 107.48772 -406.7302) (xy 107.514971 -406.730671) (xy 107.568918 -406.73843) (xy 107.621211 -406.753787)
			(xy 107.670787 -406.77643) (xy 107.716636 -406.805898) (xy 107.757824 -406.84159) (xy 107.793514 -406.88278)
			(xy 107.82298 -406.928631) (xy 107.84562 -406.978208) (xy 107.860974 -407.030502) (xy 107.861153 -407.031748)
			(xy 121.120198 -407.031748) (xy 121.120198 -406.977252) (xy 121.127953 -406.923312) (xy 121.143305 -406.871023)
			(xy 121.165942 -406.821452) (xy 121.195402 -406.775606) (xy 121.231087 -406.734419) (xy 121.272269 -406.69873)
			(xy 121.318111 -406.669264) (xy 121.36768 -406.646621) (xy 121.419967 -406.631263) (xy 121.473906 -406.623501)
			(xy 121.501154 -406.623012) (xy 122.364754 -406.623012) (xy 122.39201 -406.623432) (xy 122.445969 -406.631184)
			(xy 122.498275 -406.646537) (xy 122.547864 -406.669178) (xy 122.593725 -406.698646) (xy 122.634926 -406.734342)
			(xy 122.670626 -406.775538) (xy 122.7001 -406.821396) (xy 122.722747 -406.870981) (xy 122.738106 -406.923286)
			(xy 122.745865 -406.977244) (xy 122.745865 -407.03175) (xy 124.183398 -407.03175) (xy 124.183398 -406.97725)
			(xy 124.191154 -406.923306) (xy 124.206508 -406.871015) (xy 124.229148 -406.821441) (xy 124.258612 -406.775593)
			(xy 124.294301 -406.734405) (xy 124.335488 -406.698715) (xy 124.381335 -406.669251) (xy 124.430909 -406.64661)
			(xy 124.4832 -406.631255) (xy 124.537144 -406.623499) (xy 124.564394 -406.623012) (xy 125.427994 -406.623012)
			(xy 125.455249 -406.623434) (xy 125.509203 -406.631191) (xy 125.561504 -406.646548) (xy 125.611088 -406.669191)
			(xy 125.656944 -406.69866) (xy 125.69814 -406.734356) (xy 125.733836 -406.775551) (xy 125.763306 -406.821407)
			(xy 125.78595 -406.87099) (xy 125.801308 -406.923291) (xy 125.809065 -406.977245) (xy 125.809065 -407.031753)
			(xy 127.246575 -407.031753) (xy 127.246575 -406.977247) (xy 127.254333 -406.923296) (xy 127.26969 -406.870998)
			(xy 127.292334 -406.821418) (xy 127.321803 -406.775566) (xy 127.357499 -406.734375) (xy 127.398693 -406.698683)
			(xy 127.444548 -406.669217) (xy 127.49413 -406.646578) (xy 127.546429 -406.631226) (xy 127.600381 -406.623473)
			(xy 127.627634 -406.623012) (xy 128.491234 -406.623012) (xy 128.518485 -406.62346) (xy 128.572432 -406.631221)
			(xy 128.624725 -406.64658) (xy 128.674301 -406.669224) (xy 128.720149 -406.698693) (xy 128.761338 -406.734386)
			(xy 128.797028 -406.775578) (xy 128.826492 -406.821429) (xy 128.849132 -406.871007) (xy 128.864486 -406.923301)
			(xy 128.872242 -406.977249) (xy 128.872242 -407.031749) (xy 130.309898 -407.031749) (xy 130.309898 -406.977251)
			(xy 130.317654 -406.923309) (xy 130.333007 -406.871019) (xy 130.355645 -406.821446) (xy 130.385107 -406.775599)
			(xy 130.420794 -406.734412) (xy 130.461979 -406.698722) (xy 130.507823 -406.669257) (xy 130.557395 -406.646616)
			(xy 130.609683 -406.631259) (xy 130.663625 -406.6235) (xy 130.690874 -406.623012) (xy 131.554474 -406.623012)
			(xy 131.58173 -406.623433) (xy 131.635686 -406.631187) (xy 131.68799 -406.646542) (xy 131.737576 -406.669184)
			(xy 131.783435 -406.698653) (xy 131.824633 -406.734349) (xy 131.860331 -406.775544) (xy 131.889803 -406.821401)
			(xy 131.912449 -406.870986) (xy 131.927807 -406.923288) (xy 131.935565 -406.977245) (xy 131.935565 -407.031752)
			(xy 133.373075 -407.031752) (xy 133.373075 -406.977248) (xy 133.380832 -406.923299) (xy 133.396188 -406.871002)
			(xy 133.418831 -406.821424) (xy 133.448298 -406.775573) (xy 133.483992 -406.734382) (xy 133.525184 -406.69869)
			(xy 133.571036 -406.669224) (xy 133.620616 -406.646583) (xy 133.672912 -406.631229) (xy 133.726862 -406.623474)
			(xy 133.754114 -406.623012) (xy 134.617714 -406.623012) (xy 134.644966 -406.623459) (xy 134.698915 -406.631217)
			(xy 134.751211 -406.646574) (xy 134.800789 -406.669218) (xy 134.84664 -406.698686) (xy 134.887831 -406.734379)
			(xy 134.923523 -406.775571) (xy 134.952989 -406.821423) (xy 134.97563 -406.871002) (xy 134.990986 -406.923299)
			(xy 134.998742 -406.977248) (xy 134.998742 -407.031748) (xy 136.436398 -407.031748) (xy 136.436398 -406.977252)
			(xy 136.444153 -406.923312) (xy 136.459505 -406.871023) (xy 136.482142 -406.821452) (xy 136.511602 -406.775606)
			(xy 136.547287 -406.734419) (xy 136.588469 -406.69873) (xy 136.634311 -406.669264) (xy 136.68388 -406.646621)
			(xy 136.736167 -406.631263) (xy 136.790106 -406.623501) (xy 136.817354 -406.623012) (xy 137.680954 -406.623012)
			(xy 137.70821 -406.623432) (xy 137.762169 -406.631184) (xy 137.814475 -406.646537) (xy 137.864064 -406.669178)
			(xy 137.909925 -406.698646) (xy 137.951126 -406.734342) (xy 137.986826 -406.775538) (xy 138.0163 -406.821396)
			(xy 138.038947 -406.870981) (xy 138.054306 -406.923286) (xy 138.062065 -406.977244) (xy 138.062065 -407.03175)
			(xy 139.499598 -407.03175) (xy 139.499598 -406.97725) (xy 139.507354 -406.923306) (xy 139.522708 -406.871015)
			(xy 139.545348 -406.821441) (xy 139.574812 -406.775593) (xy 139.610501 -406.734405) (xy 139.651688 -406.698715)
			(xy 139.697535 -406.669251) (xy 139.747109 -406.64661) (xy 139.7994 -406.631255) (xy 139.853344 -406.623499)
			(xy 139.880594 -406.623012) (xy 140.744194 -406.623012) (xy 140.771449 -406.623434) (xy 140.825403 -406.631191)
			(xy 140.877704 -406.646548) (xy 140.927288 -406.669191) (xy 140.973144 -406.69866) (xy 141.01434 -406.734356)
			(xy 141.050036 -406.775551) (xy 141.079506 -406.821407) (xy 141.10215 -406.87099) (xy 141.117508 -406.923291)
			(xy 141.125265 -406.977245) (xy 141.125265 -407.031753) (xy 142.562775 -407.031753) (xy 142.562775 -406.977247)
			(xy 142.570533 -406.923296) (xy 142.58589 -406.870998) (xy 142.608534 -406.821418) (xy 142.638003 -406.775566)
			(xy 142.673699 -406.734375) (xy 142.714893 -406.698683) (xy 142.760748 -406.669217) (xy 142.81033 -406.646578)
			(xy 142.862629 -406.631226) (xy 142.916581 -406.623473) (xy 142.943834 -406.623012) (xy 143.807434 -406.623012)
			(xy 143.834685 -406.62346) (xy 143.888632 -406.631221) (xy 143.940925 -406.64658) (xy 143.990501 -406.669224)
			(xy 144.036349 -406.698693) (xy 144.077538 -406.734386) (xy 144.113228 -406.775578) (xy 144.142692 -406.821429)
			(xy 144.165332 -406.871007) (xy 144.180686 -406.923301) (xy 144.188442 -406.977249) (xy 144.188442 -407.031749)
			(xy 145.626098 -407.031749) (xy 145.626098 -406.977251) (xy 145.633854 -406.923309) (xy 145.649207 -406.871019)
			(xy 145.671845 -406.821446) (xy 145.701307 -406.775599) (xy 145.736994 -406.734412) (xy 145.778179 -406.698722)
			(xy 145.824023 -406.669257) (xy 145.873595 -406.646616) (xy 145.925883 -406.631259) (xy 145.979825 -406.6235)
			(xy 146.007074 -406.623012) (xy 146.870674 -406.623012) (xy 146.89793 -406.623433) (xy 146.951886 -406.631187)
			(xy 147.00419 -406.646542) (xy 147.053776 -406.669184) (xy 147.099635 -406.698653) (xy 147.140833 -406.734349)
			(xy 147.176531 -406.775544) (xy 147.206003 -406.821401) (xy 147.228649 -406.870986) (xy 147.244007 -406.923288)
			(xy 147.251765 -406.977245) (xy 147.251765 -407.031752) (xy 148.689275 -407.031752) (xy 148.689275 -406.977248)
			(xy 148.697032 -406.923299) (xy 148.712388 -406.871002) (xy 148.735031 -406.821424) (xy 148.764498 -406.775573)
			(xy 148.800192 -406.734382) (xy 148.841384 -406.69869) (xy 148.887236 -406.669224) (xy 148.936816 -406.646583)
			(xy 148.989112 -406.631229) (xy 149.043062 -406.623474) (xy 149.070314 -406.623012) (xy 149.933914 -406.623012)
			(xy 149.961166 -406.623459) (xy 150.015115 -406.631217) (xy 150.067411 -406.646574) (xy 150.116989 -406.669218)
			(xy 150.16284 -406.698686) (xy 150.204031 -406.734379) (xy 150.239723 -406.775571) (xy 150.269189 -406.821423)
			(xy 150.29183 -406.871002) (xy 150.307186 -406.923299) (xy 150.314942 -406.977248) (xy 150.314942 -407.031748)
			(xy 151.752598 -407.031748) (xy 151.752598 -406.977252) (xy 151.760353 -406.923312) (xy 151.775705 -406.871023)
			(xy 151.798342 -406.821452) (xy 151.827802 -406.775606) (xy 151.863487 -406.734419) (xy 151.904669 -406.69873)
			(xy 151.950511 -406.669264) (xy 152.00008 -406.646621) (xy 152.052367 -406.631263) (xy 152.106306 -406.623501)
			(xy 152.133554 -406.623012) (xy 152.997154 -406.623012) (xy 153.02441 -406.623432) (xy 153.078369 -406.631184)
			(xy 153.130675 -406.646537) (xy 153.180264 -406.669178) (xy 153.226125 -406.698646) (xy 153.267326 -406.734342)
			(xy 153.303026 -406.775538) (xy 153.3325 -406.821396) (xy 153.355147 -406.870981) (xy 153.370506 -406.923286)
			(xy 153.378265 -406.977244) (xy 153.378265 -407.03175) (xy 154.815798 -407.03175) (xy 154.815798 -406.97725)
			(xy 154.823554 -406.923306) (xy 154.838908 -406.871015) (xy 154.861548 -406.821441) (xy 154.891012 -406.775593)
			(xy 154.926701 -406.734405) (xy 154.967888 -406.698715) (xy 155.013735 -406.669251) (xy 155.063309 -406.64661)
			(xy 155.1156 -406.631255) (xy 155.169544 -406.623499) (xy 155.196794 -406.623012) (xy 156.060394 -406.623012)
			(xy 156.087649 -406.623434) (xy 156.141603 -406.631191) (xy 156.193904 -406.646548) (xy 156.243488 -406.669191)
			(xy 156.289344 -406.69866) (xy 156.33054 -406.734356) (xy 156.366236 -406.775551) (xy 156.395706 -406.821407)
			(xy 156.41835 -406.87099) (xy 156.433708 -406.923291) (xy 156.441465 -406.977245) (xy 156.441465 -407.031753)
			(xy 157.878975 -407.031753) (xy 157.878975 -406.977247) (xy 157.886733 -406.923296) (xy 157.90209 -406.870998)
			(xy 157.924734 -406.821418) (xy 157.954203 -406.775566) (xy 157.989899 -406.734375) (xy 158.031093 -406.698683)
			(xy 158.076948 -406.669217) (xy 158.12653 -406.646578) (xy 158.178829 -406.631226) (xy 158.232781 -406.623473)
			(xy 158.260034 -406.623012) (xy 159.123634 -406.623012) (xy 159.150885 -406.62346) (xy 159.204832 -406.631221)
			(xy 159.257125 -406.64658) (xy 159.306701 -406.669224) (xy 159.352549 -406.698693) (xy 159.393738 -406.734386)
			(xy 159.429428 -406.775578) (xy 159.458892 -406.821429) (xy 159.481532 -406.871007) (xy 159.496886 -406.923301)
			(xy 159.504642 -406.977249) (xy 159.504642 -407.031749) (xy 160.942298 -407.031749) (xy 160.942298 -406.977251)
			(xy 160.950054 -406.923309) (xy 160.965407 -406.871019) (xy 160.988045 -406.821446) (xy 161.017507 -406.775599)
			(xy 161.053194 -406.734412) (xy 161.094379 -406.698722) (xy 161.140223 -406.669257) (xy 161.189795 -406.646616)
			(xy 161.242083 -406.631259) (xy 161.296025 -406.6235) (xy 161.323274 -406.623012) (xy 162.186874 -406.623012)
			(xy 162.21413 -406.623433) (xy 162.268086 -406.631187) (xy 162.32039 -406.646542) (xy 162.369976 -406.669184)
			(xy 162.415835 -406.698653) (xy 162.457033 -406.734349) (xy 162.492731 -406.775544) (xy 162.522203 -406.821401)
			(xy 162.544849 -406.870986) (xy 162.560207 -406.923288) (xy 162.567965 -406.977245) (xy 162.567965 -407.031752)
			(xy 164.005475 -407.031752) (xy 164.005475 -406.977248) (xy 164.013232 -406.923299) (xy 164.028588 -406.871002)
			(xy 164.051231 -406.821424) (xy 164.080698 -406.775573) (xy 164.116392 -406.734382) (xy 164.157584 -406.69869)
			(xy 164.203436 -406.669224) (xy 164.253016 -406.646583) (xy 164.305312 -406.631229) (xy 164.359262 -406.623474)
			(xy 164.386514 -406.623012) (xy 165.250114 -406.623012) (xy 165.277366 -406.623459) (xy 165.331315 -406.631217)
			(xy 165.383611 -406.646574) (xy 165.433189 -406.669218) (xy 165.47904 -406.698686) (xy 165.520231 -406.734379)
			(xy 165.555923 -406.775571) (xy 165.585389 -406.821423) (xy 165.60803 -406.871002) (xy 165.623386 -406.923299)
			(xy 165.631142 -406.977248) (xy 165.631142 -407.031748) (xy 167.068798 -407.031748) (xy 167.068798 -406.977252)
			(xy 167.076553 -406.923312) (xy 167.091905 -406.871023) (xy 167.114542 -406.821452) (xy 167.144002 -406.775606)
			(xy 167.179687 -406.734419) (xy 167.220869 -406.69873) (xy 167.266711 -406.669264) (xy 167.31628 -406.646621)
			(xy 167.368567 -406.631263) (xy 167.422506 -406.623501) (xy 167.449754 -406.623012) (xy 168.313354 -406.623012)
			(xy 168.34061 -406.623432) (xy 168.394569 -406.631184) (xy 168.446875 -406.646537) (xy 168.496464 -406.669178)
			(xy 168.542325 -406.698646) (xy 168.583526 -406.734342) (xy 168.619226 -406.775538) (xy 168.6487 -406.821396)
			(xy 168.671347 -406.870981) (xy 168.686706 -406.923286) (xy 168.694465 -406.977244) (xy 168.694465 -407.031749)
			(xy 304.945298 -407.031749) (xy 304.945298 -406.977251) (xy 304.953054 -406.923307) (xy 304.968408 -406.871016)
			(xy 304.991047 -406.821442) (xy 305.02051 -406.775595) (xy 305.056199 -406.734407) (xy 305.097385 -406.698718)
			(xy 305.143232 -406.669252) (xy 305.192805 -406.646612) (xy 305.245095 -406.631257) (xy 305.299039 -406.623499)
			(xy 305.326288 -406.623012) (xy 306.189888 -406.623012) (xy 306.217143 -406.623434) (xy 306.271098 -406.63119)
			(xy 306.3234 -406.646546) (xy 306.372984 -406.669189) (xy 306.418841 -406.698658) (xy 306.460038 -406.734354)
			(xy 306.495735 -406.775549) (xy 306.525205 -406.821405) (xy 306.54785 -406.870989) (xy 306.563207 -406.92329)
			(xy 306.570965 -406.977245) (xy 306.570965 -407.031753) (xy 308.008475 -407.031753) (xy 308.008475 -406.977247)
			(xy 308.016233 -406.923297) (xy 308.031589 -406.870999) (xy 308.054233 -406.82142) (xy 308.083702 -406.775568)
			(xy 308.119397 -406.734377) (xy 308.16059 -406.698685) (xy 308.206445 -406.669219) (xy 308.256026 -406.64658)
			(xy 308.308324 -406.631227) (xy 308.362275 -406.623473) (xy 308.389528 -406.623012) (xy 309.253128 -406.623012)
			(xy 309.280379 -406.62346) (xy 309.334327 -406.63122) (xy 309.386621 -406.646578) (xy 309.436197 -406.669222)
			(xy 309.482047 -406.698691) (xy 309.523236 -406.734384) (xy 309.558926 -406.775576) (xy 309.588391 -406.821427)
			(xy 309.611032 -406.871005) (xy 309.626386 -406.923301) (xy 309.634142 -406.977249) (xy 309.634142 -407.031748)
			(xy 311.071798 -407.031748) (xy 311.071798 -406.977252) (xy 311.079553 -406.92331) (xy 311.094906 -406.87102)
			(xy 311.117544 -406.821448) (xy 311.147005 -406.775601) (xy 311.182692 -406.734414) (xy 311.223876 -406.698725)
			(xy 311.26972 -406.669259) (xy 311.31929 -406.646617) (xy 311.371578 -406.63126) (xy 311.42552 -406.6235)
			(xy 311.452768 -406.623012) (xy 312.316368 -406.623012) (xy 312.343624 -406.623433) (xy 312.397581 -406.631186)
			(xy 312.449886 -406.64654) (xy 312.499472 -406.669182) (xy 312.545332 -406.698651) (xy 312.586531 -406.734347)
			(xy 312.62223 -406.775542) (xy 312.651702 -406.821399) (xy 312.674348 -406.870984) (xy 312.689707 -406.923288)
			(xy 312.697465 -406.977244) (xy 312.697465 -407.031752) (xy 314.134975 -407.031752) (xy 314.134975 -406.977248)
			(xy 314.142732 -406.923299) (xy 314.158088 -406.871004) (xy 314.18073 -406.821426) (xy 314.210197 -406.775575)
			(xy 314.245889 -406.734384) (xy 314.287081 -406.698692) (xy 314.332933 -406.669226) (xy 314.382511 -406.646585)
			(xy 314.434807 -406.63123) (xy 314.488756 -406.623475) (xy 314.516008 -406.623012) (xy 315.379608 -406.623012)
			(xy 315.40686 -406.623458) (xy 315.46081 -406.631216) (xy 315.513107 -406.646573) (xy 315.562685 -406.669216)
			(xy 315.608537 -406.698684) (xy 315.649729 -406.734377) (xy 315.685421 -406.775569) (xy 315.714888 -406.821422)
			(xy 315.73753 -406.871001) (xy 315.752885 -406.923298) (xy 315.760642 -406.977248) (xy 315.760642 -407.031752)
			(xy 315.760642 -407.031754) (xy 317.198175 -407.031754) (xy 317.198175 -406.977246) (xy 317.205933 -406.923294)
			(xy 317.221291 -406.870995) (xy 317.243936 -406.821414) (xy 317.273407 -406.775561) (xy 317.309104 -406.73437)
			(xy 317.3503 -406.698678) (xy 317.396157 -406.669213) (xy 317.44574 -406.646574) (xy 317.498041 -406.631223)
			(xy 317.551994 -406.623472) (xy 317.579248 -406.623012) (xy 318.442848 -406.623012) (xy 318.470098 -406.623461)
			(xy 318.524044 -406.631224) (xy 318.576336 -406.646584) (xy 318.625909 -406.669229) (xy 318.671756 -406.698698)
			(xy 318.712943 -406.734391) (xy 318.748631 -406.775582) (xy 318.778094 -406.821433) (xy 318.800733 -406.87101)
			(xy 318.816087 -406.923303) (xy 318.823842 -406.97725) (xy 318.823842 -407.031749) (xy 320.261498 -407.031749)
			(xy 320.261498 -406.977251) (xy 320.269254 -406.923307) (xy 320.284608 -406.871016) (xy 320.307247 -406.821442)
			(xy 320.33671 -406.775595) (xy 320.372399 -406.734407) (xy 320.413585 -406.698718) (xy 320.459432 -406.669252)
			(xy 320.509005 -406.646612) (xy 320.561295 -406.631257) (xy 320.615239 -406.623499) (xy 320.642488 -406.623012)
			(xy 321.506088 -406.623012) (xy 321.533343 -406.623434) (xy 321.587298 -406.63119) (xy 321.6396 -406.646546)
			(xy 321.689184 -406.669189) (xy 321.735041 -406.698658) (xy 321.776238 -406.734354) (xy 321.811935 -406.775549)
			(xy 321.841405 -406.821405) (xy 321.86405 -406.870989) (xy 321.879407 -406.92329) (xy 321.887165 -406.977245)
			(xy 321.887165 -407.031753) (xy 323.324675 -407.031753) (xy 323.324675 -406.977247) (xy 323.332433 -406.923297)
			(xy 323.347789 -406.870999) (xy 323.370433 -406.82142) (xy 323.399902 -406.775568) (xy 323.435597 -406.734377)
			(xy 323.47679 -406.698685) (xy 323.522645 -406.669219) (xy 323.572226 -406.64658) (xy 323.624524 -406.631227)
			(xy 323.678475 -406.623473) (xy 323.705728 -406.623012) (xy 324.569328 -406.623012) (xy 324.596579 -406.62346)
			(xy 324.650527 -406.63122) (xy 324.702821 -406.646578) (xy 324.752397 -406.669222) (xy 324.798247 -406.698691)
			(xy 324.839436 -406.734384) (xy 324.875126 -406.775576) (xy 324.904591 -406.821427) (xy 324.927232 -406.871005)
			(xy 324.942586 -406.923301) (xy 324.950342 -406.977249) (xy 324.950342 -407.031748) (xy 326.387998 -407.031748)
			(xy 326.387998 -406.977252) (xy 326.395753 -406.92331) (xy 326.411106 -406.87102) (xy 326.433744 -406.821448)
			(xy 326.463205 -406.775601) (xy 326.498892 -406.734414) (xy 326.540076 -406.698725) (xy 326.58592 -406.669259)
			(xy 326.63549 -406.646617) (xy 326.687778 -406.63126) (xy 326.74172 -406.6235) (xy 326.768968 -406.623012)
			(xy 327.632568 -406.623012) (xy 327.659824 -406.623433) (xy 327.713781 -406.631186) (xy 327.766086 -406.64654)
			(xy 327.815672 -406.669182) (xy 327.861532 -406.698651) (xy 327.902731 -406.734347) (xy 327.93843 -406.775542)
			(xy 327.967902 -406.821399) (xy 327.990548 -406.870984) (xy 328.005907 -406.923288) (xy 328.013665 -406.977244)
			(xy 328.013665 -407.031752) (xy 329.451175 -407.031752) (xy 329.451175 -406.977248) (xy 329.458932 -406.923299)
			(xy 329.474288 -406.871004) (xy 329.49693 -406.821426) (xy 329.526397 -406.775575) (xy 329.562089 -406.734384)
			(xy 329.603281 -406.698692) (xy 329.649133 -406.669226) (xy 329.698711 -406.646585) (xy 329.751007 -406.63123)
			(xy 329.804956 -406.623475) (xy 329.832208 -406.623012) (xy 330.695808 -406.623012) (xy 330.72306 -406.623458)
			(xy 330.77701 -406.631216) (xy 330.829307 -406.646573) (xy 330.878885 -406.669216) (xy 330.924737 -406.698684)
			(xy 330.965929 -406.734377) (xy 331.001621 -406.775569) (xy 331.031088 -406.821422) (xy 331.05373 -406.871001)
			(xy 331.069085 -406.923298) (xy 331.076842 -406.977248) (xy 331.076842 -407.031752) (xy 331.076842 -407.031754)
			(xy 332.514375 -407.031754) (xy 332.514375 -406.977246) (xy 332.522133 -406.923294) (xy 332.537491 -406.870995)
			(xy 332.560136 -406.821414) (xy 332.589607 -406.775561) (xy 332.625304 -406.73437) (xy 332.6665 -406.698678)
			(xy 332.712357 -406.669213) (xy 332.76194 -406.646574) (xy 332.814241 -406.631223) (xy 332.868194 -406.623472)
			(xy 332.895448 -406.623012) (xy 333.759048 -406.623012) (xy 333.786298 -406.623461) (xy 333.840244 -406.631224)
			(xy 333.892536 -406.646584) (xy 333.942109 -406.669229) (xy 333.987956 -406.698698) (xy 334.029143 -406.734391)
			(xy 334.064831 -406.775582) (xy 334.094294 -406.821433) (xy 334.116933 -406.87101) (xy 334.132287 -406.923303)
			(xy 334.140042 -406.97725) (xy 334.140042 -407.031749) (xy 335.577698 -407.031749) (xy 335.577698 -406.977251)
			(xy 335.585454 -406.923307) (xy 335.600808 -406.871016) (xy 335.623447 -406.821442) (xy 335.65291 -406.775595)
			(xy 335.688599 -406.734407) (xy 335.729785 -406.698718) (xy 335.775632 -406.669252) (xy 335.825205 -406.646612)
			(xy 335.877495 -406.631257) (xy 335.931439 -406.623499) (xy 335.958688 -406.623012) (xy 336.822288 -406.623012)
			(xy 336.849543 -406.623434) (xy 336.903498 -406.63119) (xy 336.9558 -406.646546) (xy 337.005384 -406.669189)
			(xy 337.051241 -406.698658) (xy 337.092438 -406.734354) (xy 337.128135 -406.775549) (xy 337.157605 -406.821405)
			(xy 337.18025 -406.870989) (xy 337.195607 -406.92329) (xy 337.203365 -406.977245) (xy 337.203365 -407.031753)
			(xy 338.640875 -407.031753) (xy 338.640875 -406.977247) (xy 338.648633 -406.923297) (xy 338.663989 -406.870999)
			(xy 338.686633 -406.82142) (xy 338.716102 -406.775568) (xy 338.751797 -406.734377) (xy 338.79299 -406.698685)
			(xy 338.838845 -406.669219) (xy 338.888426 -406.64658) (xy 338.940724 -406.631227) (xy 338.994675 -406.623473)
			(xy 339.021928 -406.623012) (xy 339.885528 -406.623012) (xy 339.912779 -406.62346) (xy 339.966727 -406.63122)
			(xy 340.019021 -406.646578) (xy 340.068597 -406.669222) (xy 340.114447 -406.698691) (xy 340.155636 -406.734384)
			(xy 340.191326 -406.775576) (xy 340.220791 -406.821427) (xy 340.243432 -406.871005) (xy 340.258786 -406.923301)
			(xy 340.266542 -406.977249) (xy 340.266542 -407.031748) (xy 341.704198 -407.031748) (xy 341.704198 -406.977252)
			(xy 341.711953 -406.92331) (xy 341.727306 -406.87102) (xy 341.749944 -406.821448) (xy 341.779405 -406.775601)
			(xy 341.815092 -406.734414) (xy 341.856276 -406.698725) (xy 341.90212 -406.669259) (xy 341.95169 -406.646617)
			(xy 342.003978 -406.63126) (xy 342.05792 -406.6235) (xy 342.085168 -406.623012) (xy 342.948768 -406.623012)
			(xy 342.976024 -406.623433) (xy 343.029981 -406.631186) (xy 343.082286 -406.64654) (xy 343.131872 -406.669182)
			(xy 343.177732 -406.698651) (xy 343.218931 -406.734347) (xy 343.25463 -406.775542) (xy 343.284102 -406.821399)
			(xy 343.306748 -406.870984) (xy 343.322107 -406.923288) (xy 343.329865 -406.977244) (xy 343.329865 -407.031752)
			(xy 344.767375 -407.031752) (xy 344.767375 -406.977248) (xy 344.775132 -406.923299) (xy 344.790488 -406.871004)
			(xy 344.81313 -406.821426) (xy 344.842597 -406.775575) (xy 344.878289 -406.734384) (xy 344.919481 -406.698692)
			(xy 344.965333 -406.669226) (xy 345.014911 -406.646585) (xy 345.067207 -406.63123) (xy 345.121156 -406.623475)
			(xy 345.148408 -406.623012) (xy 346.012008 -406.623012) (xy 346.03926 -406.623458) (xy 346.09321 -406.631216)
			(xy 346.145507 -406.646573) (xy 346.195085 -406.669216) (xy 346.240937 -406.698684) (xy 346.282129 -406.734377)
			(xy 346.317821 -406.775569) (xy 346.347288 -406.821422) (xy 346.36993 -406.871001) (xy 346.385285 -406.923298)
			(xy 346.393042 -406.977248) (xy 346.393042 -407.031752) (xy 346.393042 -407.031754) (xy 347.830575 -407.031754)
			(xy 347.830575 -406.977246) (xy 347.838333 -406.923294) (xy 347.853691 -406.870995) (xy 347.876336 -406.821414)
			(xy 347.905807 -406.775561) (xy 347.941504 -406.73437) (xy 347.9827 -406.698678) (xy 348.028557 -406.669213)
			(xy 348.07814 -406.646574) (xy 348.130441 -406.631223) (xy 348.184394 -406.623472) (xy 348.211648 -406.623012)
			(xy 349.075248 -406.623012) (xy 349.102498 -406.623461) (xy 349.156444 -406.631224) (xy 349.208736 -406.646584)
			(xy 349.258309 -406.669229) (xy 349.304156 -406.698698) (xy 349.345343 -406.734391) (xy 349.381031 -406.775582)
			(xy 349.410494 -406.821433) (xy 349.433133 -406.87101) (xy 349.448487 -406.923303) (xy 349.456242 -406.97725)
			(xy 349.456242 -407.031749) (xy 350.893898 -407.031749) (xy 350.893898 -406.977251) (xy 350.901654 -406.923307)
			(xy 350.917008 -406.871016) (xy 350.939647 -406.821442) (xy 350.96911 -406.775595) (xy 351.004799 -406.734407)
			(xy 351.045985 -406.698718) (xy 351.091832 -406.669252) (xy 351.141405 -406.646612) (xy 351.193695 -406.631257)
			(xy 351.247639 -406.623499) (xy 351.274888 -406.623012) (xy 352.138488 -406.623012) (xy 352.165743 -406.623434)
			(xy 352.219698 -406.63119) (xy 352.272 -406.646546) (xy 352.321584 -406.669189) (xy 352.367441 -406.698658)
			(xy 352.408638 -406.734354) (xy 352.444335 -406.775549) (xy 352.473805 -406.821405) (xy 352.49645 -406.870989)
			(xy 352.511807 -406.92329) (xy 352.519565 -406.977245) (xy 352.519565 -407.031753) (xy 372.388075 -407.031753)
			(xy 372.388075 -406.977247) (xy 372.395833 -406.923296) (xy 372.411189 -406.870999) (xy 372.433833 -406.821419)
			(xy 372.463302 -406.775567) (xy 372.498997 -406.734376) (xy 372.540191 -406.698684) (xy 372.586046 -406.669219)
			(xy 372.635627 -406.646579) (xy 372.687926 -406.631226) (xy 372.741877 -406.623473) (xy 372.76913 -406.623012)
			(xy 373.63273 -406.623012) (xy 373.659981 -406.62346) (xy 373.713929 -406.63122) (xy 373.766222 -406.646579)
			(xy 373.815799 -406.669223) (xy 373.861648 -406.698691) (xy 373.902836 -406.734385) (xy 373.938527 -406.775576)
			(xy 373.967992 -406.821428) (xy 373.990632 -406.871006) (xy 374.005986 -406.923301) (xy 374.013742 -406.977249)
			(xy 374.013742 -407.031748) (xy 375.451398 -407.031748) (xy 375.451398 -406.977252) (xy 375.459153 -406.923309)
			(xy 375.474506 -406.87102) (xy 375.497144 -406.821447) (xy 375.526606 -406.775601) (xy 375.562292 -406.734414)
			(xy 375.603477 -406.698724) (xy 375.649321 -406.669258) (xy 375.698892 -406.646617) (xy 375.75118 -406.63126)
			(xy 375.805122 -406.6235) (xy 375.83237 -406.623012) (xy 376.69597 -406.623012) (xy 376.723226 -406.623433)
			(xy 376.777183 -406.631187) (xy 376.829487 -406.646541) (xy 376.879074 -406.669183) (xy 376.924933 -406.698652)
			(xy 376.966131 -406.734347) (xy 377.00183 -406.775543) (xy 377.031303 -406.8214) (xy 377.053948 -406.870985)
			(xy 377.069307 -406.923288) (xy 377.077065 -406.977244) (xy 377.077065 -407.031752) (xy 378.514575 -407.031752)
			(xy 378.514575 -406.977248) (xy 378.522332 -406.923299) (xy 378.537688 -406.871003) (xy 378.56033 -406.821425)
			(xy 378.589797 -406.775574) (xy 378.62549 -406.734383) (xy 378.666682 -406.698691) (xy 378.712534 -406.669225)
			(xy 378.762113 -406.646584) (xy 378.814409 -406.63123) (xy 378.868358 -406.623475) (xy 378.89561 -406.623012)
			(xy 379.75921 -406.623012) (xy 379.786462 -406.623459) (xy 379.840412 -406.631217) (xy 379.892708 -406.646573)
			(xy 379.942287 -406.669216) (xy 379.988138 -406.698684) (xy 380.029329 -406.734378) (xy 380.065022 -406.77557)
			(xy 380.094489 -406.821422) (xy 380.11713 -406.871001) (xy 380.132486 -406.923298) (xy 380.140242 -406.977248)
			(xy 380.140242 -407.031748) (xy 381.577898 -407.031748) (xy 381.577898 -406.977252) (xy 381.585653 -406.923312)
			(xy 381.601005 -406.871024) (xy 381.623641 -406.821453) (xy 381.653101 -406.775607) (xy 381.688785 -406.734421)
			(xy 381.729967 -406.698731) (xy 381.775809 -406.669265) (xy 381.825377 -406.646622) (xy 381.877663 -406.631264)
			(xy 381.931603 -406.623502) (xy 381.95885 -406.623012) (xy 382.82245 -406.623012) (xy 382.849707 -406.623431)
			(xy 382.903666 -406.631183) (xy 382.955973 -406.646536) (xy 383.005562 -406.669176) (xy 383.051423 -406.698645)
			(xy 383.092624 -406.73434) (xy 383.128325 -406.775536) (xy 383.1578 -406.821394) (xy 383.180447 -406.870981)
			(xy 383.195806 -406.923285) (xy 383.203565 -406.977243) (xy 383.203565 -407.031749) (xy 384.641098 -407.031749)
			(xy 384.641098 -406.977251) (xy 384.648854 -406.923307) (xy 384.664208 -406.871016) (xy 384.686847 -406.821442)
			(xy 384.716311 -406.775594) (xy 384.751999 -406.734406) (xy 384.793186 -406.698717) (xy 384.839033 -406.669252)
			(xy 384.888606 -406.646611) (xy 384.940897 -406.631256) (xy 384.994841 -406.623499) (xy 385.02209 -406.623012)
			(xy 385.88569 -406.623012) (xy 385.912945 -406.623434) (xy 385.9669 -406.63119) (xy 386.019202 -406.646546)
			(xy 386.068786 -406.66919) (xy 386.114642 -406.698659) (xy 386.155838 -406.734354) (xy 386.191535 -406.77555)
			(xy 386.221006 -406.821406) (xy 386.24365 -406.870989) (xy 386.259007 -406.923291) (xy 386.266765 -406.977245)
			(xy 386.266765 -407.031753) (xy 387.704275 -407.031753) (xy 387.704275 -406.977247) (xy 387.712033 -406.923296)
			(xy 387.727389 -406.870999) (xy 387.750033 -406.821419) (xy 387.779502 -406.775567) (xy 387.815197 -406.734376)
			(xy 387.856391 -406.698684) (xy 387.902246 -406.669219) (xy 387.951827 -406.646579) (xy 388.004126 -406.631226)
			(xy 388.058077 -406.623473) (xy 388.08533 -406.623012) (xy 388.94893 -406.623012) (xy 388.976181 -406.62346)
			(xy 389.030129 -406.63122) (xy 389.082422 -406.646579) (xy 389.131999 -406.669223) (xy 389.177848 -406.698691)
			(xy 389.219036 -406.734385) (xy 389.254727 -406.775576) (xy 389.284192 -406.821428) (xy 389.306832 -406.871006)
			(xy 389.322186 -406.923301) (xy 389.329942 -406.977249) (xy 389.329942 -407.031748) (xy 390.767598 -407.031748)
			(xy 390.767598 -406.977252) (xy 390.775353 -406.923309) (xy 390.790706 -406.87102) (xy 390.813344 -406.821447)
			(xy 390.842806 -406.775601) (xy 390.878492 -406.734414) (xy 390.919677 -406.698724) (xy 390.965521 -406.669258)
			(xy 391.015092 -406.646617) (xy 391.06738 -406.63126) (xy 391.121322 -406.6235) (xy 391.14857 -406.623012)
			(xy 392.01217 -406.623012) (xy 392.039426 -406.623433) (xy 392.093383 -406.631187) (xy 392.145687 -406.646541)
			(xy 392.195274 -406.669183) (xy 392.241133 -406.698652) (xy 392.282331 -406.734347) (xy 392.31803 -406.775543)
			(xy 392.347503 -406.8214) (xy 392.370148 -406.870985) (xy 392.385507 -406.923288) (xy 392.393265 -406.977244)
			(xy 392.393265 -407.031752) (xy 393.830775 -407.031752) (xy 393.830775 -406.977248) (xy 393.838532 -406.923299)
			(xy 393.853888 -406.871003) (xy 393.87653 -406.821425) (xy 393.905997 -406.775574) (xy 393.94169 -406.734383)
			(xy 393.982882 -406.698691) (xy 394.028734 -406.669225) (xy 394.078313 -406.646584) (xy 394.130609 -406.63123)
			(xy 394.184558 -406.623475) (xy 394.21181 -406.623012) (xy 395.07541 -406.623012) (xy 395.102662 -406.623459)
			(xy 395.156612 -406.631217) (xy 395.208908 -406.646573) (xy 395.258487 -406.669216) (xy 395.304338 -406.698684)
			(xy 395.345529 -406.734378) (xy 395.381222 -406.77557) (xy 395.410689 -406.821422) (xy 395.43333 -406.871001)
			(xy 395.448686 -406.923298) (xy 395.456442 -406.977248) (xy 395.456442 -407.031748) (xy 396.894098 -407.031748)
			(xy 396.894098 -406.977252) (xy 396.901853 -406.923312) (xy 396.917205 -406.871024) (xy 396.939841 -406.821453)
			(xy 396.969301 -406.775607) (xy 397.004985 -406.734421) (xy 397.046167 -406.698731) (xy 397.092009 -406.669265)
			(xy 397.141577 -406.646622) (xy 397.193863 -406.631264) (xy 397.247803 -406.623502) (xy 397.27505 -406.623012)
			(xy 398.13865 -406.623012) (xy 398.165907 -406.623431) (xy 398.219866 -406.631183) (xy 398.272173 -406.646536)
			(xy 398.321762 -406.669176) (xy 398.367623 -406.698645) (xy 398.408824 -406.73434) (xy 398.444525 -406.775536)
			(xy 398.474 -406.821394) (xy 398.496647 -406.870981) (xy 398.512006 -406.923285) (xy 398.519765 -406.977243)
			(xy 398.519765 -407.031749) (xy 399.957298 -407.031749) (xy 399.957298 -406.977251) (xy 399.965054 -406.923307)
			(xy 399.980408 -406.871016) (xy 400.003047 -406.821442) (xy 400.032511 -406.775594) (xy 400.068199 -406.734406)
			(xy 400.109386 -406.698717) (xy 400.155233 -406.669252) (xy 400.204806 -406.646611) (xy 400.257097 -406.631256)
			(xy 400.311041 -406.623499) (xy 400.33829 -406.623012) (xy 401.20189 -406.623012) (xy 401.229145 -406.623434)
			(xy 401.2831 -406.63119) (xy 401.335402 -406.646546) (xy 401.384986 -406.66919) (xy 401.430842 -406.698659)
			(xy 401.472038 -406.734354) (xy 401.507735 -406.77555) (xy 401.537206 -406.821406) (xy 401.55985 -406.870989)
			(xy 401.575207 -406.923291) (xy 401.582965 -406.977245) (xy 401.582965 -407.031753) (xy 403.020475 -407.031753)
			(xy 403.020475 -406.977247) (xy 403.028233 -406.923296) (xy 403.043589 -406.870999) (xy 403.066233 -406.821419)
			(xy 403.095702 -406.775567) (xy 403.131397 -406.734376) (xy 403.172591 -406.698684) (xy 403.218446 -406.669219)
			(xy 403.268027 -406.646579) (xy 403.320326 -406.631226) (xy 403.374277 -406.623473) (xy 403.40153 -406.623012)
			(xy 404.26513 -406.623012) (xy 404.292381 -406.62346) (xy 404.346329 -406.63122) (xy 404.398622 -406.646579)
			(xy 404.448199 -406.669223) (xy 404.494048 -406.698691) (xy 404.535236 -406.734385) (xy 404.570927 -406.775576)
			(xy 404.600392 -406.821428) (xy 404.623032 -406.871006) (xy 404.638386 -406.923301) (xy 404.646142 -406.977249)
			(xy 404.646142 -407.031748) (xy 406.083798 -407.031748) (xy 406.083798 -406.977252) (xy 406.091553 -406.923309)
			(xy 406.106906 -406.87102) (xy 406.129544 -406.821447) (xy 406.159006 -406.775601) (xy 406.194692 -406.734414)
			(xy 406.235877 -406.698724) (xy 406.281721 -406.669258) (xy 406.331292 -406.646617) (xy 406.38358 -406.63126)
			(xy 406.437522 -406.6235) (xy 406.46477 -406.623012) (xy 407.32837 -406.623012) (xy 407.355626 -406.623433)
			(xy 407.409583 -406.631187) (xy 407.461887 -406.646541) (xy 407.511474 -406.669183) (xy 407.557333 -406.698652)
			(xy 407.598531 -406.734347) (xy 407.63423 -406.775543) (xy 407.663703 -406.8214) (xy 407.686348 -406.870985)
			(xy 407.701707 -406.923288) (xy 407.709465 -406.977244) (xy 407.709465 -407.031752) (xy 409.146975 -407.031752)
			(xy 409.146975 -406.977248) (xy 409.154732 -406.923299) (xy 409.170088 -406.871003) (xy 409.19273 -406.821425)
			(xy 409.222197 -406.775574) (xy 409.25789 -406.734383) (xy 409.299082 -406.698691) (xy 409.344934 -406.669225)
			(xy 409.394513 -406.646584) (xy 409.446809 -406.63123) (xy 409.500758 -406.623475) (xy 409.52801 -406.623012)
			(xy 410.39161 -406.623012) (xy 410.418862 -406.623459) (xy 410.472812 -406.631217) (xy 410.525108 -406.646573)
			(xy 410.574687 -406.669216) (xy 410.620538 -406.698684) (xy 410.661729 -406.734378) (xy 410.697422 -406.77557)
			(xy 410.726889 -406.821422) (xy 410.74953 -406.871001) (xy 410.764886 -406.923298) (xy 410.772642 -406.977248)
			(xy 410.772642 -407.031748) (xy 412.210298 -407.031748) (xy 412.210298 -406.977252) (xy 412.218053 -406.923312)
			(xy 412.233405 -406.871024) (xy 412.256041 -406.821453) (xy 412.285501 -406.775607) (xy 412.321185 -406.734421)
			(xy 412.362367 -406.698731) (xy 412.408209 -406.669265) (xy 412.457777 -406.646622) (xy 412.510063 -406.631264)
			(xy 412.564003 -406.623502) (xy 412.59125 -406.623012) (xy 413.45485 -406.623012) (xy 413.482107 -406.623431)
			(xy 413.536066 -406.631183) (xy 413.588373 -406.646536) (xy 413.637962 -406.669176) (xy 413.683823 -406.698645)
			(xy 413.725024 -406.73434) (xy 413.760725 -406.775536) (xy 413.7902 -406.821394) (xy 413.812847 -406.870981)
			(xy 413.828206 -406.923285) (xy 413.835965 -406.977243) (xy 413.835965 -407.031749) (xy 415.273498 -407.031749)
			(xy 415.273498 -406.977251) (xy 415.281254 -406.923307) (xy 415.296608 -406.871016) (xy 415.319247 -406.821442)
			(xy 415.348711 -406.775594) (xy 415.384399 -406.734406) (xy 415.425586 -406.698717) (xy 415.471433 -406.669252)
			(xy 415.521006 -406.646611) (xy 415.573297 -406.631256) (xy 415.627241 -406.623499) (xy 415.65449 -406.623012)
			(xy 416.51809 -406.623012) (xy 416.545345 -406.623434) (xy 416.5993 -406.63119) (xy 416.651602 -406.646546)
			(xy 416.701186 -406.66919) (xy 416.747042 -406.698659) (xy 416.788238 -406.734354) (xy 416.823935 -406.77555)
			(xy 416.853406 -406.821406) (xy 416.87605 -406.870989) (xy 416.891407 -406.923291) (xy 416.899165 -406.977245)
			(xy 416.899165 -407.031753) (xy 418.336675 -407.031753) (xy 418.336675 -406.977247) (xy 418.344433 -406.923296)
			(xy 418.359789 -406.870999) (xy 418.382433 -406.821419) (xy 418.411902 -406.775567) (xy 418.447597 -406.734376)
			(xy 418.488791 -406.698684) (xy 418.534646 -406.669219) (xy 418.584227 -406.646579) (xy 418.636526 -406.631226)
			(xy 418.690477 -406.623473) (xy 418.71773 -406.623012) (xy 419.58133 -406.623012) (xy 419.608581 -406.62346)
			(xy 419.662529 -406.63122) (xy 419.714822 -406.646579) (xy 419.764399 -406.669223) (xy 419.810248 -406.698691)
			(xy 419.851436 -406.734385) (xy 419.887127 -406.775576) (xy 419.916592 -406.821428) (xy 419.939232 -406.871006)
			(xy 419.954586 -406.923301) (xy 419.962342 -406.977249) (xy 419.962342 -407.031751) (xy 419.954586 -407.085699)
			(xy 419.939232 -407.137994) (xy 419.916592 -407.187572) (xy 419.887127 -407.233424) (xy 419.851436 -407.274615)
			(xy 419.810248 -407.310309) (xy 419.764399 -407.339777) (xy 419.714822 -407.362421) (xy 419.662529 -407.37778)
			(xy 419.608581 -407.38554) (xy 419.58133 -407.386028) (xy 418.71773 -407.386028) (xy 418.690477 -407.385527)
			(xy 418.636526 -407.377774) (xy 418.584227 -407.362421) (xy 418.534646 -407.339781) (xy 418.488791 -407.310316)
			(xy 418.447597 -407.274624) (xy 418.411902 -407.233433) (xy 418.382433 -407.187581) (xy 418.359789 -407.138001)
			(xy 418.344433 -407.085704) (xy 418.336675 -407.031753) (xy 416.899165 -407.031753) (xy 416.899165 -407.031755)
			(xy 416.891407 -407.085709) (xy 416.87605 -407.138011) (xy 416.853406 -407.187594) (xy 416.823935 -407.23345)
			(xy 416.788238 -407.274646) (xy 416.747042 -407.310341) (xy 416.701186 -407.33981) (xy 416.651602 -407.362454)
			(xy 416.5993 -407.37781) (xy 416.545345 -407.385566) (xy 416.51809 -407.386028) (xy 415.65449 -407.386028)
			(xy 415.627241 -407.385501) (xy 415.573297 -407.377744) (xy 415.521006 -407.362389) (xy 415.471433 -407.339748)
			(xy 415.425586 -407.310283) (xy 415.384399 -407.274594) (xy 415.348711 -407.233406) (xy 415.319247 -407.187558)
			(xy 415.296608 -407.137984) (xy 415.281254 -407.085693) (xy 415.273498 -407.031749) (xy 413.835965 -407.031749)
			(xy 413.835965 -407.031757) (xy 413.828206 -407.085715) (xy 413.812847 -407.138019) (xy 413.7902 -407.187606)
			(xy 413.760725 -407.233464) (xy 413.725024 -407.27466) (xy 413.683823 -407.310355) (xy 413.637962 -407.339824)
			(xy 413.588373 -407.362464) (xy 413.536066 -407.377817) (xy 413.482107 -407.385569) (xy 413.45485 -407.386028)
			(xy 412.59125 -407.386028) (xy 412.564003 -407.385498) (xy 412.510063 -407.377736) (xy 412.457777 -407.362378)
			(xy 412.408209 -407.339735) (xy 412.362367 -407.310269) (xy 412.321185 -407.274579) (xy 412.285501 -407.233393)
			(xy 412.256041 -407.187547) (xy 412.233405 -407.137976) (xy 412.218053 -407.085688) (xy 412.210298 -407.031748)
			(xy 410.772642 -407.031748) (xy 410.772642 -407.031752) (xy 410.764886 -407.085702) (xy 410.74953 -407.137999)
			(xy 410.726889 -407.187578) (xy 410.697422 -407.23343) (xy 410.661729 -407.274622) (xy 410.620538 -407.310316)
			(xy 410.574687 -407.339784) (xy 410.525108 -407.362427) (xy 410.472812 -407.377783) (xy 410.418862 -407.385541)
			(xy 410.39161 -407.386028) (xy 409.52801 -407.386028) (xy 409.500758 -407.385525) (xy 409.446809 -407.37777)
			(xy 409.394513 -407.362416) (xy 409.344934 -407.339775) (xy 409.299082 -407.310309) (xy 409.25789 -407.274617)
			(xy 409.222197 -407.233426) (xy 409.19273 -407.187575) (xy 409.170088 -407.137997) (xy 409.154732 -407.085701)
			(xy 409.146975 -407.031752) (xy 407.709465 -407.031752) (xy 407.709465 -407.031756) (xy 407.701707 -407.085712)
			(xy 407.686348 -407.138015) (xy 407.663703 -407.1876) (xy 407.63423 -407.233457) (xy 407.598531 -407.274653)
			(xy 407.557333 -407.310348) (xy 407.511474 -407.339817) (xy 407.461887 -407.362459) (xy 407.409583 -407.377813)
			(xy 407.355626 -407.385567) (xy 407.32837 -407.386028) (xy 406.46477 -407.386028) (xy 406.437522 -407.3855)
			(xy 406.38358 -407.37774) (xy 406.331292 -407.362383) (xy 406.281721 -407.339742) (xy 406.235877 -407.310276)
			(xy 406.194692 -407.274586) (xy 406.159006 -407.233399) (xy 406.129544 -407.187553) (xy 406.106906 -407.13798)
			(xy 406.091553 -407.085691) (xy 406.083798 -407.031748) (xy 404.646142 -407.031748) (xy 404.646142 -407.031751)
			(xy 404.638386 -407.085699) (xy 404.623032 -407.137994) (xy 404.600392 -407.187572) (xy 404.570927 -407.233424)
			(xy 404.535236 -407.274615) (xy 404.494048 -407.310309) (xy 404.448199 -407.339777) (xy 404.398622 -407.362421)
			(xy 404.346329 -407.37778) (xy 404.292381 -407.38554) (xy 404.26513 -407.386028) (xy 403.40153 -407.386028)
			(xy 403.374277 -407.385527) (xy 403.320326 -407.377774) (xy 403.268027 -407.362421) (xy 403.218446 -407.339781)
			(xy 403.172591 -407.310316) (xy 403.131397 -407.274624) (xy 403.095702 -407.233433) (xy 403.066233 -407.187581)
			(xy 403.043589 -407.138001) (xy 403.028233 -407.085704) (xy 403.020475 -407.031753) (xy 401.582965 -407.031753)
			(xy 401.582965 -407.031755) (xy 401.575207 -407.085709) (xy 401.55985 -407.138011) (xy 401.537206 -407.187594)
			(xy 401.507735 -407.23345) (xy 401.472038 -407.274646) (xy 401.430842 -407.310341) (xy 401.384986 -407.33981)
			(xy 401.335402 -407.362454) (xy 401.2831 -407.37781) (xy 401.229145 -407.385566) (xy 401.20189 -407.386028)
			(xy 400.33829 -407.386028) (xy 400.311041 -407.385501) (xy 400.257097 -407.377744) (xy 400.204806 -407.362389)
			(xy 400.155233 -407.339748) (xy 400.109386 -407.310283) (xy 400.068199 -407.274594) (xy 400.032511 -407.233406)
			(xy 400.003047 -407.187558) (xy 399.980408 -407.137984) (xy 399.965054 -407.085693) (xy 399.957298 -407.031749)
			(xy 398.519765 -407.031749) (xy 398.519765 -407.031757) (xy 398.512006 -407.085715) (xy 398.496647 -407.138019)
			(xy 398.474 -407.187606) (xy 398.444525 -407.233464) (xy 398.408824 -407.27466) (xy 398.367623 -407.310355)
			(xy 398.321762 -407.339824) (xy 398.272173 -407.362464) (xy 398.219866 -407.377817) (xy 398.165907 -407.385569)
			(xy 398.13865 -407.386028) (xy 397.27505 -407.386028) (xy 397.247803 -407.385498) (xy 397.193863 -407.377736)
			(xy 397.141577 -407.362378) (xy 397.092009 -407.339735) (xy 397.046167 -407.310269) (xy 397.004985 -407.274579)
			(xy 396.969301 -407.233393) (xy 396.939841 -407.187547) (xy 396.917205 -407.137976) (xy 396.901853 -407.085688)
			(xy 396.894098 -407.031748) (xy 395.456442 -407.031748) (xy 395.456442 -407.031752) (xy 395.448686 -407.085702)
			(xy 395.43333 -407.137999) (xy 395.410689 -407.187578) (xy 395.381222 -407.23343) (xy 395.345529 -407.274622)
			(xy 395.304338 -407.310316) (xy 395.258487 -407.339784) (xy 395.208908 -407.362427) (xy 395.156612 -407.377783)
			(xy 395.102662 -407.385541) (xy 395.07541 -407.386028) (xy 394.21181 -407.386028) (xy 394.184558 -407.385525)
			(xy 394.130609 -407.37777) (xy 394.078313 -407.362416) (xy 394.028734 -407.339775) (xy 393.982882 -407.310309)
			(xy 393.94169 -407.274617) (xy 393.905997 -407.233426) (xy 393.87653 -407.187575) (xy 393.853888 -407.137997)
			(xy 393.838532 -407.085701) (xy 393.830775 -407.031752) (xy 392.393265 -407.031752) (xy 392.393265 -407.031756)
			(xy 392.385507 -407.085712) (xy 392.370148 -407.138015) (xy 392.347503 -407.1876) (xy 392.31803 -407.233457)
			(xy 392.282331 -407.274653) (xy 392.241133 -407.310348) (xy 392.195274 -407.339817) (xy 392.145687 -407.362459)
			(xy 392.093383 -407.377813) (xy 392.039426 -407.385567) (xy 392.01217 -407.386028) (xy 391.14857 -407.386028)
			(xy 391.121322 -407.3855) (xy 391.06738 -407.37774) (xy 391.015092 -407.362383) (xy 390.965521 -407.339742)
			(xy 390.919677 -407.310276) (xy 390.878492 -407.274586) (xy 390.842806 -407.233399) (xy 390.813344 -407.187553)
			(xy 390.790706 -407.13798) (xy 390.775353 -407.085691) (xy 390.767598 -407.031748) (xy 389.329942 -407.031748)
			(xy 389.329942 -407.031751) (xy 389.322186 -407.085699) (xy 389.306832 -407.137994) (xy 389.284192 -407.187572)
			(xy 389.254727 -407.233424) (xy 389.219036 -407.274615) (xy 389.177848 -407.310309) (xy 389.131999 -407.339777)
			(xy 389.082422 -407.362421) (xy 389.030129 -407.37778) (xy 388.976181 -407.38554) (xy 388.94893 -407.386028)
			(xy 388.08533 -407.386028) (xy 388.058077 -407.385527) (xy 388.004126 -407.377774) (xy 387.951827 -407.362421)
			(xy 387.902246 -407.339781) (xy 387.856391 -407.310316) (xy 387.815197 -407.274624) (xy 387.779502 -407.233433)
			(xy 387.750033 -407.187581) (xy 387.727389 -407.138001) (xy 387.712033 -407.085704) (xy 387.704275 -407.031753)
			(xy 386.266765 -407.031753) (xy 386.266765 -407.031755) (xy 386.259007 -407.085709) (xy 386.24365 -407.138011)
			(xy 386.221006 -407.187594) (xy 386.191535 -407.23345) (xy 386.155838 -407.274646) (xy 386.114642 -407.310341)
			(xy 386.068786 -407.33981) (xy 386.019202 -407.362454) (xy 385.9669 -407.37781) (xy 385.912945 -407.385566)
			(xy 385.88569 -407.386028) (xy 385.02209 -407.386028) (xy 384.994841 -407.385501) (xy 384.940897 -407.377744)
			(xy 384.888606 -407.362389) (xy 384.839033 -407.339748) (xy 384.793186 -407.310283) (xy 384.751999 -407.274594)
			(xy 384.716311 -407.233406) (xy 384.686847 -407.187558) (xy 384.664208 -407.137984) (xy 384.648854 -407.085693)
			(xy 384.641098 -407.031749) (xy 383.203565 -407.031749) (xy 383.203565 -407.031757) (xy 383.195806 -407.085715)
			(xy 383.180447 -407.138019) (xy 383.1578 -407.187606) (xy 383.128325 -407.233464) (xy 383.092624 -407.27466)
			(xy 383.051423 -407.310355) (xy 383.005562 -407.339824) (xy 382.955973 -407.362464) (xy 382.903666 -407.377817)
			(xy 382.849707 -407.385569) (xy 382.82245 -407.386028) (xy 381.95885 -407.386028) (xy 381.931603 -407.385498)
			(xy 381.877663 -407.377736) (xy 381.825377 -407.362378) (xy 381.775809 -407.339735) (xy 381.729967 -407.310269)
			(xy 381.688785 -407.274579) (xy 381.653101 -407.233393) (xy 381.623641 -407.187547) (xy 381.601005 -407.137976)
			(xy 381.585653 -407.085688) (xy 381.577898 -407.031748) (xy 380.140242 -407.031748) (xy 380.140242 -407.031752)
			(xy 380.132486 -407.085702) (xy 380.11713 -407.137999) (xy 380.094489 -407.187578) (xy 380.065022 -407.23343)
			(xy 380.029329 -407.274622) (xy 379.988138 -407.310316) (xy 379.942287 -407.339784) (xy 379.892708 -407.362427)
			(xy 379.840412 -407.377783) (xy 379.786462 -407.385541) (xy 379.75921 -407.386028) (xy 378.89561 -407.386028)
			(xy 378.868358 -407.385525) (xy 378.814409 -407.37777) (xy 378.762113 -407.362416) (xy 378.712534 -407.339775)
			(xy 378.666682 -407.310309) (xy 378.62549 -407.274617) (xy 378.589797 -407.233426) (xy 378.56033 -407.187575)
			(xy 378.537688 -407.137997) (xy 378.522332 -407.085701) (xy 378.514575 -407.031752) (xy 377.077065 -407.031752)
			(xy 377.077065 -407.031756) (xy 377.069307 -407.085712) (xy 377.053948 -407.138015) (xy 377.031303 -407.1876)
			(xy 377.00183 -407.233457) (xy 376.966131 -407.274653) (xy 376.924933 -407.310348) (xy 376.879074 -407.339817)
			(xy 376.829487 -407.362459) (xy 376.777183 -407.377813) (xy 376.723226 -407.385567) (xy 376.69597 -407.386028)
			(xy 375.83237 -407.386028) (xy 375.805122 -407.3855) (xy 375.75118 -407.37774) (xy 375.698892 -407.362383)
			(xy 375.649321 -407.339742) (xy 375.603477 -407.310276) (xy 375.562292 -407.274586) (xy 375.526606 -407.233399)
			(xy 375.497144 -407.187553) (xy 375.474506 -407.13798) (xy 375.459153 -407.085691) (xy 375.451398 -407.031748)
			(xy 374.013742 -407.031748) (xy 374.013742 -407.031751) (xy 374.005986 -407.085699) (xy 373.990632 -407.137994)
			(xy 373.967992 -407.187572) (xy 373.938527 -407.233424) (xy 373.902836 -407.274615) (xy 373.861648 -407.310309)
			(xy 373.815799 -407.339777) (xy 373.766222 -407.362421) (xy 373.713929 -407.37778) (xy 373.659981 -407.38554)
			(xy 373.63273 -407.386028) (xy 372.76913 -407.386028) (xy 372.741877 -407.385527) (xy 372.687926 -407.377774)
			(xy 372.635627 -407.362421) (xy 372.586046 -407.339781) (xy 372.540191 -407.310316) (xy 372.498997 -407.274624)
			(xy 372.463302 -407.233433) (xy 372.433833 -407.187581) (xy 372.411189 -407.138001) (xy 372.395833 -407.085704)
			(xy 372.388075 -407.031753) (xy 352.519565 -407.031753) (xy 352.519565 -407.031755) (xy 352.511807 -407.08571)
			(xy 352.49645 -407.138011) (xy 352.473805 -407.187595) (xy 352.444335 -407.233451) (xy 352.408638 -407.274646)
			(xy 352.367441 -407.310342) (xy 352.321584 -407.339811) (xy 352.272 -407.362454) (xy 352.219698 -407.37781)
			(xy 352.165743 -407.385566) (xy 352.138488 -407.386028) (xy 351.274888 -407.386028) (xy 351.247639 -407.385501)
			(xy 351.193695 -407.377743) (xy 351.141405 -407.362388) (xy 351.091832 -407.339748) (xy 351.045985 -407.310282)
			(xy 351.004799 -407.274593) (xy 350.96911 -407.233405) (xy 350.939647 -407.187558) (xy 350.917008 -407.137984)
			(xy 350.901654 -407.085693) (xy 350.893898 -407.031749) (xy 349.456242 -407.031749) (xy 349.456242 -407.03175)
			(xy 349.448487 -407.085697) (xy 349.433133 -407.137991) (xy 349.410494 -407.187567) (xy 349.381031 -407.233418)
			(xy 349.345343 -407.274609) (xy 349.304156 -407.310302) (xy 349.258309 -407.339771) (xy 349.208736 -407.362416)
			(xy 349.156444 -407.377776) (xy 349.102498 -407.385539) (xy 349.075248 -407.386028) (xy 348.211648 -407.386028)
			(xy 348.184394 -407.385528) (xy 348.130441 -407.377777) (xy 348.07814 -407.362426) (xy 348.028557 -407.339787)
			(xy 347.9827 -407.310322) (xy 347.941504 -407.27463) (xy 347.905807 -407.233439) (xy 347.876336 -407.187586)
			(xy 347.853691 -407.138005) (xy 347.838333 -407.085706) (xy 347.830575 -407.031754) (xy 346.393042 -407.031754)
			(xy 346.385285 -407.085702) (xy 346.36993 -407.137999) (xy 346.347288 -407.187578) (xy 346.317821 -407.233431)
			(xy 346.282129 -407.274623) (xy 346.240937 -407.310316) (xy 346.195085 -407.339784) (xy 346.145507 -407.362427)
			(xy 346.09321 -407.377784) (xy 346.03926 -407.385542) (xy 346.012008 -407.386028) (xy 345.148408 -407.386028)
			(xy 345.121156 -407.385525) (xy 345.067207 -407.37777) (xy 345.014911 -407.362415) (xy 344.965333 -407.339774)
			(xy 344.919481 -407.310308) (xy 344.878289 -407.274616) (xy 344.842597 -407.233425) (xy 344.81313 -407.187574)
			(xy 344.790488 -407.137996) (xy 344.775132 -407.085701) (xy 344.767375 -407.031752) (xy 343.329865 -407.031752)
			(xy 343.329865 -407.031756) (xy 343.322107 -407.085712) (xy 343.306748 -407.138016) (xy 343.284102 -407.187601)
			(xy 343.25463 -407.233458) (xy 343.218931 -407.274653) (xy 343.177732 -407.310349) (xy 343.131872 -407.339818)
			(xy 343.082286 -407.36246) (xy 343.029981 -407.377814) (xy 342.976024 -407.385567) (xy 342.948768 -407.386028)
			(xy 342.085168 -407.386028) (xy 342.05792 -407.3855) (xy 342.003978 -407.37774) (xy 341.95169 -407.362383)
			(xy 341.90212 -407.339741) (xy 341.856276 -407.310275) (xy 341.815092 -407.274586) (xy 341.779405 -407.233399)
			(xy 341.749944 -407.187552) (xy 341.727306 -407.13798) (xy 341.711953 -407.08569) (xy 341.704198 -407.031748)
			(xy 340.266542 -407.031748) (xy 340.266542 -407.031751) (xy 340.258786 -407.0857) (xy 340.243432 -407.137995)
			(xy 340.220791 -407.187573) (xy 340.191326 -407.233424) (xy 340.155636 -407.274616) (xy 340.114447 -407.310309)
			(xy 340.068597 -407.339778) (xy 340.019021 -407.362422) (xy 339.966727 -407.37778) (xy 339.912779 -407.38554)
			(xy 339.885528 -407.386028) (xy 339.021928 -407.386028) (xy 338.994675 -407.385527) (xy 338.940724 -407.377773)
			(xy 338.888426 -407.36242) (xy 338.838845 -407.339781) (xy 338.79299 -407.310315) (xy 338.751797 -407.274623)
			(xy 338.716102 -407.233432) (xy 338.686633 -407.18758) (xy 338.663989 -407.138001) (xy 338.648633 -407.085703)
			(xy 338.640875 -407.031753) (xy 337.203365 -407.031753) (xy 337.203365 -407.031755) (xy 337.195607 -407.08571)
			(xy 337.18025 -407.138011) (xy 337.157605 -407.187595) (xy 337.128135 -407.233451) (xy 337.092438 -407.274646)
			(xy 337.051241 -407.310342) (xy 337.005384 -407.339811) (xy 336.9558 -407.362454) (xy 336.903498 -407.37781)
			(xy 336.849543 -407.385566) (xy 336.822288 -407.386028) (xy 335.958688 -407.386028) (xy 335.931439 -407.385501)
			(xy 335.877495 -407.377743) (xy 335.825205 -407.362388) (xy 335.775632 -407.339748) (xy 335.729785 -407.310282)
			(xy 335.688599 -407.274593) (xy 335.65291 -407.233405) (xy 335.623447 -407.187558) (xy 335.600808 -407.137984)
			(xy 335.585454 -407.085693) (xy 335.577698 -407.031749) (xy 334.140042 -407.031749) (xy 334.140042 -407.03175)
			(xy 334.132287 -407.085697) (xy 334.116933 -407.137991) (xy 334.094294 -407.187567) (xy 334.064831 -407.233418)
			(xy 334.029143 -407.274609) (xy 333.987956 -407.310302) (xy 333.942109 -407.339771) (xy 333.892536 -407.362416)
			(xy 333.840244 -407.377776) (xy 333.786298 -407.385539) (xy 333.759048 -407.386028) (xy 332.895448 -407.386028)
			(xy 332.868194 -407.385528) (xy 332.814241 -407.377777) (xy 332.76194 -407.362426) (xy 332.712357 -407.339787)
			(xy 332.6665 -407.310322) (xy 332.625304 -407.27463) (xy 332.589607 -407.233439) (xy 332.560136 -407.187586)
			(xy 332.537491 -407.138005) (xy 332.522133 -407.085706) (xy 332.514375 -407.031754) (xy 331.076842 -407.031754)
			(xy 331.069085 -407.085702) (xy 331.05373 -407.137999) (xy 331.031088 -407.187578) (xy 331.001621 -407.233431)
			(xy 330.965929 -407.274623) (xy 330.924737 -407.310316) (xy 330.878885 -407.339784) (xy 330.829307 -407.362427)
			(xy 330.77701 -407.377784) (xy 330.72306 -407.385542) (xy 330.695808 -407.386028) (xy 329.832208 -407.386028)
			(xy 329.804956 -407.385525) (xy 329.751007 -407.37777) (xy 329.698711 -407.362415) (xy 329.649133 -407.339774)
			(xy 329.603281 -407.310308) (xy 329.562089 -407.274616) (xy 329.526397 -407.233425) (xy 329.49693 -407.187574)
			(xy 329.474288 -407.137996) (xy 329.458932 -407.085701) (xy 329.451175 -407.031752) (xy 328.013665 -407.031752)
			(xy 328.013665 -407.031756) (xy 328.005907 -407.085712) (xy 327.990548 -407.138016) (xy 327.967902 -407.187601)
			(xy 327.93843 -407.233458) (xy 327.902731 -407.274653) (xy 327.861532 -407.310349) (xy 327.815672 -407.339818)
			(xy 327.766086 -407.36246) (xy 327.713781 -407.377814) (xy 327.659824 -407.385567) (xy 327.632568 -407.386028)
			(xy 326.768968 -407.386028) (xy 326.74172 -407.3855) (xy 326.687778 -407.37774) (xy 326.63549 -407.362383)
			(xy 326.58592 -407.339741) (xy 326.540076 -407.310275) (xy 326.498892 -407.274586) (xy 326.463205 -407.233399)
			(xy 326.433744 -407.187552) (xy 326.411106 -407.13798) (xy 326.395753 -407.08569) (xy 326.387998 -407.031748)
			(xy 324.950342 -407.031748) (xy 324.950342 -407.031751) (xy 324.942586 -407.0857) (xy 324.927232 -407.137995)
			(xy 324.904591 -407.187573) (xy 324.875126 -407.233424) (xy 324.839436 -407.274616) (xy 324.798247 -407.310309)
			(xy 324.752397 -407.339778) (xy 324.702821 -407.362422) (xy 324.650527 -407.37778) (xy 324.596579 -407.38554)
			(xy 324.569328 -407.386028) (xy 323.705728 -407.386028) (xy 323.678475 -407.385527) (xy 323.624524 -407.377773)
			(xy 323.572226 -407.36242) (xy 323.522645 -407.339781) (xy 323.47679 -407.310315) (xy 323.435597 -407.274623)
			(xy 323.399902 -407.233432) (xy 323.370433 -407.18758) (xy 323.347789 -407.138001) (xy 323.332433 -407.085703)
			(xy 323.324675 -407.031753) (xy 321.887165 -407.031753) (xy 321.887165 -407.031755) (xy 321.879407 -407.08571)
			(xy 321.86405 -407.138011) (xy 321.841405 -407.187595) (xy 321.811935 -407.233451) (xy 321.776238 -407.274646)
			(xy 321.735041 -407.310342) (xy 321.689184 -407.339811) (xy 321.6396 -407.362454) (xy 321.587298 -407.37781)
			(xy 321.533343 -407.385566) (xy 321.506088 -407.386028) (xy 320.642488 -407.386028) (xy 320.615239 -407.385501)
			(xy 320.561295 -407.377743) (xy 320.509005 -407.362388) (xy 320.459432 -407.339748) (xy 320.413585 -407.310282)
			(xy 320.372399 -407.274593) (xy 320.33671 -407.233405) (xy 320.307247 -407.187558) (xy 320.284608 -407.137984)
			(xy 320.269254 -407.085693) (xy 320.261498 -407.031749) (xy 318.823842 -407.031749) (xy 318.823842 -407.03175)
			(xy 318.816087 -407.085697) (xy 318.800733 -407.137991) (xy 318.778094 -407.187567) (xy 318.748631 -407.233418)
			(xy 318.712943 -407.274609) (xy 318.671756 -407.310302) (xy 318.625909 -407.339771) (xy 318.576336 -407.362416)
			(xy 318.524044 -407.377776) (xy 318.470098 -407.385539) (xy 318.442848 -407.386028) (xy 317.579248 -407.386028)
			(xy 317.551994 -407.385528) (xy 317.498041 -407.377777) (xy 317.44574 -407.362426) (xy 317.396157 -407.339787)
			(xy 317.3503 -407.310322) (xy 317.309104 -407.27463) (xy 317.273407 -407.233439) (xy 317.243936 -407.187586)
			(xy 317.221291 -407.138005) (xy 317.205933 -407.085706) (xy 317.198175 -407.031754) (xy 315.760642 -407.031754)
			(xy 315.752885 -407.085702) (xy 315.73753 -407.137999) (xy 315.714888 -407.187578) (xy 315.685421 -407.233431)
			(xy 315.649729 -407.274623) (xy 315.608537 -407.310316) (xy 315.562685 -407.339784) (xy 315.513107 -407.362427)
			(xy 315.46081 -407.377784) (xy 315.40686 -407.385542) (xy 315.379608 -407.386028) (xy 314.516008 -407.386028)
			(xy 314.488756 -407.385525) (xy 314.434807 -407.37777) (xy 314.382511 -407.362415) (xy 314.332933 -407.339774)
			(xy 314.287081 -407.310308) (xy 314.245889 -407.274616) (xy 314.210197 -407.233425) (xy 314.18073 -407.187574)
			(xy 314.158088 -407.137996) (xy 314.142732 -407.085701) (xy 314.134975 -407.031752) (xy 312.697465 -407.031752)
			(xy 312.697465 -407.031756) (xy 312.689707 -407.085712) (xy 312.674348 -407.138016) (xy 312.651702 -407.187601)
			(xy 312.62223 -407.233458) (xy 312.586531 -407.274653) (xy 312.545332 -407.310349) (xy 312.499472 -407.339818)
			(xy 312.449886 -407.36246) (xy 312.397581 -407.377814) (xy 312.343624 -407.385567) (xy 312.316368 -407.386028)
			(xy 311.452768 -407.386028) (xy 311.42552 -407.3855) (xy 311.371578 -407.37774) (xy 311.31929 -407.362383)
			(xy 311.26972 -407.339741) (xy 311.223876 -407.310275) (xy 311.182692 -407.274586) (xy 311.147005 -407.233399)
			(xy 311.117544 -407.187552) (xy 311.094906 -407.13798) (xy 311.079553 -407.08569) (xy 311.071798 -407.031748)
			(xy 309.634142 -407.031748) (xy 309.634142 -407.031751) (xy 309.626386 -407.0857) (xy 309.611032 -407.137995)
			(xy 309.588391 -407.187573) (xy 309.558926 -407.233424) (xy 309.523236 -407.274616) (xy 309.482047 -407.310309)
			(xy 309.436197 -407.339778) (xy 309.386621 -407.362422) (xy 309.334327 -407.37778) (xy 309.280379 -407.38554)
			(xy 309.253128 -407.386028) (xy 308.389528 -407.386028) (xy 308.362275 -407.385527) (xy 308.308324 -407.377773)
			(xy 308.256026 -407.36242) (xy 308.206445 -407.339781) (xy 308.16059 -407.310315) (xy 308.119397 -407.274623)
			(xy 308.083702 -407.233432) (xy 308.054233 -407.18758) (xy 308.031589 -407.138001) (xy 308.016233 -407.085703)
			(xy 308.008475 -407.031753) (xy 306.570965 -407.031753) (xy 306.570965 -407.031755) (xy 306.563207 -407.08571)
			(xy 306.54785 -407.138011) (xy 306.525205 -407.187595) (xy 306.495735 -407.233451) (xy 306.460038 -407.274646)
			(xy 306.418841 -407.310342) (xy 306.372984 -407.339811) (xy 306.3234 -407.362454) (xy 306.271098 -407.37781)
			(xy 306.217143 -407.385566) (xy 306.189888 -407.386028) (xy 305.326288 -407.386028) (xy 305.299039 -407.385501)
			(xy 305.245095 -407.377743) (xy 305.192805 -407.362388) (xy 305.143232 -407.339748) (xy 305.097385 -407.310282)
			(xy 305.056199 -407.274593) (xy 305.02051 -407.233405) (xy 304.991047 -407.187558) (xy 304.968408 -407.137984)
			(xy 304.953054 -407.085693) (xy 304.945298 -407.031749) (xy 168.694465 -407.031749) (xy 168.694465 -407.031756)
			(xy 168.686706 -407.085714) (xy 168.671347 -407.138019) (xy 168.6487 -407.187604) (xy 168.619226 -407.233462)
			(xy 168.583526 -407.274658) (xy 168.542325 -407.310354) (xy 168.496464 -407.339822) (xy 168.446875 -407.362463)
			(xy 168.394569 -407.377816) (xy 168.34061 -407.385568) (xy 168.313354 -407.386028) (xy 167.449754 -407.386028)
			(xy 167.422506 -407.385499) (xy 167.368567 -407.377737) (xy 167.31628 -407.362379) (xy 167.266711 -407.339736)
			(xy 167.220869 -407.31027) (xy 167.179687 -407.274581) (xy 167.144002 -407.233394) (xy 167.114542 -407.187548)
			(xy 167.091905 -407.137977) (xy 167.076553 -407.085688) (xy 167.068798 -407.031748) (xy 165.631142 -407.031748)
			(xy 165.631142 -407.031752) (xy 165.623386 -407.085701) (xy 165.60803 -407.137998) (xy 165.585389 -407.187577)
			(xy 165.555923 -407.233429) (xy 165.520231 -407.274621) (xy 165.47904 -407.310314) (xy 165.433189 -407.339782)
			(xy 165.383611 -407.362426) (xy 165.331315 -407.377783) (xy 165.277366 -407.385541) (xy 165.250114 -407.386028)
			(xy 164.386514 -407.386028) (xy 164.359262 -407.385526) (xy 164.305312 -407.377771) (xy 164.253016 -407.362417)
			(xy 164.203436 -407.339776) (xy 164.157584 -407.31031) (xy 164.116392 -407.274618) (xy 164.080698 -407.233427)
			(xy 164.051231 -407.187576) (xy 164.028588 -407.137998) (xy 164.013232 -407.085701) (xy 164.005475 -407.031752)
			(xy 162.567965 -407.031752) (xy 162.567965 -407.031755) (xy 162.560207 -407.085712) (xy 162.544849 -407.138014)
			(xy 162.522203 -407.187599) (xy 162.492731 -407.233456) (xy 162.457033 -407.274651) (xy 162.415835 -407.310347)
			(xy 162.369976 -407.339816) (xy 162.32039 -407.362458) (xy 162.268086 -407.377813) (xy 162.21413 -407.385567)
			(xy 162.186874 -407.386028) (xy 161.323274 -407.386028) (xy 161.296025 -407.3855) (xy 161.242083 -407.377741)
			(xy 161.189795 -407.362384) (xy 161.140223 -407.339743) (xy 161.094379 -407.310278) (xy 161.053194 -407.274588)
			(xy 161.017507 -407.233401) (xy 160.988045 -407.187554) (xy 160.965407 -407.137981) (xy 160.950054 -407.085691)
			(xy 160.942298 -407.031749) (xy 159.504642 -407.031749) (xy 159.504642 -407.031751) (xy 159.496886 -407.085699)
			(xy 159.481532 -407.137993) (xy 159.458892 -407.187571) (xy 159.429428 -407.233422) (xy 159.393738 -407.274614)
			(xy 159.352549 -407.310307) (xy 159.306701 -407.339776) (xy 159.257125 -407.36242) (xy 159.204832 -407.377779)
			(xy 159.150885 -407.38554) (xy 159.123634 -407.386028) (xy 158.260034 -407.386028) (xy 158.232781 -407.385527)
			(xy 158.178829 -407.377774) (xy 158.12653 -407.362422) (xy 158.076948 -407.339783) (xy 158.031093 -407.310317)
			(xy 157.989899 -407.274625) (xy 157.954203 -407.233434) (xy 157.924734 -407.187582) (xy 157.90209 -407.138002)
			(xy 157.886733 -407.085704) (xy 157.878975 -407.031753) (xy 156.441465 -407.031753) (xy 156.441465 -407.031755)
			(xy 156.433708 -407.085709) (xy 156.41835 -407.13801) (xy 156.395706 -407.187593) (xy 156.366236 -407.233449)
			(xy 156.33054 -407.274644) (xy 156.289344 -407.31034) (xy 156.243488 -407.339809) (xy 156.193904 -407.362452)
			(xy 156.141603 -407.377809) (xy 156.087649 -407.385566) (xy 156.060394 -407.386028) (xy 155.196794 -407.386028)
			(xy 155.169544 -407.385501) (xy 155.1156 -407.377745) (xy 155.063309 -407.36239) (xy 155.013735 -407.339749)
			(xy 154.967888 -407.310285) (xy 154.926701 -407.274595) (xy 154.891012 -407.233407) (xy 154.861548 -407.187559)
			(xy 154.838908 -407.137985) (xy 154.823554 -407.085694) (xy 154.815798 -407.03175) (xy 153.378265 -407.03175)
			(xy 153.378265 -407.031756) (xy 153.370506 -407.085714) (xy 153.355147 -407.138019) (xy 153.3325 -407.187604)
			(xy 153.303026 -407.233462) (xy 153.267326 -407.274658) (xy 153.226125 -407.310354) (xy 153.180264 -407.339822)
			(xy 153.130675 -407.362463) (xy 153.078369 -407.377816) (xy 153.02441 -407.385568) (xy 152.997154 -407.386028)
			(xy 152.133554 -407.386028) (xy 152.106306 -407.385499) (xy 152.052367 -407.377737) (xy 152.00008 -407.362379)
			(xy 151.950511 -407.339736) (xy 151.904669 -407.31027) (xy 151.863487 -407.274581) (xy 151.827802 -407.233394)
			(xy 151.798342 -407.187548) (xy 151.775705 -407.137977) (xy 151.760353 -407.085688) (xy 151.752598 -407.031748)
			(xy 150.314942 -407.031748) (xy 150.314942 -407.031752) (xy 150.307186 -407.085701) (xy 150.29183 -407.137998)
			(xy 150.269189 -407.187577) (xy 150.239723 -407.233429) (xy 150.204031 -407.274621) (xy 150.16284 -407.310314)
			(xy 150.116989 -407.339782) (xy 150.067411 -407.362426) (xy 150.015115 -407.377783) (xy 149.961166 -407.385541)
			(xy 149.933914 -407.386028) (xy 149.070314 -407.386028) (xy 149.043062 -407.385526) (xy 148.989112 -407.377771)
			(xy 148.936816 -407.362417) (xy 148.887236 -407.339776) (xy 148.841384 -407.31031) (xy 148.800192 -407.274618)
			(xy 148.764498 -407.233427) (xy 148.735031 -407.187576) (xy 148.712388 -407.137998) (xy 148.697032 -407.085701)
			(xy 148.689275 -407.031752) (xy 147.251765 -407.031752) (xy 147.251765 -407.031755) (xy 147.244007 -407.085712)
			(xy 147.228649 -407.138014) (xy 147.206003 -407.187599) (xy 147.176531 -407.233456) (xy 147.140833 -407.274651)
			(xy 147.099635 -407.310347) (xy 147.053776 -407.339816) (xy 147.00419 -407.362458) (xy 146.951886 -407.377813)
			(xy 146.89793 -407.385567) (xy 146.870674 -407.386028) (xy 146.007074 -407.386028) (xy 145.979825 -407.3855)
			(xy 145.925883 -407.377741) (xy 145.873595 -407.362384) (xy 145.824023 -407.339743) (xy 145.778179 -407.310278)
			(xy 145.736994 -407.274588) (xy 145.701307 -407.233401) (xy 145.671845 -407.187554) (xy 145.649207 -407.137981)
			(xy 145.633854 -407.085691) (xy 145.626098 -407.031749) (xy 144.188442 -407.031749) (xy 144.188442 -407.031751)
			(xy 144.180686 -407.085699) (xy 144.165332 -407.137993) (xy 144.142692 -407.187571) (xy 144.113228 -407.233422)
			(xy 144.077538 -407.274614) (xy 144.036349 -407.310307) (xy 143.990501 -407.339776) (xy 143.940925 -407.36242)
			(xy 143.888632 -407.377779) (xy 143.834685 -407.38554) (xy 143.807434 -407.386028) (xy 142.943834 -407.386028)
			(xy 142.916581 -407.385527) (xy 142.862629 -407.377774) (xy 142.81033 -407.362422) (xy 142.760748 -407.339783)
			(xy 142.714893 -407.310317) (xy 142.673699 -407.274625) (xy 142.638003 -407.233434) (xy 142.608534 -407.187582)
			(xy 142.58589 -407.138002) (xy 142.570533 -407.085704) (xy 142.562775 -407.031753) (xy 141.125265 -407.031753)
			(xy 141.125265 -407.031755) (xy 141.117508 -407.085709) (xy 141.10215 -407.13801) (xy 141.079506 -407.187593)
			(xy 141.050036 -407.233449) (xy 141.01434 -407.274644) (xy 140.973144 -407.31034) (xy 140.927288 -407.339809)
			(xy 140.877704 -407.362452) (xy 140.825403 -407.377809) (xy 140.771449 -407.385566) (xy 140.744194 -407.386028)
			(xy 139.880594 -407.386028) (xy 139.853344 -407.385501) (xy 139.7994 -407.377745) (xy 139.747109 -407.36239)
			(xy 139.697535 -407.339749) (xy 139.651688 -407.310285) (xy 139.610501 -407.274595) (xy 139.574812 -407.233407)
			(xy 139.545348 -407.187559) (xy 139.522708 -407.137985) (xy 139.507354 -407.085694) (xy 139.499598 -407.03175)
			(xy 138.062065 -407.03175) (xy 138.062065 -407.031756) (xy 138.054306 -407.085714) (xy 138.038947 -407.138019)
			(xy 138.0163 -407.187604) (xy 137.986826 -407.233462) (xy 137.951126 -407.274658) (xy 137.909925 -407.310354)
			(xy 137.864064 -407.339822) (xy 137.814475 -407.362463) (xy 137.762169 -407.377816) (xy 137.70821 -407.385568)
			(xy 137.680954 -407.386028) (xy 136.817354 -407.386028) (xy 136.790106 -407.385499) (xy 136.736167 -407.377737)
			(xy 136.68388 -407.362379) (xy 136.634311 -407.339736) (xy 136.588469 -407.31027) (xy 136.547287 -407.274581)
			(xy 136.511602 -407.233394) (xy 136.482142 -407.187548) (xy 136.459505 -407.137977) (xy 136.444153 -407.085688)
			(xy 136.436398 -407.031748) (xy 134.998742 -407.031748) (xy 134.998742 -407.031752) (xy 134.990986 -407.085701)
			(xy 134.97563 -407.137998) (xy 134.952989 -407.187577) (xy 134.923523 -407.233429) (xy 134.887831 -407.274621)
			(xy 134.84664 -407.310314) (xy 134.800789 -407.339782) (xy 134.751211 -407.362426) (xy 134.698915 -407.377783)
			(xy 134.644966 -407.385541) (xy 134.617714 -407.386028) (xy 133.754114 -407.386028) (xy 133.726862 -407.385526)
			(xy 133.672912 -407.377771) (xy 133.620616 -407.362417) (xy 133.571036 -407.339776) (xy 133.525184 -407.31031)
			(xy 133.483992 -407.274618) (xy 133.448298 -407.233427) (xy 133.418831 -407.187576) (xy 133.396188 -407.137998)
			(xy 133.380832 -407.085701) (xy 133.373075 -407.031752) (xy 131.935565 -407.031752) (xy 131.935565 -407.031755)
			(xy 131.927807 -407.085712) (xy 131.912449 -407.138014) (xy 131.889803 -407.187599) (xy 131.860331 -407.233456)
			(xy 131.824633 -407.274651) (xy 131.783435 -407.310347) (xy 131.737576 -407.339816) (xy 131.68799 -407.362458)
			(xy 131.635686 -407.377813) (xy 131.58173 -407.385567) (xy 131.554474 -407.386028) (xy 130.690874 -407.386028)
			(xy 130.663625 -407.3855) (xy 130.609683 -407.377741) (xy 130.557395 -407.362384) (xy 130.507823 -407.339743)
			(xy 130.461979 -407.310278) (xy 130.420794 -407.274588) (xy 130.385107 -407.233401) (xy 130.355645 -407.187554)
			(xy 130.333007 -407.137981) (xy 130.317654 -407.085691) (xy 130.309898 -407.031749) (xy 128.872242 -407.031749)
			(xy 128.872242 -407.031751) (xy 128.864486 -407.085699) (xy 128.849132 -407.137993) (xy 128.826492 -407.187571)
			(xy 128.797028 -407.233422) (xy 128.761338 -407.274614) (xy 128.720149 -407.310307) (xy 128.674301 -407.339776)
			(xy 128.624725 -407.36242) (xy 128.572432 -407.377779) (xy 128.518485 -407.38554) (xy 128.491234 -407.386028)
			(xy 127.627634 -407.386028) (xy 127.600381 -407.385527) (xy 127.546429 -407.377774) (xy 127.49413 -407.362422)
			(xy 127.444548 -407.339783) (xy 127.398693 -407.310317) (xy 127.357499 -407.274625) (xy 127.321803 -407.233434)
			(xy 127.292334 -407.187582) (xy 127.26969 -407.138002) (xy 127.254333 -407.085704) (xy 127.246575 -407.031753)
			(xy 125.809065 -407.031753) (xy 125.809065 -407.031755) (xy 125.801308 -407.085709) (xy 125.78595 -407.13801)
			(xy 125.763306 -407.187593) (xy 125.733836 -407.233449) (xy 125.69814 -407.274644) (xy 125.656944 -407.31034)
			(xy 125.611088 -407.339809) (xy 125.561504 -407.362452) (xy 125.509203 -407.377809) (xy 125.455249 -407.385566)
			(xy 125.427994 -407.386028) (xy 124.564394 -407.386028) (xy 124.537144 -407.385501) (xy 124.4832 -407.377745)
			(xy 124.430909 -407.36239) (xy 124.381335 -407.339749) (xy 124.335488 -407.310285) (xy 124.294301 -407.274595)
			(xy 124.258612 -407.233407) (xy 124.229148 -407.187559) (xy 124.206508 -407.137985) (xy 124.191154 -407.085694)
			(xy 124.183398 -407.03175) (xy 122.745865 -407.03175) (xy 122.745865 -407.031756) (xy 122.738106 -407.085714)
			(xy 122.722747 -407.138019) (xy 122.7001 -407.187604) (xy 122.670626 -407.233462) (xy 122.634926 -407.274658)
			(xy 122.593725 -407.310354) (xy 122.547864 -407.339822) (xy 122.498275 -407.362463) (xy 122.445969 -407.377816)
			(xy 122.39201 -407.385568) (xy 122.364754 -407.386028) (xy 121.501154 -407.386028) (xy 121.473906 -407.385499)
			(xy 121.419967 -407.377737) (xy 121.36768 -407.362379) (xy 121.318111 -407.339736) (xy 121.272269 -407.31027)
			(xy 121.231087 -407.274581) (xy 121.195402 -407.233394) (xy 121.165942 -407.187548) (xy 121.143305 -407.137977)
			(xy 121.127953 -407.085688) (xy 121.120198 -407.031748) (xy 107.861153 -407.031748) (xy 107.86873 -407.084449)
			(xy 107.86873 -407.138951) (xy 107.860974 -407.192898) (xy 107.84562 -407.245192) (xy 107.822979 -407.294769)
			(xy 107.793514 -407.34062) (xy 107.757824 -407.38181) (xy 107.716636 -407.417502) (xy 107.670787 -407.44697)
			(xy 107.621211 -407.469613) (xy 107.568918 -407.48497) (xy 107.514971 -407.492729) (xy 107.48772 -407.493216)
			(xy 106.62412 -407.493216) (xy 106.596867 -407.492738) (xy 106.542915 -407.484984) (xy 106.490616 -407.46963)
			(xy 106.441034 -407.446989) (xy 106.395179 -407.417522) (xy 106.353985 -407.381829) (xy 106.31829 -407.340637)
			(xy 106.288821 -407.294783) (xy 106.266177 -407.245203) (xy 106.250821 -407.192905) (xy 106.243063 -407.138953)
			(xy 96.495694 -407.138953) (xy 96.473493 -407.18757) (xy 96.444028 -407.233421) (xy 96.408339 -407.274612)
			(xy 96.367151 -407.310306) (xy 96.321303 -407.339775) (xy 96.271728 -407.362419) (xy 96.219435 -407.377778)
			(xy 96.165489 -407.38554) (xy 96.138238 -407.386028) (xy 95.274638 -407.386028) (xy 95.247385 -407.385527)
			(xy 95.193433 -407.377775) (xy 95.141133 -407.362423) (xy 95.091551 -407.339784) (xy 95.045695 -407.310319)
			(xy 95.0045 -407.274627) (xy 94.968804 -407.233435) (xy 94.939334 -407.187583) (xy 94.91669 -407.138003)
			(xy 94.901333 -407.085705) (xy 94.893575 -407.031753) (xy 93.456065 -407.031753) (xy 93.456065 -407.031754)
			(xy 93.448308 -407.085708) (xy 93.432951 -407.138009) (xy 93.410307 -407.187592) (xy 93.380837 -407.233448)
			(xy 93.345141 -407.274643) (xy 93.303946 -407.310338) (xy 93.25809 -407.339808) (xy 93.208507 -407.362451)
			(xy 93.156206 -407.377808) (xy 93.102252 -407.385565) (xy 93.074998 -407.386028) (xy 92.211398 -407.386028)
			(xy 92.184148 -407.385502) (xy 92.130204 -407.377745) (xy 92.077912 -407.362391) (xy 92.028338 -407.339751)
			(xy 91.98249 -407.310286) (xy 91.941302 -407.274596) (xy 91.905613 -407.233408) (xy 91.876148 -407.187561)
			(xy 91.853508 -407.137986) (xy 91.838154 -407.085694) (xy 91.830398 -407.03175) (xy 90.392865 -407.03175)
			(xy 90.392865 -407.031756) (xy 90.385107 -407.085714) (xy 90.369748 -407.138018) (xy 90.347101 -407.187603)
			(xy 90.317627 -407.233461) (xy 90.281927 -407.274657) (xy 90.240727 -407.310352) (xy 90.194866 -407.339821)
			(xy 90.145278 -407.362462) (xy 90.092973 -407.377815) (xy 90.039014 -407.385568) (xy 90.011758 -407.386028)
			(xy 89.148158 -407.386028) (xy 89.12091 -407.385499) (xy 89.06697 -407.377738) (xy 89.014683 -407.36238)
			(xy 88.965114 -407.339738) (xy 88.919271 -407.310272) (xy 88.878088 -407.274582) (xy 88.842403 -407.233395)
			(xy 88.812942 -407.187549) (xy 88.790305 -407.137978) (xy 88.774953 -407.085689) (xy 88.767198 -407.031748)
			(xy 87.329542 -407.031748) (xy 87.329542 -407.031752) (xy 87.321786 -407.085701) (xy 87.306431 -407.137997)
			(xy 87.28379 -407.187576) (xy 87.254324 -407.233427) (xy 87.218632 -407.274619) (xy 87.177442 -407.310313)
			(xy 87.131591 -407.339781) (xy 87.082014 -407.362424) (xy 87.029718 -407.377782) (xy 86.97577 -407.385541)
			(xy 86.948518 -407.386028) (xy 86.084918 -407.386028) (xy 86.057666 -407.385526) (xy 86.003716 -407.377771)
			(xy 85.951418 -407.362418) (xy 85.901839 -407.339778) (xy 85.855986 -407.310312) (xy 85.814793 -407.27462)
			(xy 85.779099 -407.233429) (xy 85.749631 -407.187577) (xy 85.726989 -407.137998) (xy 85.711632 -407.085702)
			(xy 85.703875 -407.031752) (xy 84.266365 -407.031752) (xy 84.266365 -407.031755) (xy 84.258607 -407.085711)
			(xy 84.243249 -407.138013) (xy 84.220604 -407.187598) (xy 84.191132 -407.233454) (xy 84.155434 -407.27465)
			(xy 84.114237 -407.310345) (xy 84.068378 -407.339814) (xy 84.018793 -407.362457) (xy 83.96649 -407.377812)
			(xy 83.912533 -407.385567) (xy 83.885278 -407.386028) (xy 83.021678 -407.386028) (xy 82.994429 -407.3855)
			(xy 82.940487 -407.377742) (xy 82.888197 -407.362385) (xy 82.838626 -407.339744) (xy 82.79278 -407.310279)
			(xy 82.751595 -407.274589) (xy 82.715908 -407.233402) (xy 82.686445 -407.187555) (xy 82.663807 -407.137982)
			(xy 82.648454 -407.085692) (xy 82.640698 -407.031749) (xy 81.203042 -407.031749) (xy 81.203042 -407.031751)
			(xy 81.195286 -407.085698) (xy 81.179932 -407.137993) (xy 81.157293 -407.18757) (xy 81.127828 -407.233421)
			(xy 81.092139 -407.274612) (xy 81.050951 -407.310306) (xy 81.005103 -407.339775) (xy 80.955528 -407.362419)
			(xy 80.903235 -407.377778) (xy 80.849289 -407.38554) (xy 80.822038 -407.386028) (xy 79.958438 -407.386028)
			(xy 79.931185 -407.385527) (xy 79.877233 -407.377775) (xy 79.824933 -407.362423) (xy 79.775351 -407.339784)
			(xy 79.729495 -407.310319) (xy 79.6883 -407.274627) (xy 79.652604 -407.233435) (xy 79.623134 -407.187583)
			(xy 79.60049 -407.138003) (xy 79.585133 -407.085705) (xy 79.577375 -407.031753) (xy 78.139865 -407.031753)
			(xy 78.139865 -407.031754) (xy 78.132108 -407.085708) (xy 78.116751 -407.138009) (xy 78.094107 -407.187592)
			(xy 78.064637 -407.233448) (xy 78.028941 -407.274643) (xy 77.987746 -407.310338) (xy 77.94189 -407.339808)
			(xy 77.892307 -407.362451) (xy 77.840006 -407.377808) (xy 77.786052 -407.385565) (xy 77.758798 -407.386028)
			(xy 76.895198 -407.386028) (xy 76.867948 -407.385502) (xy 76.814004 -407.377745) (xy 76.761712 -407.362391)
			(xy 76.712138 -407.339751) (xy 76.66629 -407.310286) (xy 76.625102 -407.274596) (xy 76.589413 -407.233408)
			(xy 76.559948 -407.187561) (xy 76.537308 -407.137986) (xy 76.521954 -407.085694) (xy 76.514198 -407.03175)
			(xy 75.076665 -407.03175) (xy 75.076665 -407.031756) (xy 75.068907 -407.085714) (xy 75.053548 -407.138018)
			(xy 75.030901 -407.187603) (xy 75.001427 -407.233461) (xy 74.965727 -407.274657) (xy 74.924527 -407.310352)
			(xy 74.878666 -407.339821) (xy 74.829078 -407.362462) (xy 74.776773 -407.377815) (xy 74.722814 -407.385568)
			(xy 74.695558 -407.386028) (xy 73.831958 -407.386028) (xy 73.80471 -407.385499) (xy 73.75077 -407.377738)
			(xy 73.698483 -407.36238) (xy 73.648914 -407.339738) (xy 73.603071 -407.310272) (xy 73.561888 -407.274582)
			(xy 73.526203 -407.233395) (xy 73.496742 -407.187549) (xy 73.474105 -407.137978) (xy 73.458753 -407.085689)
			(xy 73.450998 -407.031748) (xy 72.013342 -407.031748) (xy 72.013342 -407.031752) (xy 72.005586 -407.085701)
			(xy 71.990231 -407.137997) (xy 71.96759 -407.187576) (xy 71.938124 -407.233427) (xy 71.902432 -407.274619)
			(xy 71.861242 -407.310313) (xy 71.815391 -407.339781) (xy 71.765814 -407.362424) (xy 71.713518 -407.377782)
			(xy 71.65957 -407.385541) (xy 71.632318 -407.386028) (xy 70.768718 -407.386028) (xy 70.741466 -407.385526)
			(xy 70.687516 -407.377771) (xy 70.635218 -407.362418) (xy 70.585639 -407.339778) (xy 70.539786 -407.310312)
			(xy 70.498593 -407.27462) (xy 70.462899 -407.233429) (xy 70.433431 -407.187577) (xy 70.410789 -407.137998)
			(xy 70.395432 -407.085702) (xy 70.387675 -407.031752) (xy 68.950165 -407.031752) (xy 68.950165 -407.031755)
			(xy 68.942407 -407.085711) (xy 68.927049 -407.138013) (xy 68.904404 -407.187598) (xy 68.874932 -407.233454)
			(xy 68.839234 -407.27465) (xy 68.798037 -407.310345) (xy 68.752178 -407.339814) (xy 68.702593 -407.362457)
			(xy 68.65029 -407.377812) (xy 68.596333 -407.385567) (xy 68.569078 -407.386028) (xy 67.705478 -407.386028)
			(xy 67.678229 -407.3855) (xy 67.624287 -407.377742) (xy 67.571997 -407.362385) (xy 67.522426 -407.339744)
			(xy 67.47658 -407.310279) (xy 67.435395 -407.274589) (xy 67.399708 -407.233402) (xy 67.370245 -407.187555)
			(xy 67.347607 -407.137982) (xy 67.332254 -407.085692) (xy 67.324498 -407.031749) (xy 65.886842 -407.031749)
			(xy 65.886842 -407.031751) (xy 65.879086 -407.085698) (xy 65.863732 -407.137993) (xy 65.841093 -407.18757)
			(xy 65.811628 -407.233421) (xy 65.775939 -407.274612) (xy 65.734751 -407.310306) (xy 65.688903 -407.339775)
			(xy 65.639328 -407.362419) (xy 65.587035 -407.377778) (xy 65.533089 -407.38554) (xy 65.505838 -407.386028)
			(xy 64.642238 -407.386028) (xy 64.614985 -407.385527) (xy 64.561033 -407.377775) (xy 64.508733 -407.362423)
			(xy 64.459151 -407.339784) (xy 64.413295 -407.310319) (xy 64.3721 -407.274627) (xy 64.336404 -407.233435)
			(xy 64.306934 -407.187583) (xy 64.28429 -407.138003) (xy 64.268933 -407.085705) (xy 64.261175 -407.031753)
			(xy 62.823665 -407.031753) (xy 62.823665 -407.031754) (xy 62.815908 -407.085708) (xy 62.800551 -407.138009)
			(xy 62.777907 -407.187592) (xy 62.748437 -407.233448) (xy 62.712741 -407.274643) (xy 62.671546 -407.310338)
			(xy 62.62569 -407.339808) (xy 62.576107 -407.362451) (xy 62.523806 -407.377808) (xy 62.469852 -407.385565)
			(xy 62.442598 -407.386028) (xy 61.578998 -407.386028) (xy 61.551748 -407.385502) (xy 61.497804 -407.377745)
			(xy 61.445512 -407.362391) (xy 61.395938 -407.339751) (xy 61.35009 -407.310286) (xy 61.308902 -407.274596)
			(xy 61.273213 -407.233408) (xy 61.243748 -407.187561) (xy 61.221108 -407.137986) (xy 61.205754 -407.085694)
			(xy 61.197998 -407.03175) (xy 59.760465 -407.03175) (xy 59.760465 -407.031756) (xy 59.752707 -407.085714)
			(xy 59.737348 -407.138018) (xy 59.714701 -407.187603) (xy 59.685227 -407.233461) (xy 59.649527 -407.274657)
			(xy 59.608327 -407.310352) (xy 59.562466 -407.339821) (xy 59.512878 -407.362462) (xy 59.460573 -407.377815)
			(xy 59.406614 -407.385568) (xy 59.379358 -407.386028) (xy 58.515758 -407.386028) (xy 58.48851 -407.385499)
			(xy 58.43457 -407.377738) (xy 58.382283 -407.36238) (xy 58.332714 -407.339738) (xy 58.286871 -407.310272)
			(xy 58.245688 -407.274582) (xy 58.210003 -407.233395) (xy 58.180542 -407.187549) (xy 58.157905 -407.137978)
			(xy 58.142553 -407.085689) (xy 58.134798 -407.031748) (xy 56.697142 -407.031748) (xy 56.697142 -407.031752)
			(xy 56.689386 -407.085701) (xy 56.674031 -407.137997) (xy 56.65139 -407.187576) (xy 56.621924 -407.233427)
			(xy 56.586232 -407.274619) (xy 56.545042 -407.310313) (xy 56.499191 -407.339781) (xy 56.449614 -407.362424)
			(xy 56.397318 -407.377782) (xy 56.34337 -407.385541) (xy 56.316118 -407.386028) (xy 55.452518 -407.386028)
			(xy 55.425266 -407.385526) (xy 55.371316 -407.377771) (xy 55.319018 -407.362418) (xy 55.269439 -407.339778)
			(xy 55.223586 -407.310312) (xy 55.182393 -407.27462) (xy 55.146699 -407.233429) (xy 55.117231 -407.187577)
			(xy 55.094589 -407.137998) (xy 55.079232 -407.085702) (xy 55.071475 -407.031752) (xy 53.633965 -407.031752)
			(xy 53.633965 -407.031755) (xy 53.626207 -407.085711) (xy 53.610849 -407.138013) (xy 53.588204 -407.187598)
			(xy 53.558732 -407.233454) (xy 53.523034 -407.27465) (xy 53.481837 -407.310345) (xy 53.435978 -407.339814)
			(xy 53.386393 -407.362457) (xy 53.33409 -407.377812) (xy 53.280133 -407.385567) (xy 53.252878 -407.386028)
			(xy 52.389278 -407.386028) (xy 52.362029 -407.3855) (xy 52.308087 -407.377742) (xy 52.255797 -407.362385)
			(xy 52.206226 -407.339744) (xy 52.16038 -407.310279) (xy 52.119195 -407.274589) (xy 52.083508 -407.233402)
			(xy 52.054045 -407.187555) (xy 52.031407 -407.137982) (xy 52.016054 -407.085692) (xy 52.008298 -407.031749)
			(xy 50.570642 -407.031749) (xy 50.570642 -407.031751) (xy 50.562886 -407.085698) (xy 50.547532 -407.137993)
			(xy 50.524893 -407.18757) (xy 50.495428 -407.233421) (xy 50.459739 -407.274612) (xy 50.418551 -407.310306)
			(xy 50.372703 -407.339775) (xy 50.323128 -407.362419) (xy 50.270835 -407.377778) (xy 50.216889 -407.38554)
			(xy 50.189638 -407.386028) (xy 49.326038 -407.386028) (xy 49.298785 -407.385527) (xy 49.244833 -407.377775)
			(xy 49.192533 -407.362423) (xy 49.142951 -407.339784) (xy 49.097095 -407.310319) (xy 49.0559 -407.274627)
			(xy 49.020204 -407.233435) (xy 48.990734 -407.187583) (xy 48.96809 -407.138003) (xy 48.952733 -407.085705)
			(xy 48.944975 -407.031753) (xy 16.741648 -407.031753) (xy 16.741648 -407.035508) (xy 16.741162 -407.062759)
			(xy 16.733406 -407.116707) (xy 16.718051 -407.169002) (xy 16.695409 -407.218579) (xy 16.665943 -407.264429)
			(xy 16.630252 -407.30562) (xy 16.589061 -407.341311) (xy 16.543211 -407.370777) (xy 16.493634 -407.393419)
			(xy 16.441339 -407.408774) (xy 16.387391 -407.41653) (xy 16.332889 -407.41653) (xy 16.278941 -407.408774)
			(xy 16.226646 -407.393419) (xy 16.177069 -407.370777) (xy 16.131219 -407.341311) (xy 16.090028 -407.30562)
			(xy 16.054337 -407.264429) (xy 16.024871 -407.218579) (xy 16.002229 -407.169002) (xy 15.986874 -407.116707)
			(xy 15.979118 -407.062759) (xy 15.978632 -407.035508) (xy 5.555234 -407.035508) (xy 6.274054 -407.754328)
			(xy 6.323476 -407.804436) (xy 6.417282 -407.909377) (xy 6.505056 -408.019414) (xy 6.586523 -408.134198)
			(xy 6.661426 -408.25337) (xy 6.729529 -408.376554) (xy 6.790618 -408.503362) (xy 6.844501 -408.633397)
			(xy 6.891008 -408.766247) (xy 6.929993 -408.901497) (xy 6.961334 -409.03872) (xy 6.984932 -409.177484)
			(xy 7.000712 -409.317352) (xy 7.008625 -409.457886) (xy 7.00913 -409.528264) (xy 7.00913 -410.057457)
			(xy 48.944923 -410.057457) (xy 48.944923 -410.002943) (xy 48.952682 -409.948984) (xy 48.968041 -409.896679)
			(xy 48.990688 -409.847092) (xy 49.020162 -409.801233) (xy 49.055863 -409.760036) (xy 49.097064 -409.724339)
			(xy 49.142925 -409.69487) (xy 49.192515 -409.672228) (xy 49.244821 -409.656874) (xy 49.298781 -409.64912)
			(xy 49.326038 -409.64866) (xy 50.189638 -409.64866) (xy 50.216885 -409.649213) (xy 50.270824 -409.656973)
			(xy 50.32311 -409.67233) (xy 50.372678 -409.694972) (xy 50.41852 -409.724436) (xy 50.459702 -409.760125)
			(xy 50.495386 -409.801311) (xy 50.524847 -409.847155) (xy 50.547483 -409.896726) (xy 50.562835 -409.949013)
			(xy 50.57059 -410.002953) (xy 50.57059 -410.057447) (xy 50.570589 -410.057453) (xy 52.008246 -410.057453)
			(xy 52.008246 -410.002947) (xy 52.016002 -409.948997) (xy 52.031358 -409.8967) (xy 52.053999 -409.84712)
			(xy 52.083466 -409.801267) (xy 52.119158 -409.760074) (xy 52.160349 -409.724379) (xy 52.206201 -409.69491)
			(xy 52.255779 -409.672265) (xy 52.308076 -409.656907) (xy 52.362025 -409.649147) (xy 52.389278 -409.64866)
			(xy 53.252878 -409.64866) (xy 53.28013 -409.649186) (xy 53.334078 -409.65694) (xy 53.386374 -409.672292)
			(xy 53.435953 -409.694932) (xy 53.481805 -409.724397) (xy 53.522997 -409.760087) (xy 53.55869 -409.801277)
			(xy 53.588158 -409.847127) (xy 53.6108 -409.896705) (xy 53.626156 -409.949) (xy 53.633913 -410.002948)
			(xy 53.633913 -410.057452) (xy 53.633912 -410.057456) (xy 55.071423 -410.057456) (xy 55.071423 -410.002944)
			(xy 55.079181 -409.948987) (xy 55.094539 -409.896683) (xy 55.117185 -409.847098) (xy 55.146657 -409.80124)
			(xy 55.182356 -409.760043) (xy 55.223554 -409.724346) (xy 55.269413 -409.694876) (xy 55.319 -409.672233)
			(xy 55.371305 -409.656877) (xy 55.425262 -409.649122) (xy 55.452518 -409.64866) (xy 56.316118 -409.64866)
			(xy 56.343366 -409.649211) (xy 56.397307 -409.656969) (xy 56.449595 -409.672325) (xy 56.499166 -409.694965)
			(xy 56.54501 -409.724429) (xy 56.586195 -409.760118) (xy 56.621882 -409.801304) (xy 56.651344 -409.84715)
			(xy 56.673982 -409.896721) (xy 56.689334 -409.94901) (xy 56.69709 -410.002952) (xy 56.69709 -410.057448)
			(xy 56.697089 -410.057452) (xy 58.134746 -410.057452) (xy 58.134746 -410.002948) (xy 58.142502 -409.949)
			(xy 58.157856 -409.896704) (xy 58.180496 -409.847125) (xy 58.209961 -409.801273) (xy 58.245651 -409.760081)
			(xy 58.28684 -409.724386) (xy 58.332689 -409.694916) (xy 58.382265 -409.672271) (xy 58.434559 -409.656911)
			(xy 58.488506 -409.649149) (xy 58.515758 -409.64866) (xy 59.379358 -409.64866) (xy 59.406611 -409.649184)
			(xy 59.460561 -409.656936) (xy 59.51286 -409.672287) (xy 59.562441 -409.694925) (xy 59.608296 -409.72439)
			(xy 59.64949 -409.76008) (xy 59.685185 -409.801271) (xy 59.714655 -409.847122) (xy 59.737298 -409.896701)
			(xy 59.752655 -409.948997) (xy 59.760413 -410.002948) (xy 59.760413 -410.057452) (xy 59.760413 -410.057453)
			(xy 61.197946 -410.057453) (xy 61.197946 -410.002947) (xy 61.205703 -409.948994) (xy 61.221059 -409.896695)
			(xy 61.243702 -409.847114) (xy 61.273171 -409.80126) (xy 61.308865 -409.760066) (xy 61.350059 -409.724372)
			(xy 61.395913 -409.694903) (xy 61.445494 -409.67226) (xy 61.497793 -409.656903) (xy 61.551745 -409.649146)
			(xy 61.578998 -409.64866) (xy 62.442598 -409.64866) (xy 62.469849 -409.649187) (xy 62.523795 -409.656943)
			(xy 62.576089 -409.672298) (xy 62.625665 -409.694938) (xy 62.671515 -409.724404) (xy 62.712704 -409.760094)
			(xy 62.748395 -409.801284) (xy 62.777861 -409.847133) (xy 62.800502 -409.896709) (xy 62.815856 -409.949003)
			(xy 62.823613 -410.002949) (xy 62.823613 -410.057451) (xy 62.823612 -410.057457) (xy 64.261123 -410.057457)
			(xy 64.261123 -410.002943) (xy 64.268882 -409.948984) (xy 64.284241 -409.896679) (xy 64.306888 -409.847092)
			(xy 64.336362 -409.801233) (xy 64.372063 -409.760036) (xy 64.413264 -409.724339) (xy 64.459125 -409.69487)
			(xy 64.508715 -409.672228) (xy 64.561021 -409.656874) (xy 64.614981 -409.64912) (xy 64.642238 -409.64866)
			(xy 65.505838 -409.64866) (xy 65.533085 -409.649213) (xy 65.587024 -409.656973) (xy 65.63931 -409.67233)
			(xy 65.688878 -409.694972) (xy 65.73472 -409.724436) (xy 65.775902 -409.760125) (xy 65.811586 -409.801311)
			(xy 65.841047 -409.847155) (xy 65.863683 -409.896726) (xy 65.879035 -409.949013) (xy 65.88679 -410.002953)
			(xy 65.88679 -410.057447) (xy 65.886789 -410.057453) (xy 67.324446 -410.057453) (xy 67.324446 -410.002947)
			(xy 67.332202 -409.948997) (xy 67.347558 -409.8967) (xy 67.370199 -409.84712) (xy 67.399666 -409.801267)
			(xy 67.435358 -409.760074) (xy 67.476549 -409.724379) (xy 67.522401 -409.69491) (xy 67.571979 -409.672265)
			(xy 67.624276 -409.656907) (xy 67.678225 -409.649147) (xy 67.705478 -409.64866) (xy 68.569078 -409.64866)
			(xy 68.59633 -409.649186) (xy 68.650278 -409.65694) (xy 68.702574 -409.672292) (xy 68.752153 -409.694932)
			(xy 68.798005 -409.724397) (xy 68.839197 -409.760087) (xy 68.87489 -409.801277) (xy 68.904358 -409.847127)
			(xy 68.927 -409.896705) (xy 68.942356 -409.949) (xy 68.950113 -410.002948) (xy 68.950113 -410.057452)
			(xy 68.950112 -410.057456) (xy 70.387623 -410.057456) (xy 70.387623 -410.002944) (xy 70.395381 -409.948987)
			(xy 70.410739 -409.896683) (xy 70.433385 -409.847098) (xy 70.462857 -409.80124) (xy 70.498556 -409.760043)
			(xy 70.539754 -409.724346) (xy 70.585613 -409.694876) (xy 70.6352 -409.672233) (xy 70.687505 -409.656877)
			(xy 70.741462 -409.649122) (xy 70.768718 -409.64866) (xy 71.632318 -409.64866) (xy 71.659566 -409.649211)
			(xy 71.713507 -409.656969) (xy 71.765795 -409.672325) (xy 71.815366 -409.694965) (xy 71.86121 -409.724429)
			(xy 71.902395 -409.760118) (xy 71.938082 -409.801304) (xy 71.967544 -409.84715) (xy 71.990182 -409.896721)
			(xy 72.005534 -409.94901) (xy 72.01329 -410.002952) (xy 72.01329 -410.057448) (xy 72.013289 -410.057452)
			(xy 73.450946 -410.057452) (xy 73.450946 -410.002948) (xy 73.458702 -409.949) (xy 73.474056 -409.896704)
			(xy 73.496696 -409.847125) (xy 73.526161 -409.801273) (xy 73.561851 -409.760081) (xy 73.60304 -409.724386)
			(xy 73.648889 -409.694916) (xy 73.698465 -409.672271) (xy 73.750759 -409.656911) (xy 73.804706 -409.649149)
			(xy 73.831958 -409.64866) (xy 74.695558 -409.64866) (xy 74.722811 -409.649184) (xy 74.776761 -409.656936)
			(xy 74.82906 -409.672287) (xy 74.878641 -409.694925) (xy 74.924496 -409.72439) (xy 74.96569 -409.76008)
			(xy 75.001385 -409.801271) (xy 75.030855 -409.847122) (xy 75.053498 -409.896701) (xy 75.068855 -409.948997)
			(xy 75.076613 -410.002948) (xy 75.076613 -410.057452) (xy 75.076613 -410.057453) (xy 76.514146 -410.057453)
			(xy 76.514146 -410.002947) (xy 76.521903 -409.948994) (xy 76.537259 -409.896695) (xy 76.559902 -409.847114)
			(xy 76.589371 -409.80126) (xy 76.625065 -409.760066) (xy 76.666259 -409.724372) (xy 76.712113 -409.694903)
			(xy 76.761694 -409.67226) (xy 76.813993 -409.656903) (xy 76.867945 -409.649146) (xy 76.895198 -409.64866)
			(xy 77.758798 -409.64866) (xy 77.786049 -409.649187) (xy 77.839995 -409.656943) (xy 77.892289 -409.672298)
			(xy 77.941865 -409.694938) (xy 77.987715 -409.724404) (xy 78.028904 -409.760094) (xy 78.064595 -409.801284)
			(xy 78.094061 -409.847133) (xy 78.116702 -409.896709) (xy 78.132056 -409.949003) (xy 78.139813 -410.002949)
			(xy 78.139813 -410.057451) (xy 78.139812 -410.057457) (xy 79.577323 -410.057457) (xy 79.577323 -410.002943)
			(xy 79.585082 -409.948984) (xy 79.600441 -409.896679) (xy 79.623088 -409.847092) (xy 79.652562 -409.801233)
			(xy 79.688263 -409.760036) (xy 79.729464 -409.724339) (xy 79.775325 -409.69487) (xy 79.824915 -409.672228)
			(xy 79.877221 -409.656874) (xy 79.931181 -409.64912) (xy 79.958438 -409.64866) (xy 80.822038 -409.64866)
			(xy 80.849285 -409.649213) (xy 80.903224 -409.656973) (xy 80.95551 -409.67233) (xy 81.005078 -409.694972)
			(xy 81.05092 -409.724436) (xy 81.092102 -409.760125) (xy 81.127786 -409.801311) (xy 81.157247 -409.847155)
			(xy 81.179883 -409.896726) (xy 81.195235 -409.949013) (xy 81.20299 -410.002953) (xy 81.20299 -410.057447)
			(xy 81.202989 -410.057453) (xy 82.640646 -410.057453) (xy 82.640646 -410.002947) (xy 82.648402 -409.948997)
			(xy 82.663758 -409.8967) (xy 82.686399 -409.84712) (xy 82.715866 -409.801267) (xy 82.751558 -409.760074)
			(xy 82.792749 -409.724379) (xy 82.838601 -409.69491) (xy 82.888179 -409.672265) (xy 82.940476 -409.656907)
			(xy 82.994425 -409.649147) (xy 83.021678 -409.64866) (xy 83.885278 -409.64866) (xy 83.91253 -409.649186)
			(xy 83.966478 -409.65694) (xy 84.018774 -409.672292) (xy 84.068353 -409.694932) (xy 84.114205 -409.724397)
			(xy 84.155397 -409.760087) (xy 84.19109 -409.801277) (xy 84.220558 -409.847127) (xy 84.2432 -409.896705)
			(xy 84.258556 -409.949) (xy 84.266313 -410.002948) (xy 84.266313 -410.057452) (xy 84.266312 -410.057456)
			(xy 85.703823 -410.057456) (xy 85.703823 -410.002944) (xy 85.711581 -409.948987) (xy 85.726939 -409.896683)
			(xy 85.749585 -409.847098) (xy 85.779057 -409.80124) (xy 85.814756 -409.760043) (xy 85.855954 -409.724346)
			(xy 85.901813 -409.694876) (xy 85.9514 -409.672233) (xy 86.003705 -409.656877) (xy 86.057662 -409.649122)
			(xy 86.084918 -409.64866) (xy 86.948518 -409.64866) (xy 86.975766 -409.649211) (xy 87.029707 -409.656969)
			(xy 87.081995 -409.672325) (xy 87.131566 -409.694965) (xy 87.17741 -409.724429) (xy 87.218595 -409.760118)
			(xy 87.254282 -409.801304) (xy 87.283744 -409.84715) (xy 87.306382 -409.896721) (xy 87.321734 -409.94901)
			(xy 87.32949 -410.002952) (xy 87.32949 -410.057448) (xy 87.329489 -410.057452) (xy 88.767146 -410.057452)
			(xy 88.767146 -410.002948) (xy 88.774902 -409.949) (xy 88.790256 -409.896704) (xy 88.812896 -409.847125)
			(xy 88.842361 -409.801273) (xy 88.878051 -409.760081) (xy 88.91924 -409.724386) (xy 88.965089 -409.694916)
			(xy 89.014665 -409.672271) (xy 89.066959 -409.656911) (xy 89.120906 -409.649149) (xy 89.148158 -409.64866)
			(xy 90.011758 -409.64866) (xy 90.039011 -409.649184) (xy 90.092961 -409.656936) (xy 90.14526 -409.672287)
			(xy 90.194841 -409.694925) (xy 90.240696 -409.72439) (xy 90.28189 -409.76008) (xy 90.317585 -409.801271)
			(xy 90.347055 -409.847122) (xy 90.369698 -409.896701) (xy 90.385055 -409.948997) (xy 90.392813 -410.002948)
			(xy 90.392813 -410.057452) (xy 90.392813 -410.057453) (xy 91.830346 -410.057453) (xy 91.830346 -410.002947)
			(xy 91.838103 -409.948994) (xy 91.853459 -409.896695) (xy 91.876102 -409.847114) (xy 91.905571 -409.80126)
			(xy 91.941265 -409.760066) (xy 91.982459 -409.724372) (xy 92.028313 -409.694903) (xy 92.077894 -409.67226)
			(xy 92.130193 -409.656903) (xy 92.184145 -409.649146) (xy 92.211398 -409.64866) (xy 93.074998 -409.64866)
			(xy 93.102249 -409.649187) (xy 93.156195 -409.656943) (xy 93.208489 -409.672298) (xy 93.258065 -409.694938)
			(xy 93.303915 -409.724404) (xy 93.345104 -409.760094) (xy 93.380795 -409.801284) (xy 93.410261 -409.847133)
			(xy 93.432902 -409.896709) (xy 93.448256 -409.949003) (xy 93.456013 -410.002949) (xy 93.456013 -410.057451)
			(xy 93.456012 -410.057457) (xy 94.893523 -410.057457) (xy 94.893523 -410.002943) (xy 94.901282 -409.948984)
			(xy 94.916641 -409.896679) (xy 94.939288 -409.847092) (xy 94.968762 -409.801233) (xy 95.004463 -409.760036)
			(xy 95.045664 -409.724339) (xy 95.091525 -409.69487) (xy 95.141115 -409.672228) (xy 95.193421 -409.656874)
			(xy 95.247381 -409.64912) (xy 95.274638 -409.64866) (xy 96.138238 -409.64866) (xy 96.165485 -409.649213)
			(xy 96.219424 -409.656973) (xy 96.27171 -409.67233) (xy 96.321278 -409.694972) (xy 96.36712 -409.724436)
			(xy 96.408302 -409.760125) (xy 96.443986 -409.801311) (xy 96.473447 -409.847155) (xy 96.496083 -409.896726)
			(xy 96.511435 -409.949013) (xy 96.51919 -410.002953) (xy 96.51919 -410.057447) (xy 96.519189 -410.057451)
			(xy 121.120146 -410.057451) (xy 121.120146 -410.002949) (xy 121.127902 -409.949) (xy 121.143256 -409.896705)
			(xy 121.165895 -409.847127) (xy 121.19536 -409.801275) (xy 121.231049 -409.760082) (xy 121.272238 -409.724388)
			(xy 121.318086 -409.694918) (xy 121.367662 -409.672272) (xy 121.419955 -409.656911) (xy 121.473903 -409.649149)
			(xy 121.501154 -409.64866) (xy 122.364754 -409.64866) (xy 122.392007 -409.649184) (xy 122.445958 -409.656935)
			(xy 122.498257 -409.672286) (xy 122.547839 -409.694924) (xy 122.593694 -409.724388) (xy 122.634889 -409.760079)
			(xy 122.670584 -409.801269) (xy 122.700054 -409.847121) (xy 122.722698 -409.8967) (xy 122.738055 -409.948997)
			(xy 122.745813 -410.002947) (xy 122.745813 -410.057453) (xy 124.183346 -410.057453) (xy 124.183346 -410.002947)
			(xy 124.191103 -409.948995) (xy 124.206459 -409.896696) (xy 124.229102 -409.847115) (xy 124.25857 -409.801261)
			(xy 124.294264 -409.760068) (xy 124.335457 -409.724373) (xy 124.38131 -409.694904) (xy 124.430891 -409.672261)
			(xy 124.483189 -409.656904) (xy 124.537141 -409.649146) (xy 124.564394 -409.64866) (xy 125.427994 -409.64866)
			(xy 125.455245 -409.649187) (xy 125.509192 -409.656942) (xy 125.561486 -409.672297) (xy 125.611063 -409.694937)
			(xy 125.656913 -409.724402) (xy 125.698103 -409.760093) (xy 125.733794 -409.801282) (xy 125.76326 -409.847132)
			(xy 125.785901 -409.896708) (xy 125.801256 -409.949002) (xy 125.809013 -410.002949) (xy 125.809013 -410.057451)
			(xy 125.809012 -410.057457) (xy 127.246523 -410.057457) (xy 127.246523 -410.002943) (xy 127.254282 -409.948985)
			(xy 127.269641 -409.89668) (xy 127.292287 -409.847093) (xy 127.321761 -409.801235) (xy 127.357462 -409.760037)
			(xy 127.398662 -409.724341) (xy 127.444523 -409.694871) (xy 127.494112 -409.672229) (xy 127.546418 -409.656874)
			(xy 127.600377 -409.649121) (xy 127.627634 -409.64866) (xy 128.491234 -409.64866) (xy 128.518481 -409.649213)
			(xy 128.572421 -409.656972) (xy 128.624707 -409.672329) (xy 128.674276 -409.69497) (xy 128.720118 -409.724435)
			(xy 128.761301 -409.760123) (xy 128.796985 -409.801309) (xy 128.826446 -409.847154) (xy 128.849083 -409.896725)
			(xy 128.864435 -409.949012) (xy 128.87219 -410.002953) (xy 128.87219 -410.057447) (xy 128.872189 -410.057452)
			(xy 130.309846 -410.057452) (xy 130.309846 -410.002948) (xy 130.317602 -409.948998) (xy 130.332957 -409.896701)
			(xy 130.355599 -409.847121) (xy 130.385065 -409.801268) (xy 130.420757 -409.760075) (xy 130.461947 -409.72438)
			(xy 130.507798 -409.694911) (xy 130.557376 -409.672266) (xy 130.609672 -409.656908) (xy 130.663622 -409.649148)
			(xy 130.690874 -409.64866) (xy 131.554474 -409.64866) (xy 131.581726 -409.649185) (xy 131.635675 -409.656939)
			(xy 131.687972 -409.672291) (xy 131.737551 -409.69493) (xy 131.783403 -409.724395) (xy 131.824596 -409.760086)
			(xy 131.860289 -409.801276) (xy 131.889757 -409.847126) (xy 131.9124 -409.896704) (xy 131.927756 -409.949)
			(xy 131.935513 -410.002948) (xy 131.935513 -410.057452) (xy 131.935512 -410.057456) (xy 133.373023 -410.057456)
			(xy 133.373023 -410.002944) (xy 133.380781 -409.948987) (xy 133.396139 -409.896684) (xy 133.418784 -409.847099)
			(xy 133.448256 -409.801241) (xy 133.483954 -409.760045) (xy 133.525152 -409.724348) (xy 133.571011 -409.694878)
			(xy 133.620597 -409.672234) (xy 133.672901 -409.656878) (xy 133.726858 -409.649122) (xy 133.754114 -409.64866)
			(xy 134.617714 -409.64866) (xy 134.644962 -409.649211) (xy 134.698904 -409.656969) (xy 134.751193 -409.672324)
			(xy 134.800764 -409.694964) (xy 134.846609 -409.724428) (xy 134.887794 -409.760116) (xy 134.923481 -409.801303)
			(xy 134.952943 -409.847149) (xy 134.975581 -409.896721) (xy 134.990934 -409.94901) (xy 134.99869 -410.002952)
			(xy 134.99869 -410.057448) (xy 134.99869 -410.057451) (xy 136.436346 -410.057451) (xy 136.436346 -410.002949)
			(xy 136.444102 -409.949) (xy 136.459456 -409.896705) (xy 136.482095 -409.847127) (xy 136.51156 -409.801275)
			(xy 136.547249 -409.760082) (xy 136.588438 -409.724388) (xy 136.634286 -409.694918) (xy 136.683862 -409.672272)
			(xy 136.736155 -409.656911) (xy 136.790103 -409.649149) (xy 136.817354 -409.64866) (xy 137.680954 -409.64866)
			(xy 137.708207 -409.649184) (xy 137.762158 -409.656935) (xy 137.814457 -409.672286) (xy 137.864039 -409.694924)
			(xy 137.909894 -409.724388) (xy 137.951089 -409.760079) (xy 137.986784 -409.801269) (xy 138.016254 -409.847121)
			(xy 138.038898 -409.8967) (xy 138.054255 -409.948997) (xy 138.062013 -410.002947) (xy 138.062013 -410.057453)
			(xy 139.499546 -410.057453) (xy 139.499546 -410.002947) (xy 139.507303 -409.948995) (xy 139.522659 -409.896696)
			(xy 139.545302 -409.847115) (xy 139.57477 -409.801261) (xy 139.610464 -409.760068) (xy 139.651657 -409.724373)
			(xy 139.69751 -409.694904) (xy 139.747091 -409.672261) (xy 139.799389 -409.656904) (xy 139.853341 -409.649146)
			(xy 139.880594 -409.64866) (xy 140.744194 -409.64866) (xy 140.771445 -409.649187) (xy 140.825392 -409.656942)
			(xy 140.877686 -409.672297) (xy 140.927263 -409.694937) (xy 140.973113 -409.724402) (xy 141.014303 -409.760093)
			(xy 141.049994 -409.801282) (xy 141.07946 -409.847132) (xy 141.102101 -409.896708) (xy 141.117456 -409.949002)
			(xy 141.125213 -410.002949) (xy 141.125213 -410.057451) (xy 141.125212 -410.057457) (xy 142.562723 -410.057457)
			(xy 142.562723 -410.002943) (xy 142.570482 -409.948985) (xy 142.585841 -409.89668) (xy 142.608487 -409.847093)
			(xy 142.637961 -409.801235) (xy 142.673662 -409.760037) (xy 142.714862 -409.724341) (xy 142.760723 -409.694871)
			(xy 142.810312 -409.672229) (xy 142.862618 -409.656874) (xy 142.916577 -409.649121) (xy 142.943834 -409.64866)
			(xy 143.807434 -409.64866) (xy 143.834681 -409.649213) (xy 143.888621 -409.656972) (xy 143.940907 -409.672329)
			(xy 143.990476 -409.69497) (xy 144.036318 -409.724435) (xy 144.077501 -409.760123) (xy 144.113185 -409.801309)
			(xy 144.142646 -409.847154) (xy 144.165283 -409.896725) (xy 144.180635 -409.949012) (xy 144.18839 -410.002953)
			(xy 144.18839 -410.057447) (xy 144.188389 -410.057452) (xy 145.626046 -410.057452) (xy 145.626046 -410.002948)
			(xy 145.633802 -409.948998) (xy 145.649157 -409.896701) (xy 145.671799 -409.847121) (xy 145.701265 -409.801268)
			(xy 145.736957 -409.760075) (xy 145.778147 -409.72438) (xy 145.823998 -409.694911) (xy 145.873576 -409.672266)
			(xy 145.925872 -409.656908) (xy 145.979822 -409.649148) (xy 146.007074 -409.64866) (xy 146.870674 -409.64866)
			(xy 146.897926 -409.649185) (xy 146.951875 -409.656939) (xy 147.004172 -409.672291) (xy 147.053751 -409.69493)
			(xy 147.099603 -409.724395) (xy 147.140796 -409.760086) (xy 147.176489 -409.801276) (xy 147.205957 -409.847126)
			(xy 147.2286 -409.896704) (xy 147.243956 -409.949) (xy 147.251713 -410.002948) (xy 147.251713 -410.057452)
			(xy 147.251712 -410.057456) (xy 148.689223 -410.057456) (xy 148.689223 -410.002944) (xy 148.696981 -409.948987)
			(xy 148.712339 -409.896684) (xy 148.734984 -409.847099) (xy 148.764456 -409.801241) (xy 148.800154 -409.760045)
			(xy 148.841352 -409.724348) (xy 148.887211 -409.694878) (xy 148.936797 -409.672234) (xy 148.989101 -409.656878)
			(xy 149.043058 -409.649122) (xy 149.070314 -409.64866) (xy 149.933914 -409.64866) (xy 149.961162 -409.649211)
			(xy 150.015104 -409.656969) (xy 150.067393 -409.672324) (xy 150.116964 -409.694964) (xy 150.162809 -409.724428)
			(xy 150.203994 -409.760116) (xy 150.239681 -409.801303) (xy 150.269143 -409.847149) (xy 150.291781 -409.896721)
			(xy 150.307134 -409.94901) (xy 150.31489 -410.002952) (xy 150.31489 -410.057448) (xy 150.31489 -410.057451)
			(xy 151.752546 -410.057451) (xy 151.752546 -410.002949) (xy 151.760302 -409.949) (xy 151.775656 -409.896705)
			(xy 151.798295 -409.847127) (xy 151.82776 -409.801275) (xy 151.863449 -409.760082) (xy 151.904638 -409.724388)
			(xy 151.950486 -409.694918) (xy 152.000062 -409.672272) (xy 152.052355 -409.656911) (xy 152.106303 -409.649149)
			(xy 152.133554 -409.64866) (xy 152.997154 -409.64866) (xy 153.024407 -409.649184) (xy 153.078358 -409.656935)
			(xy 153.130657 -409.672286) (xy 153.180239 -409.694924) (xy 153.226094 -409.724388) (xy 153.267289 -409.760079)
			(xy 153.302984 -409.801269) (xy 153.332454 -409.847121) (xy 153.355098 -409.8967) (xy 153.370455 -409.948997)
			(xy 153.378213 -410.002947) (xy 153.378213 -410.057453) (xy 154.815746 -410.057453) (xy 154.815746 -410.002947)
			(xy 154.823503 -409.948995) (xy 154.838859 -409.896696) (xy 154.861502 -409.847115) (xy 154.89097 -409.801261)
			(xy 154.926664 -409.760068) (xy 154.967857 -409.724373) (xy 155.01371 -409.694904) (xy 155.063291 -409.672261)
			(xy 155.115589 -409.656904) (xy 155.169541 -409.649146) (xy 155.196794 -409.64866) (xy 156.060394 -409.64866)
			(xy 156.087645 -409.649187) (xy 156.141592 -409.656942) (xy 156.193886 -409.672297) (xy 156.243463 -409.694937)
			(xy 156.289313 -409.724402) (xy 156.330503 -409.760093) (xy 156.366194 -409.801282) (xy 156.39566 -409.847132)
			(xy 156.418301 -409.896708) (xy 156.433656 -409.949002) (xy 156.441413 -410.002949) (xy 156.441413 -410.057451)
			(xy 156.441412 -410.057457) (xy 157.878923 -410.057457) (xy 157.878923 -410.002943) (xy 157.886682 -409.948985)
			(xy 157.902041 -409.89668) (xy 157.924687 -409.847093) (xy 157.954161 -409.801235) (xy 157.989862 -409.760037)
			(xy 158.031062 -409.724341) (xy 158.076923 -409.694871) (xy 158.126512 -409.672229) (xy 158.178818 -409.656874)
			(xy 158.232777 -409.649121) (xy 158.260034 -409.64866) (xy 159.123634 -409.64866) (xy 159.150881 -409.649213)
			(xy 159.204821 -409.656972) (xy 159.257107 -409.672329) (xy 159.306676 -409.69497) (xy 159.352518 -409.724435)
			(xy 159.393701 -409.760123) (xy 159.429385 -409.801309) (xy 159.458846 -409.847154) (xy 159.481483 -409.896725)
			(xy 159.496835 -409.949012) (xy 159.50459 -410.002953) (xy 159.50459 -410.057447) (xy 159.504589 -410.057452)
			(xy 160.942246 -410.057452) (xy 160.942246 -410.002948) (xy 160.950002 -409.948998) (xy 160.965357 -409.896701)
			(xy 160.987999 -409.847121) (xy 161.017465 -409.801268) (xy 161.053157 -409.760075) (xy 161.094347 -409.72438)
			(xy 161.140198 -409.694911) (xy 161.189776 -409.672266) (xy 161.242072 -409.656908) (xy 161.296022 -409.649148)
			(xy 161.323274 -409.64866) (xy 162.186874 -409.64866) (xy 162.214126 -409.649185) (xy 162.268075 -409.656939)
			(xy 162.320372 -409.672291) (xy 162.369951 -409.69493) (xy 162.415803 -409.724395) (xy 162.456996 -409.760086)
			(xy 162.492689 -409.801276) (xy 162.522157 -409.847126) (xy 162.5448 -409.896704) (xy 162.560156 -409.949)
			(xy 162.567913 -410.002948) (xy 162.567913 -410.057452) (xy 162.567912 -410.057456) (xy 164.005423 -410.057456)
			(xy 164.005423 -410.002944) (xy 164.013181 -409.948987) (xy 164.028539 -409.896684) (xy 164.051184 -409.847099)
			(xy 164.080656 -409.801241) (xy 164.116354 -409.760045) (xy 164.157552 -409.724348) (xy 164.203411 -409.694878)
			(xy 164.252997 -409.672234) (xy 164.305301 -409.656878) (xy 164.359258 -409.649122) (xy 164.386514 -409.64866)
			(xy 165.250114 -409.64866) (xy 165.277362 -409.649211) (xy 165.331304 -409.656969) (xy 165.383593 -409.672324)
			(xy 165.433164 -409.694964) (xy 165.479009 -409.724428) (xy 165.520194 -409.760116) (xy 165.555881 -409.801303)
			(xy 165.585343 -409.847149) (xy 165.607981 -409.896721) (xy 165.623334 -409.94901) (xy 165.63109 -410.002952)
			(xy 165.63109 -410.057448) (xy 165.63109 -410.057451) (xy 167.068746 -410.057451) (xy 167.068746 -410.002949)
			(xy 167.076502 -409.949) (xy 167.091856 -409.896705) (xy 167.114495 -409.847127) (xy 167.14396 -409.801275)
			(xy 167.179649 -409.760082) (xy 167.220838 -409.724388) (xy 167.266686 -409.694918) (xy 167.316262 -409.672272)
			(xy 167.368555 -409.656911) (xy 167.422503 -409.649149) (xy 167.449754 -409.64866) (xy 168.313354 -409.64866)
			(xy 168.340607 -409.649184) (xy 168.394558 -409.656935) (xy 168.446857 -409.672286) (xy 168.496439 -409.694924)
			(xy 168.542294 -409.724388) (xy 168.583489 -409.760079) (xy 168.619184 -409.801269) (xy 168.648654 -409.847121)
			(xy 168.671298 -409.8967) (xy 168.686655 -409.948997) (xy 168.694413 -410.002947) (xy 168.694413 -410.057453)
			(xy 168.686655 -410.111403) (xy 168.671298 -410.1637) (xy 168.648654 -410.213279) (xy 168.619184 -410.259131)
			(xy 168.583489 -410.300321) (xy 168.542294 -410.336012) (xy 168.496439 -410.365476) (xy 168.446857 -410.388114)
			(xy 168.394558 -410.403465) (xy 168.340607 -410.411216) (xy 168.313354 -410.411676) (xy 167.449754 -410.411676)
			(xy 167.422503 -410.411251) (xy 167.368555 -410.403489) (xy 167.316262 -410.388128) (xy 167.266686 -410.365482)
			(xy 167.220838 -410.336012) (xy 167.179649 -410.300318) (xy 167.14396 -410.259125) (xy 167.114495 -410.213273)
			(xy 167.091856 -410.163695) (xy 167.076502 -410.1114) (xy 167.068746 -410.057451) (xy 165.63109 -410.057451)
			(xy 165.623334 -410.11139) (xy 165.607981 -410.163679) (xy 165.585343 -410.213251) (xy 165.555881 -410.259097)
			(xy 165.520194 -410.300284) (xy 165.479009 -410.335972) (xy 165.433164 -410.365436) (xy 165.383593 -410.388076)
			(xy 165.331304 -410.403431) (xy 165.277362 -410.411189) (xy 165.250114 -410.411676) (xy 164.386514 -410.411676)
			(xy 164.359258 -410.411278) (xy 164.305301 -410.403522) (xy 164.252997 -410.388166) (xy 164.203411 -410.365522)
			(xy 164.157552 -410.336052) (xy 164.116354 -410.300355) (xy 164.080656 -410.259159) (xy 164.051184 -410.213301)
			(xy 164.028539 -410.163716) (xy 164.013181 -410.111413) (xy 164.005423 -410.057456) (xy 162.567912 -410.057456)
			(xy 162.560156 -410.1114) (xy 162.5448 -410.163696) (xy 162.522157 -410.213274) (xy 162.492689 -410.259124)
			(xy 162.456996 -410.300314) (xy 162.415803 -410.336005) (xy 162.369951 -410.36547) (xy 162.320372 -410.388109)
			(xy 162.268075 -410.403461) (xy 162.214126 -410.411215) (xy 162.186874 -410.411676) (xy 161.323274 -410.411676)
			(xy 161.296022 -410.411252) (xy 161.242072 -410.403492) (xy 161.189776 -410.388134) (xy 161.140198 -410.365489)
			(xy 161.094347 -410.33602) (xy 161.053157 -410.300325) (xy 161.017465 -410.259132) (xy 160.987999 -410.213279)
			(xy 160.965357 -410.163699) (xy 160.950002 -410.111402) (xy 160.942246 -410.057452) (xy 159.504589 -410.057452)
			(xy 159.496835 -410.111388) (xy 159.481483 -410.163675) (xy 159.458846 -410.213246) (xy 159.429385 -410.259091)
			(xy 159.393701 -410.300277) (xy 159.352518 -410.335965) (xy 159.306676 -410.36543) (xy 159.257107 -410.388071)
			(xy 159.204821 -410.403428) (xy 159.150881 -410.411187) (xy 159.123634 -410.411676) (xy 158.260034 -410.411676)
			(xy 158.232777 -410.411279) (xy 158.178818 -410.403526) (xy 158.126512 -410.388171) (xy 158.076923 -410.365529)
			(xy 158.031062 -410.336059) (xy 157.989862 -410.300363) (xy 157.954161 -410.259165) (xy 157.924687 -410.213307)
			(xy 157.902041 -410.16372) (xy 157.886682 -410.111415) (xy 157.878923 -410.057457) (xy 156.441412 -410.057457)
			(xy 156.433656 -410.111398) (xy 156.418301 -410.163692) (xy 156.39566 -410.213268) (xy 156.366194 -410.259118)
			(xy 156.330503 -410.300307) (xy 156.289313 -410.335998) (xy 156.243463 -410.365463) (xy 156.193886 -410.388103)
			(xy 156.141592 -410.403458) (xy 156.087645 -410.411213) (xy 156.060394 -410.411676) (xy 155.196794 -410.411676)
			(xy 155.169541 -410.411254) (xy 155.115589 -410.403496) (xy 155.063291 -410.388139) (xy 155.01371 -410.365496)
			(xy 154.967857 -410.336027) (xy 154.926664 -410.300332) (xy 154.89097 -410.259139) (xy 154.861502 -410.213285)
			(xy 154.838859 -410.163704) (xy 154.823503 -410.111405) (xy 154.815746 -410.057453) (xy 153.378213 -410.057453)
			(xy 153.370455 -410.111403) (xy 153.355098 -410.1637) (xy 153.332454 -410.213279) (xy 153.302984 -410.259131)
			(xy 153.267289 -410.300321) (xy 153.226094 -410.336012) (xy 153.180239 -410.365476) (xy 153.130657 -410.388114)
			(xy 153.078358 -410.403465) (xy 153.024407 -410.411216) (xy 152.997154 -410.411676) (xy 152.133554 -410.411676)
			(xy 152.106303 -410.411251) (xy 152.052355 -410.403489) (xy 152.000062 -410.388128) (xy 151.950486 -410.365482)
			(xy 151.904638 -410.336012) (xy 151.863449 -410.300318) (xy 151.82776 -410.259125) (xy 151.798295 -410.213273)
			(xy 151.775656 -410.163695) (xy 151.760302 -410.1114) (xy 151.752546 -410.057451) (xy 150.31489 -410.057451)
			(xy 150.307134 -410.11139) (xy 150.291781 -410.163679) (xy 150.269143 -410.213251) (xy 150.239681 -410.259097)
			(xy 150.203994 -410.300284) (xy 150.162809 -410.335972) (xy 150.116964 -410.365436) (xy 150.067393 -410.388076)
			(xy 150.015104 -410.403431) (xy 149.961162 -410.411189) (xy 149.933914 -410.411676) (xy 149.070314 -410.411676)
			(xy 149.043058 -410.411278) (xy 148.989101 -410.403522) (xy 148.936797 -410.388166) (xy 148.887211 -410.365522)
			(xy 148.841352 -410.336052) (xy 148.800154 -410.300355) (xy 148.764456 -410.259159) (xy 148.734984 -410.213301)
			(xy 148.712339 -410.163716) (xy 148.696981 -410.111413) (xy 148.689223 -410.057456) (xy 147.251712 -410.057456)
			(xy 147.243956 -410.1114) (xy 147.2286 -410.163696) (xy 147.205957 -410.213274) (xy 147.176489 -410.259124)
			(xy 147.140796 -410.300314) (xy 147.099603 -410.336005) (xy 147.053751 -410.36547) (xy 147.004172 -410.388109)
			(xy 146.951875 -410.403461) (xy 146.897926 -410.411215) (xy 146.870674 -410.411676) (xy 146.007074 -410.411676)
			(xy 145.979822 -410.411252) (xy 145.925872 -410.403492) (xy 145.873576 -410.388134) (xy 145.823998 -410.365489)
			(xy 145.778147 -410.33602) (xy 145.736957 -410.300325) (xy 145.701265 -410.259132) (xy 145.671799 -410.213279)
			(xy 145.649157 -410.163699) (xy 145.633802 -410.111402) (xy 145.626046 -410.057452) (xy 144.188389 -410.057452)
			(xy 144.180635 -410.111388) (xy 144.165283 -410.163675) (xy 144.142646 -410.213246) (xy 144.113185 -410.259091)
			(xy 144.077501 -410.300277) (xy 144.036318 -410.335965) (xy 143.990476 -410.36543) (xy 143.940907 -410.388071)
			(xy 143.888621 -410.403428) (xy 143.834681 -410.411187) (xy 143.807434 -410.411676) (xy 142.943834 -410.411676)
			(xy 142.916577 -410.411279) (xy 142.862618 -410.403526) (xy 142.810312 -410.388171) (xy 142.760723 -410.365529)
			(xy 142.714862 -410.336059) (xy 142.673662 -410.300363) (xy 142.637961 -410.259165) (xy 142.608487 -410.213307)
			(xy 142.585841 -410.16372) (xy 142.570482 -410.111415) (xy 142.562723 -410.057457) (xy 141.125212 -410.057457)
			(xy 141.117456 -410.111398) (xy 141.102101 -410.163692) (xy 141.07946 -410.213268) (xy 141.049994 -410.259118)
			(xy 141.014303 -410.300307) (xy 140.973113 -410.335998) (xy 140.927263 -410.365463) (xy 140.877686 -410.388103)
			(xy 140.825392 -410.403458) (xy 140.771445 -410.411213) (xy 140.744194 -410.411676) (xy 139.880594 -410.411676)
			(xy 139.853341 -410.411254) (xy 139.799389 -410.403496) (xy 139.747091 -410.388139) (xy 139.69751 -410.365496)
			(xy 139.651657 -410.336027) (xy 139.610464 -410.300332) (xy 139.57477 -410.259139) (xy 139.545302 -410.213285)
			(xy 139.522659 -410.163704) (xy 139.507303 -410.111405) (xy 139.499546 -410.057453) (xy 138.062013 -410.057453)
			(xy 138.054255 -410.111403) (xy 138.038898 -410.1637) (xy 138.016254 -410.213279) (xy 137.986784 -410.259131)
			(xy 137.951089 -410.300321) (xy 137.909894 -410.336012) (xy 137.864039 -410.365476) (xy 137.814457 -410.388114)
			(xy 137.762158 -410.403465) (xy 137.708207 -410.411216) (xy 137.680954 -410.411676) (xy 136.817354 -410.411676)
			(xy 136.790103 -410.411251) (xy 136.736155 -410.403489) (xy 136.683862 -410.388128) (xy 136.634286 -410.365482)
			(xy 136.588438 -410.336012) (xy 136.547249 -410.300318) (xy 136.51156 -410.259125) (xy 136.482095 -410.213273)
			(xy 136.459456 -410.163695) (xy 136.444102 -410.1114) (xy 136.436346 -410.057451) (xy 134.99869 -410.057451)
			(xy 134.990934 -410.11139) (xy 134.975581 -410.163679) (xy 134.952943 -410.213251) (xy 134.923481 -410.259097)
			(xy 134.887794 -410.300284) (xy 134.846609 -410.335972) (xy 134.800764 -410.365436) (xy 134.751193 -410.388076)
			(xy 134.698904 -410.403431) (xy 134.644962 -410.411189) (xy 134.617714 -410.411676) (xy 133.754114 -410.411676)
			(xy 133.726858 -410.411278) (xy 133.672901 -410.403522) (xy 133.620597 -410.388166) (xy 133.571011 -410.365522)
			(xy 133.525152 -410.336052) (xy 133.483954 -410.300355) (xy 133.448256 -410.259159) (xy 133.418784 -410.213301)
			(xy 133.396139 -410.163716) (xy 133.380781 -410.111413) (xy 133.373023 -410.057456) (xy 131.935512 -410.057456)
			(xy 131.927756 -410.1114) (xy 131.9124 -410.163696) (xy 131.889757 -410.213274) (xy 131.860289 -410.259124)
			(xy 131.824596 -410.300314) (xy 131.783403 -410.336005) (xy 131.737551 -410.36547) (xy 131.687972 -410.388109)
			(xy 131.635675 -410.403461) (xy 131.581726 -410.411215) (xy 131.554474 -410.411676) (xy 130.690874 -410.411676)
			(xy 130.663622 -410.411252) (xy 130.609672 -410.403492) (xy 130.557376 -410.388134) (xy 130.507798 -410.365489)
			(xy 130.461947 -410.33602) (xy 130.420757 -410.300325) (xy 130.385065 -410.259132) (xy 130.355599 -410.213279)
			(xy 130.332957 -410.163699) (xy 130.317602 -410.111402) (xy 130.309846 -410.057452) (xy 128.872189 -410.057452)
			(xy 128.864435 -410.111388) (xy 128.849083 -410.163675) (xy 128.826446 -410.213246) (xy 128.796985 -410.259091)
			(xy 128.761301 -410.300277) (xy 128.720118 -410.335965) (xy 128.674276 -410.36543) (xy 128.624707 -410.388071)
			(xy 128.572421 -410.403428) (xy 128.518481 -410.411187) (xy 128.491234 -410.411676) (xy 127.627634 -410.411676)
			(xy 127.600377 -410.411279) (xy 127.546418 -410.403526) (xy 127.494112 -410.388171) (xy 127.444523 -410.365529)
			(xy 127.398662 -410.336059) (xy 127.357462 -410.300363) (xy 127.321761 -410.259165) (xy 127.292287 -410.213307)
			(xy 127.269641 -410.16372) (xy 127.254282 -410.111415) (xy 127.246523 -410.057457) (xy 125.809012 -410.057457)
			(xy 125.801256 -410.111398) (xy 125.785901 -410.163692) (xy 125.76326 -410.213268) (xy 125.733794 -410.259118)
			(xy 125.698103 -410.300307) (xy 125.656913 -410.335998) (xy 125.611063 -410.365463) (xy 125.561486 -410.388103)
			(xy 125.509192 -410.403458) (xy 125.455245 -410.411213) (xy 125.427994 -410.411676) (xy 124.564394 -410.411676)
			(xy 124.537141 -410.411254) (xy 124.483189 -410.403496) (xy 124.430891 -410.388139) (xy 124.38131 -410.365496)
			(xy 124.335457 -410.336027) (xy 124.294264 -410.300332) (xy 124.25857 -410.259139) (xy 124.229102 -410.213285)
			(xy 124.206459 -410.163704) (xy 124.191103 -410.111405) (xy 124.183346 -410.057453) (xy 122.745813 -410.057453)
			(xy 122.738055 -410.111403) (xy 122.722698 -410.1637) (xy 122.700054 -410.213279) (xy 122.670584 -410.259131)
			(xy 122.634889 -410.300321) (xy 122.593694 -410.336012) (xy 122.547839 -410.365476) (xy 122.498257 -410.388114)
			(xy 122.445958 -410.403465) (xy 122.392007 -410.411216) (xy 122.364754 -410.411676) (xy 121.501154 -410.411676)
			(xy 121.473903 -410.411251) (xy 121.419955 -410.403489) (xy 121.367662 -410.388128) (xy 121.318086 -410.365482)
			(xy 121.272238 -410.336012) (xy 121.231049 -410.300318) (xy 121.19536 -410.259125) (xy 121.165895 -410.213273)
			(xy 121.143256 -410.163695) (xy 121.127902 -410.1114) (xy 121.120146 -410.057451) (xy 96.519189 -410.057451)
			(xy 96.511435 -410.111387) (xy 96.496083 -410.163674) (xy 96.473447 -410.213245) (xy 96.443986 -410.259089)
			(xy 96.408302 -410.300275) (xy 96.36712 -410.335964) (xy 96.321278 -410.365428) (xy 96.27171 -410.38807)
			(xy 96.219424 -410.403427) (xy 96.165485 -410.411187) (xy 96.138238 -410.411676) (xy 95.274638 -410.411676)
			(xy 95.247381 -410.41128) (xy 95.193421 -410.403526) (xy 95.141115 -410.388172) (xy 95.091525 -410.36553)
			(xy 95.045664 -410.336061) (xy 95.004463 -410.300364) (xy 94.968762 -410.259167) (xy 94.939288 -410.213308)
			(xy 94.916641 -410.163721) (xy 94.901282 -410.111416) (xy 94.893523 -410.057457) (xy 93.456012 -410.057457)
			(xy 93.448256 -410.111397) (xy 93.432902 -410.163691) (xy 93.410261 -410.213267) (xy 93.380795 -410.259116)
			(xy 93.345104 -410.300306) (xy 93.303915 -410.335996) (xy 93.258065 -410.365462) (xy 93.208489 -410.388102)
			(xy 93.156195 -410.403457) (xy 93.102249 -410.411213) (xy 93.074998 -410.411676) (xy 92.211398 -410.411676)
			(xy 92.184145 -410.411254) (xy 92.130193 -410.403497) (xy 92.077894 -410.38814) (xy 92.028313 -410.365497)
			(xy 91.982459 -410.336028) (xy 91.941265 -410.300334) (xy 91.905571 -410.25914) (xy 91.876102 -410.213286)
			(xy 91.853459 -410.163705) (xy 91.838103 -410.111406) (xy 91.830346 -410.057453) (xy 90.392813 -410.057453)
			(xy 90.385055 -410.111403) (xy 90.369698 -410.163699) (xy 90.347055 -410.213278) (xy 90.317585 -410.259129)
			(xy 90.28189 -410.30032) (xy 90.240696 -410.33601) (xy 90.194841 -410.365475) (xy 90.14526 -410.388113)
			(xy 90.092961 -410.403464) (xy 90.039011 -410.411216) (xy 90.011758 -410.411676) (xy 89.148158 -410.411676)
			(xy 89.120906 -410.411251) (xy 89.066959 -410.403489) (xy 89.014665 -410.388129) (xy 88.965089 -410.365484)
			(xy 88.91924 -410.336014) (xy 88.878051 -410.300319) (xy 88.842361 -410.259127) (xy 88.812896 -410.213275)
			(xy 88.790256 -410.163696) (xy 88.774902 -410.1114) (xy 88.767146 -410.057452) (xy 87.329489 -410.057452)
			(xy 87.321734 -410.11139) (xy 87.306382 -410.163679) (xy 87.283744 -410.21325) (xy 87.254282 -410.259096)
			(xy 87.218595 -410.300282) (xy 87.17741 -410.335971) (xy 87.131566 -410.365435) (xy 87.081995 -410.388075)
			(xy 87.029707 -410.403431) (xy 86.975766 -410.411189) (xy 86.948518 -410.411676) (xy 86.084918 -410.411676)
			(xy 86.057662 -410.411278) (xy 86.003705 -410.403523) (xy 85.9514 -410.388167) (xy 85.901813 -410.365524)
			(xy 85.855954 -410.336054) (xy 85.814756 -410.300357) (xy 85.779057 -410.25916) (xy 85.749585 -410.213302)
			(xy 85.726939 -410.163717) (xy 85.711581 -410.111413) (xy 85.703823 -410.057456) (xy 84.266312 -410.057456)
			(xy 84.258556 -410.1114) (xy 84.2432 -410.163695) (xy 84.220558 -410.213273) (xy 84.19109 -410.259123)
			(xy 84.155397 -410.300313) (xy 84.114205 -410.336003) (xy 84.068353 -410.365468) (xy 84.018774 -410.388108)
			(xy 83.966478 -410.40346) (xy 83.91253 -410.411214) (xy 83.885278 -410.411676) (xy 83.021678 -410.411676)
			(xy 82.994425 -410.411253) (xy 82.940476 -410.403493) (xy 82.888179 -410.388135) (xy 82.838601 -410.36549)
			(xy 82.792749 -410.336021) (xy 82.751558 -410.300326) (xy 82.715866 -410.259133) (xy 82.686399 -410.21328)
			(xy 82.663758 -410.1637) (xy 82.648402 -410.111403) (xy 82.640646 -410.057453) (xy 81.202989 -410.057453)
			(xy 81.195235 -410.111387) (xy 81.179883 -410.163674) (xy 81.157247 -410.213245) (xy 81.127786 -410.259089)
			(xy 81.092102 -410.300275) (xy 81.05092 -410.335964) (xy 81.005078 -410.365428) (xy 80.95551 -410.38807)
			(xy 80.903224 -410.403427) (xy 80.849285 -410.411187) (xy 80.822038 -410.411676) (xy 79.958438 -410.411676)
			(xy 79.931181 -410.41128) (xy 79.877221 -410.403526) (xy 79.824915 -410.388172) (xy 79.775325 -410.36553)
			(xy 79.729464 -410.336061) (xy 79.688263 -410.300364) (xy 79.652562 -410.259167) (xy 79.623088 -410.213308)
			(xy 79.600441 -410.163721) (xy 79.585082 -410.111416) (xy 79.577323 -410.057457) (xy 78.139812 -410.057457)
			(xy 78.132056 -410.111397) (xy 78.116702 -410.163691) (xy 78.094061 -410.213267) (xy 78.064595 -410.259116)
			(xy 78.028904 -410.300306) (xy 77.987715 -410.335996) (xy 77.941865 -410.365462) (xy 77.892289 -410.388102)
			(xy 77.839995 -410.403457) (xy 77.786049 -410.411213) (xy 77.758798 -410.411676) (xy 76.895198 -410.411676)
			(xy 76.867945 -410.411254) (xy 76.813993 -410.403497) (xy 76.761694 -410.38814) (xy 76.712113 -410.365497)
			(xy 76.666259 -410.336028) (xy 76.625065 -410.300334) (xy 76.589371 -410.25914) (xy 76.559902 -410.213286)
			(xy 76.537259 -410.163705) (xy 76.521903 -410.111406) (xy 76.514146 -410.057453) (xy 75.076613 -410.057453)
			(xy 75.068855 -410.111403) (xy 75.053498 -410.163699) (xy 75.030855 -410.213278) (xy 75.001385 -410.259129)
			(xy 74.96569 -410.30032) (xy 74.924496 -410.33601) (xy 74.878641 -410.365475) (xy 74.82906 -410.388113)
			(xy 74.776761 -410.403464) (xy 74.722811 -410.411216) (xy 74.695558 -410.411676) (xy 73.831958 -410.411676)
			(xy 73.804706 -410.411251) (xy 73.750759 -410.403489) (xy 73.698465 -410.388129) (xy 73.648889 -410.365484)
			(xy 73.60304 -410.336014) (xy 73.561851 -410.300319) (xy 73.526161 -410.259127) (xy 73.496696 -410.213275)
			(xy 73.474056 -410.163696) (xy 73.458702 -410.1114) (xy 73.450946 -410.057452) (xy 72.013289 -410.057452)
			(xy 72.005534 -410.11139) (xy 71.990182 -410.163679) (xy 71.967544 -410.21325) (xy 71.938082 -410.259096)
			(xy 71.902395 -410.300282) (xy 71.86121 -410.335971) (xy 71.815366 -410.365435) (xy 71.765795 -410.388075)
			(xy 71.713507 -410.403431) (xy 71.659566 -410.411189) (xy 71.632318 -410.411676) (xy 70.768718 -410.411676)
			(xy 70.741462 -410.411278) (xy 70.687505 -410.403523) (xy 70.6352 -410.388167) (xy 70.585613 -410.365524)
			(xy 70.539754 -410.336054) (xy 70.498556 -410.300357) (xy 70.462857 -410.25916) (xy 70.433385 -410.213302)
			(xy 70.410739 -410.163717) (xy 70.395381 -410.111413) (xy 70.387623 -410.057456) (xy 68.950112 -410.057456)
			(xy 68.942356 -410.1114) (xy 68.927 -410.163695) (xy 68.904358 -410.213273) (xy 68.87489 -410.259123)
			(xy 68.839197 -410.300313) (xy 68.798005 -410.336003) (xy 68.752153 -410.365468) (xy 68.702574 -410.388108)
			(xy 68.650278 -410.40346) (xy 68.59633 -410.411214) (xy 68.569078 -410.411676) (xy 67.705478 -410.411676)
			(xy 67.678225 -410.411253) (xy 67.624276 -410.403493) (xy 67.571979 -410.388135) (xy 67.522401 -410.36549)
			(xy 67.476549 -410.336021) (xy 67.435358 -410.300326) (xy 67.399666 -410.259133) (xy 67.370199 -410.21328)
			(xy 67.347558 -410.1637) (xy 67.332202 -410.111403) (xy 67.324446 -410.057453) (xy 65.886789 -410.057453)
			(xy 65.879035 -410.111387) (xy 65.863683 -410.163674) (xy 65.841047 -410.213245) (xy 65.811586 -410.259089)
			(xy 65.775902 -410.300275) (xy 65.73472 -410.335964) (xy 65.688878 -410.365428) (xy 65.63931 -410.38807)
			(xy 65.587024 -410.403427) (xy 65.533085 -410.411187) (xy 65.505838 -410.411676) (xy 64.642238 -410.411676)
			(xy 64.614981 -410.41128) (xy 64.561021 -410.403526) (xy 64.508715 -410.388172) (xy 64.459125 -410.36553)
			(xy 64.413264 -410.336061) (xy 64.372063 -410.300364) (xy 64.336362 -410.259167) (xy 64.306888 -410.213308)
			(xy 64.284241 -410.163721) (xy 64.268882 -410.111416) (xy 64.261123 -410.057457) (xy 62.823612 -410.057457)
			(xy 62.815856 -410.111397) (xy 62.800502 -410.163691) (xy 62.777861 -410.213267) (xy 62.748395 -410.259116)
			(xy 62.712704 -410.300306) (xy 62.671515 -410.335996) (xy 62.625665 -410.365462) (xy 62.576089 -410.388102)
			(xy 62.523795 -410.403457) (xy 62.469849 -410.411213) (xy 62.442598 -410.411676) (xy 61.578998 -410.411676)
			(xy 61.551745 -410.411254) (xy 61.497793 -410.403497) (xy 61.445494 -410.38814) (xy 61.395913 -410.365497)
			(xy 61.350059 -410.336028) (xy 61.308865 -410.300334) (xy 61.273171 -410.25914) (xy 61.243702 -410.213286)
			(xy 61.221059 -410.163705) (xy 61.205703 -410.111406) (xy 61.197946 -410.057453) (xy 59.760413 -410.057453)
			(xy 59.752655 -410.111403) (xy 59.737298 -410.163699) (xy 59.714655 -410.213278) (xy 59.685185 -410.259129)
			(xy 59.64949 -410.30032) (xy 59.608296 -410.33601) (xy 59.562441 -410.365475) (xy 59.51286 -410.388113)
			(xy 59.460561 -410.403464) (xy 59.406611 -410.411216) (xy 59.379358 -410.411676) (xy 58.515758 -410.411676)
			(xy 58.488506 -410.411251) (xy 58.434559 -410.403489) (xy 58.382265 -410.388129) (xy 58.332689 -410.365484)
			(xy 58.28684 -410.336014) (xy 58.245651 -410.300319) (xy 58.209961 -410.259127) (xy 58.180496 -410.213275)
			(xy 58.157856 -410.163696) (xy 58.142502 -410.1114) (xy 58.134746 -410.057452) (xy 56.697089 -410.057452)
			(xy 56.689334 -410.11139) (xy 56.673982 -410.163679) (xy 56.651344 -410.21325) (xy 56.621882 -410.259096)
			(xy 56.586195 -410.300282) (xy 56.54501 -410.335971) (xy 56.499166 -410.365435) (xy 56.449595 -410.388075)
			(xy 56.397307 -410.403431) (xy 56.343366 -410.411189) (xy 56.316118 -410.411676) (xy 55.452518 -410.411676)
			(xy 55.425262 -410.411278) (xy 55.371305 -410.403523) (xy 55.319 -410.388167) (xy 55.269413 -410.365524)
			(xy 55.223554 -410.336054) (xy 55.182356 -410.300357) (xy 55.146657 -410.25916) (xy 55.117185 -410.213302)
			(xy 55.094539 -410.163717) (xy 55.079181 -410.111413) (xy 55.071423 -410.057456) (xy 53.633912 -410.057456)
			(xy 53.626156 -410.1114) (xy 53.6108 -410.163695) (xy 53.588158 -410.213273) (xy 53.55869 -410.259123)
			(xy 53.522997 -410.300313) (xy 53.481805 -410.336003) (xy 53.435953 -410.365468) (xy 53.386374 -410.388108)
			(xy 53.334078 -410.40346) (xy 53.28013 -410.411214) (xy 53.252878 -410.411676) (xy 52.389278 -410.411676)
			(xy 52.362025 -410.411253) (xy 52.308076 -410.403493) (xy 52.255779 -410.388135) (xy 52.206201 -410.36549)
			(xy 52.160349 -410.336021) (xy 52.119158 -410.300326) (xy 52.083466 -410.259133) (xy 52.053999 -410.21328)
			(xy 52.031358 -410.1637) (xy 52.016002 -410.111403) (xy 52.008246 -410.057453) (xy 50.570589 -410.057453)
			(xy 50.562835 -410.111387) (xy 50.547483 -410.163674) (xy 50.524847 -410.213245) (xy 50.495386 -410.259089)
			(xy 50.459702 -410.300275) (xy 50.41852 -410.335964) (xy 50.372678 -410.365428) (xy 50.32311 -410.38807)
			(xy 50.270824 -410.403427) (xy 50.216885 -410.411187) (xy 50.189638 -410.411676) (xy 49.326038 -410.411676)
			(xy 49.298781 -410.41128) (xy 49.244821 -410.403526) (xy 49.192515 -410.388172) (xy 49.142925 -410.36553)
			(xy 49.097064 -410.336061) (xy 49.055863 -410.300364) (xy 49.020162 -410.259167) (xy 48.990688 -410.213308)
			(xy 48.968041 -410.163721) (xy 48.952682 -410.111416) (xy 48.944923 -410.057457) (xy 7.00913 -410.057457)
			(xy 7.00913 -411.241049) (xy 101.876886 -411.241049) (xy 101.876886 -411.186551) (xy 101.884641 -411.132608)
			(xy 101.899994 -411.080318) (xy 101.922631 -411.030744) (xy 101.952093 -410.984897) (xy 101.98778 -410.943708)
			(xy 102.028964 -410.908017) (xy 102.074809 -410.878551) (xy 102.12438 -410.855908) (xy 102.176669 -410.840549)
			(xy 102.230611 -410.832788) (xy 102.25786 -410.8323) (xy 103.12146 -410.8323) (xy 103.148715 -410.832745)
			(xy 103.202672 -410.840497) (xy 103.254975 -410.85585) (xy 103.304562 -410.878491) (xy 103.350421 -410.907958)
			(xy 103.391619 -410.943653) (xy 103.427318 -410.984847) (xy 103.45679 -411.030703) (xy 103.479436 -411.080287)
			(xy 103.494794 -411.132589) (xy 103.502553 -411.186545) (xy 103.502553 -411.241055) (xy 103.494794 -411.295011)
			(xy 103.479436 -411.347313) (xy 103.45679 -411.396897) (xy 103.427318 -411.442753) (xy 103.391619 -411.483947)
			(xy 103.350421 -411.519642) (xy 103.304562 -411.549109) (xy 103.254975 -411.57175) (xy 103.202672 -411.587103)
			(xy 103.148715 -411.594855) (xy 103.12146 -411.595316) (xy 102.25786 -411.595316) (xy 102.230611 -411.594812)
			(xy 102.176669 -411.587051) (xy 102.12438 -411.571692) (xy 102.074809 -411.549049) (xy 102.028964 -411.519583)
			(xy 101.98778 -411.483892) (xy 101.952093 -411.442703) (xy 101.922631 -411.396856) (xy 101.899994 -411.347282)
			(xy 101.884641 -411.294992) (xy 101.876886 -411.241049) (xy 7.00913 -411.241049) (xy 7.00913 -424.470068)
			(xy 39.528496 -424.470068) (xy 39.528496 -417.770056) (xy 39.529001 -417.664532) (xy 39.537085 -417.453638)
			(xy 39.553241 -417.243209) (xy 39.577444 -417.033552) (xy 39.609661 -416.824977) (xy 39.649843 -416.617789)
			(xy 39.697931 -416.412292) (xy 39.753855 -416.208788) (xy 39.817532 -416.007575) (xy 39.88887 -415.808948)
			(xy 39.967764 -415.6132) (xy 40.054097 -415.420618) (xy 40.147744 -415.231483) (xy 40.248566 -415.046074)
			(xy 40.356416 -414.864663) (xy 40.471135 -414.687516) (xy 40.592555 -414.514894) (xy 40.720498 -414.347048)
			(xy 40.854776 -414.184226) (xy 40.995192 -414.026667) (xy 41.14154 -413.874602) (xy 41.293605 -413.728254)
			(xy 41.451164 -413.587838) (xy 41.613986 -413.45356) (xy 41.781832 -413.325617) (xy 41.954454 -413.204197)
			(xy 42.131601 -413.089478) (xy 42.313012 -412.981628) (xy 42.498421 -412.880806) (xy 42.687556 -412.787159)
			(xy 42.880138 -412.700826) (xy 43.075886 -412.621932) (xy 43.274513 -412.550594) (xy 43.475726 -412.486917)
			(xy 43.67923 -412.430993) (xy 43.884727 -412.382905) (xy 44.091915 -412.342723) (xy 44.30049 -412.310506)
			(xy 44.510147 -412.286303) (xy 44.720576 -412.270147) (xy 44.93147 -412.262063) (xy 45.142518 -412.262063)
			(xy 45.353412 -412.270147) (xy 45.563841 -412.286303) (xy 45.773498 -412.310506) (xy 45.982073 -412.342723)
			(xy 46.189261 -412.382905) (xy 46.394758 -412.430993) (xy 46.598262 -412.486917) (xy 46.799475 -412.550594)
			(xy 46.998102 -412.621932) (xy 47.19385 -412.700826) (xy 47.386432 -412.787159) (xy 47.575567 -412.880806)
			(xy 47.760976 -412.981628) (xy 47.942387 -413.089478) (xy 48.119534 -413.204197) (xy 48.292156 -413.325617)
			(xy 48.460002 -413.45356) (xy 48.622824 -413.587838) (xy 48.649451 -413.611568) (xy 104.877616 -413.611568)
			(xy 104.877616 -412.747968) (xy 104.878102 -412.720717) (xy 104.885858 -412.666769) (xy 104.901213 -412.614474)
			(xy 104.923855 -412.564897) (xy 104.953321 -412.519047) (xy 104.989012 -412.477856) (xy 105.030203 -412.442165)
			(xy 105.076053 -412.412699) (xy 105.12563 -412.390057) (xy 105.177925 -412.374702) (xy 105.231873 -412.366946)
			(xy 105.286375 -412.366946) (xy 105.340323 -412.374702) (xy 105.392618 -412.390057) (xy 105.442195 -412.412699)
			(xy 105.488045 -412.442165) (xy 105.529236 -412.477856) (xy 105.564927 -412.519047) (xy 105.594393 -412.564897)
			(xy 105.617035 -412.614474) (xy 105.63239 -412.666769) (xy 105.640146 -412.720717) (xy 105.640632 -412.747968)
			(xy 105.640632 -413.611568) (xy 105.640146 -413.638819) (xy 105.63239 -413.692767) (xy 105.617035 -413.745062)
			(xy 105.594393 -413.794639) (xy 105.584722 -413.809688) (xy 116.689632 -413.809688) (xy 116.689632 -412.946088)
			(xy 116.690118 -412.918837) (xy 116.697874 -412.864889) (xy 116.713229 -412.812594) (xy 116.735871 -412.763017)
			(xy 116.765337 -412.717167) (xy 116.801028 -412.675976) (xy 116.842219 -412.640285) (xy 116.888069 -412.610819)
			(xy 116.937646 -412.588177) (xy 116.989941 -412.572822) (xy 117.043889 -412.565066) (xy 117.098391 -412.565066)
			(xy 117.152339 -412.572822) (xy 117.204634 -412.588177) (xy 117.254211 -412.610819) (xy 117.300061 -412.640285)
			(xy 117.341252 -412.675976) (xy 117.376943 -412.717167) (xy 117.406409 -412.763017) (xy 117.429051 -412.812594)
			(xy 117.444406 -412.864889) (xy 117.452162 -412.918837) (xy 117.452648 -412.946088) (xy 117.452648 -413.809688)
			(xy 117.452162 -413.836939) (xy 117.444406 -413.890887) (xy 117.429051 -413.943182) (xy 117.406409 -413.992759)
			(xy 117.376943 -414.038609) (xy 117.341252 -414.0798) (xy 117.300061 -414.115491) (xy 117.254211 -414.144957)
			(xy 117.204634 -414.167599) (xy 117.152339 -414.182954) (xy 117.098391 -414.19071) (xy 117.043889 -414.19071)
			(xy 116.989941 -414.182954) (xy 116.937646 -414.167599) (xy 116.888069 -414.144957) (xy 116.842219 -414.115491)
			(xy 116.801028 -414.0798) (xy 116.765337 -414.038609) (xy 116.735871 -413.992759) (xy 116.713229 -413.943182)
			(xy 116.697874 -413.890887) (xy 116.690118 -413.836939) (xy 116.689632 -413.809688) (xy 105.584722 -413.809688)
			(xy 105.564927 -413.840489) (xy 105.529236 -413.88168) (xy 105.488045 -413.917371) (xy 105.442195 -413.946837)
			(xy 105.392618 -413.969479) (xy 105.340323 -413.984834) (xy 105.286375 -413.99259) (xy 105.231873 -413.99259)
			(xy 105.177925 -413.984834) (xy 105.12563 -413.969479) (xy 105.076053 -413.946837) (xy 105.030203 -413.917371)
			(xy 104.989012 -413.88168) (xy 104.953321 -413.840489) (xy 104.923855 -413.794639) (xy 104.901213 -413.745062)
			(xy 104.885858 -413.692767) (xy 104.878102 -413.638819) (xy 104.877616 -413.611568) (xy 48.649451 -413.611568)
			(xy 48.780383 -413.728254) (xy 48.932448 -413.874602) (xy 49.078796 -414.026667) (xy 49.219212 -414.184226)
			(xy 49.35349 -414.347048) (xy 49.481433 -414.514894) (xy 49.602853 -414.687516) (xy 49.717572 -414.864663)
			(xy 49.825422 -415.046074) (xy 49.926244 -415.231483) (xy 50.019891 -415.420618) (xy 50.106224 -415.6132)
			(xy 50.133819 -415.681668) (xy 100.559616 -415.681668) (xy 100.559616 -414.818068) (xy 100.560102 -414.790817)
			(xy 100.567858 -414.736869) (xy 100.583213 -414.684574) (xy 100.605855 -414.634997) (xy 100.635321 -414.589147)
			(xy 100.671012 -414.547956) (xy 100.712203 -414.512265) (xy 100.758053 -414.482799) (xy 100.80763 -414.460157)
			(xy 100.859925 -414.444802) (xy 100.913873 -414.437046) (xy 100.968375 -414.437046) (xy 101.022323 -414.444802)
			(xy 101.074618 -414.460157) (xy 101.124195 -414.482799) (xy 101.170045 -414.512265) (xy 101.211236 -414.547956)
			(xy 101.246927 -414.589147) (xy 101.276393 -414.634997) (xy 101.299035 -414.684574) (xy 101.31439 -414.736869)
			(xy 101.322146 -414.790817) (xy 101.322632 -414.818068) (xy 101.322632 -415.681668) (xy 101.322146 -415.708919)
			(xy 101.31439 -415.762867) (xy 101.299035 -415.815162) (xy 101.276393 -415.864739) (xy 101.246927 -415.910589)
			(xy 101.211236 -415.95178) (xy 101.170045 -415.987471) (xy 101.124195 -416.016937) (xy 101.074618 -416.039579)
			(xy 101.022323 -416.054934) (xy 100.968375 -416.06269) (xy 100.913873 -416.06269) (xy 100.859925 -416.054934)
			(xy 100.80763 -416.039579) (xy 100.758053 -416.016937) (xy 100.712203 -415.987471) (xy 100.671012 -415.95178)
			(xy 100.635321 -415.910589) (xy 100.605855 -415.864739) (xy 100.583213 -415.815162) (xy 100.567858 -415.762867)
			(xy 100.560102 -415.708919) (xy 100.559616 -415.681668) (xy 50.133819 -415.681668) (xy 50.185118 -415.808948)
			(xy 50.256456 -416.007575) (xy 50.320133 -416.208788) (xy 50.376057 -416.412292) (xy 50.424145 -416.617789)
			(xy 50.464327 -416.824977) (xy 50.496544 -417.033552) (xy 50.520747 -417.243209) (xy 50.536903 -417.453638)
			(xy 50.544987 -417.664532) (xy 50.545492 -417.770056) (xy 50.545492 -420.089838) (xy 58.13806 -420.089838)
			(xy 58.138171 -420.074752) (xy 58.139951 -420.044634) (xy 58.141616 -420.02964) (xy 58.141616 -418.95014)
			(xy 58.139949 -418.935146) (xy 58.138169 -418.905028) (xy 58.13806 -418.889942) (xy 58.138171 -418.874856)
			(xy 58.139951 -418.844738) (xy 58.141616 -418.829744) (xy 58.141616 -418.218874) (xy 58.142085 -418.206785)
			(xy 58.149546 -418.183788) (xy 58.163733 -418.164211) (xy 58.183264 -418.14996) (xy 58.206237 -418.142424)
			(xy 58.218324 -418.141912) (xy 59.158124 -418.141912) (xy 59.170235 -418.142296) (xy 59.193265 -418.149803)
			(xy 59.212839 -418.164073) (xy 59.227033 -418.183702) (xy 59.234451 -418.206761) (xy 59.234832 -418.218874)
			(xy 59.234832 -420.760398) (xy 59.23439 -420.77249) (xy 59.226931 -420.795495) (xy 59.212739 -420.815078)
			(xy 59.193198 -420.829327) (xy 59.170215 -420.836854) (xy 59.158124 -420.83736) (xy 58.218324 -420.83736)
			(xy 58.206212 -420.836963) (xy 58.183179 -420.829465) (xy 58.163602 -420.8152) (xy 58.149408 -420.795571)
			(xy 58.141994 -420.772511) (xy 58.141616 -420.760398) (xy 58.141616 -420.150036) (xy 58.139948 -420.135042)
			(xy 58.138169 -420.104924) (xy 58.13806 -420.089838) (xy 50.545492 -420.089838) (xy 50.545492 -421.089836)
			(xy 60.138056 -421.089836) (xy 60.138167 -421.07475) (xy 60.139947 -421.044632) (xy 60.141612 -421.029638)
			(xy 60.141612 -419.950138) (xy 60.139945 -419.935144) (xy 60.138165 -419.905026) (xy 60.138056 -419.88994)
			(xy 60.138167 -419.874854) (xy 60.139947 -419.844736) (xy 60.141612 -419.829742) (xy 60.141612 -419.218872)
			(xy 60.14204 -419.206794) (xy 60.149513 -419.183822) (xy 60.163718 -419.164284) (xy 60.183265 -419.150091)
			(xy 60.206242 -419.142633) (xy 60.21832 -419.142164) (xy 61.15812 -419.142164) (xy 61.170193 -419.142647)
			(xy 61.193156 -419.150112) (xy 61.21269 -419.164304) (xy 61.226885 -419.183837) (xy 61.234352 -419.206799)
			(xy 61.234828 -419.218872) (xy 61.234828 -421.089836) (xy 68.13804 -421.089836) (xy 68.138151 -421.07475)
			(xy 68.139931 -421.044632) (xy 68.141596 -421.029638) (xy 68.141596 -419.950138) (xy 68.139929 -419.935144)
			(xy 68.138149 -419.905026) (xy 68.13804 -419.88994) (xy 68.138151 -419.874854) (xy 68.139931 -419.844736)
			(xy 68.141596 -419.829742) (xy 68.141596 -419.218872) (xy 68.14204 -419.206796) (xy 68.149511 -419.183827)
			(xy 68.163712 -419.16429) (xy 68.183255 -419.150096) (xy 68.206227 -419.142635) (xy 68.218304 -419.142164)
			(xy 69.158104 -419.142164) (xy 69.170176 -419.14266) (xy 69.193139 -419.150121) (xy 69.212673 -419.16431)
			(xy 69.226868 -419.18384) (xy 69.234336 -419.2068) (xy 69.234812 -419.218872) (xy 69.234812 -420.089838)
			(xy 70.138036 -420.089838) (xy 70.138149 -420.074753) (xy 70.139929 -420.044634) (xy 70.141592 -420.02964)
			(xy 70.141592 -418.95014) (xy 70.139925 -418.935146) (xy 70.138145 -418.905028) (xy 70.138036 -418.889942)
			(xy 70.13815 -418.874857) (xy 70.139929 -418.844738) (xy 70.141592 -418.829744) (xy 70.141592 -418.218874)
			(xy 70.142084 -418.206788) (xy 70.149542 -418.183794) (xy 70.163724 -418.164219) (xy 70.183249 -418.149968)
			(xy 70.206216 -418.142428) (xy 70.2183 -418.141912) (xy 71.1581 -418.141912) (xy 71.17021 -418.142316)
			(xy 71.193239 -418.149817) (xy 71.212814 -418.164081) (xy 71.227008 -418.183706) (xy 71.234426 -418.206762)
			(xy 71.234808 -418.218874) (xy 71.234808 -420.760398) (xy 71.234292 -420.772483) (xy 71.226841 -420.795475)
			(xy 71.212666 -420.815051) (xy 71.193146 -420.829303) (xy 71.170183 -420.836844) (xy 71.1581 -420.83736)
			(xy 70.2183 -420.83736) (xy 70.206187 -420.836983) (xy 70.183153 -420.829479) (xy 70.163576 -420.815209)
			(xy 70.149383 -420.795576) (xy 70.14197 -420.772512) (xy 70.141592 -420.760398) (xy 70.141592 -420.150036)
			(xy 70.139924 -420.135042) (xy 70.138145 -420.104924) (xy 70.138036 -420.089838) (xy 69.234812 -420.089838)
			(xy 69.234812 -421.089836) (xy 72.138032 -421.089836) (xy 72.138145 -421.074751) (xy 72.139925 -421.044632)
			(xy 72.141588 -421.029638) (xy 72.141588 -419.950138) (xy 72.13992 -419.935144) (xy 72.138141 -419.905026)
			(xy 72.138032 -419.88994) (xy 72.138145 -419.874855) (xy 72.139925 -419.844736) (xy 72.141588 -419.829742)
			(xy 72.141588 -419.218872) (xy 72.14204 -419.206796) (xy 72.14951 -419.183829) (xy 72.16371 -419.164293)
			(xy 72.18325 -419.150099) (xy 72.20622 -419.142636) (xy 72.218296 -419.142164) (xy 73.158096 -419.142164)
			(xy 73.170168 -419.142667) (xy 73.19313 -419.150125) (xy 73.212665 -419.164313) (xy 73.22686 -419.183841)
			(xy 73.234328 -419.206801) (xy 73.234804 -419.218872) (xy 73.234804 -419.702852) (xy 110.957342 -419.702852)
			(xy 110.957342 -419.648348) (xy 110.965098 -419.594399) (xy 110.980453 -419.542102) (xy 111.003093 -419.492523)
			(xy 111.032558 -419.44667) (xy 111.068249 -419.405477) (xy 111.109438 -419.369782) (xy 111.155288 -419.340312)
			(xy 111.204865 -419.317667) (xy 111.25716 -419.302306) (xy 111.311108 -419.294545) (xy 111.33836 -419.294056)
			(xy 112.20196 -419.294056) (xy 112.229212 -419.294589) (xy 112.283162 -419.30234) (xy 112.33546 -419.317691)
			(xy 112.385041 -419.340329) (xy 112.430894 -419.369793) (xy 112.472088 -419.405484) (xy 112.507783 -419.446674)
			(xy 112.537251 -419.492524) (xy 112.559895 -419.542102) (xy 112.575251 -419.594399) (xy 112.583009 -419.648348)
			(xy 112.583009 -419.702852) (xy 112.575251 -419.756801) (xy 112.559895 -419.809098) (xy 112.537251 -419.858676)
			(xy 112.507783 -419.904526) (xy 112.472088 -419.945716) (xy 112.430894 -419.981407) (xy 112.385041 -420.010871)
			(xy 112.33546 -420.033509) (xy 112.283162 -420.04886) (xy 112.229212 -420.056611) (xy 112.20196 -420.057072)
			(xy 111.33836 -420.057072) (xy 111.311108 -420.056655) (xy 111.25716 -420.048894) (xy 111.204865 -420.033533)
			(xy 111.155288 -420.010888) (xy 111.109438 -419.981418) (xy 111.068249 -419.945723) (xy 111.032558 -419.90453)
			(xy 111.003093 -419.858677) (xy 110.980453 -419.809098) (xy 110.965098 -419.756801) (xy 110.957342 -419.702852)
			(xy 73.234804 -419.702852) (xy 73.234804 -421.760396) (xy 73.234384 -421.772479) (xy 73.226917 -421.795462)
			(xy 73.212713 -421.815013) (xy 73.193162 -421.829217) (xy 73.170179 -421.836684) (xy 73.158096 -421.837104)
			(xy 72.218296 -421.837104) (xy 72.206221 -421.836639) (xy 72.183253 -421.829175) (xy 72.163716 -421.814979)
			(xy 72.149521 -421.79544) (xy 72.14206 -421.772471) (xy 72.141588 -421.760396) (xy 72.141588 -421.150034)
			(xy 72.13992 -421.13504) (xy 72.138141 -421.104922) (xy 72.138032 -421.089836) (xy 69.234812 -421.089836)
			(xy 69.234812 -421.760396) (xy 69.234332 -421.77247) (xy 69.226871 -421.795436) (xy 69.212679 -421.814973)
			(xy 69.193143 -421.829168) (xy 69.170178 -421.836631) (xy 69.158104 -421.837104) (xy 68.218304 -421.837104)
			(xy 68.206221 -421.836684) (xy 68.183238 -421.829217) (xy 68.163687 -421.815013) (xy 68.149483 -421.795462)
			(xy 68.142016 -421.772479) (xy 68.141596 -421.760396) (xy 68.141596 -421.150034) (xy 68.139928 -421.13504)
			(xy 68.138149 -421.104922) (xy 68.13804 -421.089836) (xy 61.234828 -421.089836) (xy 61.234828 -421.760396)
			(xy 61.234333 -421.772468) (xy 61.226874 -421.795432) (xy 61.212684 -421.814967) (xy 61.193154 -421.829163)
			(xy 61.170192 -421.836629) (xy 61.15812 -421.837104) (xy 60.21832 -421.837104) (xy 60.206238 -421.83667)
			(xy 60.183255 -421.829208) (xy 60.163704 -421.815007) (xy 60.1495 -421.795459) (xy 60.142032 -421.772478)
			(xy 60.141612 -421.760396) (xy 60.141612 -421.150034) (xy 60.139944 -421.13504) (xy 60.138165 -421.104922)
			(xy 60.138056 -421.089836) (xy 50.545492 -421.089836) (xy 50.545492 -423.68978) (xy 58.13806 -423.68978)
			(xy 58.138175 -423.674695) (xy 58.139953 -423.644576) (xy 58.141616 -423.629582) (xy 58.141616 -422.550082)
			(xy 58.139952 -422.535088) (xy 58.138171 -422.50497) (xy 58.13806 -422.489884) (xy 58.138175 -422.474799)
			(xy 58.139953 -422.44468) (xy 58.141616 -422.429686) (xy 58.141616 -421.81907) (xy 58.142081 -421.806981)
			(xy 58.149543 -421.783984) (xy 58.163731 -421.764406) (xy 58.183263 -421.750156) (xy 58.206237 -421.74262)
			(xy 58.218324 -421.742108) (xy 59.158124 -421.742108) (xy 59.170235 -421.742496) (xy 59.193264 -421.750003)
			(xy 59.212838 -421.764272) (xy 59.227031 -421.783899) (xy 59.23445 -421.806958) (xy 59.234832 -421.81907)
			(xy 59.234832 -423.68978) (xy 62.138052 -423.68978) (xy 62.138167 -423.674695) (xy 62.139945 -423.644576)
			(xy 62.141608 -423.629582) (xy 62.141608 -422.550082) (xy 62.139944 -422.535088) (xy 62.138163 -422.50497)
			(xy 62.138052 -422.489884) (xy 62.138167 -422.474799) (xy 62.139945 -422.44468) (xy 62.141608 -422.429686)
			(xy 62.141608 -421.81907) (xy 62.142081 -421.806982) (xy 62.149542 -421.783986) (xy 62.163728 -421.764409)
			(xy 62.183258 -421.750158) (xy 62.20623 -421.742621) (xy 62.218316 -421.742108) (xy 63.158116 -421.742108)
			(xy 63.170227 -421.742503) (xy 63.193256 -421.750008) (xy 63.212829 -421.764274) (xy 63.227023 -421.783901)
			(xy 63.234442 -421.806958) (xy 63.234824 -421.81907) (xy 63.234824 -424.360594) (xy 63.234387 -424.372687)
			(xy 63.226927 -424.395693) (xy 63.212734 -424.415276) (xy 63.193192 -424.429526) (xy 63.170207 -424.437051)
			(xy 63.158116 -424.437556) (xy 62.218316 -424.437556) (xy 62.206214 -424.437071) (xy 62.183196 -424.429582)
			(xy 62.163628 -424.415337) (xy 62.149431 -424.395733) (xy 62.142 -424.372697) (xy 62.141608 -424.360594)
			(xy 62.141608 -423.749978) (xy 62.139944 -423.734984) (xy 62.138162 -423.704866) (xy 62.138052 -423.68978)
			(xy 59.234832 -423.68978) (xy 59.234832 -424.360594) (xy 59.234387 -424.372686) (xy 59.226928 -424.395691)
			(xy 59.212737 -424.415274) (xy 59.193197 -424.429523) (xy 59.170215 -424.43705) (xy 59.158124 -424.437556)
			(xy 58.218324 -424.437556) (xy 58.206222 -424.437064) (xy 58.183205 -424.429578) (xy 58.163637 -424.415334)
			(xy 58.149439 -424.395732) (xy 58.142008 -424.372697) (xy 58.141616 -424.360594) (xy 58.141616 -423.749978)
			(xy 58.139952 -423.734984) (xy 58.13817 -423.704866) (xy 58.13806 -423.68978) (xy 50.545492 -423.68978)
			(xy 50.545492 -424.470068) (xy 50.544987 -424.575592) (xy 50.54061 -424.689778) (xy 64.138048 -424.689778)
			(xy 64.138163 -424.674693) (xy 64.139941 -424.644574) (xy 64.141604 -424.62958) (xy 64.141604 -423.55008)
			(xy 64.13994 -423.535086) (xy 64.138158 -423.504968) (xy 64.138048 -423.489882) (xy 64.138163 -423.474797)
			(xy 64.139941 -423.444678) (xy 64.141604 -423.429684) (xy 64.141604 -422.819068) (xy 64.142037 -422.806991)
			(xy 64.14951 -422.78402) (xy 64.163714 -422.764483) (xy 64.18326 -422.75029) (xy 64.206234 -422.74283)
			(xy 64.218312 -422.74236) (xy 65.158112 -422.74236) (xy 65.170184 -422.742854) (xy 65.193146 -422.750316)
			(xy 65.21268 -422.764506) (xy 65.226875 -422.784036) (xy 65.234343 -422.806996) (xy 65.23482 -422.819068)
			(xy 65.23482 -424.689778) (xy 68.13804 -424.689778) (xy 68.138155 -424.674693) (xy 68.139933 -424.644574)
			(xy 68.141596 -424.62958) (xy 68.141596 -423.55008) (xy 68.139932 -423.535086) (xy 68.13815 -423.504968)
			(xy 68.13804 -423.489882) (xy 68.138155 -423.474797) (xy 68.139933 -423.444678) (xy 68.141596 -423.429684)
			(xy 68.141596 -422.819068) (xy 68.142037 -422.806991) (xy 68.149509 -422.784022) (xy 68.163711 -422.764485)
			(xy 68.183255 -422.750292) (xy 68.206227 -422.742831) (xy 68.218304 -422.74236) (xy 69.158104 -422.74236)
			(xy 69.170176 -422.74286) (xy 69.193137 -422.75032) (xy 69.212672 -422.764508) (xy 69.226867 -422.784037)
			(xy 69.234335 -422.806997) (xy 69.234812 -422.819068) (xy 69.234812 -423.68978) (xy 70.138036 -423.68978)
			(xy 70.138153 -423.674695) (xy 70.139931 -423.644576) (xy 70.141592 -423.629582) (xy 70.141592 -422.550082)
			(xy 70.139928 -422.535088) (xy 70.138147 -422.50497) (xy 70.138036 -422.489884) (xy 70.138153 -422.474799)
			(xy 70.139931 -422.44468) (xy 70.141592 -422.429686) (xy 70.141592 -421.81907) (xy 70.142081 -421.806984)
			(xy 70.14954 -421.78399) (xy 70.163723 -421.764415) (xy 70.183248 -421.750163) (xy 70.206215 -421.742624)
			(xy 70.2183 -421.742108) (xy 71.1581 -421.742108) (xy 71.17021 -421.742516) (xy 71.193238 -421.750017)
			(xy 71.212812 -421.76428) (xy 71.227007 -421.783904) (xy 71.234426 -421.806959) (xy 71.234808 -421.81907)
			(xy 71.234808 -424.360594) (xy 71.234288 -424.372678) (xy 71.226839 -424.395671) (xy 71.212664 -424.415247)
			(xy 71.193145 -424.429499) (xy 71.170183 -424.43704) (xy 71.1581 -424.437556) (xy 70.2183 -424.437556)
			(xy 70.206197 -424.437085) (xy 70.183179 -424.429592) (xy 70.163611 -424.415343) (xy 70.149414 -424.395736)
			(xy 70.141983 -424.372698) (xy 70.141592 -424.360594) (xy 70.141592 -423.749978) (xy 70.139928 -423.734984)
			(xy 70.138146 -423.704866) (xy 70.138036 -423.68978) (xy 69.234812 -423.68978) (xy 69.234812 -424.689778)
			(xy 72.138032 -424.689778) (xy 72.138149 -424.674693) (xy 72.139927 -424.644574) (xy 72.141588 -424.62958)
			(xy 72.141588 -423.55008) (xy 72.139924 -423.535086) (xy 72.138142 -423.504968) (xy 72.138032 -423.489882)
			(xy 72.138149 -423.474797) (xy 72.139927 -423.444678) (xy 72.141588 -423.429684) (xy 72.141588 -422.819068)
			(xy 72.142037 -422.806992) (xy 72.149508 -422.784025) (xy 72.163708 -422.764488) (xy 72.18325 -422.750295)
			(xy 72.20622 -422.742832) (xy 72.218296 -422.74236) (xy 73.158096 -422.74236) (xy 73.170167 -422.742867)
			(xy 73.193129 -422.750325) (xy 73.212663 -422.764511) (xy 73.226859 -422.784039) (xy 73.234327 -422.806997)
			(xy 73.234804 -422.819068) (xy 73.234804 -424.80464) (xy 109.929157 -424.80464) (xy 109.929157 -424.6755)
			(xy 109.937107 -424.546605) (xy 109.952977 -424.418445) (xy 109.976706 -424.291504) (xy 110.008205 -424.166265)
			(xy 110.047354 -424.043202) (xy 110.094005 -423.922783) (xy 110.14798 -423.805464) (xy 110.209075 -423.69169)
			(xy 110.277058 -423.581893) (xy 110.351672 -423.47649) (xy 110.432633 -423.37588) (xy 110.519633 -423.280445)
			(xy 110.612344 -423.190546) (xy 110.710414 -423.106525) (xy 110.813469 -423.028701) (xy 110.92112 -422.957369)
			(xy 111.032959 -422.892799) (xy 111.14856 -422.835237) (xy 111.267485 -422.7849) (xy 111.389284 -422.74198)
			(xy 111.513494 -422.706639) (xy 111.639643 -422.679012) (xy 111.767255 -422.659203) (xy 111.895844 -422.647287)
			(xy 112.024922 -422.643311) (xy 112.154 -422.647287) (xy 112.282589 -422.659203) (xy 112.410201 -422.679012)
			(xy 112.53635 -422.706639) (xy 112.66056 -422.74198) (xy 112.782359 -422.7849) (xy 112.901284 -422.835237)
			(xy 113.016885 -422.892799) (xy 113.128724 -422.957369) (xy 113.236375 -423.028701) (xy 113.33943 -423.106525)
			(xy 113.4375 -423.190546) (xy 113.530211 -423.280445) (xy 113.617211 -423.37588) (xy 113.698172 -423.47649)
			(xy 113.772786 -423.581893) (xy 113.840769 -423.69169) (xy 113.901864 -423.805464) (xy 113.955839 -423.922783)
			(xy 114.00249 -424.043202) (xy 114.041639 -424.166265) (xy 114.073138 -424.291504) (xy 114.096867 -424.418445)
			(xy 114.112737 -424.546605) (xy 114.120687 -424.6755) (xy 114.121184 -424.74007) (xy 114.120687 -424.80464)
			(xy 114.112737 -424.933535) (xy 114.096867 -425.061695) (xy 114.073138 -425.188636) (xy 114.041639 -425.313875)
			(xy 114.00249 -425.436938) (xy 113.955839 -425.557357) (xy 113.901864 -425.674676) (xy 113.840769 -425.78845)
			(xy 113.772786 -425.898247) (xy 113.698172 -426.00365) (xy 113.617211 -426.10426) (xy 113.530211 -426.199695)
			(xy 113.4375 -426.289594) (xy 113.33943 -426.373615) (xy 113.236375 -426.451439) (xy 113.128724 -426.522771)
			(xy 113.016885 -426.587341) (xy 112.901284 -426.644903) (xy 112.782359 -426.69524) (xy 112.66056 -426.73816)
			(xy 112.53635 -426.773501) (xy 112.410201 -426.801128) (xy 112.282589 -426.820937) (xy 112.154 -426.832853)
			(xy 112.024922 -426.83683) (xy 111.895844 -426.832853) (xy 111.767255 -426.820937) (xy 111.639643 -426.801128)
			(xy 111.513494 -426.773501) (xy 111.389284 -426.73816) (xy 111.267485 -426.69524) (xy 111.14856 -426.644903)
			(xy 111.032959 -426.587341) (xy 110.92112 -426.522771) (xy 110.813469 -426.451439) (xy 110.710414 -426.373615)
			(xy 110.612344 -426.289594) (xy 110.519633 -426.199695) (xy 110.432633 -426.10426) (xy 110.351672 -426.00365)
			(xy 110.277058 -425.898247) (xy 110.209075 -425.78845) (xy 110.14798 -425.674676) (xy 110.094005 -425.557357)
			(xy 110.047354 -425.436938) (xy 110.008205 -425.313875) (xy 109.976706 -425.188636) (xy 109.952977 -425.061695)
			(xy 109.937107 -424.933535) (xy 109.929157 -424.80464) (xy 73.234804 -424.80464) (xy 73.234804 -425.360592)
			(xy 73.234381 -425.372675) (xy 73.226915 -425.395658) (xy 73.212712 -425.415209) (xy 73.193162 -425.429413)
			(xy 73.170179 -425.43688) (xy 73.158096 -425.4373) (xy 72.218296 -425.4373) (xy 72.206212 -425.436891)
			(xy 72.183228 -425.429421) (xy 72.163677 -425.415214) (xy 72.149473 -425.395661) (xy 72.142007 -425.372676)
			(xy 72.141588 -425.360592) (xy 72.141588 -424.749976) (xy 72.139924 -424.734982) (xy 72.138142 -424.704864)
			(xy 72.138032 -424.689778) (xy 69.234812 -424.689778) (xy 69.234812 -425.360592) (xy 69.234381 -425.372674)
			(xy 69.226916 -425.395656) (xy 69.212714 -425.415206) (xy 69.193167 -425.429411) (xy 69.170186 -425.436879)
			(xy 69.158104 -425.4373) (xy 68.218304 -425.4373) (xy 68.206221 -425.436884) (xy 68.183237 -425.429417)
			(xy 68.163686 -425.415212) (xy 68.149482 -425.39566) (xy 68.142015 -425.372675) (xy 68.141596 -425.360592)
			(xy 68.141596 -424.749976) (xy 68.139932 -424.734982) (xy 68.13815 -424.704864) (xy 68.13804 -424.689778)
			(xy 65.23482 -424.689778) (xy 65.23482 -425.360592) (xy 65.234329 -425.372665) (xy 65.22687 -425.39563)
			(xy 65.21268 -425.415166) (xy 65.193148 -425.429361) (xy 65.170185 -425.436826) (xy 65.158112 -425.4373)
			(xy 64.218312 -425.4373) (xy 64.206229 -425.436877) (xy 64.183246 -425.429412) (xy 64.163694 -425.415208)
			(xy 64.14949 -425.395658) (xy 64.142024 -425.372675) (xy 64.141604 -425.360592) (xy 64.141604 -424.749976)
			(xy 64.13994 -424.734982) (xy 64.138158 -424.704864) (xy 64.138048 -424.689778) (xy 50.54061 -424.689778)
			(xy 50.536903 -424.786486) (xy 50.520747 -424.996915) (xy 50.496544 -425.206572) (xy 50.464327 -425.415147)
			(xy 50.424145 -425.622335) (xy 50.376057 -425.827832) (xy 50.320133 -426.031336) (xy 50.256456 -426.232549)
			(xy 50.185118 -426.431176) (xy 50.106224 -426.626924) (xy 50.019891 -426.819506) (xy 49.926244 -427.008641)
			(xy 49.825422 -427.19405) (xy 49.768393 -427.289976) (xy 58.13806 -427.289976) (xy 58.138174 -427.274891)
			(xy 58.139952 -427.244772) (xy 58.141616 -427.229778) (xy 58.141616 -426.150024) (xy 58.139947 -426.135031)
			(xy 58.138169 -426.104912) (xy 58.13806 -426.089826) (xy 58.13817 -426.07474) (xy 58.139951 -426.044622)
			(xy 58.141616 -426.029628) (xy 58.141616 -425.419012) (xy 58.142023 -425.406928) (xy 58.149491 -425.383941)
			(xy 58.163697 -425.364389) (xy 58.183252 -425.350185) (xy 58.206239 -425.342722) (xy 58.218324 -425.342304)
			(xy 59.158124 -425.342304) (xy 59.170201 -425.342744) (xy 59.193171 -425.350215) (xy 59.212709 -425.364417)
			(xy 59.226902 -425.383961) (xy 59.234361 -425.406935) (xy 59.234832 -425.419012) (xy 59.234832 -427.960536)
			(xy 59.234367 -427.97261) (xy 59.226898 -427.995574) (xy 59.2127 -428.015109) (xy 59.193164 -428.029303)
			(xy 59.170198 -428.036769) (xy 59.158124 -428.037244) (xy 58.218324 -428.037244) (xy 58.206254 -428.036716)
			(xy 58.183294 -428.029264) (xy 58.16376 -428.015083) (xy 58.149563 -427.99556) (xy 58.142093 -427.972605)
			(xy 58.141616 -427.960536) (xy 58.141616 -427.350174) (xy 58.139952 -427.33518) (xy 58.13817 -427.305062)
			(xy 58.13806 -427.289976) (xy 49.768393 -427.289976) (xy 49.717572 -427.375461) (xy 49.602853 -427.552608)
			(xy 49.481433 -427.72523) (xy 49.35349 -427.893076) (xy 49.219212 -428.055898) (xy 49.078796 -428.213457)
			(xy 49.0054 -428.28972) (xy 60.138056 -428.28972) (xy 60.138166 -428.274634) (xy 60.139947 -428.244516)
			(xy 60.141612 -428.229522) (xy 60.141612 -427.150022) (xy 60.139943 -427.135029) (xy 60.138165 -427.10491)
			(xy 60.138056 -427.089824) (xy 60.138166 -427.074738) (xy 60.139947 -427.04462) (xy 60.141612 -427.029626)
			(xy 60.141612 -426.41901) (xy 60.142115 -426.406924) (xy 60.149566 -426.383928) (xy 60.163744 -426.364351)
			(xy 60.183268 -426.350099) (xy 60.206236 -426.342562) (xy 60.21832 -426.342048) (xy 61.15812 -426.342048)
			(xy 61.170225 -426.342499) (xy 61.193244 -426.349997) (xy 61.212812 -426.364252) (xy 61.227008 -426.383863)
			(xy 61.234437 -426.406904) (xy 61.234828 -426.41901) (xy 61.234828 -427.289976) (xy 62.138052 -427.289976)
			(xy 62.138166 -427.274891) (xy 62.139944 -427.244772) (xy 62.141608 -427.229778) (xy 62.141608 -426.150024)
			(xy 62.139939 -426.135031) (xy 62.138161 -426.104912) (xy 62.138052 -426.089826) (xy 62.138162 -426.07474)
			(xy 62.139943 -426.044622) (xy 62.141608 -426.029628) (xy 62.141608 -425.419012) (xy 62.142023 -425.406928)
			(xy 62.149489 -425.383943) (xy 62.163694 -425.364392) (xy 62.183247 -425.350188) (xy 62.206232 -425.342723)
			(xy 62.218316 -425.342304) (xy 63.158116 -425.342304) (xy 63.170193 -425.342751) (xy 63.193162 -425.350219)
			(xy 63.2127 -425.36442) (xy 63.226894 -425.383963) (xy 63.234353 -425.406935) (xy 63.234824 -425.419012)
			(xy 63.234824 -427.960536) (xy 63.234367 -427.972611) (xy 63.226896 -427.995577) (xy 63.212697 -428.015112)
			(xy 63.193159 -428.029306) (xy 63.170191 -428.03677) (xy 63.158116 -428.037244) (xy 62.218316 -428.037244)
			(xy 62.206246 -428.036723) (xy 62.183285 -428.029269) (xy 62.163751 -428.015086) (xy 62.149555 -427.995561)
			(xy 62.142085 -427.972606) (xy 62.141608 -427.960536) (xy 62.141608 -427.350174) (xy 62.139944 -427.33518)
			(xy 62.138162 -427.305062) (xy 62.138052 -427.289976) (xy 61.234828 -427.289976) (xy 61.234828 -428.28972)
			(xy 64.138048 -428.28972) (xy 64.138158 -428.274634) (xy 64.139939 -428.244516) (xy 64.141604 -428.229522)
			(xy 64.141604 -427.150022) (xy 64.139935 -427.135029) (xy 64.138157 -427.10491) (xy 64.138048 -427.089824)
			(xy 64.138158 -427.074738) (xy 64.139939 -427.04462) (xy 64.141604 -427.029626) (xy 64.141604 -426.41901)
			(xy 64.142115 -426.406925) (xy 64.149565 -426.38393) (xy 64.163741 -426.364353) (xy 64.183263 -426.350101)
			(xy 64.206228 -426.342563) (xy 64.218312 -426.342048) (xy 65.158112 -426.342048) (xy 65.170216 -426.342505)
			(xy 65.193235 -426.350002) (xy 65.212804 -426.364255) (xy 65.227 -426.383864) (xy 65.234429 -426.406905)
			(xy 65.23482 -426.41901) (xy 65.23482 -427.289976) (xy 66.138044 -427.289976) (xy 66.138159 -427.274891)
			(xy 66.139936 -427.244772) (xy 66.1416 -427.229778) (xy 66.1416 -426.150024) (xy 66.139931 -426.135031)
			(xy 66.138153 -426.104912) (xy 66.138044 -426.089826) (xy 66.138154 -426.07474) (xy 66.139935 -426.044622)
			(xy 66.1416 -426.029628) (xy 66.1416 -425.419012) (xy 66.142023 -425.406929) (xy 66.149488 -425.383946)
			(xy 66.163692 -425.364394) (xy 66.183242 -425.35019) (xy 66.206225 -425.342724) (xy 66.218308 -425.342304)
			(xy 67.158108 -425.342304) (xy 67.170192 -425.342706) (xy 67.193177 -425.350177) (xy 67.212729 -425.364386)
			(xy 67.226932 -425.383941) (xy 67.234397 -425.406928) (xy 67.234816 -425.419012) (xy 67.234816 -427.960536)
			(xy 67.234367 -427.972612) (xy 67.226895 -427.995579) (xy 67.212695 -428.015115) (xy 67.193154 -428.029308)
			(xy 67.170184 -428.036771) (xy 67.158108 -428.037244) (xy 66.218308 -428.037244) (xy 66.206237 -428.03673)
			(xy 66.183277 -428.029274) (xy 66.163743 -428.015089) (xy 66.149547 -427.995563) (xy 66.142077 -427.972606)
			(xy 66.1416 -427.960536) (xy 66.1416 -427.350174) (xy 66.139936 -427.33518) (xy 66.138154 -427.305062)
			(xy 66.138044 -427.289976) (xy 65.23482 -427.289976) (xy 65.23482 -428.28972) (xy 68.13804 -428.28972)
			(xy 68.138152 -428.274634) (xy 68.139933 -428.244516) (xy 68.141596 -428.229522) (xy 68.141596 -427.150022)
			(xy 68.139927 -427.135029) (xy 68.138149 -427.10491) (xy 68.13804 -427.089824) (xy 68.13815 -427.074738)
			(xy 68.139931 -427.04462) (xy 68.141596 -427.029626) (xy 68.141596 -426.41901) (xy 68.142115 -426.406925)
			(xy 68.149564 -426.383932) (xy 68.163739 -426.364356) (xy 68.183258 -426.350104) (xy 68.206221 -426.342564)
			(xy 68.218304 -426.342048) (xy 69.158104 -426.342048) (xy 69.170208 -426.342512) (xy 69.193227 -426.350006)
			(xy 69.212795 -426.364257) (xy 69.226991 -426.383866) (xy 69.234421 -426.406905) (xy 69.234812 -426.41901)
			(xy 69.234812 -427.289976) (xy 70.138036 -427.289976) (xy 70.138153 -427.274891) (xy 70.13993 -427.244772)
			(xy 70.141592 -427.229778) (xy 70.141592 -426.150024) (xy 70.139923 -426.135031) (xy 70.138145 -426.104912)
			(xy 70.138036 -426.089826) (xy 70.138148 -426.07474) (xy 70.139929 -426.044622) (xy 70.141592 -426.029628)
			(xy 70.141592 -425.419012) (xy 70.142023 -425.40693) (xy 70.149487 -425.383948) (xy 70.163689 -425.364397)
			(xy 70.183237 -425.350193) (xy 70.206218 -425.342725) (xy 70.2183 -425.342304) (xy 71.1581 -425.342304)
			(xy 71.170184 -425.342713) (xy 71.193169 -425.350182) (xy 71.21272 -425.364388) (xy 71.226924 -425.383942)
			(xy 71.234389 -425.406928) (xy 71.234808 -425.419012) (xy 71.234808 -427.960536) (xy 71.234367 -427.972612)
			(xy 71.226894 -427.995581) (xy 71.212692 -428.015117) (xy 71.193149 -428.029311) (xy 71.170177 -428.036772)
			(xy 71.1581 -428.037244) (xy 70.2183 -428.037244) (xy 70.206229 -428.036736) (xy 70.183268 -428.029278)
			(xy 70.163734 -428.015092) (xy 70.149538 -427.995564) (xy 70.142069 -427.972607) (xy 70.141592 -427.960536)
			(xy 70.141592 -427.350174) (xy 70.139928 -427.33518) (xy 70.138146 -427.305062) (xy 70.138036 -427.289976)
			(xy 69.234812 -427.289976) (xy 69.234812 -428.28972) (xy 72.138032 -428.28972) (xy 72.138144 -428.274634)
			(xy 72.139925 -428.244516) (xy 72.141588 -428.229522) (xy 72.141588 -427.150022) (xy 72.139919 -427.135029)
			(xy 72.138141 -427.10491) (xy 72.138032 -427.089824) (xy 72.138144 -427.074738) (xy 72.139925 -427.04462)
			(xy 72.141588 -427.029626) (xy 72.141588 -426.41901) (xy 72.142017 -426.406916) (xy 72.149477 -426.383908)
			(xy 72.163671 -426.364324) (xy 72.183216 -426.350075) (xy 72.206204 -426.342551) (xy 72.218296 -426.342048)
			(xy 73.158096 -426.342048) (xy 73.170199 -426.342519) (xy 73.193218 -426.350011) (xy 73.212787 -426.36426)
			(xy 73.226983 -426.383867) (xy 73.234413 -426.406905) (xy 73.234804 -426.41901) (xy 73.234804 -427.289976)
			(xy 75.138026 -427.289976) (xy 75.138117 -427.275402) (xy 75.139771 -427.246301) (xy 75.141328 -427.23181)
			(xy 75.141328 -426.147992) (xy 75.139785 -426.1335) (xy 75.138132 -426.1044) (xy 75.138026 -426.089826)
			(xy 75.138121 -426.075252) (xy 75.139773 -426.046151) (xy 75.141328 -426.03166) (xy 75.141328 -425.419012)
			(xy 75.141727 -425.406901) (xy 75.149227 -425.383869) (xy 75.163492 -425.364294) (xy 75.183119 -425.3501)
			(xy 75.206178 -425.342684) (xy 75.21829 -425.342304) (xy 76.15809 -425.342304) (xy 76.170175 -425.342815)
			(xy 76.19317 -425.350265) (xy 76.212747 -425.364441) (xy 76.226999 -425.383963) (xy 76.234537 -425.406928)
			(xy 76.235052 -425.419012) (xy 76.235052 -427.960536) (xy 76.234615 -427.972642) (xy 76.227112 -427.995661)
			(xy 76.212854 -428.015229) (xy 76.19324 -428.029424) (xy 76.170197 -428.036854) (xy 76.15809 -428.037244)
			(xy 75.21829 -428.037244) (xy 75.206198 -428.036801) (xy 75.183195 -428.029339) (xy 75.163614 -428.015147)
			(xy 75.149364 -427.995608) (xy 75.141835 -427.972626) (xy 75.141328 -427.960536) (xy 75.141328 -427.348142)
			(xy 75.139781 -427.33365) (xy 75.138131 -427.30455) (xy 75.138026 -427.289976) (xy 73.234804 -427.289976)
			(xy 73.234804 -428.28972) (xy 77.138022 -428.28972) (xy 77.138117 -428.275146) (xy 77.139768 -428.246045)
			(xy 77.141324 -428.231554) (xy 77.141324 -427.14799) (xy 77.139781 -427.133498) (xy 77.138128 -427.104398)
			(xy 77.138022 -427.089824) (xy 77.138117 -427.07525) (xy 77.139769 -427.046149) (xy 77.141324 -427.031658)
			(xy 77.141324 -426.41901) (xy 77.14182 -426.406897) (xy 77.149303 -426.383857) (xy 77.163539 -426.364256)
			(xy 77.183135 -426.350014) (xy 77.206174 -426.342524) (xy 77.218286 -426.342048) (xy 78.158086 -426.342048)
			(xy 78.170209 -426.342472) (xy 78.193269 -426.349962) (xy 78.212885 -426.364212) (xy 78.227136 -426.383827)
			(xy 78.234627 -426.406887) (xy 78.235048 -426.41901) (xy 78.235048 -427.289976) (xy 79.138018 -427.289976)
			(xy 79.138109 -427.275402) (xy 79.139763 -427.246301) (xy 79.14132 -427.23181) (xy 79.14132 -426.147992)
			(xy 79.139777 -426.1335) (xy 79.138124 -426.1044) (xy 79.138018 -426.089826) (xy 79.138113 -426.075252)
			(xy 79.139765 -426.046151) (xy 79.14132 -426.03166) (xy 79.14132 -425.419012) (xy 79.141727 -425.406902)
			(xy 79.149226 -425.383872) (xy 79.163489 -425.364297) (xy 79.183114 -425.350102) (xy 79.20617 -425.342685)
			(xy 79.218282 -425.342304) (xy 80.158082 -425.342304) (xy 80.170167 -425.342822) (xy 80.193161 -425.35027)
			(xy 80.212738 -425.364444) (xy 80.226991 -425.383965) (xy 80.234529 -425.406929) (xy 80.235044 -425.419012)
			(xy 80.235044 -427.960536) (xy 80.234615 -427.972642) (xy 80.227111 -427.995663) (xy 80.212851 -428.015232)
			(xy 80.193235 -428.029427) (xy 80.17019 -428.036855) (xy 80.158082 -428.037244) (xy 79.218282 -428.037244)
			(xy 79.20619 -428.036808) (xy 79.183186 -428.029344) (xy 79.163605 -428.01515) (xy 79.149355 -427.995609)
			(xy 79.141827 -427.972627) (xy 79.14132 -427.960536) (xy 79.14132 -427.348142) (xy 79.139773 -427.33365)
			(xy 79.138123 -427.30455) (xy 79.138018 -427.289976) (xy 78.235048 -427.289976) (xy 78.235048 -428.28972)
			(xy 81.138014 -428.28972) (xy 81.138108 -428.275146) (xy 81.13976 -428.246045) (xy 81.141316 -428.231554)
			(xy 81.141316 -427.14799) (xy 81.139773 -427.133498) (xy 81.13812 -427.104398) (xy 81.138014 -427.089824)
			(xy 81.138108 -427.07525) (xy 81.13976 -427.046149) (xy 81.141316 -427.031658) (xy 81.141316 -426.41901)
			(xy 81.14182 -426.406898) (xy 81.149302 -426.383859) (xy 81.163536 -426.364259) (xy 81.18313 -426.350016)
			(xy 81.206166 -426.342525) (xy 81.218278 -426.342048) (xy 82.158078 -426.342048) (xy 82.170201 -426.342479)
			(xy 82.19326 -426.349966) (xy 82.212877 -426.364215) (xy 82.227128 -426.383829) (xy 82.234619 -426.406887)
			(xy 82.23504 -426.41901) (xy 82.23504 -427.289976) (xy 83.13801 -427.289976) (xy 83.1381 -427.275402)
			(xy 83.139755 -427.246301) (xy 83.141312 -427.23181) (xy 83.141312 -426.147992) (xy 83.139769 -426.1335)
			(xy 83.138116 -426.1044) (xy 83.13801 -426.089826) (xy 83.138105 -426.075252) (xy 83.139756 -426.046151)
			(xy 83.141312 -426.03166) (xy 83.141312 -425.419012) (xy 83.141727 -425.406903) (xy 83.149224 -425.383874)
			(xy 83.163486 -425.364299) (xy 83.183109 -425.350105) (xy 83.206163 -425.342686) (xy 83.218274 -425.342304)
			(xy 84.158074 -425.342304) (xy 84.170159 -425.342829) (xy 84.193152 -425.350274) (xy 84.21273 -425.364447)
			(xy 84.226982 -425.383966) (xy 84.234521 -425.406929) (xy 84.235036 -425.419012) (xy 84.235036 -427.960536)
			(xy 84.234615 -427.972643) (xy 84.22711 -427.995665) (xy 84.212848 -428.015235) (xy 84.19323 -428.029429)
			(xy 84.170183 -428.036856) (xy 84.158074 -428.037244) (xy 83.218274 -428.037244) (xy 83.206181 -428.036815)
			(xy 83.183177 -428.029349) (xy 83.163596 -428.015153) (xy 83.149347 -427.995611) (xy 83.141819 -427.972627)
			(xy 83.141312 -427.960536) (xy 83.141312 -427.348142) (xy 83.139765 -427.33365) (xy 83.138115 -427.30455)
			(xy 83.13801 -427.289976) (xy 82.23504 -427.289976) (xy 82.23504 -428.28972) (xy 85.138006 -428.28972)
			(xy 85.1381 -428.275146) (xy 85.139752 -428.246045) (xy 85.141308 -428.231554) (xy 85.141308 -427.14799)
			(xy 85.139765 -427.133498) (xy 85.138112 -427.104398) (xy 85.138006 -427.089824) (xy 85.1381 -427.07525)
			(xy 85.139752 -427.046149) (xy 85.141308 -427.031658) (xy 85.141308 -426.41901) (xy 85.14182 -426.406899)
			(xy 85.149301 -426.383861) (xy 85.163533 -426.364262) (xy 85.183125 -426.350019) (xy 85.206159 -426.342526)
			(xy 85.21827 -426.342048) (xy 86.15807 -426.342048) (xy 86.170192 -426.342486) (xy 86.193252 -426.349971)
			(xy 86.212868 -426.364218) (xy 86.22712 -426.38383) (xy 86.234611 -426.406888) (xy 86.235032 -426.41901)
			(xy 86.235032 -427.289976) (xy 87.138002 -427.289976) (xy 87.138092 -427.275402) (xy 87.139747 -427.246301)
			(xy 87.141304 -427.23181) (xy 87.141304 -426.147992) (xy 87.139761 -426.1335) (xy 87.138108 -426.1044)
			(xy 87.138002 -426.089826) (xy 87.138097 -426.075252) (xy 87.139748 -426.046151) (xy 87.141304 -426.03166)
			(xy 87.141304 -425.419012) (xy 87.141727 -425.406903) (xy 87.149223 -425.383876) (xy 87.163483 -425.364302)
			(xy 87.183104 -425.350107) (xy 87.206156 -425.342687) (xy 87.218266 -425.342304) (xy 88.158066 -425.342304)
			(xy 88.17015 -425.342836) (xy 88.193144 -425.350279) (xy 88.212721 -425.36445) (xy 88.226974 -425.383968)
			(xy 88.234513 -425.40693) (xy 88.235028 -425.419012) (xy 88.235028 -427.960536) (xy 88.234615 -427.972644)
			(xy 88.227109 -427.995668) (xy 88.212845 -428.015238) (xy 88.193225 -428.029432) (xy 88.170175 -428.036857)
			(xy 88.158066 -428.037244) (xy 87.218266 -428.037244) (xy 87.206173 -428.036821) (xy 87.183169 -428.029353)
			(xy 87.163588 -428.015156) (xy 87.149339 -427.995612) (xy 87.141811 -427.972628) (xy 87.141304 -427.960536)
			(xy 87.141304 -427.348142) (xy 87.139757 -427.33365) (xy 87.138107 -427.30455) (xy 87.138002 -427.289976)
			(xy 86.235032 -427.289976) (xy 86.235032 -428.28972) (xy 89.137998 -428.28972) (xy 89.138092 -428.275146)
			(xy 89.139744 -428.246045) (xy 89.1413 -428.231554) (xy 89.1413 -427.14799) (xy 89.139757 -427.133498)
			(xy 89.138104 -427.104398) (xy 89.137998 -427.089824) (xy 89.138092 -427.07525) (xy 89.139744 -427.046149)
			(xy 89.1413 -427.031658) (xy 89.1413 -426.41901) (xy 89.14182 -426.4069) (xy 89.1493 -426.383863)
			(xy 89.163531 -426.364265) (xy 89.18312 -426.350022) (xy 89.206152 -426.342527) (xy 89.218262 -426.342048)
			(xy 90.158062 -426.342048) (xy 90.170184 -426.342492) (xy 90.193243 -426.349975) (xy 90.21286 -426.36422)
			(xy 90.227112 -426.383832) (xy 90.234603 -426.406888) (xy 90.235024 -426.41901) (xy 90.235024 -427.289976)
			(xy 125.238002 -427.289976) (xy 125.238092 -427.275402) (xy 125.239747 -427.246301) (xy 125.241304 -427.23181)
			(xy 125.241304 -426.147992) (xy 125.239761 -426.1335) (xy 125.238108 -426.1044) (xy 125.238002 -426.089826)
			(xy 125.238097 -426.075252) (xy 125.239748 -426.046151) (xy 125.241304 -426.03166) (xy 125.241304 -425.419012)
			(xy 125.241727 -425.406903) (xy 125.249223 -425.383876) (xy 125.263483 -425.364302) (xy 125.283104 -425.350107)
			(xy 125.306156 -425.342687) (xy 125.318266 -425.342304) (xy 126.258066 -425.342304) (xy 126.27015 -425.342836)
			(xy 126.293144 -425.350279) (xy 126.312721 -425.36445) (xy 126.326974 -425.383968) (xy 126.334513 -425.40693)
			(xy 126.335028 -425.419012) (xy 126.335028 -427.960536) (xy 126.334615 -427.972644) (xy 126.327109 -427.995668)
			(xy 126.312845 -428.015238) (xy 126.293225 -428.029432) (xy 126.270175 -428.036857) (xy 126.258066 -428.037244)
			(xy 125.318266 -428.037244) (xy 125.306173 -428.036821) (xy 125.283169 -428.029353) (xy 125.263588 -428.015156)
			(xy 125.249339 -427.995612) (xy 125.241811 -427.972628) (xy 125.241304 -427.960536) (xy 125.241304 -427.348142)
			(xy 125.239757 -427.33365) (xy 125.238107 -427.30455) (xy 125.238002 -427.289976) (xy 90.235024 -427.289976)
			(xy 90.235024 -428.960534) (xy 90.234669 -428.972662) (xy 90.227162 -428.995729) (xy 90.212895 -429.015347)
			(xy 90.193264 -429.029595) (xy 90.170191 -429.03708) (xy 90.158062 -429.037496) (xy 89.218262 -429.037496)
			(xy 89.206149 -429.037021) (xy 89.18311 -429.029528) (xy 89.163512 -429.015285) (xy 89.14927 -428.995686)
			(xy 89.141778 -428.972647) (xy 89.1413 -428.960534) (xy 89.1413 -428.347886) (xy 89.139757 -428.333394)
			(xy 89.138104 -428.304294) (xy 89.137998 -428.28972) (xy 86.235032 -428.28972) (xy 86.235032 -428.960534)
			(xy 86.234617 -428.972653) (xy 86.227117 -428.995703) (xy 86.212861 -429.015307) (xy 86.193245 -429.029546)
			(xy 86.17019 -429.037027) (xy 86.15807 -429.037496) (xy 85.21827 -429.037496) (xy 85.206157 -429.037014)
			(xy 85.183119 -429.029523) (xy 85.16352 -429.015282) (xy 85.149279 -428.995685) (xy 85.141786 -428.972647)
			(xy 85.141308 -428.960534) (xy 85.141308 -428.347886) (xy 85.139765 -428.333394) (xy 85.138112 -428.304294)
			(xy 85.138006 -428.28972) (xy 82.23504 -428.28972) (xy 82.23504 -428.960534) (xy 82.234617 -428.972653)
			(xy 82.227118 -428.995701) (xy 82.212864 -429.015304) (xy 82.19325 -429.029543) (xy 82.170197 -429.037026)
			(xy 82.158078 -429.037496) (xy 81.218278 -429.037496) (xy 81.206166 -429.037008) (xy 81.183127 -429.029519)
			(xy 81.163529 -429.01528) (xy 81.149287 -428.995683) (xy 81.141794 -428.972646) (xy 81.141316 -428.960534)
			(xy 81.141316 -428.347886) (xy 81.139773 -428.333394) (xy 81.13812 -428.304294) (xy 81.138014 -428.28972)
			(xy 78.235048 -428.28972) (xy 78.235048 -428.960534) (xy 78.234617 -428.972652) (xy 78.227119 -428.995698)
			(xy 78.212867 -429.015301) (xy 78.193255 -429.029541) (xy 78.170204 -429.037025) (xy 78.158086 -429.037496)
			(xy 77.218286 -429.037496) (xy 77.206174 -429.037001) (xy 77.183136 -429.029514) (xy 77.163537 -429.015277)
			(xy 77.149295 -428.995682) (xy 77.141802 -428.972646) (xy 77.141324 -428.960534) (xy 77.141324 -428.347886)
			(xy 77.139781 -428.333394) (xy 77.138128 -428.304294) (xy 77.138022 -428.28972) (xy 73.234804 -428.28972)
			(xy 73.234804 -428.960534) (xy 73.234323 -428.972621) (xy 73.226862 -428.995615) (xy 73.212677 -429.015191)
			(xy 73.19315 -429.029442) (xy 73.170181 -429.036981) (xy 73.158096 -429.037496) (xy 72.218296 -429.037496)
			(xy 72.206187 -429.037087) (xy 72.183158 -429.029586) (xy 72.163585 -429.015323) (xy 72.149391 -428.995699)
			(xy 72.141971 -428.972645) (xy 72.141588 -428.960534) (xy 72.141588 -428.349918) (xy 72.139919 -428.334925)
			(xy 72.138141 -428.304806) (xy 72.138032 -428.28972) (xy 69.234812 -428.28972) (xy 69.234812 -428.960534)
			(xy 69.234421 -428.97263) (xy 69.226949 -428.99564) (xy 69.212744 -429.015223) (xy 69.193192 -429.029471)
			(xy 69.170199 -429.036994) (xy 69.158104 -429.037496) (xy 68.218304 -429.037496) (xy 68.206195 -429.03708)
			(xy 68.183167 -429.029582) (xy 68.163593 -429.01532) (xy 68.149399 -428.995698) (xy 68.141979 -428.972644)
			(xy 68.141596 -428.960534) (xy 68.141596 -428.349918) (xy 68.139927 -428.334925) (xy 68.138149 -428.304806)
			(xy 68.13804 -428.28972) (xy 65.23482 -428.28972) (xy 65.23482 -428.960534) (xy 65.234421 -428.972629)
			(xy 65.22695 -428.995638) (xy 65.212747 -429.015221) (xy 65.193197 -429.029469) (xy 65.170206 -429.036993)
			(xy 65.158112 -429.037496) (xy 64.218312 -429.037496) (xy 64.206203 -429.037073) (xy 64.183176 -429.029577)
			(xy 64.163602 -429.015317) (xy 64.149407 -428.995696) (xy 64.141987 -428.972644) (xy 64.141604 -428.960534)
			(xy 64.141604 -428.349918) (xy 64.139935 -428.334925) (xy 64.138157 -428.304806) (xy 64.138048 -428.28972)
			(xy 61.234828 -428.28972) (xy 61.234828 -428.960534) (xy 61.234421 -428.972629) (xy 61.226951 -428.995636)
			(xy 61.21275 -429.015218) (xy 61.193202 -429.029466) (xy 61.170213 -429.036992) (xy 61.15812 -429.037496)
			(xy 60.21832 -429.037496) (xy 60.206212 -429.037066) (xy 60.183185 -429.029572) (xy 60.163611 -429.015314)
			(xy 60.149416 -428.995695) (xy 60.141995 -428.972643) (xy 60.141612 -428.960534) (xy 60.141612 -428.349918)
			(xy 60.139943 -428.334925) (xy 60.138165 -428.304806) (xy 60.138056 -428.28972) (xy 49.0054 -428.28972)
			(xy 48.932448 -428.365522) (xy 48.780383 -428.51187) (xy 48.622824 -428.652286) (xy 48.460002 -428.786564)
			(xy 48.292156 -428.914507) (xy 48.119534 -429.035927) (xy 47.942387 -429.150646) (xy 47.760976 -429.258496)
			(xy 47.575567 -429.359318) (xy 47.386432 -429.452965) (xy 47.19385 -429.539298) (xy 46.998102 -429.618192)
			(xy 46.799475 -429.68953) (xy 46.598262 -429.753207) (xy 46.394758 -429.809131) (xy 46.189261 -429.857219)
			(xy 45.982073 -429.897401) (xy 45.773498 -429.929618) (xy 45.563841 -429.953821) (xy 45.353412 -429.969977)
			(xy 45.142518 -429.978061) (xy 44.93147 -429.978061) (xy 44.720576 -429.969977) (xy 44.510147 -429.953821)
			(xy 44.30049 -429.929618) (xy 44.091915 -429.897401) (xy 43.884727 -429.857219) (xy 43.67923 -429.809131)
			(xy 43.475726 -429.753207) (xy 43.274513 -429.68953) (xy 43.075886 -429.618192) (xy 42.880138 -429.539298)
			(xy 42.687556 -429.452965) (xy 42.498421 -429.359318) (xy 42.313012 -429.258496) (xy 42.131601 -429.150646)
			(xy 41.954454 -429.035927) (xy 41.781832 -428.914507) (xy 41.613986 -428.786564) (xy 41.451164 -428.652286)
			(xy 41.293605 -428.51187) (xy 41.14154 -428.365522) (xy 40.995192 -428.213457) (xy 40.854776 -428.055898)
			(xy 40.720498 -427.893076) (xy 40.592555 -427.72523) (xy 40.471135 -427.552608) (xy 40.356416 -427.375461)
			(xy 40.248566 -427.19405) (xy 40.147744 -427.008641) (xy 40.054097 -426.819506) (xy 39.967764 -426.626924)
			(xy 39.88887 -426.431176) (xy 39.817532 -426.232549) (xy 39.753855 -426.031336) (xy 39.697931 -425.827832)
			(xy 39.649843 -425.622335) (xy 39.609661 -425.415147) (xy 39.577444 -425.206572) (xy 39.553241 -424.996915)
			(xy 39.537085 -424.786486) (xy 39.529001 -424.575592) (xy 39.528496 -424.470068) (xy 7.00913 -424.470068)
			(xy 7.00913 -430.889918) (xy 58.13806 -430.889918) (xy 58.138169 -430.874832) (xy 58.139951 -430.844714)
			(xy 58.141616 -430.82972) (xy 58.141616 -429.749966) (xy 58.139951 -429.734972) (xy 58.13817 -429.704854)
			(xy 58.13806 -429.689768) (xy 58.138174 -429.674682) (xy 58.139952 -429.644564) (xy 58.141616 -429.62957)
			(xy 58.141616 -429.018954) (xy 58.142068 -429.006864) (xy 58.149534 -428.983866) (xy 58.163726 -428.964289)
			(xy 58.18326 -428.950039) (xy 58.206236 -428.942504) (xy 58.218324 -428.941992) (xy 59.158124 -428.941992)
			(xy 59.170233 -428.942396) (xy 59.19326 -428.949901) (xy 59.212832 -428.964166) (xy 59.227026 -428.983789)
			(xy 59.234448 -429.006843) (xy 59.234832 -429.018954) (xy 59.234832 -431.560478) (xy 59.234373 -431.572569)
			(xy 59.226919 -431.595574) (xy 59.212732 -431.615156) (xy 59.193194 -431.629407) (xy 59.170214 -431.636934)
			(xy 59.158124 -431.63744) (xy 58.218324 -431.63744) (xy 58.20622 -431.636964) (xy 58.183201 -431.629476)
			(xy 58.163631 -431.615228) (xy 58.149434 -431.595622) (xy 58.142005 -431.572583) (xy 58.141616 -431.560478)
			(xy 58.141616 -430.950116) (xy 58.139947 -430.935123) (xy 58.138169 -430.905004) (xy 58.13806 -430.889918)
			(xy 7.00913 -430.889918) (xy 7.00913 -431.889916) (xy 60.138056 -431.889916) (xy 60.138165 -431.87483)
			(xy 60.139947 -431.844712) (xy 60.141612 -431.829718) (xy 60.141612 -430.749964) (xy 60.139947 -430.73497)
			(xy 60.138166 -430.704852) (xy 60.138056 -430.689766) (xy 60.13817 -430.67468) (xy 60.139948 -430.644562)
			(xy 60.141612 -430.629568) (xy 60.141612 -430.018952) (xy 60.142024 -430.006873) (xy 60.149502 -429.983901)
			(xy 60.163711 -429.964363) (xy 60.183262 -429.950171) (xy 60.206241 -429.942713) (xy 60.21832 -429.942244)
			(xy 61.15812 -429.942244) (xy 61.170191 -429.942747) (xy 61.19315 -429.950209) (xy 61.212683 -429.964397)
			(xy 61.226878 -429.983924) (xy 61.234349 -430.006881) (xy 61.234828 -430.018952) (xy 61.234828 -430.889918)
			(xy 62.138052 -430.889918) (xy 62.138161 -430.874832) (xy 62.139943 -430.844714) (xy 62.141608 -430.82972)
			(xy 62.141608 -429.749966) (xy 62.139943 -429.734972) (xy 62.138162 -429.704854) (xy 62.138052 -429.689768)
			(xy 62.138166 -429.674682) (xy 62.139944 -429.644564) (xy 62.141608 -429.62957) (xy 62.141608 -429.018954)
			(xy 62.142068 -429.006865) (xy 62.149533 -428.983868) (xy 62.163723 -428.964292) (xy 62.183255 -428.950042)
			(xy 62.206229 -428.942505) (xy 62.218316 -428.941992) (xy 63.158116 -428.941992) (xy 63.170225 -428.942402)
			(xy 63.193251 -428.949905) (xy 63.212824 -428.964169) (xy 63.227018 -428.983791) (xy 63.23444 -429.006844)
			(xy 63.234824 -429.018954) (xy 63.234824 -431.560478) (xy 63.234373 -431.57257) (xy 63.226918 -431.595576)
			(xy 63.212729 -431.615159) (xy 63.193189 -431.629409) (xy 63.170206 -431.636935) (xy 63.158116 -431.63744)
			(xy 62.218316 -431.63744) (xy 62.206212 -431.63697) (xy 62.183192 -431.62948) (xy 62.163622 -431.615231)
			(xy 62.149426 -431.595623) (xy 62.141997 -431.572583) (xy 62.141608 -431.560478) (xy 62.141608 -430.950116)
			(xy 62.139939 -430.935123) (xy 62.138161 -430.905004) (xy 62.138052 -430.889918) (xy 61.234828 -430.889918)
			(xy 61.234828 -431.889916) (xy 64.138048 -431.889916) (xy 64.138157 -431.87483) (xy 64.139939 -431.844712)
			(xy 64.141604 -431.829718) (xy 64.141604 -430.749964) (xy 64.139939 -430.73497) (xy 64.138158 -430.704852)
			(xy 64.138048 -430.689766) (xy 64.138162 -430.67468) (xy 64.13994 -430.644562) (xy 64.141604 -430.629568)
			(xy 64.141604 -430.018952) (xy 64.142023 -430.006874) (xy 64.149501 -429.983903) (xy 64.163708 -429.964366)
			(xy 64.183257 -429.950173) (xy 64.206233 -429.942714) (xy 64.218312 -429.942244) (xy 65.158112 -429.942244)
			(xy 65.170182 -429.942753) (xy 65.193142 -429.950213) (xy 65.212674 -429.9644) (xy 65.22687 -429.983926)
			(xy 65.234341 -430.006882) (xy 65.23482 -430.018952) (xy 65.23482 -430.889918) (xy 66.138044 -430.889918)
			(xy 66.138153 -430.874832) (xy 66.139935 -430.844714) (xy 66.1416 -430.82972) (xy 66.1416 -429.749966)
			(xy 66.139935 -429.734972) (xy 66.138154 -429.704854) (xy 66.138044 -429.689768) (xy 66.138158 -429.674682)
			(xy 66.139936 -429.644564) (xy 66.1416 -429.62957) (xy 66.1416 -429.018954) (xy 66.142067 -429.006866)
			(xy 66.149532 -428.983871) (xy 66.16372 -428.964295) (xy 66.18325 -428.950044) (xy 66.206222 -428.942507)
			(xy 66.218308 -428.941992) (xy 67.158108 -428.941992) (xy 67.170217 -428.942409) (xy 67.193243 -428.94991)
			(xy 67.212815 -428.964172) (xy 67.22701 -428.983792) (xy 67.234432 -429.006844) (xy 67.234816 -429.018954)
			(xy 67.234816 -431.560478) (xy 67.234373 -431.572571) (xy 67.226917 -431.595578) (xy 67.212726 -431.615162)
			(xy 67.193184 -431.629412) (xy 67.170199 -431.636937) (xy 67.158108 -431.63744) (xy 66.218308 -431.63744)
			(xy 66.206204 -431.636978) (xy 66.183183 -431.629485) (xy 66.163613 -431.615234) (xy 66.149417 -431.595625)
			(xy 66.141989 -431.572584) (xy 66.1416 -431.560478) (xy 66.1416 -430.950116) (xy 66.139931 -430.935123)
			(xy 66.138153 -430.905004) (xy 66.138044 -430.889918) (xy 65.23482 -430.889918) (xy 65.23482 -431.889916)
			(xy 68.13804 -431.889916) (xy 68.138151 -431.87483) (xy 68.139933 -431.844712) (xy 68.141596 -431.829718)
			(xy 68.141596 -430.749964) (xy 68.139931 -430.73497) (xy 68.13815 -430.704852) (xy 68.13804 -430.689766)
			(xy 68.138154 -430.67468) (xy 68.139932 -430.644562) (xy 68.141596 -430.629568) (xy 68.141596 -430.018952)
			(xy 68.142023 -430.006875) (xy 68.149499 -429.983905) (xy 68.163705 -429.964368) (xy 68.183252 -429.950176)
			(xy 68.206226 -429.942715) (xy 68.218304 -429.942244) (xy 69.158104 -429.942244) (xy 69.170174 -429.94276)
			(xy 69.193133 -429.950218) (xy 69.212666 -429.964403) (xy 69.226862 -429.983927) (xy 69.234333 -430.006882)
			(xy 69.234812 -430.018952) (xy 69.234812 -430.889918) (xy 70.138036 -430.889918) (xy 70.138147 -430.874832)
			(xy 70.139929 -430.844714) (xy 70.141592 -430.82972) (xy 70.141592 -429.749966) (xy 70.139927 -429.734972)
			(xy 70.138146 -429.704854) (xy 70.138036 -429.689768) (xy 70.138152 -429.674683) (xy 70.13993 -429.644564)
			(xy 70.141592 -429.62957) (xy 70.141592 -429.018954) (xy 70.142067 -429.006867) (xy 70.149531 -428.983873)
			(xy 70.163717 -428.964298) (xy 70.183245 -428.950047) (xy 70.206214 -428.942508) (xy 70.2183 -428.941992)
			(xy 71.1581 -428.941992) (xy 71.170208 -428.942416) (xy 71.193234 -428.949914) (xy 71.212807 -428.964174)
			(xy 71.227001 -428.983794) (xy 71.234424 -429.006845) (xy 71.234808 -429.018954) (xy 71.234808 -431.560478)
			(xy 71.234275 -431.572562) (xy 71.22683 -431.595553) (xy 71.212659 -431.61513) (xy 71.193142 -431.629383)
			(xy 71.170182 -431.636924) (xy 71.1581 -431.63744) (xy 70.2183 -431.63744) (xy 70.206195 -431.636984)
			(xy 70.183175 -431.62949) (xy 70.163605 -431.615237) (xy 70.149409 -431.595626) (xy 70.141981 -431.572584)
			(xy 70.141592 -431.560478) (xy 70.141592 -430.950116) (xy 70.139923 -430.935123) (xy 70.138145 -430.905004)
			(xy 70.138036 -430.889918) (xy 69.234812 -430.889918) (xy 69.234812 -431.889916) (xy 72.138032 -431.889916)
			(xy 72.138143 -431.87483) (xy 72.139925 -431.844712) (xy 72.141588 -431.829718) (xy 72.141588 -430.749964)
			(xy 72.139923 -430.73497) (xy 72.138142 -430.704852) (xy 72.138032 -430.689766) (xy 72.138148 -430.674681)
			(xy 72.139926 -430.644562) (xy 72.141588 -430.629568) (xy 72.141588 -430.018952) (xy 72.142023 -430.006875)
			(xy 72.149498 -429.983907) (xy 72.163703 -429.964371) (xy 72.183247 -429.950178) (xy 72.206219 -429.942716)
			(xy 72.218296 -429.942244) (xy 73.158096 -429.942244) (xy 73.170166 -429.942767) (xy 73.193124 -429.950222)
			(xy 73.212657 -429.964406) (xy 73.226854 -429.983929) (xy 73.234325 -430.006883) (xy 73.234804 -430.018952)
			(xy 73.234804 -430.889918) (xy 75.138026 -430.889918) (xy 75.13812 -430.875344) (xy 75.139772 -430.846243)
			(xy 75.141328 -430.831752) (xy 75.141328 -429.747934) (xy 75.13978 -429.733442) (xy 75.13813 -429.704342)
			(xy 75.138026 -429.689768) (xy 75.138125 -429.675194) (xy 75.139774 -429.646093) (xy 75.141328 -429.631602)
			(xy 75.141328 -429.018954) (xy 75.141772 -429.006838) (xy 75.149271 -428.983795) (xy 75.163521 -428.964195)
			(xy 75.183127 -428.949955) (xy 75.206174 -428.942467) (xy 75.21829 -428.941992) (xy 76.15809 -428.941992)
			(xy 76.170199 -428.94252) (xy 76.193235 -428.949999) (xy 76.212832 -428.964228) (xy 76.227076 -428.983815)
			(xy 76.234572 -429.006845) (xy 76.235052 -429.018954) (xy 76.235052 -431.560478) (xy 76.234621 -431.572601)
			(xy 76.227134 -431.59566) (xy 76.212885 -431.615277) (xy 76.193271 -431.629528) (xy 76.170213 -431.637019)
			(xy 76.15809 -431.63744) (xy 75.21829 -431.63744) (xy 75.206165 -431.637048) (xy 75.183102 -431.62955)
			(xy 75.163485 -431.615292) (xy 75.149235 -431.59567) (xy 75.141747 -431.572604) (xy 75.141328 -431.560478)
			(xy 75.141328 -430.948084) (xy 75.139785 -430.933592) (xy 75.138132 -430.904492) (xy 75.138026 -430.889918)
			(xy 73.234804 -430.889918) (xy 73.234804 -431.889916) (xy 77.138022 -431.889916) (xy 77.138116 -431.875342)
			(xy 77.139768 -431.846241) (xy 77.141324 -431.83175) (xy 77.141324 -430.747932) (xy 77.139776 -430.73344)
			(xy 77.138126 -430.70434) (xy 77.138022 -430.689766) (xy 77.138121 -430.675192) (xy 77.13977 -430.646091)
			(xy 77.141324 -430.6316) (xy 77.141324 -430.018952) (xy 77.141676 -430.006838) (xy 77.149191 -429.983805)
			(xy 77.163469 -429.964231) (xy 77.183105 -429.950039) (xy 77.20617 -429.942624) (xy 77.218286 -429.942244)
			(xy 78.158086 -429.942244) (xy 78.170175 -429.942719) (xy 78.193176 -429.950173) (xy 78.212757 -429.964357)
			(xy 78.227007 -429.983889) (xy 78.234539 -430.006864) (xy 78.235048 -430.018952) (xy 78.235048 -430.889918)
			(xy 79.138018 -430.889918) (xy 79.138112 -430.875344) (xy 79.139764 -430.846243) (xy 79.14132 -430.831752)
			(xy 79.14132 -429.747934) (xy 79.139772 -429.733442) (xy 79.138122 -429.704342) (xy 79.138018 -429.689768)
			(xy 79.138117 -429.675194) (xy 79.139766 -429.646093) (xy 79.14132 -429.631602) (xy 79.14132 -429.018954)
			(xy 79.141772 -429.006839) (xy 79.14927 -428.983797) (xy 79.163518 -428.964198) (xy 79.183122 -428.949957)
			(xy 79.206167 -428.942468) (xy 79.218282 -428.941992) (xy 80.158082 -428.941992) (xy 80.170191 -428.942526)
			(xy 80.193226 -428.950003) (xy 80.212824 -428.964231) (xy 80.227068 -428.983817) (xy 80.234563 -429.006845)
			(xy 80.235044 -429.018954) (xy 80.235044 -431.560478) (xy 80.234621 -431.572601) (xy 80.227133 -431.595663)
			(xy 80.212882 -431.61528) (xy 80.193266 -431.629531) (xy 80.170205 -431.63702) (xy 80.158082 -431.63744)
			(xy 79.218282 -431.63744) (xy 79.206156 -431.637055) (xy 79.183093 -431.629555) (xy 79.163476 -431.615295)
			(xy 79.149227 -431.595671) (xy 79.141739 -431.572604) (xy 79.14132 -431.560478) (xy 79.14132 -430.948084)
			(xy 79.139777 -430.933592) (xy 79.138124 -430.904492) (xy 79.138018 -430.889918) (xy 78.235048 -430.889918)
			(xy 78.235048 -431.889916) (xy 81.138014 -431.889916) (xy 81.138108 -431.875342) (xy 81.13976 -431.846241)
			(xy 81.141316 -431.83175) (xy 81.141316 -430.747932) (xy 81.139768 -430.73344) (xy 81.138118 -430.70434)
			(xy 81.138014 -430.689766) (xy 81.138112 -430.675192) (xy 81.139761 -430.646091) (xy 81.141316 -430.6316)
			(xy 81.141316 -430.018952) (xy 81.141676 -430.006839) (xy 81.14919 -429.983807) (xy 81.163466 -429.964234)
			(xy 81.1831 -429.950041) (xy 81.206163 -429.942625) (xy 81.218278 -429.942244) (xy 82.158078 -429.942244)
			(xy 82.170167 -429.942726) (xy 82.193167 -429.950177) (xy 82.212748 -429.96436) (xy 82.226999 -429.983891)
			(xy 82.234531 -430.006865) (xy 82.23504 -430.018952) (xy 82.23504 -430.889918) (xy 83.13801 -430.889918)
			(xy 83.138104 -430.875344) (xy 83.139756 -430.846243) (xy 83.141312 -430.831752) (xy 83.141312 -429.747934)
			(xy 83.139764 -429.733442) (xy 83.138114 -429.704342) (xy 83.13801 -429.689768) (xy 83.138108 -429.675194)
			(xy 83.139758 -429.646093) (xy 83.141312 -429.631602) (xy 83.141312 -429.018954) (xy 83.141772 -429.00684)
			(xy 83.149269 -428.983799) (xy 83.163515 -428.964201) (xy 83.183117 -428.94996) (xy 83.20616 -428.942469)
			(xy 83.218274 -428.941992) (xy 84.158074 -428.941992) (xy 84.170183 -428.942533) (xy 84.193217 -428.950008)
			(xy 84.212815 -428.964233) (xy 84.227059 -428.983818) (xy 84.234555 -429.006846) (xy 84.235036 -429.018954)
			(xy 84.235036 -431.560478) (xy 84.234621 -431.572602) (xy 84.227132 -431.595665) (xy 84.21288 -431.615282)
			(xy 84.193261 -431.629533) (xy 84.170198 -431.637022) (xy 84.158074 -431.63744) (xy 83.218274 -431.63744)
			(xy 83.206156 -431.63701) (xy 83.183108 -431.629513) (xy 83.163505 -431.615261) (xy 83.149265 -431.595649)
			(xy 83.141782 -431.572596) (xy 83.141312 -431.560478) (xy 83.141312 -430.948084) (xy 83.139769 -430.933592)
			(xy 83.138116 -430.904492) (xy 83.13801 -430.889918) (xy 82.23504 -430.889918) (xy 82.23504 -431.889916)
			(xy 85.138006 -431.889916) (xy 85.1381 -431.875342) (xy 85.139752 -431.846241) (xy 85.141308 -431.83175)
			(xy 85.141308 -430.747932) (xy 85.13976 -430.73344) (xy 85.13811 -430.70434) (xy 85.138006 -430.689766)
			(xy 85.138104 -430.675192) (xy 85.139753 -430.646091) (xy 85.141308 -430.6316) (xy 85.141308 -430.018952)
			(xy 85.141676 -430.00684) (xy 85.149189 -429.98381) (xy 85.163463 -429.964237) (xy 85.183095 -429.950044)
			(xy 85.206156 -429.942626) (xy 85.21827 -429.942244) (xy 86.15807 -429.942244) (xy 86.170158 -429.942733)
			(xy 86.193159 -429.950182) (xy 86.212739 -429.964363) (xy 86.226991 -429.983892) (xy 86.234523 -430.006865)
			(xy 86.235032 -430.018952) (xy 86.235032 -430.889918) (xy 87.138002 -430.889918) (xy 87.138096 -430.875344)
			(xy 87.139748 -430.846243) (xy 87.141304 -430.831752) (xy 87.141304 -429.747934) (xy 87.139756 -429.733442)
			(xy 87.138106 -429.704342) (xy 87.138002 -429.689768) (xy 87.1381 -429.675194) (xy 87.13975 -429.646093)
			(xy 87.141304 -429.631602) (xy 87.141304 -429.018954) (xy 87.141772 -429.00684) (xy 87.149268 -428.983801)
			(xy 87.163512 -428.964203) (xy 87.183112 -428.949962) (xy 87.206152 -428.94247) (xy 87.218266 -428.941992)
			(xy 88.158066 -428.941992) (xy 88.170174 -428.94254) (xy 88.193209 -428.950012) (xy 88.212807 -428.964236)
			(xy 88.227051 -428.98382) (xy 88.234547 -429.006846) (xy 88.235028 -429.018954) (xy 88.235028 -431.560478)
			(xy 88.234621 -431.572603) (xy 88.22713 -431.595667) (xy 88.212877 -431.615285) (xy 88.193256 -431.629536)
			(xy 88.170191 -431.637023) (xy 88.158066 -431.63744) (xy 87.218266 -431.63744) (xy 87.206147 -431.637017)
			(xy 87.183099 -431.629518) (xy 87.163496 -431.615264) (xy 87.149257 -431.59565) (xy 87.141774 -431.572597)
			(xy 87.141304 -431.560478) (xy 87.141304 -430.948084) (xy 87.13976 -430.933592) (xy 87.138108 -430.904492)
			(xy 87.138002 -430.889918) (xy 86.235032 -430.889918) (xy 86.235032 -431.889916) (xy 89.137998 -431.889916)
			(xy 89.138092 -431.875342) (xy 89.139744 -431.846241) (xy 89.1413 -431.83175) (xy 89.1413 -430.747932)
			(xy 89.139752 -430.73344) (xy 89.138102 -430.70434) (xy 89.137998 -430.689766) (xy 89.138096 -430.675192)
			(xy 89.139746 -430.646091) (xy 89.1413 -430.6316) (xy 89.1413 -430.018952) (xy 89.141676 -430.006841)
			(xy 89.149188 -429.983812) (xy 89.16346 -429.96424) (xy 89.18309 -429.950047) (xy 89.206149 -429.942627)
			(xy 89.218262 -429.942244) (xy 90.158062 -429.942244) (xy 90.17015 -429.94274) (xy 90.19315 -429.950187)
			(xy 90.212731 -429.964366) (xy 90.226983 -429.983894) (xy 90.234515 -430.006866) (xy 90.235024 -430.018952)
			(xy 90.235024 -431.360072) (xy 108.40466 -431.360072) (xy 108.405158 -431.275192) (xy 108.413115 -431.105619)
			(xy 108.429011 -430.936605) (xy 108.452812 -430.768522) (xy 108.484466 -430.601739) (xy 108.523902 -430.436623)
			(xy 108.571034 -430.273538) (xy 108.625758 -430.11284) (xy 108.687955 -429.954885) (xy 108.757487 -429.800018)
			(xy 108.834202 -429.648581) (xy 108.91793 -429.500905) (xy 109.008488 -429.357317) (xy 109.105677 -429.218131)
			(xy 109.209284 -429.083654) (xy 109.319079 -428.954181) (xy 109.434823 -428.829996) (xy 109.55626 -428.711373)
			(xy 109.683124 -428.598572) (xy 109.815135 -428.491842) (xy 109.952005 -428.391417) (xy 110.09343 -428.297518)
			(xy 110.239102 -428.21035) (xy 110.3887 -428.130107) (xy 110.541894 -428.056963) (xy 110.698348 -427.991081)
			(xy 110.857718 -427.932604) (xy 111.019654 -427.881662) (xy 111.1838 -427.838366) (xy 111.349795 -427.802811)
			(xy 111.517274 -427.775076) (xy 111.685869 -427.755222) (xy 111.855209 -427.743292) (xy 112.024922 -427.739313)
			(xy 112.194635 -427.743292) (xy 112.363975 -427.755222) (xy 112.53257 -427.775076) (xy 112.700049 -427.802811)
			(xy 112.866044 -427.838366) (xy 113.03019 -427.881662) (xy 113.192126 -427.932604) (xy 113.351496 -427.991081)
			(xy 113.50795 -428.056963) (xy 113.661144 -428.130107) (xy 113.810742 -428.21035) (xy 113.943382 -428.28972)
			(xy 127.237998 -428.28972) (xy 127.238092 -428.275146) (xy 127.239744 -428.246045) (xy 127.2413 -428.231554)
			(xy 127.2413 -427.14799) (xy 127.239757 -427.133498) (xy 127.238104 -427.104398) (xy 127.237998 -427.089824)
			(xy 127.238092 -427.07525) (xy 127.239744 -427.046149) (xy 127.2413 -427.031658) (xy 127.2413 -426.41901)
			(xy 127.24182 -426.4069) (xy 127.2493 -426.383863) (xy 127.263531 -426.364265) (xy 127.28312 -426.350022)
			(xy 127.306152 -426.342527) (xy 127.318262 -426.342048) (xy 128.258062 -426.342048) (xy 128.270184 -426.342492)
			(xy 128.293243 -426.349975) (xy 128.31286 -426.36422) (xy 128.327112 -426.383832) (xy 128.334603 -426.406888)
			(xy 128.335024 -426.41901) (xy 128.335024 -427.289976) (xy 129.237994 -427.289976) (xy 129.238084 -427.275402)
			(xy 129.239739 -427.246301) (xy 129.241296 -427.23181) (xy 129.241296 -426.147992) (xy 129.239753 -426.1335)
			(xy 129.2381 -426.1044) (xy 129.237994 -426.089826) (xy 129.238089 -426.075252) (xy 129.23974 -426.046151)
			(xy 129.241296 -426.03166) (xy 129.241296 -425.419012) (xy 129.241727 -425.406904) (xy 129.249222 -425.383878)
			(xy 129.26348 -425.364305) (xy 129.283099 -425.35011) (xy 129.306149 -425.342688) (xy 129.318258 -425.342304)
			(xy 130.258058 -425.342304) (xy 130.270142 -425.342842) (xy 130.293135 -425.350283) (xy 130.312713 -425.364453)
			(xy 130.326966 -425.383969) (xy 130.334505 -425.40693) (xy 130.33502 -425.419012) (xy 130.33502 -427.960536)
			(xy 130.334615 -427.972645) (xy 130.327108 -427.99567) (xy 130.312843 -428.01524) (xy 130.29322 -428.029435)
			(xy 130.270168 -428.036858) (xy 130.258058 -428.037244) (xy 129.318258 -428.037244) (xy 129.306165 -428.036828)
			(xy 129.28316 -428.029358) (xy 129.263579 -428.015159) (xy 129.249331 -427.995614) (xy 129.241803 -427.972628)
			(xy 129.241296 -427.960536) (xy 129.241296 -427.348142) (xy 129.239749 -427.33365) (xy 129.238099 -427.30455)
			(xy 129.237994 -427.289976) (xy 128.335024 -427.289976) (xy 128.335024 -428.28972) (xy 131.23799 -428.28972)
			(xy 131.238084 -428.275146) (xy 131.239736 -428.246045) (xy 131.241292 -428.231554) (xy 131.241292 -427.14799)
			(xy 131.239749 -427.133498) (xy 131.238096 -427.104398) (xy 131.23799 -427.089824) (xy 131.238085 -427.07525)
			(xy 131.239736 -427.046149) (xy 131.241292 -427.031658) (xy 131.241292 -426.41901) (xy 131.24182 -426.406901)
			(xy 131.249299 -426.383865) (xy 131.263528 -426.364268) (xy 131.283115 -426.350024) (xy 131.306145 -426.342528)
			(xy 131.318254 -426.342048) (xy 132.258054 -426.342048) (xy 132.270175 -426.342499) (xy 132.293234 -426.34998)
			(xy 132.312851 -426.364223) (xy 132.327104 -426.383833) (xy 132.334595 -426.406889) (xy 132.335016 -426.41901)
			(xy 132.335016 -427.289976) (xy 133.237986 -427.289976) (xy 133.238076 -427.275402) (xy 133.239731 -427.246301)
			(xy 133.241288 -427.23181) (xy 133.241288 -426.147992) (xy 133.239745 -426.1335) (xy 133.238092 -426.1044)
			(xy 133.237986 -426.089826) (xy 133.238081 -426.075252) (xy 133.239732 -426.046151) (xy 133.241288 -426.03166)
			(xy 133.241288 -425.419012) (xy 133.241727 -425.406905) (xy 133.249221 -425.38388) (xy 133.263477 -425.364308)
			(xy 133.283094 -425.350113) (xy 133.306142 -425.342689) (xy 133.31825 -425.342304) (xy 134.25805 -425.342304)
			(xy 134.270133 -425.342849) (xy 134.293126 -425.350288) (xy 134.312704 -425.364455) (xy 134.326958 -425.383971)
			(xy 134.334497 -425.406931) (xy 134.335012 -425.419012) (xy 134.335012 -427.960536) (xy 134.334614 -427.972646)
			(xy 134.327107 -427.995672) (xy 134.31284 -428.015243) (xy 134.293215 -428.029437) (xy 134.270161 -428.036859)
			(xy 134.25805 -428.037244) (xy 133.31825 -428.037244) (xy 133.306161 -428.03675) (xy 133.28316 -428.029305)
			(xy 133.263578 -428.015126) (xy 133.249326 -427.995597) (xy 133.241795 -427.972623) (xy 133.241288 -427.960536)
			(xy 133.241288 -427.348142) (xy 133.239741 -427.33365) (xy 133.238091 -427.30455) (xy 133.237986 -427.289976)
			(xy 132.335016 -427.289976) (xy 132.335016 -428.28972) (xy 135.237982 -428.28972) (xy 135.238076 -428.275146)
			(xy 135.239728 -428.246045) (xy 135.241284 -428.231554) (xy 135.241284 -427.14799) (xy 135.239741 -427.133498)
			(xy 135.238088 -427.104398) (xy 135.237982 -427.089824) (xy 135.238077 -427.07525) (xy 135.239728 -427.046149)
			(xy 135.241284 -427.031658) (xy 135.241284 -426.41901) (xy 135.241669 -426.406883) (xy 135.249164 -426.383817)
			(xy 135.263423 -426.364198) (xy 135.283049 -426.349948) (xy 135.306119 -426.342464) (xy 135.318246 -426.342048)
			(xy 136.258046 -426.342048) (xy 136.270164 -426.342473) (xy 136.29321 -426.349974) (xy 136.312812 -426.364228)
			(xy 136.327052 -426.38384) (xy 136.334536 -426.406892) (xy 136.335008 -426.41901) (xy 136.335008 -427.289976)
			(xy 137.237978 -427.289976) (xy 137.238068 -427.275402) (xy 137.239723 -427.246301) (xy 137.24128 -427.23181)
			(xy 137.24128 -426.147992) (xy 137.239737 -426.1335) (xy 137.238084 -426.1044) (xy 137.237978 -426.089826)
			(xy 137.238073 -426.075252) (xy 137.239724 -426.046151) (xy 137.24128 -426.03166) (xy 137.24128 -425.419012)
			(xy 137.241727 -425.406906) (xy 137.24922 -425.383882) (xy 137.263475 -425.364311) (xy 137.283089 -425.350115)
			(xy 137.306135 -425.342691) (xy 137.318242 -425.342304) (xy 138.258042 -425.342304) (xy 138.27013 -425.342771)
			(xy 138.293126 -425.350235) (xy 138.312702 -425.364423) (xy 138.326953 -425.383953) (xy 138.33449 -425.406925)
			(xy 138.335004 -425.419012) (xy 138.335004 -427.960536) (xy 138.334614 -427.972646) (xy 138.327106 -427.995674)
			(xy 138.312837 -428.015246) (xy 138.29321 -428.02944) (xy 138.270154 -428.03686) (xy 138.258042 -428.037244)
			(xy 137.318242 -428.037244) (xy 137.306153 -428.036757) (xy 137.283151 -428.029309) (xy 137.263569 -428.015129)
			(xy 137.249318 -427.995598) (xy 137.241787 -427.972623) (xy 137.24128 -427.960536) (xy 137.24128 -427.348142)
			(xy 137.239733 -427.33365) (xy 137.238083 -427.30455) (xy 137.237978 -427.289976) (xy 136.335008 -427.289976)
			(xy 136.335008 -428.28972) (xy 139.237974 -428.28972) (xy 139.238068 -428.275146) (xy 139.23972 -428.246045)
			(xy 139.241276 -428.231554) (xy 139.241276 -427.14799) (xy 139.239733 -427.133498) (xy 139.23808 -427.104398)
			(xy 139.237974 -427.089824) (xy 139.238069 -427.07525) (xy 139.23972 -427.046149) (xy 139.241276 -427.031658)
			(xy 139.241276 -426.41901) (xy 139.241669 -426.406884) (xy 139.249163 -426.383819) (xy 139.26342 -426.364201)
			(xy 139.283044 -426.34995) (xy 139.306112 -426.342465) (xy 139.318238 -426.342048) (xy 140.258038 -426.342048)
			(xy 140.270156 -426.342479) (xy 140.293202 -426.349978) (xy 140.312804 -426.36423) (xy 140.327044 -426.383841)
			(xy 140.334528 -426.406892) (xy 140.335 -426.41901) (xy 140.335 -427.289976) (xy 142.237968 -427.289976)
			(xy 142.238082 -427.274891) (xy 142.23986 -427.244772) (xy 142.241524 -427.229778) (xy 142.241524 -426.150024)
			(xy 142.239855 -426.135031) (xy 142.238077 -426.104912) (xy 142.237968 -426.089826) (xy 142.238078 -426.07474)
			(xy 142.239859 -426.044622) (xy 142.241524 -426.029628) (xy 142.241524 -425.419012) (xy 142.241924 -425.406927)
			(xy 142.249392 -425.383939) (xy 142.2636 -425.364386) (xy 142.283157 -425.350183) (xy 142.306147 -425.34272)
			(xy 142.318232 -425.342304) (xy 143.258032 -425.342304) (xy 143.270109 -425.342737) (xy 143.29308 -425.35021)
			(xy 143.312617 -425.364414) (xy 143.32681 -425.38396) (xy 143.33427 -425.406934) (xy 143.33474 -425.419012)
			(xy 143.33474 -427.960536) (xy 143.334267 -427.972609) (xy 143.326799 -427.995572) (xy 143.312603 -428.015106)
			(xy 143.293069 -428.0293) (xy 143.270105 -428.036768) (xy 143.258032 -428.037244) (xy 142.318232 -428.037244)
			(xy 142.306163 -428.036709) (xy 142.283203 -428.02926) (xy 142.263668 -428.01508) (xy 142.249471 -427.995558)
			(xy 142.242001 -427.972605) (xy 142.241524 -427.960536) (xy 142.241524 -427.350174) (xy 142.23986 -427.33518)
			(xy 142.238078 -427.305062) (xy 142.237968 -427.289976) (xy 140.335 -427.289976) (xy 140.335 -428.28972)
			(xy 144.237964 -428.28972) (xy 144.238073 -428.274634) (xy 144.239855 -428.244516) (xy 144.24152 -428.229522)
			(xy 144.24152 -427.150022) (xy 144.239851 -427.135029) (xy 144.238073 -427.10491) (xy 144.237964 -427.089824)
			(xy 144.238074 -427.074738) (xy 144.239855 -427.04462) (xy 144.24152 -427.029626) (xy 144.24152 -426.41901)
			(xy 144.242016 -426.406923) (xy 144.249467 -426.383926) (xy 144.263647 -426.364348) (xy 144.283173 -426.350096)
			(xy 144.306143 -426.34256) (xy 144.318228 -426.342048) (xy 145.258028 -426.342048) (xy 145.270133 -426.342492)
			(xy 145.293152 -426.349993) (xy 145.312721 -426.364249) (xy 145.326916 -426.383861) (xy 145.334345 -426.406904)
			(xy 145.334736 -426.41901) (xy 145.334736 -427.289976) (xy 146.23796 -427.289976) (xy 146.238074 -427.274891)
			(xy 146.239852 -427.244772) (xy 146.241516 -427.229778) (xy 146.241516 -426.150024) (xy 146.239847 -426.135031)
			(xy 146.238069 -426.104912) (xy 146.23796 -426.089826) (xy 146.23807 -426.07474) (xy 146.239851 -426.044622)
			(xy 146.241516 -426.029628) (xy 146.241516 -425.419012) (xy 146.241923 -425.406928) (xy 146.249391 -425.383941)
			(xy 146.263597 -425.364389) (xy 146.283152 -425.350185) (xy 146.306139 -425.342722) (xy 146.318224 -425.342304)
			(xy 147.258024 -425.342304) (xy 147.270101 -425.342744) (xy 147.293071 -425.350215) (xy 147.312609 -425.364417)
			(xy 147.326802 -425.383961) (xy 147.334261 -425.406935) (xy 147.334732 -425.419012) (xy 147.334732 -427.960536)
			(xy 147.334267 -427.97261) (xy 147.326798 -427.995574) (xy 147.3126 -428.015109) (xy 147.293064 -428.029303)
			(xy 147.270098 -428.036769) (xy 147.258024 -428.037244) (xy 146.318224 -428.037244) (xy 146.306154 -428.036716)
			(xy 146.283194 -428.029264) (xy 146.26366 -428.015083) (xy 146.249463 -427.99556) (xy 146.241993 -427.972605)
			(xy 146.241516 -427.960536) (xy 146.241516 -427.350174) (xy 146.239852 -427.33518) (xy 146.23807 -427.305062)
			(xy 146.23796 -427.289976) (xy 145.334736 -427.289976) (xy 145.334736 -428.28972) (xy 148.237956 -428.28972)
			(xy 148.238066 -428.274634) (xy 148.239847 -428.244516) (xy 148.241512 -428.229522) (xy 148.241512 -427.150022)
			(xy 148.239843 -427.135029) (xy 148.238065 -427.10491) (xy 148.237956 -427.089824) (xy 148.238066 -427.074738)
			(xy 148.239847 -427.04462) (xy 148.241512 -427.029626) (xy 148.241512 -426.41901) (xy 148.242015 -426.406924)
			(xy 148.249466 -426.383928) (xy 148.263644 -426.364351) (xy 148.283168 -426.350099) (xy 148.306136 -426.342562)
			(xy 148.31822 -426.342048) (xy 149.25802 -426.342048) (xy 149.270125 -426.342499) (xy 149.293144 -426.349997)
			(xy 149.312712 -426.364252) (xy 149.326908 -426.383863) (xy 149.334337 -426.406904) (xy 149.334728 -426.41901)
			(xy 149.334728 -427.289976) (xy 150.237952 -427.289976) (xy 150.238066 -427.274891) (xy 150.239844 -427.244772)
			(xy 150.241508 -427.229778) (xy 150.241508 -426.150024) (xy 150.239839 -426.135031) (xy 150.238061 -426.104912)
			(xy 150.237952 -426.089826) (xy 150.238062 -426.07474) (xy 150.239843 -426.044622) (xy 150.241508 -426.029628)
			(xy 150.241508 -425.419012) (xy 150.241923 -425.406928) (xy 150.249389 -425.383943) (xy 150.263594 -425.364392)
			(xy 150.283147 -425.350188) (xy 150.306132 -425.342723) (xy 150.318216 -425.342304) (xy 151.258016 -425.342304)
			(xy 151.270093 -425.342751) (xy 151.293062 -425.350219) (xy 151.3126 -425.36442) (xy 151.326794 -425.383963)
			(xy 151.334253 -425.406935) (xy 151.334724 -425.419012) (xy 151.334724 -427.960536) (xy 151.334267 -427.972611)
			(xy 151.326796 -427.995577) (xy 151.312597 -428.015112) (xy 151.293059 -428.029306) (xy 151.270091 -428.03677)
			(xy 151.258016 -428.037244) (xy 150.318216 -428.037244) (xy 150.306146 -428.036723) (xy 150.283185 -428.029269)
			(xy 150.263651 -428.015086) (xy 150.249455 -427.995561) (xy 150.241985 -427.972606) (xy 150.241508 -427.960536)
			(xy 150.241508 -427.350174) (xy 150.239844 -427.33518) (xy 150.238062 -427.305062) (xy 150.237952 -427.289976)
			(xy 149.334728 -427.289976) (xy 149.334728 -428.28972) (xy 152.237948 -428.28972) (xy 152.238058 -428.274634)
			(xy 152.239839 -428.244516) (xy 152.241504 -428.229522) (xy 152.241504 -427.150022) (xy 152.239835 -427.135029)
			(xy 152.238057 -427.10491) (xy 152.237948 -427.089824) (xy 152.238058 -427.074738) (xy 152.239839 -427.04462)
			(xy 152.241504 -427.029626) (xy 152.241504 -426.41901) (xy 152.242015 -426.406925) (xy 152.249465 -426.38393)
			(xy 152.263641 -426.364353) (xy 152.283163 -426.350101) (xy 152.306128 -426.342563) (xy 152.318212 -426.342048)
			(xy 153.258012 -426.342048) (xy 153.270116 -426.342505) (xy 153.293135 -426.350002) (xy 153.312704 -426.364255)
			(xy 153.3269 -426.383864) (xy 153.334329 -426.406905) (xy 153.33472 -426.41901) (xy 153.33472 -427.289976)
			(xy 154.237944 -427.289976) (xy 154.238059 -427.274891) (xy 154.239836 -427.244772) (xy 154.2415 -427.229778)
			(xy 154.2415 -426.150024) (xy 154.239831 -426.135031) (xy 154.238053 -426.104912) (xy 154.237944 -426.089826)
			(xy 154.238054 -426.07474) (xy 154.239835 -426.044622) (xy 154.2415 -426.029628) (xy 154.2415 -425.419012)
			(xy 154.241923 -425.406929) (xy 154.249388 -425.383946) (xy 154.263592 -425.364394) (xy 154.283142 -425.35019)
			(xy 154.306125 -425.342724) (xy 154.318208 -425.342304) (xy 155.258008 -425.342304) (xy 155.270092 -425.342706)
			(xy 155.293077 -425.350177) (xy 155.312629 -425.364386) (xy 155.326832 -425.383941) (xy 155.334297 -425.406928)
			(xy 155.334716 -425.419012) (xy 155.334716 -427.960536) (xy 155.334267 -427.972612) (xy 155.326795 -427.995579)
			(xy 155.312595 -428.015115) (xy 155.293054 -428.029308) (xy 155.270084 -428.036771) (xy 155.258008 -428.037244)
			(xy 154.318208 -428.037244) (xy 154.306137 -428.03673) (xy 154.283177 -428.029274) (xy 154.263643 -428.015089)
			(xy 154.249447 -427.995563) (xy 154.241977 -427.972606) (xy 154.2415 -427.960536) (xy 154.2415 -427.350174)
			(xy 154.239836 -427.33518) (xy 154.238054 -427.305062) (xy 154.237944 -427.289976) (xy 153.33472 -427.289976)
			(xy 153.33472 -428.28972) (xy 156.23794 -428.28972) (xy 156.238052 -428.274634) (xy 156.239833 -428.244516)
			(xy 156.241496 -428.229522) (xy 156.241496 -427.150022) (xy 156.239827 -427.135029) (xy 156.238049 -427.10491)
			(xy 156.23794 -427.089824) (xy 156.23805 -427.074738) (xy 156.239831 -427.04462) (xy 156.241496 -427.029626)
			(xy 156.241496 -426.41901) (xy 156.242015 -426.406925) (xy 156.249464 -426.383932) (xy 156.263639 -426.364356)
			(xy 156.283158 -426.350104) (xy 156.306121 -426.342564) (xy 156.318204 -426.342048) (xy 157.258004 -426.342048)
			(xy 157.270108 -426.342512) (xy 157.293127 -426.350006) (xy 157.312695 -426.364257) (xy 157.326891 -426.383866)
			(xy 157.334321 -426.406905) (xy 157.334712 -426.41901) (xy 157.334712 -428.960534) (xy 157.334321 -428.97263)
			(xy 157.326849 -428.99564) (xy 157.312644 -429.015223) (xy 157.293092 -429.029471) (xy 157.270099 -429.036994)
			(xy 157.258004 -429.037496) (xy 156.318204 -429.037496) (xy 156.306095 -429.03708) (xy 156.283067 -429.029582)
			(xy 156.263493 -429.01532) (xy 156.249299 -428.995698) (xy 156.241879 -428.972644) (xy 156.241496 -428.960534)
			(xy 156.241496 -428.349918) (xy 156.239827 -428.334925) (xy 156.238049 -428.304806) (xy 156.23794 -428.28972)
			(xy 153.33472 -428.28972) (xy 153.33472 -428.960534) (xy 153.334321 -428.972629) (xy 153.32685 -428.995638)
			(xy 153.312647 -429.015221) (xy 153.293097 -429.029469) (xy 153.270106 -429.036993) (xy 153.258012 -429.037496)
			(xy 152.318212 -429.037496) (xy 152.306103 -429.037073) (xy 152.283076 -429.029577) (xy 152.263502 -429.015317)
			(xy 152.249307 -428.995696) (xy 152.241887 -428.972644) (xy 152.241504 -428.960534) (xy 152.241504 -428.349918)
			(xy 152.239835 -428.334925) (xy 152.238057 -428.304806) (xy 152.237948 -428.28972) (xy 149.334728 -428.28972)
			(xy 149.334728 -428.960534) (xy 149.334321 -428.972629) (xy 149.326851 -428.995636) (xy 149.31265 -429.015218)
			(xy 149.293102 -429.029466) (xy 149.270113 -429.036992) (xy 149.25802 -429.037496) (xy 148.31822 -429.037496)
			(xy 148.306112 -429.037066) (xy 148.283085 -429.029572) (xy 148.263511 -429.015314) (xy 148.249316 -428.995695)
			(xy 148.241895 -428.972643) (xy 148.241512 -428.960534) (xy 148.241512 -428.349918) (xy 148.239843 -428.334925)
			(xy 148.238065 -428.304806) (xy 148.237956 -428.28972) (xy 145.334736 -428.28972) (xy 145.334736 -428.960534)
			(xy 145.334321 -428.972628) (xy 145.326852 -428.995634) (xy 145.312653 -429.015215) (xy 145.293107 -429.029464)
			(xy 145.27012 -429.03699) (xy 145.258028 -429.037496) (xy 144.318228 -429.037496) (xy 144.30612 -429.03706)
			(xy 144.283093 -429.029567) (xy 144.263519 -429.015311) (xy 144.249324 -428.995693) (xy 144.241903 -428.972643)
			(xy 144.24152 -428.960534) (xy 144.24152 -428.349918) (xy 144.239851 -428.334925) (xy 144.238073 -428.304806)
			(xy 144.237964 -428.28972) (xy 140.335 -428.28972) (xy 140.335 -428.960534) (xy 140.334518 -428.972647)
			(xy 140.327026 -428.995684) (xy 140.312785 -429.015282) (xy 140.293188 -429.029524) (xy 140.270151 -429.037017)
			(xy 140.258038 -429.037496) (xy 139.318238 -429.037496) (xy 139.306121 -429.037008) (xy 139.283069 -429.029531)
			(xy 139.263456 -429.015295) (xy 139.249202 -428.995696) (xy 139.241703 -428.972651) (xy 139.241276 -428.960534)
			(xy 139.241276 -428.347886) (xy 139.239733 -428.333394) (xy 139.23808 -428.304294) (xy 139.237974 -428.28972)
			(xy 136.335008 -428.28972) (xy 136.335008 -428.960534) (xy 136.334518 -428.972646) (xy 136.327027 -428.995682)
			(xy 136.312788 -429.01528) (xy 136.293193 -429.029522) (xy 136.270158 -429.037016) (xy 136.258046 -429.037496)
			(xy 135.318246 -429.037496) (xy 135.306129 -429.037002) (xy 135.283077 -429.029526) (xy 135.263464 -429.015292)
			(xy 135.249211 -428.995694) (xy 135.241711 -428.972651) (xy 135.241284 -428.960534) (xy 135.241284 -428.347886)
			(xy 135.239741 -428.333394) (xy 135.238088 -428.304294) (xy 135.237982 -428.28972) (xy 132.335016 -428.28972)
			(xy 132.335016 -428.960534) (xy 132.334668 -428.972663) (xy 132.327161 -428.995731) (xy 132.312892 -429.015349)
			(xy 132.293259 -429.029598) (xy 132.270184 -429.037081) (xy 132.258054 -429.037496) (xy 131.318254 -429.037496)
			(xy 131.30614 -429.037028) (xy 131.283101 -429.029532) (xy 131.263503 -429.015288) (xy 131.249262 -428.995688)
			(xy 131.24177 -428.972648) (xy 131.241292 -428.960534) (xy 131.241292 -428.347886) (xy 131.239749 -428.333394)
			(xy 131.238096 -428.304294) (xy 131.23799 -428.28972) (xy 128.335024 -428.28972) (xy 128.335024 -428.960534)
			(xy 128.334669 -428.972662) (xy 128.327162 -428.995729) (xy 128.312895 -429.015347) (xy 128.293264 -429.029595)
			(xy 128.270191 -429.03708) (xy 128.258062 -429.037496) (xy 127.318262 -429.037496) (xy 127.306149 -429.037021)
			(xy 127.28311 -429.029528) (xy 127.263512 -429.015285) (xy 127.24927 -428.995686) (xy 127.241778 -428.972647)
			(xy 127.2413 -428.960534) (xy 127.2413 -428.347886) (xy 127.239757 -428.333394) (xy 127.238104 -428.304294)
			(xy 127.237998 -428.28972) (xy 113.943382 -428.28972) (xy 113.956414 -428.297518) (xy 114.097839 -428.391417)
			(xy 114.234709 -428.491842) (xy 114.36672 -428.598572) (xy 114.493584 -428.711373) (xy 114.615021 -428.829996)
			(xy 114.730765 -428.954181) (xy 114.84056 -429.083654) (xy 114.944167 -429.218131) (xy 115.041356 -429.357317)
			(xy 115.131914 -429.500905) (xy 115.215642 -429.648581) (xy 115.292357 -429.800018) (xy 115.361889 -429.954885)
			(xy 115.424086 -430.11284) (xy 115.47881 -430.273538) (xy 115.525942 -430.436623) (xy 115.565378 -430.601739)
			(xy 115.597032 -430.768522) (xy 115.614222 -430.889918) (xy 125.238002 -430.889918) (xy 125.238096 -430.875344)
			(xy 125.239748 -430.846243) (xy 125.241304 -430.831752) (xy 125.241304 -429.747934) (xy 125.239756 -429.733442)
			(xy 125.238106 -429.704342) (xy 125.238002 -429.689768) (xy 125.2381 -429.675194) (xy 125.23975 -429.646093)
			(xy 125.241304 -429.631602) (xy 125.241304 -429.018954) (xy 125.241772 -429.00684) (xy 125.249268 -428.983801)
			(xy 125.263512 -428.964203) (xy 125.283112 -428.949962) (xy 125.306152 -428.94247) (xy 125.318266 -428.941992)
			(xy 126.258066 -428.941992) (xy 126.270174 -428.94254) (xy 126.293209 -428.950012) (xy 126.312807 -428.964236)
			(xy 126.327051 -428.98382) (xy 126.334547 -429.006846) (xy 126.335028 -429.018954) (xy 126.335028 -431.560478)
			(xy 126.334621 -431.572603) (xy 126.32713 -431.595667) (xy 126.312877 -431.615285) (xy 126.293256 -431.629536)
			(xy 126.270191 -431.637023) (xy 126.258066 -431.63744) (xy 125.318266 -431.63744) (xy 125.306147 -431.637017)
			(xy 125.283099 -431.629518) (xy 125.263496 -431.615264) (xy 125.249257 -431.59565) (xy 125.241774 -431.572597)
			(xy 125.241304 -431.560478) (xy 125.241304 -430.948084) (xy 125.23976 -430.933592) (xy 125.238108 -430.904492)
			(xy 125.238002 -430.889918) (xy 115.614222 -430.889918) (xy 115.620833 -430.936605) (xy 115.636729 -431.105619)
			(xy 115.644686 -431.275192) (xy 115.645184 -431.360072) (xy 115.644698 -431.445674) (xy 115.63661 -431.616688)
			(xy 115.620446 -431.787128) (xy 115.605768 -431.889916) (xy 127.237998 -431.889916) (xy 127.238092 -431.875342)
			(xy 127.239744 -431.846241) (xy 127.2413 -431.83175) (xy 127.2413 -430.747932) (xy 127.239752 -430.73344)
			(xy 127.238102 -430.70434) (xy 127.237998 -430.689766) (xy 127.238096 -430.675192) (xy 127.239746 -430.646091)
			(xy 127.2413 -430.6316) (xy 127.2413 -430.018952) (xy 127.241676 -430.006841) (xy 127.249188 -429.983812)
			(xy 127.26346 -429.96424) (xy 127.28309 -429.950047) (xy 127.306149 -429.942627) (xy 127.318262 -429.942244)
			(xy 128.258062 -429.942244) (xy 128.27015 -429.94274) (xy 128.29315 -429.950187) (xy 128.312731 -429.964366)
			(xy 128.326983 -429.983894) (xy 128.334515 -430.006866) (xy 128.335024 -430.018952) (xy 128.335024 -430.889918)
			(xy 129.237994 -430.889918) (xy 129.238088 -430.875344) (xy 129.23974 -430.846243) (xy 129.241296 -430.831752)
			(xy 129.241296 -429.747934) (xy 129.239749 -429.733442) (xy 129.238098 -429.704342) (xy 129.237994 -429.689768)
			(xy 129.238092 -429.675194) (xy 129.239742 -429.646093) (xy 129.241296 -429.631602) (xy 129.241296 -429.018954)
			(xy 129.241772 -429.006841) (xy 129.249267 -428.983804) (xy 129.263509 -428.964206) (xy 129.283107 -428.949965)
			(xy 129.306145 -428.942471) (xy 129.318258 -428.941992) (xy 130.258058 -428.941992) (xy 130.270166 -428.942547)
			(xy 130.2932 -428.950017) (xy 130.312798 -428.964239) (xy 130.327043 -428.983821) (xy 130.334539 -429.006847)
			(xy 130.33502 -429.018954) (xy 130.33502 -431.560478) (xy 130.334621 -431.572604) (xy 130.327129 -431.595669)
			(xy 130.312874 -431.615288) (xy 130.293251 -431.629538) (xy 130.270184 -431.637024) (xy 130.258058 -431.63744)
			(xy 129.318258 -431.63744) (xy 129.306139 -431.637024) (xy 129.283091 -431.629522) (xy 129.263488 -431.615267)
			(xy 129.249248 -431.595652) (xy 129.241766 -431.572597) (xy 129.241296 -431.560478) (xy 129.241296 -430.948084)
			(xy 129.239753 -430.933592) (xy 129.2381 -430.904492) (xy 129.237994 -430.889918) (xy 128.335024 -430.889918)
			(xy 128.335024 -431.889916) (xy 131.23799 -431.889916) (xy 131.238084 -431.875342) (xy 131.239736 -431.846241)
			(xy 131.241292 -431.83175) (xy 131.241292 -430.747932) (xy 131.239744 -430.73344) (xy 131.238094 -430.70434)
			(xy 131.23799 -430.689766) (xy 131.238088 -430.675192) (xy 131.239738 -430.646091) (xy 131.241292 -430.6316)
			(xy 131.241292 -430.018952) (xy 131.241675 -430.006841) (xy 131.249187 -429.983814) (xy 131.263458 -429.964242)
			(xy 131.283085 -429.950049) (xy 131.306142 -429.942628) (xy 131.318254 -429.942244) (xy 132.258054 -429.942244)
			(xy 132.270142 -429.942747) (xy 132.293141 -429.950191) (xy 132.312722 -429.964368) (xy 132.326974 -429.983895)
			(xy 132.334507 -430.006866) (xy 132.335016 -430.018952) (xy 132.335016 -430.889918) (xy 133.237986 -430.889918)
			(xy 133.23808 -430.875344) (xy 133.239732 -430.846243) (xy 133.241288 -430.831752) (xy 133.241288 -429.747934)
			(xy 133.239741 -429.733442) (xy 133.23809 -429.704342) (xy 133.237986 -429.689768) (xy 133.238084 -429.675194)
			(xy 133.239734 -429.646093) (xy 133.241288 -429.631602) (xy 133.241288 -429.018954) (xy 133.241772 -429.006842)
			(xy 133.249266 -428.983806) (xy 133.263506 -428.964209) (xy 133.283102 -428.949967) (xy 133.306138 -428.942472)
			(xy 133.31825 -428.941992) (xy 134.25805 -428.941992) (xy 134.270163 -428.942468) (xy 134.2932 -428.949964)
			(xy 134.312797 -428.964206) (xy 134.327038 -428.983804) (xy 134.334532 -429.006841) (xy 134.335012 -429.018954)
			(xy 134.335012 -431.560478) (xy 134.33447 -431.572586) (xy 134.326995 -431.59562) (xy 134.312769 -431.615218)
			(xy 134.293185 -431.629462) (xy 134.270158 -431.636959) (xy 134.25805 -431.63744) (xy 133.31825 -431.63744)
			(xy 133.306131 -431.63703) (xy 133.283082 -431.629527) (xy 133.263479 -431.615269) (xy 133.24924 -431.595653)
			(xy 133.241758 -431.572598) (xy 133.241288 -431.560478) (xy 133.241288 -430.948084) (xy 133.239745 -430.933592)
			(xy 133.238092 -430.904492) (xy 133.237986 -430.889918) (xy 132.335016 -430.889918) (xy 132.335016 -431.889916)
			(xy 135.237982 -431.889916) (xy 135.238076 -431.875342) (xy 135.239728 -431.846241) (xy 135.241284 -431.83175)
			(xy 135.241284 -430.747932) (xy 135.239736 -430.73344) (xy 135.238086 -430.70434) (xy 135.237982 -430.689766)
			(xy 135.23808 -430.675192) (xy 135.23973 -430.646091) (xy 135.241284 -430.6316) (xy 135.241284 -430.018952)
			(xy 135.241675 -430.006842) (xy 135.249186 -429.983816) (xy 135.263455 -429.964245) (xy 135.28308 -429.950052)
			(xy 135.306135 -429.942629) (xy 135.318246 -429.942244) (xy 136.258046 -429.942244) (xy 136.270138 -429.942668)
			(xy 136.293141 -429.950138) (xy 136.312721 -429.964336) (xy 136.32697 -429.983878) (xy 136.3345 -430.006861)
			(xy 136.335008 -430.018952) (xy 136.335008 -430.889918) (xy 137.237978 -430.889918) (xy 137.238072 -430.875344)
			(xy 137.239724 -430.846243) (xy 137.24128 -430.831752) (xy 137.24128 -429.747934) (xy 137.239733 -429.733442)
			(xy 137.238082 -429.704342) (xy 137.237978 -429.689768) (xy 137.238076 -429.675194) (xy 137.239726 -429.646093)
			(xy 137.24128 -429.631602) (xy 137.24128 -429.018954) (xy 137.241673 -429.006833) (xy 137.249178 -428.983781)
			(xy 137.263439 -428.964176) (xy 137.28306 -428.949938) (xy 137.30612 -428.942459) (xy 137.318242 -428.941992)
			(xy 138.258042 -428.941992) (xy 138.270154 -428.942475) (xy 138.293191 -428.949968) (xy 138.312788 -428.964209)
			(xy 138.32703 -428.983805) (xy 138.334524 -429.006842) (xy 138.335004 -429.018954) (xy 138.335004 -431.560478)
			(xy 138.33447 -431.572587) (xy 138.326994 -431.595623) (xy 138.312767 -431.615221) (xy 138.29318 -431.629465)
			(xy 138.270151 -431.63696) (xy 138.258042 -431.63744) (xy 137.318242 -431.63744) (xy 137.306119 -431.637004)
			(xy 137.283058 -431.629521) (xy 137.26344 -431.615274) (xy 137.249188 -431.59566) (xy 137.241699 -431.572601)
			(xy 137.24128 -431.560478) (xy 137.24128 -430.948084) (xy 137.239737 -430.933592) (xy 137.238084 -430.904492)
			(xy 137.237978 -430.889918) (xy 136.335008 -430.889918) (xy 136.335008 -431.889916) (xy 139.237974 -431.889916)
			(xy 139.238068 -431.875342) (xy 139.23972 -431.846241) (xy 139.241276 -431.83175) (xy 139.241276 -430.747932)
			(xy 139.239728 -430.73344) (xy 139.238078 -430.70434) (xy 139.237974 -430.689766) (xy 139.238072 -430.675192)
			(xy 139.239722 -430.646091) (xy 139.241276 -430.6316) (xy 139.241276 -430.018952) (xy 139.241675 -430.006843)
			(xy 139.249185 -429.983818) (xy 139.263452 -429.964248) (xy 139.283075 -429.950054) (xy 139.306128 -429.94263)
			(xy 139.318238 -429.942244) (xy 140.258038 -429.942244) (xy 140.27013 -429.942675) (xy 140.293133 -429.950143)
			(xy 140.312712 -429.964338) (xy 140.326961 -429.983879) (xy 140.334492 -430.006861) (xy 140.335 -430.018952)
			(xy 140.335 -430.889918) (xy 142.237968 -430.889918) (xy 142.238077 -430.874832) (xy 142.239859 -430.844714)
			(xy 142.241524 -430.82972) (xy 142.241524 -429.749966) (xy 142.239859 -429.734972) (xy 142.238078 -429.704854)
			(xy 142.237968 -429.689768) (xy 142.238082 -429.674682) (xy 142.23986 -429.644564) (xy 142.241524 -429.62957)
			(xy 142.241524 -429.018954) (xy 142.241968 -429.006864) (xy 142.249435 -428.983864) (xy 142.263628 -428.964286)
			(xy 142.283165 -428.950037) (xy 142.306143 -428.942503) (xy 142.318232 -428.941992) (xy 143.258032 -428.941992)
			(xy 143.270142 -428.942389) (xy 143.293169 -428.949896) (xy 143.312741 -428.964163) (xy 143.326934 -428.983788)
			(xy 143.334356 -429.006843) (xy 143.33474 -429.018954) (xy 143.33474 -431.560478) (xy 143.334273 -431.572568)
			(xy 143.32682 -431.595572) (xy 143.312634 -431.615154) (xy 143.293099 -431.629404) (xy 143.270121 -431.636933)
			(xy 143.258032 -431.63744) (xy 142.318232 -431.63744) (xy 142.306129 -431.636957) (xy 142.283109 -431.629471)
			(xy 142.263539 -431.615225) (xy 142.249342 -431.59562) (xy 142.241913 -431.572582) (xy 142.241524 -431.560478)
			(xy 142.241524 -430.950116) (xy 142.239855 -430.935123) (xy 142.238077 -430.905004) (xy 142.237968 -430.889918)
			(xy 140.335 -430.889918) (xy 140.335 -431.889916) (xy 144.237964 -431.889916) (xy 144.238073 -431.87483)
			(xy 144.239855 -431.844712) (xy 144.24152 -431.829718) (xy 144.24152 -430.749964) (xy 144.239855 -430.73497)
			(xy 144.238074 -430.704852) (xy 144.237964 -430.689766) (xy 144.238078 -430.67468) (xy 144.239856 -430.644562)
			(xy 144.24152 -430.629568) (xy 144.24152 -430.018952) (xy 144.241924 -430.006872) (xy 144.249403 -429.983899)
			(xy 144.263614 -429.96436) (xy 144.283167 -429.950168) (xy 144.306148 -429.942712) (xy 144.318228 -429.942244)
			(xy 145.258028 -429.942244) (xy 145.270099 -429.942739) (xy 145.293059 -429.950204) (xy 145.312592 -429.964394)
			(xy 145.326787 -429.983923) (xy 145.334258 -430.006881) (xy 145.334736 -430.018952) (xy 145.334736 -430.889918)
			(xy 146.23796 -430.889918) (xy 146.238069 -430.874832) (xy 146.239851 -430.844714) (xy 146.241516 -430.82972)
			(xy 146.241516 -429.749966) (xy 146.239851 -429.734972) (xy 146.23807 -429.704854) (xy 146.23796 -429.689768)
			(xy 146.238074 -429.674682) (xy 146.239852 -429.644564) (xy 146.241516 -429.62957) (xy 146.241516 -429.018954)
			(xy 146.241968 -429.006864) (xy 146.249434 -428.983866) (xy 146.263626 -428.964289) (xy 146.28316 -428.950039)
			(xy 146.306136 -428.942504) (xy 146.318224 -428.941992) (xy 147.258024 -428.941992) (xy 147.270133 -428.942396)
			(xy 147.29316 -428.949901) (xy 147.312732 -428.964166) (xy 147.326926 -428.983789) (xy 147.334348 -429.006843)
			(xy 147.334732 -429.018954) (xy 147.334732 -431.560478) (xy 147.334273 -431.572569) (xy 147.326819 -431.595574)
			(xy 147.312632 -431.615156) (xy 147.293094 -431.629407) (xy 147.270114 -431.636934) (xy 147.258024 -431.63744)
			(xy 146.318224 -431.63744) (xy 146.30612 -431.636964) (xy 146.283101 -431.629476) (xy 146.263531 -431.615228)
			(xy 146.249334 -431.595622) (xy 146.241905 -431.572583) (xy 146.241516 -431.560478) (xy 146.241516 -430.950116)
			(xy 146.239847 -430.935123) (xy 146.238069 -430.905004) (xy 146.23796 -430.889918) (xy 145.334736 -430.889918)
			(xy 145.334736 -431.889916) (xy 148.237956 -431.889916) (xy 148.238065 -431.87483) (xy 148.239847 -431.844712)
			(xy 148.241512 -431.829718) (xy 148.241512 -430.749964) (xy 148.239847 -430.73497) (xy 148.238066 -430.704852)
			(xy 148.237956 -430.689766) (xy 148.23807 -430.67468) (xy 148.239848 -430.644562) (xy 148.241512 -430.629568)
			(xy 148.241512 -430.018952) (xy 148.241924 -430.006873) (xy 148.249402 -429.983901) (xy 148.263611 -429.964363)
			(xy 148.283162 -429.950171) (xy 148.306141 -429.942713) (xy 148.31822 -429.942244) (xy 149.25802 -429.942244)
			(xy 149.270091 -429.942747) (xy 149.29305 -429.950209) (xy 149.312583 -429.964397) (xy 149.326778 -429.983924)
			(xy 149.334249 -430.006881) (xy 149.334728 -430.018952) (xy 149.334728 -430.889918) (xy 150.237952 -430.889918)
			(xy 150.238061 -430.874832) (xy 150.239843 -430.844714) (xy 150.241508 -430.82972) (xy 150.241508 -429.749966)
			(xy 150.239843 -429.734972) (xy 150.238062 -429.704854) (xy 150.237952 -429.689768) (xy 150.238066 -429.674682)
			(xy 150.239844 -429.644564) (xy 150.241508 -429.62957) (xy 150.241508 -429.018954) (xy 150.241968 -429.006865)
			(xy 150.249433 -428.983868) (xy 150.263623 -428.964292) (xy 150.283155 -428.950042) (xy 150.306129 -428.942505)
			(xy 150.318216 -428.941992) (xy 151.258016 -428.941992) (xy 151.270125 -428.942402) (xy 151.293151 -428.949905)
			(xy 151.312724 -428.964169) (xy 151.326918 -428.983791) (xy 151.33434 -429.006844) (xy 151.334724 -429.018954)
			(xy 151.334724 -431.560478) (xy 151.334273 -431.57257) (xy 151.326818 -431.595576) (xy 151.312629 -431.615159)
			(xy 151.293089 -431.629409) (xy 151.270106 -431.636935) (xy 151.258016 -431.63744) (xy 150.318216 -431.63744)
			(xy 150.306112 -431.63697) (xy 150.283092 -431.62948) (xy 150.263522 -431.615231) (xy 150.249326 -431.595623)
			(xy 150.241897 -431.572583) (xy 150.241508 -431.560478) (xy 150.241508 -430.950116) (xy 150.239839 -430.935123)
			(xy 150.238061 -430.905004) (xy 150.237952 -430.889918) (xy 149.334728 -430.889918) (xy 149.334728 -431.889916)
			(xy 152.237948 -431.889916) (xy 152.238057 -431.87483) (xy 152.239839 -431.844712) (xy 152.241504 -431.829718)
			(xy 152.241504 -430.749964) (xy 152.239839 -430.73497) (xy 152.238058 -430.704852) (xy 152.237948 -430.689766)
			(xy 152.238062 -430.67468) (xy 152.23984 -430.644562) (xy 152.241504 -430.629568) (xy 152.241504 -430.018952)
			(xy 152.241923 -430.006874) (xy 152.249401 -429.983903) (xy 152.263608 -429.964366) (xy 152.283157 -429.950173)
			(xy 152.306133 -429.942714) (xy 152.318212 -429.942244) (xy 153.258012 -429.942244) (xy 153.270082 -429.942753)
			(xy 153.293042 -429.950213) (xy 153.312574 -429.9644) (xy 153.32677 -429.983926) (xy 153.334241 -430.006882)
			(xy 153.33472 -430.018952) (xy 153.33472 -430.889918) (xy 154.237944 -430.889918) (xy 154.238053 -430.874832)
			(xy 154.239835 -430.844714) (xy 154.2415 -430.82972) (xy 154.2415 -429.749966) (xy 154.239835 -429.734972)
			(xy 154.238054 -429.704854) (xy 154.237944 -429.689768) (xy 154.238058 -429.674682) (xy 154.239836 -429.644564)
			(xy 154.2415 -429.62957) (xy 154.2415 -429.018954) (xy 154.241967 -429.006866) (xy 154.249432 -428.983871)
			(xy 154.26362 -428.964295) (xy 154.28315 -428.950044) (xy 154.306122 -428.942507) (xy 154.318208 -428.941992)
			(xy 155.258008 -428.941992) (xy 155.270117 -428.942409) (xy 155.293143 -428.94991) (xy 155.312715 -428.964172)
			(xy 155.32691 -428.983792) (xy 155.334332 -429.006844) (xy 155.334716 -429.018954) (xy 155.334716 -431.560478)
			(xy 155.334273 -431.572571) (xy 155.326817 -431.595578) (xy 155.312626 -431.615162) (xy 155.293084 -431.629412)
			(xy 155.270099 -431.636937) (xy 155.258008 -431.63744) (xy 154.318208 -431.63744) (xy 154.306104 -431.636978)
			(xy 154.283083 -431.629485) (xy 154.263513 -431.615234) (xy 154.249317 -431.595625) (xy 154.241889 -431.572584)
			(xy 154.2415 -431.560478) (xy 154.2415 -430.950116) (xy 154.239831 -430.935123) (xy 154.238053 -430.905004)
			(xy 154.237944 -430.889918) (xy 153.33472 -430.889918) (xy 153.33472 -431.889916) (xy 156.23794 -431.889916)
			(xy 156.238051 -431.87483) (xy 156.239833 -431.844712) (xy 156.241496 -431.829718) (xy 156.241496 -430.749964)
			(xy 156.239831 -430.73497) (xy 156.23805 -430.704852) (xy 156.23794 -430.689766) (xy 156.238054 -430.67468)
			(xy 156.239832 -430.644562) (xy 156.241496 -430.629568) (xy 156.241496 -430.018952) (xy 156.241923 -430.006875)
			(xy 156.249399 -429.983905) (xy 156.263605 -429.964368) (xy 156.283152 -429.950176) (xy 156.306126 -429.942715)
			(xy 156.318204 -429.942244) (xy 157.258004 -429.942244) (xy 157.270074 -429.94276) (xy 157.293033 -429.950218)
			(xy 157.312566 -429.964403) (xy 157.326762 -429.983927) (xy 157.334233 -430.006882) (xy 157.334712 -430.018952)
			(xy 157.334712 -432.560476) (xy 157.334267 -432.572557) (xy 157.326806 -432.595538) (xy 157.312609 -432.615089)
			(xy 157.293063 -432.629294) (xy 157.270085 -432.636762) (xy 157.258004 -432.637184) (xy 156.318204 -432.637184)
			(xy 156.306119 -432.636784) (xy 156.283132 -432.629314) (xy 156.26358 -432.615106) (xy 156.249376 -432.59555)
			(xy 156.241913 -432.572561) (xy 156.241496 -432.560476) (xy 156.241496 -431.950114) (xy 156.239826 -431.935121)
			(xy 156.238049 -431.905002) (xy 156.23794 -431.889916) (xy 153.33472 -431.889916) (xy 153.33472 -432.560476)
			(xy 153.334267 -432.572556) (xy 153.326807 -432.595536) (xy 153.312611 -432.615086) (xy 153.293068 -432.629291)
			(xy 153.270092 -432.636761) (xy 153.258012 -432.637184) (xy 152.318212 -432.637184) (xy 152.306128 -432.636777)
			(xy 152.283141 -432.629309) (xy 152.263589 -432.615103) (xy 152.249385 -432.595548) (xy 152.241922 -432.572561)
			(xy 152.241504 -432.560476) (xy 152.241504 -431.950114) (xy 152.239834 -431.935121) (xy 152.238057 -431.905002)
			(xy 152.237948 -431.889916) (xy 149.334728 -431.889916) (xy 149.334728 -432.560476) (xy 149.334267 -432.572555)
			(xy 149.326809 -432.595534) (xy 149.312614 -432.615083) (xy 149.293073 -432.629288) (xy 149.270099 -432.63676)
			(xy 149.25802 -432.637184) (xy 148.31822 -432.637184) (xy 148.306136 -432.63677) (xy 148.28315 -432.629305)
			(xy 148.263597 -432.6151) (xy 148.249393 -432.595547) (xy 148.24193 -432.57256) (xy 148.241512 -432.560476)
			(xy 148.241512 -431.950114) (xy 148.239842 -431.935121) (xy 148.238065 -431.905002) (xy 148.237956 -431.889916)
			(xy 145.334736 -431.889916) (xy 145.334736 -432.560476) (xy 145.334216 -432.572547) (xy 145.326763 -432.595508)
			(xy 145.31258 -432.615043) (xy 145.293055 -432.62924) (xy 145.270098 -432.636708) (xy 145.258028 -432.637184)
			(xy 144.318228 -432.637184) (xy 144.306144 -432.636763) (xy 144.283159 -432.6293) (xy 144.263606 -432.615097)
			(xy 144.249402 -432.595545) (xy 144.241938 -432.57256) (xy 144.24152 -432.560476) (xy 144.24152 -431.950114)
			(xy 144.23985 -431.935121) (xy 144.238073 -431.905002) (xy 144.237964 -431.889916) (xy 140.335 -431.889916)
			(xy 140.335 -432.560476) (xy 140.334563 -432.572584) (xy 140.32707 -432.59561) (xy 140.312814 -432.615184)
			(xy 140.293196 -432.629379) (xy 140.270147 -432.6368) (xy 140.258038 -432.637184) (xy 139.318238 -432.637184)
			(xy 139.306153 -432.636661) (xy 139.283157 -432.629217) (xy 139.263579 -432.615044) (xy 139.249326 -432.595524)
			(xy 139.241789 -432.572559) (xy 139.241276 -432.560476) (xy 139.241276 -431.948082) (xy 139.239733 -431.93359)
			(xy 139.23808 -431.90449) (xy 139.237974 -431.889916) (xy 136.335008 -431.889916) (xy 136.335008 -432.560476)
			(xy 136.334563 -432.572583) (xy 136.327071 -432.595608) (xy 136.312817 -432.615181) (xy 136.293201 -432.629376)
			(xy 136.270154 -432.636799) (xy 136.258046 -432.637184) (xy 135.318246 -432.637184) (xy 135.306161 -432.636654)
			(xy 135.283166 -432.629213) (xy 135.263587 -432.615042) (xy 135.249334 -432.595522) (xy 135.241797 -432.572559)
			(xy 135.241284 -432.560476) (xy 135.241284 -431.948082) (xy 135.239741 -431.93359) (xy 135.238088 -431.90449)
			(xy 135.237982 -431.889916) (xy 132.335016 -431.889916) (xy 132.335016 -432.560476) (xy 132.334563 -432.572582)
			(xy 132.327072 -432.595606) (xy 132.31282 -432.615178) (xy 132.293206 -432.629374) (xy 132.270161 -432.636798)
			(xy 132.258054 -432.637184) (xy 131.318254 -432.637184) (xy 131.306164 -432.636732) (xy 131.283166 -432.629266)
			(xy 131.263589 -432.615074) (xy 131.249339 -432.59554) (xy 131.241804 -432.572564) (xy 131.241292 -432.560476)
			(xy 131.241292 -431.948082) (xy 131.239749 -431.93359) (xy 131.238096 -431.90449) (xy 131.23799 -431.889916)
			(xy 128.335024 -431.889916) (xy 128.335024 -432.560476) (xy 128.334563 -432.572581) (xy 128.327074 -432.595604)
			(xy 128.312823 -432.615175) (xy 128.293212 -432.629371) (xy 128.270168 -432.636797) (xy 128.258062 -432.637184)
			(xy 127.318262 -432.637184) (xy 127.306173 -432.636726) (xy 127.283175 -432.629261) (xy 127.263598 -432.615072)
			(xy 127.249348 -432.595538) (xy 127.241812 -432.572564) (xy 127.2413 -432.560476) (xy 127.2413 -431.948082)
			(xy 127.239756 -431.93359) (xy 127.238104 -431.90449) (xy 127.237998 -431.889916) (xy 115.605768 -431.889916)
			(xy 115.596243 -431.956613) (xy 115.564055 -432.124765) (xy 115.523953 -432.291207) (xy 115.476027 -432.455567)
			(xy 115.420385 -432.617477) (xy 115.35715 -432.776576) (xy 115.286464 -432.932508) (xy 115.208486 -433.084923)
			(xy 115.12339 -433.233482) (xy 115.031365 -433.377851) (xy 114.932619 -433.517709) (xy 114.82737 -433.652742)
			(xy 114.715856 -433.782648) (xy 114.598325 -433.907137) (xy 114.47504 -434.02593) (xy 114.346277 -434.138763)
			(xy 114.212324 -434.245381) (xy 114.07348 -434.345548) (xy 113.930056 -434.439039) (xy 113.843394 -434.48986)
			(xy 125.238002 -434.48986) (xy 125.2381 -434.475286) (xy 125.239749 -434.446185) (xy 125.241304 -434.431694)
			(xy 125.241304 -433.34813) (xy 125.239756 -433.333638) (xy 125.238106 -433.304538) (xy 125.238002 -433.289964)
			(xy 125.2381 -433.27539) (xy 125.239749 -433.246289) (xy 125.241304 -433.231798) (xy 125.241304 -432.618896)
			(xy 125.241713 -432.606787) (xy 125.249214 -432.583758) (xy 125.263477 -432.564185) (xy 125.283101 -432.549991)
			(xy 125.306155 -432.542571) (xy 125.318266 -432.542188) (xy 126.258066 -432.542188) (xy 126.270159 -432.542637)
			(xy 126.293166 -432.55009) (xy 126.312751 -432.56428) (xy 126.327001 -432.583821) (xy 126.334525 -432.606805)
			(xy 126.335028 -432.618896) (xy 126.335028 -435.16042) (xy 126.334601 -435.172527) (xy 126.3271 -435.19555)
			(xy 126.31284 -435.215121) (xy 126.293222 -435.229316) (xy 126.270174 -435.236741) (xy 126.258066 -435.237128)
			(xy 125.318266 -435.237128) (xy 125.306171 -435.236721) (xy 125.283164 -435.229251) (xy 125.263582 -435.21505)
			(xy 125.249334 -435.195502) (xy 125.241808 -435.172513) (xy 125.241304 -435.16042) (xy 125.241304 -434.548026)
			(xy 125.239756 -434.533534) (xy 125.238106 -434.504434) (xy 125.238002 -434.48986) (xy 113.843394 -434.48986)
			(xy 113.782372 -434.525645) (xy 113.630759 -434.605172) (xy 113.475556 -434.677443) (xy 113.396522 -434.710332)
			(xy 113.382851 -434.716444) (xy 113.359598 -434.735293) (xy 113.342813 -434.760077) (xy 113.333939 -434.788665)
			(xy 113.333741 -434.818598) (xy 113.342235 -434.847301) (xy 113.358691 -434.872305) (xy 113.369852 -434.88229)
			(xy 113.419298 -434.924299) (xy 113.513487 -435.013553) (xy 113.601975 -435.108462) (xy 113.684422 -435.208663)
			(xy 113.760513 -435.313772) (xy 113.829956 -435.423387) (xy 113.866512 -435.489858) (xy 127.237998 -435.489858)
			(xy 127.238095 -435.475284) (xy 127.239745 -435.446183) (xy 127.2413 -435.431692) (xy 127.2413 -434.348128)
			(xy 127.239752 -434.333636) (xy 127.238102 -434.304536) (xy 127.237998 -434.289962) (xy 127.238096 -434.275388)
			(xy 127.239745 -434.246287) (xy 127.2413 -434.231796) (xy 127.2413 -433.618894) (xy 127.241806 -433.606783)
			(xy 127.24929 -433.583746) (xy 127.263525 -433.564148) (xy 127.283117 -433.549905) (xy 127.306151 -433.542411)
			(xy 127.318262 -433.541932) (xy 128.258062 -433.541932) (xy 128.270182 -433.542392) (xy 128.293239 -433.549873)
			(xy 128.312854 -433.564115) (xy 128.327107 -433.583722) (xy 128.334601 -433.606774) (xy 128.335024 -433.618894)
			(xy 128.335024 -434.48986) (xy 129.237994 -434.48986) (xy 129.238092 -434.475286) (xy 129.239741 -434.446185)
			(xy 129.241296 -434.431694) (xy 129.241296 -433.34813) (xy 129.239748 -433.333638) (xy 129.238098 -433.304538)
			(xy 129.237994 -433.289964) (xy 129.238092 -433.27539) (xy 129.239741 -433.246289) (xy 129.241296 -433.231798)
			(xy 129.241296 -432.618896) (xy 129.241713 -432.606787) (xy 129.249213 -432.583761) (xy 129.263474 -432.564188)
			(xy 129.283096 -432.549993) (xy 129.306148 -432.542572) (xy 129.318258 -432.542188) (xy 130.258058 -432.542188)
			(xy 130.27015 -432.542644) (xy 130.293158 -432.550095) (xy 130.312742 -432.564283) (xy 130.326993 -432.583822)
			(xy 130.334517 -432.606805) (xy 130.33502 -432.618896) (xy 130.33502 -435.16042) (xy 130.334601 -435.172528)
			(xy 130.327099 -435.195552) (xy 130.312837 -435.215123) (xy 130.293217 -435.229318) (xy 130.270167 -435.236742)
			(xy 130.258058 -435.237128) (xy 129.318258 -435.237128) (xy 129.306163 -435.236728) (xy 129.283156 -435.229256)
			(xy 129.263574 -435.215053) (xy 129.249326 -435.195504) (xy 129.2418 -435.172514) (xy 129.241296 -435.16042)
			(xy 129.241296 -434.548026) (xy 129.239748 -434.533534) (xy 129.238098 -434.504434) (xy 129.237994 -434.48986)
			(xy 128.335024 -434.48986) (xy 128.335024 -435.489858) (xy 131.23799 -435.489858) (xy 131.238087 -435.475284)
			(xy 131.239737 -435.446183) (xy 131.241292 -435.431692) (xy 131.241292 -434.348128) (xy 131.239744 -434.333636)
			(xy 131.238094 -434.304536) (xy 131.23799 -434.289962) (xy 131.238088 -434.275388) (xy 131.239737 -434.246287)
			(xy 131.241292 -434.231796) (xy 131.241292 -433.618894) (xy 131.241806 -433.606784) (xy 131.249289 -433.583748)
			(xy 131.263522 -433.564151) (xy 131.283112 -433.549908) (xy 131.306144 -433.542412) (xy 131.318254 -433.541932)
			(xy 132.258054 -433.541932) (xy 132.270174 -433.542399) (xy 132.29323 -433.549878) (xy 132.312846 -433.564117)
			(xy 132.327098 -433.583723) (xy 132.334593 -433.606775) (xy 132.335016 -433.618894) (xy 132.335016 -434.48986)
			(xy 133.237986 -434.48986) (xy 133.238084 -434.475286) (xy 133.239733 -434.446185) (xy 133.241288 -434.431694)
			(xy 133.241288 -433.34813) (xy 133.23974 -433.333638) (xy 133.23809 -433.304538) (xy 133.237986 -433.289964)
			(xy 133.238084 -433.27539) (xy 133.239733 -433.246289) (xy 133.241288 -433.231798) (xy 133.241288 -432.618896)
			(xy 133.241713 -432.606788) (xy 133.249212 -432.583763) (xy 133.263472 -432.564191) (xy 133.283091 -432.549996)
			(xy 133.306141 -432.542573) (xy 133.31825 -432.542188) (xy 134.25805 -432.542188) (xy 134.270142 -432.542651)
			(xy 134.293149 -432.5501) (xy 134.312734 -432.564285) (xy 134.326984 -432.583823) (xy 134.334509 -432.606806)
			(xy 134.335012 -432.618896) (xy 134.335012 -435.16042) (xy 134.334601 -435.172529) (xy 134.327097 -435.195555)
			(xy 134.312834 -435.215126) (xy 134.293212 -435.229321) (xy 134.27016 -435.236743) (xy 134.25805 -435.237128)
			(xy 133.31825 -435.237128) (xy 133.30616 -435.23665) (xy 133.283155 -435.229203) (xy 133.263572 -435.21502)
			(xy 133.249321 -435.195487) (xy 133.241793 -435.172508) (xy 133.241288 -435.16042) (xy 133.241288 -434.548026)
			(xy 133.23974 -434.533534) (xy 133.23809 -434.504434) (xy 133.237986 -434.48986) (xy 132.335016 -434.48986)
			(xy 132.335016 -435.489858) (xy 135.237982 -435.489858) (xy 135.238079 -435.475284) (xy 135.239729 -435.446183)
			(xy 135.241284 -435.431692) (xy 135.241284 -434.348128) (xy 135.239736 -434.333636) (xy 135.238086 -434.304536)
			(xy 135.237982 -434.289962) (xy 135.23808 -434.275388) (xy 135.239729 -434.246287) (xy 135.241284 -434.231796)
			(xy 135.241284 -433.618894) (xy 135.241656 -433.606766) (xy 135.249155 -433.5837) (xy 135.263418 -433.564081)
			(xy 135.283046 -433.549831) (xy 135.306118 -433.542348) (xy 135.318246 -433.541932) (xy 136.258046 -433.541932)
			(xy 136.270162 -433.542372) (xy 136.293206 -433.549872) (xy 136.312807 -433.564122) (xy 136.327047 -433.58373)
			(xy 136.334534 -433.606777) (xy 136.335008 -433.618894) (xy 136.335008 -434.48986) (xy 137.237978 -434.48986)
			(xy 137.238076 -434.475286) (xy 137.239725 -434.446185) (xy 137.24128 -434.431694) (xy 137.24128 -433.34813)
			(xy 137.239732 -433.333638) (xy 137.238082 -433.304538) (xy 137.237978 -433.289964) (xy 137.238076 -433.27539)
			(xy 137.239726 -433.246289) (xy 137.24128 -433.231798) (xy 137.24128 -432.618896) (xy 137.241712 -432.606789)
			(xy 137.249211 -432.583765) (xy 137.263469 -432.564194) (xy 137.283086 -432.549998) (xy 137.306134 -432.542574)
			(xy 137.318242 -432.542188) (xy 138.258042 -432.542188) (xy 138.270139 -432.542572) (xy 138.293149 -432.550047)
			(xy 138.312732 -432.564253) (xy 138.326979 -432.583806) (xy 138.334502 -432.606801) (xy 138.335004 -432.618896)
			(xy 138.335004 -435.16042) (xy 138.334601 -435.17253) (xy 138.327096 -435.195557) (xy 138.312831 -435.215129)
			(xy 138.293207 -435.229323) (xy 138.270153 -435.236744) (xy 138.258042 -435.237128) (xy 137.318242 -435.237128)
			(xy 137.306151 -435.236656) (xy 137.283147 -435.229207) (xy 137.263563 -435.215023) (xy 137.249313 -435.195488)
			(xy 137.241785 -435.172509) (xy 137.24128 -435.16042) (xy 137.24128 -434.548026) (xy 137.239732 -434.533534)
			(xy 137.238082 -434.504434) (xy 137.237978 -434.48986) (xy 136.335008 -434.48986) (xy 136.335008 -435.489858)
			(xy 139.237974 -435.489858) (xy 139.238072 -435.475284) (xy 139.239721 -435.446183) (xy 139.241276 -435.431692)
			(xy 139.241276 -434.348128) (xy 139.239728 -434.333636) (xy 139.238078 -434.304536) (xy 139.237974 -434.289962)
			(xy 139.238072 -434.275388) (xy 139.239721 -434.246287) (xy 139.241276 -434.231796) (xy 139.241276 -433.618894)
			(xy 139.241656 -433.606767) (xy 139.249154 -433.583702) (xy 139.263415 -433.564084) (xy 139.283041 -433.549834)
			(xy 139.306111 -433.542349) (xy 139.318238 -433.541932) (xy 140.258038 -433.541932) (xy 140.270154 -433.542379)
			(xy 140.293197 -433.549876) (xy 140.312798 -433.564125) (xy 140.327038 -433.583731) (xy 140.334526 -433.606778)
			(xy 140.335 -433.618894) (xy 140.335 -434.48986) (xy 142.237968 -434.48986) (xy 142.238081 -434.474774)
			(xy 142.23986 -434.444656) (xy 142.241524 -434.429662) (xy 142.241524 -433.350162) (xy 142.239859 -433.335168)
			(xy 142.238078 -433.30505) (xy 142.237968 -433.289964) (xy 142.238081 -433.274878) (xy 142.23986 -433.24476)
			(xy 142.241524 -433.229766) (xy 142.241524 -432.618896) (xy 142.24191 -432.60681) (xy 142.249382 -432.583822)
			(xy 142.263594 -432.564268) (xy 142.283154 -432.550066) (xy 142.306146 -432.542604) (xy 142.318232 -432.542188)
			(xy 143.258032 -432.542188) (xy 143.270108 -432.542637) (xy 143.293075 -432.550108) (xy 143.312612 -432.564308)
			(xy 143.326805 -432.58385) (xy 143.334268 -432.60682) (xy 143.33474 -432.618896) (xy 143.33474 -435.16042)
			(xy 143.334253 -435.172492) (xy 143.326789 -435.195455) (xy 143.312597 -435.214989) (xy 143.293065 -435.229184)
			(xy 143.270104 -435.236651) (xy 143.258032 -435.237128) (xy 142.318232 -435.237128) (xy 142.306153 -435.23666)
			(xy 142.283175 -435.229204) (xy 142.263626 -435.215011) (xy 142.24942 -435.195472) (xy 142.241948 -435.172499)
			(xy 142.241524 -435.16042) (xy 142.241524 -434.550058) (xy 142.239858 -434.535064) (xy 142.238078 -434.504946)
			(xy 142.237968 -434.48986) (xy 140.335 -434.48986) (xy 140.335 -435.489858) (xy 144.237964 -435.489858)
			(xy 144.238077 -435.474772) (xy 144.239856 -435.444654) (xy 144.24152 -435.42966) (xy 144.24152 -434.35016)
			(xy 144.239855 -434.335166) (xy 144.238074 -434.305048) (xy 144.237964 -434.289962) (xy 144.238077 -434.274876)
			(xy 144.239856 -434.244758) (xy 144.24152 -434.229764) (xy 144.24152 -433.618894) (xy 144.242002 -433.606806)
			(xy 144.249458 -433.583809) (xy 144.263641 -433.564231) (xy 144.28317 -433.54998) (xy 144.306142 -433.542444)
			(xy 144.318228 -433.541932) (xy 145.258028 -433.541932) (xy 145.270142 -433.542293) (xy 145.293175 -433.549804)
			(xy 145.312751 -433.564079) (xy 145.326943 -433.583714) (xy 145.334357 -433.606779) (xy 145.334736 -433.618894)
			(xy 145.334736 -434.48986) (xy 146.23796 -434.48986) (xy 146.238073 -434.474774) (xy 146.239852 -434.444656)
			(xy 146.241516 -434.429662) (xy 146.241516 -433.350162) (xy 146.239851 -433.335168) (xy 146.23807 -433.30505)
			(xy 146.23796 -433.289964) (xy 146.238073 -433.274878) (xy 146.239852 -433.24476) (xy 146.241516 -433.229766)
			(xy 146.241516 -432.618896) (xy 146.241909 -432.606811) (xy 146.249381 -432.583824) (xy 146.263591 -432.564271)
			(xy 146.283149 -432.550068) (xy 146.306138 -432.542605) (xy 146.318224 -432.542188) (xy 147.258024 -432.542188)
			(xy 147.270099 -432.542644) (xy 147.293067 -432.550113) (xy 147.312603 -432.564311) (xy 147.326797 -432.583851)
			(xy 147.334259 -432.606821) (xy 147.334732 -432.618896) (xy 147.334732 -435.16042) (xy 147.334253 -435.172493)
			(xy 147.326788 -435.195457) (xy 147.312594 -435.214991) (xy 147.29306 -435.229186) (xy 147.270097 -435.236652)
			(xy 147.258024 -435.237128) (xy 146.318224 -435.237128) (xy 146.306145 -435.236667) (xy 146.283166 -435.229209)
			(xy 146.263617 -435.215014) (xy 146.249412 -435.195473) (xy 146.24194 -435.172499) (xy 146.241516 -435.16042)
			(xy 146.241516 -434.550058) (xy 146.23985 -434.535064) (xy 146.23807 -434.504946) (xy 146.23796 -434.48986)
			(xy 145.334736 -434.48986) (xy 145.334736 -435.489858) (xy 148.237956 -435.489858) (xy 148.238069 -435.474772)
			(xy 148.239848 -435.444654) (xy 148.241512 -435.42966) (xy 148.241512 -434.35016) (xy 148.239847 -434.335166)
			(xy 148.238066 -434.305048) (xy 148.237956 -434.289962) (xy 148.238069 -434.274876) (xy 148.239848 -434.244758)
			(xy 148.241512 -434.229764) (xy 148.241512 -433.618894) (xy 148.242002 -433.606807) (xy 148.249457 -433.583811)
			(xy 148.263639 -433.564234) (xy 148.283165 -433.549982) (xy 148.306135 -433.542445) (xy 148.31822 -433.541932)
			(xy 149.25802 -433.541932) (xy 149.270133 -433.5423) (xy 149.293167 -433.549808) (xy 149.312742 -433.564081)
			(xy 149.326935 -433.583715) (xy 149.334349 -433.606779) (xy 149.334728 -433.618894) (xy 149.334728 -434.48986)
			(xy 150.237952 -434.48986) (xy 150.238065 -434.474774) (xy 150.239844 -434.444656) (xy 150.241508 -434.429662)
			(xy 150.241508 -433.350162) (xy 150.239843 -433.335168) (xy 150.238062 -433.30505) (xy 150.237952 -433.289964)
			(xy 150.238065 -433.274878) (xy 150.239844 -433.24476) (xy 150.241508 -433.229766) (xy 150.241508 -432.618896)
			(xy 150.241909 -432.606811) (xy 150.24938 -432.583826) (xy 150.263588 -432.564274) (xy 150.283144 -432.550071)
			(xy 150.306131 -432.542606) (xy 150.318216 -432.542188) (xy 151.258016 -432.542188) (xy 151.270091 -432.542651)
			(xy 151.293058 -432.550117) (xy 151.312594 -432.564314) (xy 151.326788 -432.583853) (xy 151.334251 -432.606821)
			(xy 151.334724 -432.618896) (xy 151.334724 -435.16042) (xy 151.334253 -435.172494) (xy 151.326787 -435.195459)
			(xy 151.312591 -435.214994) (xy 151.293055 -435.229189) (xy 151.27009 -435.236654) (xy 151.258016 -435.237128)
			(xy 150.318216 -435.237128) (xy 150.306144 -435.236622) (xy 150.283181 -435.229167) (xy 150.263645 -435.21498)
			(xy 150.24945 -435.195451) (xy 150.241983 -435.172492) (xy 150.241508 -435.16042) (xy 150.241508 -434.550058)
			(xy 150.239842 -434.535064) (xy 150.238062 -434.504946) (xy 150.237952 -434.48986) (xy 149.334728 -434.48986)
			(xy 149.334728 -435.489858) (xy 152.237948 -435.489858) (xy 152.238061 -435.474772) (xy 152.23984 -435.444654)
			(xy 152.241504 -435.42966) (xy 152.241504 -434.35016) (xy 152.239838 -434.335166) (xy 152.238058 -434.305048)
			(xy 152.237948 -434.289962) (xy 152.238061 -434.274876) (xy 152.23984 -434.244758) (xy 152.241504 -434.229764)
			(xy 152.241504 -433.618894) (xy 152.242002 -433.606808) (xy 152.249456 -433.583813) (xy 152.263636 -433.564236)
			(xy 152.28316 -433.549985) (xy 152.306128 -433.542447) (xy 152.318212 -433.541932) (xy 153.258012 -433.541932)
			(xy 153.270125 -433.542306) (xy 153.293158 -433.549813) (xy 153.312734 -433.564084) (xy 153.326927 -433.583717)
			(xy 153.334341 -433.60678) (xy 153.33472 -433.618894) (xy 153.33472 -434.48986) (xy 154.237944 -434.48986)
			(xy 154.238057 -434.474774) (xy 154.239836 -434.444656) (xy 154.2415 -434.429662) (xy 154.2415 -433.350162)
			(xy 154.239835 -433.335168) (xy 154.238054 -433.30505) (xy 154.237944 -433.289964) (xy 154.238057 -433.274878)
			(xy 154.239836 -433.24476) (xy 154.2415 -433.229766) (xy 154.2415 -432.618896) (xy 154.241909 -432.606812)
			(xy 154.249379 -432.583828) (xy 154.263586 -432.564277) (xy 154.283139 -432.550073) (xy 154.306124 -432.542607)
			(xy 154.318208 -432.542188) (xy 155.258008 -432.542188) (xy 155.270083 -432.542657) (xy 155.293049 -432.550122)
			(xy 155.312586 -432.564317) (xy 155.32678 -432.583854) (xy 155.334243 -432.606821) (xy 155.334716 -432.618896)
			(xy 155.334716 -433.130695) (xy 197.035917 -433.130695) (xy 197.035917 -432.953425) (xy 197.04387 -432.776334)
			(xy 197.059761 -432.599778) (xy 197.083556 -432.424113) (xy 197.115209 -432.249692) (xy 197.154655 -432.076867)
			(xy 197.201815 -431.905986) (xy 197.256594 -431.737392) (xy 197.318882 -431.571427) (xy 197.388554 -431.408422)
			(xy 197.465468 -431.248708) (xy 197.549471 -431.092605) (xy 197.640392 -430.940428) (xy 197.738049 -430.792484)
			(xy 197.842246 -430.64907) (xy 197.952772 -430.510475) (xy 198.069404 -430.376978) (xy 198.191909 -430.248849)
			(xy 198.320038 -430.126344) (xy 198.453535 -430.009712) (xy 198.59213 -429.899186) (xy 198.735544 -429.794989)
			(xy 198.883488 -429.697332) (xy 199.035665 -429.606411) (xy 199.191768 -429.522408) (xy 199.351482 -429.445494)
			(xy 199.514487 -429.375822) (xy 199.680452 -429.313534) (xy 199.849046 -429.258755) (xy 200.019927 -429.211595)
			(xy 200.192752 -429.172149) (xy 200.367173 -429.140496) (xy 200.542838 -429.116701) (xy 200.719394 -429.10081)
			(xy 200.896485 -429.092857) (xy 201.073755 -429.092857) (xy 201.250846 -429.10081) (xy 201.427402 -429.116701)
			(xy 201.603067 -429.140496) (xy 201.777488 -429.172149) (xy 201.950313 -429.211595) (xy 202.121194 -429.258755)
			(xy 202.289788 -429.313534) (xy 202.455753 -429.375822) (xy 202.618758 -429.445494) (xy 202.778472 -429.522408)
			(xy 202.934575 -429.606411) (xy 203.086752 -429.697332) (xy 203.234696 -429.794989) (xy 203.37811 -429.899186)
			(xy 203.516705 -430.009712) (xy 203.650202 -430.126344) (xy 203.778331 -430.248849) (xy 203.900836 -430.376978)
			(xy 204.017468 -430.510475) (xy 204.127994 -430.64907) (xy 204.232191 -430.792484) (xy 204.329848 -430.940428)
			(xy 204.420769 -431.092605) (xy 204.504772 -431.248708) (xy 204.581686 -431.408422) (xy 204.651358 -431.571427)
			(xy 204.713646 -431.737392) (xy 204.768425 -431.905986) (xy 204.815585 -432.076867) (xy 204.855031 -432.249692)
			(xy 204.886684 -432.424113) (xy 204.910479 -432.599778) (xy 204.92637 -432.776334) (xy 204.934323 -432.953425)
			(xy 204.93482 -433.04206) (xy 204.934323 -433.130695) (xy 204.92637 -433.307786) (xy 204.910479 -433.484342)
			(xy 204.886684 -433.660007) (xy 204.855031 -433.834428) (xy 204.815585 -434.007253) (xy 204.768425 -434.178134)
			(xy 204.713646 -434.346728) (xy 204.651358 -434.512693) (xy 204.581686 -434.675698) (xy 204.504772 -434.835412)
			(xy 204.420769 -434.991515) (xy 204.329848 -435.143692) (xy 204.232191 -435.291636) (xy 204.127994 -435.43505)
			(xy 204.057751 -435.523132) (xy 205.85684 -435.523132) (xy 205.85684 -415.567368) (xy 205.857337 -415.542419)
			(xy 205.865152 -415.493137) (xy 205.88057 -415.44568) (xy 205.903211 -415.401214) (xy 205.93252 -415.360831)
			(xy 205.949804 -415.342832) (xy 206.989172 -414.303464) (xy 207.007169 -414.286175) (xy 207.047542 -414.256843)
			(xy 207.092007 -414.234188) (xy 207.139468 -414.218769) (xy 207.188756 -414.210963) (xy 207.213708 -414.2105)
			(xy 232.807256 -414.2105) (xy 239.488472 -407.529284) (xy 239.506473 -407.512) (xy 239.546848 -407.482676)
			(xy 239.591312 -407.460027) (xy 239.638771 -407.444612) (xy 239.688058 -407.436808) (xy 239.713008 -407.43632)
			(xy 280.100532 -407.43632) (xy 280.125481 -407.436823) (xy 280.174763 -407.444637) (xy 280.222219 -407.460054)
			(xy 280.266685 -407.482694) (xy 280.307069 -407.512001) (xy 280.325068 -407.529284) (xy 280.739596 -407.943812)
			(xy 280.756896 -407.961798) (xy 280.786219 -408.002177) (xy 280.808865 -408.046645) (xy 280.824276 -408.094108)
			(xy 280.832075 -408.143397) (xy 280.83256 -408.168348) (xy 280.83256 -410.057453) (xy 304.945246 -410.057453)
			(xy 304.945246 -410.002947) (xy 304.953003 -409.948996) (xy 304.968358 -409.896698) (xy 304.991001 -409.847117)
			(xy 305.020468 -409.801263) (xy 305.056162 -409.76007) (xy 305.097354 -409.724375) (xy 305.143207 -409.694906)
			(xy 305.192786 -409.672263) (xy 305.245084 -409.656905) (xy 305.299035 -409.649147) (xy 305.326288 -409.64866)
			(xy 306.189888 -409.64866) (xy 306.217139 -409.649186) (xy 306.271087 -409.656941) (xy 306.323382 -409.672295)
			(xy 306.372959 -409.694935) (xy 306.41881 -409.7244) (xy 306.460001 -409.760091) (xy 306.495693 -409.80128)
			(xy 306.525159 -409.84713) (xy 306.547801 -409.896707) (xy 306.563156 -409.949001) (xy 306.570913 -410.002949)
			(xy 306.570913 -410.057451) (xy 306.570912 -410.057456) (xy 308.008423 -410.057456) (xy 308.008423 -410.002944)
			(xy 308.016181 -409.948986) (xy 308.03154 -409.896681) (xy 308.054187 -409.847095) (xy 308.08366 -409.801236)
			(xy 308.119359 -409.76004) (xy 308.160559 -409.724343) (xy 308.206419 -409.694873) (xy 308.256007 -409.67223)
			(xy 308.308313 -409.656875) (xy 308.362272 -409.649121) (xy 308.389528 -409.64866) (xy 309.253128 -409.64866)
			(xy 309.280376 -409.649212) (xy 309.334316 -409.656971) (xy 309.386603 -409.672327) (xy 309.436172 -409.694968)
			(xy 309.482015 -409.724433) (xy 309.523199 -409.760121) (xy 309.558884 -409.801307) (xy 309.588345 -409.847152)
			(xy 309.610982 -409.896724) (xy 309.626335 -409.949012) (xy 309.63409 -410.002952) (xy 309.63409 -410.057448)
			(xy 309.634089 -410.057452) (xy 311.071746 -410.057452) (xy 311.071746 -410.002948) (xy 311.079502 -409.948998)
			(xy 311.094857 -409.896702) (xy 311.117498 -409.847123) (xy 311.146963 -409.80127) (xy 311.182654 -409.760077)
			(xy 311.223844 -409.724383) (xy 311.269695 -409.694913) (xy 311.319272 -409.672268) (xy 311.371567 -409.656909)
			(xy 311.425516 -409.649148) (xy 311.452768 -409.64866) (xy 312.316368 -409.64866) (xy 312.34362 -409.649185)
			(xy 312.39757 -409.656938) (xy 312.449867 -409.67229) (xy 312.499447 -409.694928) (xy 312.545301 -409.724393)
			(xy 312.586494 -409.760084) (xy 312.622188 -409.801274) (xy 312.651656 -409.847125) (xy 312.674299 -409.896703)
			(xy 312.689655 -409.948999) (xy 312.697413 -410.002948) (xy 312.697413 -410.057452) (xy 312.697412 -410.057456)
			(xy 314.134923 -410.057456) (xy 314.134923 -410.002944) (xy 314.142681 -409.948988) (xy 314.158039 -409.896685)
			(xy 314.180684 -409.8471) (xy 314.210155 -409.801243) (xy 314.245852 -409.760047) (xy 314.287049 -409.72435)
			(xy 314.332907 -409.69488) (xy 314.382493 -409.672236) (xy 314.434796 -409.656879) (xy 314.488752 -409.649122)
			(xy 314.516008 -409.64866) (xy 315.379608 -409.64866) (xy 315.406857 -409.649211) (xy 315.460799 -409.656968)
			(xy 315.513088 -409.672322) (xy 315.56266 -409.694962) (xy 315.608506 -409.724426) (xy 315.649691 -409.760114)
			(xy 315.685379 -409.801301) (xy 315.714842 -409.847147) (xy 315.737481 -409.896719) (xy 315.752834 -409.949009)
			(xy 315.76059 -410.002951) (xy 315.76059 -410.057449) (xy 315.760589 -410.057457) (xy 317.198123 -410.057457)
			(xy 317.198123 -410.002943) (xy 317.205882 -409.948983) (xy 317.221242 -409.896677) (xy 317.24389 -409.847089)
			(xy 317.273365 -409.80123) (xy 317.309066 -409.760033) (xy 317.350268 -409.724336) (xy 317.396131 -409.694867)
			(xy 317.445722 -409.672225) (xy 317.49803 -409.656872) (xy 317.551991 -409.64912) (xy 317.579248 -409.64866)
			(xy 318.442848 -409.64866) (xy 318.470095 -409.649213) (xy 318.524033 -409.656975) (xy 318.576317 -409.672333)
			(xy 318.625884 -409.694975) (xy 318.671725 -409.72444) (xy 318.712906 -409.760128) (xy 318.748589 -409.801314)
			(xy 318.778048 -409.847158) (xy 318.800684 -409.896728) (xy 318.816035 -409.949014) (xy 318.82379 -410.002953)
			(xy 318.82379 -410.057447) (xy 318.823789 -410.057453) (xy 320.261446 -410.057453) (xy 320.261446 -410.002947)
			(xy 320.269203 -409.948996) (xy 320.284558 -409.896698) (xy 320.307201 -409.847117) (xy 320.336668 -409.801263)
			(xy 320.372362 -409.76007) (xy 320.413554 -409.724375) (xy 320.459407 -409.694906) (xy 320.508986 -409.672263)
			(xy 320.561284 -409.656905) (xy 320.615235 -409.649147) (xy 320.642488 -409.64866) (xy 321.506088 -409.64866)
			(xy 321.533339 -409.649186) (xy 321.587287 -409.656941) (xy 321.639582 -409.672295) (xy 321.689159 -409.694935)
			(xy 321.73501 -409.7244) (xy 321.776201 -409.760091) (xy 321.811893 -409.80128) (xy 321.841359 -409.84713)
			(xy 321.864001 -409.896707) (xy 321.879356 -409.949001) (xy 321.887113 -410.002949) (xy 321.887113 -410.057451)
			(xy 321.887112 -410.057456) (xy 323.324623 -410.057456) (xy 323.324623 -410.002944) (xy 323.332381 -409.948986)
			(xy 323.34774 -409.896681) (xy 323.370387 -409.847095) (xy 323.39986 -409.801236) (xy 323.435559 -409.76004)
			(xy 323.476759 -409.724343) (xy 323.522619 -409.694873) (xy 323.572207 -409.67223) (xy 323.624513 -409.656875)
			(xy 323.678472 -409.649121) (xy 323.705728 -409.64866) (xy 324.569328 -409.64866) (xy 324.596576 -409.649212)
			(xy 324.650516 -409.656971) (xy 324.702803 -409.672327) (xy 324.752372 -409.694968) (xy 324.798215 -409.724433)
			(xy 324.839399 -409.760121) (xy 324.875084 -409.801307) (xy 324.904545 -409.847152) (xy 324.927182 -409.896724)
			(xy 324.942535 -409.949012) (xy 324.95029 -410.002952) (xy 324.95029 -410.057448) (xy 324.950289 -410.057452)
			(xy 326.387946 -410.057452) (xy 326.387946 -410.002948) (xy 326.395702 -409.948998) (xy 326.411057 -409.896702)
			(xy 326.433698 -409.847123) (xy 326.463163 -409.80127) (xy 326.498854 -409.760077) (xy 326.540044 -409.724383)
			(xy 326.585895 -409.694913) (xy 326.635472 -409.672268) (xy 326.687767 -409.656909) (xy 326.741716 -409.649148)
			(xy 326.768968 -409.64866) (xy 327.632568 -409.64866) (xy 327.65982 -409.649185) (xy 327.71377 -409.656938)
			(xy 327.766067 -409.67229) (xy 327.815647 -409.694928) (xy 327.861501 -409.724393) (xy 327.902694 -409.760084)
			(xy 327.938388 -409.801274) (xy 327.967856 -409.847125) (xy 327.990499 -409.896703) (xy 328.005855 -409.948999)
			(xy 328.013613 -410.002948) (xy 328.013613 -410.057452) (xy 328.013612 -410.057456) (xy 329.451123 -410.057456)
			(xy 329.451123 -410.002944) (xy 329.458881 -409.948988) (xy 329.474239 -409.896685) (xy 329.496884 -409.8471)
			(xy 329.526355 -409.801243) (xy 329.562052 -409.760047) (xy 329.603249 -409.72435) (xy 329.649107 -409.69488)
			(xy 329.698693 -409.672236) (xy 329.750996 -409.656879) (xy 329.804952 -409.649122) (xy 329.832208 -409.64866)
			(xy 330.695808 -409.64866) (xy 330.723057 -409.649211) (xy 330.776999 -409.656968) (xy 330.829288 -409.672322)
			(xy 330.87886 -409.694962) (xy 330.924706 -409.724426) (xy 330.965891 -409.760114) (xy 331.001579 -409.801301)
			(xy 331.031042 -409.847147) (xy 331.053681 -409.896719) (xy 331.069034 -409.949009) (xy 331.07679 -410.002951)
			(xy 331.07679 -410.057449) (xy 331.076789 -410.057457) (xy 332.514323 -410.057457) (xy 332.514323 -410.002943)
			(xy 332.522082 -409.948983) (xy 332.537442 -409.896677) (xy 332.56009 -409.847089) (xy 332.589565 -409.80123)
			(xy 332.625266 -409.760033) (xy 332.666468 -409.724336) (xy 332.712331 -409.694867) (xy 332.761922 -409.672225)
			(xy 332.81423 -409.656872) (xy 332.868191 -409.64912) (xy 332.895448 -409.64866) (xy 333.759048 -409.64866)
			(xy 333.786295 -409.649213) (xy 333.840233 -409.656975) (xy 333.892517 -409.672333) (xy 333.942084 -409.694975)
			(xy 333.987925 -409.72444) (xy 334.029106 -409.760128) (xy 334.064789 -409.801314) (xy 334.094248 -409.847158)
			(xy 334.116884 -409.896728) (xy 334.132235 -409.949014) (xy 334.13999 -410.002953) (xy 334.13999 -410.057447)
			(xy 334.139989 -410.057453) (xy 335.577646 -410.057453) (xy 335.577646 -410.002947) (xy 335.585403 -409.948996)
			(xy 335.600758 -409.896698) (xy 335.623401 -409.847117) (xy 335.652868 -409.801263) (xy 335.688562 -409.76007)
			(xy 335.729754 -409.724375) (xy 335.775607 -409.694906) (xy 335.825186 -409.672263) (xy 335.877484 -409.656905)
			(xy 335.931435 -409.649147) (xy 335.958688 -409.64866) (xy 336.822288 -409.64866) (xy 336.849539 -409.649186)
			(xy 336.903487 -409.656941) (xy 336.955782 -409.672295) (xy 337.005359 -409.694935) (xy 337.05121 -409.7244)
			(xy 337.092401 -409.760091) (xy 337.128093 -409.80128) (xy 337.157559 -409.84713) (xy 337.180201 -409.896707)
			(xy 337.195556 -409.949001) (xy 337.203313 -410.002949) (xy 337.203313 -410.057451) (xy 337.203312 -410.057456)
			(xy 338.640823 -410.057456) (xy 338.640823 -410.002944) (xy 338.648581 -409.948986) (xy 338.66394 -409.896681)
			(xy 338.686587 -409.847095) (xy 338.71606 -409.801236) (xy 338.751759 -409.76004) (xy 338.792959 -409.724343)
			(xy 338.838819 -409.694873) (xy 338.888407 -409.67223) (xy 338.940713 -409.656875) (xy 338.994672 -409.649121)
			(xy 339.021928 -409.64866) (xy 339.885528 -409.64866) (xy 339.912776 -409.649212) (xy 339.966716 -409.656971)
			(xy 340.019003 -409.672327) (xy 340.068572 -409.694968) (xy 340.114415 -409.724433) (xy 340.155599 -409.760121)
			(xy 340.191284 -409.801307) (xy 340.220745 -409.847152) (xy 340.243382 -409.896724) (xy 340.258735 -409.949012)
			(xy 340.26649 -410.002952) (xy 340.26649 -410.057448) (xy 340.266489 -410.057452) (xy 341.704146 -410.057452)
			(xy 341.704146 -410.002948) (xy 341.711902 -409.948998) (xy 341.727257 -409.896702) (xy 341.749898 -409.847123)
			(xy 341.779363 -409.80127) (xy 341.815054 -409.760077) (xy 341.856244 -409.724383) (xy 341.902095 -409.694913)
			(xy 341.951672 -409.672268) (xy 342.003967 -409.656909) (xy 342.057916 -409.649148) (xy 342.085168 -409.64866)
			(xy 342.948768 -409.64866) (xy 342.97602 -409.649185) (xy 343.02997 -409.656938) (xy 343.082267 -409.67229)
			(xy 343.131847 -409.694928) (xy 343.177701 -409.724393) (xy 343.218894 -409.760084) (xy 343.254588 -409.801274)
			(xy 343.284056 -409.847125) (xy 343.306699 -409.896703) (xy 343.322055 -409.948999) (xy 343.329813 -410.002948)
			(xy 343.329813 -410.057452) (xy 343.329812 -410.057456) (xy 344.767323 -410.057456) (xy 344.767323 -410.002944)
			(xy 344.775081 -409.948988) (xy 344.790439 -409.896685) (xy 344.813084 -409.8471) (xy 344.842555 -409.801243)
			(xy 344.878252 -409.760047) (xy 344.919449 -409.72435) (xy 344.965307 -409.69488) (xy 345.014893 -409.672236)
			(xy 345.067196 -409.656879) (xy 345.121152 -409.649122) (xy 345.148408 -409.64866) (xy 346.012008 -409.64866)
			(xy 346.039257 -409.649211) (xy 346.093199 -409.656968) (xy 346.145488 -409.672322) (xy 346.19506 -409.694962)
			(xy 346.240906 -409.724426) (xy 346.282091 -409.760114) (xy 346.317779 -409.801301) (xy 346.347242 -409.847147)
			(xy 346.369881 -409.896719) (xy 346.385234 -409.949009) (xy 346.39299 -410.002951) (xy 346.39299 -410.057449)
			(xy 346.392989 -410.057457) (xy 347.830523 -410.057457) (xy 347.830523 -410.002943) (xy 347.838282 -409.948983)
			(xy 347.853642 -409.896677) (xy 347.87629 -409.847089) (xy 347.905765 -409.80123) (xy 347.941466 -409.760033)
			(xy 347.982668 -409.724336) (xy 348.028531 -409.694867) (xy 348.078122 -409.672225) (xy 348.13043 -409.656872)
			(xy 348.184391 -409.64912) (xy 348.211648 -409.64866) (xy 349.075248 -409.64866) (xy 349.102495 -409.649213)
			(xy 349.156433 -409.656975) (xy 349.208717 -409.672333) (xy 349.258284 -409.694975) (xy 349.304125 -409.72444)
			(xy 349.345306 -409.760128) (xy 349.380989 -409.801314) (xy 349.410448 -409.847158) (xy 349.433084 -409.896728)
			(xy 349.448435 -409.949014) (xy 349.45619 -410.002953) (xy 349.45619 -410.057447) (xy 349.456189 -410.057453)
			(xy 350.893846 -410.057453) (xy 350.893846 -410.002947) (xy 350.901603 -409.948996) (xy 350.916958 -409.896698)
			(xy 350.939601 -409.847117) (xy 350.969068 -409.801263) (xy 351.004762 -409.76007) (xy 351.045954 -409.724375)
			(xy 351.091807 -409.694906) (xy 351.141386 -409.672263) (xy 351.193684 -409.656905) (xy 351.247635 -409.649147)
			(xy 351.274888 -409.64866) (xy 352.138488 -409.64866) (xy 352.165739 -409.649186) (xy 352.219687 -409.656941)
			(xy 352.271982 -409.672295) (xy 352.321559 -409.694935) (xy 352.36741 -409.7244) (xy 352.408601 -409.760091)
			(xy 352.444293 -409.80128) (xy 352.473759 -409.84713) (xy 352.496401 -409.896707) (xy 352.511756 -409.949001)
			(xy 352.519513 -410.002949) (xy 352.519513 -410.057451) (xy 352.519512 -410.057457) (xy 372.388023 -410.057457)
			(xy 372.388023 -410.002943) (xy 372.395781 -409.948985) (xy 372.41114 -409.896681) (xy 372.433787 -409.847094)
			(xy 372.46326 -409.801236) (xy 372.49896 -409.760039) (xy 372.54016 -409.724342) (xy 372.586021 -409.694872)
			(xy 372.635609 -409.67223) (xy 372.687915 -409.656875) (xy 372.741873 -409.649121) (xy 372.76913 -409.64866)
			(xy 373.63273 -409.64866) (xy 373.659978 -409.649212) (xy 373.713917 -409.656972) (xy 373.766204 -409.672328)
			(xy 373.815773 -409.694969) (xy 373.861616 -409.724434) (xy 373.902799 -409.760122) (xy 373.938484 -409.801308)
			(xy 373.967945 -409.847153) (xy 373.990583 -409.896724) (xy 374.005935 -409.949012) (xy 374.01369 -410.002952)
			(xy 374.01369 -410.057448) (xy 374.013689 -410.057452) (xy 375.451346 -410.057452) (xy 375.451346 -410.002948)
			(xy 375.459102 -409.948998) (xy 375.474457 -409.896701) (xy 375.497098 -409.847122) (xy 375.526564 -409.801269)
			(xy 375.562255 -409.760076) (xy 375.603445 -409.724382) (xy 375.649296 -409.694912) (xy 375.698873 -409.672268)
			(xy 375.751169 -409.656909) (xy 375.805118 -409.649148) (xy 375.83237 -409.64866) (xy 376.69597 -409.64866)
			(xy 376.723222 -409.649185) (xy 376.777172 -409.656938) (xy 376.829469 -409.67229) (xy 376.879048 -409.694929)
			(xy 376.924901 -409.724394) (xy 376.966094 -409.760084) (xy 377.001788 -409.801274) (xy 377.031257 -409.847125)
			(xy 377.053899 -409.896703) (xy 377.069256 -409.948999) (xy 377.077013 -410.002948) (xy 377.077013 -410.057452)
			(xy 377.077012 -410.057456) (xy 378.514523 -410.057456) (xy 378.514523 -410.002944) (xy 378.522281 -409.948988)
			(xy 378.537639 -409.896685) (xy 378.560284 -409.8471) (xy 378.589755 -409.801242) (xy 378.625453 -409.760046)
			(xy 378.66665 -409.724349) (xy 378.712509 -409.694879) (xy 378.762094 -409.672235) (xy 378.814398 -409.656879)
			(xy 378.868354 -409.649122) (xy 378.89561 -409.64866) (xy 379.75921 -409.64866) (xy 379.786458 -409.649211)
			(xy 379.840401 -409.656968) (xy 379.89269 -409.672323) (xy 379.942261 -409.694962) (xy 379.988107 -409.724426)
			(xy 380.029292 -409.760115) (xy 380.06498 -409.801301) (xy 380.094442 -409.847147) (xy 380.117081 -409.89672)
			(xy 380.132434 -409.949009) (xy 380.14019 -410.002952) (xy 380.14019 -410.057448) (xy 380.14019 -410.057451)
			(xy 381.577846 -410.057451) (xy 381.577846 -410.002949) (xy 381.585602 -409.949001) (xy 381.600955 -409.896706)
			(xy 381.623595 -409.847128) (xy 381.653059 -409.801276) (xy 381.688748 -409.760083) (xy 381.729936 -409.724389)
			(xy 381.775784 -409.694919) (xy 381.825359 -409.672273) (xy 381.877652 -409.656912) (xy 381.931599 -409.649149)
			(xy 381.95885 -409.64866) (xy 382.82245 -409.64866) (xy 382.849703 -409.649184) (xy 382.903655 -409.656934)
			(xy 382.955954 -409.672285) (xy 383.005536 -409.694923) (xy 383.051392 -409.724387) (xy 383.092587 -409.760077)
			(xy 383.128283 -409.801268) (xy 383.157753 -409.84712) (xy 383.180398 -409.896699) (xy 383.195755 -409.948996)
			(xy 383.203513 -410.002947) (xy 383.203513 -410.057453) (xy 384.641046 -410.057453) (xy 384.641046 -410.002947)
			(xy 384.648803 -409.948996) (xy 384.664159 -409.896697) (xy 384.686801 -409.847117) (xy 384.716269 -409.801263)
			(xy 384.751962 -409.760069) (xy 384.793155 -409.724375) (xy 384.839008 -409.694906) (xy 384.888588 -409.672262)
			(xy 384.940886 -409.656905) (xy 384.994837 -409.649147) (xy 385.02209 -409.64866) (xy 385.88569 -409.64866)
			(xy 385.912941 -409.649187) (xy 385.966889 -409.656942) (xy 386.019183 -409.672296) (xy 386.06876 -409.694936)
			(xy 386.114611 -409.724401) (xy 386.155801 -409.760092) (xy 386.191493 -409.801281) (xy 386.22096 -409.847131)
			(xy 386.243601 -409.896707) (xy 386.258956 -409.949002) (xy 386.266713 -410.002949) (xy 386.266713 -410.057451)
			(xy 386.266712 -410.057457) (xy 387.704223 -410.057457) (xy 387.704223 -410.002943) (xy 387.711981 -409.948985)
			(xy 387.72734 -409.896681) (xy 387.749987 -409.847094) (xy 387.77946 -409.801236) (xy 387.81516 -409.760039)
			(xy 387.85636 -409.724342) (xy 387.902221 -409.694872) (xy 387.951809 -409.67223) (xy 388.004115 -409.656875)
			(xy 388.058073 -409.649121) (xy 388.08533 -409.64866) (xy 388.94893 -409.64866) (xy 388.976178 -409.649212)
			(xy 389.030117 -409.656972) (xy 389.082404 -409.672328) (xy 389.131973 -409.694969) (xy 389.177816 -409.724434)
			(xy 389.218999 -409.760122) (xy 389.254684 -409.801308) (xy 389.284145 -409.847153) (xy 389.306783 -409.896724)
			(xy 389.322135 -409.949012) (xy 389.32989 -410.002952) (xy 389.32989 -410.057448) (xy 389.329889 -410.057452)
			(xy 390.767546 -410.057452) (xy 390.767546 -410.002948) (xy 390.775302 -409.948998) (xy 390.790657 -409.896701)
			(xy 390.813298 -409.847122) (xy 390.842764 -409.801269) (xy 390.878455 -409.760076) (xy 390.919645 -409.724382)
			(xy 390.965496 -409.694912) (xy 391.015073 -409.672268) (xy 391.067369 -409.656909) (xy 391.121318 -409.649148)
			(xy 391.14857 -409.64866) (xy 392.01217 -409.64866) (xy 392.039422 -409.649185) (xy 392.093372 -409.656938)
			(xy 392.145669 -409.67229) (xy 392.195248 -409.694929) (xy 392.241101 -409.724394) (xy 392.282294 -409.760084)
			(xy 392.317988 -409.801274) (xy 392.347457 -409.847125) (xy 392.370099 -409.896703) (xy 392.385456 -409.948999)
			(xy 392.393213 -410.002948) (xy 392.393213 -410.057452) (xy 392.393212 -410.057456) (xy 393.830723 -410.057456)
			(xy 393.830723 -410.002944) (xy 393.838481 -409.948988) (xy 393.853839 -409.896685) (xy 393.876484 -409.8471)
			(xy 393.905955 -409.801242) (xy 393.941653 -409.760046) (xy 393.98285 -409.724349) (xy 394.028709 -409.694879)
			(xy 394.078294 -409.672235) (xy 394.130598 -409.656879) (xy 394.184554 -409.649122) (xy 394.21181 -409.64866)
			(xy 395.07541 -409.64866) (xy 395.102658 -409.649211) (xy 395.156601 -409.656968) (xy 395.20889 -409.672323)
			(xy 395.258461 -409.694962) (xy 395.304307 -409.724426) (xy 395.345492 -409.760115) (xy 395.38118 -409.801301)
			(xy 395.410642 -409.847147) (xy 395.433281 -409.89672) (xy 395.448634 -409.949009) (xy 395.45639 -410.002952)
			(xy 395.45639 -410.057448) (xy 395.45639 -410.057451) (xy 396.894046 -410.057451) (xy 396.894046 -410.002949)
			(xy 396.901802 -409.949001) (xy 396.917155 -409.896706) (xy 396.939795 -409.847128) (xy 396.969259 -409.801276)
			(xy 397.004948 -409.760083) (xy 397.046136 -409.724389) (xy 397.091984 -409.694919) (xy 397.141559 -409.672273)
			(xy 397.193852 -409.656912) (xy 397.247799 -409.649149) (xy 397.27505 -409.64866) (xy 398.13865 -409.64866)
			(xy 398.165903 -409.649184) (xy 398.219855 -409.656934) (xy 398.272154 -409.672285) (xy 398.321736 -409.694923)
			(xy 398.367592 -409.724387) (xy 398.408787 -409.760077) (xy 398.444483 -409.801268) (xy 398.473953 -409.84712)
			(xy 398.496598 -409.896699) (xy 398.511955 -409.948996) (xy 398.519713 -410.002947) (xy 398.519713 -410.057453)
			(xy 399.957246 -410.057453) (xy 399.957246 -410.002947) (xy 399.965003 -409.948996) (xy 399.980359 -409.896697)
			(xy 400.003001 -409.847117) (xy 400.032469 -409.801263) (xy 400.068162 -409.760069) (xy 400.109355 -409.724375)
			(xy 400.155208 -409.694906) (xy 400.204788 -409.672262) (xy 400.257086 -409.656905) (xy 400.311037 -409.649147)
			(xy 400.33829 -409.64866) (xy 401.20189 -409.64866) (xy 401.229141 -409.649187) (xy 401.283089 -409.656942)
			(xy 401.335383 -409.672296) (xy 401.38496 -409.694936) (xy 401.430811 -409.724401) (xy 401.472001 -409.760092)
			(xy 401.507693 -409.801281) (xy 401.53716 -409.847131) (xy 401.559801 -409.896707) (xy 401.575156 -409.949002)
			(xy 401.582913 -410.002949) (xy 401.582913 -410.057451) (xy 401.582912 -410.057457) (xy 403.020423 -410.057457)
			(xy 403.020423 -410.002943) (xy 403.028181 -409.948985) (xy 403.04354 -409.896681) (xy 403.066187 -409.847094)
			(xy 403.09566 -409.801236) (xy 403.13136 -409.760039) (xy 403.17256 -409.724342) (xy 403.218421 -409.694872)
			(xy 403.268009 -409.67223) (xy 403.320315 -409.656875) (xy 403.374273 -409.649121) (xy 403.40153 -409.64866)
			(xy 404.26513 -409.64866) (xy 404.292378 -409.649212) (xy 404.346317 -409.656972) (xy 404.398604 -409.672328)
			(xy 404.448173 -409.694969) (xy 404.494016 -409.724434) (xy 404.535199 -409.760122) (xy 404.570884 -409.801308)
			(xy 404.600345 -409.847153) (xy 404.622983 -409.896724) (xy 404.638335 -409.949012) (xy 404.64609 -410.002952)
			(xy 404.64609 -410.057448) (xy 404.646089 -410.057452) (xy 406.083746 -410.057452) (xy 406.083746 -410.002948)
			(xy 406.091502 -409.948998) (xy 406.106857 -409.896701) (xy 406.129498 -409.847122) (xy 406.158964 -409.801269)
			(xy 406.194655 -409.760076) (xy 406.235845 -409.724382) (xy 406.281696 -409.694912) (xy 406.331273 -409.672268)
			(xy 406.383569 -409.656909) (xy 406.437518 -409.649148) (xy 406.46477 -409.64866) (xy 407.32837 -409.64866)
			(xy 407.355622 -409.649185) (xy 407.409572 -409.656938) (xy 407.461869 -409.67229) (xy 407.511448 -409.694929)
			(xy 407.557301 -409.724394) (xy 407.598494 -409.760084) (xy 407.634188 -409.801274) (xy 407.663657 -409.847125)
			(xy 407.686299 -409.896703) (xy 407.701656 -409.948999) (xy 407.709413 -410.002948) (xy 407.709413 -410.057452)
			(xy 407.709412 -410.057456) (xy 409.146923 -410.057456) (xy 409.146923 -410.002944) (xy 409.154681 -409.948988)
			(xy 409.170039 -409.896685) (xy 409.192684 -409.8471) (xy 409.222155 -409.801242) (xy 409.257853 -409.760046)
			(xy 409.29905 -409.724349) (xy 409.344909 -409.694879) (xy 409.394494 -409.672235) (xy 409.446798 -409.656879)
			(xy 409.500754 -409.649122) (xy 409.52801 -409.64866) (xy 410.39161 -409.64866) (xy 410.418858 -409.649211)
			(xy 410.472801 -409.656968) (xy 410.52509 -409.672323) (xy 410.574661 -409.694962) (xy 410.620507 -409.724426)
			(xy 410.661692 -409.760115) (xy 410.69738 -409.801301) (xy 410.726842 -409.847147) (xy 410.749481 -409.89672)
			(xy 410.764834 -409.949009) (xy 410.77259 -410.002952) (xy 410.77259 -410.057448) (xy 410.77259 -410.057451)
			(xy 412.210246 -410.057451) (xy 412.210246 -410.002949) (xy 412.218002 -409.949001) (xy 412.233355 -409.896706)
			(xy 412.255995 -409.847128) (xy 412.285459 -409.801276) (xy 412.321148 -409.760083) (xy 412.362336 -409.724389)
			(xy 412.408184 -409.694919) (xy 412.457759 -409.672273) (xy 412.510052 -409.656912) (xy 412.563999 -409.649149)
			(xy 412.59125 -409.64866) (xy 413.45485 -409.64866) (xy 413.482103 -409.649184) (xy 413.536055 -409.656934)
			(xy 413.588354 -409.672285) (xy 413.637936 -409.694923) (xy 413.683792 -409.724387) (xy 413.724987 -409.760077)
			(xy 413.760683 -409.801268) (xy 413.790153 -409.84712) (xy 413.812798 -409.896699) (xy 413.828155 -409.948996)
			(xy 413.835913 -410.002947) (xy 413.835913 -410.057453) (xy 415.273446 -410.057453) (xy 415.273446 -410.002947)
			(xy 415.281203 -409.948996) (xy 415.296559 -409.896697) (xy 415.319201 -409.847117) (xy 415.348669 -409.801263)
			(xy 415.384362 -409.760069) (xy 415.425555 -409.724375) (xy 415.471408 -409.694906) (xy 415.520988 -409.672262)
			(xy 415.573286 -409.656905) (xy 415.627237 -409.649147) (xy 415.65449 -409.64866) (xy 416.51809 -409.64866)
			(xy 416.545341 -409.649187) (xy 416.599289 -409.656942) (xy 416.651583 -409.672296) (xy 416.70116 -409.694936)
			(xy 416.747011 -409.724401) (xy 416.788201 -409.760092) (xy 416.823893 -409.801281) (xy 416.85336 -409.847131)
			(xy 416.876001 -409.896707) (xy 416.891356 -409.949002) (xy 416.899113 -410.002949) (xy 416.899113 -410.057451)
			(xy 416.899112 -410.057457) (xy 418.336623 -410.057457) (xy 418.336623 -410.002943) (xy 418.344381 -409.948985)
			(xy 418.35974 -409.896681) (xy 418.382387 -409.847094) (xy 418.41186 -409.801236) (xy 418.44756 -409.760039)
			(xy 418.48876 -409.724342) (xy 418.534621 -409.694872) (xy 418.584209 -409.67223) (xy 418.636515 -409.656875)
			(xy 418.690473 -409.649121) (xy 418.71773 -409.64866) (xy 419.58133 -409.64866) (xy 419.608578 -409.649212)
			(xy 419.662517 -409.656972) (xy 419.714804 -409.672328) (xy 419.764373 -409.694969) (xy 419.810216 -409.724434)
			(xy 419.851399 -409.760122) (xy 419.887084 -409.801308) (xy 419.916545 -409.847153) (xy 419.939183 -409.896724)
			(xy 419.954535 -409.949012) (xy 419.96229 -410.002952) (xy 419.96229 -410.057448) (xy 419.954535 -410.111388)
			(xy 419.939183 -410.163676) (xy 419.916545 -410.213247) (xy 419.887084 -410.259092) (xy 419.851399 -410.300278)
			(xy 419.810216 -410.335966) (xy 419.764373 -410.365431) (xy 419.714804 -410.388072) (xy 419.662517 -410.403428)
			(xy 419.608578 -410.411188) (xy 419.58133 -410.411676) (xy 418.71773 -410.411676) (xy 418.690473 -410.411279)
			(xy 418.636515 -410.403525) (xy 418.584209 -410.38817) (xy 418.534621 -410.365528) (xy 418.48876 -410.336058)
			(xy 418.44756 -410.300361) (xy 418.41186 -410.259164) (xy 418.382387 -410.213306) (xy 418.35974 -410.163719)
			(xy 418.344381 -410.111415) (xy 418.336623 -410.057457) (xy 416.899112 -410.057457) (xy 416.891356 -410.111398)
			(xy 416.876001 -410.163693) (xy 416.85336 -410.213269) (xy 416.823893 -410.259119) (xy 416.788201 -410.300308)
			(xy 416.747011 -410.335999) (xy 416.70116 -410.365464) (xy 416.651583 -410.388104) (xy 416.599289 -410.403458)
			(xy 416.545341 -410.411213) (xy 416.51809 -410.411676) (xy 415.65449 -410.411676) (xy 415.627237 -410.411253)
			(xy 415.573286 -410.403495) (xy 415.520988 -410.388138) (xy 415.471408 -410.365494) (xy 415.425555 -410.336025)
			(xy 415.384362 -410.300331) (xy 415.348669 -410.259137) (xy 415.319201 -410.213283) (xy 415.296559 -410.163703)
			(xy 415.281203 -410.111404) (xy 415.273446 -410.057453) (xy 413.835913 -410.057453) (xy 413.828155 -410.111404)
			(xy 413.812798 -410.163701) (xy 413.790153 -410.21328) (xy 413.760683 -410.259132) (xy 413.724987 -410.300323)
			(xy 413.683792 -410.336013) (xy 413.637936 -410.365477) (xy 413.588354 -410.388115) (xy 413.536055 -410.403466)
			(xy 413.482103 -410.411216) (xy 413.45485 -410.411676) (xy 412.59125 -410.411676) (xy 412.563999 -410.411251)
			(xy 412.510052 -410.403488) (xy 412.457759 -410.388127) (xy 412.408184 -410.365481) (xy 412.362336 -410.336011)
			(xy 412.321148 -410.300317) (xy 412.285459 -410.259124) (xy 412.255995 -410.213272) (xy 412.233355 -410.163694)
			(xy 412.218002 -410.111399) (xy 412.210246 -410.057451) (xy 410.77259 -410.057451) (xy 410.764834 -410.111391)
			(xy 410.749481 -410.16368) (xy 410.726842 -410.213253) (xy 410.69738 -410.259099) (xy 410.661692 -410.300285)
			(xy 410.620507 -410.335974) (xy 410.574661 -410.365438) (xy 410.52509 -410.388077) (xy 410.472801 -410.403432)
			(xy 410.418858 -410.411189) (xy 410.39161 -410.411676) (xy 409.52801 -410.411676) (xy 409.500754 -410.411278)
			(xy 409.446798 -410.403521) (xy 409.394494 -410.388165) (xy 409.344909 -410.365521) (xy 409.29905 -410.336051)
			(xy 409.257853 -410.300354) (xy 409.222155 -410.259158) (xy 409.192684 -410.2133) (xy 409.170039 -410.163715)
			(xy 409.154681 -410.111412) (xy 409.146923 -410.057456) (xy 407.709412 -410.057456) (xy 407.701656 -410.111401)
			(xy 407.686299 -410.163697) (xy 407.663657 -410.213275) (xy 407.634188 -410.259126) (xy 407.598494 -410.300316)
			(xy 407.557301 -410.336006) (xy 407.511448 -410.365471) (xy 407.461869 -410.38811) (xy 407.409572 -410.403462)
			(xy 407.355622 -410.411215) (xy 407.32837 -410.411676) (xy 406.46477 -410.411676) (xy 406.437518 -410.411252)
			(xy 406.383569 -410.403491) (xy 406.331273 -410.388132) (xy 406.281696 -410.365488) (xy 406.235845 -410.336018)
			(xy 406.194655 -410.300324) (xy 406.158964 -410.259131) (xy 406.129498 -410.213278) (xy 406.106857 -410.163699)
			(xy 406.091502 -410.111402) (xy 406.083746 -410.057452) (xy 404.646089 -410.057452) (xy 404.638335 -410.111388)
			(xy 404.622983 -410.163676) (xy 404.600345 -410.213247) (xy 404.570884 -410.259092) (xy 404.535199 -410.300278)
			(xy 404.494016 -410.335966) (xy 404.448173 -410.365431) (xy 404.398604 -410.388072) (xy 404.346317 -410.403428)
			(xy 404.292378 -410.411188) (xy 404.26513 -410.411676) (xy 403.40153 -410.411676) (xy 403.374273 -410.411279)
			(xy 403.320315 -410.403525) (xy 403.268009 -410.38817) (xy 403.218421 -410.365528) (xy 403.17256 -410.336058)
			(xy 403.13136 -410.300361) (xy 403.09566 -410.259164) (xy 403.066187 -410.213306) (xy 403.04354 -410.163719)
			(xy 403.028181 -410.111415) (xy 403.020423 -410.057457) (xy 401.582912 -410.057457) (xy 401.575156 -410.111398)
			(xy 401.559801 -410.163693) (xy 401.53716 -410.213269) (xy 401.507693 -410.259119) (xy 401.472001 -410.300308)
			(xy 401.430811 -410.335999) (xy 401.38496 -410.365464) (xy 401.335383 -410.388104) (xy 401.283089 -410.403458)
			(xy 401.229141 -410.411213) (xy 401.20189 -410.411676) (xy 400.33829 -410.411676) (xy 400.311037 -410.411253)
			(xy 400.257086 -410.403495) (xy 400.204788 -410.388138) (xy 400.155208 -410.365494) (xy 400.109355 -410.336025)
			(xy 400.068162 -410.300331) (xy 400.032469 -410.259137) (xy 400.003001 -410.213283) (xy 399.980359 -410.163703)
			(xy 399.965003 -410.111404) (xy 399.957246 -410.057453) (xy 398.519713 -410.057453) (xy 398.511955 -410.111404)
			(xy 398.496598 -410.163701) (xy 398.473953 -410.21328) (xy 398.444483 -410.259132) (xy 398.408787 -410.300323)
			(xy 398.367592 -410.336013) (xy 398.321736 -410.365477) (xy 398.272154 -410.388115) (xy 398.219855 -410.403466)
			(xy 398.165903 -410.411216) (xy 398.13865 -410.411676) (xy 397.27505 -410.411676) (xy 397.247799 -410.411251)
			(xy 397.193852 -410.403488) (xy 397.141559 -410.388127) (xy 397.091984 -410.365481) (xy 397.046136 -410.336011)
			(xy 397.004948 -410.300317) (xy 396.969259 -410.259124) (xy 396.939795 -410.213272) (xy 396.917155 -410.163694)
			(xy 396.901802 -410.111399) (xy 396.894046 -410.057451) (xy 395.45639 -410.057451) (xy 395.448634 -410.111391)
			(xy 395.433281 -410.16368) (xy 395.410642 -410.213253) (xy 395.38118 -410.259099) (xy 395.345492 -410.300285)
			(xy 395.304307 -410.335974) (xy 395.258461 -410.365438) (xy 395.20889 -410.388077) (xy 395.156601 -410.403432)
			(xy 395.102658 -410.411189) (xy 395.07541 -410.411676) (xy 394.21181 -410.411676) (xy 394.184554 -410.411278)
			(xy 394.130598 -410.403521) (xy 394.078294 -410.388165) (xy 394.028709 -410.365521) (xy 393.98285 -410.336051)
			(xy 393.941653 -410.300354) (xy 393.905955 -410.259158) (xy 393.876484 -410.2133) (xy 393.853839 -410.163715)
			(xy 393.838481 -410.111412) (xy 393.830723 -410.057456) (xy 392.393212 -410.057456) (xy 392.385456 -410.111401)
			(xy 392.370099 -410.163697) (xy 392.347457 -410.213275) (xy 392.317988 -410.259126) (xy 392.282294 -410.300316)
			(xy 392.241101 -410.336006) (xy 392.195248 -410.365471) (xy 392.145669 -410.38811) (xy 392.093372 -410.403462)
			(xy 392.039422 -410.411215) (xy 392.01217 -410.411676) (xy 391.14857 -410.411676) (xy 391.121318 -410.411252)
			(xy 391.067369 -410.403491) (xy 391.015073 -410.388132) (xy 390.965496 -410.365488) (xy 390.919645 -410.336018)
			(xy 390.878455 -410.300324) (xy 390.842764 -410.259131) (xy 390.813298 -410.213278) (xy 390.790657 -410.163699)
			(xy 390.775302 -410.111402) (xy 390.767546 -410.057452) (xy 389.329889 -410.057452) (xy 389.322135 -410.111388)
			(xy 389.306783 -410.163676) (xy 389.284145 -410.213247) (xy 389.254684 -410.259092) (xy 389.218999 -410.300278)
			(xy 389.177816 -410.335966) (xy 389.131973 -410.365431) (xy 389.082404 -410.388072) (xy 389.030117 -410.403428)
			(xy 388.976178 -410.411188) (xy 388.94893 -410.411676) (xy 388.08533 -410.411676) (xy 388.058073 -410.411279)
			(xy 388.004115 -410.403525) (xy 387.951809 -410.38817) (xy 387.902221 -410.365528) (xy 387.85636 -410.336058)
			(xy 387.81516 -410.300361) (xy 387.77946 -410.259164) (xy 387.749987 -410.213306) (xy 387.72734 -410.163719)
			(xy 387.711981 -410.111415) (xy 387.704223 -410.057457) (xy 386.266712 -410.057457) (xy 386.258956 -410.111398)
			(xy 386.243601 -410.163693) (xy 386.22096 -410.213269) (xy 386.191493 -410.259119) (xy 386.155801 -410.300308)
			(xy 386.114611 -410.335999) (xy 386.06876 -410.365464) (xy 386.019183 -410.388104) (xy 385.966889 -410.403458)
			(xy 385.912941 -410.411213) (xy 385.88569 -410.411676) (xy 385.02209 -410.411676) (xy 384.994837 -410.411253)
			(xy 384.940886 -410.403495) (xy 384.888588 -410.388138) (xy 384.839008 -410.365494) (xy 384.793155 -410.336025)
			(xy 384.751962 -410.300331) (xy 384.716269 -410.259137) (xy 384.686801 -410.213283) (xy 384.664159 -410.163703)
			(xy 384.648803 -410.111404) (xy 384.641046 -410.057453) (xy 383.203513 -410.057453) (xy 383.195755 -410.111404)
			(xy 383.180398 -410.163701) (xy 383.157753 -410.21328) (xy 383.128283 -410.259132) (xy 383.092587 -410.300323)
			(xy 383.051392 -410.336013) (xy 383.005536 -410.365477) (xy 382.955954 -410.388115) (xy 382.903655 -410.403466)
			(xy 382.849703 -410.411216) (xy 382.82245 -410.411676) (xy 381.95885 -410.411676) (xy 381.931599 -410.411251)
			(xy 381.877652 -410.403488) (xy 381.825359 -410.388127) (xy 381.775784 -410.365481) (xy 381.729936 -410.336011)
			(xy 381.688748 -410.300317) (xy 381.653059 -410.259124) (xy 381.623595 -410.213272) (xy 381.600955 -410.163694)
			(xy 381.585602 -410.111399) (xy 381.577846 -410.057451) (xy 380.14019 -410.057451) (xy 380.132434 -410.111391)
			(xy 380.117081 -410.16368) (xy 380.094442 -410.213253) (xy 380.06498 -410.259099) (xy 380.029292 -410.300285)
			(xy 379.988107 -410.335974) (xy 379.942261 -410.365438) (xy 379.89269 -410.388077) (xy 379.840401 -410.403432)
			(xy 379.786458 -410.411189) (xy 379.75921 -410.411676) (xy 378.89561 -410.411676) (xy 378.868354 -410.411278)
			(xy 378.814398 -410.403521) (xy 378.762094 -410.388165) (xy 378.712509 -410.365521) (xy 378.66665 -410.336051)
			(xy 378.625453 -410.300354) (xy 378.589755 -410.259158) (xy 378.560284 -410.2133) (xy 378.537639 -410.163715)
			(xy 378.522281 -410.111412) (xy 378.514523 -410.057456) (xy 377.077012 -410.057456) (xy 377.069256 -410.111401)
			(xy 377.053899 -410.163697) (xy 377.031257 -410.213275) (xy 377.001788 -410.259126) (xy 376.966094 -410.300316)
			(xy 376.924901 -410.336006) (xy 376.879048 -410.365471) (xy 376.829469 -410.38811) (xy 376.777172 -410.403462)
			(xy 376.723222 -410.411215) (xy 376.69597 -410.411676) (xy 375.83237 -410.411676) (xy 375.805118 -410.411252)
			(xy 375.751169 -410.403491) (xy 375.698873 -410.388132) (xy 375.649296 -410.365488) (xy 375.603445 -410.336018)
			(xy 375.562255 -410.300324) (xy 375.526564 -410.259131) (xy 375.497098 -410.213278) (xy 375.474457 -410.163699)
			(xy 375.459102 -410.111402) (xy 375.451346 -410.057452) (xy 374.013689 -410.057452) (xy 374.005935 -410.111388)
			(xy 373.990583 -410.163676) (xy 373.967945 -410.213247) (xy 373.938484 -410.259092) (xy 373.902799 -410.300278)
			(xy 373.861616 -410.335966) (xy 373.815773 -410.365431) (xy 373.766204 -410.388072) (xy 373.713917 -410.403428)
			(xy 373.659978 -410.411188) (xy 373.63273 -410.411676) (xy 372.76913 -410.411676) (xy 372.741873 -410.411279)
			(xy 372.687915 -410.403525) (xy 372.635609 -410.38817) (xy 372.586021 -410.365528) (xy 372.54016 -410.336058)
			(xy 372.49896 -410.300361) (xy 372.46326 -410.259164) (xy 372.433787 -410.213306) (xy 372.41114 -410.163719)
			(xy 372.395781 -410.111415) (xy 372.388023 -410.057457) (xy 352.519512 -410.057457) (xy 352.511756 -410.111399)
			(xy 352.496401 -410.163693) (xy 352.473759 -410.21327) (xy 352.444293 -410.25912) (xy 352.408601 -410.300309)
			(xy 352.36741 -410.336) (xy 352.321559 -410.365465) (xy 352.271982 -410.388105) (xy 352.219687 -410.403459)
			(xy 352.165739 -410.411214) (xy 352.138488 -410.411676) (xy 351.274888 -410.411676) (xy 351.247635 -410.411253)
			(xy 351.193684 -410.403495) (xy 351.141386 -410.388137) (xy 351.091807 -410.365494) (xy 351.045954 -410.336025)
			(xy 351.004762 -410.30033) (xy 350.969068 -410.259137) (xy 350.939601 -410.213283) (xy 350.916958 -410.163702)
			(xy 350.901603 -410.111404) (xy 350.893846 -410.057453) (xy 349.456189 -410.057453) (xy 349.448435 -410.111386)
			(xy 349.433084 -410.163672) (xy 349.410448 -410.213242) (xy 349.380989 -410.259086) (xy 349.345306 -410.300272)
			(xy 349.304125 -410.33596) (xy 349.258284 -410.365425) (xy 349.208717 -410.388067) (xy 349.156433 -410.403425)
			(xy 349.102495 -410.411187) (xy 349.075248 -410.411676) (xy 348.211648 -410.411676) (xy 348.184391 -410.41128)
			(xy 348.13043 -410.403528) (xy 348.078122 -410.388175) (xy 348.028531 -410.365533) (xy 347.982668 -410.336064)
			(xy 347.941466 -410.300367) (xy 347.905765 -410.25917) (xy 347.87629 -410.213311) (xy 347.853642 -410.163723)
			(xy 347.838282 -410.111417) (xy 347.830523 -410.057457) (xy 346.392989 -410.057457) (xy 346.385234 -410.111391)
			(xy 346.369881 -410.163681) (xy 346.347242 -410.213253) (xy 346.317779 -410.259099) (xy 346.282091 -410.300286)
			(xy 346.240906 -410.335974) (xy 346.19506 -410.365438) (xy 346.145488 -410.388078) (xy 346.093199 -410.403432)
			(xy 346.039257 -410.411189) (xy 346.012008 -410.411676) (xy 345.148408 -410.411676) (xy 345.121152 -410.411278)
			(xy 345.067196 -410.403521) (xy 345.014893 -410.388164) (xy 344.965307 -410.36552) (xy 344.919449 -410.33605)
			(xy 344.878252 -410.300353) (xy 344.842555 -410.259157) (xy 344.813084 -410.2133) (xy 344.790439 -410.163715)
			(xy 344.775081 -410.111412) (xy 344.767323 -410.057456) (xy 343.329812 -410.057456) (xy 343.322055 -410.111401)
			(xy 343.306699 -410.163697) (xy 343.284056 -410.213275) (xy 343.254588 -410.259126) (xy 343.218894 -410.300316)
			(xy 343.177701 -410.336007) (xy 343.131847 -410.365472) (xy 343.082267 -410.38811) (xy 343.02997 -410.403462)
			(xy 342.97602 -410.411215) (xy 342.948768 -410.411676) (xy 342.085168 -410.411676) (xy 342.057916 -410.411252)
			(xy 342.003967 -410.403491) (xy 341.951672 -410.388132) (xy 341.902095 -410.365487) (xy 341.856244 -410.336017)
			(xy 341.815054 -410.300323) (xy 341.779363 -410.25913) (xy 341.749898 -410.213277) (xy 341.727257 -410.163698)
			(xy 341.711902 -410.111402) (xy 341.704146 -410.057452) (xy 340.266489 -410.057452) (xy 340.258735 -410.111388)
			(xy 340.243382 -410.163676) (xy 340.220745 -410.213248) (xy 340.191284 -410.259093) (xy 340.155599 -410.300279)
			(xy 340.114415 -410.335967) (xy 340.068572 -410.365432) (xy 340.019003 -410.388073) (xy 339.966716 -410.403429)
			(xy 339.912776 -410.411188) (xy 339.885528 -410.411676) (xy 339.021928 -410.411676) (xy 338.994672 -410.411279)
			(xy 338.940713 -410.403525) (xy 338.888407 -410.38817) (xy 338.838819 -410.365527) (xy 338.792959 -410.336057)
			(xy 338.751759 -410.30036) (xy 338.71606 -410.259164) (xy 338.686587 -410.213305) (xy 338.66394 -410.163719)
			(xy 338.648581 -410.111414) (xy 338.640823 -410.057456) (xy 337.203312 -410.057456) (xy 337.195556 -410.111399)
			(xy 337.180201 -410.163693) (xy 337.157559 -410.21327) (xy 337.128093 -410.25912) (xy 337.092401 -410.300309)
			(xy 337.05121 -410.336) (xy 337.005359 -410.365465) (xy 336.955782 -410.388105) (xy 336.903487 -410.403459)
			(xy 336.849539 -410.411214) (xy 336.822288 -410.411676) (xy 335.958688 -410.411676) (xy 335.931435 -410.411253)
			(xy 335.877484 -410.403495) (xy 335.825186 -410.388137) (xy 335.775607 -410.365494) (xy 335.729754 -410.336025)
			(xy 335.688562 -410.30033) (xy 335.652868 -410.259137) (xy 335.623401 -410.213283) (xy 335.600758 -410.163702)
			(xy 335.585403 -410.111404) (xy 335.577646 -410.057453) (xy 334.139989 -410.057453) (xy 334.132235 -410.111386)
			(xy 334.116884 -410.163672) (xy 334.094248 -410.213242) (xy 334.064789 -410.259086) (xy 334.029106 -410.300272)
			(xy 333.987925 -410.33596) (xy 333.942084 -410.365425) (xy 333.892517 -410.388067) (xy 333.840233 -410.403425)
			(xy 333.786295 -410.411187) (xy 333.759048 -410.411676) (xy 332.895448 -410.411676) (xy 332.868191 -410.41128)
			(xy 332.81423 -410.403528) (xy 332.761922 -410.388175) (xy 332.712331 -410.365533) (xy 332.666468 -410.336064)
			(xy 332.625266 -410.300367) (xy 332.589565 -410.25917) (xy 332.56009 -410.213311) (xy 332.537442 -410.163723)
			(xy 332.522082 -410.111417) (xy 332.514323 -410.057457) (xy 331.076789 -410.057457) (xy 331.069034 -410.111391)
			(xy 331.053681 -410.163681) (xy 331.031042 -410.213253) (xy 331.001579 -410.259099) (xy 330.965891 -410.300286)
			(xy 330.924706 -410.335974) (xy 330.87886 -410.365438) (xy 330.829288 -410.388078) (xy 330.776999 -410.403432)
			(xy 330.723057 -410.411189) (xy 330.695808 -410.411676) (xy 329.832208 -410.411676) (xy 329.804952 -410.411278)
			(xy 329.750996 -410.403521) (xy 329.698693 -410.388164) (xy 329.649107 -410.36552) (xy 329.603249 -410.33605)
			(xy 329.562052 -410.300353) (xy 329.526355 -410.259157) (xy 329.496884 -410.2133) (xy 329.474239 -410.163715)
			(xy 329.458881 -410.111412) (xy 329.451123 -410.057456) (xy 328.013612 -410.057456) (xy 328.005855 -410.111401)
			(xy 327.990499 -410.163697) (xy 327.967856 -410.213275) (xy 327.938388 -410.259126) (xy 327.902694 -410.300316)
			(xy 327.861501 -410.336007) (xy 327.815647 -410.365472) (xy 327.766067 -410.38811) (xy 327.71377 -410.403462)
			(xy 327.65982 -410.411215) (xy 327.632568 -410.411676) (xy 326.768968 -410.411676) (xy 326.741716 -410.411252)
			(xy 326.687767 -410.403491) (xy 326.635472 -410.388132) (xy 326.585895 -410.365487) (xy 326.540044 -410.336017)
			(xy 326.498854 -410.300323) (xy 326.463163 -410.25913) (xy 326.433698 -410.213277) (xy 326.411057 -410.163698)
			(xy 326.395702 -410.111402) (xy 326.387946 -410.057452) (xy 324.950289 -410.057452) (xy 324.942535 -410.111388)
			(xy 324.927182 -410.163676) (xy 324.904545 -410.213248) (xy 324.875084 -410.259093) (xy 324.839399 -410.300279)
			(xy 324.798215 -410.335967) (xy 324.752372 -410.365432) (xy 324.702803 -410.388073) (xy 324.650516 -410.403429)
			(xy 324.596576 -410.411188) (xy 324.569328 -410.411676) (xy 323.705728 -410.411676) (xy 323.678472 -410.411279)
			(xy 323.624513 -410.403525) (xy 323.572207 -410.38817) (xy 323.522619 -410.365527) (xy 323.476759 -410.336057)
			(xy 323.435559 -410.30036) (xy 323.39986 -410.259164) (xy 323.370387 -410.213305) (xy 323.34774 -410.163719)
			(xy 323.332381 -410.111414) (xy 323.324623 -410.057456) (xy 321.887112 -410.057456) (xy 321.879356 -410.111399)
			(xy 321.864001 -410.163693) (xy 321.841359 -410.21327) (xy 321.811893 -410.25912) (xy 321.776201 -410.300309)
			(xy 321.73501 -410.336) (xy 321.689159 -410.365465) (xy 321.639582 -410.388105) (xy 321.587287 -410.403459)
			(xy 321.533339 -410.411214) (xy 321.506088 -410.411676) (xy 320.642488 -410.411676) (xy 320.615235 -410.411253)
			(xy 320.561284 -410.403495) (xy 320.508986 -410.388137) (xy 320.459407 -410.365494) (xy 320.413554 -410.336025)
			(xy 320.372362 -410.30033) (xy 320.336668 -410.259137) (xy 320.307201 -410.213283) (xy 320.284558 -410.163702)
			(xy 320.269203 -410.111404) (xy 320.261446 -410.057453) (xy 318.823789 -410.057453) (xy 318.816035 -410.111386)
			(xy 318.800684 -410.163672) (xy 318.778048 -410.213242) (xy 318.748589 -410.259086) (xy 318.712906 -410.300272)
			(xy 318.671725 -410.33596) (xy 318.625884 -410.365425) (xy 318.576317 -410.388067) (xy 318.524033 -410.403425)
			(xy 318.470095 -410.411187) (xy 318.442848 -410.411676) (xy 317.579248 -410.411676) (xy 317.551991 -410.41128)
			(xy 317.49803 -410.403528) (xy 317.445722 -410.388175) (xy 317.396131 -410.365533) (xy 317.350268 -410.336064)
			(xy 317.309066 -410.300367) (xy 317.273365 -410.25917) (xy 317.24389 -410.213311) (xy 317.221242 -410.163723)
			(xy 317.205882 -410.111417) (xy 317.198123 -410.057457) (xy 315.760589 -410.057457) (xy 315.752834 -410.111391)
			(xy 315.737481 -410.163681) (xy 315.714842 -410.213253) (xy 315.685379 -410.259099) (xy 315.649691 -410.300286)
			(xy 315.608506 -410.335974) (xy 315.56266 -410.365438) (xy 315.513088 -410.388078) (xy 315.460799 -410.403432)
			(xy 315.406857 -410.411189) (xy 315.379608 -410.411676) (xy 314.516008 -410.411676) (xy 314.488752 -410.411278)
			(xy 314.434796 -410.403521) (xy 314.382493 -410.388164) (xy 314.332907 -410.36552) (xy 314.287049 -410.33605)
			(xy 314.245852 -410.300353) (xy 314.210155 -410.259157) (xy 314.180684 -410.2133) (xy 314.158039 -410.163715)
			(xy 314.142681 -410.111412) (xy 314.134923 -410.057456) (xy 312.697412 -410.057456) (xy 312.689655 -410.111401)
			(xy 312.674299 -410.163697) (xy 312.651656 -410.213275) (xy 312.622188 -410.259126) (xy 312.586494 -410.300316)
			(xy 312.545301 -410.336007) (xy 312.499447 -410.365472) (xy 312.449867 -410.38811) (xy 312.39757 -410.403462)
			(xy 312.34362 -410.411215) (xy 312.316368 -410.411676) (xy 311.452768 -410.411676) (xy 311.425516 -410.411252)
			(xy 311.371567 -410.403491) (xy 311.319272 -410.388132) (xy 311.269695 -410.365487) (xy 311.223844 -410.336017)
			(xy 311.182654 -410.300323) (xy 311.146963 -410.25913) (xy 311.117498 -410.213277) (xy 311.094857 -410.163698)
			(xy 311.079502 -410.111402) (xy 311.071746 -410.057452) (xy 309.634089 -410.057452) (xy 309.626335 -410.111388)
			(xy 309.610982 -410.163676) (xy 309.588345 -410.213248) (xy 309.558884 -410.259093) (xy 309.523199 -410.300279)
			(xy 309.482015 -410.335967) (xy 309.436172 -410.365432) (xy 309.386603 -410.388073) (xy 309.334316 -410.403429)
			(xy 309.280376 -410.411188) (xy 309.253128 -410.411676) (xy 308.389528 -410.411676) (xy 308.362272 -410.411279)
			(xy 308.308313 -410.403525) (xy 308.256007 -410.38817) (xy 308.206419 -410.365527) (xy 308.160559 -410.336057)
			(xy 308.119359 -410.30036) (xy 308.08366 -410.259164) (xy 308.054187 -410.213305) (xy 308.03154 -410.163719)
			(xy 308.016181 -410.111414) (xy 308.008423 -410.057456) (xy 306.570912 -410.057456) (xy 306.563156 -410.111399)
			(xy 306.547801 -410.163693) (xy 306.525159 -410.21327) (xy 306.495693 -410.25912) (xy 306.460001 -410.300309)
			(xy 306.41881 -410.336) (xy 306.372959 -410.365465) (xy 306.323382 -410.388105) (xy 306.271087 -410.403459)
			(xy 306.217139 -410.411214) (xy 306.189888 -410.411676) (xy 305.326288 -410.411676) (xy 305.299035 -410.411253)
			(xy 305.245084 -410.403495) (xy 305.192786 -410.388137) (xy 305.143207 -410.365494) (xy 305.097354 -410.336025)
			(xy 305.056162 -410.30033) (xy 305.020468 -410.259137) (xy 304.991001 -410.213283) (xy 304.968358 -410.163702)
			(xy 304.953003 -410.111404) (xy 304.945246 -410.057453) (xy 280.83256 -410.057453) (xy 280.83256 -415.172652)
			(xy 280.832075 -415.197601) (xy 280.824257 -415.246884) (xy 280.808837 -415.294341) (xy 280.786193 -415.338807)
			(xy 280.756881 -415.37919) (xy 280.739596 -415.397188) (xy 280.152348 -415.984436) (xy 280.134386 -416.001764)
			(xy 280.094003 -416.03109) (xy 280.04953 -416.053738) (xy 280.002061 -416.069148) (xy 279.952766 -416.076943)
			(xy 279.927812 -416.0774) (xy 275.812504 -416.0774) (xy 270.721328 -421.168576) (xy 270.703321 -421.185853)
			(xy 270.662948 -421.21518) (xy 270.618486 -421.23783) (xy 270.571027 -421.253247) (xy 270.521742 -421.261051)
			(xy 270.496792 -421.26154) (xy 233.336592 -421.26154) (xy 231.01554 -423.582592) (xy 231.01554 -424.804386)
			(xy 357.679233 -424.804386) (xy 357.679233 -424.675246) (xy 357.687183 -424.546351) (xy 357.703053 -424.418191)
			(xy 357.726782 -424.29125) (xy 357.758281 -424.166011) (xy 357.79743 -424.042948) (xy 357.844081 -423.922529)
			(xy 357.898056 -423.80521) (xy 357.959151 -423.691436) (xy 358.027134 -423.581639) (xy 358.101748 -423.476236)
			(xy 358.182709 -423.375626) (xy 358.269709 -423.280191) (xy 358.36242 -423.190292) (xy 358.46049 -423.106271)
			(xy 358.563545 -423.028447) (xy 358.671196 -422.957115) (xy 358.783035 -422.892545) (xy 358.898636 -422.834983)
			(xy 359.017561 -422.784646) (xy 359.13936 -422.741726) (xy 359.26357 -422.706385) (xy 359.389719 -422.678758)
			(xy 359.517331 -422.658949) (xy 359.64592 -422.647033) (xy 359.774998 -422.643057) (xy 359.904076 -422.647033)
			(xy 360.032665 -422.658949) (xy 360.160277 -422.678758) (xy 360.286426 -422.706385) (xy 360.410636 -422.741726)
			(xy 360.532435 -422.784646) (xy 360.65136 -422.834983) (xy 360.766961 -422.892545) (xy 360.8788 -422.957115)
			(xy 360.986451 -423.028447) (xy 361.089506 -423.106271) (xy 361.187576 -423.190292) (xy 361.280287 -423.280191)
			(xy 361.367287 -423.375626) (xy 361.448248 -423.476236) (xy 361.522862 -423.581639) (xy 361.590845 -423.691436)
			(xy 361.65194 -423.80521) (xy 361.705915 -423.922529) (xy 361.752566 -424.042948) (xy 361.791715 -424.166011)
			(xy 361.823214 -424.29125) (xy 361.846943 -424.418191) (xy 361.853367 -424.470068) (xy 421.270176 -424.470068)
			(xy 421.270176 -417.770056) (xy 421.270681 -417.664527) (xy 421.278765 -417.453623) (xy 421.294922 -417.243184)
			(xy 421.319127 -417.033518) (xy 421.351345 -416.824934) (xy 421.391528 -416.617736) (xy 421.439619 -416.412229)
			(xy 421.495545 -416.208716) (xy 421.559226 -416.007493) (xy 421.630567 -415.808858) (xy 421.709464 -415.613101)
			(xy 421.795802 -415.420509) (xy 421.889452 -415.231366) (xy 421.990279 -415.045949) (xy 422.098134 -414.864529)
			(xy 422.212858 -414.687374) (xy 422.334284 -414.514743) (xy 422.462233 -414.34689) (xy 422.596517 -414.184061)
			(xy 422.73694 -414.026495) (xy 422.883295 -413.874423) (xy 423.035367 -413.728068) (xy 423.192933 -413.587645)
			(xy 423.355762 -413.453361) (xy 423.523615 -413.325412) (xy 423.696246 -413.203986) (xy 423.873401 -413.089262)
			(xy 424.054821 -412.981407) (xy 424.240238 -412.88058) (xy 424.429381 -412.78693) (xy 424.621973 -412.700592)
			(xy 424.81773 -412.621695) (xy 425.016365 -412.550354) (xy 425.217588 -412.486673) (xy 425.421101 -412.430747)
			(xy 425.626608 -412.382656) (xy 425.833806 -412.342473) (xy 426.04239 -412.310255) (xy 426.252056 -412.28605)
			(xy 426.462495 -412.269893) (xy 426.673399 -412.261809) (xy 426.884457 -412.261809) (xy 427.095361 -412.269893)
			(xy 427.3058 -412.28605) (xy 427.515466 -412.310255) (xy 427.72405 -412.342473) (xy 427.931248 -412.382656)
			(xy 428.136755 -412.430747) (xy 428.340268 -412.486673) (xy 428.541491 -412.550354) (xy 428.740126 -412.621695)
			(xy 428.935883 -412.700592) (xy 429.128475 -412.78693) (xy 429.317618 -412.88058) (xy 429.503035 -412.981407)
			(xy 429.684455 -413.089262) (xy 429.86161 -413.203986) (xy 430.034241 -413.325412) (xy 430.202094 -413.453361)
			(xy 430.364923 -413.587645) (xy 430.522489 -413.728068) (xy 430.674561 -413.874423) (xy 430.820916 -414.026495)
			(xy 430.961339 -414.184061) (xy 431.095623 -414.34689) (xy 431.223572 -414.514743) (xy 431.344998 -414.687374)
			(xy 431.459722 -414.864529) (xy 431.567577 -415.045949) (xy 431.668404 -415.231366) (xy 431.762054 -415.420509)
			(xy 431.848392 -415.613101) (xy 431.927289 -415.808858) (xy 431.99863 -416.007493) (xy 432.062311 -416.208716)
			(xy 432.118237 -416.412229) (xy 432.166328 -416.617736) (xy 432.206511 -416.824934) (xy 432.238729 -417.033518)
			(xy 432.262934 -417.243184) (xy 432.279091 -417.453623) (xy 432.287175 -417.664527) (xy 432.28768 -417.770056)
			(xy 432.28768 -424.470068) (xy 432.287175 -424.575597) (xy 432.279091 -424.786501) (xy 432.262934 -424.99694)
			(xy 432.238729 -425.206606) (xy 432.206511 -425.41519) (xy 432.166328 -425.622388) (xy 432.118237 -425.827895)
			(xy 432.062311 -426.031408) (xy 431.99863 -426.232631) (xy 431.927289 -426.431266) (xy 431.848392 -426.627023)
			(xy 431.762054 -426.819615) (xy 431.668404 -427.008758) (xy 431.567577 -427.194175) (xy 431.459722 -427.375595)
			(xy 431.344998 -427.55275) (xy 431.223572 -427.725381) (xy 431.095623 -427.893234) (xy 430.961339 -428.056063)
			(xy 430.820916 -428.213629) (xy 430.674561 -428.365701) (xy 430.522489 -428.512056) (xy 430.364923 -428.652479)
			(xy 430.202094 -428.786763) (xy 430.034241 -428.914712) (xy 429.86161 -429.036138) (xy 429.684455 -429.150862)
			(xy 429.503035 -429.258717) (xy 429.317618 -429.359544) (xy 429.128475 -429.453194) (xy 428.935883 -429.539532)
			(xy 428.740126 -429.618429) (xy 428.541491 -429.68977) (xy 428.340268 -429.753451) (xy 428.136755 -429.809377)
			(xy 427.931248 -429.857468) (xy 427.72405 -429.897651) (xy 427.515466 -429.929869) (xy 427.3058 -429.954074)
			(xy 427.095361 -429.970231) (xy 426.884457 -429.978315) (xy 426.673399 -429.978315) (xy 426.462495 -429.970231)
			(xy 426.252056 -429.954074) (xy 426.04239 -429.929869) (xy 425.833806 -429.897651) (xy 425.626608 -429.857468)
			(xy 425.421101 -429.809377) (xy 425.217588 -429.753451) (xy 425.016365 -429.68977) (xy 424.81773 -429.618429)
			(xy 424.621973 -429.539532) (xy 424.429381 -429.453194) (xy 424.240238 -429.359544) (xy 424.054821 -429.258717)
			(xy 423.873401 -429.150862) (xy 423.696246 -429.036138) (xy 423.523615 -428.914712) (xy 423.355762 -428.786763)
			(xy 423.192933 -428.652479) (xy 423.035367 -428.512056) (xy 422.883295 -428.365701) (xy 422.73694 -428.213629)
			(xy 422.596517 -428.056063) (xy 422.462233 -427.893234) (xy 422.334284 -427.725381) (xy 422.212858 -427.55275)
			(xy 422.098134 -427.375595) (xy 421.990279 -427.194175) (xy 421.889452 -427.008758) (xy 421.795802 -426.819615)
			(xy 421.709464 -426.627023) (xy 421.630567 -426.431266) (xy 421.559226 -426.232631) (xy 421.495545 -426.031408)
			(xy 421.439619 -425.827895) (xy 421.391528 -425.622388) (xy 421.351345 -425.41519) (xy 421.319127 -425.206606)
			(xy 421.294922 -424.99694) (xy 421.278765 -424.786501) (xy 421.270681 -424.575597) (xy 421.270176 -424.470068)
			(xy 361.853367 -424.470068) (xy 361.862813 -424.546351) (xy 361.870763 -424.675246) (xy 361.87126 -424.739816)
			(xy 361.870763 -424.804386) (xy 361.862813 -424.933281) (xy 361.846943 -425.061441) (xy 361.823214 -425.188382)
			(xy 361.791715 -425.313621) (xy 361.752566 -425.436684) (xy 361.705915 -425.557103) (xy 361.65194 -425.674422)
			(xy 361.590845 -425.788196) (xy 361.522862 -425.897993) (xy 361.448248 -426.003396) (xy 361.367287 -426.104006)
			(xy 361.280287 -426.199441) (xy 361.187576 -426.28934) (xy 361.089506 -426.373361) (xy 360.986451 -426.451185)
			(xy 360.8788 -426.522517) (xy 360.766961 -426.587087) (xy 360.65136 -426.644649) (xy 360.532435 -426.694986)
			(xy 360.410636 -426.737906) (xy 360.286426 -426.773247) (xy 360.160277 -426.800874) (xy 360.032665 -426.820683)
			(xy 359.904076 -426.832599) (xy 359.774998 -426.836576) (xy 359.64592 -426.832599) (xy 359.517331 -426.820683)
			(xy 359.389719 -426.800874) (xy 359.26357 -426.773247) (xy 359.13936 -426.737906) (xy 359.017561 -426.694986)
			(xy 358.898636 -426.644649) (xy 358.783035 -426.587087) (xy 358.671196 -426.522517) (xy 358.563545 -426.451185)
			(xy 358.46049 -426.373361) (xy 358.36242 -426.28934) (xy 358.269709 -426.199441) (xy 358.182709 -426.104006)
			(xy 358.101748 -426.003396) (xy 358.027134 -425.897993) (xy 357.959151 -425.788196) (xy 357.898056 -425.674422)
			(xy 357.844081 -425.557103) (xy 357.79743 -425.436684) (xy 357.758281 -425.313621) (xy 357.726782 -425.188382)
			(xy 357.703053 -425.061441) (xy 357.687183 -424.933281) (xy 357.679233 -424.804386) (xy 231.01554 -424.804386)
			(xy 231.01554 -427.289976) (xy 314.138056 -427.289976) (xy 314.13817 -427.274891) (xy 314.139948 -427.244772)
			(xy 314.141612 -427.229778) (xy 314.141612 -426.150024) (xy 314.139943 -426.135031) (xy 314.138165 -426.104912)
			(xy 314.138056 -426.089826) (xy 314.138166 -426.07474) (xy 314.139947 -426.044622) (xy 314.141612 -426.029628)
			(xy 314.141612 -425.419012) (xy 314.142023 -425.406928) (xy 314.14949 -425.383942) (xy 314.163696 -425.36439)
			(xy 314.183249 -425.350186) (xy 314.206236 -425.342722) (xy 314.21832 -425.342304) (xy 315.15812 -425.342304)
			(xy 315.170197 -425.342748) (xy 315.193167 -425.350217) (xy 315.212704 -425.364419) (xy 315.226898 -425.383962)
			(xy 315.234357 -425.406935) (xy 315.234828 -425.419012) (xy 315.234828 -427.960536) (xy 315.234367 -427.97261)
			(xy 315.226897 -427.995576) (xy 315.212699 -428.01511) (xy 315.193161 -428.029304) (xy 315.170195 -428.036769)
			(xy 315.15812 -428.037244) (xy 314.21832 -428.037244) (xy 314.20625 -428.036719) (xy 314.18329 -428.029267)
			(xy 314.163755 -428.015085) (xy 314.149559 -427.995561) (xy 314.142089 -427.972606) (xy 314.141612 -427.960536)
			(xy 314.141612 -427.350174) (xy 314.139948 -427.33518) (xy 314.138166 -427.305062) (xy 314.138056 -427.289976)
			(xy 231.01554 -427.289976) (xy 231.01554 -428.28972) (xy 316.138052 -428.28972) (xy 316.138162 -428.274634)
			(xy 316.139943 -428.244516) (xy 316.141608 -428.229522) (xy 316.141608 -427.150022) (xy 316.139939 -427.135029)
			(xy 316.138161 -427.10491) (xy 316.138052 -427.089824) (xy 316.138162 -427.074738) (xy 316.139943 -427.04462)
			(xy 316.141608 -427.029626) (xy 316.141608 -426.41901) (xy 316.142115 -426.406924) (xy 316.149565 -426.383929)
			(xy 316.163743 -426.364352) (xy 316.183266 -426.3501) (xy 316.206232 -426.342562) (xy 316.218316 -426.342048)
			(xy 317.158116 -426.342048) (xy 317.170221 -426.342502) (xy 317.193239 -426.349999) (xy 317.212808 -426.364253)
			(xy 317.227004 -426.383863) (xy 317.234433 -426.406904) (xy 317.234824 -426.41901) (xy 317.234824 -427.289976)
			(xy 318.138048 -427.289976) (xy 318.138162 -427.274891) (xy 318.13994 -427.244772) (xy 318.141604 -427.229778)
			(xy 318.141604 -426.150024) (xy 318.139935 -426.135031) (xy 318.138157 -426.104912) (xy 318.138048 -426.089826)
			(xy 318.138158 -426.07474) (xy 318.139939 -426.044622) (xy 318.141604 -426.029628) (xy 318.141604 -425.419012)
			(xy 318.142023 -425.406929) (xy 318.149489 -425.383944) (xy 318.163693 -425.364393) (xy 318.183244 -425.350189)
			(xy 318.206229 -425.342723) (xy 318.218312 -425.342304) (xy 319.158112 -425.342304) (xy 319.170188 -425.342754)
			(xy 319.193158 -425.350222) (xy 319.212696 -425.364421) (xy 319.226889 -425.383964) (xy 319.234349 -425.406935)
			(xy 319.23482 -425.419012) (xy 319.23482 -427.960536) (xy 319.234367 -427.972611) (xy 319.226896 -427.995578)
			(xy 319.212696 -428.015113) (xy 319.193156 -428.029307) (xy 319.170187 -428.036771) (xy 319.158112 -428.037244)
			(xy 318.218312 -428.037244) (xy 318.206242 -428.036726) (xy 318.183281 -428.029271) (xy 318.163747 -428.015087)
			(xy 318.149551 -427.995562) (xy 318.142081 -427.972606) (xy 318.141604 -427.960536) (xy 318.141604 -427.350174)
			(xy 318.13994 -427.33518) (xy 318.138158 -427.305062) (xy 318.138048 -427.289976) (xy 317.234824 -427.289976)
			(xy 317.234824 -428.28972) (xy 320.138044 -428.28972) (xy 320.138154 -428.274634) (xy 320.139935 -428.244516)
			(xy 320.1416 -428.229522) (xy 320.1416 -427.150022) (xy 320.139931 -427.135029) (xy 320.138153 -427.10491)
			(xy 320.138044 -427.089824) (xy 320.138154 -427.074738) (xy 320.139935 -427.04462) (xy 320.1416 -427.029626)
			(xy 320.1416 -426.41901) (xy 320.142115 -426.406925) (xy 320.149564 -426.383931) (xy 320.16374 -426.364355)
			(xy 320.183261 -426.350103) (xy 320.206225 -426.342563) (xy 320.218308 -426.342048) (xy 321.158108 -426.342048)
			(xy 321.170212 -426.342509) (xy 321.193231 -426.350004) (xy 321.212799 -426.364256) (xy 321.226996 -426.383865)
			(xy 321.234425 -426.406905) (xy 321.234816 -426.41901) (xy 321.234816 -427.289976) (xy 322.13804 -427.289976)
			(xy 322.138155 -427.274891) (xy 322.139932 -427.244772) (xy 322.141596 -427.229778) (xy 322.141596 -426.150024)
			(xy 322.139927 -426.135031) (xy 322.138149 -426.104912) (xy 322.13804 -426.089826) (xy 322.13815 -426.07474)
			(xy 322.139931 -426.044622) (xy 322.141596 -426.029628) (xy 322.141596 -425.419012) (xy 322.142023 -425.40693)
			(xy 322.149488 -425.383947) (xy 322.16369 -425.364396) (xy 322.183239 -425.350191) (xy 322.206222 -425.342724)
			(xy 322.218304 -425.342304) (xy 323.158104 -425.342304) (xy 323.170188 -425.342709) (xy 323.193173 -425.350179)
			(xy 323.212724 -425.364387) (xy 323.226928 -425.383941) (xy 323.234393 -425.406928) (xy 323.234812 -425.419012)
			(xy 323.234812 -427.960536) (xy 323.234367 -427.972612) (xy 323.226895 -427.99558) (xy 323.212693 -428.015116)
			(xy 323.193151 -428.029309) (xy 323.17018 -428.036772) (xy 323.158104 -428.037244) (xy 322.218304 -428.037244)
			(xy 322.206233 -428.036733) (xy 322.183272 -428.029276) (xy 322.163738 -428.01509) (xy 322.149542 -427.995564)
			(xy 322.142073 -427.972607) (xy 322.141596 -427.960536) (xy 322.141596 -427.350174) (xy 322.139932 -427.33518)
			(xy 322.13815 -427.305062) (xy 322.13804 -427.289976) (xy 321.234816 -427.289976) (xy 321.234816 -428.28972)
			(xy 324.138036 -428.28972) (xy 324.138148 -428.274634) (xy 324.139929 -428.244516) (xy 324.141592 -428.229522)
			(xy 324.141592 -427.150022) (xy 324.139923 -427.135029) (xy 324.138145 -427.10491) (xy 324.138036 -427.089824)
			(xy 324.138148 -427.074738) (xy 324.139929 -427.04462) (xy 324.141592 -427.029626) (xy 324.141592 -426.41901)
			(xy 324.142115 -426.406926) (xy 324.149563 -426.383934) (xy 324.163737 -426.364358) (xy 324.183256 -426.350105)
			(xy 324.206218 -426.342564) (xy 324.2183 -426.342048) (xy 325.1581 -426.342048) (xy 325.170204 -426.342515)
			(xy 325.193222 -426.350009) (xy 325.212791 -426.364259) (xy 325.226987 -426.383866) (xy 325.234417 -426.406905)
			(xy 325.234808 -426.41901) (xy 325.234808 -427.289976) (xy 326.138032 -427.289976) (xy 326.138149 -427.274891)
			(xy 326.139927 -427.244772) (xy 326.141588 -427.229778) (xy 326.141588 -426.150024) (xy 326.139919 -426.135031)
			(xy 326.138141 -426.104912) (xy 326.138032 -426.089826) (xy 326.138144 -426.07474) (xy 326.139925 -426.044622)
			(xy 326.141588 -426.029628) (xy 326.141588 -425.419012) (xy 326.142023 -425.40693) (xy 326.149487 -425.383949)
			(xy 326.163687 -425.364399) (xy 326.183234 -425.350194) (xy 326.206214 -425.342726) (xy 326.218296 -425.342304)
			(xy 327.158096 -425.342304) (xy 327.17018 -425.342716) (xy 327.193164 -425.350184) (xy 327.212716 -425.36439)
			(xy 327.22692 -425.383943) (xy 327.234385 -425.406928) (xy 327.234804 -425.419012) (xy 327.234804 -427.960536)
			(xy 327.234367 -427.972613) (xy 327.226894 -427.995582) (xy 327.21269 -428.015119) (xy 327.193146 -428.029312)
			(xy 327.170173 -428.036773) (xy 327.158096 -428.037244) (xy 326.218296 -428.037244) (xy 326.206225 -428.03674)
			(xy 326.183264 -428.02928) (xy 326.16373 -428.015093) (xy 326.149534 -427.995565) (xy 326.142065 -427.972607)
			(xy 326.141588 -427.960536) (xy 326.141588 -427.350174) (xy 326.139924 -427.33518) (xy 326.138142 -427.305062)
			(xy 326.138032 -427.289976) (xy 325.234808 -427.289976) (xy 325.234808 -428.28972) (xy 328.138028 -428.28972)
			(xy 328.13814 -428.274634) (xy 328.139921 -428.244516) (xy 328.141584 -428.229522) (xy 328.141584 -427.150022)
			(xy 328.139915 -427.135029) (xy 328.138137 -427.10491) (xy 328.138028 -427.089824) (xy 328.13814 -427.074738)
			(xy 328.139921 -427.04462) (xy 328.141584 -427.029626) (xy 328.141584 -426.41901) (xy 328.142017 -426.406917)
			(xy 328.149476 -426.383909) (xy 328.16367 -426.364325) (xy 328.183214 -426.350076) (xy 328.2062 -426.342551)
			(xy 328.218292 -426.342048) (xy 329.158092 -426.342048) (xy 329.170195 -426.342522) (xy 329.193214 -426.350013)
			(xy 329.212782 -426.364262) (xy 329.226979 -426.383868) (xy 329.234409 -426.406906) (xy 329.2348 -426.41901)
			(xy 329.2348 -427.289976) (xy 331.138022 -427.289976) (xy 331.138113 -427.275402) (xy 331.139767 -427.246301)
			(xy 331.141324 -427.23181) (xy 331.141324 -426.147992) (xy 331.139781 -426.1335) (xy 331.138128 -426.1044)
			(xy 331.138022 -426.089826) (xy 331.138117 -426.075252) (xy 331.139769 -426.046151) (xy 331.141324 -426.03166)
			(xy 331.141324 -425.419012) (xy 331.141727 -425.406901) (xy 331.149226 -425.38387) (xy 331.16349 -425.364295)
			(xy 331.183116 -425.350101) (xy 331.206174 -425.342684) (xy 331.218286 -425.342304) (xy 332.158086 -425.342304)
			(xy 332.170171 -425.342819) (xy 332.193165 -425.350267) (xy 332.212742 -425.364443) (xy 332.226995 -425.383964)
			(xy 332.234533 -425.406929) (xy 332.235048 -425.419012) (xy 332.235048 -427.960536) (xy 332.234615 -427.972642)
			(xy 332.227111 -427.995662) (xy 332.212852 -428.01523) (xy 332.193238 -428.029426) (xy 332.170193 -428.036854)
			(xy 332.158086 -428.037244) (xy 331.218286 -428.037244) (xy 331.206194 -428.036804) (xy 331.18319 -428.029342)
			(xy 331.163609 -428.015149) (xy 331.14936 -427.995609) (xy 331.141831 -427.972627) (xy 331.141324 -427.960536)
			(xy 331.141324 -427.348142) (xy 331.139777 -427.33365) (xy 331.138127 -427.30455) (xy 331.138022 -427.289976)
			(xy 329.2348 -427.289976) (xy 329.2348 -428.28972) (xy 333.138018 -428.28972) (xy 333.138113 -428.275146)
			(xy 333.139764 -428.246045) (xy 333.14132 -428.231554) (xy 333.14132 -427.14799) (xy 333.139777 -427.133498)
			(xy 333.138124 -427.104398) (xy 333.138018 -427.089824) (xy 333.138113 -427.07525) (xy 333.139765 -427.046149)
			(xy 333.14132 -427.031658) (xy 333.14132 -426.41901) (xy 333.14182 -426.406898) (xy 333.149302 -426.383858)
			(xy 333.163538 -426.364258) (xy 333.183133 -426.350015) (xy 333.20617 -426.342525) (xy 333.218282 -426.342048)
			(xy 334.158082 -426.342048) (xy 334.170205 -426.342475) (xy 334.193265 -426.349964) (xy 334.212881 -426.364213)
			(xy 334.227132 -426.383828) (xy 334.234623 -426.406887) (xy 334.235044 -426.41901) (xy 334.235044 -427.289976)
			(xy 335.138014 -427.289976) (xy 335.138104 -427.275402) (xy 335.139759 -427.246301) (xy 335.141316 -427.23181)
			(xy 335.141316 -426.147992) (xy 335.139773 -426.1335) (xy 335.13812 -426.1044) (xy 335.138014 -426.089826)
			(xy 335.138109 -426.075252) (xy 335.13976 -426.046151) (xy 335.141316 -426.03166) (xy 335.141316 -425.419012)
			(xy 335.141727 -425.406902) (xy 335.149225 -425.383873) (xy 335.163487 -425.364298) (xy 335.183111 -425.350104)
			(xy 335.206167 -425.342685) (xy 335.218278 -425.342304) (xy 336.158078 -425.342304) (xy 336.170163 -425.342825)
			(xy 336.193157 -425.350272) (xy 336.212734 -425.364446) (xy 336.226986 -425.383966) (xy 336.234525 -425.406929)
			(xy 336.23504 -425.419012) (xy 336.23504 -427.960536) (xy 336.234615 -427.972643) (xy 336.22711 -427.995664)
			(xy 336.21285 -428.015233) (xy 336.193233 -428.029428) (xy 336.170186 -428.036855) (xy 336.158078 -428.037244)
			(xy 335.218278 -428.037244) (xy 335.206186 -428.036811) (xy 335.183182 -428.029347) (xy 335.163601 -428.015152)
			(xy 335.149351 -427.99561) (xy 335.141823 -427.972627) (xy 335.141316 -427.960536) (xy 335.141316 -427.348142)
			(xy 335.139769 -427.33365) (xy 335.138119 -427.30455) (xy 335.138014 -427.289976) (xy 334.235044 -427.289976)
			(xy 334.235044 -428.28972) (xy 337.13801 -428.28972) (xy 337.138104 -428.275146) (xy 337.139756 -428.246045)
			(xy 337.141312 -428.231554) (xy 337.141312 -427.14799) (xy 337.139769 -427.133498) (xy 337.138116 -427.104398)
			(xy 337.13801 -427.089824) (xy 337.138104 -427.07525) (xy 337.139756 -427.046149) (xy 337.141312 -427.031658)
			(xy 337.141312 -426.41901) (xy 337.14182 -426.406899) (xy 337.149301 -426.38386) (xy 337.163535 -426.36426)
			(xy 337.183128 -426.350018) (xy 337.206163 -426.342526) (xy 337.218274 -426.342048) (xy 338.158074 -426.342048)
			(xy 338.170196 -426.342482) (xy 338.193256 -426.349969) (xy 338.212872 -426.364216) (xy 338.227124 -426.38383)
			(xy 338.234615 -426.406888) (xy 338.235036 -426.41901) (xy 338.235036 -427.289976) (xy 339.138006 -427.289976)
			(xy 339.138096 -427.275402) (xy 339.139751 -427.246301) (xy 339.141308 -427.23181) (xy 339.141308 -426.147992)
			(xy 339.139765 -426.1335) (xy 339.138112 -426.1044) (xy 339.138006 -426.089826) (xy 339.138101 -426.075252)
			(xy 339.139752 -426.046151) (xy 339.141308 -426.03166) (xy 339.141308 -425.419012) (xy 339.141727 -425.406903)
			(xy 339.149224 -425.383875) (xy 339.163485 -425.364301) (xy 339.183106 -425.350106) (xy 339.20616 -425.342687)
			(xy 339.21827 -425.342304) (xy 340.15807 -425.342304) (xy 340.170154 -425.342832) (xy 340.193148 -425.350276)
			(xy 340.212725 -425.364448) (xy 340.226978 -425.383967) (xy 340.234517 -425.40693) (xy 340.235032 -425.419012)
			(xy 340.235032 -427.960536) (xy 340.234615 -427.972644) (xy 340.227109 -427.995667) (xy 340.212847 -428.015236)
			(xy 340.193228 -428.029431) (xy 340.170179 -428.036856) (xy 340.15807 -428.037244) (xy 339.21827 -428.037244)
			(xy 339.206177 -428.036818) (xy 339.183173 -428.029351) (xy 339.163592 -428.015154) (xy 339.149343 -427.995612)
			(xy 339.141815 -427.972627) (xy 339.141308 -427.960536) (xy 339.141308 -427.348142) (xy 339.139761 -427.33365)
			(xy 339.138111 -427.30455) (xy 339.138006 -427.289976) (xy 338.235036 -427.289976) (xy 338.235036 -428.28972)
			(xy 341.138002 -428.28972) (xy 341.138096 -428.275146) (xy 341.139748 -428.246045) (xy 341.141304 -428.231554)
			(xy 341.141304 -427.14799) (xy 341.139761 -427.133498) (xy 341.138108 -427.104398) (xy 341.138002 -427.089824)
			(xy 341.138096 -427.07525) (xy 341.139748 -427.046149) (xy 341.141304 -427.031658) (xy 341.141304 -426.41901)
			(xy 341.14182 -426.406899) (xy 341.1493 -426.383862) (xy 341.163532 -426.364263) (xy 341.183123 -426.35002)
			(xy 341.206156 -426.342527) (xy 341.218266 -426.342048) (xy 342.158066 -426.342048) (xy 342.170188 -426.342489)
			(xy 342.193247 -426.349973) (xy 342.212864 -426.364219) (xy 342.227116 -426.383831) (xy 342.234607 -426.406888)
			(xy 342.235028 -426.41901) (xy 342.235028 -427.289976) (xy 343.137998 -427.289976) (xy 343.138088 -427.275402)
			(xy 343.139743 -427.246301) (xy 343.1413 -427.23181) (xy 343.1413 -426.147992) (xy 343.139757 -426.1335)
			(xy 343.138104 -426.1044) (xy 343.137998 -426.089826) (xy 343.138093 -426.075252) (xy 343.139744 -426.046151)
			(xy 343.1413 -426.03166) (xy 343.1413 -425.419012) (xy 343.141727 -425.406904) (xy 343.149223 -425.383877)
			(xy 343.163482 -425.364304) (xy 343.183101 -425.350109) (xy 343.206152 -425.342688) (xy 343.218262 -425.342304)
			(xy 344.158062 -425.342304) (xy 344.170146 -425.342839) (xy 344.193139 -425.350281) (xy 344.212717 -425.364451)
			(xy 344.22697 -425.383968) (xy 344.234509 -425.40693) (xy 344.235024 -425.419012) (xy 344.235024 -427.960536)
			(xy 344.234615 -427.972644) (xy 344.227108 -427.995669) (xy 344.212844 -428.015239) (xy 344.193223 -428.029433)
			(xy 344.170172 -428.036857) (xy 344.158062 -428.037244) (xy 343.218262 -428.037244) (xy 343.206169 -428.036825)
			(xy 343.183164 -428.029356) (xy 343.163584 -428.015157) (xy 343.149335 -427.995613) (xy 343.141807 -427.972628)
			(xy 343.1413 -427.960536) (xy 343.1413 -427.348142) (xy 343.139753 -427.33365) (xy 343.138103 -427.30455)
			(xy 343.137998 -427.289976) (xy 342.235028 -427.289976) (xy 342.235028 -428.28972) (xy 345.137994 -428.28972)
			(xy 345.138088 -428.275146) (xy 345.13974 -428.246045) (xy 345.141296 -428.231554) (xy 345.141296 -427.14799)
			(xy 345.139753 -427.133498) (xy 345.1381 -427.104398) (xy 345.137994 -427.089824) (xy 345.138088 -427.07525)
			(xy 345.13974 -427.046149) (xy 345.141296 -427.031658) (xy 345.141296 -426.41901) (xy 345.14182 -426.4069)
			(xy 345.149299 -426.383864) (xy 345.163529 -426.364266) (xy 345.183118 -426.350023) (xy 345.206148 -426.342528)
			(xy 345.218258 -426.342048) (xy 346.158058 -426.342048) (xy 346.17018 -426.342496) (xy 346.193239 -426.349978)
			(xy 346.212855 -426.364222) (xy 346.227108 -426.383833) (xy 346.234599 -426.406889) (xy 346.23502 -426.41901)
			(xy 346.23502 -427.289976) (xy 381.237998 -427.289976) (xy 381.238088 -427.275402) (xy 381.239743 -427.246301)
			(xy 381.2413 -427.23181) (xy 381.2413 -426.147992) (xy 381.239757 -426.1335) (xy 381.238104 -426.1044)
			(xy 381.237998 -426.089826) (xy 381.238093 -426.075252) (xy 381.239744 -426.046151) (xy 381.2413 -426.03166)
			(xy 381.2413 -425.419012) (xy 381.241727 -425.406904) (xy 381.249223 -425.383877) (xy 381.263482 -425.364304)
			(xy 381.283101 -425.350109) (xy 381.306152 -425.342688) (xy 381.318262 -425.342304) (xy 382.258062 -425.342304)
			(xy 382.270146 -425.342839) (xy 382.293139 -425.350281) (xy 382.312717 -425.364451) (xy 382.32697 -425.383968)
			(xy 382.334509 -425.40693) (xy 382.335024 -425.419012) (xy 382.335024 -427.960536) (xy 382.334615 -427.972644)
			(xy 382.327108 -427.995669) (xy 382.312844 -428.015239) (xy 382.293223 -428.029433) (xy 382.270172 -428.036857)
			(xy 382.258062 -428.037244) (xy 381.318262 -428.037244) (xy 381.306169 -428.036825) (xy 381.283164 -428.029356)
			(xy 381.263584 -428.015157) (xy 381.249335 -427.995613) (xy 381.241807 -427.972628) (xy 381.2413 -427.960536)
			(xy 381.2413 -427.348142) (xy 381.239753 -427.33365) (xy 381.238103 -427.30455) (xy 381.237998 -427.289976)
			(xy 346.23502 -427.289976) (xy 346.23502 -428.960534) (xy 346.234669 -428.972663) (xy 346.227162 -428.99573)
			(xy 346.212894 -429.015348) (xy 346.193262 -429.029597) (xy 346.170187 -429.03708) (xy 346.158058 -429.037496)
			(xy 345.218258 -429.037496) (xy 345.206145 -429.037025) (xy 345.183106 -429.02953) (xy 345.163508 -429.015287)
			(xy 345.149266 -428.995687) (xy 345.141774 -428.972647) (xy 345.141296 -428.960534) (xy 345.141296 -428.347886)
			(xy 345.139753 -428.333394) (xy 345.1381 -428.304294) (xy 345.137994 -428.28972) (xy 342.235028 -428.28972)
			(xy 342.235028 -428.960534) (xy 342.234617 -428.972654) (xy 342.227116 -428.995704) (xy 342.21286 -429.015308)
			(xy 342.193243 -429.029547) (xy 342.170186 -429.037027) (xy 342.158066 -429.037496) (xy 341.218266 -429.037496)
			(xy 341.206153 -429.037018) (xy 341.183114 -429.029525) (xy 341.163516 -429.015284) (xy 341.149275 -428.995686)
			(xy 341.141782 -428.972647) (xy 341.141304 -428.960534) (xy 341.141304 -428.347886) (xy 341.139761 -428.333394)
			(xy 341.138108 -428.304294) (xy 341.138002 -428.28972) (xy 338.235036 -428.28972) (xy 338.235036 -428.960534)
			(xy 338.234617 -428.972653) (xy 338.227117 -428.995702) (xy 338.212862 -429.015305) (xy 338.193248 -429.029545)
			(xy 338.170193 -429.037026) (xy 338.158074 -429.037496) (xy 337.218274 -429.037496) (xy 337.206161 -429.037011)
			(xy 337.183123 -429.029521) (xy 337.163525 -429.015281) (xy 337.149283 -428.995684) (xy 337.14179 -428.972646)
			(xy 337.141312 -428.960534) (xy 337.141312 -428.347886) (xy 337.139769 -428.333394) (xy 337.138116 -428.304294)
			(xy 337.13801 -428.28972) (xy 334.235044 -428.28972) (xy 334.235044 -428.960534) (xy 334.234617 -428.972652)
			(xy 334.227118 -428.9957) (xy 334.212865 -429.015302) (xy 334.193253 -429.029542) (xy 334.1702 -429.037025)
			(xy 334.158082 -429.037496) (xy 333.218282 -429.037496) (xy 333.20617 -429.037004) (xy 333.183132 -429.029516)
			(xy 333.163533 -429.015278) (xy 333.149291 -428.995683) (xy 333.141798 -428.972646) (xy 333.14132 -428.960534)
			(xy 333.14132 -428.347886) (xy 333.139777 -428.333394) (xy 333.138124 -428.304294) (xy 333.138018 -428.28972)
			(xy 329.2348 -428.28972) (xy 329.2348 -428.960534) (xy 329.234322 -428.972621) (xy 329.226861 -428.995616)
			(xy 329.212676 -429.015192) (xy 329.193148 -429.029443) (xy 329.170178 -429.036981) (xy 329.158092 -429.037496)
			(xy 328.218292 -429.037496) (xy 328.206182 -429.037091) (xy 328.183154 -429.029588) (xy 328.163581 -429.015324)
			(xy 328.149386 -428.9957) (xy 328.141967 -428.972645) (xy 328.141584 -428.960534) (xy 328.141584 -428.349918)
			(xy 328.139915 -428.334925) (xy 328.138137 -428.304806) (xy 328.138028 -428.28972) (xy 325.234808 -428.28972)
			(xy 325.234808 -428.960534) (xy 325.234323 -428.972621) (xy 325.226862 -428.995614) (xy 325.212679 -429.01519)
			(xy 325.193153 -429.029441) (xy 325.170185 -429.03698) (xy 325.1581 -429.037496) (xy 324.2183 -429.037496)
			(xy 324.206191 -429.037084) (xy 324.183163 -429.029584) (xy 324.163589 -429.015321) (xy 324.149395 -428.995699)
			(xy 324.141975 -428.972645) (xy 324.141592 -428.960534) (xy 324.141592 -428.349918) (xy 324.139923 -428.334925)
			(xy 324.138145 -428.304806) (xy 324.138036 -428.28972) (xy 321.234816 -428.28972) (xy 321.234816 -428.960534)
			(xy 321.234421 -428.97263) (xy 321.226949 -428.995639) (xy 321.212746 -429.015222) (xy 321.193195 -429.02947)
			(xy 321.170203 -429.036993) (xy 321.158108 -429.037496) (xy 320.218308 -429.037496) (xy 320.206199 -429.037077)
			(xy 320.183171 -429.029579) (xy 320.163598 -429.015319) (xy 320.149403 -428.995697) (xy 320.141983 -428.972644)
			(xy 320.1416 -428.960534) (xy 320.1416 -428.349918) (xy 320.139931 -428.334925) (xy 320.138153 -428.304806)
			(xy 320.138044 -428.28972) (xy 317.234824 -428.28972) (xy 317.234824 -428.960534) (xy 317.234421 -428.972629)
			(xy 317.226951 -428.995637) (xy 317.212749 -429.015219) (xy 317.1932 -429.029467) (xy 317.17021 -429.036992)
			(xy 317.158116 -429.037496) (xy 316.218316 -429.037496) (xy 316.206208 -429.03707) (xy 316.18318 -429.029574)
			(xy 316.163607 -429.015315) (xy 316.149412 -428.995695) (xy 316.141991 -428.972644) (xy 316.141608 -428.960534)
			(xy 316.141608 -428.349918) (xy 316.139939 -428.334925) (xy 316.138161 -428.304806) (xy 316.138052 -428.28972)
			(xy 231.01554 -428.28972) (xy 231.01554 -433.130695) (xy 266.885917 -433.130695) (xy 266.885917 -432.953425)
			(xy 266.89387 -432.776334) (xy 266.909761 -432.599778) (xy 266.933556 -432.424113) (xy 266.965209 -432.249692)
			(xy 267.004655 -432.076867) (xy 267.051815 -431.905986) (xy 267.106594 -431.737392) (xy 267.168882 -431.571427)
			(xy 267.238554 -431.408422) (xy 267.315468 -431.248708) (xy 267.399471 -431.092605) (xy 267.490392 -430.940428)
			(xy 267.588049 -430.792484) (xy 267.692246 -430.64907) (xy 267.802772 -430.510475) (xy 267.919404 -430.376978)
			(xy 268.041909 -430.248849) (xy 268.170038 -430.126344) (xy 268.303535 -430.009712) (xy 268.44213 -429.899186)
			(xy 268.585544 -429.794989) (xy 268.733488 -429.697332) (xy 268.885665 -429.606411) (xy 269.041768 -429.522408)
			(xy 269.201482 -429.445494) (xy 269.364487 -429.375822) (xy 269.530452 -429.313534) (xy 269.699046 -429.258755)
			(xy 269.869927 -429.211595) (xy 270.042752 -429.172149) (xy 270.217173 -429.140496) (xy 270.392838 -429.116701)
			(xy 270.569394 -429.10081) (xy 270.746485 -429.092857) (xy 270.923755 -429.092857) (xy 271.100846 -429.10081)
			(xy 271.277402 -429.116701) (xy 271.453067 -429.140496) (xy 271.627488 -429.172149) (xy 271.800313 -429.211595)
			(xy 271.971194 -429.258755) (xy 272.139788 -429.313534) (xy 272.305753 -429.375822) (xy 272.468758 -429.445494)
			(xy 272.628472 -429.522408) (xy 272.784575 -429.606411) (xy 272.936752 -429.697332) (xy 273.084696 -429.794989)
			(xy 273.22811 -429.899186) (xy 273.366705 -430.009712) (xy 273.500202 -430.126344) (xy 273.628331 -430.248849)
			(xy 273.750836 -430.376978) (xy 273.867468 -430.510475) (xy 273.977994 -430.64907) (xy 274.082191 -430.792484)
			(xy 274.146507 -430.889918) (xy 314.138056 -430.889918) (xy 314.138165 -430.874832) (xy 314.139947 -430.844714)
			(xy 314.141612 -430.82972) (xy 314.141612 -429.749966) (xy 314.139947 -429.734972) (xy 314.138166 -429.704854)
			(xy 314.138056 -429.689768) (xy 314.13817 -429.674682) (xy 314.139948 -429.644564) (xy 314.141612 -429.62957)
			(xy 314.141612 -429.018954) (xy 314.142068 -429.006865) (xy 314.149534 -428.983867) (xy 314.163724 -428.964291)
			(xy 314.183258 -428.950041) (xy 314.206232 -428.942505) (xy 314.21832 -428.941992) (xy 315.15812 -428.941992)
			(xy 315.170229 -428.942399) (xy 315.193256 -428.949903) (xy 315.212828 -428.964167) (xy 315.227022 -428.98379)
			(xy 315.234444 -429.006843) (xy 315.234828 -429.018954) (xy 315.234828 -431.560478) (xy 315.234373 -431.57257)
			(xy 315.226919 -431.595575) (xy 315.21273 -431.615158) (xy 315.193192 -431.629408) (xy 315.17021 -431.636935)
			(xy 315.15812 -431.63744) (xy 314.21832 -431.63744) (xy 314.206216 -431.636967) (xy 314.183196 -431.629478)
			(xy 314.163627 -431.61523) (xy 314.14943 -431.595622) (xy 314.142001 -431.572583) (xy 314.141612 -431.560478)
			(xy 314.141612 -430.950116) (xy 314.139943 -430.935123) (xy 314.138165 -430.905004) (xy 314.138056 -430.889918)
			(xy 274.146507 -430.889918) (xy 274.179848 -430.940428) (xy 274.270769 -431.092605) (xy 274.354772 -431.248708)
			(xy 274.431686 -431.408422) (xy 274.501358 -431.571427) (xy 274.563646 -431.737392) (xy 274.613204 -431.889916)
			(xy 316.138052 -431.889916) (xy 316.138161 -431.87483) (xy 316.139943 -431.844712) (xy 316.141608 -431.829718)
			(xy 316.141608 -430.749964) (xy 316.139943 -430.73497) (xy 316.138162 -430.704852) (xy 316.138052 -430.689766)
			(xy 316.138166 -430.67468) (xy 316.139944 -430.644562) (xy 316.141608 -430.629568) (xy 316.141608 -430.018952)
			(xy 316.142023 -430.006873) (xy 316.149501 -429.983902) (xy 316.16371 -429.964364) (xy 316.183259 -429.950172)
			(xy 316.206237 -429.942713) (xy 316.218316 -429.942244) (xy 317.158116 -429.942244) (xy 317.170187 -429.94275)
			(xy 317.193146 -429.950211) (xy 317.212679 -429.964399) (xy 317.226874 -429.983925) (xy 317.234345 -430.006882)
			(xy 317.234824 -430.018952) (xy 317.234824 -430.889918) (xy 318.138048 -430.889918) (xy 318.138157 -430.874832)
			(xy 318.139939 -430.844714) (xy 318.141604 -430.82972) (xy 318.141604 -429.749966) (xy 318.139939 -429.734972)
			(xy 318.138158 -429.704854) (xy 318.138048 -429.689768) (xy 318.138162 -429.674682) (xy 318.13994 -429.644564)
			(xy 318.141604 -429.62957) (xy 318.141604 -429.018954) (xy 318.142067 -429.006866) (xy 318.149532 -428.98387)
			(xy 318.163721 -428.964293) (xy 318.183253 -428.950043) (xy 318.206225 -428.942506) (xy 318.218312 -428.941992)
			(xy 319.158112 -428.941992) (xy 319.170221 -428.942406) (xy 319.193247 -428.949908) (xy 319.212819 -428.96417)
			(xy 319.227014 -428.983792) (xy 319.234436 -429.006844) (xy 319.23482 -429.018954) (xy 319.23482 -431.560478)
			(xy 319.234373 -431.57257) (xy 319.226918 -431.595577) (xy 319.212727 -431.615161) (xy 319.193187 -431.629411)
			(xy 319.170203 -431.636936) (xy 319.158112 -431.63744) (xy 318.218312 -431.63744) (xy 318.206208 -431.636974)
			(xy 318.183188 -431.629483) (xy 318.163618 -431.615232) (xy 318.149422 -431.595624) (xy 318.141993 -431.572583)
			(xy 318.141604 -431.560478) (xy 318.141604 -430.950116) (xy 318.139935 -430.935123) (xy 318.138157 -430.905004)
			(xy 318.138048 -430.889918) (xy 317.234824 -430.889918) (xy 317.234824 -431.889916) (xy 320.138044 -431.889916)
			(xy 320.138153 -431.87483) (xy 320.139935 -431.844712) (xy 320.1416 -431.829718) (xy 320.1416 -430.749964)
			(xy 320.139935 -430.73497) (xy 320.138154 -430.704852) (xy 320.138044 -430.689766) (xy 320.138158 -430.67468)
			(xy 320.139936 -430.644562) (xy 320.1416 -430.629568) (xy 320.1416 -430.018952) (xy 320.142023 -430.006874)
			(xy 320.1495 -429.983904) (xy 320.163707 -429.964367) (xy 320.183254 -429.950174) (xy 320.20623 -429.942714)
			(xy 320.218308 -429.942244) (xy 321.158108 -429.942244) (xy 321.170178 -429.942757) (xy 321.193137 -429.950216)
			(xy 321.21267 -429.964401) (xy 321.226866 -429.983927) (xy 321.234337 -430.006882) (xy 321.234816 -430.018952)
			(xy 321.234816 -430.889918) (xy 322.13804 -430.889918) (xy 322.138151 -430.874832) (xy 322.139933 -430.844714)
			(xy 322.141596 -430.82972) (xy 322.141596 -429.749966) (xy 322.139931 -429.734972) (xy 322.13815 -429.704854)
			(xy 322.13804 -429.689768) (xy 322.138154 -429.674682) (xy 322.139932 -429.644564) (xy 322.141596 -429.62957)
			(xy 322.141596 -429.018954) (xy 322.142067 -429.006866) (xy 322.149531 -428.983872) (xy 322.163718 -428.964296)
			(xy 322.183248 -428.950046) (xy 322.206218 -428.942507) (xy 322.218304 -428.941992) (xy 323.158104 -428.941992)
			(xy 323.170212 -428.942413) (xy 323.193238 -428.949912) (xy 323.212811 -428.964173) (xy 323.227006 -428.983793)
			(xy 323.234428 -429.006844) (xy 323.234812 -429.018954) (xy 323.234812 -431.560478) (xy 323.234373 -431.572571)
			(xy 323.226916 -431.595579) (xy 323.212724 -431.615164) (xy 323.193182 -431.629413) (xy 323.170196 -431.636937)
			(xy 323.158104 -431.63744) (xy 322.218304 -431.63744) (xy 322.206199 -431.636981) (xy 322.183179 -431.629488)
			(xy 322.163609 -431.615236) (xy 322.149413 -431.595625) (xy 322.141985 -431.572584) (xy 322.141596 -431.560478)
			(xy 322.141596 -430.950116) (xy 322.139927 -430.935123) (xy 322.138149 -430.905004) (xy 322.13804 -430.889918)
			(xy 321.234816 -430.889918) (xy 321.234816 -431.889916) (xy 324.138036 -431.889916) (xy 324.138147 -431.87483)
			(xy 324.139929 -431.844712) (xy 324.141592 -431.829718) (xy 324.141592 -430.749964) (xy 324.139927 -430.73497)
			(xy 324.138146 -430.704852) (xy 324.138036 -430.689766) (xy 324.138152 -430.674681) (xy 324.13993 -430.644562)
			(xy 324.141592 -430.629568) (xy 324.141592 -430.018952) (xy 324.142023 -430.006875) (xy 324.149499 -429.983906)
			(xy 324.163704 -429.96437) (xy 324.183249 -429.950177) (xy 324.206223 -429.942716) (xy 324.2183 -429.942244)
			(xy 325.1581 -429.942244) (xy 325.17017 -429.942764) (xy 325.193129 -429.95022) (xy 325.212662 -429.964404)
			(xy 325.226858 -429.983928) (xy 325.234329 -430.006883) (xy 325.234808 -430.018952) (xy 325.234808 -430.889918)
			(xy 326.138032 -430.889918) (xy 326.138143 -430.874832) (xy 326.139925 -430.844714) (xy 326.141588 -430.82972)
			(xy 326.141588 -429.749966) (xy 326.139923 -429.734972) (xy 326.138142 -429.704854) (xy 326.138032 -429.689768)
			(xy 326.138148 -429.674683) (xy 326.139926 -429.644564) (xy 326.141588 -429.62957) (xy 326.141588 -429.018954)
			(xy 326.141969 -429.006857) (xy 326.149444 -428.983847) (xy 326.163651 -428.964264) (xy 326.183205 -428.950016)
			(xy 326.2062 -428.942494) (xy 326.218296 -428.941992) (xy 327.158096 -428.941992) (xy 327.170204 -428.942419)
			(xy 327.19323 -428.949917) (xy 327.212802 -428.964176) (xy 327.226997 -428.983795) (xy 327.23442 -429.006845)
			(xy 327.234804 -429.018954) (xy 327.234804 -431.560478) (xy 327.234275 -431.572562) (xy 327.226829 -431.595555)
			(xy 327.212657 -431.615131) (xy 327.19314 -431.629384) (xy 327.170178 -431.636924) (xy 327.158096 -431.63744)
			(xy 326.218296 -431.63744) (xy 326.206191 -431.636988) (xy 326.18317 -431.629492) (xy 326.163601 -431.615238)
			(xy 326.149405 -431.595627) (xy 326.141977 -431.572584) (xy 326.141588 -431.560478) (xy 326.141588 -430.950116)
			(xy 326.139919 -430.935123) (xy 326.138141 -430.905004) (xy 326.138032 -430.889918) (xy 325.234808 -430.889918)
			(xy 325.234808 -431.889916) (xy 328.138028 -431.889916) (xy 328.138139 -431.87483) (xy 328.139921 -431.844712)
			(xy 328.141584 -431.829718) (xy 328.141584 -430.749964) (xy 328.139919 -430.73497) (xy 328.138138 -430.704852)
			(xy 328.138028 -430.689766) (xy 328.138144 -430.674681) (xy 328.139922 -430.644562) (xy 328.141584 -430.629568)
			(xy 328.141584 -430.018952) (xy 328.142023 -430.006876) (xy 328.149498 -429.983908) (xy 328.163701 -429.964373)
			(xy 328.183244 -429.95018) (xy 328.206215 -429.942717) (xy 328.218292 -429.942244) (xy 329.158092 -429.942244)
			(xy 329.170161 -429.94277) (xy 329.19312 -429.950225) (xy 329.212653 -429.964407) (xy 329.22685 -429.98393)
			(xy 329.234321 -430.006883) (xy 329.2348 -430.018952) (xy 329.2348 -430.889918) (xy 331.138022 -430.889918)
			(xy 331.138116 -430.875344) (xy 331.139768 -430.846243) (xy 331.141324 -430.831752) (xy 331.141324 -429.747934)
			(xy 331.139776 -429.733442) (xy 331.138126 -429.704342) (xy 331.138022 -429.689768) (xy 331.138121 -429.675194)
			(xy 331.13977 -429.646093) (xy 331.141324 -429.631602) (xy 331.141324 -429.018954) (xy 331.141772 -429.006838)
			(xy 331.14927 -428.983796) (xy 331.163519 -428.964196) (xy 331.183125 -428.949956) (xy 331.20617 -428.942467)
			(xy 331.218286 -428.941992) (xy 332.158086 -428.941992) (xy 332.170195 -428.942523) (xy 332.19323 -428.950001)
			(xy 332.212828 -428.964229) (xy 332.227072 -428.983816) (xy 332.234568 -429.006845) (xy 332.235048 -429.018954)
			(xy 332.235048 -431.560478) (xy 332.234621 -431.572601) (xy 332.227133 -431.595662) (xy 332.212884 -431.615278)
			(xy 332.193269 -431.62953) (xy 332.170209 -431.63702) (xy 332.158086 -431.63744) (xy 331.218286 -431.63744)
			(xy 331.20616 -431.637051) (xy 331.183097 -431.629553) (xy 331.163481 -431.615294) (xy 331.149231 -431.59567)
			(xy 331.141743 -431.572604) (xy 331.141324 -431.560478) (xy 331.141324 -430.948084) (xy 331.139781 -430.933592)
			(xy 331.138128 -430.904492) (xy 331.138022 -430.889918) (xy 329.2348 -430.889918) (xy 329.2348 -431.889916)
			(xy 333.138018 -431.889916) (xy 333.138112 -431.875342) (xy 333.139764 -431.846241) (xy 333.14132 -431.83175)
			(xy 333.14132 -430.747932) (xy 333.139772 -430.73344) (xy 333.138122 -430.70434) (xy 333.138018 -430.689766)
			(xy 333.138117 -430.675192) (xy 333.139766 -430.646091) (xy 333.14132 -430.6316) (xy 333.14132 -430.018952)
			(xy 333.141676 -430.006839) (xy 333.149191 -429.983806) (xy 333.163467 -429.964232) (xy 333.183103 -429.95004)
			(xy 333.206167 -429.942624) (xy 333.218282 -429.942244) (xy 334.158082 -429.942244) (xy 334.170171 -429.942723)
			(xy 334.193172 -429.950175) (xy 334.212752 -429.964358) (xy 334.227003 -429.98389) (xy 334.234535 -430.006865)
			(xy 334.235044 -430.018952) (xy 334.235044 -430.889918) (xy 335.138014 -430.889918) (xy 335.138108 -430.875344)
			(xy 335.13976 -430.846243) (xy 335.141316 -430.831752) (xy 335.141316 -429.747934) (xy 335.139768 -429.733442)
			(xy 335.138118 -429.704342) (xy 335.138014 -429.689768) (xy 335.138112 -429.675194) (xy 335.139762 -429.646093)
			(xy 335.141316 -429.631602) (xy 335.141316 -429.018954) (xy 335.141772 -429.006839) (xy 335.149269 -428.983798)
			(xy 335.163516 -428.964199) (xy 335.18312 -428.949958) (xy 335.206163 -428.942468) (xy 335.218278 -428.941992)
			(xy 336.158078 -428.941992) (xy 336.170187 -428.94253) (xy 336.193222 -428.950005) (xy 336.21282 -428.964232)
			(xy 336.227064 -428.983817) (xy 336.234559 -429.006846) (xy 336.23504 -429.018954) (xy 336.23504 -431.560478)
			(xy 336.234621 -431.572602) (xy 336.227132 -431.595664) (xy 336.212881 -431.615281) (xy 336.193264 -431.629532)
			(xy 336.170202 -431.637021) (xy 336.158078 -431.63744) (xy 335.218278 -431.63744) (xy 335.20616 -431.637007)
			(xy 335.183112 -431.629511) (xy 335.163509 -431.61526) (xy 335.149269 -431.595648) (xy 335.141786 -431.572596)
			(xy 335.141316 -431.560478) (xy 335.141316 -430.948084) (xy 335.139773 -430.933592) (xy 335.13812 -430.904492)
			(xy 335.138014 -430.889918) (xy 334.235044 -430.889918) (xy 334.235044 -431.889916) (xy 337.13801 -431.889916)
			(xy 337.138104 -431.875342) (xy 337.139756 -431.846241) (xy 337.141312 -431.83175) (xy 337.141312 -430.747932)
			(xy 337.139764 -430.73344) (xy 337.138114 -430.70434) (xy 337.13801 -430.689766) (xy 337.138108 -430.675192)
			(xy 337.139757 -430.646091) (xy 337.141312 -430.6316) (xy 337.141312 -430.018952) (xy 337.141676 -430.006839)
			(xy 337.14919 -429.983809) (xy 337.163465 -429.964235) (xy 337.183098 -429.950043) (xy 337.20616 -429.942625)
			(xy 337.218274 -429.942244) (xy 338.158074 -429.942244) (xy 338.170163 -429.94273) (xy 338.193163 -429.95018)
			(xy 338.212744 -429.964361) (xy 338.226995 -429.983891) (xy 338.234527 -430.006865) (xy 338.235036 -430.018952)
			(xy 338.235036 -430.889918) (xy 339.138006 -430.889918) (xy 339.1381 -430.875344) (xy 339.139752 -430.846243)
			(xy 339.141308 -430.831752) (xy 339.141308 -429.747934) (xy 339.13976 -429.733442) (xy 339.13811 -429.704342)
			(xy 339.138006 -429.689768) (xy 339.138104 -429.675194) (xy 339.139754 -429.646093) (xy 339.141308 -429.631602)
			(xy 339.141308 -429.018954) (xy 339.141772 -429.00684) (xy 339.149268 -428.9838) (xy 339.163513 -428.964202)
			(xy 339.183115 -428.949961) (xy 339.206156 -428.94247) (xy 339.21827 -428.941992) (xy 340.15807 -428.941992)
			(xy 340.170178 -428.942537) (xy 340.193213 -428.95001) (xy 340.212811 -428.964235) (xy 340.227055 -428.983819)
			(xy 340.234551 -429.006846) (xy 340.235032 -429.018954) (xy 340.235032 -431.560478) (xy 340.234621 -431.572603)
			(xy 340.227131 -431.595666) (xy 340.212878 -431.615284) (xy 340.193259 -431.629535) (xy 340.170195 -431.637022)
			(xy 340.15807 -431.63744) (xy 339.21827 -431.63744) (xy 339.206152 -431.637014) (xy 339.183104 -431.629515)
			(xy 339.163501 -431.615262) (xy 339.149261 -431.59565) (xy 339.141778 -431.572597) (xy 339.141308 -431.560478)
			(xy 339.141308 -430.948084) (xy 339.139764 -430.933592) (xy 339.138112 -430.904492) (xy 339.138006 -430.889918)
			(xy 338.235036 -430.889918) (xy 338.235036 -431.889916) (xy 341.138002 -431.889916) (xy 341.138096 -431.875342)
			(xy 341.139748 -431.846241) (xy 341.141304 -431.83175) (xy 341.141304 -430.747932) (xy 341.139756 -430.73344)
			(xy 341.138106 -430.70434) (xy 341.138002 -430.689766) (xy 341.1381 -430.675192) (xy 341.13975 -430.646091)
			(xy 341.141304 -430.6316) (xy 341.141304 -430.018952) (xy 341.141676 -430.00684) (xy 341.149189 -429.983811)
			(xy 341.163462 -429.964238) (xy 341.183093 -429.950045) (xy 341.206153 -429.942626) (xy 341.218266 -429.942244)
			(xy 342.158066 -429.942244) (xy 342.170154 -429.942736) (xy 342.193154 -429.950184) (xy 342.212735 -429.964364)
			(xy 342.226987 -429.983893) (xy 342.234519 -430.006866) (xy 342.235028 -430.018952) (xy 342.235028 -430.889918)
			(xy 343.137998 -430.889918) (xy 343.138092 -430.875344) (xy 343.139744 -430.846243) (xy 343.1413 -430.831752)
			(xy 343.1413 -429.747934) (xy 343.139752 -429.733442) (xy 343.138102 -429.704342) (xy 343.137998 -429.689768)
			(xy 343.138096 -429.675194) (xy 343.139746 -429.646093) (xy 343.1413 -429.631602) (xy 343.1413 -429.018954)
			(xy 343.141772 -429.006841) (xy 343.149267 -428.983803) (xy 343.163511 -428.964205) (xy 343.18311 -428.949964)
			(xy 343.206149 -428.942471) (xy 343.218262 -428.941992) (xy 344.158062 -428.941992) (xy 344.17017 -428.942543)
			(xy 344.193204 -428.950015) (xy 344.212803 -428.964238) (xy 344.227047 -428.98382) (xy 344.234543 -429.006847)
			(xy 344.235024 -429.018954) (xy 344.235024 -431.560478) (xy 344.234621 -431.572603) (xy 344.22713 -431.595668)
			(xy 344.212875 -431.615287) (xy 344.193254 -431.629537) (xy 344.170187 -431.637023) (xy 344.158062 -431.63744)
			(xy 343.218262 -431.63744) (xy 343.206143 -431.63702) (xy 343.183095 -431.62952) (xy 343.163492 -431.615265)
			(xy 343.149253 -431.595651) (xy 343.14177 -431.572597) (xy 343.1413 -431.560478) (xy 343.1413 -430.948084)
			(xy 343.139756 -430.933592) (xy 343.138104 -430.904492) (xy 343.137998 -430.889918) (xy 342.235028 -430.889918)
			(xy 342.235028 -431.889916) (xy 345.137994 -431.889916) (xy 345.138088 -431.875342) (xy 345.13974 -431.846241)
			(xy 345.141296 -431.83175) (xy 345.141296 -430.747932) (xy 345.139748 -430.73344) (xy 345.138098 -430.70434)
			(xy 345.137994 -430.689766) (xy 345.138092 -430.675192) (xy 345.139742 -430.646091) (xy 345.141296 -430.6316)
			(xy 345.141296 -430.018952) (xy 345.141676 -430.006841) (xy 345.149188 -429.983813) (xy 345.163459 -429.964241)
			(xy 345.183088 -429.950048) (xy 345.206145 -429.942628) (xy 345.218258 -429.942244) (xy 346.158058 -429.942244)
			(xy 346.170146 -429.942743) (xy 346.193146 -429.950189) (xy 346.212727 -429.964367) (xy 346.226979 -429.983894)
			(xy 346.234511 -430.006866) (xy 346.23502 -430.018952) (xy 346.23502 -431.359818) (xy 356.154736 -431.359818)
			(xy 356.155234 -431.274938) (xy 356.163191 -431.105365) (xy 356.179087 -430.936351) (xy 356.202888 -430.768268)
			(xy 356.234542 -430.601485) (xy 356.273978 -430.436369) (xy 356.32111 -430.273284) (xy 356.375834 -430.112586)
			(xy 356.438031 -429.954631) (xy 356.507563 -429.799764) (xy 356.584278 -429.648327) (xy 356.668006 -429.500651)
			(xy 356.758564 -429.357063) (xy 356.855753 -429.217877) (xy 356.95936 -429.0834) (xy 357.069155 -428.953927)
			(xy 357.184899 -428.829742) (xy 357.306336 -428.711119) (xy 357.4332 -428.598318) (xy 357.565211 -428.491588)
			(xy 357.702081 -428.391163) (xy 357.843506 -428.297264) (xy 357.989178 -428.210096) (xy 358.138776 -428.129853)
			(xy 358.29197 -428.056709) (xy 358.448424 -427.990827) (xy 358.607794 -427.93235) (xy 358.76973 -427.881408)
			(xy 358.933876 -427.838112) (xy 359.099871 -427.802557) (xy 359.26735 -427.774822) (xy 359.435945 -427.754968)
			(xy 359.605285 -427.743038) (xy 359.774998 -427.739059) (xy 359.944711 -427.743038) (xy 360.114051 -427.754968)
			(xy 360.282646 -427.774822) (xy 360.450125 -427.802557) (xy 360.61612 -427.838112) (xy 360.780266 -427.881408)
			(xy 360.942202 -427.93235) (xy 361.101572 -427.990827) (xy 361.258026 -428.056709) (xy 361.41122 -428.129853)
			(xy 361.560818 -428.210096) (xy 361.693883 -428.28972) (xy 383.237994 -428.28972) (xy 383.238088 -428.275146)
			(xy 383.23974 -428.246045) (xy 383.241296 -428.231554) (xy 383.241296 -427.14799) (xy 383.239753 -427.133498)
			(xy 383.2381 -427.104398) (xy 383.237994 -427.089824) (xy 383.238088 -427.07525) (xy 383.23974 -427.046149)
			(xy 383.241296 -427.031658) (xy 383.241296 -426.41901) (xy 383.24182 -426.4069) (xy 383.249299 -426.383864)
			(xy 383.263529 -426.364266) (xy 383.283118 -426.350023) (xy 383.306148 -426.342528) (xy 383.318258 -426.342048)
			(xy 384.258058 -426.342048) (xy 384.27018 -426.342496) (xy 384.293239 -426.349978) (xy 384.312855 -426.364222)
			(xy 384.327108 -426.383833) (xy 384.334599 -426.406889) (xy 384.33502 -426.41901) (xy 384.33502 -427.289976)
			(xy 385.23799 -427.289976) (xy 385.23808 -427.275402) (xy 385.239735 -427.246301) (xy 385.241292 -427.23181)
			(xy 385.241292 -426.147992) (xy 385.239749 -426.1335) (xy 385.238096 -426.1044) (xy 385.23799 -426.089826)
			(xy 385.238085 -426.075252) (xy 385.239736 -426.046151) (xy 385.241292 -426.03166) (xy 385.241292 -425.419012)
			(xy 385.241727 -425.406905) (xy 385.249222 -425.383879) (xy 385.263479 -425.364307) (xy 385.283096 -425.350111)
			(xy 385.306145 -425.342689) (xy 385.318254 -425.342304) (xy 386.258054 -425.342304) (xy 386.270138 -425.342846)
			(xy 386.293131 -425.350286) (xy 386.312708 -425.364454) (xy 386.326962 -425.38397) (xy 386.334501 -425.40693)
			(xy 386.335016 -425.419012) (xy 386.335016 -427.960536) (xy 386.334615 -427.972645) (xy 386.327107 -427.995671)
			(xy 386.312841 -428.015242) (xy 386.293218 -428.029436) (xy 386.270165 -428.036859) (xy 386.258054 -428.037244)
			(xy 385.318254 -428.037244) (xy 385.30616 -428.036832) (xy 385.283156 -428.02936) (xy 385.263575 -428.01516)
			(xy 385.249327 -427.995615) (xy 385.241799 -427.972628) (xy 385.241292 -427.960536) (xy 385.241292 -427.348142)
			(xy 385.239745 -427.33365) (xy 385.238095 -427.30455) (xy 385.23799 -427.289976) (xy 384.33502 -427.289976)
			(xy 384.33502 -428.28972) (xy 387.237986 -428.28972) (xy 387.23808 -428.275146) (xy 387.239732 -428.246045)
			(xy 387.241288 -428.231554) (xy 387.241288 -427.14799) (xy 387.239745 -427.133498) (xy 387.238092 -427.104398)
			(xy 387.237986 -427.089824) (xy 387.238081 -427.07525) (xy 387.239732 -427.046149) (xy 387.241288 -427.031658)
			(xy 387.241288 -426.41901) (xy 387.24182 -426.406901) (xy 387.249298 -426.383867) (xy 387.263526 -426.364269)
			(xy 387.283113 -426.350025) (xy 387.306141 -426.342529) (xy 387.31825 -426.342048) (xy 388.25805 -426.342048)
			(xy 388.270168 -426.342469) (xy 388.293215 -426.349972) (xy 388.312816 -426.364226) (xy 388.327056 -426.383839)
			(xy 388.33454 -426.406891) (xy 388.335012 -426.41901) (xy 388.335012 -427.289976) (xy 389.237982 -427.289976)
			(xy 389.238072 -427.275402) (xy 389.239727 -427.246301) (xy 389.241284 -427.23181) (xy 389.241284 -426.147992)
			(xy 389.239741 -426.1335) (xy 389.238088 -426.1044) (xy 389.237982 -426.089826) (xy 389.238077 -426.075252)
			(xy 389.239728 -426.046151) (xy 389.241284 -426.03166) (xy 389.241284 -425.419012) (xy 389.241727 -425.406905)
			(xy 389.249221 -425.383881) (xy 389.263476 -425.364309) (xy 389.283091 -425.350114) (xy 389.306138 -425.34269)
			(xy 389.318246 -425.342304) (xy 390.258046 -425.342304) (xy 390.270134 -425.342767) (xy 390.29313 -425.350232)
			(xy 390.312707 -425.364421) (xy 390.326957 -425.383953) (xy 390.334494 -425.406925) (xy 390.335008 -425.419012)
			(xy 390.335008 -427.960536) (xy 390.334614 -427.972646) (xy 390.327106 -427.995673) (xy 390.312838 -428.015245)
			(xy 390.293213 -428.029438) (xy 390.270157 -428.03686) (xy 390.258046 -428.037244) (xy 389.318246 -428.037244)
			(xy 389.306157 -428.036753) (xy 389.283155 -428.029307) (xy 389.263573 -428.015127) (xy 389.249322 -427.995597)
			(xy 389.241791 -427.972623) (xy 389.241284 -427.960536) (xy 389.241284 -427.348142) (xy 389.239737 -427.33365)
			(xy 389.238087 -427.30455) (xy 389.237982 -427.289976) (xy 388.335012 -427.289976) (xy 388.335012 -428.28972)
			(xy 391.237978 -428.28972) (xy 391.238072 -428.275146) (xy 391.239724 -428.246045) (xy 391.24128 -428.231554)
			(xy 391.24128 -427.14799) (xy 391.239737 -427.133498) (xy 391.238084 -427.104398) (xy 391.237978 -427.089824)
			(xy 391.238073 -427.07525) (xy 391.239724 -427.046149) (xy 391.24128 -427.031658) (xy 391.24128 -426.41901)
			(xy 391.241669 -426.406884) (xy 391.249164 -426.383818) (xy 391.263422 -426.364199) (xy 391.283047 -426.349949)
			(xy 391.306115 -426.342464) (xy 391.318242 -426.342048) (xy 392.258042 -426.342048) (xy 392.27016 -426.342476)
			(xy 392.293206 -426.349976) (xy 392.312808 -426.364229) (xy 392.327048 -426.383841) (xy 392.334532 -426.406892)
			(xy 392.335004 -426.41901) (xy 392.335004 -427.289976) (xy 393.237974 -427.289976) (xy 393.238064 -427.275402)
			(xy 393.239719 -427.246301) (xy 393.241276 -427.23181) (xy 393.241276 -426.147992) (xy 393.239733 -426.1335)
			(xy 393.23808 -426.1044) (xy 393.237974 -426.089826) (xy 393.238069 -426.075252) (xy 393.23972 -426.046151)
			(xy 393.241276 -426.03166) (xy 393.241276 -425.419012) (xy 393.241726 -425.406906) (xy 393.24922 -425.383883)
			(xy 393.263473 -425.364312) (xy 393.283086 -425.350116) (xy 393.306131 -425.342691) (xy 393.318238 -425.342304)
			(xy 394.258038 -425.342304) (xy 394.270126 -425.342774) (xy 394.293122 -425.350237) (xy 394.312698 -425.364424)
			(xy 394.326949 -425.383954) (xy 394.334486 -425.406926) (xy 394.335 -425.419012) (xy 394.335 -427.960536)
			(xy 394.334614 -427.972647) (xy 394.327105 -427.995675) (xy 394.312835 -428.015248) (xy 394.293208 -428.029441)
			(xy 394.27015 -428.036861) (xy 394.258038 -428.037244) (xy 393.318238 -428.037244) (xy 393.306149 -428.03676)
			(xy 393.283147 -428.029312) (xy 393.263565 -428.01513) (xy 393.249314 -427.995599) (xy 393.241783 -427.972623)
			(xy 393.241276 -427.960536) (xy 393.241276 -427.348142) (xy 393.239729 -427.33365) (xy 393.238079 -427.30455)
			(xy 393.237974 -427.289976) (xy 392.335004 -427.289976) (xy 392.335004 -428.28972) (xy 395.23797 -428.28972)
			(xy 395.238064 -428.275146) (xy 395.239716 -428.246045) (xy 395.241272 -428.231554) (xy 395.241272 -427.14799)
			(xy 395.239729 -427.133498) (xy 395.238076 -427.104398) (xy 395.23797 -427.089824) (xy 395.238065 -427.07525)
			(xy 395.239716 -427.046149) (xy 395.241272 -427.031658) (xy 395.241272 -426.41901) (xy 395.241669 -426.406884)
			(xy 395.249163 -426.38382) (xy 395.263419 -426.364202) (xy 395.283042 -426.349952) (xy 395.306108 -426.342465)
			(xy 395.318234 -426.342048) (xy 396.258034 -426.342048) (xy 396.270151 -426.342483) (xy 396.293197 -426.349981)
			(xy 396.312799 -426.364232) (xy 396.327039 -426.383842) (xy 396.334524 -426.406892) (xy 396.334996 -426.41901)
			(xy 396.334996 -427.289976) (xy 398.237964 -427.289976) (xy 398.238078 -427.274891) (xy 398.239856 -427.244772)
			(xy 398.24152 -427.229778) (xy 398.24152 -426.150024) (xy 398.239851 -426.135031) (xy 398.238073 -426.104912)
			(xy 398.237964 -426.089826) (xy 398.238074 -426.07474) (xy 398.239855 -426.044622) (xy 398.24152 -426.029628)
			(xy 398.24152 -425.419012) (xy 398.241924 -425.406927) (xy 398.249391 -425.38394) (xy 398.263599 -425.364387)
			(xy 398.283154 -425.350184) (xy 398.306143 -425.342721) (xy 398.318228 -425.342304) (xy 399.258028 -425.342304)
			(xy 399.270105 -425.34274) (xy 399.293075 -425.350212) (xy 399.312613 -425.364415) (xy 399.326806 -425.38396)
			(xy 399.334266 -425.406935) (xy 399.334736 -425.419012) (xy 399.334736 -427.960536) (xy 399.334267 -427.97261)
			(xy 399.326798 -427.995573) (xy 399.312602 -428.015107) (xy 399.293066 -428.029302) (xy 399.270102 -428.036768)
			(xy 399.258028 -428.037244) (xy 398.318228 -428.037244) (xy 398.306158 -428.036713) (xy 398.283198 -428.029262)
			(xy 398.263664 -428.015082) (xy 398.249467 -427.995559) (xy 398.241997 -427.972605) (xy 398.24152 -427.960536)
			(xy 398.24152 -427.350174) (xy 398.239856 -427.33518) (xy 398.238074 -427.305062) (xy 398.237964 -427.289976)
			(xy 396.334996 -427.289976) (xy 396.334996 -428.28972) (xy 400.23796 -428.28972) (xy 400.238069 -428.274634)
			(xy 400.239851 -428.244516) (xy 400.241516 -428.229522) (xy 400.241516 -427.150022) (xy 400.239847 -427.135029)
			(xy 400.238069 -427.10491) (xy 400.23796 -427.089824) (xy 400.23807 -427.074738) (xy 400.239851 -427.04462)
			(xy 400.241516 -427.029626) (xy 400.241516 -426.41901) (xy 400.242016 -426.406923) (xy 400.249467 -426.383927)
			(xy 400.263646 -426.364349) (xy 400.283171 -426.350097) (xy 400.306139 -426.342561) (xy 400.318224 -426.342048)
			(xy 401.258024 -426.342048) (xy 401.270129 -426.342495) (xy 401.293148 -426.349995) (xy 401.312716 -426.36425)
			(xy 401.326912 -426.383862) (xy 401.334341 -426.406904) (xy 401.334732 -426.41901) (xy 401.334732 -427.289976)
			(xy 402.237956 -427.289976) (xy 402.23807 -427.274891) (xy 402.239848 -427.244772) (xy 402.241512 -427.229778)
			(xy 402.241512 -426.150024) (xy 402.239843 -426.135031) (xy 402.238065 -426.104912) (xy 402.237956 -426.089826)
			(xy 402.238066 -426.07474) (xy 402.239847 -426.044622) (xy 402.241512 -426.029628) (xy 402.241512 -425.419012)
			(xy 402.241923 -425.406928) (xy 402.24939 -425.383942) (xy 402.263596 -425.36439) (xy 402.283149 -425.350186)
			(xy 402.306136 -425.342722) (xy 402.31822 -425.342304) (xy 403.25802 -425.342304) (xy 403.270097 -425.342748)
			(xy 403.293067 -425.350217) (xy 403.312604 -425.364419) (xy 403.326798 -425.383962) (xy 403.334257 -425.406935)
			(xy 403.334728 -425.419012) (xy 403.334728 -427.960536) (xy 403.334267 -427.97261) (xy 403.326797 -427.995576)
			(xy 403.312599 -428.01511) (xy 403.293061 -428.029304) (xy 403.270095 -428.036769) (xy 403.25802 -428.037244)
			(xy 402.31822 -428.037244) (xy 402.30615 -428.036719) (xy 402.28319 -428.029267) (xy 402.263655 -428.015085)
			(xy 402.249459 -427.995561) (xy 402.241989 -427.972606) (xy 402.241512 -427.960536) (xy 402.241512 -427.350174)
			(xy 402.239848 -427.33518) (xy 402.238066 -427.305062) (xy 402.237956 -427.289976) (xy 401.334732 -427.289976)
			(xy 401.334732 -428.28972) (xy 404.237952 -428.28972) (xy 404.238062 -428.274634) (xy 404.239843 -428.244516)
			(xy 404.241508 -428.229522) (xy 404.241508 -427.150022) (xy 404.239839 -427.135029) (xy 404.238061 -427.10491)
			(xy 404.237952 -427.089824) (xy 404.238062 -427.074738) (xy 404.239843 -427.04462) (xy 404.241508 -427.029626)
			(xy 404.241508 -426.41901) (xy 404.242015 -426.406924) (xy 404.249465 -426.383929) (xy 404.263643 -426.364352)
			(xy 404.283166 -426.3501) (xy 404.306132 -426.342562) (xy 404.318216 -426.342048) (xy 405.258016 -426.342048)
			(xy 405.270121 -426.342502) (xy 405.293139 -426.349999) (xy 405.312708 -426.364253) (xy 405.326904 -426.383863)
			(xy 405.334333 -426.406904) (xy 405.334724 -426.41901) (xy 405.334724 -427.289976) (xy 406.237948 -427.289976)
			(xy 406.238062 -427.274891) (xy 406.23984 -427.244772) (xy 406.241504 -427.229778) (xy 406.241504 -426.150024)
			(xy 406.239835 -426.135031) (xy 406.238057 -426.104912) (xy 406.237948 -426.089826) (xy 406.238058 -426.07474)
			(xy 406.239839 -426.044622) (xy 406.241504 -426.029628) (xy 406.241504 -425.419012) (xy 406.241923 -425.406929)
			(xy 406.249389 -425.383944) (xy 406.263593 -425.364393) (xy 406.283144 -425.350189) (xy 406.306129 -425.342723)
			(xy 406.318212 -425.342304) (xy 407.258012 -425.342304) (xy 407.270088 -425.342754) (xy 407.293058 -425.350222)
			(xy 407.312596 -425.364421) (xy 407.326789 -425.383964) (xy 407.334249 -425.406935) (xy 407.33472 -425.419012)
			(xy 407.33472 -427.960536) (xy 407.334267 -427.972611) (xy 407.326796 -427.995578) (xy 407.312596 -428.015113)
			(xy 407.293056 -428.029307) (xy 407.270087 -428.036771) (xy 407.258012 -428.037244) (xy 406.318212 -428.037244)
			(xy 406.306142 -428.036726) (xy 406.283181 -428.029271) (xy 406.263647 -428.015087) (xy 406.249451 -427.995562)
			(xy 406.241981 -427.972606) (xy 406.241504 -427.960536) (xy 406.241504 -427.350174) (xy 406.23984 -427.33518)
			(xy 406.238058 -427.305062) (xy 406.237948 -427.289976) (xy 405.334724 -427.289976) (xy 405.334724 -428.28972)
			(xy 408.237944 -428.28972) (xy 408.238054 -428.274634) (xy 408.239835 -428.244516) (xy 408.2415 -428.229522)
			(xy 408.2415 -427.150022) (xy 408.239831 -427.135029) (xy 408.238053 -427.10491) (xy 408.237944 -427.089824)
			(xy 408.238054 -427.074738) (xy 408.239835 -427.04462) (xy 408.2415 -427.029626) (xy 408.2415 -426.41901)
			(xy 408.242015 -426.406925) (xy 408.249464 -426.383931) (xy 408.26364 -426.364355) (xy 408.283161 -426.350103)
			(xy 408.306125 -426.342563) (xy 408.318208 -426.342048) (xy 409.258008 -426.342048) (xy 409.270112 -426.342509)
			(xy 409.293131 -426.350004) (xy 409.312699 -426.364256) (xy 409.326896 -426.383865) (xy 409.334325 -426.406905)
			(xy 409.334716 -426.41901) (xy 409.334716 -427.289976) (xy 410.23794 -427.289976) (xy 410.238055 -427.274891)
			(xy 410.239832 -427.244772) (xy 410.241496 -427.229778) (xy 410.241496 -426.150024) (xy 410.239827 -426.135031)
			(xy 410.238049 -426.104912) (xy 410.23794 -426.089826) (xy 410.23805 -426.07474) (xy 410.239831 -426.044622)
			(xy 410.241496 -426.029628) (xy 410.241496 -425.419012) (xy 410.241923 -425.40693) (xy 410.249388 -425.383947)
			(xy 410.26359 -425.364396) (xy 410.283139 -425.350191) (xy 410.306122 -425.342724) (xy 410.318204 -425.342304)
			(xy 411.258004 -425.342304) (xy 411.270088 -425.342709) (xy 411.293073 -425.350179) (xy 411.312624 -425.364387)
			(xy 411.326828 -425.383941) (xy 411.334293 -425.406928) (xy 411.334712 -425.419012) (xy 411.334712 -427.960536)
			(xy 411.334267 -427.972612) (xy 411.326795 -427.99558) (xy 411.312593 -428.015116) (xy 411.293051 -428.029309)
			(xy 411.27008 -428.036772) (xy 411.258004 -428.037244) (xy 410.318204 -428.037244) (xy 410.306133 -428.036733)
			(xy 410.283172 -428.029276) (xy 410.263638 -428.01509) (xy 410.249442 -427.995564) (xy 410.241973 -427.972607)
			(xy 410.241496 -427.960536) (xy 410.241496 -427.350174) (xy 410.239832 -427.33518) (xy 410.23805 -427.305062)
			(xy 410.23794 -427.289976) (xy 409.334716 -427.289976) (xy 409.334716 -428.28972) (xy 412.237936 -428.28972)
			(xy 412.238048 -428.274634) (xy 412.239829 -428.244516) (xy 412.241492 -428.229522) (xy 412.241492 -427.150022)
			(xy 412.239823 -427.135029) (xy 412.238045 -427.10491) (xy 412.237936 -427.089824) (xy 412.238048 -427.074738)
			(xy 412.239829 -427.04462) (xy 412.241492 -427.029626) (xy 412.241492 -426.41901) (xy 412.242015 -426.406926)
			(xy 412.249463 -426.383934) (xy 412.263637 -426.364358) (xy 412.283156 -426.350105) (xy 412.306118 -426.342564)
			(xy 412.3182 -426.342048) (xy 413.258 -426.342048) (xy 413.270104 -426.342515) (xy 413.293122 -426.350009)
			(xy 413.312691 -426.364259) (xy 413.326887 -426.383866) (xy 413.334317 -426.406905) (xy 413.334708 -426.41901)
			(xy 413.334708 -428.960534) (xy 413.334223 -428.972621) (xy 413.326762 -428.995614) (xy 413.312579 -429.01519)
			(xy 413.293053 -429.029441) (xy 413.270085 -429.03698) (xy 413.258 -429.037496) (xy 412.3182 -429.037496)
			(xy 412.306091 -429.037084) (xy 412.283063 -429.029584) (xy 412.263489 -429.015321) (xy 412.249295 -428.995699)
			(xy 412.241875 -428.972645) (xy 412.241492 -428.960534) (xy 412.241492 -428.349918) (xy 412.239823 -428.334925)
			(xy 412.238045 -428.304806) (xy 412.237936 -428.28972) (xy 409.334716 -428.28972) (xy 409.334716 -428.960534)
			(xy 409.334321 -428.97263) (xy 409.326849 -428.995639) (xy 409.312646 -429.015222) (xy 409.293095 -429.02947)
			(xy 409.270103 -429.036993) (xy 409.258008 -429.037496) (xy 408.318208 -429.037496) (xy 408.306099 -429.037077)
			(xy 408.283071 -429.029579) (xy 408.263498 -429.015319) (xy 408.249303 -428.995697) (xy 408.241883 -428.972644)
			(xy 408.2415 -428.960534) (xy 408.2415 -428.349918) (xy 408.239831 -428.334925) (xy 408.238053 -428.304806)
			(xy 408.237944 -428.28972) (xy 405.334724 -428.28972) (xy 405.334724 -428.960534) (xy 405.334321 -428.972629)
			(xy 405.326851 -428.995637) (xy 405.312649 -429.015219) (xy 405.2931 -429.029467) (xy 405.27011 -429.036992)
			(xy 405.258016 -429.037496) (xy 404.318216 -429.037496) (xy 404.306108 -429.03707) (xy 404.28308 -429.029574)
			(xy 404.263507 -429.015315) (xy 404.249312 -428.995695) (xy 404.241891 -428.972644) (xy 404.241508 -428.960534)
			(xy 404.241508 -428.349918) (xy 404.239839 -428.334925) (xy 404.238061 -428.304806) (xy 404.237952 -428.28972)
			(xy 401.334732 -428.28972) (xy 401.334732 -428.960534) (xy 401.334321 -428.972628) (xy 401.326852 -428.995635)
			(xy 401.312652 -429.015216) (xy 401.293105 -429.029465) (xy 401.270117 -429.036991) (xy 401.258024 -429.037496)
			(xy 400.318224 -429.037496) (xy 400.306116 -429.037063) (xy 400.283089 -429.02957) (xy 400.263515 -429.015313)
			(xy 400.24932 -428.995694) (xy 400.241899 -428.972643) (xy 400.241516 -428.960534) (xy 400.241516 -428.349918)
			(xy 400.239847 -428.334925) (xy 400.238069 -428.304806) (xy 400.23796 -428.28972) (xy 396.334996 -428.28972)
			(xy 396.334996 -428.960534) (xy 396.334518 -428.972647) (xy 396.327025 -428.995686) (xy 396.312784 -429.015284)
			(xy 396.293186 -429.029525) (xy 396.270147 -429.037018) (xy 396.258034 -429.037496) (xy 395.318234 -429.037496)
			(xy 395.306125 -429.03696) (xy 395.283088 -429.029486) (xy 395.263489 -429.01526) (xy 395.249245 -428.995673)
			(xy 395.241751 -428.972643) (xy 395.241272 -428.960534) (xy 395.241272 -428.347886) (xy 395.239729 -428.333394)
			(xy 395.238076 -428.304294) (xy 395.23797 -428.28972) (xy 392.335004 -428.28972) (xy 392.335004 -428.960534)
			(xy 392.334518 -428.972646) (xy 392.327027 -428.995683) (xy 392.312787 -429.015281) (xy 392.293191 -429.029523)
			(xy 392.270154 -429.037017) (xy 392.258042 -429.037496) (xy 391.318242 -429.037496) (xy 391.306125 -429.037005)
			(xy 391.283073 -429.029528) (xy 391.26346 -429.015294) (xy 391.249206 -428.995695) (xy 391.241707 -428.972651)
			(xy 391.24128 -428.960534) (xy 391.24128 -428.347886) (xy 391.239737 -428.333394) (xy 391.238084 -428.304294)
			(xy 391.237978 -428.28972) (xy 388.335012 -428.28972) (xy 388.335012 -428.960534) (xy 388.334518 -428.972645)
			(xy 388.327028 -428.995681) (xy 388.31279 -429.015278) (xy 388.293196 -429.02952) (xy 388.270161 -429.037016)
			(xy 388.25805 -429.037496) (xy 387.31825 -429.037496) (xy 387.306136 -429.037031) (xy 387.283097 -429.029535)
			(xy 387.263499 -429.015289) (xy 387.249258 -428.995689) (xy 387.241766 -428.972648) (xy 387.241288 -428.960534)
			(xy 387.241288 -428.347886) (xy 387.239745 -428.333394) (xy 387.238092 -428.304294) (xy 387.237986 -428.28972)
			(xy 384.33502 -428.28972) (xy 384.33502 -428.960534) (xy 384.334669 -428.972663) (xy 384.327162 -428.99573)
			(xy 384.312894 -429.015348) (xy 384.293262 -429.029597) (xy 384.270187 -429.03708) (xy 384.258058 -429.037496)
			(xy 383.318258 -429.037496) (xy 383.306145 -429.037025) (xy 383.283106 -429.02953) (xy 383.263508 -429.015287)
			(xy 383.249266 -428.995687) (xy 383.241774 -428.972647) (xy 383.241296 -428.960534) (xy 383.241296 -428.347886)
			(xy 383.239753 -428.333394) (xy 383.2381 -428.304294) (xy 383.237994 -428.28972) (xy 361.693883 -428.28972)
			(xy 361.70649 -428.297264) (xy 361.847915 -428.391163) (xy 361.984785 -428.491588) (xy 362.116796 -428.598318)
			(xy 362.24366 -428.711119) (xy 362.365097 -428.829742) (xy 362.480841 -428.953927) (xy 362.590636 -429.0834)
			(xy 362.694243 -429.217877) (xy 362.791432 -429.357063) (xy 362.88199 -429.500651) (xy 362.965718 -429.648327)
			(xy 363.042433 -429.799764) (xy 363.111965 -429.954631) (xy 363.174162 -430.112586) (xy 363.228886 -430.273284)
			(xy 363.276018 -430.436369) (xy 363.315454 -430.601485) (xy 363.347108 -430.768268) (xy 363.364334 -430.889918)
			(xy 381.237998 -430.889918) (xy 381.238092 -430.875344) (xy 381.239744 -430.846243) (xy 381.2413 -430.831752)
			(xy 381.2413 -429.747934) (xy 381.239752 -429.733442) (xy 381.238102 -429.704342) (xy 381.237998 -429.689768)
			(xy 381.238096 -429.675194) (xy 381.239746 -429.646093) (xy 381.2413 -429.631602) (xy 381.2413 -429.018954)
			(xy 381.241772 -429.006841) (xy 381.249267 -428.983803) (xy 381.263511 -428.964205) (xy 381.28311 -428.949964)
			(xy 381.306149 -428.942471) (xy 381.318262 -428.941992) (xy 382.258062 -428.941992) (xy 382.27017 -428.942543)
			(xy 382.293204 -428.950015) (xy 382.312803 -428.964238) (xy 382.327047 -428.98382) (xy 382.334543 -429.006847)
			(xy 382.335024 -429.018954) (xy 382.335024 -431.560478) (xy 382.334621 -431.572603) (xy 382.32713 -431.595668)
			(xy 382.312875 -431.615287) (xy 382.293254 -431.629537) (xy 382.270187 -431.637023) (xy 382.258062 -431.63744)
			(xy 381.318262 -431.63744) (xy 381.306143 -431.63702) (xy 381.283095 -431.62952) (xy 381.263492 -431.615265)
			(xy 381.249253 -431.595651) (xy 381.24177 -431.572597) (xy 381.2413 -431.560478) (xy 381.2413 -430.948084)
			(xy 381.239756 -430.933592) (xy 381.238104 -430.904492) (xy 381.237998 -430.889918) (xy 363.364334 -430.889918)
			(xy 363.370909 -430.936351) (xy 363.386805 -431.105365) (xy 363.394762 -431.274938) (xy 363.39526 -431.359818)
			(xy 363.39483 -431.445421) (xy 363.38674 -431.616436) (xy 363.370574 -431.786877) (xy 363.355859 -431.889916)
			(xy 383.237994 -431.889916) (xy 383.238088 -431.875342) (xy 383.23974 -431.846241) (xy 383.241296 -431.83175)
			(xy 383.241296 -430.747932) (xy 383.239748 -430.73344) (xy 383.238098 -430.70434) (xy 383.237994 -430.689766)
			(xy 383.238092 -430.675192) (xy 383.239742 -430.646091) (xy 383.241296 -430.6316) (xy 383.241296 -430.018952)
			(xy 383.241676 -430.006841) (xy 383.249188 -429.983813) (xy 383.263459 -429.964241) (xy 383.283088 -429.950048)
			(xy 383.306145 -429.942628) (xy 383.318258 -429.942244) (xy 384.258058 -429.942244) (xy 384.270146 -429.942743)
			(xy 384.293146 -429.950189) (xy 384.312727 -429.964367) (xy 384.326979 -429.983894) (xy 384.334511 -430.006866)
			(xy 384.33502 -430.018952) (xy 384.33502 -430.889918) (xy 385.23799 -430.889918) (xy 385.238084 -430.875344)
			(xy 385.239736 -430.846243) (xy 385.241292 -430.831752) (xy 385.241292 -429.747934) (xy 385.239745 -429.733442)
			(xy 385.238094 -429.704342) (xy 385.23799 -429.689768) (xy 385.238088 -429.675194) (xy 385.239738 -429.646093)
			(xy 385.241292 -429.631602) (xy 385.241292 -429.018954) (xy 385.241772 -429.006842) (xy 385.249266 -428.983805)
			(xy 385.263508 -428.964208) (xy 385.283105 -428.949966) (xy 385.306142 -428.942472) (xy 385.318254 -428.941992)
			(xy 386.258054 -428.941992) (xy 386.270162 -428.94255) (xy 386.293196 -428.950019) (xy 386.312794 -428.96424)
			(xy 386.327039 -428.983822) (xy 386.334535 -429.006847) (xy 386.335016 -429.018954) (xy 386.335016 -431.560478)
			(xy 386.334621 -431.572604) (xy 386.327129 -431.59567) (xy 386.312872 -431.61529) (xy 386.293249 -431.62954)
			(xy 386.27018 -431.637024) (xy 386.258054 -431.63744) (xy 385.318254 -431.63744) (xy 385.306135 -431.637027)
			(xy 385.283086 -431.629525) (xy 385.263484 -431.615268) (xy 385.249244 -431.595653) (xy 385.241762 -431.572598)
			(xy 385.241292 -431.560478) (xy 385.241292 -430.948084) (xy 385.239749 -430.933592) (xy 385.238096 -430.904492)
			(xy 385.23799 -430.889918) (xy 384.33502 -430.889918) (xy 384.33502 -431.889916) (xy 387.237986 -431.889916)
			(xy 387.23808 -431.875342) (xy 387.239732 -431.846241) (xy 387.241288 -431.83175) (xy 387.241288 -430.747932)
			(xy 387.23974 -430.73344) (xy 387.23809 -430.70434) (xy 387.237986 -430.689766) (xy 387.238084 -430.675192)
			(xy 387.239734 -430.646091) (xy 387.241288 -430.6316) (xy 387.241288 -430.018952) (xy 387.241675 -430.006842)
			(xy 387.249187 -429.983815) (xy 387.263456 -429.964244) (xy 387.283083 -429.95005) (xy 387.306138 -429.942629)
			(xy 387.31825 -429.942244) (xy 388.25805 -429.942244) (xy 388.270137 -429.94275) (xy 388.293137 -429.950193)
			(xy 388.312718 -429.96437) (xy 388.32697 -429.983896) (xy 388.334503 -430.006866) (xy 388.335012 -430.018952)
			(xy 388.335012 -430.889918) (xy 389.237982 -430.889918) (xy 389.238076 -430.875344) (xy 389.239728 -430.846243)
			(xy 389.241284 -430.831752) (xy 389.241284 -429.747934) (xy 389.239737 -429.733442) (xy 389.238086 -429.704342)
			(xy 389.237982 -429.689768) (xy 389.23808 -429.675194) (xy 389.23973 -429.646093) (xy 389.241284 -429.631602)
			(xy 389.241284 -429.018954) (xy 389.241673 -429.006832) (xy 389.249179 -428.98378) (xy 389.26344 -428.964175)
			(xy 389.283062 -428.949937) (xy 389.306124 -428.942459) (xy 389.318246 -428.941992) (xy 390.258046 -428.941992)
			(xy 390.270158 -428.942472) (xy 390.293195 -428.949966) (xy 390.312792 -428.964208) (xy 390.327034 -428.983805)
			(xy 390.334528 -429.006842) (xy 390.335008 -429.018954) (xy 390.335008 -431.560478) (xy 390.33447 -431.572587)
			(xy 390.326995 -431.595622) (xy 390.312768 -431.61522) (xy 390.293183 -431.629464) (xy 390.270154 -431.636959)
			(xy 390.258046 -431.63744) (xy 389.318246 -431.63744) (xy 389.306123 -431.637001) (xy 389.283062 -431.629518)
			(xy 389.263445 -431.615273) (xy 389.249193 -431.595659) (xy 389.241703 -431.5726) (xy 389.241284 -431.560478)
			(xy 389.241284 -430.948084) (xy 389.239741 -430.933592) (xy 389.238088 -430.904492) (xy 389.237982 -430.889918)
			(xy 388.335012 -430.889918) (xy 388.335012 -431.889916) (xy 391.237978 -431.889916) (xy 391.238072 -431.875342)
			(xy 391.239724 -431.846241) (xy 391.24128 -431.83175) (xy 391.24128 -430.747932) (xy 391.239732 -430.73344)
			(xy 391.238082 -430.70434) (xy 391.237978 -430.689766) (xy 391.238076 -430.675192) (xy 391.239726 -430.646091)
			(xy 391.24128 -430.6316) (xy 391.24128 -430.018952) (xy 391.241675 -430.006843) (xy 391.249186 -429.983817)
			(xy 391.263453 -429.964247) (xy 391.283077 -429.950053) (xy 391.306131 -429.94263) (xy 391.318242 -429.942244)
			(xy 392.258042 -429.942244) (xy 392.270134 -429.942672) (xy 392.293137 -429.95014) (xy 392.312716 -429.964337)
			(xy 392.326965 -429.983879) (xy 392.334496 -430.006861) (xy 392.335004 -430.018952) (xy 392.335004 -430.889918)
			(xy 393.237974 -430.889918) (xy 393.238068 -430.875344) (xy 393.23972 -430.846243) (xy 393.241276 -430.831752)
			(xy 393.241276 -429.747934) (xy 393.239729 -429.733442) (xy 393.238078 -429.704342) (xy 393.237974 -429.689768)
			(xy 393.238072 -429.675194) (xy 393.239722 -429.646093) (xy 393.241276 -429.631602) (xy 393.241276 -429.018954)
			(xy 393.241673 -429.006833) (xy 393.249178 -428.983782) (xy 393.263438 -428.964178) (xy 393.283057 -428.949939)
			(xy 393.306117 -428.94246) (xy 393.318238 -428.941992) (xy 394.258038 -428.941992) (xy 394.27015 -428.942479)
			(xy 394.293187 -428.949971) (xy 394.312784 -428.964211) (xy 394.327026 -428.983806) (xy 394.33452 -429.006842)
			(xy 394.335 -429.018954) (xy 394.335 -431.560478) (xy 394.33447 -431.572588) (xy 394.326994 -431.595624)
			(xy 394.312765 -431.615223) (xy 394.293177 -431.629466) (xy 394.270147 -431.636961) (xy 394.258038 -431.63744)
			(xy 393.318238 -431.63744) (xy 393.306115 -431.637007) (xy 393.283054 -431.629523) (xy 393.263436 -431.615275)
			(xy 393.249184 -431.595661) (xy 393.241695 -431.572601) (xy 393.241276 -431.560478) (xy 393.241276 -430.948084)
			(xy 393.239733 -430.933592) (xy 393.23808 -430.904492) (xy 393.237974 -430.889918) (xy 392.335004 -430.889918)
			(xy 392.335004 -431.889916) (xy 395.23797 -431.889916) (xy 395.238064 -431.875342) (xy 395.239716 -431.846241)
			(xy 395.241272 -431.83175) (xy 395.241272 -430.747932) (xy 395.239724 -430.73344) (xy 395.238074 -430.70434)
			(xy 395.23797 -430.689766) (xy 395.238068 -430.675192) (xy 395.239718 -430.646091) (xy 395.241272 -430.6316)
			(xy 395.241272 -430.018952) (xy 395.241675 -430.006843) (xy 395.249184 -429.983819) (xy 395.26345 -429.96425)
			(xy 395.283072 -429.950056) (xy 395.306124 -429.942631) (xy 395.318234 -429.942244) (xy 396.258034 -429.942244)
			(xy 396.270126 -429.942678) (xy 396.293128 -429.950145) (xy 396.312708 -429.96434) (xy 396.326957 -429.98388)
			(xy 396.334488 -430.006862) (xy 396.334996 -430.018952) (xy 396.334996 -430.889918) (xy 398.237964 -430.889918)
			(xy 398.238073 -430.874832) (xy 398.239855 -430.844714) (xy 398.24152 -430.82972) (xy 398.24152 -429.749966)
			(xy 398.239855 -429.734972) (xy 398.238074 -429.704854) (xy 398.237964 -429.689768) (xy 398.238078 -429.674682)
			(xy 398.239856 -429.644564) (xy 398.24152 -429.62957) (xy 398.24152 -429.018954) (xy 398.241968 -429.006864)
			(xy 398.249435 -428.983865) (xy 398.263627 -428.964288) (xy 398.283163 -428.950038) (xy 398.306139 -428.942504)
			(xy 398.318228 -428.941992) (xy 399.258028 -428.941992) (xy 399.270138 -428.942392) (xy 399.293164 -428.949899)
			(xy 399.312736 -428.964165) (xy 399.32693 -428.983789) (xy 399.334352 -429.006843) (xy 399.334736 -429.018954)
			(xy 399.334736 -431.560478) (xy 399.334273 -431.572569) (xy 399.32682 -431.595573) (xy 399.312633 -431.615155)
			(xy 399.293097 -431.629405) (xy 399.270117 -431.636934) (xy 399.258028 -431.63744) (xy 398.318228 -431.63744)
			(xy 398.306125 -431.63696) (xy 398.283105 -431.629473) (xy 398.263535 -431.615227) (xy 398.249338 -431.595621)
			(xy 398.241909 -431.572582) (xy 398.24152 -431.560478) (xy 398.24152 -430.950116) (xy 398.239851 -430.935123)
			(xy 398.238073 -430.905004) (xy 398.237964 -430.889918) (xy 396.334996 -430.889918) (xy 396.334996 -431.889916)
			(xy 400.23796 -431.889916) (xy 400.238069 -431.87483) (xy 400.239851 -431.844712) (xy 400.241516 -431.829718)
			(xy 400.241516 -430.749964) (xy 400.239851 -430.73497) (xy 400.23807 -430.704852) (xy 400.23796 -430.689766)
			(xy 400.238074 -430.67468) (xy 400.239852 -430.644562) (xy 400.241516 -430.629568) (xy 400.241516 -430.018952)
			(xy 400.241924 -430.006873) (xy 400.249402 -429.9839) (xy 400.263613 -429.964361) (xy 400.283164 -429.950169)
			(xy 400.306144 -429.942712) (xy 400.318224 -429.942244) (xy 401.258024 -429.942244) (xy 401.270095 -429.942743)
			(xy 401.293055 -429.950206) (xy 401.312587 -429.964396) (xy 401.326783 -429.983924) (xy 401.334253 -430.006881)
			(xy 401.334732 -430.018952) (xy 401.334732 -430.889918) (xy 402.237956 -430.889918) (xy 402.238065 -430.874832)
			(xy 402.239847 -430.844714) (xy 402.241512 -430.82972) (xy 402.241512 -429.749966) (xy 402.239847 -429.734972)
			(xy 402.238066 -429.704854) (xy 402.237956 -429.689768) (xy 402.23807 -429.674682) (xy 402.239848 -429.644564)
			(xy 402.241512 -429.62957) (xy 402.241512 -429.018954) (xy 402.241968 -429.006865) (xy 402.249434 -428.983867)
			(xy 402.263624 -428.964291) (xy 402.283158 -428.950041) (xy 402.306132 -428.942505) (xy 402.31822 -428.941992)
			(xy 403.25802 -428.941992) (xy 403.270129 -428.942399) (xy 403.293156 -428.949903) (xy 403.312728 -428.964167)
			(xy 403.326922 -428.98379) (xy 403.334344 -429.006843) (xy 403.334728 -429.018954) (xy 403.334728 -431.560478)
			(xy 403.334273 -431.57257) (xy 403.326819 -431.595575) (xy 403.31263 -431.615158) (xy 403.293092 -431.629408)
			(xy 403.27011 -431.636935) (xy 403.25802 -431.63744) (xy 402.31822 -431.63744) (xy 402.306116 -431.636967)
			(xy 402.283096 -431.629478) (xy 402.263527 -431.61523) (xy 402.24933 -431.595622) (xy 402.241901 -431.572583)
			(xy 402.241512 -431.560478) (xy 402.241512 -430.950116) (xy 402.239843 -430.935123) (xy 402.238065 -430.905004)
			(xy 402.237956 -430.889918) (xy 401.334732 -430.889918) (xy 401.334732 -431.889916) (xy 404.237952 -431.889916)
			(xy 404.238061 -431.87483) (xy 404.239843 -431.844712) (xy 404.241508 -431.829718) (xy 404.241508 -430.749964)
			(xy 404.239843 -430.73497) (xy 404.238062 -430.704852) (xy 404.237952 -430.689766) (xy 404.238066 -430.67468)
			(xy 404.239844 -430.644562) (xy 404.241508 -430.629568) (xy 404.241508 -430.018952) (xy 404.241923 -430.006873)
			(xy 404.249401 -429.983902) (xy 404.26361 -429.964364) (xy 404.283159 -429.950172) (xy 404.306137 -429.942713)
			(xy 404.318216 -429.942244) (xy 405.258016 -429.942244) (xy 405.270087 -429.94275) (xy 405.293046 -429.950211)
			(xy 405.312579 -429.964399) (xy 405.326774 -429.983925) (xy 405.334245 -430.006882) (xy 405.334724 -430.018952)
			(xy 405.334724 -430.889918) (xy 406.237948 -430.889918) (xy 406.238057 -430.874832) (xy 406.239839 -430.844714)
			(xy 406.241504 -430.82972) (xy 406.241504 -429.749966) (xy 406.239839 -429.734972) (xy 406.238058 -429.704854)
			(xy 406.237948 -429.689768) (xy 406.238062 -429.674682) (xy 406.23984 -429.644564) (xy 406.241504 -429.62957)
			(xy 406.241504 -429.018954) (xy 406.241967 -429.006866) (xy 406.249432 -428.98387) (xy 406.263621 -428.964293)
			(xy 406.283153 -428.950043) (xy 406.306125 -428.942506) (xy 406.318212 -428.941992) (xy 407.258012 -428.941992)
			(xy 407.270121 -428.942406) (xy 407.293147 -428.949908) (xy 407.312719 -428.96417) (xy 407.326914 -428.983792)
			(xy 407.334336 -429.006844) (xy 407.33472 -429.018954) (xy 407.33472 -431.560478) (xy 407.334273 -431.57257)
			(xy 407.326818 -431.595577) (xy 407.312627 -431.615161) (xy 407.293087 -431.629411) (xy 407.270103 -431.636936)
			(xy 407.258012 -431.63744) (xy 406.318212 -431.63744) (xy 406.306108 -431.636974) (xy 406.283088 -431.629483)
			(xy 406.263518 -431.615232) (xy 406.249322 -431.595624) (xy 406.241893 -431.572583) (xy 406.241504 -431.560478)
			(xy 406.241504 -430.950116) (xy 406.239835 -430.935123) (xy 406.238057 -430.905004) (xy 406.237948 -430.889918)
			(xy 405.334724 -430.889918) (xy 405.334724 -431.889916) (xy 408.237944 -431.889916) (xy 408.238053 -431.87483)
			(xy 408.239835 -431.844712) (xy 408.2415 -431.829718) (xy 408.2415 -430.749964) (xy 408.239835 -430.73497)
			(xy 408.238054 -430.704852) (xy 408.237944 -430.689766) (xy 408.238058 -430.67468) (xy 408.239836 -430.644562)
			(xy 408.2415 -430.629568) (xy 408.2415 -430.018952) (xy 408.241923 -430.006874) (xy 408.2494 -429.983904)
			(xy 408.263607 -429.964367) (xy 408.283154 -429.950174) (xy 408.30613 -429.942714) (xy 408.318208 -429.942244)
			(xy 409.258008 -429.942244) (xy 409.270078 -429.942757) (xy 409.293037 -429.950216) (xy 409.31257 -429.964401)
			(xy 409.326766 -429.983927) (xy 409.334237 -430.006882) (xy 409.334716 -430.018952) (xy 409.334716 -430.889918)
			(xy 410.23794 -430.889918) (xy 410.238051 -430.874832) (xy 410.239833 -430.844714) (xy 410.241496 -430.82972)
			(xy 410.241496 -429.749966) (xy 410.239831 -429.734972) (xy 410.23805 -429.704854) (xy 410.23794 -429.689768)
			(xy 410.238054 -429.674682) (xy 410.239832 -429.644564) (xy 410.241496 -429.62957) (xy 410.241496 -429.018954)
			(xy 410.241967 -429.006866) (xy 410.249431 -428.983872) (xy 410.263618 -428.964296) (xy 410.283148 -428.950046)
			(xy 410.306118 -428.942507) (xy 410.318204 -428.941992) (xy 411.258004 -428.941992) (xy 411.270112 -428.942413)
			(xy 411.293138 -428.949912) (xy 411.312711 -428.964173) (xy 411.326906 -428.983793) (xy 411.334328 -429.006844)
			(xy 411.334712 -429.018954) (xy 411.334712 -431.560478) (xy 411.334273 -431.572571) (xy 411.326816 -431.595579)
			(xy 411.312624 -431.615164) (xy 411.293082 -431.629413) (xy 411.270096 -431.636937) (xy 411.258004 -431.63744)
			(xy 410.318204 -431.63744) (xy 410.306099 -431.636981) (xy 410.283079 -431.629488) (xy 410.263509 -431.615236)
			(xy 410.249313 -431.595625) (xy 410.241885 -431.572584) (xy 410.241496 -431.560478) (xy 410.241496 -430.950116)
			(xy 410.239827 -430.935123) (xy 410.238049 -430.905004) (xy 410.23794 -430.889918) (xy 409.334716 -430.889918)
			(xy 409.334716 -431.889916) (xy 412.237936 -431.889916) (xy 412.238047 -431.87483) (xy 412.239829 -431.844712)
			(xy 412.241492 -431.829718) (xy 412.241492 -430.749964) (xy 412.239827 -430.73497) (xy 412.238046 -430.704852)
			(xy 412.237936 -430.689766) (xy 412.238052 -430.674681) (xy 412.23983 -430.644562) (xy 412.241492 -430.629568)
			(xy 412.241492 -430.018952) (xy 412.241923 -430.006875) (xy 412.249399 -429.983906) (xy 412.263604 -429.96437)
			(xy 412.283149 -429.950177) (xy 412.306123 -429.942716) (xy 412.3182 -429.942244) (xy 413.258 -429.942244)
			(xy 413.27007 -429.942764) (xy 413.293029 -429.95022) (xy 413.312562 -429.964404) (xy 413.326758 -429.983928)
			(xy 413.334229 -430.006883) (xy 413.334708 -430.018952) (xy 413.334708 -432.560476) (xy 413.334267 -432.572557)
			(xy 413.326806 -432.595539) (xy 413.312607 -432.61509) (xy 413.293061 -432.629295) (xy 413.270081 -432.636763)
			(xy 413.258 -432.637184) (xy 412.3182 -432.637184) (xy 412.306115 -432.636787) (xy 412.283128 -432.629317)
			(xy 412.263576 -432.615107) (xy 412.249372 -432.59555) (xy 412.241909 -432.572561) (xy 412.241492 -432.560476)
			(xy 412.241492 -431.950114) (xy 412.239822 -431.935121) (xy 412.238045 -431.905002) (xy 412.237936 -431.889916)
			(xy 409.334716 -431.889916) (xy 409.334716 -432.560476) (xy 409.334267 -432.572557) (xy 409.326807 -432.595537)
			(xy 409.31261 -432.615087) (xy 409.293066 -432.629292) (xy 409.270088 -432.636762) (xy 409.258008 -432.637184)
			(xy 408.318208 -432.637184) (xy 408.306123 -432.63678) (xy 408.283137 -432.629312) (xy 408.263584 -432.615105)
			(xy 408.249381 -432.595549) (xy 408.241917 -432.572561) (xy 408.2415 -432.560476) (xy 408.2415 -431.950114)
			(xy 408.23983 -431.935121) (xy 408.238053 -431.905002) (xy 408.237944 -431.889916) (xy 405.334724 -431.889916)
			(xy 405.334724 -432.560476) (xy 405.334267 -432.572556) (xy 405.326808 -432.595535) (xy 405.312613 -432.615084)
			(xy 405.293071 -432.62929) (xy 405.270096 -432.636761) (xy 405.258016 -432.637184) (xy 404.318216 -432.637184)
			(xy 404.306132 -432.636773) (xy 404.283146 -432.629307) (xy 404.263593 -432.615101) (xy 404.249389 -432.595547)
			(xy 404.241926 -432.57256) (xy 404.241508 -432.560476) (xy 404.241508 -431.950114) (xy 404.239838 -431.935121)
			(xy 404.238061 -431.905002) (xy 404.237952 -431.889916) (xy 401.334732 -431.889916) (xy 401.334732 -432.560476)
			(xy 401.334216 -432.572547) (xy 401.326763 -432.595509) (xy 401.312579 -432.615045) (xy 401.293052 -432.629241)
			(xy 401.270095 -432.636708) (xy 401.258024 -432.637184) (xy 400.318224 -432.637184) (xy 400.30614 -432.636766)
			(xy 400.283154 -432.629303) (xy 400.263601 -432.615099) (xy 400.249397 -432.595546) (xy 400.241934 -432.57256)
			(xy 400.241516 -432.560476) (xy 400.241516 -431.950114) (xy 400.239846 -431.935121) (xy 400.238069 -431.905002)
			(xy 400.23796 -431.889916) (xy 396.334996 -431.889916) (xy 396.334996 -432.560476) (xy 396.334563 -432.572584)
			(xy 396.32707 -432.595611) (xy 396.312813 -432.615185) (xy 396.293194 -432.62938) (xy 396.270143 -432.636801)
			(xy 396.258034 -432.637184) (xy 395.318234 -432.637184) (xy 395.306149 -432.636664) (xy 395.283153 -432.62922)
			(xy 395.263575 -432.615046) (xy 395.249322 -432.595525) (xy 395.241785 -432.572559) (xy 395.241272 -432.560476)
			(xy 395.241272 -431.948082) (xy 395.239729 -431.93359) (xy 395.238076 -431.90449) (xy 395.23797 -431.889916)
			(xy 392.335004 -431.889916) (xy 392.335004 -432.560476) (xy 392.334563 -432.572583) (xy 392.327071 -432.595609)
			(xy 392.312815 -432.615182) (xy 392.293199 -432.629378) (xy 392.27015 -432.6368) (xy 392.258042 -432.637184)
			(xy 391.318242 -432.637184) (xy 391.306157 -432.636657) (xy 391.283162 -432.629215) (xy 391.263583 -432.615043)
			(xy 391.24933 -432.595523) (xy 391.241793 -432.572559) (xy 391.24128 -432.560476) (xy 391.24128 -431.948082)
			(xy 391.239737 -431.93359) (xy 391.238084 -431.90449) (xy 391.237978 -431.889916) (xy 388.335012 -431.889916)
			(xy 388.335012 -432.560476) (xy 388.334563 -432.572582) (xy 388.327072 -432.595607) (xy 388.312818 -432.615179)
			(xy 388.293204 -432.629375) (xy 388.270158 -432.636799) (xy 388.25805 -432.637184) (xy 387.31825 -432.637184)
			(xy 387.306165 -432.636651) (xy 387.28317 -432.62921) (xy 387.263592 -432.61504) (xy 387.249339 -432.595522)
			(xy 387.241801 -432.572559) (xy 387.241288 -432.560476) (xy 387.241288 -431.948082) (xy 387.239745 -431.93359)
			(xy 387.238092 -431.90449) (xy 387.237986 -431.889916) (xy 384.33502 -431.889916) (xy 384.33502 -432.560476)
			(xy 384.334563 -432.572582) (xy 384.327073 -432.595605) (xy 384.312821 -432.615176) (xy 384.293209 -432.629373)
			(xy 384.270165 -432.636797) (xy 384.258058 -432.637184) (xy 383.318258 -432.637184) (xy 383.306169 -432.636729)
			(xy 383.283171 -432.629264) (xy 383.263593 -432.615073) (xy 383.249343 -432.595539) (xy 383.241808 -432.572564)
			(xy 383.241296 -432.560476) (xy 383.241296 -431.948082) (xy 383.239753 -431.93359) (xy 383.2381 -431.90449)
			(xy 383.237994 -431.889916) (xy 363.355859 -431.889916) (xy 363.346369 -431.956363) (xy 363.314178 -432.124516)
			(xy 363.274074 -432.290959) (xy 363.226145 -432.455319) (xy 363.170501 -432.61723) (xy 363.107264 -432.776329)
			(xy 363.036576 -432.932261) (xy 362.958595 -433.084677) (xy 362.873496 -433.233236) (xy 362.781469 -433.377605)
			(xy 362.68272 -433.517463) (xy 362.577469 -433.652495) (xy 362.465953 -433.782401) (xy 362.348419 -433.90689)
			(xy 362.225132 -434.025683) (xy 362.096367 -434.138515) (xy 361.962411 -434.245133) (xy 361.823565 -434.345299)
			(xy 361.680139 -434.438789) (xy 361.593049 -434.48986) (xy 381.237998 -434.48986) (xy 381.238096 -434.475286)
			(xy 381.239745 -434.446185) (xy 381.2413 -434.431694) (xy 381.2413 -433.34813) (xy 381.239752 -433.333638)
			(xy 381.238102 -433.304538) (xy 381.237998 -433.289964) (xy 381.238096 -433.27539) (xy 381.239745 -433.246289)
			(xy 381.2413 -433.231798) (xy 381.2413 -432.618896) (xy 381.241713 -432.606787) (xy 381.249213 -432.583759)
			(xy 381.263476 -432.564186) (xy 381.283098 -432.549992) (xy 381.306152 -432.542571) (xy 381.318262 -432.542188)
			(xy 382.258062 -432.542188) (xy 382.270154 -432.542641) (xy 382.293162 -432.550093) (xy 382.312747 -432.564281)
			(xy 382.326997 -432.583821) (xy 382.334521 -432.606805) (xy 382.335024 -432.618896) (xy 382.335024 -435.16042)
			(xy 382.334601 -435.172528) (xy 382.327099 -435.195551) (xy 382.312838 -435.215122) (xy 382.29322 -435.229317)
			(xy 382.270171 -435.236741) (xy 382.258062 -435.237128) (xy 381.318262 -435.237128) (xy 381.306167 -435.236724)
			(xy 381.28316 -435.229253) (xy 381.263578 -435.215052) (xy 381.24933 -435.195503) (xy 381.241804 -435.172514)
			(xy 381.2413 -435.16042) (xy 381.2413 -434.548026) (xy 381.239752 -434.533534) (xy 381.238102 -434.504434)
			(xy 381.237998 -434.48986) (xy 361.593049 -434.48986) (xy 361.532453 -434.525394) (xy 361.380838 -434.60492)
			(xy 361.225633 -434.67719) (xy 361.146598 -434.710078) (xy 361.132966 -434.716266) (xy 361.109724 -434.735103)
			(xy 361.092944 -434.759873) (xy 361.084069 -434.788444) (xy 361.083862 -434.818361) (xy 361.092341 -434.847052)
			(xy 361.108777 -434.872051) (xy 361.119928 -434.882036) (xy 361.169374 -434.924045) (xy 361.263563 -435.013299)
			(xy 361.352051 -435.108208) (xy 361.434498 -435.208409) (xy 361.510589 -435.313518) (xy 361.580032 -435.423133)
			(xy 361.616728 -435.489858) (xy 383.237994 -435.489858) (xy 383.238091 -435.475284) (xy 383.239741 -435.446183)
			(xy 383.241296 -435.431692) (xy 383.241296 -434.348128) (xy 383.239748 -434.333636) (xy 383.238098 -434.304536)
			(xy 383.237994 -434.289962) (xy 383.238092 -434.275388) (xy 383.239741 -434.246287) (xy 383.241296 -434.231796)
			(xy 383.241296 -433.618894) (xy 383.241806 -433.606783) (xy 383.24929 -433.583747) (xy 383.263524 -433.564149)
			(xy 383.283115 -433.549906) (xy 383.306148 -433.542412) (xy 383.318258 -433.541932) (xy 384.258058 -433.541932)
			(xy 384.270178 -433.542396) (xy 384.293234 -433.549876) (xy 384.31285 -433.564116) (xy 384.327103 -433.583722)
			(xy 384.334597 -433.606774) (xy 384.33502 -433.618894) (xy 384.33502 -434.48986) (xy 385.23799 -434.48986)
			(xy 385.238088 -434.475286) (xy 385.239737 -434.446185) (xy 385.241292 -434.431694) (xy 385.241292 -433.34813)
			(xy 385.239744 -433.333638) (xy 385.238094 -433.304538) (xy 385.23799 -433.289964) (xy 385.238088 -433.27539)
			(xy 385.239737 -433.246289) (xy 385.241292 -433.231798) (xy 385.241292 -432.618896) (xy 385.241713 -432.606788)
			(xy 385.249212 -432.583762) (xy 385.263473 -432.564189) (xy 385.283093 -432.549994) (xy 385.306144 -432.542572)
			(xy 385.318254 -432.542188) (xy 386.258054 -432.542188) (xy 386.270146 -432.542647) (xy 386.293153 -432.550097)
			(xy 386.312738 -432.564284) (xy 386.326988 -432.583823) (xy 386.334513 -432.606806) (xy 386.335016 -432.618896)
			(xy 386.335016 -435.16042) (xy 386.334601 -435.172528) (xy 386.327098 -435.195554) (xy 386.312836 -435.215125)
			(xy 386.293215 -435.229319) (xy 386.270164 -435.236743) (xy 386.258054 -435.237128) (xy 385.318254 -435.237128)
			(xy 385.306159 -435.236731) (xy 385.283151 -435.229258) (xy 385.263569 -435.215054) (xy 385.249322 -435.195505)
			(xy 385.241796 -435.172514) (xy 385.241292 -435.16042) (xy 385.241292 -434.548026) (xy 385.239744 -434.533534)
			(xy 385.238094 -434.504434) (xy 385.23799 -434.48986) (xy 384.33502 -434.48986) (xy 384.33502 -435.489858)
			(xy 387.237986 -435.489858) (xy 387.238083 -435.475284) (xy 387.239733 -435.446183) (xy 387.241288 -435.431692)
			(xy 387.241288 -434.348128) (xy 387.23974 -434.333636) (xy 387.23809 -434.304536) (xy 387.237986 -434.289962)
			(xy 387.238084 -434.275388) (xy 387.239733 -434.246287) (xy 387.241288 -434.231796) (xy 387.241288 -433.618894)
			(xy 387.241806 -433.606784) (xy 387.249289 -433.583749) (xy 387.263521 -433.564152) (xy 387.28311 -433.549909)
			(xy 387.30614 -433.542413) (xy 387.31825 -433.541932) (xy 388.25805 -433.541932) (xy 388.270167 -433.542369)
			(xy 388.29321 -433.549869) (xy 388.312811 -433.564121) (xy 388.327051 -433.583729) (xy 388.334538 -433.606777)
			(xy 388.335012 -433.618894) (xy 388.335012 -434.48986) (xy 389.237982 -434.48986) (xy 389.23808 -434.475286)
			(xy 389.239729 -434.446185) (xy 389.241284 -434.431694) (xy 389.241284 -433.34813) (xy 389.239736 -433.333638)
			(xy 389.238086 -433.304538) (xy 389.237982 -433.289964) (xy 389.23808 -433.27539) (xy 389.23973 -433.246289)
			(xy 389.241284 -433.231798) (xy 389.241284 -432.618896) (xy 389.241713 -432.606789) (xy 389.249211 -432.583764)
			(xy 389.26347 -432.564192) (xy 389.283088 -432.549997) (xy 389.306137 -432.542573) (xy 389.318246 -432.542188)
			(xy 390.258046 -432.542188) (xy 390.270143 -432.542569) (xy 390.293153 -432.550044) (xy 390.312736 -432.564251)
			(xy 390.326984 -432.583805) (xy 390.334506 -432.6068) (xy 390.335008 -432.618896) (xy 390.335008 -435.16042)
			(xy 390.334601 -435.172529) (xy 390.327097 -435.195556) (xy 390.312833 -435.215128) (xy 390.29321 -435.229322)
			(xy 390.270157 -435.236744) (xy 390.258046 -435.237128) (xy 389.318246 -435.237128) (xy 389.306156 -435.236653)
			(xy 389.283151 -435.229205) (xy 389.263568 -435.215022) (xy 389.249317 -435.195487) (xy 389.241789 -435.172509)
			(xy 389.241284 -435.16042) (xy 389.241284 -434.548026) (xy 389.239736 -434.533534) (xy 389.238086 -434.504434)
			(xy 389.237982 -434.48986) (xy 388.335012 -434.48986) (xy 388.335012 -435.489858) (xy 391.237978 -435.489858)
			(xy 391.238076 -435.475284) (xy 391.239725 -435.446183) (xy 391.24128 -435.431692) (xy 391.24128 -434.348128)
			(xy 391.239732 -434.333636) (xy 391.238082 -434.304536) (xy 391.237978 -434.289962) (xy 391.238076 -434.275388)
			(xy 391.239725 -434.246287) (xy 391.24128 -434.231796) (xy 391.24128 -433.618894) (xy 391.241656 -433.606767)
			(xy 391.249155 -433.583701) (xy 391.263416 -433.564082) (xy 391.283044 -433.549833) (xy 391.306115 -433.542348)
			(xy 391.318242 -433.541932) (xy 392.258042 -433.541932) (xy 392.270158 -433.542376) (xy 392.293202 -433.549874)
			(xy 392.312802 -433.564123) (xy 392.327043 -433.583731) (xy 392.33453 -433.606778) (xy 392.335004 -433.618894)
			(xy 392.335004 -434.48986) (xy 393.237974 -434.48986) (xy 393.238072 -434.475286) (xy 393.239721 -434.446185)
			(xy 393.241276 -434.431694) (xy 393.241276 -433.34813) (xy 393.239728 -433.333638) (xy 393.238078 -433.304538)
			(xy 393.237974 -433.289964) (xy 393.238072 -433.27539) (xy 393.239722 -433.246289) (xy 393.241276 -433.231798)
			(xy 393.241276 -432.618896) (xy 393.241712 -432.606789) (xy 393.24921 -432.583766) (xy 393.263467 -432.564195)
			(xy 393.283083 -432.55) (xy 393.30613 -432.542575) (xy 393.318238 -432.542188) (xy 394.258038 -432.542188)
			(xy 394.270134 -432.542576) (xy 394.293144 -432.550049) (xy 394.312728 -432.564254) (xy 394.326975 -432.583807)
			(xy 394.334498 -432.606801) (xy 394.335 -432.618896) (xy 394.335 -435.16042) (xy 394.334601 -435.17253)
			(xy 394.327096 -435.195558) (xy 394.31283 -435.215131) (xy 394.293205 -435.229325) (xy 394.270149 -435.236745)
			(xy 394.258038 -435.237128) (xy 393.318238 -435.237128) (xy 393.306147 -435.23666) (xy 393.283142 -435.22921)
			(xy 393.263559 -435.215024) (xy 393.249308 -435.195489) (xy 393.241781 -435.172509) (xy 393.241276 -435.16042)
			(xy 393.241276 -434.548026) (xy 393.239728 -434.533534) (xy 393.238078 -434.504434) (xy 393.237974 -434.48986)
			(xy 392.335004 -434.48986) (xy 392.335004 -435.489858) (xy 395.23797 -435.489858) (xy 395.238068 -435.475284)
			(xy 395.239717 -435.446183) (xy 395.241272 -435.431692) (xy 395.241272 -434.348128) (xy 395.239724 -434.333636)
			(xy 395.238074 -434.304536) (xy 395.23797 -434.289962) (xy 395.238068 -434.275388) (xy 395.239717 -434.246287)
			(xy 395.241272 -434.231796) (xy 395.241272 -433.618894) (xy 395.241656 -433.606768) (xy 395.249154 -433.583703)
			(xy 395.263413 -433.564085) (xy 395.283039 -433.549835) (xy 395.306107 -433.542349) (xy 395.318234 -433.541932)
			(xy 396.258034 -433.541932) (xy 396.27015 -433.542383) (xy 396.293193 -433.549878) (xy 396.312794 -433.564126)
			(xy 396.327034 -433.583732) (xy 396.334522 -433.606778) (xy 396.334996 -433.618894) (xy 396.334996 -434.48986)
			(xy 398.237964 -434.48986) (xy 398.238077 -434.474774) (xy 398.239856 -434.444656) (xy 398.24152 -434.429662)
			(xy 398.24152 -433.350162) (xy 398.239855 -433.335168) (xy 398.238074 -433.30505) (xy 398.237964 -433.289964)
			(xy 398.238077 -433.274878) (xy 398.239856 -433.24476) (xy 398.24152 -433.229766) (xy 398.24152 -432.618896)
			(xy 398.241909 -432.60681) (xy 398.249382 -432.583823) (xy 398.263593 -432.56427) (xy 398.283151 -432.550067)
			(xy 398.306142 -432.542604) (xy 398.318228 -432.542188) (xy 399.258028 -432.542188) (xy 399.270104 -432.54264)
			(xy 399.293071 -432.55011) (xy 399.312607 -432.56431) (xy 399.326801 -432.58385) (xy 399.334264 -432.60682)
			(xy 399.334736 -432.618896) (xy 399.334736 -435.16042) (xy 399.334253 -435.172493) (xy 399.326788 -435.195456)
			(xy 399.312596 -435.21499) (xy 399.293063 -435.229185) (xy 399.270101 -435.236652) (xy 399.258028 -435.237128)
			(xy 398.318228 -435.237128) (xy 398.306149 -435.236664) (xy 398.28317 -435.229206) (xy 398.263621 -435.215013)
			(xy 398.249416 -435.195473) (xy 398.241944 -435.172499) (xy 398.24152 -435.16042) (xy 398.24152 -434.550058)
			(xy 398.239854 -434.535064) (xy 398.238074 -434.504946) (xy 398.237964 -434.48986) (xy 396.334996 -434.48986)
			(xy 396.334996 -435.489858) (xy 400.23796 -435.489858) (xy 400.238073 -435.474772) (xy 400.239852 -435.444654)
			(xy 400.241516 -435.42966) (xy 400.241516 -434.35016) (xy 400.239851 -434.335166) (xy 400.23807 -434.305048)
			(xy 400.23796 -434.289962) (xy 400.238073 -434.274876) (xy 400.239852 -434.244758) (xy 400.241516 -434.229764)
			(xy 400.241516 -433.618894) (xy 400.242002 -433.606807) (xy 400.249457 -433.58381) (xy 400.26364 -433.564232)
			(xy 400.283168 -433.549981) (xy 400.306138 -433.542445) (xy 400.318224 -433.541932) (xy 401.258024 -433.541932)
			(xy 401.270137 -433.542296) (xy 401.293171 -433.549806) (xy 401.312746 -433.56408) (xy 401.326939 -433.583715)
			(xy 401.334353 -433.606779) (xy 401.334732 -433.618894) (xy 401.334732 -434.48986) (xy 402.237956 -434.48986)
			(xy 402.238069 -434.474774) (xy 402.239848 -434.444656) (xy 402.241512 -434.429662) (xy 402.241512 -433.350162)
			(xy 402.239847 -433.335168) (xy 402.238066 -433.30505) (xy 402.237956 -433.289964) (xy 402.238069 -433.274878)
			(xy 402.239848 -433.24476) (xy 402.241512 -433.229766) (xy 402.241512 -432.618896) (xy 402.241909 -432.606811)
			(xy 402.24938 -432.583825) (xy 402.26359 -432.564273) (xy 402.283146 -432.550069) (xy 402.306135 -432.542606)
			(xy 402.31822 -432.542188) (xy 403.25802 -432.542188) (xy 403.270095 -432.542647) (xy 403.293062 -432.550115)
			(xy 403.312599 -432.564313) (xy 403.326793 -432.583852) (xy 403.334255 -432.606821) (xy 403.334728 -432.618896)
			(xy 403.334728 -435.16042) (xy 403.334253 -435.172494) (xy 403.326787 -435.195458) (xy 403.312593 -435.214993)
			(xy 403.293058 -435.229187) (xy 403.270094 -435.236653) (xy 403.25802 -435.237128) (xy 402.31822 -435.237128)
			(xy 402.306148 -435.236619) (xy 402.283185 -435.229165) (xy 402.26365 -435.214979) (xy 402.249454 -435.195451)
			(xy 402.241987 -435.172491) (xy 402.241512 -435.16042) (xy 402.241512 -434.550058) (xy 402.239846 -434.535064)
			(xy 402.238066 -434.504946) (xy 402.237956 -434.48986) (xy 401.334732 -434.48986) (xy 401.334732 -435.489858)
			(xy 404.237952 -435.489858) (xy 404.238065 -435.474772) (xy 404.239844 -435.444654) (xy 404.241508 -435.42966)
			(xy 404.241508 -434.35016) (xy 404.239843 -434.335166) (xy 404.238062 -434.305048) (xy 404.237952 -434.289962)
			(xy 404.238065 -434.274876) (xy 404.239844 -434.244758) (xy 404.241508 -434.229764) (xy 404.241508 -433.618894)
			(xy 404.242002 -433.606807) (xy 404.249456 -433.583812) (xy 404.263637 -433.564235) (xy 404.283163 -433.549984)
			(xy 404.306131 -433.542446) (xy 404.318216 -433.541932) (xy 405.258016 -433.541932) (xy 405.270129 -433.542303)
			(xy 405.293162 -433.549811) (xy 405.312738 -433.564083) (xy 405.326931 -433.583716) (xy 405.334345 -433.606779)
			(xy 405.334724 -433.618894) (xy 405.334724 -434.48986) (xy 406.237948 -434.48986) (xy 406.238061 -434.474774)
			(xy 406.23984 -434.444656) (xy 406.241504 -434.429662) (xy 406.241504 -433.350162) (xy 406.239839 -433.335168)
			(xy 406.238058 -433.30505) (xy 406.237948 -433.289964) (xy 406.238061 -433.274878) (xy 406.23984 -433.24476)
			(xy 406.241504 -433.229766) (xy 406.241504 -432.618896) (xy 406.241909 -432.606812) (xy 406.249379 -432.583827)
			(xy 406.263587 -432.564276) (xy 406.283141 -432.550072) (xy 406.306128 -432.542607) (xy 406.318212 -432.542188)
			(xy 407.258012 -432.542188) (xy 407.270087 -432.542654) (xy 407.293054 -432.550119) (xy 407.31259 -432.564316)
			(xy 407.326784 -432.583854) (xy 407.334247 -432.606821) (xy 407.33472 -432.618896) (xy 407.33472 -435.16042)
			(xy 407.334253 -435.172494) (xy 407.326786 -435.19546) (xy 407.31259 -435.214996) (xy 407.293053 -435.22919)
			(xy 407.270086 -435.236654) (xy 407.258012 -435.237128) (xy 406.318212 -435.237128) (xy 406.30614 -435.236626)
			(xy 406.283177 -435.229169) (xy 406.263641 -435.214982) (xy 406.249446 -435.195452) (xy 406.241979 -435.172492)
			(xy 406.241504 -435.16042) (xy 406.241504 -434.550058) (xy 406.239838 -434.535064) (xy 406.238058 -434.504946)
			(xy 406.237948 -434.48986) (xy 405.334724 -434.48986) (xy 405.334724 -435.489858) (xy 408.237944 -435.489858)
			(xy 408.238057 -435.474772) (xy 408.239836 -435.444654) (xy 408.2415 -435.42966) (xy 408.2415 -434.35016)
			(xy 408.239834 -434.335166) (xy 408.238054 -434.305048) (xy 408.237944 -434.289962) (xy 408.238057 -434.274876)
			(xy 408.239836 -434.244758) (xy 408.2415 -434.229764) (xy 408.2415 -433.618894) (xy 408.242002 -433.606808)
			(xy 408.249455 -433.583814) (xy 408.263634 -433.564238) (xy 408.283158 -433.549986) (xy 408.306124 -433.542447)
			(xy 408.318208 -433.541932) (xy 409.258008 -433.541932) (xy 409.270121 -433.54231) (xy 409.293154 -433.549815)
			(xy 409.312729 -433.564086) (xy 409.326923 -433.583717) (xy 409.334337 -433.60678) (xy 409.334716 -433.618894)
			(xy 409.334716 -434.48986) (xy 410.23794 -434.48986) (xy 410.238053 -434.474774) (xy 410.239832 -434.444656)
			(xy 410.241496 -434.429662) (xy 410.241496 -433.350162) (xy 410.239831 -433.335168) (xy 410.23805 -433.30505)
			(xy 410.23794 -433.289964) (xy 410.238053 -433.274878) (xy 410.239832 -433.24476) (xy 410.241496 -433.229766)
			(xy 410.241496 -432.618896) (xy 410.241961 -432.606821) (xy 410.249425 -432.583853) (xy 410.263621 -432.564316)
			(xy 410.28316 -432.550121) (xy 410.306129 -432.54266) (xy 410.318204 -432.542188) (xy 411.258004 -432.542188)
			(xy 411.270078 -432.542661) (xy 411.293045 -432.550124) (xy 411.312582 -432.564318) (xy 411.326776 -432.583855)
			(xy 411.334239 -432.606822) (xy 411.334712 -432.618896) (xy 411.334712 -435.16042) (xy 411.334253 -435.172495)
			(xy 411.326785 -435.195462) (xy 411.312587 -435.214999) (xy 411.293048 -435.229193) (xy 411.270079 -435.236655)
			(xy 411.258004 -435.237128) (xy 410.318204 -435.237128) (xy 410.306132 -435.236633) (xy 410.283168 -435.229174)
			(xy 410.263633 -435.214984) (xy 410.249437 -435.195454) (xy 410.241971 -435.172492) (xy 410.241496 -435.16042)
			(xy 410.241496 -434.550058) (xy 410.23983 -434.535064) (xy 410.23805 -434.504946) (xy 410.23794 -434.48986)
			(xy 409.334716 -434.48986) (xy 409.334716 -435.489858) (xy 412.237936 -435.489858) (xy 412.238051 -435.474773)
			(xy 412.23983 -435.444654) (xy 412.241492 -435.42966) (xy 412.241492 -434.35016) (xy 412.239826 -434.335166)
			(xy 412.238046 -434.305048) (xy 412.237936 -434.289962) (xy 412.238051 -434.274877) (xy 412.23983 -434.244758)
			(xy 412.241492 -434.229764) (xy 412.241492 -433.618894) (xy 412.242002 -433.606809) (xy 412.249454 -433.583816)
			(xy 412.263631 -433.564241) (xy 412.283153 -433.549989) (xy 412.306117 -433.542448) (xy 412.3182 -433.541932)
			(xy 413.258 -433.541932) (xy 413.270112 -433.542317) (xy 413.293145 -433.54982) (xy 413.312721 -433.564088)
			(xy 413.326914 -433.583719) (xy 413.334329 -433.60678) (xy 413.334708 -433.618894) (xy 413.334708 -436.160418)
			(xy 413.334209 -436.172504) (xy 413.326753 -436.195497) (xy 413.312573 -436.215072) (xy 413.29305 -436.229324)
			(xy 413.270084 -436.236864) (xy 413.258 -436.23738) (xy 412.3182 -436.23738) (xy 412.306089 -436.236984)
			(xy 412.283058 -436.229482) (xy 412.263483 -436.215216) (xy 412.24929 -436.195589) (xy 412.241872 -436.17253)
			(xy 412.241492 -436.160418) (xy 412.241492 -435.550056) (xy 412.239826 -435.535062) (xy 412.238046 -435.504944)
			(xy 412.237936 -435.489858) (xy 409.334716 -435.489858) (xy 409.334716 -436.160418) (xy 409.334307 -436.172513)
			(xy 409.32684 -436.195522) (xy 409.31264 -436.215105) (xy 409.293092 -436.229353) (xy 409.270102 -436.236877)
			(xy 409.258008 -436.23738) (xy 408.318208 -436.23738) (xy 408.306098 -436.236977) (xy 408.283067 -436.229477)
			(xy 408.263492 -436.215213) (xy 408.249298 -436.195587) (xy 408.24188 -436.17253) (xy 408.2415 -436.160418)
			(xy 408.2415 -435.550056) (xy 408.239834 -435.535062) (xy 408.238054 -435.504944) (xy 408.237944 -435.489858)
			(xy 405.334724 -435.489858) (xy 405.334724 -436.160418) (xy 405.334307 -436.172512) (xy 405.326841 -436.195519)
			(xy 405.312643 -436.215102) (xy 405.293097 -436.229351) (xy 405.270109 -436.236876) (xy 405.258016 -436.23738)
			(xy 404.318216 -436.23738) (xy 404.306106 -436.23697) (xy 404.283076 -436.229472) (xy 404.263501 -436.21521)
			(xy 404.249306 -436.195585) (xy 404.241889 -436.172529) (xy 404.241508 -436.160418) (xy 404.241508 -435.550056)
			(xy 404.239842 -435.535062) (xy 404.238062 -435.504944) (xy 404.237952 -435.489858) (xy 401.334732 -435.489858)
			(xy 401.334732 -436.160418) (xy 401.334308 -436.172511) (xy 401.326843 -436.195517) (xy 401.312646 -436.215099)
			(xy 401.293102 -436.229348) (xy 401.270116 -436.236875) (xy 401.258024 -436.23738) (xy 400.318224 -436.23738)
			(xy 400.306114 -436.236963) (xy 400.283085 -436.229468) (xy 400.263509 -436.215207) (xy 400.249315 -436.195584)
			(xy 400.241897 -436.172529) (xy 400.241516 -436.160418) (xy 400.241516 -435.550056) (xy 400.23985 -435.535062)
			(xy 400.23807 -435.504944) (xy 400.23796 -435.489858) (xy 396.334996 -435.489858) (xy 396.334996 -436.160418)
			(xy 396.334504 -436.17253) (xy 396.327016 -436.195568) (xy 396.312778 -436.215167) (xy 396.293183 -436.229409)
			(xy 396.270146 -436.236902) (xy 396.258034 -436.23738) (xy 395.318234 -436.23738) (xy 395.306115 -436.236911)
			(xy 395.28306 -436.229431) (xy 395.263446 -436.215191) (xy 395.249193 -436.195587) (xy 395.241697 -436.172537)
			(xy 395.241272 -436.160418) (xy 395.241272 -435.548024) (xy 395.239724 -435.533532) (xy 395.238074 -435.504432)
			(xy 395.23797 -435.489858) (xy 392.335004 -435.489858) (xy 392.335004 -436.160418) (xy 392.334504 -436.172529)
			(xy 392.327017 -436.195566) (xy 392.312781 -436.215164) (xy 392.293188 -436.229406) (xy 392.270153 -436.236901)
			(xy 392.258042 -436.23738) (xy 391.318242 -436.23738) (xy 391.306123 -436.236905) (xy 391.283069 -436.229426)
			(xy 391.263455 -436.215188) (xy 391.249201 -436.195585) (xy 391.241705 -436.172536) (xy 391.24128 -436.160418)
			(xy 391.24128 -435.548024) (xy 391.239732 -435.533532) (xy 391.238082 -435.504432) (xy 391.237978 -435.489858)
			(xy 388.335012 -435.489858) (xy 388.335012 -436.160418) (xy 388.334505 -436.172529) (xy 388.327018 -436.195564)
			(xy 388.312784 -436.215161) (xy 388.293193 -436.229404) (xy 388.27016 -436.2369) (xy 388.25805 -436.23738)
			(xy 387.31825 -436.23738) (xy 387.306135 -436.236931) (xy 387.283093 -436.229432) (xy 387.263493 -436.215184)
			(xy 387.249253 -436.195578) (xy 387.241764 -436.172534) (xy 387.241288 -436.160418) (xy 387.241288 -435.548024)
			(xy 387.23974 -435.533532) (xy 387.23809 -435.504432) (xy 387.237986 -435.489858) (xy 384.33502 -435.489858)
			(xy 384.33502 -436.160418) (xy 384.334654 -436.172546) (xy 384.327152 -436.195612) (xy 384.312888 -436.215231)
			(xy 384.293258 -436.22948) (xy 384.270186 -436.236964) (xy 384.258058 -436.23738) (xy 383.318258 -436.23738)
			(xy 383.306143 -436.236924) (xy 383.283101 -436.229428) (xy 383.263502 -436.215181) (xy 383.249261 -436.195577)
			(xy 383.241772 -436.172533) (xy 383.241296 -436.160418) (xy 383.241296 -435.548024) (xy 383.239748 -435.533532)
			(xy 383.238098 -435.504432) (xy 383.237994 -435.489858) (xy 361.616728 -435.489858) (xy 361.642562 -435.536833)
			(xy 361.697938 -435.654184) (xy 361.74595 -435.774736) (xy 361.786412 -435.898026) (xy 361.81917 -436.023584)
			(xy 361.844098 -436.150927) (xy 361.861101 -436.279569) (xy 361.870114 -436.409016) (xy 361.871103 -436.538773)
			(xy 361.864062 -436.668342) (xy 361.849021 -436.797228) (xy 361.826035 -436.924936) (xy 361.795194 -437.050978)
			(xy 361.756614 -437.174871) (xy 361.710445 -437.29614) (xy 361.656862 -437.41432) (xy 361.596072 -437.52896)
			(xy 361.528306 -437.63962) (xy 361.453825 -437.745876) (xy 361.372914 -437.847321) (xy 361.285882 -437.943567)
			(xy 361.193064 -438.034245) (xy 361.128666 -438.089802) (xy 381.21844 -438.089802) (xy 381.218949 -438.057222)
			(xy 381.226923 -437.992551) (xy 381.24274 -437.929339) (xy 381.266163 -437.868533) (xy 381.29684 -437.811045)
			(xy 381.334312 -437.757737) (xy 381.378017 -437.709407) (xy 381.402336 -437.68772) (xy 381.482854 -437.523382)
			(xy 381.487553 -437.512865) (xy 381.491041 -437.490107) (xy 381.487557 -437.467349) (xy 381.482854 -437.456834)
			(xy 381.401828 -437.291734) (xy 381.377559 -437.270044) (xy 381.333961 -437.221711) (xy 381.296587 -437.168419)
			(xy 381.265994 -437.110966) (xy 381.24264 -437.050209) (xy 381.226873 -436.987056) (xy 381.21893 -436.922451)
			(xy 381.21844 -436.889906) (xy 381.219141 -436.85078) (xy 381.230615 -436.773373) (xy 381.2413 -436.735728)
			(xy 381.2413 -436.219092) (xy 381.241709 -436.206983) (xy 381.249211 -436.183955) (xy 381.263474 -436.164382)
			(xy 381.283097 -436.150188) (xy 381.306151 -436.142767) (xy 381.318262 -436.142384) (xy 382.258062 -436.142384)
			(xy 382.270154 -436.142841) (xy 382.293161 -436.150292) (xy 382.312745 -436.16448) (xy 382.326995 -436.184019)
			(xy 382.334521 -436.207002) (xy 382.335024 -436.219092) (xy 382.335024 -438.760616) (xy 382.334598 -438.772723)
			(xy 382.327097 -438.795747) (xy 382.312837 -438.815318) (xy 382.293219 -438.829513) (xy 382.270171 -438.836937)
			(xy 382.258062 -438.837324) (xy 381.318262 -438.837324) (xy 381.306167 -438.836924) (xy 381.283159 -438.829453)
			(xy 381.263577 -438.81525) (xy 381.249329 -438.795701) (xy 381.241804 -438.77271) (xy 381.2413 -438.760616)
			(xy 381.2413 -438.24398) (xy 381.230613 -438.206335) (xy 381.219136 -438.128928) (xy 381.21844 -438.089802)
			(xy 361.128666 -438.089802) (xy 361.094814 -438.119007) (xy 360.991508 -438.19753) (xy 360.883543 -438.269512)
			(xy 360.771333 -438.334677) (xy 360.655306 -438.392776) (xy 360.535907 -438.443587) (xy 360.413594 -438.486915)
			(xy 360.288835 -438.522593) (xy 360.162108 -438.550485) (xy 360.033898 -438.570485) (xy 359.904696 -438.582516)
			(xy 359.774998 -438.586531) (xy 359.6453 -438.582516) (xy 359.516098 -438.570485) (xy 359.387888 -438.550485)
			(xy 359.261161 -438.522593) (xy 359.136402 -438.486915) (xy 359.014089 -438.443587) (xy 358.89469 -438.392776)
			(xy 358.778663 -438.334677) (xy 358.666453 -438.269512) (xy 358.558488 -438.19753) (xy 358.455182 -438.119007)
			(xy 358.356932 -438.034245) (xy 358.264114 -437.943567) (xy 358.177082 -437.847321) (xy 358.096171 -437.745876)
			(xy 358.02169 -437.63962) (xy 357.953924 -437.52896) (xy 357.893134 -437.41432) (xy 357.839551 -437.29614)
			(xy 357.793382 -437.174871) (xy 357.754802 -437.050978) (xy 357.723961 -436.924936) (xy 357.700975 -436.797228)
			(xy 357.685934 -436.668342) (xy 357.678893 -436.538773) (xy 357.679882 -436.409016) (xy 357.688895 -436.279569)
			(xy 357.705898 -436.150927) (xy 357.730826 -436.023584) (xy 357.763584 -435.898026) (xy 357.804046 -435.774736)
			(xy 357.852058 -435.654184) (xy 357.907434 -435.536833) (xy 357.969964 -435.423133) (xy 358.039407 -435.313518)
			(xy 358.115498 -435.208409) (xy 358.197945 -435.108208) (xy 358.286433 -435.013299) (xy 358.380622 -434.924045)
			(xy 358.430068 -434.882036) (xy 358.441235 -434.872067) (xy 358.457661 -434.847056) (xy 358.466134 -434.818358)
			(xy 358.465926 -434.788437) (xy 358.457055 -434.759859) (xy 358.440283 -434.735079) (xy 358.417049 -434.716224)
			(xy 358.403398 -434.710078) (xy 358.324356 -434.677212) (xy 358.169157 -434.604934) (xy 358.017549 -434.5254)
			(xy 357.869871 -434.438788) (xy 357.726451 -434.345291) (xy 357.587612 -434.24512) (xy 357.453663 -434.138498)
			(xy 357.324904 -434.025662) (xy 357.201623 -433.906867) (xy 357.084096 -433.782376) (xy 356.972584 -433.652469)
			(xy 356.867339 -433.517435) (xy 356.768594 -433.377578) (xy 356.676571 -433.233209) (xy 356.591476 -433.084651)
			(xy 356.513498 -432.932237) (xy 356.442812 -432.776307) (xy 356.379576 -432.61721) (xy 356.323932 -432.455301)
			(xy 356.276004 -432.290943) (xy 356.235899 -432.124503) (xy 356.203706 -431.956354) (xy 356.179498 -431.78687)
			(xy 356.163329 -431.616432) (xy 356.155235 -431.44542) (xy 356.154736 -431.359818) (xy 346.23502 -431.359818)
			(xy 346.23502 -432.560476) (xy 346.234563 -432.572582) (xy 346.227073 -432.595605) (xy 346.212821 -432.615176)
			(xy 346.193209 -432.629373) (xy 346.170165 -432.636797) (xy 346.158058 -432.637184) (xy 345.218258 -432.637184)
			(xy 345.206169 -432.636729) (xy 345.183171 -432.629264) (xy 345.163593 -432.615073) (xy 345.149343 -432.595539)
			(xy 345.141808 -432.572564) (xy 345.141296 -432.560476) (xy 345.141296 -431.948082) (xy 345.139753 -431.93359)
			(xy 345.1381 -431.90449) (xy 345.137994 -431.889916) (xy 342.235028 -431.889916) (xy 342.235028 -432.560476)
			(xy 342.234563 -432.572581) (xy 342.227074 -432.595602) (xy 342.212824 -432.615174) (xy 342.193214 -432.62937)
			(xy 342.170172 -432.636796) (xy 342.158066 -432.637184) (xy 341.218266 -432.637184) (xy 341.206177 -432.636722)
			(xy 341.183179 -432.629259) (xy 341.163602 -432.61507) (xy 341.149352 -432.595538) (xy 341.141816 -432.572563)
			(xy 341.141304 -432.560476) (xy 341.141304 -431.948082) (xy 341.13976 -431.93359) (xy 341.138108 -431.90449)
			(xy 341.138002 -431.889916) (xy 338.235036 -431.889916) (xy 338.235036 -432.560476) (xy 338.234564 -432.57258)
			(xy 338.227075 -432.5956) (xy 338.212827 -432.615171) (xy 338.193219 -432.629367) (xy 338.170179 -432.636795)
			(xy 338.158074 -432.637184) (xy 337.218274 -432.637184) (xy 337.206185 -432.636715) (xy 337.183188 -432.629254)
			(xy 337.163611 -432.615067) (xy 337.14936 -432.595536) (xy 337.141824 -432.572563) (xy 337.141312 -432.560476)
			(xy 337.141312 -431.948082) (xy 337.139768 -431.93359) (xy 337.138116 -431.90449) (xy 337.13801 -431.889916)
			(xy 334.235044 -431.889916) (xy 334.235044 -432.560476) (xy 334.234564 -432.572579) (xy 334.227076 -432.595598)
			(xy 334.21283 -432.615168) (xy 334.193224 -432.629365) (xy 334.170186 -432.636794) (xy 334.158082 -432.637184)
			(xy 333.218282 -432.637184) (xy 333.206194 -432.636709) (xy 333.183197 -432.62925) (xy 333.163619 -432.615065)
			(xy 333.149368 -432.595535) (xy 333.141832 -432.572563) (xy 333.14132 -432.560476) (xy 333.14132 -431.948082)
			(xy 333.139776 -431.93359) (xy 333.138124 -431.90449) (xy 333.138018 -431.889916) (xy 329.2348 -431.889916)
			(xy 329.2348 -432.560476) (xy 329.234367 -432.572558) (xy 329.226905 -432.595542) (xy 329.212704 -432.615093)
			(xy 329.193156 -432.629297) (xy 329.170174 -432.636764) (xy 329.158092 -432.637184) (xy 328.218292 -432.637184)
			(xy 328.206206 -432.636794) (xy 328.183219 -432.629321) (xy 328.163667 -432.61511) (xy 328.149464 -432.595552)
			(xy 328.142001 -432.572562) (xy 328.141584 -432.560476) (xy 328.141584 -431.950114) (xy 328.139914 -431.935121)
			(xy 328.138137 -431.905002) (xy 328.138028 -431.889916) (xy 325.234808 -431.889916) (xy 325.234808 -432.560476)
			(xy 325.234367 -432.572557) (xy 325.226906 -432.595539) (xy 325.212707 -432.61509) (xy 325.193161 -432.629295)
			(xy 325.170181 -432.636763) (xy 325.1581 -432.637184) (xy 324.2183 -432.637184) (xy 324.206215 -432.636787)
			(xy 324.183228 -432.629317) (xy 324.163676 -432.615107) (xy 324.149472 -432.59555) (xy 324.142009 -432.572561)
			(xy 324.141592 -432.560476) (xy 324.141592 -431.950114) (xy 324.139922 -431.935121) (xy 324.138145 -431.905002)
			(xy 324.138036 -431.889916) (xy 321.234816 -431.889916) (xy 321.234816 -432.560476) (xy 321.234367 -432.572557)
			(xy 321.226907 -432.595537) (xy 321.21271 -432.615087) (xy 321.193166 -432.629292) (xy 321.170188 -432.636762)
			(xy 321.158108 -432.637184) (xy 320.218308 -432.637184) (xy 320.206223 -432.63678) (xy 320.183237 -432.629312)
			(xy 320.163684 -432.615105) (xy 320.149481 -432.595549) (xy 320.142017 -432.572561) (xy 320.1416 -432.560476)
			(xy 320.1416 -431.950114) (xy 320.13993 -431.935121) (xy 320.138153 -431.905002) (xy 320.138044 -431.889916)
			(xy 317.234824 -431.889916) (xy 317.234824 -432.560476) (xy 317.234367 -432.572556) (xy 317.226908 -432.595535)
			(xy 317.212713 -432.615084) (xy 317.193171 -432.62929) (xy 317.170196 -432.636761) (xy 317.158116 -432.637184)
			(xy 316.218316 -432.637184) (xy 316.206232 -432.636773) (xy 316.183246 -432.629307) (xy 316.163693 -432.615101)
			(xy 316.149489 -432.595547) (xy 316.142026 -432.57256) (xy 316.141608 -432.560476) (xy 316.141608 -431.950114)
			(xy 316.139938 -431.935121) (xy 316.138161 -431.905002) (xy 316.138052 -431.889916) (xy 274.613204 -431.889916)
			(xy 274.618425 -431.905986) (xy 274.665585 -432.076867) (xy 274.705031 -432.249692) (xy 274.736684 -432.424113)
			(xy 274.760479 -432.599778) (xy 274.77637 -432.776334) (xy 274.784323 -432.953425) (xy 274.78482 -433.04206)
			(xy 274.784323 -433.130695) (xy 274.77637 -433.307786) (xy 274.760479 -433.484342) (xy 274.736684 -433.660007)
			(xy 274.705031 -433.834428) (xy 274.665585 -434.007253) (xy 274.618425 -434.178134) (xy 274.563646 -434.346728)
			(xy 274.509927 -434.48986) (xy 314.118498 -434.48986) (xy 314.118984 -434.457304) (xy 314.126934 -434.392678)
			(xy 314.142721 -434.329509) (xy 314.166111 -434.268742) (xy 314.196751 -434.21129) (xy 314.234182 -434.158012)
			(xy 314.277844 -434.109708) (xy 314.30214 -434.088032) (xy 314.382912 -433.923186) (xy 314.38761 -433.912668)
			(xy 314.391101 -433.889911) (xy 314.387617 -433.867152) (xy 314.382912 -433.856638) (xy 314.30214 -433.691792)
			(xy 314.277865 -433.670094) (xy 314.23421 -433.621789) (xy 314.196782 -433.568513) (xy 314.166143 -433.511064)
			(xy 314.14275 -433.450303) (xy 314.126955 -433.387139) (xy 314.118994 -433.322518) (xy 314.118498 -433.289964)
			(xy 314.119225 -433.250639) (xy 314.13083 -433.172849) (xy 314.141612 -433.135024) (xy 314.141612 -432.618896)
			(xy 314.142009 -432.606811) (xy 314.14948 -432.583825) (xy 314.16369 -432.564273) (xy 314.183246 -432.550069)
			(xy 314.206235 -432.542606) (xy 314.21832 -432.542188) (xy 315.15812 -432.542188) (xy 315.170195 -432.542647)
			(xy 315.193162 -432.550115) (xy 315.212699 -432.564313) (xy 315.226893 -432.583852) (xy 315.234355 -432.606821)
			(xy 315.234828 -432.618896) (xy 315.234828 -435.16042) (xy 315.234353 -435.172494) (xy 315.226887 -435.195458)
			(xy 315.212693 -435.214993) (xy 315.193158 -435.229187) (xy 315.170194 -435.236653) (xy 315.15812 -435.237128)
			(xy 314.21832 -435.237128) (xy 314.206248 -435.236619) (xy 314.183285 -435.229165) (xy 314.16375 -435.214979)
			(xy 314.149554 -435.195451) (xy 314.142087 -435.172491) (xy 314.141612 -435.16042) (xy 314.141612 -434.6448)
			(xy 314.130805 -434.606981) (xy 314.119203 -434.529187) (xy 314.118498 -434.48986) (xy 274.509927 -434.48986)
			(xy 274.501358 -434.512693) (xy 274.431686 -434.675698) (xy 274.354772 -434.835412) (xy 274.270769 -434.991515)
			(xy 274.179848 -435.143692) (xy 274.082191 -435.291636) (xy 273.977994 -435.43505) (xy 273.934286 -435.489858)
			(xy 316.118494 -435.489858) (xy 316.118945 -435.4573) (xy 316.126897 -435.392672) (xy 316.142688 -435.329501)
			(xy 316.166082 -435.268733) (xy 316.196728 -435.211281) (xy 316.234166 -435.158004) (xy 316.277836 -435.109703)
			(xy 316.302136 -435.08803) (xy 316.382908 -434.923184) (xy 316.387608 -434.912667) (xy 316.391098 -434.889909)
			(xy 316.387613 -434.86715) (xy 316.382908 -434.856636) (xy 316.302136 -434.69179) (xy 316.27786 -434.670094)
			(xy 316.234205 -434.621788) (xy 316.196777 -434.568512) (xy 316.166138 -434.511063) (xy 316.142745 -434.450301)
			(xy 316.126951 -434.387137) (xy 316.11899 -434.322516) (xy 316.118494 -434.289962) (xy 316.119221 -434.250637)
			(xy 316.130826 -434.172847) (xy 316.141608 -434.135022) (xy 316.141608 -433.618894) (xy 316.142102 -433.606807)
			(xy 316.149556 -433.583812) (xy 316.163737 -433.564235) (xy 316.183263 -433.549984) (xy 316.206231 -433.542446)
			(xy 316.218316 -433.541932) (xy 317.158116 -433.541932) (xy 317.170229 -433.542303) (xy 317.193262 -433.549811)
			(xy 317.212838 -433.564083) (xy 317.227031 -433.583716) (xy 317.234445 -433.606779) (xy 317.234824 -433.618894)
			(xy 317.234824 -434.48986) (xy 318.11849 -434.48986) (xy 318.118944 -434.457302) (xy 318.126896 -434.392675)
			(xy 318.142686 -434.329503) (xy 318.16608 -434.268736) (xy 318.196725 -434.211283) (xy 318.234163 -434.158007)
			(xy 318.277832 -434.109705) (xy 318.302132 -434.088032) (xy 318.382904 -433.923186) (xy 318.387603 -433.912668)
			(xy 318.391094 -433.889911) (xy 318.387609 -433.867152) (xy 318.382904 -433.856638) (xy 318.302132 -433.691792)
			(xy 318.277856 -433.670096) (xy 318.234201 -433.62179) (xy 318.196773 -433.568514) (xy 318.166134 -433.511065)
			(xy 318.142742 -433.450303) (xy 318.126947 -433.387139) (xy 318.118986 -433.322518) (xy 318.11849 -433.289964)
			(xy 318.119218 -433.250639) (xy 318.130822 -433.172849) (xy 318.141604 -433.135024) (xy 318.141604 -432.618896)
			(xy 318.142009 -432.606812) (xy 318.149479 -432.583827) (xy 318.163687 -432.564276) (xy 318.183241 -432.550072)
			(xy 318.206228 -432.542607) (xy 318.218312 -432.542188) (xy 319.158112 -432.542188) (xy 319.170187 -432.542654)
			(xy 319.193154 -432.550119) (xy 319.21269 -432.564316) (xy 319.226884 -432.583854) (xy 319.234347 -432.606821)
			(xy 319.23482 -432.618896) (xy 319.23482 -435.16042) (xy 319.234353 -435.172494) (xy 319.226886 -435.19546)
			(xy 319.21269 -435.214996) (xy 319.193153 -435.22919) (xy 319.170186 -435.236654) (xy 319.158112 -435.237128)
			(xy 318.218312 -435.237128) (xy 318.20624 -435.236626) (xy 318.183277 -435.229169) (xy 318.163741 -435.214982)
			(xy 318.149546 -435.195452) (xy 318.142079 -435.172492) (xy 318.141604 -435.16042) (xy 318.141604 -434.6448)
			(xy 318.130797 -434.606981) (xy 318.119195 -434.529187) (xy 318.11849 -434.48986) (xy 317.234824 -434.48986)
			(xy 317.234824 -435.489858) (xy 320.118486 -435.489858) (xy 320.11894 -435.4573) (xy 320.126892 -435.392673)
			(xy 320.142683 -435.329502) (xy 320.166076 -435.268734) (xy 320.196722 -435.211281) (xy 320.234159 -435.158005)
			(xy 320.277828 -435.109703) (xy 320.302128 -435.08803) (xy 320.3829 -434.923184) (xy 320.3876 -434.912667)
			(xy 320.391091 -434.889909) (xy 320.387606 -434.86715) (xy 320.3829 -434.856636) (xy 320.302128 -434.69179)
			(xy 320.27785 -434.670096) (xy 320.234195 -434.62179) (xy 320.196768 -434.568513) (xy 320.166129 -434.511063)
			(xy 320.142737 -434.450301) (xy 320.126942 -434.387137) (xy 320.118982 -434.322517) (xy 320.118486 -434.289962)
			(xy 320.119213 -434.250637) (xy 320.130818 -434.172847) (xy 320.1416 -434.135022) (xy 320.1416 -433.618894)
			(xy 320.142102 -433.606808) (xy 320.149555 -433.583814) (xy 320.163734 -433.564238) (xy 320.183258 -433.549986)
			(xy 320.206224 -433.542447) (xy 320.218308 -433.541932) (xy 321.158108 -433.541932) (xy 321.170221 -433.54231)
			(xy 321.193254 -433.549815) (xy 321.212829 -433.564086) (xy 321.227023 -433.583717) (xy 321.234437 -433.60678)
			(xy 321.234816 -433.618894) (xy 321.234816 -434.48986) (xy 322.118482 -434.48986) (xy 322.118939 -434.457303)
			(xy 322.12689 -434.392675) (xy 322.142681 -434.329504) (xy 322.166074 -434.268736) (xy 322.196719 -434.211284)
			(xy 322.234156 -434.158007) (xy 322.277824 -434.109706) (xy 322.302124 -434.088032) (xy 322.382896 -433.923186)
			(xy 322.387595 -433.912668) (xy 322.391086 -433.889911) (xy 322.387602 -433.867152) (xy 322.382896 -433.856638)
			(xy 322.302124 -433.691792) (xy 322.277846 -433.670097) (xy 322.234192 -433.621791) (xy 322.196765 -433.568515)
			(xy 322.166126 -433.511065) (xy 322.142734 -433.450303) (xy 322.126939 -433.387139) (xy 322.118978 -433.322518)
			(xy 322.118482 -433.289964) (xy 322.11921 -433.250639) (xy 322.130814 -433.172849) (xy 322.141596 -433.135024)
			(xy 322.141596 -432.618896) (xy 322.142061 -432.606821) (xy 322.149525 -432.583853) (xy 322.163721 -432.564316)
			(xy 322.18326 -432.550121) (xy 322.206229 -432.54266) (xy 322.218304 -432.542188) (xy 323.158104 -432.542188)
			(xy 323.170178 -432.542661) (xy 323.193145 -432.550124) (xy 323.212682 -432.564318) (xy 323.226876 -432.583855)
			(xy 323.234339 -432.606822) (xy 323.234812 -432.618896) (xy 323.234812 -435.16042) (xy 323.234353 -435.172495)
			(xy 323.226885 -435.195462) (xy 323.212687 -435.214999) (xy 323.193148 -435.229193) (xy 323.170179 -435.236655)
			(xy 323.158104 -435.237128) (xy 322.218304 -435.237128) (xy 322.206232 -435.236633) (xy 322.183268 -435.229174)
			(xy 322.163733 -435.214984) (xy 322.149537 -435.195454) (xy 322.142071 -435.172492) (xy 322.141596 -435.16042)
			(xy 322.141596 -434.6448) (xy 322.130788 -434.606981) (xy 322.119187 -434.529187) (xy 322.118482 -434.48986)
			(xy 321.234816 -434.48986) (xy 321.234816 -435.489858) (xy 324.118478 -435.489858) (xy 324.118935 -435.457301)
			(xy 324.126886 -435.392673) (xy 324.142677 -435.329502) (xy 324.16607 -435.268734) (xy 324.196715 -435.211282)
			(xy 324.234152 -435.158005) (xy 324.27782 -435.109704) (xy 324.30212 -435.08803) (xy 324.382892 -434.923184)
			(xy 324.387593 -434.912667) (xy 324.391084 -434.889909) (xy 324.387598 -434.86715) (xy 324.382892 -434.856636)
			(xy 324.30212 -434.69179) (xy 324.27784 -434.670097) (xy 324.234186 -434.621791) (xy 324.196759 -434.568514)
			(xy 324.166121 -434.511064) (xy 324.142729 -434.450302) (xy 324.126934 -434.387137) (xy 324.118974 -434.322517)
			(xy 324.118478 -434.289962) (xy 324.119206 -434.250637) (xy 324.13081 -434.172847) (xy 324.141592 -434.135022)
			(xy 324.141592 -433.618894) (xy 324.142102 -433.606809) (xy 324.149554 -433.583816) (xy 324.163731 -433.564241)
			(xy 324.183253 -433.549989) (xy 324.206217 -433.542448) (xy 324.2183 -433.541932) (xy 325.1581 -433.541932)
			(xy 325.170212 -433.542317) (xy 325.193245 -433.54982) (xy 325.212821 -433.564088) (xy 325.227014 -433.583719)
			(xy 325.234429 -433.60678) (xy 325.234808 -433.618894) (xy 325.234808 -434.48986) (xy 326.118474 -434.48986)
			(xy 326.118934 -434.457303) (xy 326.126885 -434.392675) (xy 326.142675 -434.329504) (xy 326.166068 -434.268737)
			(xy 326.196712 -434.211284) (xy 326.234149 -434.158007) (xy 326.277816 -434.109706) (xy 326.302116 -434.088032)
			(xy 326.382888 -433.923186) (xy 326.387588 -433.912669) (xy 326.391079 -433.889911) (xy 326.387594 -433.867152)
			(xy 326.382888 -433.856638) (xy 326.302116 -433.691792) (xy 326.277837 -433.670099) (xy 326.234182 -433.621793)
			(xy 326.196756 -433.568516) (xy 326.166117 -433.511066) (xy 326.142725 -433.450304) (xy 326.126931 -433.387139)
			(xy 326.11897 -433.322519) (xy 326.118474 -433.289964) (xy 326.119202 -433.250639) (xy 326.130807 -433.172849)
			(xy 326.141588 -433.135024) (xy 326.141588 -432.618896) (xy 326.142061 -432.606822) (xy 326.149524 -432.583855)
			(xy 326.163718 -432.564318) (xy 326.183255 -432.550124) (xy 326.206222 -432.542661) (xy 326.218296 -432.542188)
			(xy 327.158096 -432.542188) (xy 327.17017 -432.542668) (xy 327.193136 -432.550129) (xy 327.212673 -432.564321)
			(xy 327.226868 -432.583857) (xy 327.234331 -432.606822) (xy 327.234804 -432.618896) (xy 327.234804 -435.16042)
			(xy 327.234353 -435.172496) (xy 327.226884 -435.195464) (xy 327.212684 -435.215001) (xy 327.193143 -435.229195)
			(xy 327.170172 -435.236656) (xy 327.158096 -435.237128) (xy 326.218296 -435.237128) (xy 326.206223 -435.236639)
			(xy 326.183259 -435.229178) (xy 326.163724 -435.214987) (xy 326.149529 -435.195455) (xy 326.142063 -435.172493)
			(xy 326.141588 -435.16042) (xy 326.141588 -434.6448) (xy 326.13078 -434.606981) (xy 326.119179 -434.529187)
			(xy 326.118474 -434.48986) (xy 325.234808 -434.48986) (xy 325.234808 -435.489858) (xy 328.11847 -435.489858)
			(xy 328.11893 -435.457301) (xy 328.126881 -435.392673) (xy 328.142671 -435.329503) (xy 328.166064 -435.268735)
			(xy 328.196709 -435.211282) (xy 328.234145 -435.158006) (xy 328.277813 -435.109704) (xy 328.302112 -435.08803)
			(xy 328.382884 -434.923184) (xy 328.387585 -434.912667) (xy 328.391077 -434.889909) (xy 328.387591 -434.86715)
			(xy 328.382884 -434.856636) (xy 328.302112 -434.69179) (xy 328.277831 -434.670099) (xy 328.234177 -434.621792)
			(xy 328.196751 -434.568515) (xy 328.166112 -434.511065) (xy 328.142721 -434.450302) (xy 328.126926 -434.387138)
			(xy 328.118966 -434.322517) (xy 328.11847 -434.289962) (xy 328.119198 -434.250637) (xy 328.130803 -434.172847)
			(xy 328.141584 -434.135022) (xy 328.141584 -433.618894) (xy 328.142003 -433.6068) (xy 328.149467 -433.583792)
			(xy 328.163664 -433.564208) (xy 328.183211 -433.549959) (xy 328.206199 -433.542435) (xy 328.218292 -433.541932)
			(xy 329.158092 -433.541932) (xy 329.170204 -433.542323) (xy 329.193236 -433.549824) (xy 329.212812 -433.564091)
			(xy 329.227006 -433.58372) (xy 329.234421 -433.606781) (xy 329.2348 -433.618894) (xy 329.2348 -434.48986)
			(xy 331.118464 -434.48986) (xy 331.118927 -434.457303) (xy 331.126878 -434.392676) (xy 331.142668 -434.329505)
			(xy 331.16606 -434.268738) (xy 331.196704 -434.211285) (xy 331.23414 -434.158008) (xy 331.277807 -434.109706)
			(xy 331.302106 -434.088032) (xy 331.382878 -433.923186) (xy 331.387578 -433.912669) (xy 331.39107 -433.889911)
			(xy 331.387585 -433.867152) (xy 331.382878 -433.856638) (xy 331.302106 -433.691792) (xy 331.277825 -433.670101)
			(xy 331.234171 -433.621794) (xy 331.196745 -433.568517) (xy 331.166106 -433.511066) (xy 331.142715 -433.450304)
			(xy 331.126921 -433.387139) (xy 331.11896 -433.322519) (xy 331.118464 -433.289964) (xy 331.119155 -433.250837)
			(xy 331.130636 -433.173431) (xy 331.141324 -433.135786) (xy 331.141324 -432.618896) (xy 331.141713 -432.606785)
			(xy 331.149217 -432.583753) (xy 331.163484 -432.564178) (xy 331.183113 -432.549984) (xy 331.206173 -432.542568)
			(xy 331.218286 -432.542188) (xy 332.158086 -432.542188) (xy 332.17018 -432.54262) (xy 332.193188 -432.550079)
			(xy 332.212772 -432.564273) (xy 332.227021 -432.583817) (xy 332.234545 -432.606804) (xy 332.235048 -432.618896)
			(xy 332.235048 -435.16042) (xy 332.234601 -435.172525) (xy 332.227102 -435.195545) (xy 332.212847 -435.215113)
			(xy 332.193235 -435.229309) (xy 332.170192 -435.236738) (xy 332.158086 -435.237128) (xy 331.218286 -435.237128)
			(xy 331.206192 -435.236704) (xy 331.183186 -435.22924) (xy 331.163603 -435.215043) (xy 331.149354 -435.195499)
			(xy 331.141828 -435.172512) (xy 331.141324 -435.16042) (xy 331.141324 -434.644038) (xy 331.130628 -434.606395)
			(xy 331.119157 -434.528987) (xy 331.118464 -434.48986) (xy 329.2348 -434.48986) (xy 329.2348 -435.489858)
			(xy 333.11846 -435.489858) (xy 333.118923 -435.457301) (xy 333.126874 -435.392674) (xy 333.142664 -435.329503)
			(xy 333.166057 -435.268736) (xy 333.1967 -435.211283) (xy 333.234136 -435.158006) (xy 333.277803 -435.109704)
			(xy 333.302102 -435.08803) (xy 333.382874 -434.923184) (xy 333.387576 -434.912667) (xy 333.391068 -434.889909)
			(xy 333.387581 -434.86715) (xy 333.382874 -434.856636) (xy 333.302102 -434.69179) (xy 333.277819 -434.670101)
			(xy 333.234165 -434.621794) (xy 333.196739 -434.568516) (xy 333.166101 -434.511065) (xy 333.14271 -434.450303)
			(xy 333.126916 -434.387138) (xy 333.118956 -434.322517) (xy 333.11846 -434.289962) (xy 333.119151 -434.250835)
			(xy 333.130632 -434.173429) (xy 333.14132 -434.135784) (xy 333.14132 -433.618894) (xy 333.141807 -433.606781)
			(xy 333.149293 -433.583741) (xy 333.163532 -433.564141) (xy 333.18313 -433.549899) (xy 333.206169 -433.542408)
			(xy 333.218282 -433.541932) (xy 334.158082 -433.541932) (xy 334.170203 -433.542375) (xy 334.19326 -433.549862)
			(xy 334.212875 -433.564108) (xy 334.227127 -433.583718) (xy 334.234621 -433.606773) (xy 334.235044 -433.618894)
			(xy 334.235044 -434.48986) (xy 335.118456 -434.48986) (xy 335.118922 -434.457303) (xy 335.126873 -434.392676)
			(xy 335.142662 -434.329505) (xy 335.166054 -434.268738) (xy 335.196698 -434.211285) (xy 335.234133 -434.158008)
			(xy 335.277799 -434.109706) (xy 335.302098 -434.088032) (xy 335.38287 -433.923186) (xy 335.387571 -433.912669)
			(xy 335.391063 -433.889911) (xy 335.387577 -433.867152) (xy 335.38287 -433.856638) (xy 335.302098 -433.691792)
			(xy 335.277815 -433.670103) (xy 335.234162 -433.621796) (xy 335.196736 -433.568518) (xy 335.166098 -433.511067)
			(xy 335.142707 -433.450304) (xy 335.126912 -433.38714) (xy 335.118952 -433.322519) (xy 335.118456 -433.289964)
			(xy 335.119147 -433.250837) (xy 335.130628 -433.173431) (xy 335.141316 -433.135786) (xy 335.141316 -432.618896)
			(xy 335.141713 -432.606785) (xy 335.149215 -432.583755) (xy 335.163481 -432.564181) (xy 335.183108 -432.549987)
			(xy 335.206166 -432.542569) (xy 335.218278 -432.542188) (xy 336.158078 -432.542188) (xy 336.170171 -432.542627)
			(xy 336.193179 -432.550084) (xy 336.212764 -432.564276) (xy 336.227013 -432.583818) (xy 336.234537 -432.606804)
			(xy 336.23504 -432.618896) (xy 336.23504 -435.16042) (xy 336.234601 -435.172526) (xy 336.227101 -435.195547)
			(xy 336.212844 -435.215116) (xy 336.19323 -435.229312) (xy 336.170185 -435.236739) (xy 336.158078 -435.237128)
			(xy 335.218278 -435.237128) (xy 335.206184 -435.236711) (xy 335.183177 -435.229244) (xy 335.163595 -435.215046)
			(xy 335.149346 -435.1955) (xy 335.14182 -435.172513) (xy 335.141316 -435.16042) (xy 335.141316 -434.644038)
			(xy 335.13062 -434.606395) (xy 335.119149 -434.528987) (xy 335.118456 -434.48986) (xy 334.235044 -434.48986)
			(xy 334.235044 -435.489858) (xy 337.118452 -435.489858) (xy 337.118918 -435.457301) (xy 337.126869 -435.392674)
			(xy 337.142659 -435.329504) (xy 337.166051 -435.268736) (xy 337.196694 -435.211284) (xy 337.234129 -435.158007)
			(xy 337.277795 -435.109704) (xy 337.302094 -435.08803) (xy 337.382866 -434.923184) (xy 337.387563 -434.912666)
			(xy 337.391051 -434.889909) (xy 337.387568 -434.867151) (xy 337.382866 -434.856636) (xy 337.302094 -434.69179)
			(xy 337.277809 -434.670103) (xy 337.234156 -434.621795) (xy 337.196731 -434.568517) (xy 337.166093 -434.511066)
			(xy 337.142702 -434.450303) (xy 337.126908 -434.387138) (xy 337.118948 -434.322517) (xy 337.118452 -434.289962)
			(xy 337.119143 -434.250835) (xy 337.130624 -434.173429) (xy 337.141312 -434.135784) (xy 337.141312 -433.618894)
			(xy 337.141806 -433.606782) (xy 337.149292 -433.583743) (xy 337.163529 -433.564143) (xy 337.183125 -433.549901)
			(xy 337.206162 -433.54241) (xy 337.218274 -433.541932) (xy 338.158074 -433.541932) (xy 338.170195 -433.542382)
			(xy 338.193252 -433.549866) (xy 338.212867 -433.56411) (xy 338.227119 -433.58372) (xy 338.234613 -433.606773)
			(xy 338.235036 -433.618894) (xy 338.235036 -434.48986) (xy 339.118448 -434.48986) (xy 339.118917 -434.457303)
			(xy 339.126867 -434.392676) (xy 339.142657 -434.329506) (xy 339.166048 -434.268739) (xy 339.196691 -434.211286)
			(xy 339.234126 -434.158009) (xy 339.277792 -434.109706) (xy 339.30209 -434.088032) (xy 339.382862 -433.923186)
			(xy 339.387558 -433.912668) (xy 339.391046 -433.889911) (xy 339.387564 -433.867153) (xy 339.382862 -433.856638)
			(xy 339.30209 -433.691792) (xy 339.277805 -433.670105) (xy 339.234152 -433.621797) (xy 339.196727 -433.568518)
			(xy 339.166089 -433.511068) (xy 339.142698 -433.450305) (xy 339.126904 -433.38714) (xy 339.118944 -433.322519)
			(xy 339.118448 -433.289964) (xy 339.11914 -433.250837) (xy 339.13062 -433.173431) (xy 339.141308 -433.135786)
			(xy 339.141308 -432.618896) (xy 339.141713 -432.606786) (xy 339.149214 -432.583757) (xy 339.163479 -432.564184)
			(xy 339.183103 -432.549989) (xy 339.206159 -432.54257) (xy 339.21827 -432.542188) (xy 340.15807 -432.542188)
			(xy 340.170163 -432.542634) (xy 340.19317 -432.550088) (xy 340.212755 -432.564278) (xy 340.227005 -432.58382)
			(xy 340.234529 -432.606805) (xy 340.235032 -432.618896) (xy 340.235032 -435.16042) (xy 340.234601 -435.172527)
			(xy 340.2271 -435.195549) (xy 340.212841 -435.215119) (xy 340.193225 -435.229314) (xy 340.170178 -435.23674)
			(xy 340.15807 -435.237128) (xy 339.21827 -435.237128) (xy 339.206176 -435.236718) (xy 339.183169 -435.229249)
			(xy 339.163586 -435.215049) (xy 339.149338 -435.195502) (xy 339.141812 -435.172513) (xy 339.141308 -435.16042)
			(xy 339.141308 -434.644038) (xy 339.130612 -434.606395) (xy 339.119141 -434.528987) (xy 339.118448 -434.48986)
			(xy 338.235036 -434.48986) (xy 338.235036 -435.489858) (xy 341.118444 -435.489858) (xy 341.118913 -435.457301)
			(xy 341.126863 -435.392674) (xy 341.142653 -435.329504) (xy 341.166045 -435.268737) (xy 341.196687 -435.211284)
			(xy 341.234122 -435.158007) (xy 341.277788 -435.109704) (xy 341.302086 -435.08803) (xy 341.382858 -434.923184)
			(xy 341.387556 -434.912666) (xy 341.391043 -434.889909) (xy 341.387561 -434.867151) (xy 341.382858 -434.856636)
			(xy 341.302086 -434.69179) (xy 341.2778 -434.670105) (xy 341.234147 -434.621796) (xy 341.196722 -434.568518)
			(xy 341.166084 -434.511066) (xy 341.142694 -434.450303) (xy 341.1269 -434.387138) (xy 341.11894 -434.322517)
			(xy 341.118444 -434.289962) (xy 341.119135 -434.250835) (xy 341.130616 -434.173429) (xy 341.141304 -434.135784)
			(xy 341.141304 -433.618894) (xy 341.141806 -433.606783) (xy 341.149291 -433.583745) (xy 341.163526 -433.564146)
			(xy 341.18312 -433.549904) (xy 341.206155 -433.542411) (xy 341.218266 -433.541932) (xy 342.158066 -433.541932)
			(xy 342.170186 -433.542389) (xy 342.193243 -433.549871) (xy 342.212858 -433.564113) (xy 342.227111 -433.583721)
			(xy 342.234605 -433.606774) (xy 342.235028 -433.618894) (xy 342.235028 -434.48986) (xy 343.11844 -434.48986)
			(xy 343.118911 -434.457303) (xy 343.126862 -434.392677) (xy 343.142651 -434.329506) (xy 343.166042 -434.268739)
			(xy 343.196685 -434.211287) (xy 343.234119 -434.158009) (xy 343.277784 -434.109707) (xy 343.302082 -434.088032)
			(xy 343.382854 -433.923186) (xy 343.38755 -433.912668) (xy 343.391039 -433.889911) (xy 343.387557 -433.867153)
			(xy 343.382854 -433.856638) (xy 343.302082 -433.691792) (xy 343.277796 -433.670107) (xy 343.234143 -433.621798)
			(xy 343.196718 -433.568519) (xy 343.166081 -433.511068) (xy 343.14269 -433.450305) (xy 343.126896 -433.38714)
			(xy 343.118936 -433.322519) (xy 343.11844 -433.289964) (xy 343.119132 -433.250837) (xy 343.130612 -433.173431)
			(xy 343.1413 -433.135786) (xy 343.1413 -432.618896) (xy 343.141713 -432.606787) (xy 343.149213 -432.583759)
			(xy 343.163476 -432.564186) (xy 343.183098 -432.549992) (xy 343.206152 -432.542571) (xy 343.218262 -432.542188)
			(xy 344.158062 -432.542188) (xy 344.170154 -432.542641) (xy 344.193162 -432.550093) (xy 344.212747 -432.564281)
			(xy 344.226997 -432.583821) (xy 344.234521 -432.606805) (xy 344.235024 -432.618896) (xy 344.235024 -435.16042)
			(xy 344.234601 -435.172528) (xy 344.227099 -435.195551) (xy 344.212838 -435.215122) (xy 344.19322 -435.229317)
			(xy 344.170171 -435.236741) (xy 344.158062 -435.237128) (xy 343.218262 -435.237128) (xy 343.206167 -435.236724)
			(xy 343.18316 -435.229253) (xy 343.163578 -435.215052) (xy 343.14933 -435.195503) (xy 343.141804 -435.172514)
			(xy 343.1413 -435.16042) (xy 343.1413 -434.644038) (xy 343.130604 -434.606395) (xy 343.119133 -434.528987)
			(xy 343.11844 -434.48986) (xy 342.235028 -434.48986) (xy 342.235028 -435.489858) (xy 345.118436 -435.489858)
			(xy 345.118907 -435.457301) (xy 345.126858 -435.392675) (xy 345.142647 -435.329505) (xy 345.166039 -435.268738)
			(xy 345.196681 -435.211285) (xy 345.234115 -435.158008) (xy 345.27778 -435.109705) (xy 345.302078 -435.08803)
			(xy 345.38285 -434.923184) (xy 345.387548 -434.912666) (xy 345.391036 -434.889909) (xy 345.387553 -434.867151)
			(xy 345.38285 -434.856636) (xy 345.302078 -434.69179) (xy 345.27781 -434.670084) (xy 345.234153 -434.621782)
			(xy 345.196724 -434.568507) (xy 345.166083 -434.51106) (xy 345.142689 -434.450299) (xy 345.126893 -434.387136)
			(xy 345.118932 -434.322516) (xy 345.118436 -434.289962) (xy 345.119128 -434.250835) (xy 345.130608 -434.173429)
			(xy 345.141296 -434.135784) (xy 345.141296 -433.618894) (xy 345.141806 -433.606783) (xy 345.14929 -433.583747)
			(xy 345.163524 -433.564149) (xy 345.183115 -433.549906) (xy 345.206148 -433.542412) (xy 345.218258 -433.541932)
			(xy 346.158058 -433.541932) (xy 346.170178 -433.542396) (xy 346.193234 -433.549876) (xy 346.21285 -433.564116)
			(xy 346.227103 -433.583722) (xy 346.234597 -433.606774) (xy 346.23502 -433.618894) (xy 346.23502 -436.160418)
			(xy 346.234654 -436.172546) (xy 346.227152 -436.195612) (xy 346.212888 -436.215231) (xy 346.193258 -436.22948)
			(xy 346.170186 -436.236964) (xy 346.158058 -436.23738) (xy 345.218258 -436.23738) (xy 345.206143 -436.236924)
			(xy 345.183101 -436.229428) (xy 345.163502 -436.215181) (xy 345.149261 -436.195577) (xy 345.141772 -436.172533)
			(xy 345.141296 -436.160418) (xy 345.141296 -435.644036) (xy 345.130599 -435.606393) (xy 345.119128 -435.528985)
			(xy 345.118436 -435.489858) (xy 342.235028 -435.489858) (xy 342.235028 -436.160418) (xy 342.234655 -436.172545)
			(xy 342.227153 -436.19561) (xy 342.212891 -436.215228) (xy 342.193264 -436.229477) (xy 342.170193 -436.236963)
			(xy 342.158066 -436.23738) (xy 341.218266 -436.23738) (xy 341.206151 -436.236918) (xy 341.18311 -436.229423)
			(xy 341.16351 -436.215178) (xy 341.149269 -436.195576) (xy 341.14178 -436.172533) (xy 341.141304 -436.160418)
			(xy 341.141304 -435.644036) (xy 341.130608 -435.606393) (xy 341.119136 -435.528985) (xy 341.118444 -435.489858)
			(xy 338.235036 -435.489858) (xy 338.235036 -436.160418) (xy 338.234655 -436.172544) (xy 338.227154 -436.195608)
			(xy 338.212894 -436.215225) (xy 338.193269 -436.229474) (xy 338.1702 -436.236962) (xy 338.158074 -436.23738)
			(xy 337.218274 -436.23738) (xy 337.20616 -436.236911) (xy 337.183119 -436.229419) (xy 337.163519 -436.215175)
			(xy 337.149278 -436.195574) (xy 337.141788 -436.172532) (xy 337.141312 -436.160418) (xy 337.141312 -435.644036)
			(xy 337.130616 -435.606393) (xy 337.119144 -435.528985) (xy 337.118452 -435.489858) (xy 334.235044 -435.489858)
			(xy 334.235044 -436.160418) (xy 334.234604 -436.172535) (xy 334.227109 -436.195582) (xy 334.21286 -436.215185)
			(xy 334.19325 -436.229426) (xy 334.1702 -436.236909) (xy 334.158082 -436.23738) (xy 333.218282 -436.23738)
			(xy 333.206168 -436.236904) (xy 333.183127 -436.229414) (xy 333.163528 -436.215172) (xy 333.149286 -436.195573)
			(xy 333.141796 -436.172532) (xy 333.14132 -436.160418) (xy 333.14132 -435.644036) (xy 333.130624 -435.606393)
			(xy 333.119152 -435.528985) (xy 333.11846 -435.489858) (xy 329.2348 -435.489858) (xy 329.2348 -436.160418)
			(xy 329.234309 -436.172505) (xy 329.226852 -436.195499) (xy 329.21267 -436.215075) (xy 329.193145 -436.229327)
			(xy 329.170177 -436.236865) (xy 329.158092 -436.23738) (xy 328.218292 -436.23738) (xy 328.206181 -436.23699)
			(xy 328.18315 -436.229486) (xy 328.163575 -436.215219) (xy 328.149381 -436.19559) (xy 328.141964 -436.172531)
			(xy 328.141584 -436.160418) (xy 328.141584 -435.644798) (xy 328.130775 -435.606979) (xy 328.119175 -435.529185)
			(xy 328.11847 -435.489858) (xy 325.234808 -435.489858) (xy 325.234808 -436.160418) (xy 325.234309 -436.172504)
			(xy 325.226853 -436.195497) (xy 325.212673 -436.215072) (xy 325.19315 -436.229324) (xy 325.170184 -436.236864)
			(xy 325.1581 -436.23738) (xy 324.2183 -436.23738) (xy 324.206189 -436.236984) (xy 324.183158 -436.229482)
			(xy 324.163583 -436.215216) (xy 324.14939 -436.195589) (xy 324.141972 -436.17253) (xy 324.141592 -436.160418)
			(xy 324.141592 -435.644798) (xy 324.130784 -435.606979) (xy 324.119183 -435.529185) (xy 324.118478 -435.489858)
			(xy 321.234816 -435.489858) (xy 321.234816 -436.160418) (xy 321.234407 -436.172513) (xy 321.22694 -436.195522)
			(xy 321.21274 -436.215105) (xy 321.193192 -436.229353) (xy 321.170202 -436.236877) (xy 321.158108 -436.23738)
			(xy 320.218308 -436.23738) (xy 320.206198 -436.236977) (xy 320.183167 -436.229477) (xy 320.163592 -436.215213)
			(xy 320.149398 -436.195587) (xy 320.14198 -436.17253) (xy 320.1416 -436.160418) (xy 320.1416 -435.644798)
			(xy 320.130792 -435.606979) (xy 320.119191 -435.529185) (xy 320.118486 -435.489858) (xy 317.234824 -435.489858)
			(xy 317.234824 -436.160418) (xy 317.234407 -436.172512) (xy 317.226941 -436.195519) (xy 317.212743 -436.215102)
			(xy 317.193197 -436.229351) (xy 317.170209 -436.236876) (xy 317.158116 -436.23738) (xy 316.218316 -436.23738)
			(xy 316.206206 -436.23697) (xy 316.183176 -436.229472) (xy 316.163601 -436.21521) (xy 316.149406 -436.195585)
			(xy 316.141989 -436.172529) (xy 316.141608 -436.160418) (xy 316.141608 -435.644798) (xy 316.1308 -435.606979)
			(xy 316.119199 -435.529185) (xy 316.118494 -435.489858) (xy 273.934286 -435.489858) (xy 273.867468 -435.573645)
			(xy 273.750836 -435.707142) (xy 273.628331 -435.835271) (xy 273.500202 -435.957776) (xy 273.366705 -436.074408)
			(xy 273.22811 -436.184934) (xy 273.084696 -436.289131) (xy 272.936752 -436.386788) (xy 272.784575 -436.477709)
			(xy 272.628472 -436.561712) (xy 272.468758 -436.638626) (xy 272.305753 -436.708298) (xy 272.139788 -436.770586)
			(xy 271.971194 -436.825365) (xy 271.800313 -436.872525) (xy 271.627488 -436.911971) (xy 271.453067 -436.943624)
			(xy 271.277402 -436.967419) (xy 271.100846 -436.98331) (xy 270.923755 -436.991263) (xy 270.746485 -436.991263)
			(xy 270.569394 -436.98331) (xy 270.392838 -436.967419) (xy 270.217173 -436.943624) (xy 270.042752 -436.911971)
			(xy 269.869927 -436.872525) (xy 269.699046 -436.825365) (xy 269.530452 -436.770586) (xy 269.364487 -436.708298)
			(xy 269.201482 -436.638626) (xy 269.041768 -436.561712) (xy 268.885665 -436.477709) (xy 268.733488 -436.386788)
			(xy 268.585544 -436.289131) (xy 268.44213 -436.184934) (xy 268.303535 -436.074408) (xy 268.170038 -435.957776)
			(xy 268.041909 -435.835271) (xy 267.919404 -435.707142) (xy 267.802772 -435.573645) (xy 267.692246 -435.43505)
			(xy 267.588049 -435.291636) (xy 267.490392 -435.143692) (xy 267.399471 -434.991515) (xy 267.315468 -434.835412)
			(xy 267.238554 -434.675698) (xy 267.168882 -434.512693) (xy 267.106594 -434.346728) (xy 267.051815 -434.178134)
			(xy 267.004655 -434.007253) (xy 266.965209 -433.834428) (xy 266.933556 -433.660007) (xy 266.909761 -433.484342)
			(xy 266.89387 -433.307786) (xy 266.885917 -433.130695) (xy 231.01554 -433.130695) (xy 231.01554 -435.063392)
			(xy 231.015024 -435.08834) (xy 231.007214 -435.137622) (xy 230.991802 -435.185079) (xy 230.969165 -435.229545)
			(xy 230.939859 -435.269929) (xy 230.922576 -435.287928) (xy 229.133908 -437.076596) (xy 229.115913 -437.093886)
			(xy 229.075537 -437.12321) (xy 229.031071 -437.145858) (xy 228.98361 -437.161272) (xy 228.934323 -437.169073)
			(xy 228.909372 -437.16956) (xy 207.503268 -437.16956) (xy 207.478319 -437.169063) (xy 207.429037 -437.161248)
			(xy 207.38158 -437.14583) (xy 207.337114 -437.123189) (xy 207.296731 -437.09388) (xy 207.278732 -437.076596)
			(xy 205.949804 -435.747668) (xy 205.932495 -435.72969) (xy 205.903173 -435.68931) (xy 205.880529 -435.64484)
			(xy 205.865119 -435.597375) (xy 205.857324 -435.548084) (xy 205.85684 -435.523132) (xy 204.057751 -435.523132)
			(xy 204.017468 -435.573645) (xy 203.900836 -435.707142) (xy 203.778331 -435.835271) (xy 203.650202 -435.957776)
			(xy 203.516705 -436.074408) (xy 203.37811 -436.184934) (xy 203.234696 -436.289131) (xy 203.086752 -436.386788)
			(xy 202.934575 -436.477709) (xy 202.778472 -436.561712) (xy 202.618758 -436.638626) (xy 202.455753 -436.708298)
			(xy 202.289788 -436.770586) (xy 202.121194 -436.825365) (xy 201.950313 -436.872525) (xy 201.777488 -436.911971)
			(xy 201.603067 -436.943624) (xy 201.427402 -436.967419) (xy 201.250846 -436.98331) (xy 201.073755 -436.991263)
			(xy 200.896485 -436.991263) (xy 200.719394 -436.98331) (xy 200.542838 -436.967419) (xy 200.367173 -436.943624)
			(xy 200.192752 -436.911971) (xy 200.019927 -436.872525) (xy 199.849046 -436.825365) (xy 199.680452 -436.770586)
			(xy 199.514487 -436.708298) (xy 199.351482 -436.638626) (xy 199.191768 -436.561712) (xy 199.035665 -436.477709)
			(xy 198.883488 -436.386788) (xy 198.735544 -436.289131) (xy 198.59213 -436.184934) (xy 198.453535 -436.074408)
			(xy 198.320038 -435.957776) (xy 198.191909 -435.835271) (xy 198.069404 -435.707142) (xy 197.952772 -435.573645)
			(xy 197.842246 -435.43505) (xy 197.738049 -435.291636) (xy 197.640392 -435.143692) (xy 197.549471 -434.991515)
			(xy 197.465468 -434.835412) (xy 197.388554 -434.675698) (xy 197.318882 -434.512693) (xy 197.256594 -434.346728)
			(xy 197.201815 -434.178134) (xy 197.154655 -434.007253) (xy 197.115209 -433.834428) (xy 197.083556 -433.660007)
			(xy 197.059761 -433.484342) (xy 197.04387 -433.307786) (xy 197.035917 -433.130695) (xy 155.334716 -433.130695)
			(xy 155.334716 -435.16042) (xy 155.334253 -435.172495) (xy 155.326786 -435.195461) (xy 155.312589 -435.214997)
			(xy 155.29305 -435.229191) (xy 155.270083 -435.236655) (xy 155.258008 -435.237128) (xy 154.318208 -435.237128)
			(xy 154.306136 -435.236629) (xy 154.283172 -435.229171) (xy 154.263637 -435.214983) (xy 154.249441 -435.195453)
			(xy 154.241975 -435.172492) (xy 154.2415 -435.16042) (xy 154.2415 -434.550058) (xy 154.239834 -434.535064)
			(xy 154.238054 -434.504946) (xy 154.237944 -434.48986) (xy 153.33472 -434.48986) (xy 153.33472 -435.489858)
			(xy 156.23794 -435.489858) (xy 156.238053 -435.474772) (xy 156.239832 -435.444654) (xy 156.241496 -435.42966)
			(xy 156.241496 -434.35016) (xy 156.23983 -434.335166) (xy 156.23805 -434.305048) (xy 156.23794 -434.289962)
			(xy 156.238053 -434.274876) (xy 156.239832 -434.244758) (xy 156.241496 -434.229764) (xy 156.241496 -433.618894)
			(xy 156.242002 -433.606809) (xy 156.249455 -433.583815) (xy 156.263633 -433.564239) (xy 156.283155 -433.549987)
			(xy 156.30612 -433.542448) (xy 156.318204 -433.541932) (xy 157.258004 -433.541932) (xy 157.270116 -433.542313)
			(xy 157.293149 -433.549818) (xy 157.312725 -433.564087) (xy 157.326918 -433.583718) (xy 157.334333 -433.60678)
			(xy 157.334712 -433.618894) (xy 157.334712 -436.160418) (xy 157.334307 -436.172513) (xy 157.32684 -436.195523)
			(xy 157.312639 -436.215106) (xy 157.293089 -436.229355) (xy 157.270098 -436.236878) (xy 157.258004 -436.23738)
			(xy 156.318204 -436.23738) (xy 156.306093 -436.23698) (xy 156.283063 -436.229479) (xy 156.263488 -436.215214)
			(xy 156.249294 -436.195588) (xy 156.241876 -436.17253) (xy 156.241496 -436.160418) (xy 156.241496 -435.550056)
			(xy 156.23983 -435.535062) (xy 156.23805 -435.504944) (xy 156.23794 -435.489858) (xy 153.33472 -435.489858)
			(xy 153.33472 -436.160418) (xy 153.334307 -436.172513) (xy 153.326841 -436.195521) (xy 153.312642 -436.215104)
			(xy 153.293094 -436.229352) (xy 153.270105 -436.236877) (xy 153.258012 -436.23738) (xy 152.318212 -436.23738)
			(xy 152.306102 -436.236973) (xy 152.283072 -436.229474) (xy 152.263497 -436.215211) (xy 152.249302 -436.195586)
			(xy 152.241885 -436.17253) (xy 152.241504 -436.160418) (xy 152.241504 -435.550056) (xy 152.239838 -435.535062)
			(xy 152.238058 -435.504944) (xy 152.237948 -435.489858) (xy 149.334728 -435.489858) (xy 149.334728 -436.160418)
			(xy 149.334308 -436.172512) (xy 149.326842 -436.195518) (xy 149.312645 -436.215101) (xy 149.293099 -436.22935)
			(xy 149.270112 -436.236876) (xy 149.25802 -436.23738) (xy 148.31822 -436.23738) (xy 148.30611 -436.236966)
			(xy 148.28308 -436.22947) (xy 148.263505 -436.215208) (xy 148.249311 -436.195585) (xy 148.241893 -436.172529)
			(xy 148.241512 -436.160418) (xy 148.241512 -435.550056) (xy 148.239846 -435.535062) (xy 148.238066 -435.504944)
			(xy 148.237956 -435.489858) (xy 145.334736 -435.489858) (xy 145.334736 -436.160418) (xy 145.334308 -436.172511)
			(xy 145.326843 -436.195516) (xy 145.312647 -436.215098) (xy 145.293104 -436.229347) (xy 145.27012 -436.236874)
			(xy 145.258028 -436.23738) (xy 144.318228 -436.23738) (xy 144.306119 -436.236959) (xy 144.283089 -436.229465)
			(xy 144.263514 -436.215206) (xy 144.249319 -436.195583) (xy 144.241901 -436.172529) (xy 144.24152 -436.160418)
			(xy 144.24152 -435.550056) (xy 144.239854 -435.535062) (xy 144.238074 -435.504944) (xy 144.237964 -435.489858)
			(xy 140.335 -435.489858) (xy 140.335 -436.160418) (xy 140.334504 -436.17253) (xy 140.327017 -436.195567)
			(xy 140.31278 -436.215165) (xy 140.293185 -436.229408) (xy 140.27015 -436.236901) (xy 140.258038 -436.23738)
			(xy 139.318238 -436.23738) (xy 139.306119 -436.236908) (xy 139.283064 -436.229428) (xy 139.26345 -436.21519)
			(xy 139.249197 -436.195586) (xy 139.241701 -436.172537) (xy 139.241276 -436.160418) (xy 139.241276 -435.548024)
			(xy 139.239728 -435.533532) (xy 139.238078 -435.504432) (xy 139.237974 -435.489858) (xy 136.335008 -435.489858)
			(xy 136.335008 -436.160418) (xy 136.334505 -436.172529) (xy 136.327018 -436.195565) (xy 136.312782 -436.215163)
			(xy 136.29319 -436.229405) (xy 136.270157 -436.2369) (xy 136.258046 -436.23738) (xy 135.318246 -436.23738)
			(xy 135.306127 -436.236901) (xy 135.283073 -436.229424) (xy 135.263459 -436.215187) (xy 135.249205 -436.195584)
			(xy 135.241709 -436.172536) (xy 135.241284 -436.160418) (xy 135.241284 -435.548024) (xy 135.239736 -435.533532)
			(xy 135.238086 -435.504432) (xy 135.237982 -435.489858) (xy 132.335016 -435.489858) (xy 132.335016 -436.160418)
			(xy 132.334654 -436.172546) (xy 132.327152 -436.195613) (xy 132.312886 -436.215232) (xy 132.293256 -436.229481)
			(xy 132.270183 -436.236965) (xy 132.258054 -436.23738) (xy 131.318254 -436.23738) (xy 131.306139 -436.236928)
			(xy 131.283097 -436.22943) (xy 131.263498 -436.215182) (xy 131.249257 -436.195578) (xy 131.241768 -436.172533)
			(xy 131.241292 -436.160418) (xy 131.241292 -435.548024) (xy 131.239744 -435.533532) (xy 131.238094 -435.504432)
			(xy 131.23799 -435.489858) (xy 128.335024 -435.489858) (xy 128.335024 -436.160418) (xy 128.334655 -436.172545)
			(xy 128.327153 -436.195611) (xy 128.312889 -436.215229) (xy 128.293261 -436.229478) (xy 128.27019 -436.236963)
			(xy 128.258062 -436.23738) (xy 127.318262 -436.23738) (xy 127.306147 -436.236921) (xy 127.283106 -436.229425)
			(xy 127.263506 -436.21518) (xy 127.249265 -436.195576) (xy 127.241776 -436.172533) (xy 127.2413 -436.160418)
			(xy 127.2413 -435.548024) (xy 127.239751 -435.533532) (xy 127.238102 -435.504432) (xy 127.237998 -435.489858)
			(xy 113.866512 -435.489858) (xy 113.892486 -435.537087) (xy 113.947862 -435.654438) (xy 113.995874 -435.77499)
			(xy 114.036336 -435.89828) (xy 114.069094 -436.023838) (xy 114.094022 -436.151181) (xy 114.111025 -436.279823)
			(xy 114.120038 -436.40927) (xy 114.121027 -436.539027) (xy 114.113986 -436.668596) (xy 114.098945 -436.797482)
			(xy 114.075959 -436.92519) (xy 114.045118 -437.051232) (xy 114.006538 -437.175125) (xy 113.960369 -437.296394)
			(xy 113.906786 -437.414574) (xy 113.845996 -437.529214) (xy 113.77823 -437.639874) (xy 113.703749 -437.74613)
			(xy 113.622838 -437.847575) (xy 113.535806 -437.943821) (xy 113.442988 -438.034499) (xy 113.378885 -438.089802)
			(xy 125.218444 -438.089802) (xy 125.218952 -438.057222) (xy 125.226926 -437.99255) (xy 125.242743 -437.929338)
			(xy 125.266166 -437.868533) (xy 125.296843 -437.811045) (xy 125.334315 -437.757736) (xy 125.378021 -437.709407)
			(xy 125.40234 -437.68772) (xy 125.482858 -437.523382) (xy 125.487557 -437.512865) (xy 125.491044 -437.490107)
			(xy 125.487561 -437.467349) (xy 125.482858 -437.456834) (xy 125.401832 -437.291734) (xy 125.377564 -437.270043)
			(xy 125.333966 -437.22171) (xy 125.296591 -437.168419) (xy 125.265998 -437.110966) (xy 125.242644 -437.050209)
			(xy 125.226877 -436.987056) (xy 125.218934 -436.922451) (xy 125.218444 -436.889906) (xy 125.219145 -436.85078)
			(xy 125.230619 -436.773373) (xy 125.241304 -436.735728) (xy 125.241304 -436.219092) (xy 125.241709 -436.206982)
			(xy 125.249212 -436.183954) (xy 125.263476 -436.164381) (xy 125.2831 -436.150186) (xy 125.306155 -436.142767)
			(xy 125.318266 -436.142384) (xy 126.258066 -436.142384) (xy 126.270158 -436.142837) (xy 126.293165 -436.15029)
			(xy 126.312749 -436.164478) (xy 126.327 -436.184018) (xy 126.334525 -436.207001) (xy 126.335028 -436.219092)
			(xy 126.335028 -438.760616) (xy 126.334598 -438.772723) (xy 126.327097 -438.795746) (xy 126.312838 -438.815316)
			(xy 126.293222 -438.829511) (xy 126.270174 -438.836937) (xy 126.258066 -438.837324) (xy 125.318266 -438.837324)
			(xy 125.306171 -438.836921) (xy 125.283163 -438.829451) (xy 125.263581 -438.815249) (xy 125.249333 -438.7957)
			(xy 125.241808 -438.77271) (xy 125.241304 -438.760616) (xy 125.241304 -438.24398) (xy 125.230617 -438.206335)
			(xy 125.21914 -438.128928) (xy 125.218444 -438.089802) (xy 113.378885 -438.089802) (xy 113.344738 -438.119261)
			(xy 113.241432 -438.197784) (xy 113.133467 -438.269766) (xy 113.021257 -438.334931) (xy 112.90523 -438.39303)
			(xy 112.785831 -438.443841) (xy 112.663518 -438.487169) (xy 112.538759 -438.522847) (xy 112.412032 -438.550739)
			(xy 112.283822 -438.570739) (xy 112.15462 -438.58277) (xy 112.024922 -438.586785) (xy 111.895224 -438.58277)
			(xy 111.766022 -438.570739) (xy 111.637812 -438.550739) (xy 111.511085 -438.522847) (xy 111.386326 -438.487169)
			(xy 111.264013 -438.443841) (xy 111.144614 -438.39303) (xy 111.028587 -438.334931) (xy 110.916377 -438.269766)
			(xy 110.808412 -438.197784) (xy 110.705106 -438.119261) (xy 110.606856 -438.034499) (xy 110.514038 -437.943821)
			(xy 110.427006 -437.847575) (xy 110.346095 -437.74613) (xy 110.271614 -437.639874) (xy 110.203848 -437.529214)
			(xy 110.143058 -437.414574) (xy 110.089475 -437.296394) (xy 110.043306 -437.175125) (xy 110.004726 -437.051232)
			(xy 109.973885 -436.92519) (xy 109.950899 -436.797482) (xy 109.935858 -436.668596) (xy 109.928817 -436.539027)
			(xy 109.929806 -436.40927) (xy 109.938819 -436.279823) (xy 109.955822 -436.151181) (xy 109.98075 -436.023838)
			(xy 110.013508 -435.89828) (xy 110.05397 -435.77499) (xy 110.101982 -435.654438) (xy 110.157358 -435.537087)
			(xy 110.219888 -435.423387) (xy 110.289331 -435.313772) (xy 110.365422 -435.208663) (xy 110.447869 -435.108462)
			(xy 110.536357 -435.013553) (xy 110.630546 -434.924299) (xy 110.679992 -434.88229) (xy 110.691093 -434.872254)
			(xy 110.707515 -434.847259) (xy 110.71599 -434.818578) (xy 110.71579 -434.788672) (xy 110.706933 -434.760107)
			(xy 110.690178 -434.735334) (xy 110.666963 -434.71648) (xy 110.653322 -434.710332) (xy 110.574304 -434.677407)
			(xy 110.419107 -434.605131) (xy 110.267499 -434.5256) (xy 110.119821 -434.438991) (xy 109.976402 -434.345497)
			(xy 109.837562 -434.245328) (xy 109.703613 -434.138709) (xy 109.574854 -434.025876) (xy 109.451573 -433.907083)
			(xy 109.334045 -433.782595) (xy 109.222533 -433.65269) (xy 109.117287 -433.517659) (xy 109.018541 -433.377804)
			(xy 108.926517 -433.233438) (xy 108.84142 -433.084883) (xy 108.763441 -432.932471) (xy 108.692754 -432.776543)
			(xy 108.629516 -432.617449) (xy 108.57387 -432.455542) (xy 108.52594 -432.291187) (xy 108.485833 -432.124749)
			(xy 108.453638 -431.956601) (xy 108.429428 -431.78712) (xy 108.413257 -431.616683) (xy 108.405161 -431.445673)
			(xy 108.40466 -431.360072) (xy 90.235024 -431.360072) (xy 90.235024 -432.560476) (xy 90.234563 -432.572581)
			(xy 90.227074 -432.595604) (xy 90.212823 -432.615175) (xy 90.193212 -432.629371) (xy 90.170168 -432.636797)
			(xy 90.158062 -432.637184) (xy 89.218262 -432.637184) (xy 89.206173 -432.636726) (xy 89.183175 -432.629261)
			(xy 89.163598 -432.615072) (xy 89.149348 -432.595538) (xy 89.141812 -432.572564) (xy 89.1413 -432.560476)
			(xy 89.1413 -431.948082) (xy 89.139756 -431.93359) (xy 89.138104 -431.90449) (xy 89.137998 -431.889916)
			(xy 86.235032 -431.889916) (xy 86.235032 -432.560476) (xy 86.234563 -432.57258) (xy 86.227075 -432.595601)
			(xy 86.212825 -432.615172) (xy 86.193217 -432.629369) (xy 86.170175 -432.636796) (xy 86.15807 -432.637184)
			(xy 85.21827 -432.637184) (xy 85.206181 -432.636719) (xy 85.183184 -432.629257) (xy 85.163606 -432.615069)
			(xy 85.149356 -432.595537) (xy 85.14182 -432.572563) (xy 85.141308 -432.560476) (xy 85.141308 -431.948082)
			(xy 85.139764 -431.93359) (xy 85.138112 -431.90449) (xy 85.138006 -431.889916) (xy 82.23504 -431.889916)
			(xy 82.23504 -432.560476) (xy 82.234564 -432.57258) (xy 82.227076 -432.595599) (xy 82.212828 -432.615169)
			(xy 82.193222 -432.629366) (xy 82.170183 -432.636795) (xy 82.158078 -432.637184) (xy 81.218278 -432.637184)
			(xy 81.20619 -432.636712) (xy 81.183192 -432.629252) (xy 81.163615 -432.615066) (xy 81.149364 -432.595535)
			(xy 81.141828 -432.572563) (xy 81.141316 -432.560476) (xy 81.141316 -431.948082) (xy 81.139772 -431.93359)
			(xy 81.13812 -431.90449) (xy 81.138014 -431.889916) (xy 78.235048 -431.889916) (xy 78.235048 -432.560476)
			(xy 78.234564 -432.572579) (xy 78.227077 -432.595597) (xy 78.212831 -432.615166) (xy 78.193227 -432.629364)
			(xy 78.17019 -432.636793) (xy 78.158086 -432.637184) (xy 77.218286 -432.637184) (xy 77.206198 -432.636705)
			(xy 77.183201 -432.629248) (xy 77.163623 -432.615063) (xy 77.149372 -432.595534) (xy 77.141836 -432.572562)
			(xy 77.141324 -432.560476) (xy 77.141324 -431.948082) (xy 77.13978 -431.93359) (xy 77.138128 -431.90449)
			(xy 77.138022 -431.889916) (xy 73.234804 -431.889916) (xy 73.234804 -432.560476) (xy 73.234367 -432.572558)
			(xy 73.226905 -432.59554) (xy 73.212706 -432.615091) (xy 73.193158 -432.629296) (xy 73.170178 -432.636764)
			(xy 73.158096 -432.637184) (xy 72.218296 -432.637184) (xy 72.206211 -432.636791) (xy 72.183224 -432.629319)
			(xy 72.163671 -432.615109) (xy 72.149468 -432.595551) (xy 72.142005 -432.572562) (xy 72.141588 -432.560476)
			(xy 72.141588 -431.950114) (xy 72.139918 -431.935121) (xy 72.138141 -431.905002) (xy 72.138032 -431.889916)
			(xy 69.234812 -431.889916) (xy 69.234812 -432.560476) (xy 69.234367 -432.572557) (xy 69.226906 -432.595538)
			(xy 69.212709 -432.615089) (xy 69.193163 -432.629294) (xy 69.170185 -432.636762) (xy 69.158104 -432.637184)
			(xy 68.218304 -432.637184) (xy 68.206219 -432.636784) (xy 68.183232 -432.629314) (xy 68.16368 -432.615106)
			(xy 68.149476 -432.59555) (xy 68.142013 -432.572561) (xy 68.141596 -432.560476) (xy 68.141596 -431.950114)
			(xy 68.139926 -431.935121) (xy 68.138149 -431.905002) (xy 68.13804 -431.889916) (xy 65.23482 -431.889916)
			(xy 65.23482 -432.560476) (xy 65.234367 -432.572556) (xy 65.226907 -432.595536) (xy 65.212711 -432.615086)
			(xy 65.193168 -432.629291) (xy 65.170192 -432.636761) (xy 65.158112 -432.637184) (xy 64.218312 -432.637184)
			(xy 64.206228 -432.636777) (xy 64.183241 -432.629309) (xy 64.163689 -432.615103) (xy 64.149485 -432.595548)
			(xy 64.142022 -432.572561) (xy 64.141604 -432.560476) (xy 64.141604 -431.950114) (xy 64.139934 -431.935121)
			(xy 64.138157 -431.905002) (xy 64.138048 -431.889916) (xy 61.234828 -431.889916) (xy 61.234828 -432.560476)
			(xy 61.234367 -432.572555) (xy 61.226909 -432.595534) (xy 61.212714 -432.615083) (xy 61.193173 -432.629288)
			(xy 61.170199 -432.63676) (xy 61.15812 -432.637184) (xy 60.21832 -432.637184) (xy 60.206236 -432.63677)
			(xy 60.18325 -432.629305) (xy 60.163697 -432.6151) (xy 60.149493 -432.595547) (xy 60.14203 -432.57256)
			(xy 60.141612 -432.560476) (xy 60.141612 -431.950114) (xy 60.139942 -431.935121) (xy 60.138165 -431.905002)
			(xy 60.138056 -431.889916) (xy 7.00913 -431.889916) (xy 7.00913 -434.48986) (xy 58.118502 -434.48986)
			(xy 58.118986 -434.457304) (xy 58.126936 -434.392678) (xy 58.142724 -434.329509) (xy 58.166114 -434.268742)
			(xy 58.196754 -434.211289) (xy 58.234185 -434.158012) (xy 58.277847 -434.109707) (xy 58.302144 -434.088032)
			(xy 58.382916 -433.923186) (xy 58.387614 -433.912668) (xy 58.391105 -433.889911) (xy 58.387621 -433.867152)
			(xy 58.382916 -433.856638) (xy 58.302144 -433.691792) (xy 58.27787 -433.670093) (xy 58.234215 -433.621788)
			(xy 58.196787 -433.568513) (xy 58.166147 -433.511064) (xy 58.142754 -433.450302) (xy 58.126959 -433.387139)
			(xy 58.118998 -433.322518) (xy 58.118502 -433.289964) (xy 58.119229 -433.250639) (xy 58.130834 -433.172849)
			(xy 58.141616 -433.135024) (xy 58.141616 -432.618896) (xy 58.142009 -432.606811) (xy 58.149481 -432.583824)
			(xy 58.163691 -432.564271) (xy 58.183249 -432.550068) (xy 58.206238 -432.542605) (xy 58.218324 -432.542188)
			(xy 59.158124 -432.542188) (xy 59.170199 -432.542644) (xy 59.193167 -432.550113) (xy 59.212703 -432.564311)
			(xy 59.226897 -432.583851) (xy 59.234359 -432.606821) (xy 59.234832 -432.618896) (xy 59.234832 -435.16042)
			(xy 59.234353 -435.172493) (xy 59.226888 -435.195457) (xy 59.212694 -435.214991) (xy 59.19316 -435.229186)
			(xy 59.170197 -435.236652) (xy 59.158124 -435.237128) (xy 58.218324 -435.237128) (xy 58.206245 -435.236667)
			(xy 58.183266 -435.229209) (xy 58.163717 -435.215014) (xy 58.149512 -435.195473) (xy 58.14204 -435.172499)
			(xy 58.141616 -435.16042) (xy 58.141616 -434.6448) (xy 58.130809 -434.606981) (xy 58.119207 -434.529187)
			(xy 58.118502 -434.48986) (xy 7.00913 -434.48986) (xy 7.00913 -435.489858) (xy 60.118498 -435.489858)
			(xy 60.118982 -435.457302) (xy 60.126932 -435.392676) (xy 60.142721 -435.329507) (xy 60.16611 -435.26874)
			(xy 60.19675 -435.211287) (xy 60.234182 -435.15801) (xy 60.277843 -435.109706) (xy 60.30214 -435.08803)
			(xy 60.382912 -434.923184) (xy 60.387612 -434.912667) (xy 60.391102 -434.889909) (xy 60.387617 -434.86715)
			(xy 60.382912 -434.856636) (xy 60.30214 -434.69179) (xy 60.277865 -434.670093) (xy 60.234209 -434.621788)
			(xy 60.196781 -434.568512) (xy 60.166142 -434.511063) (xy 60.14275 -434.450301) (xy 60.126955 -434.387137)
			(xy 60.118994 -434.322516) (xy 60.118498 -434.289962) (xy 60.119225 -434.250637) (xy 60.13083 -434.172847)
			(xy 60.141612 -434.135022) (xy 60.141612 -433.618894) (xy 60.142102 -433.606807) (xy 60.149557 -433.583811)
			(xy 60.163739 -433.564234) (xy 60.183265 -433.549982) (xy 60.206235 -433.542445) (xy 60.21832 -433.541932)
			(xy 61.15812 -433.541932) (xy 61.170233 -433.5423) (xy 61.193267 -433.549808) (xy 61.212842 -433.564081)
			(xy 61.227035 -433.583715) (xy 61.234449 -433.606779) (xy 61.234828 -433.618894) (xy 61.234828 -434.48986)
			(xy 62.118494 -434.48986) (xy 62.118947 -434.457302) (xy 62.126898 -434.392675) (xy 62.142689 -434.329503)
			(xy 62.166083 -434.268735) (xy 62.196729 -434.211283) (xy 62.234167 -434.158006) (xy 62.277836 -434.109705)
			(xy 62.302136 -434.088032) (xy 62.382908 -433.923186) (xy 62.387606 -433.912668) (xy 62.391097 -433.889911)
			(xy 62.387613 -433.867152) (xy 62.382908 -433.856638) (xy 62.302136 -433.691792) (xy 62.277861 -433.670095)
			(xy 62.234205 -433.62179) (xy 62.196778 -433.568513) (xy 62.166138 -433.511064) (xy 62.142746 -433.450303)
			(xy 62.126951 -433.387139) (xy 62.11899 -433.322518) (xy 62.118494 -433.289964) (xy 62.119221 -433.250639)
			(xy 62.130826 -433.172849) (xy 62.141608 -433.135024) (xy 62.141608 -432.618896) (xy 62.142009 -432.606811)
			(xy 62.14948 -432.583826) (xy 62.163688 -432.564274) (xy 62.183244 -432.550071) (xy 62.206231 -432.542606)
			(xy 62.218316 -432.542188) (xy 63.158116 -432.542188) (xy 63.170191 -432.542651) (xy 63.193158 -432.550117)
			(xy 63.212694 -432.564314) (xy 63.226888 -432.583853) (xy 63.234351 -432.606821) (xy 63.234824 -432.618896)
			(xy 63.234824 -435.16042) (xy 63.234353 -435.172494) (xy 63.226887 -435.195459) (xy 63.212691 -435.214994)
			(xy 63.193155 -435.229189) (xy 63.17019 -435.236654) (xy 63.158116 -435.237128) (xy 62.218316 -435.237128)
			(xy 62.206244 -435.236622) (xy 62.183281 -435.229167) (xy 62.163745 -435.21498) (xy 62.14955 -435.195451)
			(xy 62.142083 -435.172492) (xy 62.141608 -435.16042) (xy 62.141608 -434.6448) (xy 62.130801 -434.606981)
			(xy 62.119199 -434.529187) (xy 62.118494 -434.48986) (xy 61.234828 -434.48986) (xy 61.234828 -435.489858)
			(xy 64.11849 -435.489858) (xy 64.118943 -435.4573) (xy 64.126894 -435.392673) (xy 64.142685 -435.329501)
			(xy 64.166079 -435.268734) (xy 64.196725 -435.211281) (xy 64.234163 -435.158004) (xy 64.277832 -435.109703)
			(xy 64.302132 -435.08803) (xy 64.382904 -434.923184) (xy 64.387604 -434.912667) (xy 64.391095 -434.889909)
			(xy 64.387609 -434.86715) (xy 64.382904 -434.856636) (xy 64.302132 -434.69179) (xy 64.277855 -434.670095)
			(xy 64.2342 -434.621789) (xy 64.196773 -434.568512) (xy 64.166133 -434.511063) (xy 64.142741 -434.450301)
			(xy 64.126947 -434.387137) (xy 64.118986 -434.322516) (xy 64.11849 -434.289962) (xy 64.119217 -434.250637)
			(xy 64.130822 -434.172847) (xy 64.141604 -434.135022) (xy 64.141604 -433.618894) (xy 64.142102 -433.606808)
			(xy 64.149556 -433.583813) (xy 64.163736 -433.564236) (xy 64.18326 -433.549985) (xy 64.206228 -433.542447)
			(xy 64.218312 -433.541932) (xy 65.158112 -433.541932) (xy 65.170225 -433.542306) (xy 65.193258 -433.549813)
			(xy 65.212834 -433.564084) (xy 65.227027 -433.583717) (xy 65.234441 -433.60678) (xy 65.23482 -433.618894)
			(xy 65.23482 -434.48986) (xy 66.118486 -434.48986) (xy 66.118942 -434.457302) (xy 66.126893 -434.392675)
			(xy 66.142684 -434.329504) (xy 66.166077 -434.268736) (xy 66.196722 -434.211283) (xy 66.23416 -434.158007)
			(xy 66.277828 -434.109705) (xy 66.302128 -434.088032) (xy 66.3829 -433.923186) (xy 66.387599 -433.912668)
			(xy 66.39109 -433.889911) (xy 66.387605 -433.867152) (xy 66.3829 -433.856638) (xy 66.302128 -433.691792)
			(xy 66.277851 -433.670097) (xy 66.234196 -433.621791) (xy 66.196769 -433.568514) (xy 66.16613 -433.511065)
			(xy 66.142738 -433.450303) (xy 66.126943 -433.387139) (xy 66.118982 -433.322518) (xy 66.118486 -433.289964)
			(xy 66.119214 -433.250639) (xy 66.130818 -433.172849) (xy 66.1416 -433.135024) (xy 66.1416 -432.618896)
			(xy 66.142009 -432.606812) (xy 66.149479 -432.583828) (xy 66.163686 -432.564277) (xy 66.183239 -432.550073)
			(xy 66.206224 -432.542607) (xy 66.218308 -432.542188) (xy 67.158108 -432.542188) (xy 67.170183 -432.542657)
			(xy 67.193149 -432.550122) (xy 67.212686 -432.564317) (xy 67.22688 -432.583854) (xy 67.234343 -432.606821)
			(xy 67.234816 -432.618896) (xy 67.234816 -435.16042) (xy 67.234353 -435.172495) (xy 67.226886 -435.195461)
			(xy 67.212689 -435.214997) (xy 67.19315 -435.229191) (xy 67.170183 -435.236655) (xy 67.158108 -435.237128)
			(xy 66.218308 -435.237128) (xy 66.206236 -435.236629) (xy 66.183272 -435.229171) (xy 66.163737 -435.214983)
			(xy 66.149541 -435.195453) (xy 66.142075 -435.172492) (xy 66.1416 -435.16042) (xy 66.1416 -434.6448)
			(xy 66.130792 -434.606981) (xy 66.119191 -434.529187) (xy 66.118486 -434.48986) (xy 65.23482 -434.48986)
			(xy 65.23482 -435.489858) (xy 68.118482 -435.489858) (xy 68.118938 -435.457301) (xy 68.126889 -435.392673)
			(xy 68.14268 -435.329502) (xy 68.166073 -435.268734) (xy 68.196718 -435.211281) (xy 68.234156 -435.158005)
			(xy 68.277824 -435.109704) (xy 68.302124 -435.08803) (xy 68.382896 -434.923184) (xy 68.387596 -434.912667)
			(xy 68.391087 -434.889909) (xy 68.387602 -434.86715) (xy 68.382896 -434.856636) (xy 68.302124 -434.69179)
			(xy 68.277845 -434.670096) (xy 68.234191 -434.62179) (xy 68.196764 -434.568513) (xy 68.166125 -434.511064)
			(xy 68.142733 -434.450302) (xy 68.126938 -434.387137) (xy 68.118978 -434.322517) (xy 68.118482 -434.289962)
			(xy 68.119209 -434.250637) (xy 68.130814 -434.172847) (xy 68.141596 -434.135022) (xy 68.141596 -433.618894)
			(xy 68.142102 -433.606809) (xy 68.149555 -433.583815) (xy 68.163733 -433.564239) (xy 68.183255 -433.549987)
			(xy 68.20622 -433.542448) (xy 68.218304 -433.541932) (xy 69.158104 -433.541932) (xy 69.170216 -433.542313)
			(xy 69.193249 -433.549818) (xy 69.212825 -433.564087) (xy 69.227018 -433.583718) (xy 69.234433 -433.60678)
			(xy 69.234812 -433.618894) (xy 69.234812 -434.48986) (xy 70.118478 -434.48986) (xy 70.118936 -434.457303)
			(xy 70.126887 -434.392675) (xy 70.142678 -434.329504) (xy 70.166071 -434.268737) (xy 70.196716 -434.211284)
			(xy 70.234152 -434.158007) (xy 70.27782 -434.109706) (xy 70.30212 -434.088032) (xy 70.382892 -433.923186)
			(xy 70.387591 -433.912669) (xy 70.391083 -433.889911) (xy 70.387598 -433.867152) (xy 70.382892 -433.856638)
			(xy 70.30212 -433.691792) (xy 70.277841 -433.670098) (xy 70.234187 -433.621792) (xy 70.19676 -433.568515)
			(xy 70.166121 -433.511065) (xy 70.142729 -433.450303) (xy 70.126935 -433.387139) (xy 70.118974 -433.322519)
			(xy 70.118478 -433.289964) (xy 70.119206 -433.250639) (xy 70.130811 -433.172849) (xy 70.141592 -433.135024)
			(xy 70.141592 -432.618896) (xy 70.142061 -432.606821) (xy 70.149524 -432.583854) (xy 70.16372 -432.564317)
			(xy 70.183258 -432.550123) (xy 70.206225 -432.54266) (xy 70.2183 -432.542188) (xy 71.1581 -432.542188)
			(xy 71.170174 -432.542664) (xy 71.193141 -432.550126) (xy 71.212677 -432.56432) (xy 71.226872 -432.583856)
			(xy 71.234335 -432.606822) (xy 71.234808 -432.618896) (xy 71.234808 -435.16042) (xy 71.234353 -435.172496)
			(xy 71.226885 -435.195463) (xy 71.212686 -435.215) (xy 71.193145 -435.229194) (xy 71.170176 -435.236656)
			(xy 71.1581 -435.237128) (xy 70.2183 -435.237128) (xy 70.206227 -435.236636) (xy 70.183264 -435.229176)
			(xy 70.163728 -435.214986) (xy 70.149533 -435.195454) (xy 70.142067 -435.172492) (xy 70.141592 -435.16042)
			(xy 70.141592 -434.6448) (xy 70.130784 -434.606981) (xy 70.119183 -434.529187) (xy 70.118478 -434.48986)
			(xy 69.234812 -434.48986) (xy 69.234812 -435.489858) (xy 72.118474 -435.489858) (xy 72.118932 -435.457301)
			(xy 72.126884 -435.392673) (xy 72.142674 -435.329502) (xy 72.166067 -435.268735) (xy 72.196712 -435.211282)
			(xy 72.234149 -435.158005) (xy 72.277816 -435.109704) (xy 72.302116 -435.08803) (xy 72.382888 -434.923184)
			(xy 72.387589 -434.912667) (xy 72.39108 -434.889909) (xy 72.387594 -434.86715) (xy 72.382888 -434.856636)
			(xy 72.302116 -434.69179) (xy 72.277836 -434.670098) (xy 72.234182 -434.621792) (xy 72.196755 -434.568514)
			(xy 72.166116 -434.511064) (xy 72.142725 -434.450302) (xy 72.12693 -434.387137) (xy 72.11897 -434.322517)
			(xy 72.118474 -434.289962) (xy 72.119202 -434.250637) (xy 72.130806 -434.172847) (xy 72.141588 -434.135022)
			(xy 72.141588 -433.618894) (xy 72.142003 -433.606799) (xy 72.149468 -433.583791) (xy 72.163666 -433.564207)
			(xy 72.183213 -433.549958) (xy 72.206203 -433.542435) (xy 72.218296 -433.541932) (xy 73.158096 -433.541932)
			(xy 73.170208 -433.54232) (xy 73.193241 -433.549822) (xy 73.212817 -433.56409) (xy 73.22701 -433.58372)
			(xy 73.234425 -433.606781) (xy 73.234804 -433.618894) (xy 73.234804 -434.48986) (xy 75.118468 -434.48986)
			(xy 75.11893 -434.457303) (xy 75.126881 -434.392676) (xy 75.142671 -434.329505) (xy 75.166063 -434.268737)
			(xy 75.196707 -434.211285) (xy 75.234144 -434.158008) (xy 75.277811 -434.109706) (xy 75.30211 -434.088032)
			(xy 75.382882 -433.923186) (xy 75.387582 -433.912669) (xy 75.391074 -433.889911) (xy 75.387588 -433.867152)
			(xy 75.382882 -433.856638) (xy 75.30211 -433.691792) (xy 75.277829 -433.670101) (xy 75.234176 -433.621794)
			(xy 75.196749 -433.568516) (xy 75.166111 -433.511066) (xy 75.142719 -433.450304) (xy 75.126925 -433.387139)
			(xy 75.118964 -433.322519) (xy 75.118468 -433.289964) (xy 75.119159 -433.250837) (xy 75.130639 -433.173431)
			(xy 75.141328 -433.135786) (xy 75.141328 -432.618896) (xy 75.141713 -432.606784) (xy 75.149217 -432.583752)
			(xy 75.163486 -432.564176) (xy 75.183116 -432.549983) (xy 75.206177 -432.542567) (xy 75.21829 -432.542188)
			(xy 76.15809 -432.542188) (xy 76.170184 -432.542617) (xy 76.193192 -432.550077) (xy 76.212776 -432.564271)
			(xy 76.227025 -432.583816) (xy 76.234549 -432.606804) (xy 76.235052 -432.618896) (xy 76.235052 -435.16042)
			(xy 76.234601 -435.172525) (xy 76.227103 -435.195544) (xy 76.212848 -435.215112) (xy 76.193237 -435.229308)
			(xy 76.170196 -435.236737) (xy 76.15809 -435.237128) (xy 75.21829 -435.237128) (xy 75.206197 -435.2367)
			(xy 75.183191 -435.229237) (xy 75.163608 -435.215041) (xy 75.149359 -435.195498) (xy 75.141833 -435.172512)
			(xy 75.141328 -435.16042) (xy 75.141328 -434.644038) (xy 75.130633 -434.606395) (xy 75.119161 -434.528987)
			(xy 75.118468 -434.48986) (xy 73.234804 -434.48986) (xy 73.234804 -435.489858) (xy 77.118464 -435.489858)
			(xy 77.118926 -435.457301) (xy 77.126877 -435.392674) (xy 77.142667 -435.329503) (xy 77.16606 -435.268736)
			(xy 77.196704 -435.211283) (xy 77.23414 -435.158006) (xy 77.277807 -435.109704) (xy 77.302106 -435.08803)
			(xy 77.382878 -434.923184) (xy 77.387579 -434.912667) (xy 77.391071 -434.889909) (xy 77.387585 -434.86715)
			(xy 77.382878 -434.856636) (xy 77.302106 -434.69179) (xy 77.277824 -434.6701) (xy 77.23417 -434.621793)
			(xy 77.196744 -434.568515) (xy 77.166106 -434.511065) (xy 77.142714 -434.450302) (xy 77.12692 -434.387138)
			(xy 77.11896 -434.322517) (xy 77.118464 -434.289962) (xy 77.119155 -434.250835) (xy 77.130635 -434.173429)
			(xy 77.141324 -434.135784) (xy 77.141324 -433.618894) (xy 77.141807 -433.606781) (xy 77.149294 -433.58374)
			(xy 77.163534 -433.564139) (xy 77.183132 -433.549897) (xy 77.206173 -433.542408) (xy 77.218286 -433.541932)
			(xy 78.158086 -433.541932) (xy 78.170207 -433.542372) (xy 78.193265 -433.54986) (xy 78.21288 -433.564106)
			(xy 78.227131 -433.583717) (xy 78.234625 -433.606773) (xy 78.235048 -433.618894) (xy 78.235048 -434.48986)
			(xy 79.11846 -434.48986) (xy 79.118924 -434.457303) (xy 79.126875 -434.392676) (xy 79.142665 -434.329505)
			(xy 79.166057 -434.268738) (xy 79.196701 -434.211285) (xy 79.234137 -434.158008) (xy 79.277803 -434.109706)
			(xy 79.302102 -434.088032) (xy 79.382874 -433.923186) (xy 79.387574 -433.912669) (xy 79.391067 -433.889911)
			(xy 79.387581 -433.867152) (xy 79.382874 -433.856638) (xy 79.302102 -433.691792) (xy 79.27782 -433.670102)
			(xy 79.234166 -433.621795) (xy 79.19674 -433.568517) (xy 79.166102 -433.511067) (xy 79.142711 -433.450304)
			(xy 79.126916 -433.38714) (xy 79.118956 -433.322519) (xy 79.11846 -433.289964) (xy 79.119151 -433.250837)
			(xy 79.130632 -433.173431) (xy 79.14132 -433.135786) (xy 79.14132 -432.618896) (xy 79.141713 -432.606785)
			(xy 79.149216 -432.583754) (xy 79.163483 -432.564179) (xy 79.183111 -432.549985) (xy 79.206169 -432.542568)
			(xy 79.218282 -432.542188) (xy 80.158082 -432.542188) (xy 80.170175 -432.542624) (xy 80.193183 -432.550081)
			(xy 80.212768 -432.564274) (xy 80.227017 -432.583818) (xy 80.234541 -432.606804) (xy 80.235044 -432.618896)
			(xy 80.235044 -435.16042) (xy 80.234601 -435.172526) (xy 80.227102 -435.195546) (xy 80.212845 -435.215115)
			(xy 80.193232 -435.22931) (xy 80.170189 -435.236739) (xy 80.158082 -435.237128) (xy 79.218282 -435.237128)
			(xy 79.206188 -435.236708) (xy 79.183182 -435.229242) (xy 79.163599 -435.215045) (xy 79.14935 -435.195499)
			(xy 79.141824 -435.172512) (xy 79.14132 -435.16042) (xy 79.14132 -434.644038) (xy 79.130624 -434.606395)
			(xy 79.119153 -434.528987) (xy 79.11846 -434.48986) (xy 78.235048 -434.48986) (xy 78.235048 -435.489858)
			(xy 81.118456 -435.489858) (xy 81.11892 -435.457301) (xy 81.126871 -435.392674) (xy 81.142661 -435.329503)
			(xy 81.166054 -435.268736) (xy 81.196697 -435.211283) (xy 81.234133 -435.158006) (xy 81.277799 -435.109704)
			(xy 81.302098 -435.08803) (xy 81.38287 -434.923184) (xy 81.387572 -434.912667) (xy 81.391064 -434.889909)
			(xy 81.387577 -434.86715) (xy 81.38287 -434.856636) (xy 81.302098 -434.69179) (xy 81.277814 -434.670102)
			(xy 81.234161 -434.621794) (xy 81.196735 -434.568516) (xy 81.166097 -434.511066) (xy 81.142706 -434.450303)
			(xy 81.126912 -434.387138) (xy 81.118952 -434.322517) (xy 81.118456 -434.289962) (xy 81.119147 -434.250835)
			(xy 81.130628 -434.173429) (xy 81.141316 -434.135784) (xy 81.141316 -433.618894) (xy 81.141807 -433.606781)
			(xy 81.149293 -433.583742) (xy 81.163531 -433.564142) (xy 81.183127 -433.5499) (xy 81.206165 -433.542409)
			(xy 81.218278 -433.541932) (xy 82.158078 -433.541932) (xy 82.170199 -433.542379) (xy 82.193256 -433.549864)
			(xy 82.212871 -433.564109) (xy 82.227123 -433.583719) (xy 82.234617 -433.606773) (xy 82.23504 -433.618894)
			(xy 82.23504 -434.48986) (xy 83.118452 -434.48986) (xy 83.118919 -434.457303) (xy 83.12687 -434.392676)
			(xy 83.14266 -434.329506) (xy 83.166051 -434.268739) (xy 83.196694 -434.211286) (xy 83.23413 -434.158009)
			(xy 83.277795 -434.109706) (xy 83.302094 -434.088032) (xy 83.382866 -433.923186) (xy 83.387562 -433.912668)
			(xy 83.39105 -433.889911) (xy 83.387568 -433.867153) (xy 83.382866 -433.856638) (xy 83.302094 -433.691792)
			(xy 83.27781 -433.670104) (xy 83.234157 -433.621796) (xy 83.196731 -433.568518) (xy 83.166094 -433.511067)
			(xy 83.142702 -433.450305) (xy 83.126908 -433.38714) (xy 83.118948 -433.322519) (xy 83.118452 -433.289964)
			(xy 83.119144 -433.250837) (xy 83.130624 -433.173431) (xy 83.141312 -433.135786) (xy 83.141312 -432.618896)
			(xy 83.141713 -432.606786) (xy 83.149215 -432.583756) (xy 83.16348 -432.564182) (xy 83.183106 -432.549988)
			(xy 83.206162 -432.542569) (xy 83.218274 -432.542188) (xy 84.158074 -432.542188) (xy 84.170167 -432.54263)
			(xy 84.193175 -432.550086) (xy 84.212759 -432.564277) (xy 84.227009 -432.583819) (xy 84.234533 -432.606804)
			(xy 84.235036 -432.618896) (xy 84.235036 -435.16042) (xy 84.234601 -435.172526) (xy 84.227101 -435.195548)
			(xy 84.212843 -435.215118) (xy 84.193227 -435.229313) (xy 84.170182 -435.23674) (xy 84.158074 -435.237128)
			(xy 83.218274 -435.237128) (xy 83.20618 -435.236714) (xy 83.183173 -435.229247) (xy 83.163591 -435.215047)
			(xy 83.149342 -435.195501) (xy 83.141816 -435.172513) (xy 83.141312 -435.16042) (xy 83.141312 -434.644038)
			(xy 83.130616 -434.606395) (xy 83.119145 -434.528987) (xy 83.118452 -434.48986) (xy 82.23504 -434.48986)
			(xy 82.23504 -435.489858) (xy 85.118448 -435.489858) (xy 85.118915 -435.457301) (xy 85.126866 -435.392674)
			(xy 85.142656 -435.329504) (xy 85.166048 -435.268737) (xy 85.196691 -435.211284) (xy 85.234126 -435.158007)
			(xy 85.277791 -435.109704) (xy 85.30209 -435.08803) (xy 85.382862 -434.923184) (xy 85.387559 -434.912666)
			(xy 85.391047 -434.889909) (xy 85.387565 -434.867151) (xy 85.382862 -434.856636) (xy 85.30209 -434.69179)
			(xy 85.277804 -434.670104) (xy 85.234152 -434.621796) (xy 85.196726 -434.568517) (xy 85.166089 -434.511066)
			(xy 85.142698 -434.450303) (xy 85.126904 -434.387138) (xy 85.118944 -434.322517) (xy 85.118448 -434.289962)
			(xy 85.119139 -434.250835) (xy 85.13062 -434.173429) (xy 85.141308 -434.135784) (xy 85.141308 -433.618894)
			(xy 85.141806 -433.606782) (xy 85.149292 -433.583744) (xy 85.163528 -433.564145) (xy 85.183122 -433.549903)
			(xy 85.206158 -433.54241) (xy 85.21827 -433.541932) (xy 86.15807 -433.541932) (xy 86.170191 -433.542385)
			(xy 86.193247 -433.549869) (xy 86.212863 -433.564112) (xy 86.227115 -433.58372) (xy 86.234609 -433.606774)
			(xy 86.235032 -433.618894) (xy 86.235032 -434.48986) (xy 87.118444 -434.48986) (xy 87.118914 -434.457303)
			(xy 87.126865 -434.392677) (xy 87.142654 -434.329506) (xy 87.166045 -434.268739) (xy 87.196688 -434.211286)
			(xy 87.234122 -434.158009) (xy 87.277788 -434.109706) (xy 87.302086 -434.088032) (xy 87.382858 -433.923186)
			(xy 87.387554 -433.912668) (xy 87.391043 -433.889911) (xy 87.387561 -433.867153) (xy 87.382858 -433.856638)
			(xy 87.302086 -433.691792) (xy 87.277801 -433.670106) (xy 87.234148 -433.621797) (xy 87.196723 -433.568519)
			(xy 87.166085 -433.511068) (xy 87.142694 -433.450305) (xy 87.1269 -433.38714) (xy 87.11894 -433.322519)
			(xy 87.118444 -433.289964) (xy 87.119136 -433.250837) (xy 87.130616 -433.173431) (xy 87.141304 -433.135786)
			(xy 87.141304 -432.618896) (xy 87.141713 -432.606787) (xy 87.149214 -432.583758) (xy 87.163477 -432.564185)
			(xy 87.183101 -432.549991) (xy 87.206155 -432.542571) (xy 87.218266 -432.542188) (xy 88.158066 -432.542188)
			(xy 88.170159 -432.542637) (xy 88.193166 -432.55009) (xy 88.212751 -432.56428) (xy 88.227001 -432.583821)
			(xy 88.234525 -432.606805) (xy 88.235028 -432.618896) (xy 88.235028 -435.16042) (xy 88.234601 -435.172527)
			(xy 88.2271 -435.19555) (xy 88.21284 -435.215121) (xy 88.193222 -435.229316) (xy 88.170174 -435.236741)
			(xy 88.158066 -435.237128) (xy 87.218266 -435.237128) (xy 87.206171 -435.236721) (xy 87.183164 -435.229251)
			(xy 87.163582 -435.21505) (xy 87.149334 -435.195502) (xy 87.141808 -435.172513) (xy 87.141304 -435.16042)
			(xy 87.141304 -434.644038) (xy 87.130608 -434.606395) (xy 87.119137 -434.528987) (xy 87.118444 -434.48986)
			(xy 86.235032 -434.48986) (xy 86.235032 -435.489858) (xy 89.11844 -435.489858) (xy 89.11891 -435.457301)
			(xy 89.126861 -435.392675) (xy 89.14265 -435.329504) (xy 89.166042 -435.268737) (xy 89.196684 -435.211284)
			(xy 89.234119 -435.158007) (xy 89.277784 -435.109705) (xy 89.302082 -435.08803) (xy 89.382854 -434.923184)
			(xy 89.387552 -434.912666) (xy 89.39104 -434.889909) (xy 89.387557 -434.867151) (xy 89.382854 -434.856636)
			(xy 89.302082 -434.69179) (xy 89.277795 -434.670106) (xy 89.234142 -434.621797) (xy 89.196717 -434.568518)
			(xy 89.16608 -434.511067) (xy 89.14269 -434.450303) (xy 89.126896 -434.387138) (xy 89.118936 -434.322517)
			(xy 89.11844 -434.289962) (xy 89.119132 -434.250835) (xy 89.130612 -434.173429) (xy 89.1413 -434.135784)
			(xy 89.1413 -433.618894) (xy 89.141806 -433.606783) (xy 89.14929 -433.583746) (xy 89.163525 -433.564148)
			(xy 89.183117 -433.549905) (xy 89.206151 -433.542411) (xy 89.218262 -433.541932) (xy 90.158062 -433.541932)
			(xy 90.170182 -433.542392) (xy 90.193239 -433.549873) (xy 90.212854 -433.564115) (xy 90.227107 -433.583722)
			(xy 90.234601 -433.606774) (xy 90.235024 -433.618894) (xy 90.235024 -436.160418) (xy 90.234655 -436.172545)
			(xy 90.227153 -436.195611) (xy 90.212889 -436.215229) (xy 90.193261 -436.229478) (xy 90.17019 -436.236963)
			(xy 90.158062 -436.23738) (xy 89.218262 -436.23738) (xy 89.206147 -436.236921) (xy 89.183106 -436.229425)
			(xy 89.163506 -436.21518) (xy 89.149265 -436.195576) (xy 89.141776 -436.172533) (xy 89.1413 -436.160418)
			(xy 89.1413 -435.644036) (xy 89.130603 -435.606393) (xy 89.119132 -435.528985) (xy 89.11844 -435.489858)
			(xy 86.235032 -435.489858) (xy 86.235032 -436.160418) (xy 86.234655 -436.172545) (xy 86.227154 -436.195609)
			(xy 86.212892 -436.215226) (xy 86.193266 -436.229476) (xy 86.170197 -436.236962) (xy 86.15807 -436.23738)
			(xy 85.21827 -436.23738) (xy 85.206156 -436.236914) (xy 85.183114 -436.229421) (xy 85.163515 -436.215177)
			(xy 85.149274 -436.195575) (xy 85.141784 -436.172532) (xy 85.141308 -436.160418) (xy 85.141308 -435.644036)
			(xy 85.130612 -435.606393) (xy 85.11914 -435.528985) (xy 85.118448 -435.489858) (xy 82.23504 -435.489858)
			(xy 82.23504 -436.160418) (xy 82.234655 -436.172544) (xy 82.227155 -436.195607) (xy 82.212895 -436.215224)
			(xy 82.193271 -436.229473) (xy 82.170204 -436.236961) (xy 82.158078 -436.23738) (xy 81.218278 -436.23738)
			(xy 81.206164 -436.236907) (xy 81.183123 -436.229416) (xy 81.163523 -436.215174) (xy 81.149282 -436.195573)
			(xy 81.141792 -436.172532) (xy 81.141316 -436.160418) (xy 81.141316 -435.644036) (xy 81.13062 -435.606393)
			(xy 81.119148 -435.528985) (xy 81.118456 -435.489858) (xy 78.235048 -435.489858) (xy 78.235048 -436.160418)
			(xy 78.234604 -436.172535) (xy 78.22711 -436.195581) (xy 78.212861 -436.215184) (xy 78.193252 -436.229424)
			(xy 78.170203 -436.236909) (xy 78.158086 -436.23738) (xy 77.218286 -436.23738) (xy 77.206172 -436.236901)
			(xy 77.183132 -436.229412) (xy 77.163532 -436.215171) (xy 77.14929 -436.195572) (xy 77.1418 -436.172531)
			(xy 77.141324 -436.160418) (xy 77.141324 -435.644036) (xy 77.130628 -435.606393) (xy 77.119156 -435.528985)
			(xy 77.118464 -435.489858) (xy 73.234804 -435.489858) (xy 73.234804 -436.160418) (xy 73.234309 -436.172504)
			(xy 73.226853 -436.195498) (xy 73.212672 -436.215074) (xy 73.193147 -436.229325) (xy 73.17018 -436.236865)
			(xy 73.158096 -436.23738) (xy 72.218296 -436.23738) (xy 72.206185 -436.236987) (xy 72.183154 -436.229484)
			(xy 72.163579 -436.215217) (xy 72.149385 -436.195589) (xy 72.141968 -436.172531) (xy 72.141588 -436.160418)
			(xy 72.141588 -435.644798) (xy 72.13078 -435.606979) (xy 72.119179 -435.529185) (xy 72.118474 -435.489858)
			(xy 69.234812 -435.489858) (xy 69.234812 -436.160418) (xy 69.234407 -436.172513) (xy 69.22694 -436.195523)
			(xy 69.212739 -436.215106) (xy 69.193189 -436.229355) (xy 69.170198 -436.236878) (xy 69.158104 -436.23738)
			(xy 68.218304 -436.23738) (xy 68.206193 -436.23698) (xy 68.183163 -436.229479) (xy 68.163588 -436.215214)
			(xy 68.149394 -436.195588) (xy 68.141976 -436.17253) (xy 68.141596 -436.160418) (xy 68.141596 -435.644798)
			(xy 68.130788 -435.606979) (xy 68.119187 -435.529185) (xy 68.118482 -435.489858) (xy 65.23482 -435.489858)
			(xy 65.23482 -436.160418) (xy 65.234407 -436.172513) (xy 65.226941 -436.195521) (xy 65.212742 -436.215104)
			(xy 65.193194 -436.229352) (xy 65.170205 -436.236877) (xy 65.158112 -436.23738) (xy 64.218312 -436.23738)
			(xy 64.206202 -436.236973) (xy 64.183172 -436.229474) (xy 64.163597 -436.215211) (xy 64.149402 -436.195586)
			(xy 64.141985 -436.17253) (xy 64.141604 -436.160418) (xy 64.141604 -435.644798) (xy 64.130796 -435.606979)
			(xy 64.119195 -435.529185) (xy 64.11849 -435.489858) (xy 61.234828 -435.489858) (xy 61.234828 -436.160418)
			(xy 61.234408 -436.172512) (xy 61.226942 -436.195518) (xy 61.212745 -436.215101) (xy 61.193199 -436.22935)
			(xy 61.170212 -436.236876) (xy 61.15812 -436.23738) (xy 60.21832 -436.23738) (xy 60.20621 -436.236966)
			(xy 60.18318 -436.22947) (xy 60.163605 -436.215208) (xy 60.149411 -436.195585) (xy 60.141993 -436.172529)
			(xy 60.141612 -436.160418) (xy 60.141612 -435.644798) (xy 60.130804 -435.606979) (xy 60.119203 -435.529185)
			(xy 60.118498 -435.489858) (xy 7.00913 -435.489858) (xy 7.00913 -438.089802) (xy 58.13806 -438.089802)
			(xy 58.138177 -438.074717) (xy 58.139953 -438.044598) (xy 58.141616 -438.029604) (xy 58.141616 -436.950104)
			(xy 58.139946 -436.935111) (xy 58.138168 -436.904992) (xy 58.13806 -436.889906) (xy 58.138168 -436.87482)
			(xy 58.13995 -436.844702) (xy 58.141616 -436.829708) (xy 58.141616 -436.219092) (xy 58.142006 -436.207006)
			(xy 58.149479 -436.184019) (xy 58.16369 -436.164467) (xy 58.183248 -436.150264) (xy 58.206238 -436.142801)
			(xy 58.218324 -436.142384) (xy 59.158124 -436.142384) (xy 59.170199 -436.142844) (xy 59.193166 -436.150312)
			(xy 59.212701 -436.16451) (xy 59.226895 -436.184049) (xy 59.234359 -436.207017) (xy 59.234832 -436.219092)
			(xy 59.234832 -438.760616) (xy 59.23435 -438.772689) (xy 59.226886 -438.795653) (xy 59.212693 -438.815187)
			(xy 59.19316 -438.829382) (xy 59.170197 -438.836848) (xy 59.158124 -438.837324) (xy 58.218324 -438.837324)
			(xy 58.206244 -438.836867) (xy 58.183265 -438.829408) (xy 58.163716 -438.815213) (xy 58.14951 -438.795671)
			(xy 58.142039 -438.772696) (xy 58.141616 -438.760616) (xy 58.141616 -438.15) (xy 58.139945 -438.135007)
			(xy 58.138168 -438.104888) (xy 58.13806 -438.089802) (xy 7.00913 -438.089802) (xy 7.00913 -439.0898)
			(xy 60.138056 -439.0898) (xy 60.138173 -439.074715) (xy 60.139949 -439.044596) (xy 60.141612 -439.029602)
			(xy 60.141612 -437.950102) (xy 60.139941 -437.935109) (xy 60.138164 -437.90499) (xy 60.138056 -437.889904)
			(xy 60.138173 -437.874819) (xy 60.139949 -437.8447) (xy 60.141612 -437.829706) (xy 60.141612 -437.21909)
			(xy 60.142099 -437.207003) (xy 60.149555 -437.184007) (xy 60.163737 -437.164429) (xy 60.183265 -437.150178)
			(xy 60.206234 -437.142641) (xy 60.21832 -437.142128) (xy 61.15812 -437.142128) (xy 61.170233 -437.1425)
			(xy 61.193265 -437.150008) (xy 61.212841 -437.16428) (xy 61.227034 -437.183913) (xy 61.234449 -437.206976)
			(xy 61.234828 -437.21909) (xy 61.234828 -438.089802) (xy 62.138052 -438.089802) (xy 62.138169 -438.074717)
			(xy 62.139945 -438.044598) (xy 62.141608 -438.029604) (xy 62.141608 -436.950104) (xy 62.139938 -436.935111)
			(xy 62.13816 -436.904992) (xy 62.138052 -436.889906) (xy 62.13816 -436.87482) (xy 62.139942 -436.844702)
			(xy 62.141608 -436.829708) (xy 62.141608 -436.219092) (xy 62.142006 -436.207007) (xy 62.149478 -436.184021)
			(xy 62.163687 -436.16447) (xy 62.183243 -436.150267) (xy 62.206231 -436.142802) (xy 62.218316 -436.142384)
			(xy 63.158116 -436.142384) (xy 63.170191 -436.142851) (xy 63.193157 -436.150317) (xy 63.212693 -436.164513)
			(xy 63.226887 -436.18405) (xy 63.234351 -436.207017) (xy 63.234824 -436.219092) (xy 63.234824 -438.760616)
			(xy 63.23435 -438.77269) (xy 63.226885 -438.795655) (xy 63.21269 -438.81519) (xy 63.193155 -438.829385)
			(xy 63.17019 -438.83685) (xy 63.158116 -438.837324) (xy 62.218316 -438.837324) (xy 62.206244 -438.836822)
			(xy 62.18328 -438.829366) (xy 62.163744 -438.815179) (xy 62.149548 -438.795649) (xy 62.142083 -438.772688)
			(xy 62.141608 -438.760616) (xy 62.141608 -438.15) (xy 62.139937 -438.135007) (xy 62.13816 -438.104888)
			(xy 62.138052 -438.089802) (xy 61.234828 -438.089802) (xy 61.234828 -439.0898) (xy 64.138048 -439.0898)
			(xy 64.138165 -439.074715) (xy 64.139941 -439.044596) (xy 64.141604 -439.029602) (xy 64.141604 -437.950102)
			(xy 64.139933 -437.935109) (xy 64.138156 -437.90499) (xy 64.138048 -437.889904) (xy 64.138165 -437.874819)
			(xy 64.139941 -437.8447) (xy 64.141604 -437.829706) (xy 64.141604 -437.21909) (xy 64.142098 -437.207004)
			(xy 64.149553 -437.184009) (xy 64.163734 -437.164432) (xy 64.18326 -437.150181) (xy 64.206227 -437.142643)
			(xy 64.218312 -437.142128) (xy 65.158112 -437.142128) (xy 65.170224 -437.142506) (xy 65.193257 -437.150012)
			(xy 65.212832 -437.164283) (xy 65.227025 -437.183914) (xy 65.234441 -437.206976) (xy 65.23482 -437.21909)
			(xy 65.23482 -438.089802) (xy 66.138044 -438.089802) (xy 66.138161 -438.074717) (xy 66.139937 -438.044598)
			(xy 66.1416 -438.029604) (xy 66.1416 -436.950104) (xy 66.13993 -436.935111) (xy 66.138152 -436.904992)
			(xy 66.138044 -436.889906) (xy 66.138152 -436.87482) (xy 66.139934 -436.844702) (xy 66.1416 -436.829708)
			(xy 66.1416 -436.219092) (xy 66.142058 -436.207016) (xy 66.149523 -436.184047) (xy 66.163721 -436.16451)
			(xy 66.183262 -436.150316) (xy 66.206232 -436.142855) (xy 66.218308 -436.142384) (xy 67.158108 -436.142384)
			(xy 67.170182 -436.142857) (xy 67.193148 -436.150321) (xy 67.212684 -436.164516) (xy 67.226879 -436.184052)
			(xy 67.234343 -436.207018) (xy 67.234816 -436.219092) (xy 67.234816 -438.760616) (xy 67.234349 -438.772691)
			(xy 67.226883 -438.795657) (xy 67.212687 -438.815193) (xy 67.19315 -438.829387) (xy 67.170183 -438.836851)
			(xy 67.158108 -438.837324) (xy 66.218308 -438.837324) (xy 66.206235 -438.836829) (xy 66.183271 -438.829371)
			(xy 66.163735 -438.815182) (xy 66.14954 -438.79565) (xy 66.142075 -438.772688) (xy 66.1416 -438.760616)
			(xy 66.1416 -438.15) (xy 66.139929 -438.135007) (xy 66.138152 -438.104888) (xy 66.138044 -438.089802)
			(xy 65.23482 -438.089802) (xy 65.23482 -439.0898) (xy 68.13804 -439.0898) (xy 68.138157 -439.074715)
			(xy 68.139933 -439.044596) (xy 68.141596 -439.029602) (xy 68.141596 -437.950102) (xy 68.139925 -437.935109)
			(xy 68.138148 -437.90499) (xy 68.13804 -437.889904) (xy 68.138157 -437.874819) (xy 68.139933 -437.8447)
			(xy 68.141596 -437.829706) (xy 68.141596 -437.21909) (xy 68.142098 -437.207004) (xy 68.149552 -437.184011)
			(xy 68.163731 -437.164435) (xy 68.183255 -437.150183) (xy 68.20622 -437.142644) (xy 68.218304 -437.142128)
			(xy 69.158104 -437.142128) (xy 69.170216 -437.142513) (xy 69.193248 -437.150017) (xy 69.212824 -437.164286)
			(xy 69.227017 -437.183916) (xy 69.234433 -437.206977) (xy 69.234812 -437.21909) (xy 69.234812 -438.089802)
			(xy 70.138036 -438.089802) (xy 70.138153 -438.074717) (xy 70.139929 -438.044598) (xy 70.141592 -438.029604)
			(xy 70.141592 -436.950104) (xy 70.139922 -436.935111) (xy 70.138144 -436.904992) (xy 70.138036 -436.889906)
			(xy 70.138146 -436.87482) (xy 70.139928 -436.844702) (xy 70.141592 -436.829708) (xy 70.141592 -436.219092)
			(xy 70.142058 -436.207017) (xy 70.149522 -436.18405) (xy 70.163718 -436.164513) (xy 70.183257 -436.150319)
			(xy 70.206225 -436.142856) (xy 70.2183 -436.142384) (xy 71.1581 -436.142384) (xy 71.170174 -436.142864)
			(xy 71.19314 -436.150326) (xy 71.212676 -436.164518) (xy 71.226871 -436.184053) (xy 71.234335 -436.207018)
			(xy 71.234808 -436.219092) (xy 71.234808 -438.760616) (xy 71.234349 -438.772691) (xy 71.226882 -438.795659)
			(xy 71.212684 -438.815196) (xy 71.193145 -438.82939) (xy 71.170175 -438.836852) (xy 71.1581 -438.837324)
			(xy 70.2183 -438.837324) (xy 70.206227 -438.836836) (xy 70.183263 -438.829375) (xy 70.163727 -438.815184)
			(xy 70.149532 -438.795652) (xy 70.142067 -438.772689) (xy 70.141592 -438.760616) (xy 70.141592 -438.15)
			(xy 70.139921 -438.135007) (xy 70.138144 -438.104888) (xy 70.138036 -438.089802) (xy 69.234812 -438.089802)
			(xy 69.234812 -439.0898) (xy 72.138032 -439.0898) (xy 72.138151 -439.074715) (xy 72.139927 -439.044596)
			(xy 72.141588 -439.029602) (xy 72.141588 -437.950102) (xy 72.139917 -437.935109) (xy 72.13814 -437.90499)
			(xy 72.138032 -437.889904) (xy 72.138151 -437.874819) (xy 72.139927 -437.8447) (xy 72.141588 -437.829706)
			(xy 72.141588 -437.21909) (xy 72.142 -437.206995) (xy 72.149465 -437.183986) (xy 72.163664 -437.164402)
			(xy 72.183212 -437.150154) (xy 72.206202 -437.142631) (xy 72.218296 -437.142128) (xy 73.158096 -437.142128)
			(xy 73.170207 -437.14252) (xy 73.193239 -437.150022) (xy 73.212815 -437.164288) (xy 73.227009 -437.183917)
			(xy 73.234425 -437.206977) (xy 73.234804 -437.21909) (xy 73.234804 -438.089802) (xy 75.138026 -438.089802)
			(xy 75.138119 -438.075228) (xy 75.139772 -438.046127) (xy 75.141328 -438.031636) (xy 75.141328 -436.948072)
			(xy 75.139784 -436.93358) (xy 75.138131 -436.90448) (xy 75.138026 -436.889906) (xy 75.138119 -436.875332)
			(xy 75.139772 -436.846231) (xy 75.141328 -436.83174) (xy 75.141328 -436.219092) (xy 75.14171 -436.20698)
			(xy 75.149215 -436.183948) (xy 75.163484 -436.164372) (xy 75.183115 -436.150179) (xy 75.206176 -436.142763)
			(xy 75.21829 -436.142384) (xy 76.15809 -436.142384) (xy 76.170183 -436.142817) (xy 76.193191 -436.150276)
			(xy 76.212775 -436.16447) (xy 76.227024 -436.184014) (xy 76.234549 -436.207) (xy 76.235052 -436.219092)
			(xy 76.235052 -438.760616) (xy 76.234598 -438.772721) (xy 76.227101 -438.795739) (xy 76.212847 -438.815308)
			(xy 76.193237 -438.829504) (xy 76.170196 -438.836933) (xy 76.15809 -438.837324) (xy 75.21829 -438.837324)
			(xy 75.206196 -438.8369) (xy 75.183189 -438.829436) (xy 75.163607 -438.81524) (xy 75.149358 -438.795695)
			(xy 75.141832 -438.772708) (xy 75.141328 -438.760616) (xy 75.141328 -438.147968) (xy 75.139783 -438.133476)
			(xy 75.138131 -438.104376) (xy 75.138026 -438.089802) (xy 73.234804 -438.089802) (xy 73.234804 -439.0898)
			(xy 77.138022 -439.0898) (xy 77.138115 -439.075226) (xy 77.139768 -439.046125) (xy 77.141324 -439.031634)
			(xy 77.141324 -437.94807) (xy 77.139779 -437.933578) (xy 77.138127 -437.904478) (xy 77.138022 -437.889904)
			(xy 77.138115 -437.87533) (xy 77.139768 -437.846229) (xy 77.141324 -437.831738) (xy 77.141324 -437.21909)
			(xy 77.141803 -437.206976) (xy 77.149291 -437.183935) (xy 77.163532 -437.164335) (xy 77.183132 -437.150093)
			(xy 77.206172 -437.142604) (xy 77.218286 -437.142128) (xy 78.158086 -437.142128) (xy 78.170207 -437.142572)
			(xy 78.193264 -437.150059) (xy 78.212878 -437.164305) (xy 78.22713 -437.183915) (xy 78.234624 -437.206969)
			(xy 78.235048 -437.21909) (xy 78.235048 -438.089802) (xy 79.138018 -438.089802) (xy 79.138111 -438.075228)
			(xy 79.139764 -438.046127) (xy 79.14132 -438.031636) (xy 79.14132 -436.948072) (xy 79.139776 -436.93358)
			(xy 79.138123 -436.90448) (xy 79.138018 -436.889906) (xy 79.138111 -436.875332) (xy 79.139764 -436.846231)
			(xy 79.14132 -436.83174) (xy 79.14132 -436.219092) (xy 79.14171 -436.206981) (xy 79.149214 -436.18395)
			(xy 79.163481 -436.164375) (xy 79.18311 -436.150181) (xy 79.206169 -436.142764) (xy 79.218282 -436.142384)
			(xy 80.158082 -436.142384) (xy 80.170175 -436.142824) (xy 80.193182 -436.150281) (xy 80.212766 -436.164473)
			(xy 80.227016 -436.184015) (xy 80.234541 -436.207) (xy 80.235044 -436.219092) (xy 80.235044 -438.760616)
			(xy 80.234598 -438.772721) (xy 80.227099 -438.795742) (xy 80.212844 -438.815311) (xy 80.193232 -438.829506)
			(xy 80.170189 -438.836935) (xy 80.158082 -438.837324) (xy 79.218282 -438.837324) (xy 79.206188 -438.836907)
			(xy 79.183181 -438.829441) (xy 79.163598 -438.815243) (xy 79.149349 -438.795697) (xy 79.141824 -438.772709)
			(xy 79.14132 -438.760616) (xy 79.14132 -438.147968) (xy 79.139775 -438.133476) (xy 79.138123 -438.104376)
			(xy 79.138018 -438.089802) (xy 78.235048 -438.089802) (xy 78.235048 -439.0898) (xy 81.138014 -439.0898)
			(xy 81.138106 -439.075226) (xy 81.13976 -439.046125) (xy 81.141316 -439.031634) (xy 81.141316 -437.94807)
			(xy 81.139771 -437.933578) (xy 81.138119 -437.904478) (xy 81.138014 -437.889904) (xy 81.138107 -437.87533)
			(xy 81.13976 -437.846229) (xy 81.141316 -437.831738) (xy 81.141316 -437.21909) (xy 81.141803 -437.206977)
			(xy 81.14929 -437.183937) (xy 81.163529 -437.164338) (xy 81.183127 -437.150096) (xy 81.206165 -437.142605)
			(xy 81.218278 -437.142128) (xy 82.158078 -437.142128) (xy 82.170199 -437.142579) (xy 82.193255 -437.150064)
			(xy 82.21287 -437.164308) (xy 82.227122 -437.183916) (xy 82.234616 -437.20697) (xy 82.23504 -437.21909)
			(xy 82.23504 -438.089802) (xy 83.13801 -438.089802) (xy 83.138103 -438.075228) (xy 83.139756 -438.046127)
			(xy 83.141312 -438.031636) (xy 83.141312 -436.948072) (xy 83.139767 -436.93358) (xy 83.138115 -436.90448)
			(xy 83.13801 -436.889906) (xy 83.138103 -436.875332) (xy 83.139756 -436.846231) (xy 83.141312 -436.83174)
			(xy 83.141312 -436.219092) (xy 83.14171 -436.206981) (xy 83.149213 -436.183952) (xy 83.163479 -436.164378)
			(xy 83.183105 -436.150184) (xy 83.206162 -436.142765) (xy 83.218274 -436.142384) (xy 84.158074 -436.142384)
			(xy 84.170167 -436.14283) (xy 84.193174 -436.150285) (xy 84.212758 -436.164476) (xy 84.227008 -436.184017)
			(xy 84.234533 -436.207001) (xy 84.235036 -436.219092) (xy 84.235036 -438.760616) (xy 84.234598 -438.772722)
			(xy 84.227098 -438.795744) (xy 84.212841 -438.815313) (xy 84.193227 -438.829509) (xy 84.170181 -438.836936)
			(xy 84.158074 -438.837324) (xy 83.218274 -438.837324) (xy 83.206179 -438.836914) (xy 83.183172 -438.829446)
			(xy 83.163589 -438.815246) (xy 83.149341 -438.795698) (xy 83.141816 -438.772709) (xy 83.141312 -438.760616)
			(xy 83.141312 -438.147968) (xy 83.139767 -438.133476) (xy 83.138115 -438.104376) (xy 83.13801 -438.089802)
			(xy 82.23504 -438.089802) (xy 82.23504 -439.0898) (xy 85.138006 -439.0898) (xy 85.138098 -439.075226)
			(xy 85.139752 -439.046125) (xy 85.141308 -439.031634) (xy 85.141308 -437.94807) (xy 85.139763 -437.933578)
			(xy 85.138111 -437.904478) (xy 85.138006 -437.889904) (xy 85.138099 -437.87533) (xy 85.139752 -437.846229)
			(xy 85.141308 -437.831738) (xy 85.141308 -437.21909) (xy 85.141803 -437.206978) (xy 85.149289 -437.18394)
			(xy 85.163526 -437.164341) (xy 85.183122 -437.150098) (xy 85.206158 -437.142606) (xy 85.21827 -437.142128)
			(xy 86.15807 -437.142128) (xy 86.17019 -437.142585) (xy 86.193246 -437.150068) (xy 86.212861 -437.16431)
			(xy 86.227114 -437.183918) (xy 86.234608 -437.20697) (xy 86.235032 -437.21909) (xy 86.235032 -438.089802)
			(xy 87.138002 -438.089802) (xy 87.138095 -438.075228) (xy 87.139748 -438.046127) (xy 87.141304 -438.031636)
			(xy 87.141304 -436.948072) (xy 87.139759 -436.93358) (xy 87.138107 -436.90448) (xy 87.138002 -436.889906)
			(xy 87.138095 -436.875332) (xy 87.139748 -436.846231) (xy 87.141304 -436.83174) (xy 87.141304 -436.219092)
			(xy 87.141709 -436.206982) (xy 87.149212 -436.183954) (xy 87.163476 -436.164381) (xy 87.1831 -436.150186)
			(xy 87.206155 -436.142767) (xy 87.218266 -436.142384) (xy 88.158066 -436.142384) (xy 88.170158 -436.142837)
			(xy 88.193165 -436.15029) (xy 88.212749 -436.164478) (xy 88.227 -436.184018) (xy 88.234525 -436.207001)
			(xy 88.235028 -436.219092) (xy 88.235028 -438.760616) (xy 88.234598 -438.772723) (xy 88.227097 -438.795746)
			(xy 88.212838 -438.815316) (xy 88.193222 -438.829511) (xy 88.170174 -438.836937) (xy 88.158066 -438.837324)
			(xy 87.218266 -438.837324) (xy 87.206171 -438.836921) (xy 87.183163 -438.829451) (xy 87.163581 -438.815249)
			(xy 87.149333 -438.7957) (xy 87.141808 -438.77271) (xy 87.141304 -438.760616) (xy 87.141304 -438.147968)
			(xy 87.139759 -438.133476) (xy 87.138107 -438.104376) (xy 87.138002 -438.089802) (xy 86.235032 -438.089802)
			(xy 86.235032 -439.0898) (xy 89.137998 -439.0898) (xy 89.13809 -439.075226) (xy 89.139744 -439.046125)
			(xy 89.1413 -439.031634) (xy 89.1413 -437.94807) (xy 89.139755 -437.933578) (xy 89.138103 -437.904478)
			(xy 89.137998 -437.889904) (xy 89.138091 -437.87533) (xy 89.139744 -437.846229) (xy 89.1413 -437.831738)
			(xy 89.1413 -437.21909) (xy 89.141803 -437.206979) (xy 89.149288 -437.183942) (xy 89.163524 -437.164343)
			(xy 89.183117 -437.150101) (xy 89.206151 -437.142607) (xy 89.218262 -437.142128) (xy 90.158062 -437.142128)
			(xy 90.170182 -437.142592) (xy 90.193238 -437.150073) (xy 90.212853 -437.164313) (xy 90.227105 -437.183919)
			(xy 90.2346 -437.20697) (xy 90.235024 -437.21909) (xy 90.235024 -439.0898) (xy 127.21844 -439.0898)
			(xy 127.218948 -439.05722) (xy 127.226922 -438.992549) (xy 127.242739 -438.929336) (xy 127.266162 -438.868531)
			(xy 127.296839 -438.811043) (xy 127.334312 -438.757735) (xy 127.378017 -438.709405) (xy 127.402336 -438.687718)
			(xy 127.482854 -438.52338) (xy 127.487555 -438.512864) (xy 127.491042 -438.490105) (xy 127.487558 -438.467347)
			(xy 127.482854 -438.456832) (xy 127.401828 -438.291732) (xy 127.377558 -438.270043) (xy 127.33396 -438.22171)
			(xy 127.296586 -438.168418) (xy 127.265993 -438.110964) (xy 127.242639 -438.050207) (xy 127.226873 -437.987054)
			(xy 127.21893 -437.92245) (xy 127.21844 -437.889904) (xy 127.219141 -437.850778) (xy 127.230615 -437.773371)
			(xy 127.2413 -437.735726) (xy 127.2413 -437.21909) (xy 127.241803 -437.206979) (xy 127.249288 -437.183942)
			(xy 127.263524 -437.164343) (xy 127.283117 -437.150101) (xy 127.306151 -437.142607) (xy 127.318262 -437.142128)
			(xy 128.258062 -437.142128) (xy 128.270182 -437.142592) (xy 128.293238 -437.150073) (xy 128.312853 -437.164313)
			(xy 128.327105 -437.183919) (xy 128.3346 -437.20697) (xy 128.335024 -437.21909) (xy 128.335024 -438.089802)
			(xy 129.218436 -438.089802) (xy 129.218946 -438.057222) (xy 129.226921 -437.992551) (xy 129.242737 -437.929339)
			(xy 129.26616 -437.868533) (xy 129.296837 -437.811045) (xy 129.334308 -437.757737) (xy 129.378013 -437.709407)
			(xy 129.402332 -437.68772) (xy 129.48285 -437.523382) (xy 129.487549 -437.512865) (xy 129.491037 -437.490107)
			(xy 129.487554 -437.467349) (xy 129.48285 -437.456834) (xy 129.401824 -437.291734) (xy 129.377554 -437.270045)
			(xy 129.333957 -437.221711) (xy 129.296582 -437.16842) (xy 129.265989 -437.110966) (xy 129.242635 -437.050209)
			(xy 129.226869 -436.987056) (xy 129.218926 -436.922452) (xy 129.218436 -436.889906) (xy 129.219137 -436.85078)
			(xy 129.230611 -436.773373) (xy 129.241296 -436.735728) (xy 129.241296 -436.219092) (xy 129.241709 -436.206983)
			(xy 129.24921 -436.183956) (xy 129.263473 -436.164384) (xy 129.283095 -436.150189) (xy 129.306148 -436.142768)
			(xy 129.318258 -436.142384) (xy 130.258058 -436.142384) (xy 130.27015 -436.142844) (xy 130.293156 -436.150294)
			(xy 130.312741 -436.164481) (xy 130.326991 -436.184019) (xy 130.334516 -436.207002) (xy 130.33502 -436.219092)
			(xy 130.33502 -438.760616) (xy 130.334598 -438.772724) (xy 130.327096 -438.795748) (xy 130.312836 -438.815319)
			(xy 130.293217 -438.829514) (xy 130.270167 -438.836938) (xy 130.258058 -438.837324) (xy 129.318258 -438.837324)
			(xy 129.306163 -438.836928) (xy 129.283155 -438.829455) (xy 129.263572 -438.815252) (xy 129.249324 -438.795701)
			(xy 129.2418 -438.77271) (xy 129.241296 -438.760616) (xy 129.241296 -438.24398) (xy 129.230609 -438.206335)
			(xy 129.219132 -438.128928) (xy 129.218436 -438.089802) (xy 128.335024 -438.089802) (xy 128.335024 -439.0898)
			(xy 131.218432 -439.0898) (xy 131.218942 -439.05722) (xy 131.226917 -438.992549) (xy 131.242734 -438.929337)
			(xy 131.266156 -438.868531) (xy 131.296833 -438.811044) (xy 131.334304 -438.757735) (xy 131.378009 -438.709405)
			(xy 131.402328 -438.687718) (xy 131.482846 -438.52338) (xy 131.487547 -438.512864) (xy 131.491034 -438.490105)
			(xy 131.48755 -438.467347) (xy 131.482846 -438.456832) (xy 131.40182 -438.291732) (xy 131.377549 -438.270045)
			(xy 131.333951 -438.221711) (xy 131.296577 -438.168419) (xy 131.265985 -438.110965) (xy 131.242631 -438.050207)
			(xy 131.226865 -437.987054) (xy 131.218922 -437.92245) (xy 131.218432 -437.889904) (xy 131.219133 -437.850778)
			(xy 131.230607 -437.773371) (xy 131.241292 -437.735726) (xy 131.241292 -437.21909) (xy 131.241803 -437.20698)
			(xy 131.249287 -437.183944) (xy 131.263521 -437.164346) (xy 131.283112 -437.150104) (xy 131.306144 -437.142608)
			(xy 131.318254 -437.142128) (xy 132.258054 -437.142128) (xy 132.270173 -437.142599) (xy 132.293229 -437.150077)
			(xy 132.312844 -437.164316) (xy 132.327097 -437.183921) (xy 132.334592 -437.206971) (xy 132.335016 -437.21909)
			(xy 132.335016 -438.089802) (xy 133.218428 -438.089802) (xy 133.218941 -438.057222) (xy 133.226915 -437.992551)
			(xy 133.242732 -437.929339) (xy 133.266154 -437.868534) (xy 133.29683 -437.811046) (xy 133.334301 -437.757737)
			(xy 133.378005 -437.709407) (xy 133.402324 -437.68772) (xy 133.482842 -437.523382) (xy 133.487542 -437.512865)
			(xy 133.49103 -437.490107) (xy 133.487546 -437.467349) (xy 133.482842 -437.456834) (xy 133.401816 -437.291734)
			(xy 133.377545 -437.270046) (xy 133.333948 -437.221713) (xy 133.296573 -437.168421) (xy 133.265981 -437.110967)
			(xy 133.242627 -437.050209) (xy 133.226861 -436.987056) (xy 133.218918 -436.922452) (xy 133.218428 -436.889906)
			(xy 133.21913 -436.85078) (xy 133.230603 -436.773373) (xy 133.241288 -436.735728) (xy 133.241288 -436.219092)
			(xy 133.241709 -436.206984) (xy 133.249209 -436.183958) (xy 133.26347 -436.164386) (xy 133.28309 -436.150192)
			(xy 133.306141 -436.142769) (xy 133.31825 -436.142384) (xy 134.25805 -436.142384) (xy 134.270141 -436.142851)
			(xy 134.293148 -436.150299) (xy 134.312732 -436.164484) (xy 134.326983 -436.184021) (xy 134.334508 -436.207002)
			(xy 134.335012 -436.219092) (xy 134.335012 -438.760616) (xy 134.334598 -438.772725) (xy 134.327095 -438.79575)
			(xy 134.312833 -438.815322) (xy 134.293212 -438.829517) (xy 134.27016 -438.836939) (xy 134.25805 -438.837324)
			(xy 133.31825 -438.837324) (xy 133.306159 -438.836849) (xy 133.283154 -438.829402) (xy 133.26357 -438.815219)
			(xy 133.249319 -438.795684) (xy 133.241793 -438.772705) (xy 133.241288 -438.760616) (xy 133.241288 -438.24398)
			(xy 133.230601 -438.206335) (xy 133.219124 -438.128928) (xy 133.218428 -438.089802) (xy 132.335016 -438.089802)
			(xy 132.335016 -439.0898) (xy 135.218424 -439.0898) (xy 135.218937 -439.05722) (xy 135.226911 -438.992549)
			(xy 135.242728 -438.929337) (xy 135.26615 -438.868532) (xy 135.296826 -438.811044) (xy 135.334297 -438.757736)
			(xy 135.378001 -438.709405) (xy 135.40232 -438.687718) (xy 135.482838 -438.52338) (xy 135.487539 -438.512864)
			(xy 135.491027 -438.490105) (xy 135.487543 -438.467347) (xy 135.482838 -438.456832) (xy 135.401812 -438.291732)
			(xy 135.377539 -438.270046) (xy 135.333942 -438.221712) (xy 135.296568 -438.16842) (xy 135.265976 -438.110965)
			(xy 135.242623 -438.050208) (xy 135.226857 -437.987055) (xy 135.218914 -437.92245) (xy 135.218424 -437.889904)
			(xy 135.219125 -437.850778) (xy 135.230599 -437.773371) (xy 135.241284 -437.735726) (xy 135.241284 -437.21909)
			(xy 135.241652 -437.206962) (xy 135.249153 -437.183895) (xy 135.263416 -437.164276) (xy 135.283045 -437.150027)
			(xy 135.306118 -437.142544) (xy 135.318246 -437.142128) (xy 136.258046 -437.142128) (xy 136.270162 -437.142572)
			(xy 136.293205 -437.150071) (xy 136.312805 -437.164321) (xy 136.327045 -437.183927) (xy 136.334533 -437.206974)
			(xy 136.335008 -437.21909) (xy 136.335008 -438.089802) (xy 137.21842 -438.089802) (xy 137.218936 -438.057222)
			(xy 137.22691 -437.992551) (xy 137.242726 -437.92934) (xy 137.266148 -437.868534) (xy 137.296824 -437.811047)
			(xy 137.334294 -437.757738) (xy 137.377998 -437.709407) (xy 137.402316 -437.68772) (xy 137.482834 -437.523382)
			(xy 137.487534 -437.512865) (xy 137.491023 -437.490107) (xy 137.487539 -437.467349) (xy 137.482834 -437.456834)
			(xy 137.401808 -437.291734) (xy 137.377535 -437.270048) (xy 137.333938 -437.221714) (xy 137.296565 -437.168422)
			(xy 137.265972 -437.110967) (xy 137.242619 -437.05021) (xy 137.226853 -436.987057) (xy 137.21891 -436.922452)
			(xy 137.21842 -436.889906) (xy 137.219122 -436.85078) (xy 137.230595 -436.773373) (xy 137.24128 -436.735728)
			(xy 137.24128 -436.219092) (xy 137.241709 -436.206985) (xy 137.249208 -436.183961) (xy 137.263467 -436.164389)
			(xy 137.283085 -436.150194) (xy 137.306133 -436.14277) (xy 137.318242 -436.142384) (xy 138.258042 -436.142384)
			(xy 138.270138 -436.142772) (xy 138.293148 -436.150246) (xy 138.312731 -436.164451) (xy 138.326978 -436.184004)
			(xy 138.334501 -436.206997) (xy 138.335004 -436.219092) (xy 138.335004 -438.760616) (xy 138.334597 -438.772725)
			(xy 138.327094 -438.795752) (xy 138.31283 -438.815325) (xy 138.293207 -438.829519) (xy 138.270153 -438.83694)
			(xy 138.258042 -438.837324) (xy 137.318242 -438.837324) (xy 137.306151 -438.836856) (xy 137.283146 -438.829407)
			(xy 137.263562 -438.815222) (xy 137.249311 -438.795686) (xy 137.241785 -438.772705) (xy 137.24128 -438.760616)
			(xy 137.24128 -438.24398) (xy 137.230592 -438.206335) (xy 137.219116 -438.128928) (xy 137.21842 -438.089802)
			(xy 136.335008 -438.089802) (xy 136.335008 -439.0898) (xy 139.218416 -439.0898) (xy 139.218931 -439.05722)
			(xy 139.226905 -438.992549) (xy 139.242722 -438.929338) (xy 139.266144 -438.868532) (xy 139.296819 -438.811045)
			(xy 139.33429 -438.757736) (xy 139.377993 -438.709405) (xy 139.402312 -438.687718) (xy 139.48283 -438.52338)
			(xy 139.487532 -438.512864) (xy 139.49102 -438.490105) (xy 139.487535 -438.467347) (xy 139.48283 -438.456832)
			(xy 139.401804 -438.291732) (xy 139.377529 -438.270048) (xy 139.333933 -438.221713) (xy 139.296559 -438.168421)
			(xy 139.265967 -438.110966) (xy 139.242614 -438.050208) (xy 139.226849 -437.987055) (xy 139.218906 -437.92245)
			(xy 139.218416 -437.889904) (xy 139.219114 -437.850778) (xy 139.230589 -437.773371) (xy 139.241276 -437.735726)
			(xy 139.241276 -437.21909) (xy 139.241652 -437.206963) (xy 139.249152 -437.183897) (xy 139.263413 -437.164279)
			(xy 139.28304 -437.15003) (xy 139.306111 -437.142545) (xy 139.318238 -437.142128) (xy 140.258038 -437.142128)
			(xy 140.270154 -437.142579) (xy 140.293196 -437.150076) (xy 140.312797 -437.164323) (xy 140.327037 -437.183929)
			(xy 140.334525 -437.206974) (xy 140.335 -437.21909) (xy 140.335 -438.089802) (xy 142.21841 -438.089802)
			(xy 142.218929 -438.057222) (xy 142.226903 -437.992552) (xy 142.242719 -437.92934) (xy 142.26614 -437.868535)
			(xy 142.296815 -437.811047) (xy 142.334285 -437.757738) (xy 142.377988 -437.709407) (xy 142.402306 -437.68772)
			(xy 142.482824 -437.523382) (xy 142.487525 -437.512865) (xy 142.491014 -437.490107) (xy 142.487529 -437.467348)
			(xy 142.482824 -437.456834) (xy 142.401798 -437.291734) (xy 142.377523 -437.27005) (xy 142.333927 -437.221716)
			(xy 142.296554 -437.168423) (xy 142.265962 -437.110968) (xy 142.242609 -437.05021) (xy 142.226843 -436.987057)
			(xy 142.2189 -436.922452) (xy 142.21841 -436.889906) (xy 142.219146 -436.850581) (xy 142.230745 -436.772791)
			(xy 142.241524 -436.734966) (xy 142.241524 -436.219092) (xy 142.241906 -436.207006) (xy 142.24938 -436.184017)
			(xy 142.263593 -436.164464) (xy 142.283153 -436.150262) (xy 142.306145 -436.1428) (xy 142.318232 -436.142384)
			(xy 143.258032 -436.142384) (xy 143.270107 -436.142837) (xy 143.293074 -436.150307) (xy 143.31261 -436.164507)
			(xy 143.326804 -436.184047) (xy 143.334267 -436.207016) (xy 143.33474 -436.219092) (xy 143.33474 -438.760616)
			(xy 143.33425 -438.772688) (xy 143.326787 -438.79565) (xy 143.312596 -438.815184) (xy 143.293065 -438.829379)
			(xy 143.270104 -438.836847) (xy 143.258032 -438.837324) (xy 142.318232 -438.837324) (xy 142.306153 -438.83686)
			(xy 142.283174 -438.829403) (xy 142.263624 -438.81521) (xy 142.249418 -438.795669) (xy 142.241947 -438.772695)
			(xy 142.241524 -438.760616) (xy 142.241524 -438.244742) (xy 142.230726 -438.20692) (xy 142.219118 -438.129129)
			(xy 142.21841 -438.089802) (xy 140.335 -438.089802) (xy 140.335 -439.0898) (xy 144.218406 -439.0898)
			(xy 144.218925 -439.05722) (xy 144.226899 -438.99255) (xy 144.242715 -438.929338) (xy 144.266136 -438.868533)
			(xy 144.296811 -438.811045) (xy 144.334281 -438.757736) (xy 144.377984 -438.709405) (xy 144.402302 -438.687718)
			(xy 144.48282 -438.52338) (xy 144.487522 -438.512864) (xy 144.491011 -438.490105) (xy 144.487526 -438.467346)
			(xy 144.48282 -438.456832) (xy 144.401794 -438.291732) (xy 144.377517 -438.27005) (xy 144.333921 -438.221715)
			(xy 144.296548 -438.168422) (xy 144.265957 -438.110967) (xy 144.242604 -438.050209) (xy 144.226839 -437.987055)
			(xy 144.218896 -437.92245) (xy 144.218406 -437.889904) (xy 144.219142 -437.850579) (xy 144.230741 -437.772789)
			(xy 144.24152 -437.734964) (xy 144.24152 -437.21909) (xy 144.241999 -437.207002) (xy 144.249456 -437.184004)
			(xy 144.26364 -437.164426) (xy 144.28317 -437.150176) (xy 144.306142 -437.14264) (xy 144.318228 -437.142128)
			(xy 145.258028 -437.142128) (xy 145.270141 -437.142493) (xy 145.293174 -437.150003) (xy 145.312749 -437.164277)
			(xy 145.326942 -437.183911) (xy 145.334357 -437.206975) (xy 145.334736 -437.21909) (xy 145.334736 -438.089802)
			(xy 146.218402 -438.089802) (xy 146.218924 -438.057222) (xy 146.226897 -437.992552) (xy 146.242713 -437.929341)
			(xy 146.266134 -437.868536) (xy 146.296809 -437.811048) (xy 146.334278 -437.757739) (xy 146.37798 -437.709407)
			(xy 146.402298 -437.68772) (xy 146.482816 -437.523382) (xy 146.487517 -437.512865) (xy 146.491007 -437.490107)
			(xy 146.487522 -437.467348) (xy 146.482816 -437.456834) (xy 146.40179 -437.291734) (xy 146.377514 -437.270052)
			(xy 146.333918 -437.221717) (xy 146.296545 -437.168424) (xy 146.265953 -437.110969) (xy 146.2426 -437.05021)
			(xy 146.226835 -436.987057) (xy 146.218892 -436.922452) (xy 146.218402 -436.889906) (xy 146.219138 -436.850581)
			(xy 146.230737 -436.772791) (xy 146.241516 -436.734966) (xy 146.241516 -436.219092) (xy 146.241906 -436.207006)
			(xy 146.249379 -436.184019) (xy 146.26359 -436.164467) (xy 146.283148 -436.150264) (xy 146.306138 -436.142801)
			(xy 146.318224 -436.142384) (xy 147.258024 -436.142384) (xy 147.270099 -436.142844) (xy 147.293066 -436.150312)
			(xy 147.312601 -436.16451) (xy 147.326795 -436.184049) (xy 147.334259 -436.207017) (xy 147.334732 -436.219092)
			(xy 147.334732 -438.760616) (xy 147.33425 -438.772689) (xy 147.326786 -438.795653) (xy 147.312593 -438.815187)
			(xy 147.29306 -438.829382) (xy 147.270097 -438.836848) (xy 147.258024 -438.837324) (xy 146.318224 -438.837324)
			(xy 146.306144 -438.836867) (xy 146.283165 -438.829408) (xy 146.263616 -438.815213) (xy 146.24941 -438.795671)
			(xy 146.241939 -438.772696) (xy 146.241516 -438.760616) (xy 146.241516 -438.244742) (xy 146.230718 -438.20692)
			(xy 146.21911 -438.129129) (xy 146.218402 -438.089802) (xy 145.334736 -438.089802) (xy 145.334736 -439.0898)
			(xy 148.218398 -439.0898) (xy 148.21892 -439.05722) (xy 148.226893 -438.99255) (xy 148.242709 -438.929339)
			(xy 148.26613 -438.868534) (xy 148.296805 -438.811046) (xy 148.334274 -438.757737) (xy 148.377976 -438.709405)
			(xy 148.402294 -438.687718) (xy 148.482812 -438.52338) (xy 148.487515 -438.512864) (xy 148.491004 -438.490105)
			(xy 148.487518 -438.467346) (xy 148.482812 -438.456832) (xy 148.401786 -438.291732) (xy 148.377508 -438.270052)
			(xy 148.333912 -438.221716) (xy 148.296539 -438.168423) (xy 148.265948 -438.110967) (xy 148.242596 -438.050209)
			(xy 148.22683 -437.987055) (xy 148.218888 -437.92245) (xy 148.218398 -437.889904) (xy 148.219134 -437.850579)
			(xy 148.230733 -437.772789) (xy 148.241512 -437.734964) (xy 148.241512 -437.21909) (xy 148.241999 -437.207003)
			(xy 148.249455 -437.184007) (xy 148.263637 -437.164429) (xy 148.283165 -437.150178) (xy 148.306134 -437.142641)
			(xy 148.31822 -437.142128) (xy 149.25802 -437.142128) (xy 149.270133 -437.1425) (xy 149.293165 -437.150008)
			(xy 149.312741 -437.16428) (xy 149.326934 -437.183913) (xy 149.334349 -437.206976) (xy 149.334728 -437.21909)
			(xy 149.334728 -438.089802) (xy 150.218394 -438.089802) (xy 150.218918 -438.057222) (xy 150.226892 -437.992552)
			(xy 150.242707 -437.929341) (xy 150.266128 -437.868536) (xy 150.296802 -437.811048) (xy 150.334271 -437.757739)
			(xy 150.377972 -437.709407) (xy 150.40229 -437.68772) (xy 150.482808 -437.523382) (xy 150.487509 -437.512865)
			(xy 150.490999 -437.490107) (xy 150.487514 -437.467348) (xy 150.482808 -437.456834) (xy 150.401782 -437.291734)
			(xy 150.377504 -437.270054) (xy 150.333908 -437.221718) (xy 150.296536 -437.168424) (xy 150.265945 -437.110969)
			(xy 150.242592 -437.050211) (xy 150.226827 -436.987057) (xy 150.218884 -436.922452) (xy 150.218394 -436.889906)
			(xy 150.21913 -436.850581) (xy 150.230729 -436.772791) (xy 150.241508 -436.734966) (xy 150.241508 -436.219092)
			(xy 150.241906 -436.207007) (xy 150.249378 -436.184021) (xy 150.263587 -436.16447) (xy 150.283143 -436.150267)
			(xy 150.306131 -436.142802) (xy 150.318216 -436.142384) (xy 151.258016 -436.142384) (xy 151.270091 -436.142851)
			(xy 151.293057 -436.150317) (xy 151.312593 -436.164513) (xy 151.326787 -436.18405) (xy 151.334251 -436.207017)
			(xy 151.334724 -436.219092) (xy 151.334724 -438.760616) (xy 151.33425 -438.77269) (xy 151.326785 -438.795655)
			(xy 151.31259 -438.81519) (xy 151.293055 -438.829385) (xy 151.27009 -438.83685) (xy 151.258016 -438.837324)
			(xy 150.318216 -438.837324) (xy 150.306144 -438.836822) (xy 150.28318 -438.829366) (xy 150.263644 -438.815179)
			(xy 150.249448 -438.795649) (xy 150.241983 -438.772688) (xy 150.241508 -438.760616) (xy 150.241508 -438.244742)
			(xy 150.23071 -438.20692) (xy 150.219102 -438.129129) (xy 150.218394 -438.089802) (xy 149.334728 -438.089802)
			(xy 149.334728 -439.0898) (xy 152.21839 -439.0898) (xy 152.218914 -439.05722) (xy 152.226888 -438.99255)
			(xy 152.242704 -438.929339) (xy 152.266124 -438.868534) (xy 152.296798 -438.811046) (xy 152.334267 -438.757737)
			(xy 152.377968 -438.709405) (xy 152.402286 -438.687718) (xy 152.482804 -438.52338) (xy 152.487507 -438.512864)
			(xy 152.490996 -438.490105) (xy 152.48751 -438.467346) (xy 152.482804 -438.456832) (xy 152.401778 -438.291732)
			(xy 152.377498 -438.270054) (xy 152.333903 -438.221718) (xy 152.296531 -438.168423) (xy 152.26594 -438.110968)
			(xy 152.242587 -438.050209) (xy 152.226822 -437.987055) (xy 152.21888 -437.92245) (xy 152.21839 -437.889904)
			(xy 152.219126 -437.850579) (xy 152.230725 -437.772789) (xy 152.241504 -437.734964) (xy 152.241504 -437.21909)
			(xy 152.241998 -437.207004) (xy 152.249453 -437.184009) (xy 152.263634 -437.164432) (xy 152.28316 -437.150181)
			(xy 152.306127 -437.142643) (xy 152.318212 -437.142128) (xy 153.258012 -437.142128) (xy 153.270124 -437.142506)
			(xy 153.293157 -437.150012) (xy 153.312732 -437.164283) (xy 153.326925 -437.183914) (xy 153.334341 -437.206976)
			(xy 153.33472 -437.21909) (xy 153.33472 -438.089802) (xy 154.218386 -438.089802) (xy 154.218913 -438.057222)
			(xy 154.226886 -437.992553) (xy 154.242702 -437.929342) (xy 154.266122 -437.868537) (xy 154.296796 -437.811049)
			(xy 154.334264 -437.757739) (xy 154.377965 -437.709408) (xy 154.402282 -437.68772) (xy 154.4828 -437.523382)
			(xy 154.487502 -437.512866) (xy 154.490992 -437.490107) (xy 154.487506 -437.467348) (xy 154.4828 -437.456834)
			(xy 154.401774 -437.291734) (xy 154.377494 -437.270056) (xy 154.333899 -437.221719) (xy 154.296527 -437.168425)
			(xy 154.265936 -437.11097) (xy 154.242584 -437.050211) (xy 154.226819 -436.987057) (xy 154.218876 -436.922452)
			(xy 154.218386 -436.889906) (xy 154.219123 -436.850581) (xy 154.230721 -436.772791) (xy 154.2415 -436.734966)
			(xy 154.2415 -436.219092) (xy 154.241958 -436.207016) (xy 154.249423 -436.184047) (xy 154.263621 -436.16451)
			(xy 154.283162 -436.150316) (xy 154.306132 -436.142855) (xy 154.318208 -436.142384) (xy 155.258008 -436.142384)
			(xy 155.270082 -436.142857) (xy 155.293048 -436.150321) (xy 155.312584 -436.164516) (xy 155.326779 -436.184052)
			(xy 155.334243 -436.207018) (xy 155.334716 -436.219092) (xy 155.334716 -438.760616) (xy 155.334249 -438.772691)
			(xy 155.326783 -438.795657) (xy 155.312587 -438.815193) (xy 155.29305 -438.829387) (xy 155.270083 -438.836851)
			(xy 155.258008 -438.837324) (xy 154.318208 -438.837324) (xy 154.306135 -438.836829) (xy 154.283171 -438.829371)
			(xy 154.263635 -438.815182) (xy 154.24944 -438.79565) (xy 154.241975 -438.772688) (xy 154.2415 -438.760616)
			(xy 154.2415 -438.244742) (xy 154.230701 -438.20692) (xy 154.219094 -438.129129) (xy 154.218386 -438.089802)
			(xy 153.33472 -438.089802) (xy 153.33472 -439.0898) (xy 156.218382 -439.0898) (xy 156.218909 -439.05722)
			(xy 156.226883 -438.992551) (xy 156.242698 -438.92934) (xy 156.266118 -438.868535) (xy 156.296792 -438.811047)
			(xy 156.33426 -438.757738) (xy 156.377961 -438.709406) (xy 156.402278 -438.687718) (xy 156.482796 -438.52338)
			(xy 156.487499 -438.512864) (xy 156.490989 -438.490105) (xy 156.487502 -438.467346) (xy 156.482796 -438.456832)
			(xy 156.40177 -438.291732) (xy 156.377509 -438.270033) (xy 156.333909 -438.221703) (xy 156.296532 -438.168413)
			(xy 156.265938 -438.110961) (xy 156.242583 -438.050205) (xy 156.226815 -437.987053) (xy 156.218872 -437.922449)
			(xy 156.218382 -437.889904) (xy 156.219119 -437.850579) (xy 156.230717 -437.772789) (xy 156.241496 -437.734964)
			(xy 156.241496 -437.21909) (xy 156.241998 -437.207004) (xy 156.249452 -437.184011) (xy 156.263631 -437.164435)
			(xy 156.283155 -437.150183) (xy 156.30612 -437.142644) (xy 156.318204 -437.142128) (xy 157.258004 -437.142128)
			(xy 157.270116 -437.142513) (xy 157.293148 -437.150017) (xy 157.312724 -437.164286) (xy 157.326917 -437.183916)
			(xy 157.334333 -437.206977) (xy 157.334712 -437.21909) (xy 157.334712 -438.089802) (xy 314.138056 -438.089802)
			(xy 314.138173 -438.074717) (xy 314.139949 -438.044598) (xy 314.141612 -438.029604) (xy 314.141612 -436.950104)
			(xy 314.139942 -436.935111) (xy 314.138164 -436.904992) (xy 314.138056 -436.889906) (xy 314.138164 -436.87482)
			(xy 314.139946 -436.844702) (xy 314.141612 -436.829708) (xy 314.141612 -436.219092) (xy 314.142006 -436.207007)
			(xy 314.149478 -436.18402) (xy 314.163688 -436.164469) (xy 314.183246 -436.150265) (xy 314.206235 -436.142802)
			(xy 314.21832 -436.142384) (xy 315.15812 -436.142384) (xy 315.170195 -436.142847) (xy 315.193161 -436.150314)
			(xy 315.212697 -436.164511) (xy 315.226891 -436.18405) (xy 315.234355 -436.207017) (xy 315.234828 -436.219092)
			(xy 315.234828 -438.760616) (xy 315.23435 -438.772689) (xy 315.226885 -438.795654) (xy 315.212691 -438.815189)
			(xy 315.193157 -438.829383) (xy 315.170193 -438.836849) (xy 315.15812 -438.837324) (xy 314.21832 -438.837324)
			(xy 314.20624 -438.83687) (xy 314.183261 -438.82941) (xy 314.163711 -438.815214) (xy 314.149506 -438.795672)
			(xy 314.142035 -438.772696) (xy 314.141612 -438.760616) (xy 314.141612 -438.15) (xy 314.139941 -438.135007)
			(xy 314.138164 -438.104888) (xy 314.138056 -438.089802) (xy 157.334712 -438.089802) (xy 157.334712 -439.0898)
			(xy 316.138052 -439.0898) (xy 316.138169 -439.074715) (xy 316.139945 -439.044596) (xy 316.141608 -439.029602)
			(xy 316.141608 -437.950102) (xy 316.139937 -437.935109) (xy 316.13816 -437.90499) (xy 316.138052 -437.889904)
			(xy 316.138169 -437.874819) (xy 316.139945 -437.8447) (xy 316.141608 -437.829706) (xy 316.141608 -437.21909)
			(xy 316.142098 -437.207003) (xy 316.149554 -437.184008) (xy 316.163736 -437.164431) (xy 316.183262 -437.150179)
			(xy 316.206231 -437.142642) (xy 316.218316 -437.142128) (xy 317.158116 -437.142128) (xy 317.170229 -437.142503)
			(xy 317.193261 -437.15001) (xy 317.212836 -437.164281) (xy 317.227029 -437.183914) (xy 317.234445 -437.206976)
			(xy 317.234824 -437.21909) (xy 317.234824 -438.089802) (xy 318.138048 -438.089802) (xy 318.138165 -438.074717)
			(xy 318.139941 -438.044598) (xy 318.141604 -438.029604) (xy 318.141604 -436.950104) (xy 318.139934 -436.935111)
			(xy 318.138156 -436.904992) (xy 318.138048 -436.889906) (xy 318.138156 -436.87482) (xy 318.139938 -436.844702)
			(xy 318.141604 -436.829708) (xy 318.141604 -436.219092) (xy 318.142006 -436.207008) (xy 318.149477 -436.184023)
			(xy 318.163686 -436.164471) (xy 318.183241 -436.150268) (xy 318.206228 -436.142803) (xy 318.218312 -436.142384)
			(xy 319.158112 -436.142384) (xy 319.170186 -436.142854) (xy 319.193153 -436.150319) (xy 319.212689 -436.164514)
			(xy 319.226883 -436.184051) (xy 319.234347 -436.207018) (xy 319.23482 -436.219092) (xy 319.23482 -438.760616)
			(xy 319.234349 -438.77269) (xy 319.226884 -438.795656) (xy 319.212689 -438.815191) (xy 319.193152 -438.829386)
			(xy 319.170186 -438.83685) (xy 319.158112 -438.837324) (xy 318.218312 -438.837324) (xy 318.20624 -438.836826)
			(xy 318.183276 -438.829369) (xy 318.16374 -438.81518) (xy 318.149544 -438.79565) (xy 318.142079 -438.772688)
			(xy 318.141604 -438.760616) (xy 318.141604 -438.15) (xy 318.139933 -438.135007) (xy 318.138156 -438.104888)
			(xy 318.138048 -438.089802) (xy 317.234824 -438.089802) (xy 317.234824 -439.0898) (xy 320.138044 -439.0898)
			(xy 320.138161 -439.074715) (xy 320.139937 -439.044596) (xy 320.1416 -439.029602) (xy 320.1416 -437.950102)
			(xy 320.139929 -437.935109) (xy 320.138152 -437.90499) (xy 320.138044 -437.889904) (xy 320.138161 -437.874819)
			(xy 320.139937 -437.8447) (xy 320.1416 -437.829706) (xy 320.1416 -437.21909) (xy 320.142098 -437.207004)
			(xy 320.149553 -437.18401) (xy 320.163733 -437.164434) (xy 320.183257 -437.150182) (xy 320.206224 -437.142643)
			(xy 320.218308 -437.142128) (xy 321.158108 -437.142128) (xy 321.17022 -437.14251) (xy 321.193252 -437.150015)
			(xy 321.212828 -437.164284) (xy 321.227021 -437.183915) (xy 321.234437 -437.206976) (xy 321.234816 -437.21909)
			(xy 321.234816 -438.089802) (xy 322.13804 -438.089802) (xy 322.138157 -438.074717) (xy 322.139933 -438.044598)
			(xy 322.141596 -438.029604) (xy 322.141596 -436.950104) (xy 322.139926 -436.935111) (xy 322.138148 -436.904992)
			(xy 322.13804 -436.889906) (xy 322.13815 -436.87482) (xy 322.139932 -436.844702) (xy 322.141596 -436.829708)
			(xy 322.141596 -436.219092) (xy 322.142058 -436.207017) (xy 322.149523 -436.184049) (xy 322.16372 -436.164511)
			(xy 322.183259 -436.150317) (xy 322.206229 -436.142856) (xy 322.218304 -436.142384) (xy 323.158104 -436.142384)
			(xy 323.170178 -436.142861) (xy 323.193144 -436.150323) (xy 323.21268 -436.164517) (xy 323.226875 -436.184053)
			(xy 323.234339 -436.207018) (xy 323.234812 -436.219092) (xy 323.234812 -438.760616) (xy 323.234349 -438.772691)
			(xy 323.226883 -438.795658) (xy 323.212686 -438.815194) (xy 323.193147 -438.829388) (xy 323.170179 -438.836851)
			(xy 323.158104 -438.837324) (xy 322.218304 -438.837324) (xy 322.206231 -438.836833) (xy 322.183267 -438.829373)
			(xy 322.163731 -438.815183) (xy 322.149536 -438.795651) (xy 322.142071 -438.772689) (xy 322.141596 -438.760616)
			(xy 322.141596 -438.15) (xy 322.139925 -438.135007) (xy 322.138148 -438.104888) (xy 322.13804 -438.089802)
			(xy 321.234816 -438.089802) (xy 321.234816 -439.0898) (xy 324.138036 -439.0898) (xy 324.138153 -439.074715)
			(xy 324.139929 -439.044596) (xy 324.141592 -439.029602) (xy 324.141592 -437.950102) (xy 324.139921 -437.935109)
			(xy 324.138144 -437.90499) (xy 324.138036 -437.889904) (xy 324.138153 -437.874819) (xy 324.139929 -437.8447)
			(xy 324.141592 -437.829706) (xy 324.141592 -437.21909) (xy 324.142098 -437.207005) (xy 324.149552 -437.184012)
			(xy 324.16373 -437.164436) (xy 324.183252 -437.150184) (xy 324.206217 -437.142644) (xy 324.2183 -437.142128)
			(xy 325.1581 -437.142128) (xy 325.170212 -437.142516) (xy 325.193244 -437.150019) (xy 325.212819 -437.164287)
			(xy 325.227013 -437.183916) (xy 325.234429 -437.206977) (xy 325.234808 -437.21909) (xy 325.234808 -438.089802)
			(xy 326.138032 -438.089802) (xy 326.138151 -438.074717) (xy 326.139927 -438.044598) (xy 326.141588 -438.029604)
			(xy 326.141588 -436.950104) (xy 326.139917 -436.935111) (xy 326.13814 -436.904992) (xy 326.138032 -436.889906)
			(xy 326.138142 -436.87482) (xy 326.139924 -436.844702) (xy 326.141588 -436.829708) (xy 326.141588 -436.219092)
			(xy 326.142057 -436.207017) (xy 326.149522 -436.184051) (xy 326.163717 -436.164514) (xy 326.183254 -436.15032)
			(xy 326.206221 -436.142857) (xy 326.218296 -436.142384) (xy 327.158096 -436.142384) (xy 327.17017 -436.142868)
			(xy 327.193135 -436.150328) (xy 327.212672 -436.16452) (xy 327.226867 -436.184054) (xy 327.234331 -436.207019)
			(xy 327.234804 -436.219092) (xy 327.234804 -438.760616) (xy 327.234349 -438.772692) (xy 327.226882 -438.79566)
			(xy 327.212683 -438.815197) (xy 327.193142 -438.829391) (xy 327.170172 -438.836852) (xy 327.158096 -438.837324)
			(xy 326.218296 -438.837324) (xy 326.206223 -438.836839) (xy 326.183258 -438.829378) (xy 326.163723 -438.815186)
			(xy 326.149528 -438.795652) (xy 326.142063 -438.772689) (xy 326.141588 -438.760616) (xy 326.141588 -438.15)
			(xy 326.139917 -438.135007) (xy 326.13814 -438.104888) (xy 326.138032 -438.089802) (xy 325.234808 -438.089802)
			(xy 325.234808 -439.0898) (xy 328.138028 -439.0898) (xy 328.138147 -439.074715) (xy 328.139923 -439.044596)
			(xy 328.141584 -439.029602) (xy 328.141584 -437.950102) (xy 328.139913 -437.935109) (xy 328.138136 -437.90499)
			(xy 328.138028 -437.889904) (xy 328.138147 -437.874819) (xy 328.139923 -437.8447) (xy 328.141584 -437.829706)
			(xy 328.141584 -437.21909) (xy 328.142 -437.206996) (xy 328.149465 -437.183987) (xy 328.163663 -437.164404)
			(xy 328.18321 -437.150155) (xy 328.206199 -437.142631) (xy 328.218292 -437.142128) (xy 329.158092 -437.142128)
			(xy 329.170203 -437.142523) (xy 329.193235 -437.150024) (xy 329.212811 -437.16429) (xy 329.227005 -437.183918)
			(xy 329.234421 -437.206977) (xy 329.2348 -437.21909) (xy 329.2348 -438.089802) (xy 331.138022 -438.089802)
			(xy 331.138115 -438.075228) (xy 331.139768 -438.046127) (xy 331.141324 -438.031636) (xy 331.141324 -436.948072)
			(xy 331.13978 -436.93358) (xy 331.138127 -436.90448) (xy 331.138022 -436.889906) (xy 331.138115 -436.875332)
			(xy 331.139768 -436.846231) (xy 331.141324 -436.83174) (xy 331.141324 -436.219092) (xy 331.14171 -436.20698)
			(xy 331.149214 -436.183949) (xy 331.163483 -436.164374) (xy 331.183112 -436.15018) (xy 331.206173 -436.142764)
			(xy 331.218286 -436.142384) (xy 332.158086 -436.142384) (xy 332.170179 -436.14282) (xy 332.193187 -436.150278)
			(xy 332.212771 -436.164471) (xy 332.22702 -436.184014) (xy 332.234545 -436.207) (xy 332.235048 -436.219092)
			(xy 332.235048 -438.760616) (xy 332.234598 -438.772721) (xy 332.2271 -438.795741) (xy 332.212845 -438.815309)
			(xy 332.193234 -438.829505) (xy 332.170192 -438.836934) (xy 332.158086 -438.837324) (xy 331.218286 -438.837324)
			(xy 331.206192 -438.836904) (xy 331.183185 -438.829439) (xy 331.163602 -438.815242) (xy 331.149353 -438.795696)
			(xy 331.141828 -438.772709) (xy 331.141324 -438.760616) (xy 331.141324 -438.147968) (xy 331.139779 -438.133476)
			(xy 331.138127 -438.104376) (xy 331.138022 -438.089802) (xy 329.2348 -438.089802) (xy 329.2348 -439.0898)
			(xy 333.138018 -439.0898) (xy 333.138111 -439.075226) (xy 333.139764 -439.046125) (xy 333.14132 -439.031634)
			(xy 333.14132 -437.94807) (xy 333.139775 -437.933578) (xy 333.138123 -437.904478) (xy 333.138018 -437.889904)
			(xy 333.138111 -437.87533) (xy 333.139764 -437.846229) (xy 333.14132 -437.831738) (xy 333.14132 -437.21909)
			(xy 333.141803 -437.206977) (xy 333.149291 -437.183936) (xy 333.163531 -437.164336) (xy 333.183129 -437.150095)
			(xy 333.206169 -437.142604) (xy 333.218282 -437.142128) (xy 334.158082 -437.142128) (xy 334.170203 -437.142575)
			(xy 334.193259 -437.150061) (xy 334.212874 -437.164306) (xy 334.227126 -437.183916) (xy 334.23462 -437.206969)
			(xy 334.235044 -437.21909) (xy 334.235044 -438.089802) (xy 335.138014 -438.089802) (xy 335.138106 -438.075228)
			(xy 335.13976 -438.046127) (xy 335.141316 -438.031636) (xy 335.141316 -436.948072) (xy 335.139772 -436.93358)
			(xy 335.138119 -436.90448) (xy 335.138014 -436.889906) (xy 335.138107 -436.875332) (xy 335.13976 -436.846231)
			(xy 335.141316 -436.83174) (xy 335.141316 -436.219092) (xy 335.14171 -436.206981) (xy 335.149213 -436.183951)
			(xy 335.16348 -436.164376) (xy 335.183107 -436.150183) (xy 335.206166 -436.142765) (xy 335.218278 -436.142384)
			(xy 336.158078 -436.142384) (xy 336.170171 -436.142827) (xy 336.193178 -436.150283) (xy 336.212762 -436.164474)
			(xy 336.227012 -436.184016) (xy 336.234537 -436.207001) (xy 336.23504 -436.219092) (xy 336.23504 -438.760616)
			(xy 336.234598 -438.772722) (xy 336.227099 -438.795743) (xy 336.212843 -438.815312) (xy 336.193229 -438.829508)
			(xy 336.170185 -438.836935) (xy 336.158078 -438.837324) (xy 335.218278 -438.837324) (xy 335.206184 -438.836911)
			(xy 335.183176 -438.829444) (xy 335.163594 -438.815245) (xy 335.149345 -438.795698) (xy 335.14182 -438.772709)
			(xy 335.141316 -438.760616) (xy 335.141316 -438.147968) (xy 335.139771 -438.133476) (xy 335.138119 -438.104376)
			(xy 335.138014 -438.089802) (xy 334.235044 -438.089802) (xy 334.235044 -439.0898) (xy 337.13801 -439.0898)
			(xy 337.138102 -439.075226) (xy 337.139756 -439.046125) (xy 337.141312 -439.031634) (xy 337.141312 -437.94807)
			(xy 337.139767 -437.933578) (xy 337.138115 -437.904478) (xy 337.13801 -437.889904) (xy 337.138103 -437.87533)
			(xy 337.139756 -437.846229) (xy 337.141312 -437.831738) (xy 337.141312 -437.21909) (xy 337.141803 -437.206978)
			(xy 337.14929 -437.183938) (xy 337.163528 -437.164339) (xy 337.183124 -437.150097) (xy 337.206162 -437.142606)
			(xy 337.218274 -437.142128) (xy 338.158074 -437.142128) (xy 338.170194 -437.142582) (xy 338.193251 -437.150066)
			(xy 338.212865 -437.164309) (xy 338.227118 -437.183917) (xy 338.234612 -437.20697) (xy 338.235036 -437.21909)
			(xy 338.235036 -438.089802) (xy 339.138006 -438.089802) (xy 339.138099 -438.075228) (xy 339.139752 -438.046127)
			(xy 339.141308 -438.031636) (xy 339.141308 -436.948072) (xy 339.139763 -436.93358) (xy 339.138111 -436.90448)
			(xy 339.138006 -436.889906) (xy 339.138099 -436.875332) (xy 339.139752 -436.846231) (xy 339.141308 -436.83174)
			(xy 339.141308 -436.219092) (xy 339.141709 -436.206982) (xy 339.149212 -436.183953) (xy 339.163477 -436.164379)
			(xy 339.183102 -436.150185) (xy 339.206158 -436.142766) (xy 339.21827 -436.142384) (xy 340.15807 -436.142384)
			(xy 340.170162 -436.142834) (xy 340.193169 -436.150288) (xy 340.212754 -436.164477) (xy 340.227004 -436.184017)
			(xy 340.234529 -436.207001) (xy 340.235032 -436.219092) (xy 340.235032 -438.760616) (xy 340.234598 -438.772723)
			(xy 340.227098 -438.795745) (xy 340.21284 -438.815315) (xy 340.193224 -438.82951) (xy 340.170178 -438.836936)
			(xy 340.15807 -438.837324) (xy 339.21827 -438.837324) (xy 339.206175 -438.836918) (xy 339.183168 -438.829448)
			(xy 339.163585 -438.815247) (xy 339.149337 -438.795699) (xy 339.141812 -438.77271) (xy 339.141308 -438.760616)
			(xy 339.141308 -438.147968) (xy 339.139763 -438.133476) (xy 339.138111 -438.104376) (xy 339.138006 -438.089802)
			(xy 338.235036 -438.089802) (xy 338.235036 -439.0898) (xy 341.138002 -439.0898) (xy 341.138094 -439.075226)
			(xy 341.139748 -439.046125) (xy 341.141304 -439.031634) (xy 341.141304 -437.94807) (xy 341.139759 -437.933578)
			(xy 341.138107 -437.904478) (xy 341.138002 -437.889904) (xy 341.138095 -437.87533) (xy 341.139748 -437.846229)
			(xy 341.141304 -437.831738) (xy 341.141304 -437.21909) (xy 341.141803 -437.206978) (xy 341.149289 -437.183941)
			(xy 341.163525 -437.164342) (xy 341.183119 -437.1501) (xy 341.206154 -437.142607) (xy 341.218266 -437.142128)
			(xy 342.158066 -437.142128) (xy 342.170186 -437.142589) (xy 342.193242 -437.15007) (xy 342.212857 -437.164312)
			(xy 342.22711 -437.183918) (xy 342.234604 -437.20697) (xy 342.235028 -437.21909) (xy 342.235028 -438.089802)
			(xy 343.137998 -438.089802) (xy 343.138091 -438.075228) (xy 343.139744 -438.046127) (xy 343.1413 -438.031636)
			(xy 343.1413 -436.948072) (xy 343.139755 -436.93358) (xy 343.138103 -436.90448) (xy 343.137998 -436.889906)
			(xy 343.138091 -436.875332) (xy 343.139744 -436.846231) (xy 343.1413 -436.83174) (xy 343.1413 -436.219092)
			(xy 343.141709 -436.206983) (xy 343.149211 -436.183955) (xy 343.163474 -436.164382) (xy 343.183097 -436.150188)
			(xy 343.206151 -436.142767) (xy 343.218262 -436.142384) (xy 344.158062 -436.142384) (xy 344.170154 -436.142841)
			(xy 344.193161 -436.150292) (xy 344.212745 -436.16448) (xy 344.226995 -436.184019) (xy 344.234521 -436.207002)
			(xy 344.235024 -436.219092) (xy 344.235024 -438.760616) (xy 344.234598 -438.772723) (xy 344.227097 -438.795747)
			(xy 344.212837 -438.815318) (xy 344.193219 -438.829513) (xy 344.170171 -438.836937) (xy 344.158062 -438.837324)
			(xy 343.218262 -438.837324) (xy 343.206167 -438.836924) (xy 343.183159 -438.829453) (xy 343.163577 -438.81525)
			(xy 343.149329 -438.795701) (xy 343.141804 -438.77271) (xy 343.1413 -438.760616) (xy 343.1413 -438.147968)
			(xy 343.139755 -438.133476) (xy 343.138103 -438.104376) (xy 343.137998 -438.089802) (xy 342.235028 -438.089802)
			(xy 342.235028 -439.0898) (xy 345.137994 -439.0898) (xy 345.138086 -439.075226) (xy 345.13974 -439.046125)
			(xy 345.141296 -439.031634) (xy 345.141296 -437.94807) (xy 345.139752 -437.933578) (xy 345.138099 -437.904478)
			(xy 345.137994 -437.889904) (xy 345.138087 -437.87533) (xy 345.13974 -437.846229) (xy 345.141296 -437.831738)
			(xy 345.141296 -437.21909) (xy 345.141803 -437.206979) (xy 345.149288 -437.183943) (xy 345.163522 -437.164345)
			(xy 345.183114 -437.150102) (xy 345.206147 -437.142608) (xy 345.218258 -437.142128) (xy 346.158058 -437.142128)
			(xy 346.170178 -437.142595) (xy 346.193233 -437.150075) (xy 346.212848 -437.164315) (xy 346.227101 -437.18392)
			(xy 346.234596 -437.206971) (xy 346.23502 -437.21909) (xy 346.23502 -439.0898) (xy 383.218436 -439.0898)
			(xy 383.218945 -439.05722) (xy 383.226919 -438.992549) (xy 383.242736 -438.929337) (xy 383.266159 -438.868531)
			(xy 383.296836 -438.811043) (xy 383.334308 -438.757735) (xy 383.378013 -438.709405) (xy 383.402332 -438.687718)
			(xy 383.48285 -438.52338) (xy 383.487551 -438.512864) (xy 383.491038 -438.490105) (xy 383.487554 -438.467347)
			(xy 383.48285 -438.456832) (xy 383.401824 -438.291732) (xy 383.377553 -438.270044) (xy 383.333956 -438.22171)
			(xy 383.296582 -438.168418) (xy 383.265989 -438.110965) (xy 383.242635 -438.050207) (xy 383.226869 -437.987054)
			(xy 383.218926 -437.92245) (xy 383.218436 -437.889904) (xy 383.219137 -437.850778) (xy 383.230611 -437.773371)
			(xy 383.241296 -437.735726) (xy 383.241296 -437.21909) (xy 383.241803 -437.206979) (xy 383.249288 -437.183943)
			(xy 383.263522 -437.164345) (xy 383.283114 -437.150102) (xy 383.306147 -437.142608) (xy 383.318258 -437.142128)
			(xy 384.258058 -437.142128) (xy 384.270178 -437.142595) (xy 384.293233 -437.150075) (xy 384.312848 -437.164315)
			(xy 384.327101 -437.18392) (xy 384.334596 -437.206971) (xy 384.33502 -437.21909) (xy 384.33502 -438.089802)
			(xy 385.218432 -438.089802) (xy 385.218944 -438.057222) (xy 385.226918 -437.992551) (xy 385.242735 -437.929339)
			(xy 385.266157 -437.868534) (xy 385.296833 -437.811046) (xy 385.334305 -437.757737) (xy 385.378009 -437.709407)
			(xy 385.402328 -437.68772) (xy 385.482846 -437.523382) (xy 385.487546 -437.512865) (xy 385.491034 -437.490107)
			(xy 385.48755 -437.467349) (xy 385.482846 -437.456834) (xy 385.40182 -437.291734) (xy 385.37755 -437.270046)
			(xy 385.333952 -437.221712) (xy 385.296578 -437.16842) (xy 385.265985 -437.110966) (xy 385.242631 -437.050209)
			(xy 385.226865 -436.987056) (xy 385.218922 -436.922452) (xy 385.218432 -436.889906) (xy 385.219133 -436.85078)
			(xy 385.230607 -436.773373) (xy 385.241292 -436.735728) (xy 385.241292 -436.219092) (xy 385.241709 -436.206983)
			(xy 385.24921 -436.183957) (xy 385.263472 -436.164385) (xy 385.283092 -436.15019) (xy 385.306144 -436.142768)
			(xy 385.318254 -436.142384) (xy 386.258054 -436.142384) (xy 386.270146 -436.142847) (xy 386.293152 -436.150297)
			(xy 386.312737 -436.164483) (xy 386.326987 -436.18402) (xy 386.334512 -436.207002) (xy 386.335016 -436.219092)
			(xy 386.335016 -438.760616) (xy 386.334598 -438.772724) (xy 386.327096 -438.795749) (xy 386.312834 -438.815321)
			(xy 386.293214 -438.829515) (xy 386.270163 -438.836939) (xy 386.258054 -438.837324) (xy 385.318254 -438.837324)
			(xy 385.306158 -438.836931) (xy 385.28315 -438.829457) (xy 385.263568 -438.815253) (xy 385.24932 -438.795702)
			(xy 385.241796 -438.77271) (xy 385.241292 -438.760616) (xy 385.241292 -438.24398) (xy 385.230605 -438.206335)
			(xy 385.219128 -438.128928) (xy 385.218432 -438.089802) (xy 384.33502 -438.089802) (xy 384.33502 -439.0898)
			(xy 387.218428 -439.0898) (xy 387.21894 -439.05722) (xy 387.226914 -438.992549) (xy 387.242731 -438.929337)
			(xy 387.266153 -438.868532) (xy 387.29683 -438.811044) (xy 387.334301 -438.757735) (xy 387.378005 -438.709405)
			(xy 387.402324 -438.687718) (xy 387.482842 -438.52338) (xy 387.487543 -438.512864) (xy 387.491031 -438.490105)
			(xy 387.487546 -438.467347) (xy 387.482842 -438.456832) (xy 387.401816 -438.291732) (xy 387.377544 -438.270045)
			(xy 387.333947 -438.221712) (xy 387.296573 -438.168419) (xy 387.26598 -438.110965) (xy 387.242627 -438.050208)
			(xy 387.226861 -437.987055) (xy 387.218918 -437.92245) (xy 387.218428 -437.889904) (xy 387.219129 -437.850778)
			(xy 387.230603 -437.773371) (xy 387.241288 -437.735726) (xy 387.241288 -437.21909) (xy 387.241803 -437.20698)
			(xy 387.249287 -437.183945) (xy 387.263519 -437.164348) (xy 387.283109 -437.150105) (xy 387.30614 -437.142609)
			(xy 387.31825 -437.142128) (xy 388.25805 -437.142128) (xy 388.270166 -437.142569) (xy 388.293209 -437.150069)
			(xy 388.312809 -437.164319) (xy 388.32705 -437.183927) (xy 388.334537 -437.206974) (xy 388.335012 -437.21909)
			(xy 388.335012 -438.089802) (xy 389.218424 -438.089802) (xy 389.218939 -438.057222) (xy 389.226913 -437.992551)
			(xy 389.242729 -437.92934) (xy 389.266151 -437.868534) (xy 389.296827 -437.811046) (xy 389.334298 -437.757738)
			(xy 389.378002 -437.709407) (xy 389.40232 -437.68772) (xy 389.482838 -437.523382) (xy 389.487538 -437.512865)
			(xy 389.491026 -437.490107) (xy 389.487542 -437.467349) (xy 389.482838 -437.456834) (xy 389.401812 -437.291734)
			(xy 389.37754 -437.270047) (xy 389.333943 -437.221713) (xy 389.296569 -437.168421) (xy 389.265977 -437.110967)
			(xy 389.242623 -437.050209) (xy 389.226857 -436.987056) (xy 389.218914 -436.922452) (xy 389.218424 -436.889906)
			(xy 389.219126 -436.85078) (xy 389.230599 -436.773373) (xy 389.241284 -436.735728) (xy 389.241284 -436.219092)
			(xy 389.241709 -436.206984) (xy 389.249209 -436.183959) (xy 389.263469 -436.164388) (xy 389.283087 -436.150193)
			(xy 389.306137 -436.142769) (xy 389.318246 -436.142384) (xy 390.258046 -436.142384) (xy 390.270142 -436.142769)
			(xy 390.293152 -436.150244) (xy 390.312735 -436.16445) (xy 390.326982 -436.184003) (xy 390.334505 -436.206997)
			(xy 390.335008 -436.219092) (xy 390.335008 -438.760616) (xy 390.334598 -438.772725) (xy 390.327095 -438.795751)
			(xy 390.312831 -438.815324) (xy 390.293209 -438.829518) (xy 390.270156 -438.83694) (xy 390.258046 -438.837324)
			(xy 389.318246 -438.837324) (xy 389.306155 -438.836853) (xy 389.28315 -438.829404) (xy 389.263566 -438.81522)
			(xy 389.249315 -438.795685) (xy 389.241789 -438.772705) (xy 389.241284 -438.760616) (xy 389.241284 -438.24398)
			(xy 389.230596 -438.206335) (xy 389.21912 -438.128928) (xy 389.218424 -438.089802) (xy 388.335012 -438.089802)
			(xy 388.335012 -439.0898) (xy 391.21842 -439.0898) (xy 391.218935 -439.05722) (xy 391.226909 -438.992549)
			(xy 391.242725 -438.929338) (xy 391.266147 -438.868532) (xy 391.296823 -438.811044) (xy 391.334294 -438.757736)
			(xy 391.377998 -438.709405) (xy 391.402316 -438.687718) (xy 391.482834 -438.52338) (xy 391.487536 -438.512864)
			(xy 391.491024 -438.490105) (xy 391.487539 -438.467347) (xy 391.482834 -438.456832) (xy 391.401808 -438.291732)
			(xy 391.377534 -438.270047) (xy 391.333937 -438.221713) (xy 391.296564 -438.16842) (xy 391.265972 -438.110966)
			(xy 391.242618 -438.050208) (xy 391.226853 -437.987055) (xy 391.21891 -437.92245) (xy 391.21842 -437.889904)
			(xy 391.219121 -437.850778) (xy 391.230595 -437.773371) (xy 391.24128 -437.735726) (xy 391.24128 -437.21909)
			(xy 391.241652 -437.206963) (xy 391.249152 -437.183896) (xy 391.263415 -437.164278) (xy 391.283043 -437.150029)
			(xy 391.306114 -437.142544) (xy 391.318242 -437.142128) (xy 392.258042 -437.142128) (xy 392.270158 -437.142576)
			(xy 392.293201 -437.150073) (xy 392.312801 -437.164322) (xy 392.327041 -437.183928) (xy 392.334529 -437.206974)
			(xy 392.335004 -437.21909) (xy 392.335004 -438.089802) (xy 393.218416 -438.089802) (xy 393.218933 -438.057222)
			(xy 393.226907 -437.992552) (xy 393.242723 -437.92934) (xy 393.266145 -437.868535) (xy 393.29682 -437.811047)
			(xy 393.334291 -437.757738) (xy 393.377994 -437.709407) (xy 393.402312 -437.68772) (xy 393.48283 -437.523382)
			(xy 393.48753 -437.512865) (xy 393.491019 -437.490107) (xy 393.487535 -437.467349) (xy 393.48283 -437.456834)
			(xy 393.401804 -437.291734) (xy 393.37753 -437.270049) (xy 393.333934 -437.221715) (xy 393.29656 -437.168422)
			(xy 393.265968 -437.110968) (xy 393.242615 -437.05021) (xy 393.226849 -436.987057) (xy 393.218906 -436.922452)
			(xy 393.218416 -436.889906) (xy 393.219114 -436.85078) (xy 393.23059 -436.773373) (xy 393.241276 -436.735728)
			(xy 393.241276 -436.219092) (xy 393.241709 -436.206985) (xy 393.249208 -436.183962) (xy 393.263466 -436.164391)
			(xy 393.283082 -436.150195) (xy 393.30613 -436.142771) (xy 393.318238 -436.142384) (xy 394.258038 -436.142384)
			(xy 394.270134 -436.142776) (xy 394.293143 -436.150248) (xy 394.312726 -436.164453) (xy 394.326974 -436.184004)
			(xy 394.334497 -436.206997) (xy 394.335 -436.219092) (xy 394.335 -438.760616) (xy 394.334597 -438.772726)
			(xy 394.327094 -438.795754) (xy 394.312828 -438.815326) (xy 394.293204 -438.82952) (xy 394.270149 -438.836941)
			(xy 394.258038 -438.837324) (xy 393.318238 -438.837324) (xy 393.306147 -438.83686) (xy 393.283141 -438.829409)
			(xy 393.263558 -438.815223) (xy 393.249307 -438.795686) (xy 393.241781 -438.772706) (xy 393.241276 -438.760616)
			(xy 393.241276 -438.24398) (xy 393.230588 -438.206335) (xy 393.219112 -438.128928) (xy 393.218416 -438.089802)
			(xy 392.335004 -438.089802) (xy 392.335004 -439.0898) (xy 395.218412 -439.0898) (xy 395.218929 -439.05722)
			(xy 395.226903 -438.99255) (xy 395.242719 -438.929338) (xy 395.266141 -438.868533) (xy 395.296816 -438.811045)
			(xy 395.334286 -438.757736) (xy 395.37799 -438.709405) (xy 395.402308 -438.687718) (xy 395.482826 -438.52338)
			(xy 395.487528 -438.512864) (xy 395.491017 -438.490105) (xy 395.487531 -438.467346) (xy 395.482826 -438.456832)
			(xy 395.4018 -438.291732) (xy 395.377525 -438.270049) (xy 395.333928 -438.221714) (xy 395.296555 -438.168421)
			(xy 395.265963 -438.110966) (xy 395.24261 -438.050208) (xy 395.226845 -437.987055) (xy 395.218902 -437.92245)
			(xy 395.218412 -437.889904) (xy 395.21911 -437.850778) (xy 395.230586 -437.773371) (xy 395.241272 -437.735726)
			(xy 395.241272 -437.21909) (xy 395.241652 -437.206963) (xy 395.249151 -437.183898) (xy 395.263412 -437.164281)
			(xy 395.283038 -437.150031) (xy 395.306107 -437.142545) (xy 395.318234 -437.142128) (xy 396.258034 -437.142128)
			(xy 396.270149 -437.142583) (xy 396.293192 -437.150078) (xy 396.312792 -437.164325) (xy 396.327033 -437.18393)
			(xy 396.334521 -437.206975) (xy 396.334996 -437.21909) (xy 396.334996 -438.089802) (xy 398.218406 -438.089802)
			(xy 398.218926 -438.057222) (xy 398.2269 -437.992552) (xy 398.242716 -437.92934) (xy 398.266137 -437.868535)
			(xy 398.296812 -437.811047) (xy 398.334281 -437.757738) (xy 398.377984 -437.709407) (xy 398.402302 -437.68772)
			(xy 398.48282 -437.523382) (xy 398.487521 -437.512865) (xy 398.49101 -437.490107) (xy 398.487525 -437.467348)
			(xy 398.48282 -437.456834) (xy 398.401794 -437.291734) (xy 398.377518 -437.270051) (xy 398.333922 -437.221716)
			(xy 398.296549 -437.168423) (xy 398.265957 -437.110968) (xy 398.242604 -437.05021) (xy 398.226839 -436.987057)
			(xy 398.218896 -436.922452) (xy 398.218406 -436.889906) (xy 398.219142 -436.850581) (xy 398.230741 -436.772791)
			(xy 398.24152 -436.734966) (xy 398.24152 -436.219092) (xy 398.241906 -436.207006) (xy 398.249379 -436.184018)
			(xy 398.263591 -436.164466) (xy 398.283151 -436.150263) (xy 398.306142 -436.1428) (xy 398.318228 -436.142384)
			(xy 399.258028 -436.142384) (xy 399.270103 -436.14284) (xy 399.29307 -436.150309) (xy 399.312606 -436.164508)
			(xy 399.3268 -436.184048) (xy 399.334263 -436.207017) (xy 399.334736 -436.219092) (xy 399.334736 -438.760616)
			(xy 399.33425 -438.772689) (xy 399.326786 -438.795651) (xy 399.312594 -438.815186) (xy 399.293062 -438.829381)
			(xy 399.270101 -438.836848) (xy 399.258028 -438.837324) (xy 398.318228 -438.837324) (xy 398.306148 -438.836864)
			(xy 398.283169 -438.829406) (xy 398.26362 -438.815211) (xy 398.249414 -438.79567) (xy 398.241943 -438.772695)
			(xy 398.24152 -438.760616) (xy 398.24152 -438.244742) (xy 398.230722 -438.20692) (xy 398.219114 -438.129129)
			(xy 398.218406 -438.089802) (xy 396.334996 -438.089802) (xy 396.334996 -439.0898) (xy 400.218402 -439.0898)
			(xy 400.218922 -439.05722) (xy 400.226896 -438.99255) (xy 400.242712 -438.929339) (xy 400.266133 -438.868533)
			(xy 400.296808 -438.811046) (xy 400.334278 -438.757736) (xy 400.37798 -438.709405) (xy 400.402298 -438.687718)
			(xy 400.482816 -438.52338) (xy 400.487519 -438.512864) (xy 400.491008 -438.490105) (xy 400.487522 -438.467346)
			(xy 400.482816 -438.456832) (xy 400.40179 -438.291732) (xy 400.377513 -438.270051) (xy 400.333917 -438.221716)
			(xy 400.296544 -438.168422) (xy 400.265953 -438.110967) (xy 400.2426 -438.050209) (xy 400.226834 -437.987055)
			(xy 400.218892 -437.92245) (xy 400.218402 -437.889904) (xy 400.219138 -437.850579) (xy 400.230737 -437.772789)
			(xy 400.241516 -437.734964) (xy 400.241516 -437.21909) (xy 400.241999 -437.207002) (xy 400.249455 -437.184006)
			(xy 400.263639 -437.164428) (xy 400.283167 -437.150177) (xy 400.306138 -437.142641) (xy 400.318224 -437.142128)
			(xy 401.258024 -437.142128) (xy 401.270137 -437.142496) (xy 401.29317 -437.150006) (xy 401.312745 -437.164279)
			(xy 401.326938 -437.183912) (xy 401.334353 -437.206975) (xy 401.334732 -437.21909) (xy 401.334732 -438.089802)
			(xy 402.218398 -438.089802) (xy 402.218921 -438.057222) (xy 402.226895 -437.992552) (xy 402.24271 -437.929341)
			(xy 402.266131 -437.868536) (xy 402.296805 -437.811048) (xy 402.334274 -437.757739) (xy 402.377976 -437.709407)
			(xy 402.402294 -437.68772) (xy 402.482812 -437.523382) (xy 402.487513 -437.512866) (xy 402.491003 -437.490107)
			(xy 402.487518 -437.467348) (xy 402.482812 -437.456834) (xy 402.401786 -437.291734) (xy 402.377509 -437.270053)
			(xy 402.333913 -437.221717) (xy 402.29654 -437.168424) (xy 402.265949 -437.110969) (xy 402.242596 -437.050211)
			(xy 402.226831 -436.987057) (xy 402.218888 -436.922452) (xy 402.218398 -436.889906) (xy 402.219134 -436.850581)
			(xy 402.230733 -436.772791) (xy 402.241512 -436.734966) (xy 402.241512 -436.219092) (xy 402.241906 -436.207007)
			(xy 402.249378 -436.18402) (xy 402.263588 -436.164469) (xy 402.283146 -436.150265) (xy 402.306135 -436.142802)
			(xy 402.31822 -436.142384) (xy 403.25802 -436.142384) (xy 403.270095 -436.142847) (xy 403.293061 -436.150314)
			(xy 403.312597 -436.164511) (xy 403.326791 -436.18405) (xy 403.334255 -436.207017) (xy 403.334728 -436.219092)
			(xy 403.334728 -438.760616) (xy 403.33425 -438.772689) (xy 403.326785 -438.795654) (xy 403.312591 -438.815189)
			(xy 403.293057 -438.829383) (xy 403.270093 -438.836849) (xy 403.25802 -438.837324) (xy 402.31822 -438.837324)
			(xy 402.30614 -438.83687) (xy 402.283161 -438.82941) (xy 402.263611 -438.815214) (xy 402.249406 -438.795672)
			(xy 402.241935 -438.772696) (xy 402.241512 -438.760616) (xy 402.241512 -438.244742) (xy 402.230714 -438.20692)
			(xy 402.219106 -438.129129) (xy 402.218398 -438.089802) (xy 401.334732 -438.089802) (xy 401.334732 -439.0898)
			(xy 404.218394 -439.0898) (xy 404.218917 -439.05722) (xy 404.226891 -438.99255) (xy 404.242706 -438.929339)
			(xy 404.266127 -438.868534) (xy 404.296802 -438.811046) (xy 404.334271 -438.757737) (xy 404.377972 -438.709405)
			(xy 404.40229 -438.687718) (xy 404.482808 -438.52338) (xy 404.487511 -438.512864) (xy 404.491 -438.490105)
			(xy 404.487514 -438.467346) (xy 404.482808 -438.456832) (xy 404.401782 -438.291732) (xy 404.377503 -438.270053)
			(xy 404.333907 -438.221717) (xy 404.296535 -438.168423) (xy 404.265944 -438.110968) (xy 404.242591 -438.050209)
			(xy 404.226826 -437.987055) (xy 404.218884 -437.92245) (xy 404.218394 -437.889904) (xy 404.21913 -437.850579)
			(xy 404.230729 -437.772789) (xy 404.241508 -437.734964) (xy 404.241508 -437.21909) (xy 404.241998 -437.207003)
			(xy 404.249454 -437.184008) (xy 404.263636 -437.164431) (xy 404.283162 -437.150179) (xy 404.306131 -437.142642)
			(xy 404.318216 -437.142128) (xy 405.258016 -437.142128) (xy 405.270129 -437.142503) (xy 405.293161 -437.15001)
			(xy 405.312736 -437.164281) (xy 405.326929 -437.183914) (xy 405.334345 -437.206976) (xy 405.334724 -437.21909)
			(xy 405.334724 -438.089802) (xy 406.21839 -438.089802) (xy 406.218916 -438.057222) (xy 406.226889 -437.992553)
			(xy 406.242704 -437.929341) (xy 406.266125 -437.868536) (xy 406.296799 -437.811048) (xy 406.334267 -437.757739)
			(xy 406.377969 -437.709407) (xy 406.402286 -437.68772) (xy 406.482804 -437.523382) (xy 406.487505 -437.512865)
			(xy 406.490995 -437.490107) (xy 406.48751 -437.467348) (xy 406.482804 -437.456834) (xy 406.401778 -437.291734)
			(xy 406.377499 -437.270055) (xy 406.333904 -437.221719) (xy 406.296531 -437.168425) (xy 406.26594 -437.110969)
			(xy 406.242588 -437.050211) (xy 406.226823 -436.987057) (xy 406.21888 -436.922452) (xy 406.21839 -436.889906)
			(xy 406.219127 -436.850581) (xy 406.230725 -436.772791) (xy 406.241504 -436.734966) (xy 406.241504 -436.219092)
			(xy 406.241906 -436.207008) (xy 406.249377 -436.184023) (xy 406.263586 -436.164471) (xy 406.283141 -436.150268)
			(xy 406.306128 -436.142803) (xy 406.318212 -436.142384) (xy 407.258012 -436.142384) (xy 407.270086 -436.142854)
			(xy 407.293053 -436.150319) (xy 407.312589 -436.164514) (xy 407.326783 -436.184051) (xy 407.334247 -436.207018)
			(xy 407.33472 -436.219092) (xy 407.33472 -438.760616) (xy 407.334249 -438.77269) (xy 407.326784 -438.795656)
			(xy 407.312589 -438.815191) (xy 407.293052 -438.829386) (xy 407.270086 -438.83685) (xy 407.258012 -438.837324)
			(xy 406.318212 -438.837324) (xy 406.30614 -438.836826) (xy 406.283176 -438.829369) (xy 406.26364 -438.81518)
			(xy 406.249444 -438.79565) (xy 406.241979 -438.772688) (xy 406.241504 -438.760616) (xy 406.241504 -438.244742)
			(xy 406.230705 -438.20692) (xy 406.219098 -438.129129) (xy 406.21839 -438.089802) (xy 405.334724 -438.089802)
			(xy 405.334724 -439.0898) (xy 408.218386 -439.0898) (xy 408.218912 -439.05722) (xy 408.226885 -438.992551)
			(xy 408.242701 -438.92934) (xy 408.266121 -438.868535) (xy 408.296795 -438.811047) (xy 408.334263 -438.757737)
			(xy 408.377965 -438.709406) (xy 408.402282 -438.687718) (xy 408.4828 -438.52338) (xy 408.487503 -438.512864)
			(xy 408.490993 -438.490105) (xy 408.487506 -438.467346) (xy 408.4828 -438.456832) (xy 408.401774 -438.291732)
			(xy 408.377493 -438.270055) (xy 408.333898 -438.221718) (xy 408.296526 -438.168424) (xy 408.265935 -438.110968)
			(xy 408.242583 -438.050209) (xy 408.226818 -437.987055) (xy 408.218876 -437.92245) (xy 408.218386 -437.889904)
			(xy 408.219122 -437.850579) (xy 408.230721 -437.772789) (xy 408.2415 -437.734964) (xy 408.2415 -437.21909)
			(xy 408.241998 -437.207004) (xy 408.249453 -437.18401) (xy 408.263633 -437.164434) (xy 408.283157 -437.150182)
			(xy 408.306124 -437.142643) (xy 408.318208 -437.142128) (xy 409.258008 -437.142128) (xy 409.27012 -437.14251)
			(xy 409.293152 -437.150015) (xy 409.312728 -437.164284) (xy 409.326921 -437.183915) (xy 409.334337 -437.206976)
			(xy 409.334716 -437.21909) (xy 409.334716 -438.089802) (xy 410.218382 -438.089802) (xy 410.21891 -438.057222)
			(xy 410.226884 -437.992553) (xy 410.242699 -437.929342) (xy 410.266119 -437.868537) (xy 410.296792 -437.811049)
			(xy 410.33426 -437.75774) (xy 410.377961 -437.709408) (xy 410.402278 -437.68772) (xy 410.482796 -437.523382)
			(xy 410.487498 -437.512866) (xy 410.490988 -437.490107) (xy 410.487502 -437.467348) (xy 410.482796 -437.456834)
			(xy 410.40177 -437.291734) (xy 410.37751 -437.270034) (xy 410.33391 -437.221704) (xy 410.296533 -437.168415)
			(xy 410.265939 -437.110963) (xy 410.242583 -437.050207) (xy 410.226816 -436.987055) (xy 410.218872 -436.922451)
			(xy 410.218382 -436.889906) (xy 410.219119 -436.850581) (xy 410.230717 -436.772791) (xy 410.241496 -436.734966)
			(xy 410.241496 -436.219092) (xy 410.241958 -436.207017) (xy 410.249423 -436.184049) (xy 410.26362 -436.164511)
			(xy 410.283159 -436.150317) (xy 410.306129 -436.142856) (xy 410.318204 -436.142384) (xy 411.258004 -436.142384)
			(xy 411.270078 -436.142861) (xy 411.293044 -436.150323) (xy 411.31258 -436.164517) (xy 411.326775 -436.184053)
			(xy 411.334239 -436.207018) (xy 411.334712 -436.219092) (xy 411.334712 -438.760616) (xy 411.334249 -438.772691)
			(xy 411.326783 -438.795658) (xy 411.312586 -438.815194) (xy 411.293047 -438.829388) (xy 411.270079 -438.836851)
			(xy 411.258004 -438.837324) (xy 410.318204 -438.837324) (xy 410.306131 -438.836833) (xy 410.283167 -438.829373)
			(xy 410.263631 -438.815183) (xy 410.249436 -438.795651) (xy 410.241971 -438.772689) (xy 410.241496 -438.760616)
			(xy 410.241496 -438.244742) (xy 410.230697 -438.20692) (xy 410.21909 -438.129129) (xy 410.218382 -438.089802)
			(xy 409.334716 -438.089802) (xy 409.334716 -439.0898) (xy 412.218378 -439.0898) (xy 412.218906 -439.05722)
			(xy 412.22688 -438.992551) (xy 412.242695 -438.92934) (xy 412.266115 -438.868535) (xy 412.296789 -438.811047)
			(xy 412.334256 -438.757738) (xy 412.377957 -438.709406) (xy 412.402274 -438.687718) (xy 412.482792 -438.52338)
			(xy 412.487495 -438.512864) (xy 412.490985 -438.490105) (xy 412.487499 -438.467346) (xy 412.482792 -438.456832)
			(xy 412.401766 -438.291732) (xy 412.377504 -438.270034) (xy 412.333904 -438.221704) (xy 412.296528 -438.168414)
			(xy 412.265934 -438.110962) (xy 412.242578 -438.050205) (xy 412.226811 -437.987053) (xy 412.218868 -437.922449)
			(xy 412.218378 -437.889904) (xy 412.219115 -437.850579) (xy 412.230713 -437.772789) (xy 412.241492 -437.734964)
			(xy 412.241492 -437.21909) (xy 412.241998 -437.207005) (xy 412.249452 -437.184012) (xy 412.26363 -437.164436)
			(xy 412.283152 -437.150184) (xy 412.306117 -437.142644) (xy 412.3182 -437.142128) (xy 413.258 -437.142128)
			(xy 413.270112 -437.142516) (xy 413.293144 -437.150019) (xy 413.312719 -437.164287) (xy 413.326913 -437.183916)
			(xy 413.334329 -437.206977) (xy 413.334708 -437.21909) (xy 413.334708 -439.760614) (xy 413.334206 -439.7727)
			(xy 413.326751 -439.795693) (xy 413.312572 -439.815268) (xy 413.293049 -439.82952) (xy 413.270084 -439.83706)
			(xy 413.258 -439.837576) (xy 412.3182 -439.837576) (xy 412.306089 -439.837184) (xy 412.283057 -439.829681)
			(xy 412.263482 -439.815414) (xy 412.249288 -439.795786) (xy 412.241872 -439.772727) (xy 412.241492 -439.760614)
			(xy 412.241492 -439.24474) (xy 412.230693 -439.206919) (xy 412.219086 -439.129127) (xy 412.218378 -439.0898)
			(xy 409.334716 -439.0898) (xy 409.334716 -439.760614) (xy 409.334304 -439.772709) (xy 409.326838 -439.795717)
			(xy 409.312639 -439.815301) (xy 409.293091 -439.829549) (xy 409.270101 -439.837073) (xy 409.258008 -439.837576)
			(xy 408.318208 -439.837576) (xy 408.306097 -439.837177) (xy 408.283066 -439.829677) (xy 408.263491 -439.815412)
			(xy 408.249296 -439.795785) (xy 408.24188 -439.772726) (xy 408.2415 -439.760614) (xy 408.2415 -439.24474)
			(xy 408.230701 -439.206918) (xy 408.219094 -439.129127) (xy 408.218386 -439.0898) (xy 405.334724 -439.0898)
			(xy 405.334724 -439.760614) (xy 405.334304 -439.772708) (xy 405.326839 -439.795715) (xy 405.312642 -439.815298)
			(xy 405.293096 -439.829547) (xy 405.270109 -439.837072) (xy 405.258016 -439.837576) (xy 404.318216 -439.837576)
			(xy 404.306106 -439.83717) (xy 404.283075 -439.829672) (xy 404.263499 -439.815408) (xy 404.249305 -439.795783)
			(xy 404.241888 -439.772726) (xy 404.241508 -439.760614) (xy 404.241508 -439.24474) (xy 404.230709 -439.206918)
			(xy 404.219102 -439.129127) (xy 404.218394 -439.0898) (xy 401.334732 -439.0898) (xy 401.334732 -439.760614)
			(xy 401.334304 -439.772707) (xy 401.32684 -439.795713) (xy 401.312645 -439.815295) (xy 401.293101 -439.829544)
			(xy 401.270116 -439.837071) (xy 401.258024 -439.837576) (xy 400.318224 -439.837576) (xy 400.306114 -439.837163)
			(xy 400.283083 -439.829667) (xy 400.263508 -439.815406) (xy 400.249313 -439.795781) (xy 400.241896 -439.772725)
			(xy 400.241516 -439.760614) (xy 400.241516 -439.24474) (xy 400.230717 -439.206918) (xy 400.21911 -439.129127)
			(xy 400.218402 -439.0898) (xy 396.334996 -439.0898) (xy 396.334996 -439.760614) (xy 396.334501 -439.772726)
			(xy 396.327014 -439.795764) (xy 396.312777 -439.815363) (xy 396.293182 -439.829605) (xy 396.270146 -439.837098)
			(xy 396.258034 -439.837576) (xy 395.318234 -439.837576) (xy 395.306114 -439.837111) (xy 395.283059 -439.82963)
			(xy 395.263445 -439.81539) (xy 395.249192 -439.795784) (xy 395.241696 -439.772733) (xy 395.241272 -439.760614)
			(xy 395.241272 -439.243978) (xy 395.230584 -439.206333) (xy 395.219107 -439.128926) (xy 395.218412 -439.0898)
			(xy 392.335004 -439.0898) (xy 392.335004 -439.760614) (xy 392.334501 -439.772725) (xy 392.327015 -439.795762)
			(xy 392.31278 -439.81536) (xy 392.293187 -439.829602) (xy 392.270153 -439.837097) (xy 392.258042 -439.837576)
			(xy 391.318242 -439.837576) (xy 391.306123 -439.837105) (xy 391.283068 -439.829626) (xy 391.263453 -439.815387)
			(xy 391.2492 -439.795783) (xy 391.241704 -439.772733) (xy 391.24128 -439.760614) (xy 391.24128 -439.243978)
			(xy 391.230592 -439.206333) (xy 391.219115 -439.128926) (xy 391.21842 -439.0898) (xy 388.335012 -439.0898)
			(xy 388.335012 -439.760614) (xy 388.334501 -439.772724) (xy 388.327016 -439.79576) (xy 388.312782 -439.815357)
			(xy 388.293192 -439.8296) (xy 388.27016 -439.837096) (xy 388.25805 -439.837576) (xy 387.31825 -439.837576)
			(xy 387.306134 -439.837131) (xy 387.283092 -439.829632) (xy 387.263492 -439.815382) (xy 387.249252 -439.795776)
			(xy 387.241763 -439.77273) (xy 387.241288 -439.760614) (xy 387.241288 -439.243978) (xy 387.2306 -439.206333)
			(xy 387.219123 -439.128926) (xy 387.218428 -439.0898) (xy 384.33502 -439.0898) (xy 384.33502 -439.760614)
			(xy 384.334651 -439.772742) (xy 384.32715 -439.795808) (xy 384.312886 -439.815426) (xy 384.293258 -439.829675)
			(xy 384.270186 -439.83716) (xy 384.258058 -439.837576) (xy 383.318258 -439.837576) (xy 383.306143 -439.837124)
			(xy 383.2831 -439.829627) (xy 383.263501 -439.815379) (xy 383.24926 -439.795774) (xy 383.241771 -439.77273)
			(xy 383.241296 -439.760614) (xy 383.241296 -439.243978) (xy 383.230608 -439.206333) (xy 383.219131 -439.128926)
			(xy 383.218436 -439.0898) (xy 346.23502 -439.0898) (xy 346.23502 -439.760614) (xy 346.234651 -439.772742)
			(xy 346.22715 -439.795808) (xy 346.212886 -439.815426) (xy 346.193258 -439.829675) (xy 346.170186 -439.83716)
			(xy 346.158058 -439.837576) (xy 345.218258 -439.837576) (xy 345.206143 -439.837124) (xy 345.1831 -439.829627)
			(xy 345.163501 -439.815379) (xy 345.14926 -439.795774) (xy 345.141771 -439.77273) (xy 345.141296 -439.760614)
			(xy 345.141296 -439.147966) (xy 345.139751 -439.133474) (xy 345.138099 -439.104374) (xy 345.137994 -439.0898)
			(xy 342.235028 -439.0898) (xy 342.235028 -439.760614) (xy 342.234651 -439.772741) (xy 342.227151 -439.795806)
			(xy 342.212889 -439.815424) (xy 342.193263 -439.829673) (xy 342.170193 -439.837159) (xy 342.158066 -439.837576)
			(xy 341.218266 -439.837576) (xy 341.206151 -439.837118) (xy 341.183109 -439.829623) (xy 341.163509 -439.815377)
			(xy 341.149268 -439.795773) (xy 341.141779 -439.772729) (xy 341.141304 -439.760614) (xy 341.141304 -439.147966)
			(xy 341.139759 -439.133474) (xy 341.138107 -439.104374) (xy 341.138002 -439.0898) (xy 338.235036 -439.0898)
			(xy 338.235036 -439.760614) (xy 338.234651 -439.77274) (xy 338.227152 -439.795804) (xy 338.212892 -439.815421)
			(xy 338.193268 -439.82967) (xy 338.1702 -439.837158) (xy 338.158074 -439.837576) (xy 337.218274 -439.837576)
			(xy 337.206159 -439.837111) (xy 337.183118 -439.829618) (xy 337.163518 -439.815374) (xy 337.149276 -439.795772)
			(xy 337.141787 -439.772729) (xy 337.141312 -439.760614) (xy 337.141312 -439.147966) (xy 337.139767 -439.133474)
			(xy 337.138115 -439.104374) (xy 337.13801 -439.0898) (xy 334.235044 -439.0898) (xy 334.235044 -439.760614)
			(xy 334.234651 -439.772739) (xy 334.227153 -439.795802) (xy 334.212895 -439.815418) (xy 334.193273 -439.829668)
			(xy 334.170207 -439.837157) (xy 334.158082 -439.837576) (xy 333.218282 -439.837576) (xy 333.206168 -439.837104)
			(xy 333.183126 -439.829614) (xy 333.163526 -439.815371) (xy 333.149285 -439.79577) (xy 333.141795 -439.772728)
			(xy 333.14132 -439.760614) (xy 333.14132 -439.147966) (xy 333.139775 -439.133474) (xy 333.138123 -439.104374)
			(xy 333.138018 -439.0898) (xy 329.2348 -439.0898) (xy 329.2348 -439.760614) (xy 329.234306 -439.7727)
			(xy 329.22685 -439.795695) (xy 329.212669 -439.815271) (xy 329.193144 -439.829523) (xy 329.170177 -439.837061)
			(xy 329.158092 -439.837576) (xy 328.218292 -439.837576) (xy 328.20618 -439.83719) (xy 328.183149 -439.829686)
			(xy 328.163574 -439.815417) (xy 328.14938 -439.795788) (xy 328.141964 -439.772727) (xy 328.141584 -439.760614)
			(xy 328.141584 -439.149998) (xy 328.139913 -439.135005) (xy 328.138136 -439.104886) (xy 328.138028 -439.0898)
			(xy 325.234808 -439.0898) (xy 325.234808 -439.760614) (xy 325.234306 -439.7727) (xy 325.226851 -439.795693)
			(xy 325.212672 -439.815268) (xy 325.193149 -439.82952) (xy 325.170184 -439.83706) (xy 325.1581 -439.837576)
			(xy 324.2183 -439.837576) (xy 324.206189 -439.837184) (xy 324.183157 -439.829681) (xy 324.163582 -439.815414)
			(xy 324.149388 -439.795786) (xy 324.141972 -439.772727) (xy 324.141592 -439.760614) (xy 324.141592 -439.149998)
			(xy 324.139921 -439.135005) (xy 324.138144 -439.104886) (xy 324.138036 -439.0898) (xy 321.234816 -439.0898)
			(xy 321.234816 -439.760614) (xy 321.234404 -439.772709) (xy 321.226938 -439.795717) (xy 321.212739 -439.815301)
			(xy 321.193191 -439.829549) (xy 321.170201 -439.837073) (xy 321.158108 -439.837576) (xy 320.218308 -439.837576)
			(xy 320.206197 -439.837177) (xy 320.183166 -439.829677) (xy 320.163591 -439.815412) (xy 320.149396 -439.795785)
			(xy 320.14198 -439.772726) (xy 320.1416 -439.760614) (xy 320.1416 -439.149998) (xy 320.139929 -439.135005)
			(xy 320.138152 -439.104886) (xy 320.138044 -439.0898) (xy 317.234824 -439.0898) (xy 317.234824 -439.760614)
			(xy 317.234404 -439.772708) (xy 317.226939 -439.795715) (xy 317.212742 -439.815298) (xy 317.193196 -439.829547)
			(xy 317.170209 -439.837072) (xy 317.158116 -439.837576) (xy 316.218316 -439.837576) (xy 316.206206 -439.83717)
			(xy 316.183175 -439.829672) (xy 316.163599 -439.815408) (xy 316.149405 -439.795783) (xy 316.141988 -439.772726)
			(xy 316.141608 -439.760614) (xy 316.141608 -439.149998) (xy 316.139937 -439.135005) (xy 316.13816 -439.104886)
			(xy 316.138052 -439.0898) (xy 157.334712 -439.0898) (xy 157.334712 -439.760614) (xy 157.334304 -439.772709)
			(xy 157.326838 -439.795718) (xy 157.312637 -439.815302) (xy 157.293089 -439.829551) (xy 157.270098 -439.837074)
			(xy 157.258004 -439.837576) (xy 156.318204 -439.837576) (xy 156.306093 -439.83718) (xy 156.283062 -439.829679)
			(xy 156.263486 -439.815413) (xy 156.249292 -439.795785) (xy 156.241876 -439.772727) (xy 156.241496 -439.760614)
			(xy 156.241496 -439.24474) (xy 156.230697 -439.206918) (xy 156.21909 -439.129127) (xy 156.218382 -439.0898)
			(xy 153.33472 -439.0898) (xy 153.33472 -439.760614) (xy 153.334304 -439.772708) (xy 153.326839 -439.795716)
			(xy 153.31264 -439.815299) (xy 153.293094 -439.829548) (xy 153.270105 -439.837073) (xy 153.258012 -439.837576)
			(xy 152.318212 -439.837576) (xy 152.306101 -439.837173) (xy 152.28307 -439.829674) (xy 152.263495 -439.81541)
			(xy 152.249301 -439.795784) (xy 152.241884 -439.772726) (xy 152.241504 -439.760614) (xy 152.241504 -439.24474)
			(xy 152.230705 -439.206918) (xy 152.219098 -439.129127) (xy 152.21839 -439.0898) (xy 149.334728 -439.0898)
			(xy 149.334728 -439.760614) (xy 149.334304 -439.772708) (xy 149.32684 -439.795714) (xy 149.312643 -439.815297)
			(xy 149.293099 -439.829546) (xy 149.270112 -439.837072) (xy 149.25802 -439.837576) (xy 148.31822 -439.837576)
			(xy 148.30611 -439.837166) (xy 148.283079 -439.829669) (xy 148.263504 -439.815407) (xy 148.249309 -439.795782)
			(xy 148.241892 -439.772726) (xy 148.241512 -439.760614) (xy 148.241512 -439.24474) (xy 148.230713 -439.206918)
			(xy 148.219106 -439.129127) (xy 148.218398 -439.0898) (xy 145.334736 -439.0898) (xy 145.334736 -439.760614)
			(xy 145.334304 -439.772707) (xy 145.326841 -439.795712) (xy 145.312646 -439.815294) (xy 145.293104 -439.829543)
			(xy 145.270119 -439.83707) (xy 145.258028 -439.837576) (xy 144.318228 -439.837576) (xy 144.306118 -439.837159)
			(xy 144.283088 -439.829665) (xy 144.263512 -439.815404) (xy 144.249317 -439.795781) (xy 144.2419 -439.772725)
			(xy 144.24152 -439.760614) (xy 144.24152 -439.24474) (xy 144.230721 -439.206918) (xy 144.219114 -439.129127)
			(xy 144.218406 -439.0898) (xy 140.335 -439.0898) (xy 140.335 -439.760614) (xy 140.334501 -439.772726)
			(xy 140.327015 -439.795763) (xy 140.312778 -439.815361) (xy 140.293184 -439.829604) (xy 140.270149 -439.837097)
			(xy 140.258038 -439.837576) (xy 139.318238 -439.837576) (xy 139.306119 -439.837108) (xy 139.283063 -439.829628)
			(xy 139.263449 -439.815388) (xy 139.249196 -439.795783) (xy 139.2417 -439.772733) (xy 139.241276 -439.760614)
			(xy 139.241276 -439.243978) (xy 139.230588 -439.206333) (xy 139.219111 -439.128926) (xy 139.218416 -439.0898)
			(xy 136.335008 -439.0898) (xy 136.335008 -439.760614) (xy 136.334501 -439.772725) (xy 136.327016 -439.795761)
			(xy 136.312781 -439.815358) (xy 136.293189 -439.829601) (xy 136.270157 -439.837096) (xy 136.258046 -439.837576)
			(xy 135.318246 -439.837576) (xy 135.306127 -439.837101) (xy 135.283072 -439.829623) (xy 135.263457 -439.815385)
			(xy 135.249204 -439.795782) (xy 135.241708 -439.772733) (xy 135.241284 -439.760614) (xy 135.241284 -439.243978)
			(xy 135.230596 -439.206333) (xy 135.219119 -439.128926) (xy 135.218424 -439.0898) (xy 132.335016 -439.0898)
			(xy 132.335016 -439.760614) (xy 132.334651 -439.772742) (xy 132.327149 -439.795809) (xy 132.312885 -439.815428)
			(xy 132.293255 -439.829677) (xy 132.270182 -439.83716) (xy 132.258054 -439.837576) (xy 131.318254 -439.837576)
			(xy 131.306138 -439.837128) (xy 131.283096 -439.82963) (xy 131.263496 -439.815381) (xy 131.249256 -439.795775)
			(xy 131.241767 -439.77273) (xy 131.241292 -439.760614) (xy 131.241292 -439.243978) (xy 131.230604 -439.206333)
			(xy 131.219127 -439.128926) (xy 131.218432 -439.0898) (xy 128.335024 -439.0898) (xy 128.335024 -439.760614)
			(xy 128.334651 -439.772741) (xy 128.32715 -439.795807) (xy 128.312888 -439.815425) (xy 128.29326 -439.829674)
			(xy 128.27019 -439.837159) (xy 128.258062 -439.837576) (xy 127.318262 -439.837576) (xy 127.306147 -439.837121)
			(xy 127.283105 -439.829625) (xy 127.263505 -439.815378) (xy 127.249264 -439.795774) (xy 127.241775 -439.772729)
			(xy 127.2413 -439.760614) (xy 127.2413 -439.243978) (xy 127.230612 -439.206333) (xy 127.219135 -439.128926)
			(xy 127.21844 -439.0898) (xy 90.235024 -439.0898) (xy 90.235024 -439.760614) (xy 90.234651 -439.772741)
			(xy 90.22715 -439.795807) (xy 90.212888 -439.815425) (xy 90.19326 -439.829674) (xy 90.17019 -439.837159)
			(xy 90.158062 -439.837576) (xy 89.218262 -439.837576) (xy 89.206147 -439.837121) (xy 89.183105 -439.829625)
			(xy 89.163505 -439.815378) (xy 89.149264 -439.795774) (xy 89.141775 -439.772729) (xy 89.1413 -439.760614)
			(xy 89.1413 -439.147966) (xy 89.139755 -439.133474) (xy 89.138103 -439.104374) (xy 89.137998 -439.0898)
			(xy 86.235032 -439.0898) (xy 86.235032 -439.760614) (xy 86.234651 -439.77274) (xy 86.227152 -439.795805)
			(xy 86.212891 -439.815422) (xy 86.193265 -439.829672) (xy 86.170197 -439.837158) (xy 86.15807 -439.837576)
			(xy 85.21827 -439.837576) (xy 85.206155 -439.837114) (xy 85.183113 -439.82962) (xy 85.163513 -439.815375)
			(xy 85.149272 -439.795772) (xy 85.141783 -439.772729) (xy 85.141308 -439.760614) (xy 85.141308 -439.147966)
			(xy 85.139763 -439.133474) (xy 85.138111 -439.104374) (xy 85.138006 -439.0898) (xy 82.23504 -439.0898)
			(xy 82.23504 -439.760614) (xy 82.234651 -439.77274) (xy 82.227153 -439.795803) (xy 82.212894 -439.815419)
			(xy 82.19327 -439.829669) (xy 82.170204 -439.837157) (xy 82.158078 -439.837576) (xy 81.218278 -439.837576)
			(xy 81.206164 -439.837107) (xy 81.183122 -439.829616) (xy 81.163522 -439.815372) (xy 81.149281 -439.795771)
			(xy 81.141791 -439.772728) (xy 81.141316 -439.760614) (xy 81.141316 -439.147966) (xy 81.139771 -439.133474)
			(xy 81.138119 -439.104374) (xy 81.138014 -439.0898) (xy 78.235048 -439.0898) (xy 78.235048 -439.760614)
			(xy 78.2346 -439.772731) (xy 78.227107 -439.795777) (xy 78.21286 -439.81538) (xy 78.193252 -439.82962)
			(xy 78.170203 -439.837105) (xy 78.158086 -439.837576) (xy 77.218286 -439.837576) (xy 77.206172 -439.837101)
			(xy 77.183131 -439.829611) (xy 77.16353 -439.81537) (xy 77.149289 -439.795769) (xy 77.141799 -439.772728)
			(xy 77.141324 -439.760614) (xy 77.141324 -439.147966) (xy 77.139779 -439.133474) (xy 77.138127 -439.104374)
			(xy 77.138022 -439.0898) (xy 73.234804 -439.0898) (xy 73.234804 -439.760614) (xy 73.234306 -439.7727)
			(xy 73.22685 -439.795694) (xy 73.21267 -439.81527) (xy 73.193146 -439.829521) (xy 73.17018 -439.837061)
			(xy 73.158096 -439.837576) (xy 72.218296 -439.837576) (xy 72.206185 -439.837187) (xy 72.183153 -439.829683)
			(xy 72.163578 -439.815416) (xy 72.149384 -439.795787) (xy 72.141968 -439.772727) (xy 72.141588 -439.760614)
			(xy 72.141588 -439.149998) (xy 72.139917 -439.135005) (xy 72.13814 -439.104886) (xy 72.138032 -439.0898)
			(xy 69.234812 -439.0898) (xy 69.234812 -439.760614) (xy 69.234404 -439.772709) (xy 69.226938 -439.795718)
			(xy 69.212737 -439.815302) (xy 69.193189 -439.829551) (xy 69.170198 -439.837074) (xy 69.158104 -439.837576)
			(xy 68.218304 -439.837576) (xy 68.206193 -439.83718) (xy 68.183162 -439.829679) (xy 68.163586 -439.815413)
			(xy 68.149392 -439.795785) (xy 68.141976 -439.772727) (xy 68.141596 -439.760614) (xy 68.141596 -439.149998)
			(xy 68.139925 -439.135005) (xy 68.138148 -439.104886) (xy 68.13804 -439.0898) (xy 65.23482 -439.0898)
			(xy 65.23482 -439.760614) (xy 65.234404 -439.772708) (xy 65.226939 -439.795716) (xy 65.21274 -439.815299)
			(xy 65.193194 -439.829548) (xy 65.170205 -439.837073) (xy 65.158112 -439.837576) (xy 64.218312 -439.837576)
			(xy 64.206201 -439.837173) (xy 64.18317 -439.829674) (xy 64.163595 -439.81541) (xy 64.149401 -439.795784)
			(xy 64.141984 -439.772726) (xy 64.141604 -439.760614) (xy 64.141604 -439.149998) (xy 64.139933 -439.135005)
			(xy 64.138156 -439.104886) (xy 64.138048 -439.0898) (xy 61.234828 -439.0898) (xy 61.234828 -439.760614)
			(xy 61.234404 -439.772708) (xy 61.22694 -439.795714) (xy 61.212743 -439.815297) (xy 61.193199 -439.829546)
			(xy 61.170212 -439.837072) (xy 61.15812 -439.837576) (xy 60.21832 -439.837576) (xy 60.20621 -439.837166)
			(xy 60.183179 -439.829669) (xy 60.163604 -439.815407) (xy 60.149409 -439.795782) (xy 60.141992 -439.772726)
			(xy 60.141612 -439.760614) (xy 60.141612 -439.149998) (xy 60.139941 -439.135005) (xy 60.138164 -439.104886)
			(xy 60.138056 -439.0898) (xy 7.00913 -439.0898) (xy 7.00913 -439.989976) (xy 7.009638 -440.045746)
			(xy 7.017973 -440.156973) (xy 7.034597 -440.267266) (xy 7.059417 -440.376009) (xy 7.092293 -440.482593)
			(xy 7.133043 -440.586422) (xy 7.181438 -440.686915) (xy 7.237207 -440.783511) (xy 7.300039 -440.87567)
			(xy 7.369583 -440.962874) (xy 7.445449 -441.044639) (xy 7.527212 -441.120505) (xy 7.614417 -441.190048)
			(xy 7.706575 -441.252881) (xy 7.803171 -441.30865) (xy 7.903664 -441.357045) (xy 8.007493 -441.397795)
			(xy 8.114077 -441.430672) (xy 8.22282 -441.455492) (xy 8.333113 -441.472116) (xy 8.44434 -441.480451)
			(xy 8.50011 -441.480956) (xy 194.495928 -441.480956)
		)
		(stroke
			(width 0)
			(type solid)
		)
		(fill yes)
		(layer "In3.Cu")
		(net "GND")
	)
	(gr_line
		(start 206.17434 -435.523132)
		(end 207.503268 -436.85206)
		(stroke
			(width 0.635)
			(type default)
		)
		(layer "In3.Cu")
	)
	(gr_line
		(start 206.17434 -415.567368)
		(end 206.17434 -435.523132)
		(stroke
			(width 0.635)
			(type default)
		)
		(layer "In3.Cu")
	)
	(gr_line
		(start 207.213708 -414.528)
		(end 206.17434 -415.567368)
		(stroke
			(width 0.635)
			(type default)
		)
		(layer "In3.Cu")
	)
	(gr_line
		(start 207.503268 -436.85206)
		(end 228.909372 -436.85206)
		(stroke
			(width 0.635)
			(type default)
		)
		(layer "In3.Cu")
	)
	(gr_line
		(start 228.909372 -436.85206)
		(end 230.69804 -435.063392)
		(stroke
			(width 0.635)
			(type default)
		)
		(layer "In3.Cu")
	)
	(gr_line
		(start 230.69804 -423.45102)
		(end 230.69804 -435.063392)
		(stroke
			(width 0.635)
			(type default)
		)
		(layer "In3.Cu")
	)
	(gr_line
		(start 232.938828 -414.528)
		(end 207.213708 -414.528)
		(stroke
			(width 0.635)
			(type default)
		)
		(layer "In3.Cu")
	)
	(gr_line
		(start 233.20502 -420.94404)
		(end 230.69804 -423.45102)
		(stroke
			(width 0.635)
			(type default)
		)
		(layer "In3.Cu")
	)
	(gr_line
		(start 239.67694 -402.10994)
		(end 239.86236 -402.29536)
		(stroke
			(width 0.508)
			(type default)
		)
		(layer "In3.Cu")
	)
	(gr_line
		(start 239.67694 -397.53286)
		(end 239.67694 -402.10994)
		(stroke
			(width 0.508)
			(type default)
		)
		(layer "In3.Cu")
	)
	(gr_line
		(start 239.713008 -407.75382)
		(end 232.938828 -414.528)
		(stroke
			(width 0.635)
			(type default)
		)
		(layer "In3.Cu")
	)
	(gr_line
		(start 239.81918 -401.97786)
		(end 239.81918 -397.5608)
		(stroke
			(width 0.2)
			(type default)
		)
		(layer "In3.Cu")
	)
	(gr_line
		(start 239.81918 -397.5608)
		(end 240.07826 -397.30172)
		(stroke
			(width 0.2)
			(type default)
		)
		(layer "In3.Cu")
	)
	(gr_line
		(start 239.86236 -402.29536)
		(end 275.44522 -402.29536)
		(stroke
			(width 0.508)
			(type default)
		)
		(layer "In3.Cu")
	)
	(gr_line
		(start 239.96904 -402.12772)
		(end 239.81918 -401.97786)
		(stroke
			(width 0.2)
			(type default)
		)
		(layer "In3.Cu")
	)
	(gr_line
		(start 240.06556 -397.14424)
		(end 239.67694 -397.53286)
		(stroke
			(width 0.508)
			(type default)
		)
		(layer "In3.Cu")
	)
	(gr_line
		(start 240.07826 -397.30172)
		(end 280.16454 -397.30172)
		(stroke
			(width 0.2)
			(type default)
		)
		(layer "In3.Cu")
	)
	(gr_line
		(start 270.496792 -420.94404)
		(end 233.20502 -420.94404)
		(stroke
			(width 0.635)
			(type default)
		)
		(layer "In3.Cu")
	)
	(gr_line
		(start 275.44522 -402.29536)
		(end 280.32202 -402.29536)
		(stroke
			(width 0.508)
			(type default)
		)
		(layer "In3.Cu")
	)
	(gr_line
		(start 275.680932 -415.7599)
		(end 270.496792 -420.94404)
		(stroke
			(width 0.635)
			(type default)
		)
		(layer "In3.Cu")
	)
	(gr_line
		(start 279.927812 -415.7599)
		(end 275.680932 -415.7599)
		(stroke
			(width 0.635)
			(type default)
		)
		(layer "In3.Cu")
	)
	(gr_line
		(start 279.927812 -415.7599)
		(end 280.51506 -415.172652)
		(stroke
			(width 0.635)
			(type default)
		)
		(layer "In3.Cu")
	)
	(gr_line
		(start 280.100532 -407.75382)
		(end 239.713008 -407.75382)
		(stroke
			(width 0.635)
			(type default)
		)
		(layer "In3.Cu")
	)
	(gr_line
		(start 280.16454 -397.30172)
		(end 280.34742 -397.4846)
		(stroke
			(width 0.2)
			(type default)
		)
		(layer "In3.Cu")
	)
	(gr_line
		(start 280.17978 -402.12772)
		(end 239.96904 -402.12772)
		(stroke
			(width 0.2)
			(type default)
		)
		(layer "In3.Cu")
	)
	(gr_line
		(start 280.24074 -397.14424)
		(end 240.06556 -397.14424)
		(stroke
			(width 0.508)
			(type default)
		)
		(layer "In3.Cu")
	)
	(gr_line
		(start 280.32202 -402.29536)
		(end 280.50998 -402.1074)
		(stroke
			(width 0.508)
			(type default)
		)
		(layer "In3.Cu")
	)
	(gr_line
		(start 280.34742 -401.96008)
		(end 280.17978 -402.12772)
		(stroke
			(width 0.2)
			(type default)
		)
		(layer "In3.Cu")
	)
	(gr_line
		(start 280.34742 -397.4846)
		(end 280.34742 -401.96008)
		(stroke
			(width 0.2)
			(type default)
		)
		(layer "In3.Cu")
	)
	(gr_line
		(start 280.50998 -402.1074)
		(end 280.50998 -397.41348)
		(stroke
			(width 0.508)
			(type default)
		)
		(layer "In3.Cu")
	)
	(gr_line
		(start 280.50998 -397.41348)
		(end 280.24074 -397.14424)
		(stroke
			(width 0.508)
			(type default)
		)
		(layer "In3.Cu")
	)
	(gr_line
		(start 280.51506 -415.172652)
		(end 280.51506 -408.168348)
		(stroke
			(width 0.635)
			(type default)
		)
		(layer "In3.Cu")
	)
	(gr_line
		(start 280.51506 -408.168348)
		(end 280.100532 -407.75382)
		(stroke
			(width 0.635)
			(type default)
		)
		(layer "In3.Cu")
	)
	(gr_poly
		(pts
			(xy 84.203794 -265.109706) (xy 84.203794 -265.06551) (xy 83.848194 -265.06551) (xy 83.848194 -265.109706)
			(xy 83.895184 -265.262106) (xy 84.156804 -265.262106)
		)
		(stroke
			(width 0)
			(type solid)
		)
		(fill yes)
		(layer "In4.Cu")
		(net "M_B_CPU1_SA_DQ<26>")
	)
	(gr_poly
		(pts
			(xy 84.203794 -263.891014) (xy 84.156804 -263.738614) (xy 83.895184 -263.738614) (xy 83.848194 -263.891014)
			(xy 83.848194 -263.93521) (xy 84.203794 -263.93521)
		)
		(stroke
			(width 0)
			(type solid)
		)
		(fill yes)
		(layer "In4.Cu")
		(net "M_B_CPU1_SA_DQ<27>")
	)
	(gr_poly
		(pts
			(xy 84.203794 -263.482074) (xy 84.203794 -263.437878) (xy 83.848194 -263.437878) (xy 83.848194 -263.482074)
			(xy 83.895184 -263.634474) (xy 84.156804 -263.634474)
		)
		(stroke
			(width 0)
			(type solid)
		)
		(fill yes)
		(layer "In4.Cu")
		(net "M_B_CPU1_SA_DQS_DP<3>")
	)
	(gr_poly
		(pts
			(xy 84.203794 -262.262874) (xy 84.156804 -262.110474) (xy 83.895184 -262.110474) (xy 83.848194 -262.262874)
			(xy 83.848194 -262.307324) (xy 84.203794 -262.307324)
		)
		(stroke
			(width 0)
			(type solid)
		)
		(fill yes)
		(layer "In4.Cu")
		(net "M_B_CPU1_SA_DQS_DP<8>")
	)
	(gr_poly
		(pts
			(xy 84.203794 -261.854442) (xy 84.203794 -261.809992) (xy 83.848194 -261.809992) (xy 83.848194 -261.854442)
			(xy 83.895184 -262.006842) (xy 84.156804 -262.006842)
		)
		(stroke
			(width 0)
			(type solid)
		)
		(fill yes)
		(layer "In4.Cu")
		(net "M_B_CPU1_SA_DQ<28>")
	)
	(gr_poly
		(pts
			(xy 84.55533 -244.940582) (xy 84.50834 -244.788182) (xy 84.24672 -244.788182) (xy 84.19973 -244.940582)
			(xy 84.19973 -244.985032) (xy 84.55533 -244.985032)
		)
		(stroke
			(width 0)
			(type solid)
		)
		(fill yes)
		(layer "In4.Cu")
		(net "M_C_CPU1_SB_CS_N<1>")
	)
	(gr_poly
		(pts
			(xy 84.55533 -230.290878) (xy 84.50834 -230.138478) (xy 84.24672 -230.138478) (xy 84.19973 -230.290878)
			(xy 84.19973 -230.335074) (xy 84.55533 -230.335074)
		)
		(stroke
			(width 0)
			(type solid)
		)
		(fill yes)
		(layer "In4.Cu")
		(net "M_C_CPU1_SB_DQS_DN<2>")
	)
	(gr_poly
		(pts
			(xy 84.563966 -246.568722) (xy 84.516976 -246.416322) (xy 84.255356 -246.416322) (xy 84.208366 -246.568722)
			(xy 84.208366 -246.613172) (xy 84.563966 -246.613172)
		)
		(stroke
			(width 0)
			(type solid)
		)
		(fill yes)
		(layer "In4.Cu")
		(net "M_C_CPU1_SB_PAR")
	)
	(gr_poly
		(pts
			(xy 84.563966 -246.16029) (xy 84.563966 -246.11584) (xy 84.208366 -246.11584) (xy 84.208366 -246.16029)
			(xy 84.255356 -246.31269) (xy 84.516976 -246.31269)
		)
		(stroke
			(width 0)
			(type solid)
		)
		(fill yes)
		(layer "In4.Cu")
		(net "M_C_CPU1_SB_CS_N<2>")
	)
	(gr_poly
		(pts
			(xy 84.563966 -231.510078) (xy 84.563966 -231.465882) (xy 84.208366 -231.465882) (xy 84.208366 -231.510078)
			(xy 84.255356 -231.662478) (xy 84.516976 -231.662478)
		)
		(stroke
			(width 0)
			(type solid)
		)
		(fill yes)
		(layer "In4.Cu")
		(net "M_C_CPU1_SB_DQ<17>")
	)
	(gr_poly
		(pts
			(xy 84.563966 -228.663246) (xy 84.516976 -228.510846) (xy 84.255356 -228.510846) (xy 84.208366 -228.663246)
			(xy 84.208366 -228.707696) (xy 84.563966 -228.707696)
		)
		(stroke
			(width 0)
			(type solid)
		)
		(fill yes)
		(layer "In4.Cu")
		(net "M_C_CPU1_SB_DQ<22>")
	)
	(gr_poly
		(pts
			(xy 84.572348 -242.905026) (xy 84.572348 -242.860576) (xy 84.216748 -242.860576) (xy 84.216748 -242.905026)
			(xy 84.263738 -243.057426) (xy 84.525358 -243.057426)
		)
		(stroke
			(width 0)
			(type solid)
		)
		(fill yes)
		(layer "In4.Cu")
		(net "M_C_CPU1_SB_CB<5>")
	)
	(gr_poly
		(pts
			(xy 84.572348 -231.91851) (xy 84.525358 -231.76611) (xy 84.263738 -231.76611) (xy 84.216748 -231.91851)
			(xy 84.216748 -231.96296) (xy 84.572348 -231.96296)
		)
		(stroke
			(width 0)
			(type solid)
		)
		(fill yes)
		(layer "In4.Cu")
		(net "M_C_CPU1_SB_DQ<18>")
	)
	(gr_poly
		(pts
			(xy 84.578698 -228.255322) (xy 84.578698 -228.210872) (xy 84.223098 -228.210872) (xy 84.223098 -228.255322)
			(xy 84.270088 -228.407722) (xy 84.531708 -228.407722)
		)
		(stroke
			(width 0)
			(type solid)
		)
		(fill yes)
		(layer "In4.Cu")
		(net "M_C_CPU1_SB_DQ<21>")
	)
	(gr_poly
		(pts
			(xy 84.673694 -266.332462) (xy 84.626704 -266.180062) (xy 84.365084 -266.180062) (xy 84.318094 -266.332462)
			(xy 84.318094 -266.376658) (xy 84.673694 -266.376658)
		)
		(stroke
			(width 0)
			(type solid)
		)
		(fill yes)
		(layer "In4.Cu")
		(net "M_C_CPU1_SA_DQ<22>")
	)
	(gr_poly
		(pts
			(xy 84.673694 -265.92403) (xy 84.673694 -265.87958) (xy 84.318094 -265.87958) (xy 84.318094 -265.92403)
			(xy 84.365084 -266.07643) (xy 84.626704 -266.07643)
		)
		(stroke
			(width 0)
			(type solid)
		)
		(fill yes)
		(layer "In4.Cu")
		(net "M_C_CPU1_SA_DQ<21>")
	)
	(gr_poly
		(pts
			(xy 84.673694 -264.70483) (xy 84.626704 -264.55243) (xy 84.365084 -264.55243) (xy 84.318094 -264.70483)
			(xy 84.318094 -264.749026) (xy 84.673694 -264.749026)
		)
		(stroke
			(width 0)
			(type solid)
		)
		(fill yes)
		(layer "In4.Cu")
		(net "M_B_CPU1_SA_DQ<24>")
	)
	(gr_poly
		(pts
			(xy 84.673694 -264.29589) (xy 84.673694 -264.251694) (xy 84.318094 -264.251694) (xy 84.318094 -264.29589)
			(xy 84.365084 -264.44829) (xy 84.626704 -264.44829)
		)
		(stroke
			(width 0)
			(type solid)
		)
		(fill yes)
		(layer "In4.Cu")
		(net "M_B_CPU1_SA_DQ<25>")
	)
	(gr_poly
		(pts
			(xy 84.673694 -263.07669) (xy 84.626704 -262.92429) (xy 84.365084 -262.92429) (xy 84.318094 -263.07669)
			(xy 84.318094 -263.12114) (xy 84.673694 -263.12114)
		)
		(stroke
			(width 0)
			(type solid)
		)
		(fill yes)
		(layer "In4.Cu")
		(net "M_B_CPU1_SA_DQS_DN<3>")
	)
	(gr_poly
		(pts
			(xy 84.673694 -262.668258) (xy 84.673694 -262.623808) (xy 84.318094 -262.623808) (xy 84.318094 -262.668258)
			(xy 84.365084 -262.820658) (xy 84.626704 -262.820658)
		)
		(stroke
			(width 0)
			(type solid)
		)
		(fill yes)
		(layer "In4.Cu")
		(net "M_B_CPU1_SA_DQS_DN<8>")
	)
	(gr_poly
		(pts
			(xy 84.673694 -261.449058) (xy 84.626704 -261.296658) (xy 84.365084 -261.296658) (xy 84.318094 -261.449058)
			(xy 84.318094 -261.493508) (xy 84.673694 -261.493508)
		)
		(stroke
			(width 0)
			(type solid)
		)
		(fill yes)
		(layer "In4.Cu")
		(net "M_B_CPU1_SA_DQ<30>")
	)
	(gr_poly
		(pts
			(xy 84.673694 -261.040626) (xy 84.673694 -260.996176) (xy 84.318094 -260.996176) (xy 84.318094 -261.040626)
			(xy 84.365084 -261.193026) (xy 84.626704 -261.193026)
		)
		(stroke
			(width 0)
			(type solid)
		)
		(fill yes)
		(layer "In4.Cu")
		(net "M_B_CPU1_SA_DQ<29>")
	)
	(gr_poly
		(pts
			(xy 84.888832 -223.223582) (xy 84.927186 -223.201484) (xy 84.749386 -222.893636) (xy 84.711032 -222.915734)
			(xy 84.602574 -223.032574) (xy 84.733384 -223.259142)
		)
		(stroke
			(width 0)
			(type solid)
		)
		(fill yes)
		(layer "In4.Cu")
		(net "M_B_CPU1_SB_DQ<30>")
	)
	(gr_poly
		(pts
			(xy 84.923376 -241.86134) (xy 84.885022 -241.839242) (xy 84.729574 -241.803682) (xy 84.598764 -242.03025)
			(xy 84.707222 -242.14709) (xy 84.745576 -242.169188)
		)
		(stroke
			(width 0)
			(type solid)
		)
		(fill yes)
		(layer "In4.Cu")
		(net "M_C_CPU1_SB_CB<7>")
	)
	(gr_poly
		(pts
			(xy 84.923376 -236.97819) (xy 84.885022 -236.956092) (xy 84.729574 -236.920532) (xy 84.598764 -237.1471)
			(xy 84.707222 -237.26394) (xy 84.745576 -237.286038)
		)
		(stroke
			(width 0)
			(type solid)
		)
		(fill yes)
		(layer "In4.Cu")
		(net "M_B_CPU1_SB_DQ<0>")
	)
	(gr_poly
		(pts
			(xy 84.999068 -224.231962) (xy 85.107526 -224.115122) (xy 84.976716 -223.888554) (xy 84.821268 -223.924114)
			(xy 84.782914 -223.946212) (xy 84.960714 -224.25406)
		)
		(stroke
			(width 0)
			(type solid)
		)
		(fill yes)
		(layer "In4.Cu")
		(net "M_B_CPU1_SB_DQS_DP<8>")
	)
	(gr_poly
		(pts
			(xy 84.999068 -222.604584) (xy 85.107526 -222.487744) (xy 84.976716 -222.261176) (xy 84.821268 -222.296736)
			(xy 84.782914 -222.318834) (xy 84.960714 -222.626682)
		)
		(stroke
			(width 0)
			(type solid)
		)
		(fill yes)
		(layer "In4.Cu")
		(net "M_B_CPU1_SB_DQ<28>")
	)
	(gr_poly
		(pts
			(xy 85.02523 -243.718842) (xy 85.02523 -243.674392) (xy 84.66963 -243.674392) (xy 84.66963 -243.718842)
			(xy 84.71662 -243.871242) (xy 84.97824 -243.871242)
		)
		(stroke
			(width 0)
			(type solid)
		)
		(fill yes)
		(layer "In4.Cu")
		(net "M_C_CPU1_SB_CB<4>")
	)
	(gr_poly
		(pts
			(xy 85.02523 -232.732326) (xy 84.97824 -232.579926) (xy 84.71662 -232.579926) (xy 84.66963 -232.732326)
			(xy 84.66963 -232.776776) (xy 85.02523 -232.776776)
		)
		(stroke
			(width 0)
			(type solid)
		)
		(fill yes)
		(layer "In4.Cu")
		(net "M_B_CPU1_SB_DQ<7>")
	)
	(gr_poly
		(pts
			(xy 85.02523 -232.324402) (xy 85.02523 -232.279952) (xy 84.66963 -232.279952) (xy 84.66963 -232.324402)
			(xy 84.71662 -232.476802) (xy 84.97824 -232.476802)
		)
		(stroke
			(width 0)
			(type solid)
		)
		(fill yes)
		(layer "In4.Cu")
		(net "M_C_CPU1_SB_DQ<16>")
	)
	(gr_poly
		(pts
			(xy 85.033866 -247.382538) (xy 84.986876 -247.230138) (xy 84.725256 -247.230138) (xy 84.678266 -247.382538)
			(xy 84.678266 -247.426988) (xy 85.033866 -247.426988)
		)
		(stroke
			(width 0)
			(type solid)
		)
		(fill yes)
		(layer "In4.Cu")
		(net "M_C_CPU1_SB_CA<5>")
	)
	(gr_poly
		(pts
			(xy 85.033866 -246.974106) (xy 85.033866 -246.929656) (xy 84.678266 -246.929656) (xy 84.678266 -246.974106)
			(xy 84.725256 -247.126506) (xy 84.986876 -247.126506)
		)
		(stroke
			(width 0)
			(type solid)
		)
		(fill yes)
		(layer "In4.Cu")
		(net "M_C_CPU1_SB_CA<6>")
	)
	(gr_poly
		(pts
			(xy 85.033866 -245.754906) (xy 84.986876 -245.602506) (xy 84.725256 -245.602506) (xy 84.678266 -245.754906)
			(xy 84.678266 -245.799356) (xy 85.033866 -245.799356)
		)
		(stroke
			(width 0)
			(type solid)
		)
		(fill yes)
		(layer "In4.Cu")
		(net "M_C_CPU1_SB_CS_N<0>")
	)
	(gr_poly
		(pts
			(xy 85.033866 -240.871502) (xy 84.986876 -240.719102) (xy 84.725256 -240.719102) (xy 84.678266 -240.871502)
			(xy 84.678266 -240.915952) (xy 85.033866 -240.915952)
		)
		(stroke
			(width 0)
			(type solid)
		)
		(fill yes)
		(layer "In4.Cu")
		(net "M_C_CPU1_SB_DQS_DN<9>")
	)
	(gr_poly
		(pts
			(xy 85.033866 -238.83493) (xy 85.033866 -238.790734) (xy 84.678266 -238.790734) (xy 84.678266 -238.83493)
			(xy 84.725256 -238.98733) (xy 84.986876 -238.98733)
		)
		(stroke
			(width 0)
			(type solid)
		)
		(fill yes)
		(layer "In4.Cu")
		(net "M_C_CPU1_SB_CB<1>")
	)
	(gr_poly
		(pts
			(xy 85.033866 -235.988098) (xy 84.986876 -235.835698) (xy 84.725256 -235.835698) (xy 84.678266 -235.988098)
			(xy 84.678266 -236.032548) (xy 85.033866 -236.032548)
		)
		(stroke
			(width 0)
			(type solid)
		)
		(fill yes)
		(layer "In4.Cu")
		(net "M_B_CPU1_SB_DQ<3>")
	)
	(gr_poly
		(pts
			(xy 85.033866 -233.952034) (xy 85.033866 -233.907584) (xy 84.678266 -233.907584) (xy 84.678266 -233.952034)
			(xy 84.725256 -234.104434) (xy 84.986876 -234.104434)
		)
		(stroke
			(width 0)
			(type solid)
		)
		(fill yes)
		(layer "In4.Cu")
		(net "M_B_CPU1_SB_DQ<4>")
	)
	(gr_poly
		(pts
			(xy 85.033866 -231.104694) (xy 84.986876 -230.952294) (xy 84.725256 -230.952294) (xy 84.678266 -231.104694)
			(xy 84.678266 -231.149144) (xy 85.033866 -231.149144)
		)
		(stroke
			(width 0)
			(type solid)
		)
		(fill yes)
		(layer "In4.Cu")
		(net "M_C_CPU1_SB_DQ<19>")
	)
	(gr_poly
		(pts
			(xy 85.033866 -229.06863) (xy 85.033866 -229.02418) (xy 84.678266 -229.02418) (xy 84.678266 -229.06863)
			(xy 84.725256 -229.22103) (xy 84.986876 -229.22103)
		)
		(stroke
			(width 0)
			(type solid)
		)
		(fill yes)
		(layer "In4.Cu")
		(net "M_C_CPU1_SB_DQ<20>")
	)
	(gr_poly
		(pts
			(xy 85.03793 -227.855018) (xy 84.99094 -227.702618) (xy 84.72932 -227.702618) (xy 84.68233 -227.855018)
			(xy 84.68233 -227.899468) (xy 85.03793 -227.899468)
		)
		(stroke
			(width 0)
			(type solid)
		)
		(fill yes)
		(layer "In4.Cu")
		(net "M_C_CPU1_SB_DQ<23>")
	)
	(gr_poly
		(pts
			(xy 85.042248 -245.346474) (xy 85.042248 -245.302278) (xy 84.686648 -245.302278) (xy 84.686648 -245.346474)
			(xy 84.733638 -245.498874) (xy 84.995258 -245.498874)
		)
		(stroke
			(width 0)
			(type solid)
		)
		(fill yes)
		(layer "In4.Cu")
		(net "M_C_CPU1_SB_CS_N<3>")
	)
	(gr_poly
		(pts
			(xy 85.042248 -239.243362) (xy 84.995258 -239.090962) (xy 84.733638 -239.090962) (xy 84.686648 -239.243362)
			(xy 84.686648 -239.287812) (xy 85.042248 -239.287812)
		)
		(stroke
			(width 0)
			(type solid)
		)
		(fill yes)
		(layer "In4.Cu")
		(net "M_C_CPU1_SB_CB<2>")
	)
	(gr_poly
		(pts
			(xy 85.042248 -235.579666) (xy 85.042248 -235.53547) (xy 84.686648 -235.53547) (xy 84.686648 -235.579666)
			(xy 84.733638 -235.732066) (xy 84.995258 -235.732066)
		)
		(stroke
			(width 0)
			(type solid)
		)
		(fill yes)
		(layer "In4.Cu")
		(net "M_B_CPU1_SB_DQS_DP<0>")
	)
	(gr_poly
		(pts
			(xy 85.042248 -234.360466) (xy 84.995258 -234.208066) (xy 84.733638 -234.208066) (xy 84.686648 -234.360466)
			(xy 84.686648 -234.404662) (xy 85.042248 -234.404662)
		)
		(stroke
			(width 0)
			(type solid)
		)
		(fill yes)
		(layer "In4.Cu")
		(net "M_B_CPU1_SB_DQS_DP<5>")
	)
	(gr_poly
		(pts
			(xy 85.042248 -230.696262) (xy 85.042248 -230.652066) (xy 84.686648 -230.652066) (xy 84.686648 -230.696262)
			(xy 84.733638 -230.848662) (xy 84.995258 -230.848662)
		)
		(stroke
			(width 0)
			(type solid)
		)
		(fill yes)
		(layer "In4.Cu")
		(net "M_C_CPU1_SB_DQS_DP<2>")
	)
	(gr_poly
		(pts
			(xy 85.042248 -229.477062) (xy 84.995258 -229.324662) (xy 84.733638 -229.324662) (xy 84.686648 -229.477062)
			(xy 84.686648 -229.521258) (xy 85.042248 -229.521258)
		)
		(stroke
			(width 0)
			(type solid)
		)
		(fill yes)
		(layer "In4.Cu")
		(net "M_C_CPU1_SB_DQS_DP<7>")
	)
	(gr_poly
		(pts
			(xy 85.105748 -242.570762) (xy 84.99729 -242.453922) (xy 84.958936 -242.431824) (xy 84.781136 -242.739672)
			(xy 84.81949 -242.76177) (xy 84.974938 -242.79733)
		)
		(stroke
			(width 0)
			(type solid)
		)
		(fill yes)
		(layer "In4.Cu")
		(net "M_C_CPU1_SB_CB<5>")
	)
	(gr_poly
		(pts
			(xy 85.107526 -237.686088) (xy 84.999068 -237.569248) (xy 84.960714 -237.54715) (xy 84.782914 -237.854998)
			(xy 84.821268 -237.877096) (xy 84.976716 -237.912656)
		)
		(stroke
			(width 0)
			(type solid)
		)
		(fill yes)
		(layer "In4.Cu")
		(net "M_B_CPU1_SB_DQ<2>")
	)
	(gr_poly
		(pts
			(xy 85.143594 -266.737846) (xy 85.143594 -266.693396) (xy 84.787994 -266.693396) (xy 84.787994 -266.737846)
			(xy 84.834984 -266.890246) (xy 85.096604 -266.890246)
		)
		(stroke
			(width 0)
			(type solid)
		)
		(fill yes)
		(layer "In4.Cu")
		(net "M_C_CPU1_SA_DQ<20>")
	)
	(gr_poly
		(pts
			(xy 85.143594 -265.518646) (xy 85.096604 -265.366246) (xy 84.834984 -265.366246) (xy 84.787994 -265.518646)
			(xy 84.787994 -265.562842) (xy 85.143594 -265.562842)
		)
		(stroke
			(width 0)
			(type solid)
		)
		(fill yes)
		(layer "In4.Cu")
		(net "M_C_CPU1_SA_DQ<23>")
	)
	(gr_poly
		(pts
			(xy 85.143594 -265.109706) (xy 85.143594 -265.06551) (xy 84.787994 -265.06551) (xy 84.787994 -265.109706)
			(xy 84.834984 -265.262106) (xy 85.096604 -265.262106)
		)
		(stroke
			(width 0)
			(type solid)
		)
		(fill yes)
		(layer "In4.Cu")
		(net "M_B_CPU1_SA_DQ<26>")
	)
	(gr_poly
		(pts
			(xy 85.143594 -263.891014) (xy 85.096604 -263.738614) (xy 84.834984 -263.738614) (xy 84.787994 -263.891014)
			(xy 84.787994 -263.93521) (xy 85.143594 -263.93521)
		)
		(stroke
			(width 0)
			(type solid)
		)
		(fill yes)
		(layer "In4.Cu")
		(net "M_B_CPU1_SA_DQ<27>")
	)
	(gr_poly
		(pts
			(xy 85.143594 -263.482074) (xy 85.143594 -263.437878) (xy 84.787994 -263.437878) (xy 84.787994 -263.482074)
			(xy 84.834984 -263.634474) (xy 85.096604 -263.634474)
		)
		(stroke
			(width 0)
			(type solid)
		)
		(fill yes)
		(layer "In4.Cu")
		(net "M_B_CPU1_SA_DQS_DP<3>")
	)
	(gr_poly
		(pts
			(xy 85.143594 -262.262874) (xy 85.096604 -262.110474) (xy 84.834984 -262.110474) (xy 84.787994 -262.262874)
			(xy 84.787994 -262.307324) (xy 85.143594 -262.307324)
		)
		(stroke
			(width 0)
			(type solid)
		)
		(fill yes)
		(layer "In4.Cu")
		(net "M_B_CPU1_SA_DQS_DP<8>")
	)
	(gr_poly
		(pts
			(xy 85.143594 -261.854442) (xy 85.143594 -261.809992) (xy 84.787994 -261.809992) (xy 84.787994 -261.854442)
			(xy 84.834984 -262.006842) (xy 85.096604 -262.006842)
		)
		(stroke
			(width 0)
			(type solid)
		)
		(fill yes)
		(layer "In4.Cu")
		(net "M_B_CPU1_SA_DQ<28>")
	)
	(gr_poly
		(pts
			(xy 85.143594 -260.635242) (xy 85.096604 -260.482842) (xy 84.834984 -260.482842) (xy 84.787994 -260.635242)
			(xy 84.787994 -260.679438) (xy 85.143594 -260.679438)
		)
		(stroke
			(width 0)
			(type solid)
		)
		(fill yes)
		(layer "In4.Cu")
		(net "M_B_CPU1_SA_DQ<31>")
	)
	(gr_poly
		(pts
			(xy 85.358478 -222.409512) (xy 85.396832 -222.387414) (xy 85.219032 -222.079566) (xy 85.180678 -222.101664)
			(xy 85.07222 -222.218504) (xy 85.20303 -222.445072)
		)
		(stroke
			(width 0)
			(type solid)
		)
		(fill yes)
		(layer "In4.Cu")
		(net "M_B_CPU1_SB_DQ<31>")
	)
	(gr_poly
		(pts
			(xy 85.397594 -244.29593) (xy 85.35924 -244.273832) (xy 85.203792 -244.238272) (xy 85.072982 -244.46484)
			(xy 85.18144 -244.58168) (xy 85.219794 -244.603778)
		)
		(stroke
			(width 0)
			(type solid)
		)
		(fill yes)
		(layer "In4.Cu")
		(net "M_C_CPU1_SB_CS_N<1>")
	)
	(gr_poly
		(pts
			(xy 85.398864 -237.782354) (xy 85.36051 -237.760256) (xy 85.205062 -237.724696) (xy 85.074252 -237.951264)
			(xy 85.18271 -238.068104) (xy 85.221064 -238.090202)
		)
		(stroke
			(width 0)
			(type solid)
		)
		(fill yes)
		(layer "In4.Cu")
		(net "M_C_CPU1_SB_CB<3>")
	)
	(gr_poly
		(pts
			(xy 85.400642 -242.664234) (xy 85.362288 -242.642136) (xy 85.20684 -242.606576) (xy 85.07603 -242.833144)
			(xy 85.184488 -242.949984) (xy 85.222842 -242.972082)
		)
		(stroke
			(width 0)
			(type solid)
		)
		(fill yes)
		(layer "In4.Cu")
		(net "M_C_CPU1_SB_CB<6>")
	)
	(gr_poly
		(pts
			(xy 85.469222 -223.418654) (xy 85.57768 -223.301814) (xy 85.44687 -223.075246) (xy 85.291422 -223.110806)
			(xy 85.253068 -223.132904) (xy 85.430868 -223.440752)
		)
		(stroke
			(width 0)
			(type solid)
		)
		(fill yes)
		(layer "In4.Cu")
		(net "M_B_CPU1_SB_DQ<28>")
	)
	(gr_poly
		(pts
			(xy 85.49513 -240.057178) (xy 85.44814 -239.904778) (xy 85.18652 -239.904778) (xy 85.13953 -240.057178)
			(xy 85.13953 -240.101628) (xy 85.49513 -240.101628)
		)
		(stroke
			(width 0)
			(type solid)
		)
		(fill yes)
		(layer "In4.Cu")
		(net "M_C_CPU1_SB_DQS_DP<4>")
	)
	(gr_poly
		(pts
			(xy 85.49513 -239.649254) (xy 85.49513 -239.604804) (xy 85.13953 -239.604804) (xy 85.13953 -239.649254)
			(xy 85.18652 -239.801654) (xy 85.44814 -239.801654)
		)
		(stroke
			(width 0)
			(type solid)
		)
		(fill yes)
		(layer "In4.Cu")
		(net "M_C_CPU1_SB_CB<0>")
	)
	(gr_poly
		(pts
			(xy 85.49513 -235.174282) (xy 85.44814 -235.021882) (xy 85.18652 -235.021882) (xy 85.13953 -235.174282)
			(xy 85.13953 -235.218478) (xy 85.49513 -235.218478)
		)
		(stroke
			(width 0)
			(type solid)
		)
		(fill yes)
		(layer "In4.Cu")
		(net "M_B_CPU1_SB_DQS_DN<0>")
	)
	(gr_poly
		(pts
			(xy 85.49513 -234.76585) (xy 85.49513 -234.721654) (xy 85.13953 -234.721654) (xy 85.13953 -234.76585)
			(xy 85.18652 -234.91825) (xy 85.44814 -234.91825)
		)
		(stroke
			(width 0)
			(type solid)
		)
		(fill yes)
		(layer "In4.Cu")
		(net "M_B_CPU1_SB_DQS_DN<5>")
	)
	(gr_poly
		(pts
			(xy 85.49513 -230.290878) (xy 85.44814 -230.138478) (xy 85.18652 -230.138478) (xy 85.13953 -230.290878)
			(xy 85.13953 -230.335074) (xy 85.49513 -230.335074)
		)
		(stroke
			(width 0)
			(type solid)
		)
		(fill yes)
		(layer "In4.Cu")
		(net "M_C_CPU1_SB_DQS_DN<2>")
	)
	(gr_poly
		(pts
			(xy 85.49513 -229.882446) (xy 85.49513 -229.83825) (xy 85.13953 -229.83825) (xy 85.13953 -229.882446)
			(xy 85.18652 -230.034846) (xy 85.44814 -230.034846)
		)
		(stroke
			(width 0)
			(type solid)
		)
		(fill yes)
		(layer "In4.Cu")
		(net "M_C_CPU1_SB_DQS_DN<7>")
	)
	(gr_poly
		(pts
			(xy 85.503258 -273.833336) (xy 85.464904 -273.811238) (xy 85.309456 -273.775678) (xy 85.178646 -274.002246)
			(xy 85.287104 -274.119086) (xy 85.325458 -274.141184)
		)
		(stroke
			(width 0)
			(type solid)
		)
		(fill yes)
		(layer "In4.Cu")
		(net "M_B_CPU1_SA_DQS_DP<6>")
	)
	(gr_poly
		(pts
			(xy 85.503766 -247.787922) (xy 85.503766 -247.743472) (xy 85.148166 -247.743472) (xy 85.148166 -247.787922)
			(xy 85.195156 -247.940322) (xy 85.456776 -247.940322)
		)
		(stroke
			(width 0)
			(type solid)
		)
		(fill yes)
		(layer "In4.Cu")
		(net "M_C_CPU1_SB_CA<4>")
	)
	(gr_poly
		(pts
			(xy 85.503766 -246.568722) (xy 85.456776 -246.416322) (xy 85.195156 -246.416322) (xy 85.148166 -246.568722)
			(xy 85.148166 -246.613172) (xy 85.503766 -246.613172)
		)
		(stroke
			(width 0)
			(type solid)
		)
		(fill yes)
		(layer "In4.Cu")
		(net "M_C_CPU1_SB_PAR")
	)
	(gr_poly
		(pts
			(xy 85.503766 -246.16029) (xy 85.503766 -246.11584) (xy 85.148166 -246.11584) (xy 85.148166 -246.16029)
			(xy 85.195156 -246.31269) (xy 85.456776 -246.31269)
		)
		(stroke
			(width 0)
			(type solid)
		)
		(fill yes)
		(layer "In4.Cu")
		(net "M_C_CPU1_SB_CS_N<2>")
	)
	(gr_poly
		(pts
			(xy 85.503766 -241.276886) (xy 85.503766 -241.232436) (xy 85.148166 -241.232436) (xy 85.148166 -241.276886)
			(xy 85.195156 -241.429286) (xy 85.456776 -241.429286)
		)
		(stroke
			(width 0)
			(type solid)
		)
		(fill yes)
		(layer "In4.Cu")
		(net "M_C_CPU1_SB_DQS_DP<9>")
	)
	(gr_poly
		(pts
			(xy 85.503766 -236.393482) (xy 85.503766 -236.349286) (xy 85.148166 -236.349286) (xy 85.148166 -236.393482)
			(xy 85.195156 -236.545882) (xy 85.456776 -236.545882)
		)
		(stroke
			(width 0)
			(type solid)
		)
		(fill yes)
		(layer "In4.Cu")
		(net "M_B_CPU1_SB_DQ<1>")
	)
	(gr_poly
		(pts
			(xy 85.503766 -233.54665) (xy 85.456776 -233.39425) (xy 85.195156 -233.39425) (xy 85.148166 -233.54665)
			(xy 85.148166 -233.590846) (xy 85.503766 -233.590846)
		)
		(stroke
			(width 0)
			(type solid)
		)
		(fill yes)
		(layer "In4.Cu")
		(net "M_B_CPU1_SB_DQ<6>")
	)
	(gr_poly
		(pts
			(xy 85.503766 -231.510078) (xy 85.503766 -231.465882) (xy 85.148166 -231.465882) (xy 85.148166 -231.510078)
			(xy 85.195156 -231.662478) (xy 85.456776 -231.662478)
		)
		(stroke
			(width 0)
			(type solid)
		)
		(fill yes)
		(layer "In4.Cu")
		(net "M_C_CPU1_SB_DQ<17>")
	)
	(gr_poly
		(pts
			(xy 85.503766 -228.663246) (xy 85.456776 -228.510846) (xy 85.195156 -228.510846) (xy 85.148166 -228.663246)
			(xy 85.148166 -228.707696) (xy 85.503766 -228.707696)
		)
		(stroke
			(width 0)
			(type solid)
		)
		(fill yes)
		(layer "In4.Cu")
		(net "M_C_CPU1_SB_DQ<22>")
	)
	(gr_poly
		(pts
			(xy 85.503766 -224.998534) (xy 85.503766 -224.954338) (xy 85.148166 -224.954338) (xy 85.148166 -224.998534)
			(xy 85.195156 -225.150934) (xy 85.456776 -225.150934)
		)
		(stroke
			(width 0)
			(type solid)
		)
		(fill yes)
		(layer "In4.Cu")
		(net "M_B_CPU1_SB_DQS_DN<8>")
	)
	(gr_poly
		(pts
			(xy 85.509354 -275.450046) (xy 85.471 -275.427948) (xy 85.315552 -275.392388) (xy 85.184742 -275.618956)
			(xy 85.2932 -275.735796) (xy 85.331554 -275.757894)
		)
		(stroke
			(width 0)
			(type solid)
		)
		(fill yes)
		(layer "In4.Cu")
		(net "M_B_CPU1_SA_DQS_DN<1>")
	)
	(gr_poly
		(pts
			(xy 85.509608 -272.194528) (xy 85.471254 -272.17243) (xy 85.315806 -272.13687) (xy 85.184996 -272.363438)
			(xy 85.293454 -272.480278) (xy 85.331808 -272.502376)
		)
		(stroke
			(width 0)
			(type solid)
		)
		(fill yes)
		(layer "In4.Cu")
		(net "M_B_CPU1_SA_DQ<14>")
	)
	(gr_poly
		(pts
			(xy 85.509608 -226.627182) (xy 85.509608 -226.582732) (xy 85.154008 -226.582732) (xy 85.154008 -226.627182)
			(xy 85.200998 -226.779582) (xy 85.462618 -226.779582)
		)
		(stroke
			(width 0)
			(type solid)
		)
		(fill yes)
		(layer "In4.Cu")
		(net "M_B_CPU1_SB_DQ<24>")
	)
	(gr_poly
		(pts
			(xy 85.512148 -241.685318) (xy 85.465158 -241.532918) (xy 85.203538 -241.532918) (xy 85.156548 -241.685318)
			(xy 85.156548 -241.729514) (xy 85.512148 -241.729514)
		)
		(stroke
			(width 0)
			(type solid)
		)
		(fill yes)
		(layer "In4.Cu")
		(net "M_C_CPU1_SB_CB<7>")
	)
	(gr_poly
		(pts
			(xy 85.512148 -236.801914) (xy 85.465158 -236.649514) (xy 85.203538 -236.649514) (xy 85.156548 -236.801914)
			(xy 85.156548 -236.846364) (xy 85.512148 -236.846364)
		)
		(stroke
			(width 0)
			(type solid)
		)
		(fill yes)
		(layer "In4.Cu")
		(net "M_B_CPU1_SB_DQ<0>")
	)
	(gr_poly
		(pts
			(xy 85.512148 -233.138218) (xy 85.512148 -233.093768) (xy 85.156548 -233.093768) (xy 85.156548 -233.138218)
			(xy 85.203538 -233.290618) (xy 85.465158 -233.290618)
		)
		(stroke
			(width 0)
			(type solid)
		)
		(fill yes)
		(layer "In4.Cu")
		(net "M_B_CPU1_SB_DQ<5>")
	)
	(gr_poly
		(pts
			(xy 85.512148 -231.91851) (xy 85.465158 -231.76611) (xy 85.203538 -231.76611) (xy 85.156548 -231.91851)
			(xy 85.156548 -231.96296) (xy 85.512148 -231.96296)
		)
		(stroke
			(width 0)
			(type solid)
		)
		(fill yes)
		(layer "In4.Cu")
		(net "M_C_CPU1_SB_DQ<18>")
	)
	(gr_poly
		(pts
			(xy 85.512148 -228.254814) (xy 85.512148 -228.210618) (xy 85.156548 -228.210618) (xy 85.156548 -228.254814)
			(xy 85.203538 -228.407214) (xy 85.465158 -228.407214)
		)
		(stroke
			(width 0)
			(type solid)
		)
		(fill yes)
		(layer "In4.Cu")
		(net "M_C_CPU1_SB_DQ<21>")
	)
	(gr_poly
		(pts
			(xy 85.575648 -245.013734) (xy 85.46719 -244.896894) (xy 85.428836 -244.874796) (xy 85.251036 -245.182644)
			(xy 85.28939 -245.204742) (xy 85.444838 -245.240302)
		)
		(stroke
			(width 0)
			(type solid)
		)
		(fill yes)
		(layer "In4.Cu")
		(net "M_C_CPU1_SB_CS_N<3>")
	)
	(gr_poly
		(pts
			(xy 85.578696 -238.497364) (xy 85.470238 -238.380524) (xy 85.431884 -238.358426) (xy 85.254084 -238.666274)
			(xy 85.292438 -238.688372) (xy 85.447886 -238.723932)
		)
		(stroke
			(width 0)
			(type solid)
		)
		(fill yes)
		(layer "In4.Cu")
		(net "M_C_CPU1_SB_CB<1>")
	)
	(gr_poly
		(pts
			(xy 85.583014 -243.373656) (xy 85.474556 -243.256816) (xy 85.436202 -243.234718) (xy 85.258402 -243.542566)
			(xy 85.296756 -243.564664) (xy 85.452204 -243.600224)
		)
		(stroke
			(width 0)
			(type solid)
		)
		(fill yes)
		(layer "In4.Cu")
		(net "M_C_CPU1_SB_CB<4>")
	)
	(gr_poly
		(pts
			(xy 85.613494 -267.960094) (xy 85.566504 -267.807694) (xy 85.304884 -267.807694) (xy 85.257894 -267.960094)
			(xy 85.257894 -268.004544) (xy 85.613494 -268.004544)
		)
		(stroke
			(width 0)
			(type solid)
		)
		(fill yes)
		(layer "In4.Cu")
		(net "M_C_CPU1_SA_DQS_DN<2>")
	)
	(gr_poly
		(pts
			(xy 85.613494 -267.551662) (xy 85.613494 -267.507212) (xy 85.257894 -267.507212) (xy 85.257894 -267.551662)
			(xy 85.304884 -267.704062) (xy 85.566504 -267.704062)
		)
		(stroke
			(width 0)
			(type solid)
		)
		(fill yes)
		(layer "In4.Cu")
		(net "M_C_CPU1_SA_DQS_DN<7>")
	)
	(gr_poly
		(pts
			(xy 85.613494 -266.332462) (xy 85.566504 -266.180062) (xy 85.304884 -266.180062) (xy 85.257894 -266.332462)
			(xy 85.257894 -266.376658) (xy 85.613494 -266.376658)
		)
		(stroke
			(width 0)
			(type solid)
		)
		(fill yes)
		(layer "In4.Cu")
		(net "M_C_CPU1_SA_DQ<22>")
	)
	(gr_poly
		(pts
			(xy 85.613494 -265.92403) (xy 85.613494 -265.87958) (xy 85.257894 -265.87958) (xy 85.257894 -265.92403)
			(xy 85.304884 -266.07643) (xy 85.566504 -266.07643)
		)
		(stroke
			(width 0)
			(type solid)
		)
		(fill yes)
		(layer "In4.Cu")
		(net "M_C_CPU1_SA_DQ<21>")
	)
	(gr_poly
		(pts
			(xy 85.613494 -264.70483) (xy 85.566504 -264.55243) (xy 85.304884 -264.55243) (xy 85.257894 -264.70483)
			(xy 85.257894 -264.749026) (xy 85.613494 -264.749026)
		)
		(stroke
			(width 0)
			(type solid)
		)
		(fill yes)
		(layer "In4.Cu")
		(net "M_B_CPU1_SA_DQ<24>")
	)
	(gr_poly
		(pts
			(xy 85.613494 -264.29589) (xy 85.613494 -264.251694) (xy 85.257894 -264.251694) (xy 85.257894 -264.29589)
			(xy 85.304884 -264.44829) (xy 85.566504 -264.44829)
		)
		(stroke
			(width 0)
			(type solid)
		)
		(fill yes)
		(layer "In4.Cu")
		(net "M_B_CPU1_SA_DQ<25>")
	)
	(gr_poly
		(pts
			(xy 85.613494 -263.07669) (xy 85.566504 -262.92429) (xy 85.304884 -262.92429) (xy 85.257894 -263.07669)
			(xy 85.257894 -263.12114) (xy 85.613494 -263.12114)
		)
		(stroke
			(width 0)
			(type solid)
		)
		(fill yes)
		(layer "In4.Cu")
		(net "M_B_CPU1_SA_DQS_DN<3>")
	)
	(gr_poly
		(pts
			(xy 85.613494 -262.668258) (xy 85.613494 -262.623808) (xy 85.257894 -262.623808) (xy 85.257894 -262.668258)
			(xy 85.304884 -262.820658) (xy 85.566504 -262.820658)
		)
		(stroke
			(width 0)
			(type solid)
		)
		(fill yes)
		(layer "In4.Cu")
		(net "M_B_CPU1_SA_DQS_DN<8>")
	)
	(gr_poly
		(pts
			(xy 85.613494 -261.449058) (xy 85.566504 -261.296658) (xy 85.304884 -261.296658) (xy 85.257894 -261.449058)
			(xy 85.257894 -261.493508) (xy 85.613494 -261.493508)
		)
		(stroke
			(width 0)
			(type solid)
		)
		(fill yes)
		(layer "In4.Cu")
		(net "M_B_CPU1_SA_DQ<30>")
	)
	(gr_poly
		(pts
			(xy 85.613494 -261.040626) (xy 85.613494 -260.996176) (xy 85.257894 -260.996176) (xy 85.257894 -261.040626)
			(xy 85.304884 -261.193026) (xy 85.566504 -261.193026)
		)
		(stroke
			(width 0)
			(type solid)
		)
		(fill yes)
		(layer "In4.Cu")
		(net "M_B_CPU1_SA_DQ<29>")
	)
	(gr_poly
		(pts
			(xy 85.692742 -274.531582) (xy 85.584284 -274.414742) (xy 85.54593 -274.392644) (xy 85.36813 -274.700492)
			(xy 85.406484 -274.72259) (xy 85.561932 -274.75815)
		)
		(stroke
			(width 0)
			(type solid)
		)
		(fill yes)
		(layer "In4.Cu")
		(net "M_B_CPU1_SA_DQS_DN<6>")
	)
	(gr_poly
		(pts
			(xy 85.828632 -223.223582) (xy 85.866986 -223.201484) (xy 85.689186 -222.893636) (xy 85.650832 -222.915734)
			(xy 85.542374 -223.032574) (xy 85.673184 -223.259142)
		)
		(stroke
			(width 0)
			(type solid)
		)
		(fill yes)
		(layer "In4.Cu")
		(net "M_B_CPU1_SB_DQ<31>")
	)
	(gr_poly
		(pts
			(xy 85.863176 -243.489226) (xy 85.824822 -243.467128) (xy 85.669374 -243.431568) (xy 85.538564 -243.658136)
			(xy 85.647022 -243.774976) (xy 85.685376 -243.797074)
		)
		(stroke
			(width 0)
			(type solid)
		)
		(fill yes)
		(layer "In4.Cu")
		(net "M_C_CPU1_SB_CS_N<1>")
	)
	(gr_poly
		(pts
			(xy 85.867748 -238.59871) (xy 85.829394 -238.576612) (xy 85.673946 -238.541052) (xy 85.543136 -238.76762)
			(xy 85.651594 -238.88446) (xy 85.689948 -238.906558)
		)
		(stroke
			(width 0)
			(type solid)
		)
		(fill yes)
		(layer "In4.Cu")
		(net "M_C_CPU1_SB_CB<2>")
	)
	(gr_poly
		(pts
			(xy 85.870542 -245.104666) (xy 85.832188 -245.082568) (xy 85.67674 -245.047008) (xy 85.54593 -245.273576)
			(xy 85.654388 -245.390416) (xy 85.692742 -245.412514)
		)
		(stroke
			(width 0)
			(type solid)
		)
		(fill yes)
		(layer "In4.Cu")
		(net "M_C_CPU1_SB_CS_N<0>")
	)
	(gr_poly
		(pts
			(xy 85.939122 -222.604584) (xy 86.04758 -222.487744) (xy 85.91677 -222.261176) (xy 85.761322 -222.296736)
			(xy 85.722968 -222.318834) (xy 85.900768 -222.626682)
		)
		(stroke
			(width 0)
			(type solid)
		)
		(fill yes)
		(layer "In4.Cu")
		(net "M_B_CPU1_SB_DQ<29>")
	)
	(gr_poly
		(pts
			(xy 85.96757 -242.499134) (xy 85.92058 -242.346734) (xy 85.65896 -242.346734) (xy 85.61197 -242.499134)
			(xy 85.61197 -242.54333) (xy 85.96757 -242.54333)
		)
		(stroke
			(width 0)
			(type solid)
		)
		(fill yes)
		(layer "In4.Cu")
		(net "M_C_CPU1_SB_CB<6>")
	)
	(gr_poly
		(pts
			(xy 85.96757 -242.090702) (xy 85.96757 -242.046506) (xy 85.61197 -242.046506) (xy 85.61197 -242.090702)
			(xy 85.65896 -242.243102) (xy 85.92058 -242.243102)
		)
		(stroke
			(width 0)
			(type solid)
		)
		(fill yes)
		(layer "In4.Cu")
		(net "M_C_CPU1_SB_CB<5>")
	)
	(gr_poly
		(pts
			(xy 85.96757 -237.61573) (xy 85.92058 -237.46333) (xy 85.65896 -237.46333) (xy 85.61197 -237.61573)
			(xy 85.61197 -237.66018) (xy 85.96757 -237.66018)
		)
		(stroke
			(width 0)
			(type solid)
		)
		(fill yes)
		(layer "In4.Cu")
		(net "M_C_CPU1_SB_CB<3>")
	)
	(gr_poly
		(pts
			(xy 85.96757 -237.207806) (xy 85.96757 -237.163356) (xy 85.61197 -237.163356) (xy 85.61197 -237.207806)
			(xy 85.65896 -237.360206) (xy 85.92058 -237.360206)
		)
		(stroke
			(width 0)
			(type solid)
		)
		(fill yes)
		(layer "In4.Cu")
		(net "M_B_CPU1_SB_DQ<2>")
	)
	(gr_poly
		(pts
			(xy 85.96757 -232.732326) (xy 85.92058 -232.579926) (xy 85.65896 -232.579926) (xy 85.61197 -232.732326)
			(xy 85.61197 -232.776776) (xy 85.96757 -232.776776)
		)
		(stroke
			(width 0)
			(type solid)
		)
		(fill yes)
		(layer "In4.Cu")
		(net "M_B_CPU1_SB_DQ<7>")
	)
	(gr_poly
		(pts
			(xy 85.96757 -232.324402) (xy 85.96757 -232.279952) (xy 85.61197 -232.279952) (xy 85.61197 -232.324402)
			(xy 85.65896 -232.476802) (xy 85.92058 -232.476802)
		)
		(stroke
			(width 0)
			(type solid)
		)
		(fill yes)
		(layer "In4.Cu")
		(net "M_C_CPU1_SB_DQ<16>")
	)
	(gr_poly
		(pts
			(xy 85.96757 -227.848922) (xy 85.92058 -227.696522) (xy 85.65896 -227.696522) (xy 85.61197 -227.848922)
			(xy 85.61197 -227.893372) (xy 85.96757 -227.893372)
		)
		(stroke
			(width 0)
			(type solid)
		)
		(fill yes)
		(layer "In4.Cu")
		(net "M_C_CPU1_SB_DQ<23>")
	)
	(gr_poly
		(pts
			(xy 85.96757 -226.22129) (xy 85.92058 -226.06889) (xy 85.65896 -226.06889) (xy 85.61197 -226.22129)
			(xy 85.61197 -226.26574) (xy 85.96757 -226.26574)
		)
		(stroke
			(width 0)
			(type solid)
		)
		(fill yes)
		(layer "In4.Cu")
		(net "M_B_CPU1_SB_DQ<26>")
	)
	(gr_poly
		(pts
			(xy 85.96757 -224.593658) (xy 85.92058 -224.441258) (xy 85.65896 -224.441258) (xy 85.61197 -224.593658)
			(xy 85.61197 -224.637854) (xy 85.96757 -224.637854)
		)
		(stroke
			(width 0)
			(type solid)
		)
		(fill yes)
		(layer "In4.Cu")
		(net "M_B_CPU1_SB_DQS_DP<8>")
	)
	(gr_poly
		(pts
			(xy 85.972904 -282.786074) (xy 85.93455 -282.763976) (xy 85.779102 -282.728416) (xy 85.648292 -282.954984)
			(xy 85.75675 -283.071824) (xy 85.795104 -283.093922)
		)
		(stroke
			(width 0)
			(type solid)
		)
		(fill yes)
		(layer "In4.Cu")
		(net "M_C_CPU1_SA_DQS_DP<5>")
	)
	(gr_poly
		(pts
			(xy 85.972904 -274.647152) (xy 85.93455 -274.625054) (xy 85.779102 -274.589494) (xy 85.648292 -274.816062)
			(xy 85.75675 -274.932902) (xy 85.795104 -274.955)
		)
		(stroke
			(width 0)
			(type solid)
		)
		(fill yes)
		(layer "In4.Cu")
		(net "M_B_CPU1_SA_DQS_DN<1>")
	)
	(gr_poly
		(pts
			(xy 85.973158 -273.019774) (xy 85.934804 -272.997676) (xy 85.779356 -272.962116) (xy 85.648546 -273.188684)
			(xy 85.757004 -273.305524) (xy 85.795358 -273.327622)
		)
		(stroke
			(width 0)
			(type solid)
		)
		(fill yes)
		(layer "In4.Cu")
		(net "M_B_CPU1_SA_DQS_DP<6>")
	)
	(gr_poly
		(pts
			(xy 85.973666 -247.382538) (xy 85.926676 -247.230138) (xy 85.665056 -247.230138) (xy 85.618066 -247.382538)
			(xy 85.618066 -247.426988) (xy 85.973666 -247.426988)
		)
		(stroke
			(width 0)
			(type solid)
		)
		(fill yes)
		(layer "In4.Cu")
		(net "M_C_CPU1_SB_CA<5>")
	)
	(gr_poly
		(pts
			(xy 85.973666 -246.974106) (xy 85.973666 -246.929656) (xy 85.618066 -246.929656) (xy 85.618066 -246.974106)
			(xy 85.665056 -247.126506) (xy 85.926676 -247.126506)
		)
		(stroke
			(width 0)
			(type solid)
		)
		(fill yes)
		(layer "In4.Cu")
		(net "M_C_CPU1_SB_CA<6>")
	)
	(gr_poly
		(pts
			(xy 85.973666 -240.871502) (xy 85.926676 -240.719102) (xy 85.665056 -240.719102) (xy 85.618066 -240.871502)
			(xy 85.618066 -240.915952) (xy 85.973666 -240.915952)
		)
		(stroke
			(width 0)
			(type solid)
		)
		(fill yes)
		(layer "In4.Cu")
		(net "M_C_CPU1_SB_DQS_DN<9>")
	)
	(gr_poly
		(pts
			(xy 85.973666 -235.988098) (xy 85.926676 -235.835698) (xy 85.665056 -235.835698) (xy 85.618066 -235.988098)
			(xy 85.618066 -236.032548) (xy 85.973666 -236.032548)
		)
		(stroke
			(width 0)
			(type solid)
		)
		(fill yes)
		(layer "In4.Cu")
		(net "M_B_CPU1_SB_DQ<3>")
	)
	(gr_poly
		(pts
			(xy 85.973666 -233.952034) (xy 85.973666 -233.907584) (xy 85.618066 -233.907584) (xy 85.618066 -233.952034)
			(xy 85.665056 -234.104434) (xy 85.926676 -234.104434)
		)
		(stroke
			(width 0)
			(type solid)
		)
		(fill yes)
		(layer "In4.Cu")
		(net "M_B_CPU1_SB_DQ<4>")
	)
	(gr_poly
		(pts
			(xy 85.973666 -231.104694) (xy 85.926676 -230.952294) (xy 85.665056 -230.952294) (xy 85.618066 -231.104694)
			(xy 85.618066 -231.149144) (xy 85.973666 -231.149144)
		)
		(stroke
			(width 0)
			(type solid)
		)
		(fill yes)
		(layer "In4.Cu")
		(net "M_C_CPU1_SB_DQ<19>")
	)
	(gr_poly
		(pts
			(xy 85.973666 -229.06863) (xy 85.973666 -229.02418) (xy 85.618066 -229.02418) (xy 85.618066 -229.06863)
			(xy 85.665056 -229.22103) (xy 85.926676 -229.22103)
		)
		(stroke
			(width 0)
			(type solid)
		)
		(fill yes)
		(layer "In4.Cu")
		(net "M_C_CPU1_SB_DQ<20>")
	)
	(gr_poly
		(pts
			(xy 85.977476 -271.384522) (xy 85.939122 -271.362424) (xy 85.783674 -271.326864) (xy 85.652864 -271.553432)
			(xy 85.761322 -271.670272) (xy 85.799676 -271.69237)
		)
		(stroke
			(width 0)
			(type solid)
		)
		(fill yes)
		(layer "In4.Cu")
		(net "M_B_CPU1_SA_DQ<14>")
	)
	(gr_poly
		(pts
			(xy 85.978492 -276.265386) (xy 85.940138 -276.243288) (xy 85.78469 -276.207728) (xy 85.65388 -276.434296)
			(xy 85.762338 -276.551136) (xy 85.800692 -276.573234)
		)
		(stroke
			(width 0)
			(type solid)
		)
		(fill yes)
		(layer "In4.Cu")
		(net "M_B_CPU1_SA_DQ<11>")
	)
	(gr_poly
		(pts
			(xy 85.982048 -240.46307) (xy 85.982048 -240.418874) (xy 85.626448 -240.418874) (xy 85.626448 -240.46307)
			(xy 85.673438 -240.61547) (xy 85.935058 -240.61547)
		)
		(stroke
			(width 0)
			(type solid)
		)
		(fill yes)
		(layer "In4.Cu")
		(net "M_C_CPU1_SB_DQS_DN<4>")
	)
	(gr_poly
		(pts
			(xy 85.982048 -235.579666) (xy 85.982048 -235.53547) (xy 85.626448 -235.53547) (xy 85.626448 -235.579666)
			(xy 85.673438 -235.732066) (xy 85.935058 -235.732066)
		)
		(stroke
			(width 0)
			(type solid)
		)
		(fill yes)
		(layer "In4.Cu")
		(net "M_B_CPU1_SB_DQS_DP<0>")
	)
	(gr_poly
		(pts
			(xy 85.982048 -234.360466) (xy 85.935058 -234.208066) (xy 85.673438 -234.208066) (xy 85.626448 -234.360466)
			(xy 85.626448 -234.404662) (xy 85.982048 -234.404662)
		)
		(stroke
			(width 0)
			(type solid)
		)
		(fill yes)
		(layer "In4.Cu")
		(net "M_B_CPU1_SB_DQS_DP<5>")
	)
	(gr_poly
		(pts
			(xy 85.982048 -230.696262) (xy 85.982048 -230.652066) (xy 85.626448 -230.652066) (xy 85.626448 -230.696262)
			(xy 85.673438 -230.848662) (xy 85.935058 -230.848662)
		)
		(stroke
			(width 0)
			(type solid)
		)
		(fill yes)
		(layer "In4.Cu")
		(net "M_C_CPU1_SB_DQS_DP<2>")
	)
	(gr_poly
		(pts
			(xy 85.982048 -229.477062) (xy 85.935058 -229.324662) (xy 85.673438 -229.324662) (xy 85.626448 -229.477062)
			(xy 85.626448 -229.521258) (xy 85.982048 -229.521258)
		)
		(stroke
			(width 0)
			(type solid)
		)
		(fill yes)
		(layer "In4.Cu")
		(net "M_C_CPU1_SB_DQS_DP<7>")
	)
	(gr_poly
		(pts
			(xy 86.048342 -244.194584) (xy 85.939884 -244.077744) (xy 85.90153 -244.055646) (xy 85.72373 -244.363494)
			(xy 85.762084 -244.385592) (xy 85.917532 -244.421152)
		)
		(stroke
			(width 0)
			(type solid)
		)
		(fill yes)
		(layer "In4.Cu")
		(net "M_C_CPU1_SB_CS_N<3>")
	)
	(gr_poly
		(pts
			(xy 86.048596 -245.82247) (xy 85.940138 -245.70563) (xy 85.901784 -245.683532) (xy 85.723984 -245.99138)
			(xy 85.762338 -246.013478) (xy 85.917786 -246.049038)
		)
		(stroke
			(width 0)
			(type solid)
		)
		(fill yes)
		(layer "In4.Cu")
		(net "M_C_CPU1_SB_CS_N<2>")
	)
	(gr_poly
		(pts
			(xy 86.052914 -239.304068) (xy 85.944456 -239.187228) (xy 85.906102 -239.16513) (xy 85.728302 -239.472978)
			(xy 85.766656 -239.495076) (xy 85.922104 -239.530636)
		)
		(stroke
			(width 0)
			(type solid)
		)
		(fill yes)
		(layer "In4.Cu")
		(net "M_C_CPU1_SB_CB<0>")
	)
	(gr_poly
		(pts
			(xy 86.083394 -285.051754) (xy 86.036404 -284.899354) (xy 85.774784 -284.899354) (xy 85.727794 -285.051754)
			(xy 85.727794 -285.096204) (xy 86.083394 -285.096204)
		)
		(stroke
			(width 0)
			(type solid)
		)
		(fill yes)
		(layer "In4.Cu")
		(net "M_C_CPU1_SA_DQS_DN<0>")
	)
	(gr_poly
		(pts
			(xy 86.083394 -270.40205) (xy 86.036404 -270.24965) (xy 85.774784 -270.24965) (xy 85.727794 -270.40205)
			(xy 85.727794 -270.446246) (xy 86.083394 -270.446246)
		)
		(stroke
			(width 0)
			(type solid)
		)
		(fill yes)
		(layer "In4.Cu")
		(net "M_B_CPU1_SA_DQ<15>")
	)
	(gr_poly
		(pts
			(xy 86.083394 -268.77391) (xy 86.036404 -268.62151) (xy 85.774784 -268.62151) (xy 85.727794 -268.77391)
			(xy 85.727794 -268.81836) (xy 86.083394 -268.81836)
		)
		(stroke
			(width 0)
			(type solid)
		)
		(fill yes)
		(layer "In4.Cu")
		(net "M_C_CPU1_SA_DQ<19>")
	)
	(gr_poly
		(pts
			(xy 86.083394 -268.365478) (xy 86.083394 -268.321028) (xy 85.727794 -268.321028) (xy 85.727794 -268.365478)
			(xy 85.774784 -268.517878) (xy 86.036404 -268.517878)
		)
		(stroke
			(width 0)
			(type solid)
		)
		(fill yes)
		(layer "In4.Cu")
		(net "M_C_CPU1_SA_DQS_DP<2>")
	)
	(gr_poly
		(pts
			(xy 86.083394 -267.146278) (xy 86.036404 -266.993878) (xy 85.774784 -266.993878) (xy 85.727794 -267.146278)
			(xy 85.727794 -267.190474) (xy 86.083394 -267.190474)
		)
		(stroke
			(width 0)
			(type solid)
		)
		(fill yes)
		(layer "In4.Cu")
		(net "M_C_CPU1_SA_DQS_DP<7>")
	)
	(gr_poly
		(pts
			(xy 86.083394 -266.737846) (xy 86.083394 -266.693396) (xy 85.727794 -266.693396) (xy 85.727794 -266.737846)
			(xy 85.774784 -266.890246) (xy 86.036404 -266.890246)
		)
		(stroke
			(width 0)
			(type solid)
		)
		(fill yes)
		(layer "In4.Cu")
		(net "M_C_CPU1_SA_DQ<20>")
	)
	(gr_poly
		(pts
			(xy 86.083394 -265.518646) (xy 86.036404 -265.366246) (xy 85.774784 -265.366246) (xy 85.727794 -265.518646)
			(xy 85.727794 -265.562842) (xy 86.083394 -265.562842)
		)
		(stroke
			(width 0)
			(type solid)
		)
		(fill yes)
		(layer "In4.Cu")
		(net "M_C_CPU1_SA_DQ<23>")
	)
	(gr_poly
		(pts
			(xy 86.083394 -265.109706) (xy 86.083394 -265.06551) (xy 85.727794 -265.06551) (xy 85.727794 -265.109706)
			(xy 85.774784 -265.262106) (xy 86.036404 -265.262106)
		)
		(stroke
			(width 0)
			(type solid)
		)
		(fill yes)
		(layer "In4.Cu")
		(net "M_B_CPU1_SA_DQ<26>")
	)
	(gr_poly
		(pts
			(xy 86.083394 -263.891014) (xy 86.036404 -263.738614) (xy 85.774784 -263.738614) (xy 85.727794 -263.891014)
			(xy 85.727794 -263.93521) (xy 86.083394 -263.93521)
		)
		(stroke
			(width 0)
			(type solid)
		)
		(fill yes)
		(layer "In4.Cu")
		(net "M_B_CPU1_SA_DQ<27>")
	)
	(gr_poly
		(pts
			(xy 86.083394 -263.482074) (xy 86.083394 -263.437878) (xy 85.727794 -263.437878) (xy 85.727794 -263.482074)
			(xy 85.774784 -263.634474) (xy 86.036404 -263.634474)
		)
		(stroke
			(width 0)
			(type solid)
		)
		(fill yes)
		(layer "In4.Cu")
		(net "M_B_CPU1_SA_DQS_DP<3>")
	)
	(gr_poly
		(pts
			(xy 86.083394 -262.262874) (xy 86.036404 -262.110474) (xy 85.774784 -262.110474) (xy 85.727794 -262.262874)
			(xy 85.727794 -262.307324) (xy 86.083394 -262.307324)
		)
		(stroke
			(width 0)
			(type solid)
		)
		(fill yes)
		(layer "In4.Cu")
		(net "M_B_CPU1_SA_DQS_DP<8>")
	)
	(gr_poly
		(pts
			(xy 86.083394 -261.854442) (xy 86.083394 -261.809992) (xy 85.727794 -261.809992) (xy 85.727794 -261.854442)
			(xy 85.774784 -262.006842) (xy 86.036404 -262.006842)
		)
		(stroke
			(width 0)
			(type solid)
		)
		(fill yes)
		(layer "In4.Cu")
		(net "M_B_CPU1_SA_DQ<28>")
	)
	(gr_poly
		(pts
			(xy 86.083394 -260.635242) (xy 86.036404 -260.482842) (xy 85.774784 -260.482842) (xy 85.727794 -260.635242)
			(xy 85.727794 -260.679438) (xy 86.083394 -260.679438)
		)
		(stroke
			(width 0)
			(type solid)
		)
		(fill yes)
		(layer "In4.Cu")
		(net "M_B_CPU1_SA_DQ<31>")
	)
	(gr_poly
		(pts
			(xy 86.083394 -258.59867) (xy 86.083394 -258.554474) (xy 85.727794 -258.554474) (xy 85.727794 -258.59867)
			(xy 85.774784 -258.75107) (xy 86.036404 -258.75107)
		)
		(stroke
			(width 0)
			(type solid)
		)
		(fill yes)
		(layer "In4.Cu")
		(net "M_C_CPU1_SA_CS_N<0>")
	)
	(gr_poly
		(pts
			(xy 86.083394 -257.37947) (xy 86.036404 -257.22707) (xy 85.774784 -257.22707) (xy 85.727794 -257.37947)
			(xy 85.727794 -257.42392) (xy 86.083394 -257.42392)
		)
		(stroke
			(width 0)
			(type solid)
		)
		(fill yes)
		(layer "In4.Cu")
		(net "M_C_CPU1_SA_CS_N<3>")
	)
	(gr_poly
		(pts
			(xy 86.083394 -256.971038) (xy 86.083394 -256.926588) (xy 85.727794 -256.926588) (xy 85.727794 -256.971038)
			(xy 85.774784 -257.123438) (xy 86.036404 -257.123438)
		)
		(stroke
			(width 0)
			(type solid)
		)
		(fill yes)
		(layer "In4.Cu")
		(net "M_C_CPU1_SA_CA<0>")
	)
	(gr_poly
		(pts
			(xy 86.083394 -255.751838) (xy 86.036404 -255.599438) (xy 85.774784 -255.599438) (xy 85.727794 -255.751838)
			(xy 85.727794 -255.796288) (xy 86.083394 -255.796288)
		)
		(stroke
			(width 0)
			(type solid)
		)
		(fill yes)
		(layer "In4.Cu")
		(net "M_C_CPU1_SA_CA<3>")
	)
	(gr_poly
		(pts
			(xy 86.156292 -272.101056) (xy 86.047834 -271.984216) (xy 86.00948 -271.962118) (xy 85.83168 -272.269966)
			(xy 85.870034 -272.292064) (xy 86.025482 -272.327624)
		)
		(stroke
			(width 0)
			(type solid)
		)
		(fill yes)
		(layer "In4.Cu")
		(net "M_B_CPU1_SA_DQ<12>")
	)
	(gr_poly
		(pts
			(xy 86.157308 -276.982428) (xy 86.04885 -276.865588) (xy 86.010496 -276.84349) (xy 85.832696 -277.151338)
			(xy 85.87105 -277.173436) (xy 86.026498 -277.208996)
		)
		(stroke
			(width 0)
			(type solid)
		)
		(fill yes)
		(layer "In4.Cu")
		(net "M_B_CPU1_SA_DQ<9>")
	)
	(gr_poly
		(pts
			(xy 86.162896 -273.717766) (xy 86.054438 -273.600926) (xy 86.016084 -273.578828) (xy 85.838284 -273.886676)
			(xy 85.876638 -273.908774) (xy 86.032086 -273.944334)
		)
		(stroke
			(width 0)
			(type solid)
		)
		(fill yes)
		(layer "In4.Cu")
		(net "M_B_CPU1_SA_DQS_DN<6>")
	)
	(gr_poly
		(pts
			(xy 86.333076 -239.419638) (xy 86.294722 -239.39754) (xy 86.139274 -239.36198) (xy 86.008464 -239.588548)
			(xy 86.116922 -239.705388) (xy 86.155276 -239.727486)
		)
		(stroke
			(width 0)
			(type solid)
		)
		(fill yes)
		(layer "In4.Cu")
		(net "M_C_CPU1_SB_DQS_DP<4>")
	)
	(gr_poly
		(pts
			(xy 86.337394 -244.29593) (xy 86.29904 -244.273832) (xy 86.143592 -244.238272) (xy 86.012782 -244.46484)
			(xy 86.12124 -244.58168) (xy 86.159594 -244.603778)
		)
		(stroke
			(width 0)
			(type solid)
		)
		(fill yes)
		(layer "In4.Cu")
		(net "M_C_CPU1_SB_CS_N<0>")
	)
	(gr_poly
		(pts
			(xy 86.337648 -245.923816) (xy 86.299294 -245.901718) (xy 86.143846 -245.866158) (xy 86.013036 -246.092726)
			(xy 86.121494 -246.209566) (xy 86.159848 -246.231664)
		)
		(stroke
			(width 0)
			(type solid)
		)
		(fill yes)
		(layer "In4.Cu")
		(net "M_C_CPU1_SB_PAR")
	)
	(gr_poly
		(pts
			(xy 86.409022 -223.418654) (xy 86.51748 -223.301814) (xy 86.38667 -223.075246) (xy 86.231222 -223.110806)
			(xy 86.192868 -223.132904) (xy 86.370668 -223.440752)
		)
		(stroke
			(width 0)
			(type solid)
		)
		(fill yes)
		(layer "In4.Cu")
		(net "M_B_CPU1_SB_DQ<29>")
	)
	(gr_poly
		(pts
			(xy 86.43493 -235.174282) (xy 86.38794 -235.021882) (xy 86.12632 -235.021882) (xy 86.07933 -235.174282)
			(xy 86.07933 -235.218478) (xy 86.43493 -235.218478)
		)
		(stroke
			(width 0)
			(type solid)
		)
		(fill yes)
		(layer "In4.Cu")
		(net "M_B_CPU1_SB_DQS_DN<0>")
	)
	(gr_poly
		(pts
			(xy 86.43493 -234.76585) (xy 86.43493 -234.721654) (xy 86.07933 -234.721654) (xy 86.07933 -234.76585)
			(xy 86.12632 -234.91825) (xy 86.38794 -234.91825)
		)
		(stroke
			(width 0)
			(type solid)
		)
		(fill yes)
		(layer "In4.Cu")
		(net "M_B_CPU1_SB_DQS_DN<5>")
	)
	(gr_poly
		(pts
			(xy 86.43493 -230.290878) (xy 86.38794 -230.138478) (xy 86.12632 -230.138478) (xy 86.07933 -230.290878)
			(xy 86.07933 -230.335074) (xy 86.43493 -230.335074)
		)
		(stroke
			(width 0)
			(type solid)
		)
		(fill yes)
		(layer "In4.Cu")
		(net "M_C_CPU1_SB_DQS_DN<2>")
	)
	(gr_poly
		(pts
			(xy 86.43493 -229.882446) (xy 86.43493 -229.83825) (xy 86.07933 -229.83825) (xy 86.07933 -229.882446)
			(xy 86.12632 -230.034846) (xy 86.38794 -230.034846)
		)
		(stroke
			(width 0)
			(type solid)
		)
		(fill yes)
		(layer "In4.Cu")
		(net "M_C_CPU1_SB_DQS_DN<7>")
	)
	(gr_poly
		(pts
			(xy 86.443058 -273.833336) (xy 86.404704 -273.811238) (xy 86.249256 -273.775678) (xy 86.118446 -274.002246)
			(xy 86.226904 -274.119086) (xy 86.265258 -274.141184)
		)
		(stroke
			(width 0)
			(type solid)
		)
		(fill yes)
		(layer "In4.Cu")
		(net "M_B_CPU1_SA_DQS_DN<1>")
	)
	(gr_poly
		(pts
			(xy 86.443566 -247.787922) (xy 86.443566 -247.743472) (xy 86.087966 -247.743472) (xy 86.087966 -247.787922)
			(xy 86.134956 -247.940322) (xy 86.396576 -247.940322)
		)
		(stroke
			(width 0)
			(type solid)
		)
		(fill yes)
		(layer "In4.Cu")
		(net "M_C_CPU1_SB_CA<4>")
	)
	(gr_poly
		(pts
			(xy 86.443566 -242.904518) (xy 86.443566 -242.860322) (xy 86.087966 -242.860322) (xy 86.087966 -242.904518)
			(xy 86.134956 -243.056918) (xy 86.396576 -243.056918)
		)
		(stroke
			(width 0)
			(type solid)
		)
		(fill yes)
		(layer "In4.Cu")
		(net "M_C_CPU1_SB_CB<4>")
	)
	(gr_poly
		(pts
			(xy 86.443566 -241.685318) (xy 86.396576 -241.532918) (xy 86.134956 -241.532918) (xy 86.087966 -241.685318)
			(xy 86.087966 -241.729768) (xy 86.443566 -241.729768)
		)
		(stroke
			(width 0)
			(type solid)
		)
		(fill yes)
		(layer "In4.Cu")
		(net "M_C_CPU1_SB_CB<7>")
	)
	(gr_poly
		(pts
			(xy 86.443566 -241.276886) (xy 86.443566 -241.232436) (xy 86.087966 -241.232436) (xy 86.087966 -241.276886)
			(xy 86.134956 -241.429286) (xy 86.396576 -241.429286)
		)
		(stroke
			(width 0)
			(type solid)
		)
		(fill yes)
		(layer "In4.Cu")
		(net "M_C_CPU1_SB_DQS_DP<9>")
	)
	(gr_poly
		(pts
			(xy 86.443566 -238.430054) (xy 86.396576 -238.277654) (xy 86.134956 -238.277654) (xy 86.087966 -238.430054)
			(xy 86.087966 -238.47425) (xy 86.443566 -238.47425)
		)
		(stroke
			(width 0)
			(type solid)
		)
		(fill yes)
		(layer "In4.Cu")
		(net "M_C_CPU1_SB_CB<2>")
	)
	(gr_poly
		(pts
			(xy 86.443566 -238.021114) (xy 86.443566 -237.976918) (xy 86.087966 -237.976918) (xy 86.087966 -238.021114)
			(xy 86.134956 -238.173514) (xy 86.396576 -238.173514)
		)
		(stroke
			(width 0)
			(type solid)
		)
		(fill yes)
		(layer "In4.Cu")
		(net "M_C_CPU1_SB_CB<1>")
	)
	(gr_poly
		(pts
			(xy 86.443566 -236.802422) (xy 86.396576 -236.650022) (xy 86.134956 -236.650022) (xy 86.087966 -236.802422)
			(xy 86.087966 -236.846618) (xy 86.443566 -236.846618)
		)
		(stroke
			(width 0)
			(type solid)
		)
		(fill yes)
		(layer "In4.Cu")
		(net "M_B_CPU1_SB_DQ<0>")
	)
	(gr_poly
		(pts
			(xy 86.443566 -236.393482) (xy 86.443566 -236.349286) (xy 86.087966 -236.349286) (xy 86.087966 -236.393482)
			(xy 86.134956 -236.545882) (xy 86.396576 -236.545882)
		)
		(stroke
			(width 0)
			(type solid)
		)
		(fill yes)
		(layer "In4.Cu")
		(net "M_B_CPU1_SB_DQ<1>")
	)
	(gr_poly
		(pts
			(xy 86.443566 -233.54665) (xy 86.396576 -233.39425) (xy 86.134956 -233.39425) (xy 86.087966 -233.54665)
			(xy 86.087966 -233.590846) (xy 86.443566 -233.590846)
		)
		(stroke
			(width 0)
			(type solid)
		)
		(fill yes)
		(layer "In4.Cu")
		(net "M_B_CPU1_SB_DQ<6>")
	)
	(gr_poly
		(pts
			(xy 86.443566 -233.13771) (xy 86.443566 -233.093514) (xy 86.087966 -233.093514) (xy 86.087966 -233.13771)
			(xy 86.134956 -233.29011) (xy 86.396576 -233.29011)
		)
		(stroke
			(width 0)
			(type solid)
		)
		(fill yes)
		(layer "In4.Cu")
		(net "M_B_CPU1_SB_DQ<5>")
	)
	(gr_poly
		(pts
			(xy 86.443566 -231.919018) (xy 86.396576 -231.766618) (xy 86.134956 -231.766618) (xy 86.087966 -231.919018)
			(xy 86.087966 -231.963214) (xy 86.443566 -231.963214)
		)
		(stroke
			(width 0)
			(type solid)
		)
		(fill yes)
		(layer "In4.Cu")
		(net "M_C_CPU1_SB_DQ<18>")
	)
	(gr_poly
		(pts
			(xy 86.443566 -231.510078) (xy 86.443566 -231.465882) (xy 86.087966 -231.465882) (xy 86.087966 -231.510078)
			(xy 86.134956 -231.662478) (xy 86.396576 -231.662478)
		)
		(stroke
			(width 0)
			(type solid)
		)
		(fill yes)
		(layer "In4.Cu")
		(net "M_C_CPU1_SB_DQ<17>")
	)
	(gr_poly
		(pts
			(xy 86.443566 -228.663246) (xy 86.396576 -228.510846) (xy 86.134956 -228.510846) (xy 86.087966 -228.663246)
			(xy 86.087966 -228.707696) (xy 86.443566 -228.707696)
		)
		(stroke
			(width 0)
			(type solid)
		)
		(fill yes)
		(layer "In4.Cu")
		(net "M_C_CPU1_SB_DQ<22>")
	)
	(gr_poly
		(pts
			(xy 86.443566 -228.254814) (xy 86.443566 -228.210364) (xy 86.087966 -228.210364) (xy 86.087966 -228.254814)
			(xy 86.134956 -228.407214) (xy 86.396576 -228.407214)
		)
		(stroke
			(width 0)
			(type solid)
		)
		(fill yes)
		(layer "In4.Cu")
		(net "M_C_CPU1_SB_DQ<21>")
	)
	(gr_poly
		(pts
			(xy 86.443566 -224.999042) (xy 86.443566 -224.954592) (xy 86.087966 -224.954592) (xy 86.087966 -224.999042)
			(xy 86.134956 -225.151442) (xy 86.396576 -225.151442)
		)
		(stroke
			(width 0)
			(type solid)
		)
		(fill yes)
		(layer "In4.Cu")
		(net "M_B_CPU1_SB_DQS_DN<8>")
	)
	(gr_poly
		(pts
			(xy 86.448138 -277.079964) (xy 86.409784 -277.057866) (xy 86.254336 -277.022306) (xy 86.123526 -277.248874)
			(xy 86.231984 -277.365714) (xy 86.270338 -277.387812)
		)
		(stroke
			(width 0)
			(type solid)
		)
		(fill yes)
		(layer "In4.Cu")
		(net "M_B_CPU1_SA_DQ<10>")
	)
	(gr_poly
		(pts
			(xy 86.448392 -272.19656) (xy 86.410038 -272.174462) (xy 86.25459 -272.138902) (xy 86.12378 -272.36547)
			(xy 86.232238 -272.48231) (xy 86.270592 -272.504408)
		)
		(stroke
			(width 0)
			(type solid)
		)
		(fill yes)
		(layer "In4.Cu")
		(net "M_B_CPU1_SA_DQS_DP<6>")
	)
	(gr_poly
		(pts
			(xy 86.449154 -275.450046) (xy 86.4108 -275.427948) (xy 86.255352 -275.392388) (xy 86.124542 -275.618956)
			(xy 86.233 -275.735796) (xy 86.271354 -275.757894)
		)
		(stroke
			(width 0)
			(type solid)
		)
		(fill yes)
		(layer "In4.Cu")
		(net "M_B_CPU1_SA_DQ<11>")
	)
	(gr_poly
		(pts
			(xy 86.449408 -280.33345) (xy 86.411054 -280.311352) (xy 86.255606 -280.275792) (xy 86.124796 -280.50236)
			(xy 86.233254 -280.6192) (xy 86.271608 -280.641298)
		)
		(stroke
			(width 0)
			(type solid)
		)
		(fill yes)
		(layer "In4.Cu")
		(net "M_C_CPU1_SA_DQ<7>")
	)
	(gr_poly
		(pts
			(xy 86.451948 -243.31295) (xy 86.404958 -243.16055) (xy 86.143338 -243.16055) (xy 86.096348 -243.31295)
			(xy 86.096348 -243.3574) (xy 86.451948 -243.3574)
		)
		(stroke
			(width 0)
			(type solid)
		)
		(fill yes)
		(layer "In4.Cu")
		(net "M_C_CPU1_SB_CS_N<1>")
	)
	(gr_poly
		(pts
			(xy 86.515448 -245.012464) (xy 86.40699 -244.895624) (xy 86.368636 -244.873526) (xy 86.190836 -245.181374)
			(xy 86.22919 -245.203472) (xy 86.384638 -245.239032)
		)
		(stroke
			(width 0)
			(type solid)
		)
		(fill yes)
		(layer "In4.Cu")
		(net "M_C_CPU1_SB_CS_N<2>")
	)
	(gr_poly
		(pts
			(xy 86.515448 -240.13033) (xy 86.40699 -240.01349) (xy 86.368636 -239.991392) (xy 86.190836 -240.29924)
			(xy 86.22919 -240.321338) (xy 86.384638 -240.356898)
		)
		(stroke
			(width 0)
			(type solid)
		)
		(fill yes)
		(layer "In4.Cu")
		(net "M_C_CPU1_SB_DQS_DN<4>")
	)
	(gr_poly
		(pts
			(xy 86.518496 -246.636286) (xy 86.410038 -246.519446) (xy 86.371684 -246.497348) (xy 86.193884 -246.805196)
			(xy 86.232238 -246.827294) (xy 86.387686 -246.862854)
		)
		(stroke
			(width 0)
			(type solid)
		)
		(fill yes)
		(layer "In4.Cu")
		(net "M_C_CPU1_SB_CA<6>")
	)
	(gr_poly
		(pts
			(xy 86.553294 -285.86557) (xy 86.506304 -285.71317) (xy 86.244684 -285.71317) (xy 86.197694 -285.86557)
			(xy 86.197694 -285.91002) (xy 86.553294 -285.91002)
		)
		(stroke
			(width 0)
			(type solid)
		)
		(fill yes)
		(layer "In4.Cu")
		(net "M_C_CPU1_SA_DQ<3>")
	)
	(gr_poly
		(pts
			(xy 86.553294 -271.215866) (xy 86.506304 -271.063466) (xy 86.244684 -271.063466) (xy 86.197694 -271.215866)
			(xy 86.197694 -271.260062) (xy 86.553294 -271.260062)
		)
		(stroke
			(width 0)
			(type solid)
		)
		(fill yes)
		(layer "In4.Cu")
		(net "M_B_CPU1_SA_DQ<14>")
	)
	(gr_poly
		(pts
			(xy 86.553294 -270.806926) (xy 86.553294 -270.76273) (xy 86.197694 -270.76273) (xy 86.197694 -270.806926)
			(xy 86.244684 -270.959326) (xy 86.506304 -270.959326)
		)
		(stroke
			(width 0)
			(type solid)
		)
		(fill yes)
		(layer "In4.Cu")
		(net "M_B_CPU1_SA_DQ<13>")
	)
	(gr_poly
		(pts
			(xy 86.553294 -269.587726) (xy 86.506304 -269.435326) (xy 86.244684 -269.435326) (xy 86.197694 -269.587726)
			(xy 86.197694 -269.632176) (xy 86.553294 -269.632176)
		)
		(stroke
			(width 0)
			(type solid)
		)
		(fill yes)
		(layer "In4.Cu")
		(net "M_C_CPU1_SA_DQ<18>")
	)
	(gr_poly
		(pts
			(xy 86.553294 -269.179294) (xy 86.553294 -269.134844) (xy 86.197694 -269.134844) (xy 86.197694 -269.179294)
			(xy 86.244684 -269.331694) (xy 86.506304 -269.331694)
		)
		(stroke
			(width 0)
			(type solid)
		)
		(fill yes)
		(layer "In4.Cu")
		(net "M_C_CPU1_SA_DQ<17>")
	)
	(gr_poly
		(pts
			(xy 86.553294 -267.960094) (xy 86.506304 -267.807694) (xy 86.244684 -267.807694) (xy 86.197694 -267.960094)
			(xy 86.197694 -268.004544) (xy 86.553294 -268.004544)
		)
		(stroke
			(width 0)
			(type solid)
		)
		(fill yes)
		(layer "In4.Cu")
		(net "M_C_CPU1_SA_DQS_DN<2>")
	)
	(gr_poly
		(pts
			(xy 86.553294 -267.551662) (xy 86.553294 -267.507212) (xy 86.197694 -267.507212) (xy 86.197694 -267.551662)
			(xy 86.244684 -267.704062) (xy 86.506304 -267.704062)
		)
		(stroke
			(width 0)
			(type solid)
		)
		(fill yes)
		(layer "In4.Cu")
		(net "M_C_CPU1_SA_DQS_DN<7>")
	)
	(gr_poly
		(pts
			(xy 86.553294 -266.332462) (xy 86.506304 -266.180062) (xy 86.244684 -266.180062) (xy 86.197694 -266.332462)
			(xy 86.197694 -266.376658) (xy 86.553294 -266.376658)
		)
		(stroke
			(width 0)
			(type solid)
		)
		(fill yes)
		(layer "In4.Cu")
		(net "M_C_CPU1_SA_DQ<22>")
	)
	(gr_poly
		(pts
			(xy 86.553294 -265.92403) (xy 86.553294 -265.87958) (xy 86.197694 -265.87958) (xy 86.197694 -265.92403)
			(xy 86.244684 -266.07643) (xy 86.506304 -266.07643)
		)
		(stroke
			(width 0)
			(type solid)
		)
		(fill yes)
		(layer "In4.Cu")
		(net "M_C_CPU1_SA_DQ<21>")
	)
	(gr_poly
		(pts
			(xy 86.553294 -264.70483) (xy 86.506304 -264.55243) (xy 86.244684 -264.55243) (xy 86.197694 -264.70483)
			(xy 86.197694 -264.749026) (xy 86.553294 -264.749026)
		)
		(stroke
			(width 0)
			(type solid)
		)
		(fill yes)
		(layer "In4.Cu")
		(net "M_B_CPU1_SA_DQ<24>")
	)
	(gr_poly
		(pts
			(xy 86.553294 -264.29589) (xy 86.553294 -264.251694) (xy 86.197694 -264.251694) (xy 86.197694 -264.29589)
			(xy 86.244684 -264.44829) (xy 86.506304 -264.44829)
		)
		(stroke
			(width 0)
			(type solid)
		)
		(fill yes)
		(layer "In4.Cu")
		(net "M_B_CPU1_SA_DQ<25>")
	)
	(gr_poly
		(pts
			(xy 86.553294 -263.07669) (xy 86.506304 -262.92429) (xy 86.244684 -262.92429) (xy 86.197694 -263.07669)
			(xy 86.197694 -263.12114) (xy 86.553294 -263.12114)
		)
		(stroke
			(width 0)
			(type solid)
		)
		(fill yes)
		(layer "In4.Cu")
		(net "M_B_CPU1_SA_DQS_DN<3>")
	)
	(gr_poly
		(pts
			(xy 86.553294 -262.668258) (xy 86.553294 -262.623808) (xy 86.197694 -262.623808) (xy 86.197694 -262.668258)
			(xy 86.244684 -262.820658) (xy 86.506304 -262.820658)
		)
		(stroke
			(width 0)
			(type solid)
		)
		(fill yes)
		(layer "In4.Cu")
		(net "M_B_CPU1_SA_DQS_DN<8>")
	)
	(gr_poly
		(pts
			(xy 86.553294 -261.449058) (xy 86.506304 -261.296658) (xy 86.244684 -261.296658) (xy 86.197694 -261.449058)
			(xy 86.197694 -261.493508) (xy 86.553294 -261.493508)
		)
		(stroke
			(width 0)
			(type solid)
		)
		(fill yes)
		(layer "In4.Cu")
		(net "M_B_CPU1_SA_DQ<30>")
	)
	(gr_poly
		(pts
			(xy 86.553294 -261.040626) (xy 86.553294 -260.996176) (xy 86.197694 -260.996176) (xy 86.197694 -261.040626)
			(xy 86.244684 -261.193026) (xy 86.506304 -261.193026)
		)
		(stroke
			(width 0)
			(type solid)
		)
		(fill yes)
		(layer "In4.Cu")
		(net "M_B_CPU1_SA_DQ<29>")
	)
	(gr_poly
		(pts
			(xy 86.553294 -258.193286) (xy 86.506304 -258.040886) (xy 86.244684 -258.040886) (xy 86.197694 -258.193286)
			(xy 86.197694 -258.237736) (xy 86.553294 -258.237736)
		)
		(stroke
			(width 0)
			(type solid)
		)
		(fill yes)
		(layer "In4.Cu")
		(net "M_C_CPU1_SA_CS_N<2>")
	)
	(gr_poly
		(pts
			(xy 86.553294 -257.784854) (xy 86.553294 -257.740404) (xy 86.197694 -257.740404) (xy 86.197694 -257.784854)
			(xy 86.244684 -257.937254) (xy 86.506304 -257.937254)
		)
		(stroke
			(width 0)
			(type solid)
		)
		(fill yes)
		(layer "In4.Cu")
		(net "M_C_CPU1_SA_CS_N<1>")
	)
	(gr_poly
		(pts
			(xy 86.553294 -256.565654) (xy 86.506304 -256.413254) (xy 86.244684 -256.413254) (xy 86.197694 -256.565654)
			(xy 86.197694 -256.610104) (xy 86.553294 -256.610104)
		)
		(stroke
			(width 0)
			(type solid)
		)
		(fill yes)
		(layer "In4.Cu")
		(net "M_C_CPU1_SA_CA<1>")
	)
	(gr_poly
		(pts
			(xy 86.553294 -256.157222) (xy 86.553294 -256.112772) (xy 86.197694 -256.112772) (xy 86.197694 -256.157222)
			(xy 86.244684 -256.309622) (xy 86.506304 -256.309622)
		)
		(stroke
			(width 0)
			(type solid)
		)
		(fill yes)
		(layer "In4.Cu")
		(net "M_C_CPU1_SA_CA<2>")
	)
	(gr_poly
		(pts
			(xy 86.553294 -254.938022) (xy 86.506304 -254.785622) (xy 86.244684 -254.785622) (xy 86.197694 -254.938022)
			(xy 86.197694 -254.982218) (xy 86.553294 -254.982218)
		)
		(stroke
			(width 0)
			(type solid)
		)
		(fill yes)
		(layer "In4.Cu")
		(net "M_C_CPU1_SA_CA<5>")
	)
	(gr_poly
		(pts
			(xy 86.553294 -254.529082) (xy 86.553294 -254.484886) (xy 86.197694 -254.484886) (xy 86.197694 -254.529082)
			(xy 86.244684 -254.681482) (xy 86.506304 -254.681482)
		)
		(stroke
			(width 0)
			(type solid)
		)
		(fill yes)
		(layer "In4.Cu")
		(net "M_C_CPU1_SA_CA<6>")
	)
	(gr_poly
		(pts
			(xy 86.553548 -285.456884) (xy 86.553548 -285.412434) (xy 86.197948 -285.412434) (xy 86.197948 -285.456884)
			(xy 86.244938 -285.609284) (xy 86.506558 -285.609284)
		)
		(stroke
			(width 0)
			(type solid)
		)
		(fill yes)
		(layer "In4.Cu")
		(net "M_C_CPU1_SA_DQS_DP<0>")
	)
	(gr_poly
		(pts
			(xy 86.55939 -282.610052) (xy 86.5124 -282.457652) (xy 86.25078 -282.457652) (xy 86.20379 -282.610052)
			(xy 86.20379 -282.654248) (xy 86.55939 -282.654248)
		)
		(stroke
			(width 0)
			(type solid)
		)
		(fill yes)
		(layer "In4.Cu")
		(net "M_C_CPU1_SA_DQS_DP<5>")
	)
	(gr_poly
		(pts
			(xy 86.55939 -282.201874) (xy 86.55939 -282.157424) (xy 86.20379 -282.157424) (xy 86.20379 -282.201874)
			(xy 86.25078 -282.354274) (xy 86.5124 -282.354274)
		)
		(stroke
			(width 0)
			(type solid)
		)
		(fill yes)
		(layer "In4.Cu")
		(net "M_C_CPU1_SA_DQ<4>")
	)
	(gr_poly
		(pts
			(xy 86.626954 -276.16912) (xy 86.518496 -276.05228) (xy 86.480142 -276.030182) (xy 86.302342 -276.33803)
			(xy 86.340696 -276.360128) (xy 86.496144 -276.395688)
		)
		(stroke
			(width 0)
			(type solid)
		)
		(fill yes)
		(layer "In4.Cu")
		(net "M_B_CPU1_SA_DQ<9>")
	)
	(gr_poly
		(pts
			(xy 86.632542 -281.042872) (xy 86.524084 -280.926032) (xy 86.48573 -280.903934) (xy 86.30793 -281.211782)
			(xy 86.346284 -281.23388) (xy 86.501732 -281.26944)
		)
		(stroke
			(width 0)
			(type solid)
		)
		(fill yes)
		(layer "In4.Cu")
		(net "M_C_CPU1_SA_DQ<5>")
	)
	(gr_poly
		(pts
			(xy 86.632542 -274.531582) (xy 86.524084 -274.414742) (xy 86.48573 -274.392644) (xy 86.30793 -274.700492)
			(xy 86.346284 -274.72259) (xy 86.501732 -274.75815)
		)
		(stroke
			(width 0)
			(type solid)
		)
		(fill yes)
		(layer "In4.Cu")
		(net "M_B_CPU1_SA_DQS_DP<1>")
	)
	(gr_poly
		(pts
			(xy 86.632796 -272.903696) (xy 86.524338 -272.786856) (xy 86.485984 -272.764758) (xy 86.308184 -273.072606)
			(xy 86.346538 -273.094704) (xy 86.501986 -273.130264)
		)
		(stroke
			(width 0)
			(type solid)
		)
		(fill yes)
		(layer "In4.Cu")
		(net "M_B_CPU1_SA_DQS_DN<6>")
	)
	(gr_poly
		(pts
			(xy 86.807548 -246.737632) (xy 86.769194 -246.715534) (xy 86.613746 -246.679974) (xy 86.482936 -246.906542)
			(xy 86.591394 -247.023382) (xy 86.629748 -247.04548)
		)
		(stroke
			(width 0)
			(type solid)
		)
		(fill yes)
		(layer "In4.Cu")
		(net "M_C_CPU1_SB_CA<5>")
	)
	(gr_poly
		(pts
			(xy 86.810342 -245.104666) (xy 86.771988 -245.082568) (xy 86.61654 -245.047008) (xy 86.48573 -245.273576)
			(xy 86.594188 -245.390416) (xy 86.632542 -245.412514)
		)
		(stroke
			(width 0)
			(type solid)
		)
		(fill yes)
		(layer "In4.Cu")
		(net "M_C_CPU1_SB_PAR")
	)
	(gr_poly
		(pts
			(xy 86.810342 -240.221262) (xy 86.771988 -240.199164) (xy 86.61654 -240.163604) (xy 86.48573 -240.390172)
			(xy 86.594188 -240.507012) (xy 86.632542 -240.52911)
		)
		(stroke
			(width 0)
			(type solid)
		)
		(fill yes)
		(layer "In4.Cu")
		(net "M_C_CPU1_SB_DQS_DN<9>")
	)
	(gr_poly
		(pts
			(xy 86.90483 -243.718842) (xy 86.90483 -243.674392) (xy 86.54923 -243.674392) (xy 86.54923 -243.718842)
			(xy 86.59622 -243.871242) (xy 86.85784 -243.871242)
		)
		(stroke
			(width 0)
			(type solid)
		)
		(fill yes)
		(layer "In4.Cu")
		(net "M_C_CPU1_SB_CS_N<3>")
	)
	(gr_poly
		(pts
			(xy 86.90737 -242.499134) (xy 86.86038 -242.346734) (xy 86.59876 -242.346734) (xy 86.55177 -242.499134)
			(xy 86.55177 -242.543584) (xy 86.90737 -242.543584)
		)
		(stroke
			(width 0)
			(type solid)
		)
		(fill yes)
		(layer "In4.Cu")
		(net "M_C_CPU1_SB_CB<6>")
	)
	(gr_poly
		(pts
			(xy 86.90737 -242.090702) (xy 86.90737 -242.046252) (xy 86.55177 -242.046252) (xy 86.55177 -242.090702)
			(xy 86.59876 -242.243102) (xy 86.86038 -242.243102)
		)
		(stroke
			(width 0)
			(type solid)
		)
		(fill yes)
		(layer "In4.Cu")
		(net "M_C_CPU1_SB_CB<5>")
	)
	(gr_poly
		(pts
			(xy 86.90737 -237.616238) (xy 86.86038 -237.463838) (xy 86.59876 -237.463838) (xy 86.55177 -237.616238)
			(xy 86.55177 -237.660434) (xy 86.90737 -237.660434)
		)
		(stroke
			(width 0)
			(type solid)
		)
		(fill yes)
		(layer "In4.Cu")
		(net "M_C_CPU1_SB_CB<3>")
	)
	(gr_poly
		(pts
			(xy 86.90737 -237.207298) (xy 86.90737 -237.163102) (xy 86.55177 -237.163102) (xy 86.55177 -237.207298)
			(xy 86.59876 -237.359698) (xy 86.86038 -237.359698)
		)
		(stroke
			(width 0)
			(type solid)
		)
		(fill yes)
		(layer "In4.Cu")
		(net "M_B_CPU1_SB_DQ<2>")
	)
	(gr_poly
		(pts
			(xy 86.90737 -227.84943) (xy 86.86038 -227.69703) (xy 86.59876 -227.69703) (xy 86.55177 -227.84943)
			(xy 86.55177 -227.893626) (xy 86.90737 -227.893626)
		)
		(stroke
			(width 0)
			(type solid)
		)
		(fill yes)
		(layer "In4.Cu")
		(net "M_C_CPU1_SB_DQ<23>")
	)
	(gr_poly
		(pts
			(xy 86.912704 -274.647152) (xy 86.87435 -274.625054) (xy 86.718902 -274.589494) (xy 86.588092 -274.816062)
			(xy 86.69655 -274.932902) (xy 86.734904 -274.955)
		)
		(stroke
			(width 0)
			(type solid)
		)
		(fill yes)
		(layer "In4.Cu")
		(net "M_B_CPU1_SA_DQ<11>")
	)
	(gr_poly
		(pts
			(xy 86.912958 -281.158696) (xy 86.874604 -281.136598) (xy 86.719156 -281.101038) (xy 86.588346 -281.327606)
			(xy 86.696804 -281.444446) (xy 86.735158 -281.466544)
		)
		(stroke
			(width 0)
			(type solid)
		)
		(fill yes)
		(layer "In4.Cu")
		(net "M_C_CPU1_SA_DQ<6>")
	)
	(gr_poly
		(pts
			(xy 86.912958 -279.530556) (xy 86.874604 -279.508458) (xy 86.719156 -279.472898) (xy 86.588346 -279.699466)
			(xy 86.696804 -279.816306) (xy 86.735158 -279.838404)
		)
		(stroke
			(width 0)
			(type solid)
		)
		(fill yes)
		(layer "In4.Cu")
		(net "M_C_CPU1_SA_DQ<7>")
	)
	(gr_poly
		(pts
			(xy 86.912958 -273.01952) (xy 86.874604 -272.997422) (xy 86.719156 -272.961862) (xy 86.588346 -273.18843)
			(xy 86.696804 -273.30527) (xy 86.735158 -273.327368)
		)
		(stroke
			(width 0)
			(type solid)
		)
		(fill yes)
		(layer "In4.Cu")
		(net "M_B_CPU1_SA_DQS_DN<1>")
	)
	(gr_poly
		(pts
			(xy 86.913212 -244.127274) (xy 86.866222 -243.974874) (xy 86.604602 -243.974874) (xy 86.557612 -244.127274)
			(xy 86.557612 -244.17147) (xy 86.913212 -244.17147)
		)
		(stroke
			(width 0)
			(type solid)
		)
		(fill yes)
		(layer "In4.Cu")
		(net "M_C_CPU1_SB_CS_N<0>")
	)
	(gr_poly
		(pts
			(xy 86.913466 -248.601738) (xy 86.913466 -248.557542) (xy 86.557866 -248.557542) (xy 86.557866 -248.601738)
			(xy 86.604856 -248.754138) (xy 86.866476 -248.754138)
		)
		(stroke
			(width 0)
			(type solid)
		)
		(fill yes)
		(layer "In4.Cu")
		(net "M_C_CPU1_SB_CA<2>")
	)
	(gr_poly
		(pts
			(xy 86.913466 -238.83493) (xy 86.913466 -238.790734) (xy 86.557866 -238.790734) (xy 86.557866 -238.83493)
			(xy 86.604856 -238.98733) (xy 86.866476 -238.98733)
		)
		(stroke
			(width 0)
			(type solid)
		)
		(fill yes)
		(layer "In4.Cu")
		(net "M_C_CPU1_SB_CB<0>")
	)
	(gr_poly
		(pts
			(xy 86.913466 -235.988098) (xy 86.866476 -235.835698) (xy 86.604856 -235.835698) (xy 86.557866 -235.988098)
			(xy 86.557866 -236.032548) (xy 86.913466 -236.032548)
		)
		(stroke
			(width 0)
			(type solid)
		)
		(fill yes)
		(layer "In4.Cu")
		(net "M_B_CPU1_SB_DQ<3>")
	)
	(gr_poly
		(pts
			(xy 86.913466 -233.952034) (xy 86.913466 -233.907584) (xy 86.557866 -233.907584) (xy 86.557866 -233.952034)
			(xy 86.604856 -234.104434) (xy 86.866476 -234.104434)
		)
		(stroke
			(width 0)
			(type solid)
		)
		(fill yes)
		(layer "In4.Cu")
		(net "M_B_CPU1_SB_DQ<4>")
	)
	(gr_poly
		(pts
			(xy 86.913466 -232.732834) (xy 86.866476 -232.580434) (xy 86.604856 -232.580434) (xy 86.557866 -232.732834)
			(xy 86.557866 -232.77703) (xy 86.913466 -232.77703)
		)
		(stroke
			(width 0)
			(type solid)
		)
		(fill yes)
		(layer "In4.Cu")
		(net "M_B_CPU1_SB_DQ<7>")
	)
	(gr_poly
		(pts
			(xy 86.913466 -232.323894) (xy 86.913466 -232.279698) (xy 86.557866 -232.279698) (xy 86.557866 -232.323894)
			(xy 86.604856 -232.476294) (xy 86.866476 -232.476294)
		)
		(stroke
			(width 0)
			(type solid)
		)
		(fill yes)
		(layer "In4.Cu")
		(net "M_C_CPU1_SB_DQ<16>")
	)
	(gr_poly
		(pts
			(xy 86.913466 -231.104694) (xy 86.866476 -230.952294) (xy 86.604856 -230.952294) (xy 86.557866 -231.104694)
			(xy 86.557866 -231.149144) (xy 86.913466 -231.149144)
		)
		(stroke
			(width 0)
			(type solid)
		)
		(fill yes)
		(layer "In4.Cu")
		(net "M_C_CPU1_SB_DQ<19>")
	)
	(gr_poly
		(pts
			(xy 86.913466 -229.06863) (xy 86.913466 -229.02418) (xy 86.557866 -229.02418) (xy 86.557866 -229.06863)
			(xy 86.604856 -229.22103) (xy 86.866476 -229.22103)
		)
		(stroke
			(width 0)
			(type solid)
		)
		(fill yes)
		(layer "In4.Cu")
		(net "M_C_CPU1_SB_DQ<20>")
	)
	(gr_poly
		(pts
			(xy 86.918292 -276.265386) (xy 86.879938 -276.243288) (xy 86.72449 -276.207728) (xy 86.59368 -276.434296)
			(xy 86.702138 -276.551136) (xy 86.740492 -276.573234)
		)
		(stroke
			(width 0)
			(type solid)
		)
		(fill yes)
		(layer "In4.Cu")
		(net "M_B_CPU1_SA_DQ<10>")
	)
	(gr_poly
		(pts
			(xy 86.921848 -239.243362) (xy 86.874858 -239.090962) (xy 86.613238 -239.090962) (xy 86.566248 -239.243362)
			(xy 86.566248 -239.287812) (xy 86.921848 -239.287812)
		)
		(stroke
			(width 0)
			(type solid)
		)
		(fill yes)
		(layer "In4.Cu")
		(net "M_C_CPU1_SB_DQS_DP<4>")
	)
	(gr_poly
		(pts
			(xy 86.921848 -235.579666) (xy 86.921848 -235.53547) (xy 86.566248 -235.53547) (xy 86.566248 -235.579666)
			(xy 86.613238 -235.732066) (xy 86.874858 -235.732066)
		)
		(stroke
			(width 0)
			(type solid)
		)
		(fill yes)
		(layer "In4.Cu")
		(net "M_B_CPU1_SB_DQS_DP<0>")
	)
	(gr_poly
		(pts
			(xy 86.921848 -234.360466) (xy 86.874858 -234.208066) (xy 86.613238 -234.208066) (xy 86.566248 -234.360466)
			(xy 86.566248 -234.404662) (xy 86.921848 -234.404662)
		)
		(stroke
			(width 0)
			(type solid)
		)
		(fill yes)
		(layer "In4.Cu")
		(net "M_B_CPU1_SB_DQS_DP<5>")
	)
	(gr_poly
		(pts
			(xy 86.921848 -230.696262) (xy 86.921848 -230.652066) (xy 86.566248 -230.652066) (xy 86.566248 -230.696262)
			(xy 86.613238 -230.848662) (xy 86.874858 -230.848662)
		)
		(stroke
			(width 0)
			(type solid)
		)
		(fill yes)
		(layer "In4.Cu")
		(net "M_C_CPU1_SB_DQS_DP<2>")
	)
	(gr_poly
		(pts
			(xy 86.921848 -229.477062) (xy 86.874858 -229.324662) (xy 86.613238 -229.324662) (xy 86.566248 -229.477062)
			(xy 86.566248 -229.521258) (xy 86.921848 -229.521258)
		)
		(stroke
			(width 0)
			(type solid)
		)
		(fill yes)
		(layer "In4.Cu")
		(net "M_C_CPU1_SB_DQS_DP<7>")
	)
	(gr_poly
		(pts
			(xy 86.988396 -247.450102) (xy 86.879938 -247.333262) (xy 86.841584 -247.311164) (xy 86.663784 -247.619012)
			(xy 86.702138 -247.64111) (xy 86.857586 -247.67667)
		)
		(stroke
			(width 0)
			(type solid)
		)
		(fill yes)
		(layer "In4.Cu")
		(net "M_C_CPU1_SB_CA<4>")
	)
	(gr_poly
		(pts
			(xy 86.988396 -245.82247) (xy 86.879938 -245.70563) (xy 86.841584 -245.683532) (xy 86.663784 -245.99138)
			(xy 86.702138 -246.013478) (xy 86.857586 -246.049038)
		)
		(stroke
			(width 0)
			(type solid)
		)
		(fill yes)
		(layer "In4.Cu")
		(net "M_C_CPU1_SB_CA<6>")
	)
	(gr_poly
		(pts
			(xy 86.988396 -240.939066) (xy 86.879938 -240.822226) (xy 86.841584 -240.800128) (xy 86.663784 -241.107976)
			(xy 86.702138 -241.130074) (xy 86.857586 -241.165634)
		)
		(stroke
			(width 0)
			(type solid)
		)
		(fill yes)
		(layer "In4.Cu")
		(net "M_C_CPU1_SB_DQS_DP<9>")
	)
	(gr_poly
		(pts
			(xy 87.014812 -283.01569) (xy 87.014812 -282.971494) (xy 86.659212 -282.971494) (xy 86.659212 -283.01569)
			(xy 86.706202 -283.16809) (xy 86.967822 -283.16809)
		)
		(stroke
			(width 0)
			(type solid)
		)
		(fill yes)
		(layer "In4.Cu")
		(net "M_C_CPU1_SA_DQS_DN<5>")
	)
	(gr_poly
		(pts
			(xy 87.014812 -272.029174) (xy 86.967822 -271.876774) (xy 86.706202 -271.876774) (xy 86.659212 -272.029174)
			(xy 86.659212 -272.073624) (xy 87.014812 -272.073624)
		)
		(stroke
			(width 0)
			(type solid)
		)
		(fill yes)
		(layer "In4.Cu")
		(net "M_B_CPU1_SA_DQS_DP<6>")
	)
	(gr_poly
		(pts
			(xy 87.023194 -286.270954) (xy 87.023194 -286.226758) (xy 86.667594 -286.226758) (xy 86.667594 -286.270954)
			(xy 86.714584 -286.423354) (xy 86.976204 -286.423354)
		)
		(stroke
			(width 0)
			(type solid)
		)
		(fill yes)
		(layer "In4.Cu")
		(net "M_C_CPU1_SA_DQ<1>")
	)
	(gr_poly
		(pts
			(xy 87.023194 -285.051754) (xy 86.976204 -284.899354) (xy 86.714584 -284.899354) (xy 86.667594 -285.051754)
			(xy 86.667594 -285.096204) (xy 87.023194 -285.096204)
		)
		(stroke
			(width 0)
			(type solid)
		)
		(fill yes)
		(layer "In4.Cu")
		(net "M_C_CPU1_SA_DQS_DN<0>")
	)
	(gr_poly
		(pts
			(xy 87.023194 -271.620742) (xy 87.023194 -271.576546) (xy 86.667594 -271.576546) (xy 86.667594 -271.620742)
			(xy 86.714584 -271.773142) (xy 86.976204 -271.773142)
		)
		(stroke
			(width 0)
			(type solid)
		)
		(fill yes)
		(layer "In4.Cu")
		(net "M_B_CPU1_SA_DQ<12>")
	)
	(gr_poly
		(pts
			(xy 87.023194 -270.40205) (xy 86.976204 -270.24965) (xy 86.714584 -270.24965) (xy 86.667594 -270.40205)
			(xy 86.667594 -270.446246) (xy 87.023194 -270.446246)
		)
		(stroke
			(width 0)
			(type solid)
		)
		(fill yes)
		(layer "In4.Cu")
		(net "M_B_CPU1_SA_DQ<15>")
	)
	(gr_poly
		(pts
			(xy 87.023194 -269.99311) (xy 87.023194 -269.948914) (xy 86.667594 -269.948914) (xy 86.667594 -269.99311)
			(xy 86.714584 -270.14551) (xy 86.976204 -270.14551)
		)
		(stroke
			(width 0)
			(type solid)
		)
		(fill yes)
		(layer "In4.Cu")
		(net "M_C_CPU1_SA_DQ<16>")
	)
	(gr_poly
		(pts
			(xy 87.023194 -268.77391) (xy 86.976204 -268.62151) (xy 86.714584 -268.62151) (xy 86.667594 -268.77391)
			(xy 86.667594 -268.81836) (xy 87.023194 -268.81836)
		)
		(stroke
			(width 0)
			(type solid)
		)
		(fill yes)
		(layer "In4.Cu")
		(net "M_C_CPU1_SA_DQ<19>")
	)
	(gr_poly
		(pts
			(xy 87.023194 -268.365478) (xy 87.023194 -268.321028) (xy 86.667594 -268.321028) (xy 86.667594 -268.365478)
			(xy 86.714584 -268.517878) (xy 86.976204 -268.517878)
		)
		(stroke
			(width 0)
			(type solid)
		)
		(fill yes)
		(layer "In4.Cu")
		(net "M_C_CPU1_SA_DQS_DP<2>")
	)
	(gr_poly
		(pts
			(xy 87.023194 -267.146278) (xy 86.976204 -266.993878) (xy 86.714584 -266.993878) (xy 86.667594 -267.146278)
			(xy 86.667594 -267.190474) (xy 87.023194 -267.190474)
		)
		(stroke
			(width 0)
			(type solid)
		)
		(fill yes)
		(layer "In4.Cu")
		(net "M_C_CPU1_SA_DQS_DP<7>")
	)
	(gr_poly
		(pts
			(xy 87.023194 -266.737846) (xy 87.023194 -266.693396) (xy 86.667594 -266.693396) (xy 86.667594 -266.737846)
			(xy 86.714584 -266.890246) (xy 86.976204 -266.890246)
		)
		(stroke
			(width 0)
			(type solid)
		)
		(fill yes)
		(layer "In4.Cu")
		(net "M_C_CPU1_SA_DQ<20>")
	)
	(gr_poly
		(pts
			(xy 87.023194 -265.518646) (xy 86.976204 -265.366246) (xy 86.714584 -265.366246) (xy 86.667594 -265.518646)
			(xy 86.667594 -265.562842) (xy 87.023194 -265.562842)
		)
		(stroke
			(width 0)
			(type solid)
		)
		(fill yes)
		(layer "In4.Cu")
		(net "M_C_CPU1_SA_DQ<23>")
	)
	(gr_poly
		(pts
			(xy 87.023194 -265.109706) (xy 87.023194 -265.06551) (xy 86.667594 -265.06551) (xy 86.667594 -265.109706)
			(xy 86.714584 -265.262106) (xy 86.976204 -265.262106)
		)
		(stroke
			(width 0)
			(type solid)
		)
		(fill yes)
		(layer "In4.Cu")
		(net "M_B_CPU1_SA_DQ<26>")
	)
	(gr_poly
		(pts
			(xy 87.023194 -263.891014) (xy 86.976204 -263.738614) (xy 86.714584 -263.738614) (xy 86.667594 -263.891014)
			(xy 86.667594 -263.93521) (xy 87.023194 -263.93521)
		)
		(stroke
			(width 0)
			(type solid)
		)
		(fill yes)
		(layer "In4.Cu")
		(net "M_B_CPU1_SA_DQ<27>")
	)
	(gr_poly
		(pts
			(xy 87.023194 -263.482074) (xy 87.023194 -263.437878) (xy 86.667594 -263.437878) (xy 86.667594 -263.482074)
			(xy 86.714584 -263.634474) (xy 86.976204 -263.634474)
		)
		(stroke
			(width 0)
			(type solid)
		)
		(fill yes)
		(layer "In4.Cu")
		(net "M_B_CPU1_SA_DQS_DP<3>")
	)
	(gr_poly
		(pts
			(xy 87.023194 -262.262874) (xy 86.976204 -262.110474) (xy 86.714584 -262.110474) (xy 86.667594 -262.262874)
			(xy 86.667594 -262.307324) (xy 87.023194 -262.307324)
		)
		(stroke
			(width 0)
			(type solid)
		)
		(fill yes)
		(layer "In4.Cu")
		(net "M_B_CPU1_SA_DQS_DP<8>")
	)
	(gr_poly
		(pts
			(xy 87.023194 -261.854442) (xy 87.023194 -261.809992) (xy 86.667594 -261.809992) (xy 86.667594 -261.854442)
			(xy 86.714584 -262.006842) (xy 86.976204 -262.006842)
		)
		(stroke
			(width 0)
			(type solid)
		)
		(fill yes)
		(layer "In4.Cu")
		(net "M_B_CPU1_SA_DQ<28>")
	)
	(gr_poly
		(pts
			(xy 87.023194 -260.635242) (xy 86.976204 -260.482842) (xy 86.714584 -260.482842) (xy 86.667594 -260.635242)
			(xy 86.667594 -260.679438) (xy 87.023194 -260.679438)
		)
		(stroke
			(width 0)
			(type solid)
		)
		(fill yes)
		(layer "In4.Cu")
		(net "M_B_CPU1_SA_DQ<31>")
	)
	(gr_poly
		(pts
			(xy 87.023194 -258.59867) (xy 87.023194 -258.554474) (xy 86.667594 -258.554474) (xy 86.667594 -258.59867)
			(xy 86.714584 -258.75107) (xy 86.976204 -258.75107)
		)
		(stroke
			(width 0)
			(type solid)
		)
		(fill yes)
		(layer "In4.Cu")
		(net "M_C_CPU1_SA_CS_N<0>")
	)
	(gr_poly
		(pts
			(xy 87.023194 -257.37947) (xy 86.976204 -257.22707) (xy 86.714584 -257.22707) (xy 86.667594 -257.37947)
			(xy 86.667594 -257.42392) (xy 87.023194 -257.42392)
		)
		(stroke
			(width 0)
			(type solid)
		)
		(fill yes)
		(layer "In4.Cu")
		(net "M_C_CPU1_SA_CS_N<3>")
	)
	(gr_poly
		(pts
			(xy 87.023194 -256.971038) (xy 87.023194 -256.926588) (xy 86.667594 -256.926588) (xy 86.667594 -256.971038)
			(xy 86.714584 -257.123438) (xy 86.976204 -257.123438)
		)
		(stroke
			(width 0)
			(type solid)
		)
		(fill yes)
		(layer "In4.Cu")
		(net "M_C_CPU1_SA_CA<0>")
	)
	(gr_poly
		(pts
			(xy 87.023194 -255.751838) (xy 86.976204 -255.599438) (xy 86.714584 -255.599438) (xy 86.667594 -255.751838)
			(xy 86.667594 -255.796288) (xy 87.023194 -255.796288)
		)
		(stroke
			(width 0)
			(type solid)
		)
		(fill yes)
		(layer "In4.Cu")
		(net "M_C_CPU1_SA_CA<3>")
	)
	(gr_poly
		(pts
			(xy 87.023194 -255.343406) (xy 87.023194 -255.298956) (xy 86.667594 -255.298956) (xy 86.667594 -255.343406)
			(xy 86.714584 -255.495806) (xy 86.976204 -255.495806)
		)
		(stroke
			(width 0)
			(type solid)
		)
		(fill yes)
		(layer "In4.Cu")
		(net "M_C_CPU1_SA_CA<4>")
	)
	(gr_poly
		(pts
			(xy 87.023194 -254.124206) (xy 86.976204 -253.971806) (xy 86.714584 -253.971806) (xy 86.667594 -254.124206)
			(xy 86.667594 -254.168402) (xy 87.023194 -254.168402)
		)
		(stroke
			(width 0)
			(type solid)
		)
		(fill yes)
		(layer "In4.Cu")
		(net "M_C_CPU1_SA_PAR")
	)
	(gr_poly
		(pts
			(xy 87.095838 -275.356574) (xy 86.98738 -275.239734) (xy 86.949026 -275.217636) (xy 86.771226 -275.525484)
			(xy 86.80958 -275.547582) (xy 86.965028 -275.583142)
		)
		(stroke
			(width 0)
			(type solid)
		)
		(fill yes)
		(layer "In4.Cu")
		(net "M_B_CPU1_SA_DQ<9>")
	)
	(gr_poly
		(pts
			(xy 87.096092 -280.239978) (xy 86.987634 -280.123138) (xy 86.94928 -280.10104) (xy 86.77148 -280.408888)
			(xy 86.809834 -280.430986) (xy 86.965282 -280.466546)
		)
		(stroke
			(width 0)
			(type solid)
		)
		(fill yes)
		(layer "In4.Cu")
		(net "M_C_CPU1_SA_DQ<5>")
	)
	(gr_poly
		(pts
			(xy 87.102696 -281.856434) (xy 86.994238 -281.739594) (xy 86.955884 -281.717496) (xy 86.778084 -282.025344)
			(xy 86.816438 -282.047442) (xy 86.971886 -282.083002)
		)
		(stroke
			(width 0)
			(type solid)
		)
		(fill yes)
		(layer "In4.Cu")
		(net "M_C_CPU1_SA_DQ<4>")
	)
	(gr_poly
		(pts
			(xy 87.102696 -273.717766) (xy 86.994238 -273.600926) (xy 86.955884 -273.578828) (xy 86.778084 -273.886676)
			(xy 86.816438 -273.908774) (xy 86.971886 -273.944334)
		)
		(stroke
			(width 0)
			(type solid)
		)
		(fill yes)
		(layer "In4.Cu")
		(net "M_B_CPU1_SA_DQS_DP<1>")
	)
	(gr_poly
		(pts
			(xy 87.277448 -247.551448) (xy 87.239094 -247.52935) (xy 87.083646 -247.49379) (xy 86.952836 -247.720358)
			(xy 87.061294 -247.837198) (xy 87.099648 -247.859296)
		)
		(stroke
			(width 0)
			(type solid)
		)
		(fill yes)
		(layer "In4.Cu")
		(net "M_C_CPU1_SB_CA<3>")
	)
	(gr_poly
		(pts
			(xy 87.277448 -245.923816) (xy 87.239094 -245.901718) (xy 87.083646 -245.866158) (xy 86.952836 -246.092726)
			(xy 87.061294 -246.209566) (xy 87.099648 -246.231664)
		)
		(stroke
			(width 0)
			(type solid)
		)
		(fill yes)
		(layer "In4.Cu")
		(net "M_C_CPU1_SB_CA<5>")
	)
	(gr_poly
		(pts
			(xy 87.277448 -241.040412) (xy 87.239094 -241.018314) (xy 87.083646 -240.982754) (xy 86.952836 -241.209322)
			(xy 87.061294 -241.326162) (xy 87.099648 -241.34826)
		)
		(stroke
			(width 0)
			(type solid)
		)
		(fill yes)
		(layer "In4.Cu")
		(net "M_C_CPU1_SB_CB<7>")
	)
	(gr_poly
		(pts
			(xy 87.37473 -244.940582) (xy 87.32774 -244.788182) (xy 87.06612 -244.788182) (xy 87.01913 -244.940582)
			(xy 87.01913 -244.985032) (xy 87.37473 -244.985032)
		)
		(stroke
			(width 0)
			(type solid)
		)
		(fill yes)
		(layer "In4.Cu")
		(net "M_C_CPU1_SB_PAR")
	)
	(gr_poly
		(pts
			(xy 87.37473 -240.057178) (xy 87.32774 -239.904778) (xy 87.06612 -239.904778) (xy 87.01913 -240.057178)
			(xy 87.01913 -240.101628) (xy 87.37473 -240.101628)
		)
		(stroke
			(width 0)
			(type solid)
		)
		(fill yes)
		(layer "In4.Cu")
		(net "M_C_CPU1_SB_DQS_DN<9>")
	)
	(gr_poly
		(pts
			(xy 87.37473 -239.649254) (xy 87.37473 -239.604804) (xy 87.01913 -239.604804) (xy 87.01913 -239.649254)
			(xy 87.06612 -239.801654) (xy 87.32774 -239.801654)
		)
		(stroke
			(width 0)
			(type solid)
		)
		(fill yes)
		(layer "In4.Cu")
		(net "M_C_CPU1_SB_DQS_DN<4>")
	)
	(gr_poly
		(pts
			(xy 87.37473 -235.174282) (xy 87.32774 -235.021882) (xy 87.06612 -235.021882) (xy 87.01913 -235.174282)
			(xy 87.01913 -235.218478) (xy 87.37473 -235.218478)
		)
		(stroke
			(width 0)
			(type solid)
		)
		(fill yes)
		(layer "In4.Cu")
		(net "M_B_CPU1_SB_DQS_DN<0>")
	)
	(gr_poly
		(pts
			(xy 87.37473 -234.76585) (xy 87.37473 -234.721654) (xy 87.01913 -234.721654) (xy 87.01913 -234.76585)
			(xy 87.06612 -234.91825) (xy 87.32774 -234.91825)
		)
		(stroke
			(width 0)
			(type solid)
		)
		(fill yes)
		(layer "In4.Cu")
		(net "M_B_CPU1_SB_DQS_DN<5>")
	)
	(gr_poly
		(pts
			(xy 87.37473 -230.290878) (xy 87.32774 -230.138478) (xy 87.06612 -230.138478) (xy 87.01913 -230.290878)
			(xy 87.01913 -230.335074) (xy 87.37473 -230.335074)
		)
		(stroke
			(width 0)
			(type solid)
		)
		(fill yes)
		(layer "In4.Cu")
		(net "M_C_CPU1_SB_DQS_DN<2>")
	)
	(gr_poly
		(pts
			(xy 87.37473 -229.882446) (xy 87.37473 -229.83825) (xy 87.01913 -229.83825) (xy 87.01913 -229.882446)
			(xy 87.06612 -230.034846) (xy 87.32774 -230.034846)
		)
		(stroke
			(width 0)
			(type solid)
		)
		(fill yes)
		(layer "In4.Cu")
		(net "M_C_CPU1_SB_DQS_DN<7>")
	)
	(gr_poly
		(pts
			(xy 87.382858 -281.972258) (xy 87.344504 -281.95016) (xy 87.189056 -281.9146) (xy 87.058246 -282.141168)
			(xy 87.166704 -282.258008) (xy 87.205058 -282.280106)
		)
		(stroke
			(width 0)
			(type solid)
		)
		(fill yes)
		(layer "In4.Cu")
		(net "M_C_CPU1_SA_DQS_DP<5>")
	)
	(gr_poly
		(pts
			(xy 87.383112 -244.53215) (xy 87.383112 -244.487954) (xy 87.027512 -244.487954) (xy 87.027512 -244.53215)
			(xy 87.074502 -244.68455) (xy 87.336122 -244.68455)
		)
		(stroke
			(width 0)
			(type solid)
		)
		(fill yes)
		(layer "In4.Cu")
		(net "M_C_CPU1_SB_CS_N<2>")
	)
	(gr_poly
		(pts
			(xy 87.383366 -238.430054) (xy 87.336376 -238.277654) (xy 87.074756 -238.277654) (xy 87.027766 -238.430054)
			(xy 87.027766 -238.47425) (xy 87.383366 -238.47425)
		)
		(stroke
			(width 0)
			(type solid)
		)
		(fill yes)
		(layer "In4.Cu")
		(net "M_C_CPU1_SB_CB<2>")
	)
	(gr_poly
		(pts
			(xy 87.383366 -236.393482) (xy 87.383366 -236.349286) (xy 87.027766 -236.349286) (xy 87.027766 -236.393482)
			(xy 87.074756 -236.545882) (xy 87.336376 -236.545882)
		)
		(stroke
			(width 0)
			(type solid)
		)
		(fill yes)
		(layer "In4.Cu")
		(net "M_B_CPU1_SB_DQ<1>")
	)
	(gr_poly
		(pts
			(xy 87.383366 -233.54665) (xy 87.336376 -233.39425) (xy 87.074756 -233.39425) (xy 87.027766 -233.54665)
			(xy 87.027766 -233.590846) (xy 87.383366 -233.590846)
		)
		(stroke
			(width 0)
			(type solid)
		)
		(fill yes)
		(layer "In4.Cu")
		(net "M_B_CPU1_SB_DQ<6>")
	)
	(gr_poly
		(pts
			(xy 87.383366 -233.13771) (xy 87.383366 -233.093514) (xy 87.027766 -233.093514) (xy 87.027766 -233.13771)
			(xy 87.074756 -233.29011) (xy 87.336376 -233.29011)
		)
		(stroke
			(width 0)
			(type solid)
		)
		(fill yes)
		(layer "In4.Cu")
		(net "M_B_CPU1_SB_DQ<5>")
	)
	(gr_poly
		(pts
			(xy 87.383366 -231.919018) (xy 87.336376 -231.766618) (xy 87.074756 -231.766618) (xy 87.027766 -231.919018)
			(xy 87.027766 -231.963214) (xy 87.383366 -231.963214)
		)
		(stroke
			(width 0)
			(type solid)
		)
		(fill yes)
		(layer "In4.Cu")
		(net "M_C_CPU1_SB_DQ<18>")
	)
	(gr_poly
		(pts
			(xy 87.383366 -231.510078) (xy 87.383366 -231.465882) (xy 87.027766 -231.465882) (xy 87.027766 -231.510078)
			(xy 87.074756 -231.662478) (xy 87.336376 -231.662478)
		)
		(stroke
			(width 0)
			(type solid)
		)
		(fill yes)
		(layer "In4.Cu")
		(net "M_C_CPU1_SB_DQ<17>")
	)
	(gr_poly
		(pts
			(xy 87.383366 -228.663246) (xy 87.336376 -228.510846) (xy 87.074756 -228.510846) (xy 87.027766 -228.663246)
			(xy 87.027766 -228.707696) (xy 87.383366 -228.707696)
		)
		(stroke
			(width 0)
			(type solid)
		)
		(fill yes)
		(layer "In4.Cu")
		(net "M_C_CPU1_SB_DQ<22>")
	)
	(gr_poly
		(pts
			(xy 87.387176 -273.826224) (xy 87.348822 -273.804126) (xy 87.193374 -273.768566) (xy 87.062564 -273.995134)
			(xy 87.171022 -274.111974) (xy 87.209376 -274.134072)
		)
		(stroke
			(width 0)
			(type solid)
		)
		(fill yes)
		(layer "In4.Cu")
		(net "M_B_CPU1_SA_DQ<11>")
	)
	(gr_poly
		(pts
			(xy 87.388446 -278.707088) (xy 87.350092 -278.68499) (xy 87.194644 -278.64943) (xy 87.063834 -278.875998)
			(xy 87.172292 -278.992838) (xy 87.210646 -279.014936)
		)
		(stroke
			(width 0)
			(type solid)
		)
		(fill yes)
		(layer "In4.Cu")
		(net "M_C_CPU1_SA_DQ<7>")
	)
	(gr_poly
		(pts
			(xy 87.388954 -275.450046) (xy 87.3506 -275.427948) (xy 87.195152 -275.392388) (xy 87.064342 -275.618956)
			(xy 87.1728 -275.735796) (xy 87.211154 -275.757894)
		)
		(stroke
			(width 0)
			(type solid)
		)
		(fill yes)
		(layer "In4.Cu")
		(net "M_B_CPU1_SA_DQ<10>")
	)
	(gr_poly
		(pts
			(xy 87.391748 -243.31295) (xy 87.344758 -243.16055) (xy 87.083138 -243.16055) (xy 87.036148 -243.31295)
			(xy 87.036148 -243.3574) (xy 87.391748 -243.3574)
		)
		(stroke
			(width 0)
			(type solid)
		)
		(fill yes)
		(layer "In4.Cu")
		(net "M_C_CPU1_SB_CS_N<1>")
	)
	(gr_poly
		(pts
			(xy 87.391748 -242.905026) (xy 87.391748 -242.860576) (xy 87.036148 -242.860576) (xy 87.036148 -242.905026)
			(xy 87.083138 -243.057426) (xy 87.344758 -243.057426)
		)
		(stroke
			(width 0)
			(type solid)
		)
		(fill yes)
		(layer "In4.Cu")
		(net "M_C_CPU1_SB_CB<4>")
	)
	(gr_poly
		(pts
			(xy 87.391748 -238.021622) (xy 87.391748 -237.977172) (xy 87.036148 -237.977172) (xy 87.036148 -238.021622)
			(xy 87.083138 -238.174022) (xy 87.344758 -238.174022)
		)
		(stroke
			(width 0)
			(type solid)
		)
		(fill yes)
		(layer "In4.Cu")
		(net "M_C_CPU1_SB_CB<1>")
	)
	(gr_poly
		(pts
			(xy 87.391748 -236.801914) (xy 87.344758 -236.649514) (xy 87.083138 -236.649514) (xy 87.036148 -236.801914)
			(xy 87.036148 -236.846364) (xy 87.391748 -236.846364)
		)
		(stroke
			(width 0)
			(type solid)
		)
		(fill yes)
		(layer "In4.Cu")
		(net "M_B_CPU1_SB_DQ<0>")
	)
	(gr_poly
		(pts
			(xy 87.391748 -228.254814) (xy 87.391748 -228.210618) (xy 87.036148 -228.210618) (xy 87.036148 -228.254814)
			(xy 87.083138 -228.407214) (xy 87.344758 -228.407214)
		)
		(stroke
			(width 0)
			(type solid)
		)
		(fill yes)
		(layer "In4.Cu")
		(net "M_C_CPU1_SB_DQ<21>")
	)
	(gr_poly
		(pts
			(xy 87.456264 -248.267982) (xy 87.347806 -248.151142) (xy 87.309452 -248.129044) (xy 87.131652 -248.436892)
			(xy 87.170006 -248.45899) (xy 87.325454 -248.49455)
		)
		(stroke
			(width 0)
			(type solid)
		)
		(fill yes)
		(layer "In4.Cu")
		(net "M_C_CPU1_SB_CA<2>")
	)
	(gr_poly
		(pts
			(xy 87.458296 -246.636286) (xy 87.349838 -246.519446) (xy 87.311484 -246.497348) (xy 87.133684 -246.805196)
			(xy 87.172038 -246.827294) (xy 87.327486 -246.862854)
		)
		(stroke
			(width 0)
			(type solid)
		)
		(fill yes)
		(layer "In4.Cu")
		(net "M_C_CPU1_SB_CA<4>")
	)
	(gr_poly
		(pts
			(xy 87.462614 -241.74577) (xy 87.354156 -241.62893) (xy 87.315802 -241.606832) (xy 87.138002 -241.91468)
			(xy 87.176356 -241.936778) (xy 87.331804 -241.972338)
		)
		(stroke
			(width 0)
			(type solid)
		)
		(fill yes)
		(layer "In4.Cu")
		(net "M_C_CPU1_SB_CB<5>")
	)
	(gr_poly
		(pts
			(xy 87.484712 -280.98242) (xy 87.437722 -280.83002) (xy 87.176102 -280.83002) (xy 87.129112 -280.98242)
			(xy 87.129112 -281.026616) (xy 87.484712 -281.026616)
		)
		(stroke
			(width 0)
			(type solid)
		)
		(fill yes)
		(layer "In4.Cu")
		(net "M_C_CPU1_SA_DQ<6>")
	)
	(gr_poly
		(pts
			(xy 87.493094 -287.49371) (xy 87.446104 -287.34131) (xy 87.184484 -287.34131) (xy 87.137494 -287.49371)
			(xy 87.137494 -287.537906) (xy 87.493094 -287.537906)
		)
		(stroke
			(width 0)
			(type solid)
		)
		(fill yes)
		(layer "In4.Cu")
		(net "M_C_CPU1_SA_DQ<2>")
	)
	(gr_poly
		(pts
			(xy 87.493094 -285.86557) (xy 87.446104 -285.71317) (xy 87.184484 -285.71317) (xy 87.137494 -285.86557)
			(xy 87.137494 -285.91002) (xy 87.493094 -285.91002)
		)
		(stroke
			(width 0)
			(type solid)
		)
		(fill yes)
		(layer "In4.Cu")
		(net "M_C_CPU1_SA_DQ<3>")
	)
	(gr_poly
		(pts
			(xy 87.493094 -285.456884) (xy 87.493094 -285.412688) (xy 87.137494 -285.412688) (xy 87.137494 -285.456884)
			(xy 87.184484 -285.609284) (xy 87.446104 -285.609284)
		)
		(stroke
			(width 0)
			(type solid)
		)
		(fill yes)
		(layer "In4.Cu")
		(net "M_C_CPU1_SA_DQS_DP<0>")
	)
	(gr_poly
		(pts
			(xy 87.493094 -271.215866) (xy 87.446104 -271.063466) (xy 87.184484 -271.063466) (xy 87.137494 -271.215866)
			(xy 87.137494 -271.260062) (xy 87.493094 -271.260062)
		)
		(stroke
			(width 0)
			(type solid)
		)
		(fill yes)
		(layer "In4.Cu")
		(net "M_B_CPU1_SA_DQ<14>")
	)
	(gr_poly
		(pts
			(xy 87.493094 -270.806926) (xy 87.493094 -270.76273) (xy 87.137494 -270.76273) (xy 87.137494 -270.806926)
			(xy 87.184484 -270.959326) (xy 87.446104 -270.959326)
		)
		(stroke
			(width 0)
			(type solid)
		)
		(fill yes)
		(layer "In4.Cu")
		(net "M_B_CPU1_SA_DQ<13>")
	)
	(gr_poly
		(pts
			(xy 87.493094 -269.587726) (xy 87.446104 -269.435326) (xy 87.184484 -269.435326) (xy 87.137494 -269.587726)
			(xy 87.137494 -269.632176) (xy 87.493094 -269.632176)
		)
		(stroke
			(width 0)
			(type solid)
		)
		(fill yes)
		(layer "In4.Cu")
		(net "M_C_CPU1_SA_DQ<18>")
	)
	(gr_poly
		(pts
			(xy 87.493094 -269.179294) (xy 87.493094 -269.134844) (xy 87.137494 -269.134844) (xy 87.137494 -269.179294)
			(xy 87.184484 -269.331694) (xy 87.446104 -269.331694)
		)
		(stroke
			(width 0)
			(type solid)
		)
		(fill yes)
		(layer "In4.Cu")
		(net "M_C_CPU1_SA_DQ<17>")
	)
	(gr_poly
		(pts
			(xy 87.493094 -267.960094) (xy 87.446104 -267.807694) (xy 87.184484 -267.807694) (xy 87.137494 -267.960094)
			(xy 87.137494 -268.004544) (xy 87.493094 -268.004544)
		)
		(stroke
			(width 0)
			(type solid)
		)
		(fill yes)
		(layer "In4.Cu")
		(net "M_C_CPU1_SA_DQS_DN<2>")
	)
	(gr_poly
		(pts
			(xy 87.493094 -267.551662) (xy 87.493094 -267.507212) (xy 87.137494 -267.507212) (xy 87.137494 -267.551662)
			(xy 87.184484 -267.704062) (xy 87.446104 -267.704062)
		)
		(stroke
			(width 0)
			(type solid)
		)
		(fill yes)
		(layer "In4.Cu")
		(net "M_C_CPU1_SA_DQS_DN<7>")
	)
	(gr_poly
		(pts
			(xy 87.493094 -266.332462) (xy 87.446104 -266.180062) (xy 87.184484 -266.180062) (xy 87.137494 -266.332462)
			(xy 87.137494 -266.376658) (xy 87.493094 -266.376658)
		)
		(stroke
			(width 0)
			(type solid)
		)
		(fill yes)
		(layer "In4.Cu")
		(net "M_C_CPU1_SA_DQ<22>")
	)
	(gr_poly
		(pts
			(xy 87.493094 -265.92403) (xy 87.493094 -265.87958) (xy 87.137494 -265.87958) (xy 87.137494 -265.92403)
			(xy 87.184484 -266.07643) (xy 87.446104 -266.07643)
		)
		(stroke
			(width 0)
			(type solid)
		)
		(fill yes)
		(layer "In4.Cu")
		(net "M_C_CPU1_SA_DQ<21>")
	)
	(gr_poly
		(pts
			(xy 87.493094 -264.70483) (xy 87.446104 -264.55243) (xy 87.184484 -264.55243) (xy 87.137494 -264.70483)
			(xy 87.137494 -264.749026) (xy 87.493094 -264.749026)
		)
		(stroke
			(width 0)
			(type solid)
		)
		(fill yes)
		(layer "In4.Cu")
		(net "M_B_CPU1_SA_DQ<24>")
	)
	(gr_poly
		(pts
			(xy 87.493094 -264.29589) (xy 87.493094 -264.251694) (xy 87.137494 -264.251694) (xy 87.137494 -264.29589)
			(xy 87.184484 -264.44829) (xy 87.446104 -264.44829)
		)
		(stroke
			(width 0)
			(type solid)
		)
		(fill yes)
		(layer "In4.Cu")
		(net "M_B_CPU1_SA_DQ<25>")
	)
	(gr_poly
		(pts
			(xy 87.493094 -263.07669) (xy 87.446104 -262.92429) (xy 87.184484 -262.92429) (xy 87.137494 -263.07669)
			(xy 87.137494 -263.12114) (xy 87.493094 -263.12114)
		)
		(stroke
			(width 0)
			(type solid)
		)
		(fill yes)
		(layer "In4.Cu")
		(net "M_B_CPU1_SA_DQS_DN<3>")
	)
	(gr_poly
		(pts
			(xy 87.493094 -262.668258) (xy 87.493094 -262.623808) (xy 87.137494 -262.623808) (xy 87.137494 -262.668258)
			(xy 87.184484 -262.820658) (xy 87.446104 -262.820658)
		)
		(stroke
			(width 0)
			(type solid)
		)
		(fill yes)
		(layer "In4.Cu")
		(net "M_B_CPU1_SA_DQS_DN<8>")
	)
	(gr_poly
		(pts
			(xy 87.493094 -261.449058) (xy 87.446104 -261.296658) (xy 87.184484 -261.296658) (xy 87.137494 -261.449058)
			(xy 87.137494 -261.493508) (xy 87.493094 -261.493508)
		)
		(stroke
			(width 0)
			(type solid)
		)
		(fill yes)
		(layer "In4.Cu")
		(net "M_B_CPU1_SA_DQ<30>")
	)
	(gr_poly
		(pts
			(xy 87.493094 -261.040626) (xy 87.493094 -260.996176) (xy 87.137494 -260.996176) (xy 87.137494 -261.040626)
			(xy 87.184484 -261.193026) (xy 87.446104 -261.193026)
		)
		(stroke
			(width 0)
			(type solid)
		)
		(fill yes)
		(layer "In4.Cu")
		(net "M_B_CPU1_SA_DQ<29>")
	)
	(gr_poly
		(pts
			(xy 87.493094 -258.193286) (xy 87.446104 -258.040886) (xy 87.184484 -258.040886) (xy 87.137494 -258.193286)
			(xy 87.137494 -258.237736) (xy 87.493094 -258.237736)
		)
		(stroke
			(width 0)
			(type solid)
		)
		(fill yes)
		(layer "In4.Cu")
		(net "M_C_CPU1_SA_CS_N<2>")
	)
	(gr_poly
		(pts
			(xy 87.493094 -257.784854) (xy 87.493094 -257.740404) (xy 87.137494 -257.740404) (xy 87.137494 -257.784854)
			(xy 87.184484 -257.937254) (xy 87.446104 -257.937254)
		)
		(stroke
			(width 0)
			(type solid)
		)
		(fill yes)
		(layer "In4.Cu")
		(net "M_C_CPU1_SA_CS_N<1>")
	)
	(gr_poly
		(pts
			(xy 87.493094 -256.565654) (xy 87.446104 -256.413254) (xy 87.184484 -256.413254) (xy 87.137494 -256.565654)
			(xy 87.137494 -256.610104) (xy 87.493094 -256.610104)
		)
		(stroke
			(width 0)
			(type solid)
		)
		(fill yes)
		(layer "In4.Cu")
		(net "M_C_CPU1_SA_CA<1>")
	)
	(gr_poly
		(pts
			(xy 87.493094 -256.157222) (xy 87.493094 -256.112772) (xy 87.137494 -256.112772) (xy 87.137494 -256.157222)
			(xy 87.184484 -256.309622) (xy 87.446104 -256.309622)
		)
		(stroke
			(width 0)
			(type solid)
		)
		(fill yes)
		(layer "In4.Cu")
		(net "M_C_CPU1_SA_CA<2>")
	)
	(gr_poly
		(pts
			(xy 87.493094 -254.938022) (xy 87.446104 -254.785622) (xy 87.184484 -254.785622) (xy 87.137494 -254.938022)
			(xy 87.137494 -254.982218) (xy 87.493094 -254.982218)
		)
		(stroke
			(width 0)
			(type solid)
		)
		(fill yes)
		(layer "In4.Cu")
		(net "M_C_CPU1_SA_CA<5>")
	)
	(gr_poly
		(pts
			(xy 87.493094 -254.529082) (xy 87.493094 -254.484886) (xy 87.137494 -254.484886) (xy 87.137494 -254.529082)
			(xy 87.184484 -254.681482) (xy 87.446104 -254.681482)
		)
		(stroke
			(width 0)
			(type solid)
		)
		(fill yes)
		(layer "In4.Cu")
		(net "M_C_CPU1_SA_CA<6>")
	)
	(gr_poly
		(pts
			(xy 87.49919 -272.843498) (xy 87.4522 -272.691098) (xy 87.19058 -272.691098) (xy 87.14359 -272.843498)
			(xy 87.14359 -272.887948) (xy 87.49919 -272.887948)
		)
		(stroke
			(width 0)
			(type solid)
		)
		(fill yes)
		(layer "In4.Cu")
		(net "M_B_CPU1_SA_DQS_DN<1>")
	)
	(gr_poly
		(pts
			(xy 87.49919 -272.435066) (xy 87.49919 -272.390616) (xy 87.14359 -272.390616) (xy 87.14359 -272.435066)
			(xy 87.19058 -272.587466) (xy 87.4522 -272.587466)
		)
		(stroke
			(width 0)
			(type solid)
		)
		(fill yes)
		(layer "In4.Cu")
		(net "M_B_CPU1_SA_DQS_DN<6>")
	)
	(gr_poly
		(pts
			(xy 87.566754 -276.16912) (xy 87.458296 -276.05228) (xy 87.419942 -276.030182) (xy 87.242142 -276.33803)
			(xy 87.280496 -276.360128) (xy 87.435944 -276.395688)
		)
		(stroke
			(width 0)
			(type solid)
		)
		(fill yes)
		(layer "In4.Cu")
		(net "M_B_CPU1_SA_DQ<8>")
	)
	(gr_poly
		(pts
			(xy 87.567262 -282.679648) (xy 87.458804 -282.562808) (xy 87.42045 -282.54071) (xy 87.24265 -282.848558)
			(xy 87.281004 -282.870656) (xy 87.436452 -282.906216)
		)
		(stroke
			(width 0)
			(type solid)
		)
		(fill yes)
		(layer "In4.Cu")
		(net "M_C_CPU1_SA_DQS_DN<5>")
	)
	(gr_poly
		(pts
			(xy 87.572342 -274.531582) (xy 87.463884 -274.414742) (xy 87.42553 -274.392644) (xy 87.24773 -274.700492)
			(xy 87.286084 -274.72259) (xy 87.441532 -274.75815)
		)
		(stroke
			(width 0)
			(type solid)
		)
		(fill yes)
		(layer "In4.Cu")
		(net "M_B_CPU1_SA_DQ<9>")
	)
	(gr_poly
		(pts
			(xy 87.572596 -279.414986) (xy 87.464138 -279.298146) (xy 87.425784 -279.276048) (xy 87.247984 -279.583896)
			(xy 87.286338 -279.605994) (xy 87.441786 -279.641554)
		)
		(stroke
			(width 0)
			(type solid)
		)
		(fill yes)
		(layer "In4.Cu")
		(net "M_C_CPU1_SA_DQ<5>")
	)
	(gr_poly
		(pts
			(xy 87.74303 -241.861594) (xy 87.704676 -241.839496) (xy 87.549228 -241.803936) (xy 87.418418 -242.030504)
			(xy 87.526876 -242.147344) (xy 87.56523 -242.169442)
		)
		(stroke
			(width 0)
			(type solid)
		)
		(fill yes)
		(layer "In4.Cu")
		(net "M_C_CPU1_SB_CB<6>")
	)
	(gr_poly
		(pts
			(xy 87.747348 -246.737632) (xy 87.708994 -246.715534) (xy 87.553546 -246.679974) (xy 87.422736 -246.906542)
			(xy 87.531194 -247.023382) (xy 87.569548 -247.04548)
		)
		(stroke
			(width 0)
			(type solid)
		)
		(fill yes)
		(layer "In4.Cu")
		(net "M_C_CPU1_SB_CA<3>")
	)
	(gr_poly
		(pts
			(xy 87.820754 -280.430986) (xy 87.859108 -280.408888) (xy 87.681308 -280.10104) (xy 87.642954 -280.123138)
			(xy 87.534496 -280.239978) (xy 87.665306 -280.466546)
		)
		(stroke
			(width 0)
			(type solid)
		)
		(fill yes)
		(layer "In4.Cu")
		(net "M_C_CPU1_SA_DQ<6>")
	)
	(gr_poly
		(pts
			(xy 87.84717 -243.718842) (xy 87.84717 -243.674392) (xy 87.49157 -243.674392) (xy 87.49157 -243.718842)
			(xy 87.53856 -243.871242) (xy 87.80018 -243.871242)
		)
		(stroke
			(width 0)
			(type solid)
		)
		(fill yes)
		(layer "In4.Cu")
		(net "M_C_CPU1_SB_CS_N<3>")
	)
	(gr_poly
		(pts
			(xy 87.84717 -237.207806) (xy 87.84717 -237.163356) (xy 87.49157 -237.163356) (xy 87.49157 -237.207806)
			(xy 87.53856 -237.360206) (xy 87.80018 -237.360206)
		)
		(stroke
			(width 0)
			(type solid)
		)
		(fill yes)
		(layer "In4.Cu")
		(net "M_B_CPU1_SB_DQ<2>")
	)
	(gr_poly
		(pts
			(xy 87.84717 -227.848922) (xy 87.80018 -227.696522) (xy 87.53856 -227.696522) (xy 87.49157 -227.848922)
			(xy 87.49157 -227.893372) (xy 87.84717 -227.893372)
		)
		(stroke
			(width 0)
			(type solid)
		)
		(fill yes)
		(layer "In4.Cu")
		(net "M_C_CPU1_SB_DQ<23>")
	)
	(gr_poly
		(pts
			(xy 87.850218 -229.06863) (xy 87.850218 -229.02418) (xy 87.494618 -229.02418) (xy 87.494618 -229.06863)
			(xy 87.541608 -229.22103) (xy 87.803228 -229.22103)
		)
		(stroke
			(width 0)
			(type solid)
		)
		(fill yes)
		(layer "In4.Cu")
		(net "M_C_CPU1_SB_DQ<20>")
	)
	(gr_poly
		(pts
			(xy 87.850726 -274.6502) (xy 87.812372 -274.628102) (xy 87.656924 -274.592542) (xy 87.526114 -274.81911)
			(xy 87.634572 -274.93595) (xy 87.672926 -274.958048)
		)
		(stroke
			(width 0)
			(type solid)
		)
		(fill yes)
		(layer "In4.Cu")
		(net "M_B_CPU1_SA_DQ<10>")
	)
	(gr_poly
		(pts
			(xy 87.853266 -245.754906) (xy 87.806276 -245.602506) (xy 87.544656 -245.602506) (xy 87.497666 -245.754906)
			(xy 87.497666 -245.799356) (xy 87.853266 -245.799356)
		)
		(stroke
			(width 0)
			(type solid)
		)
		(fill yes)
		(layer "In4.Cu")
		(net "M_C_CPU1_SB_CA<5>")
	)
	(gr_poly
		(pts
			(xy 87.853266 -240.871502) (xy 87.806276 -240.719102) (xy 87.544656 -240.719102) (xy 87.497666 -240.871502)
			(xy 87.497666 -240.915952) (xy 87.853266 -240.915952)
		)
		(stroke
			(width 0)
			(type solid)
		)
		(fill yes)
		(layer "In4.Cu")
		(net "M_C_CPU1_SB_CB<7>")
	)
	(gr_poly
		(pts
			(xy 87.853266 -238.83493) (xy 87.853266 -238.790734) (xy 87.497666 -238.790734) (xy 87.497666 -238.83493)
			(xy 87.544656 -238.98733) (xy 87.806276 -238.98733)
		)
		(stroke
			(width 0)
			(type solid)
		)
		(fill yes)
		(layer "In4.Cu")
		(net "M_C_CPU1_SB_CB<0>")
	)
	(gr_poly
		(pts
			(xy 87.853266 -235.988098) (xy 87.806276 -235.835698) (xy 87.544656 -235.835698) (xy 87.497666 -235.988098)
			(xy 87.497666 -236.032548) (xy 87.853266 -236.032548)
		)
		(stroke
			(width 0)
			(type solid)
		)
		(fill yes)
		(layer "In4.Cu")
		(net "M_B_CPU1_SB_DQ<3>")
	)
	(gr_poly
		(pts
			(xy 87.853266 -233.952034) (xy 87.853266 -233.907584) (xy 87.497666 -233.907584) (xy 87.497666 -233.952034)
			(xy 87.544656 -234.104434) (xy 87.806276 -234.104434)
		)
		(stroke
			(width 0)
			(type solid)
		)
		(fill yes)
		(layer "In4.Cu")
		(net "M_B_CPU1_SB_DQ<4>")
	)
	(gr_poly
		(pts
			(xy 87.853266 -232.732834) (xy 87.806276 -232.580434) (xy 87.544656 -232.580434) (xy 87.497666 -232.732834)
			(xy 87.497666 -232.77703) (xy 87.853266 -232.77703)
		)
		(stroke
			(width 0)
			(type solid)
		)
		(fill yes)
		(layer "In4.Cu")
		(net "M_B_CPU1_SB_DQ<7>")
	)
	(gr_poly
		(pts
			(xy 87.853266 -232.323894) (xy 87.853266 -232.279698) (xy 87.497666 -232.279698) (xy 87.497666 -232.323894)
			(xy 87.544656 -232.476294) (xy 87.806276 -232.476294)
		)
		(stroke
			(width 0)
			(type solid)
		)
		(fill yes)
		(layer "In4.Cu")
		(net "M_C_CPU1_SB_DQ<16>")
	)
	(gr_poly
		(pts
			(xy 87.853266 -231.104694) (xy 87.806276 -230.952294) (xy 87.544656 -230.952294) (xy 87.497666 -231.104694)
			(xy 87.497666 -231.149144) (xy 87.853266 -231.149144)
		)
		(stroke
			(width 0)
			(type solid)
		)
		(fill yes)
		(layer "In4.Cu")
		(net "M_C_CPU1_SB_DQ<19>")
	)
	(gr_poly
		(pts
			(xy 87.857076 -284.406848) (xy 87.818722 -284.38475) (xy 87.663274 -284.34919) (xy 87.532464 -284.575758)
			(xy 87.640922 -284.692598) (xy 87.679276 -284.714696)
		)
		(stroke
			(width 0)
			(type solid)
		)
		(fill yes)
		(layer "In4.Cu")
		(net "M_C_CPU1_SA_DQS_DN<0>")
	)
	(gr_poly
		(pts
			(xy 87.857076 -279.523444) (xy 87.818722 -279.501346) (xy 87.663274 -279.465786) (xy 87.532464 -279.692354)
			(xy 87.640922 -279.809194) (xy 87.679276 -279.831292)
		)
		(stroke
			(width 0)
			(type solid)
		)
		(fill yes)
		(layer "In4.Cu")
		(net "M_C_CPU1_SA_DQ<6>")
	)
	(gr_poly
		(pts
			(xy 87.858092 -277.893272) (xy 87.819738 -277.871174) (xy 87.66429 -277.835614) (xy 87.53348 -278.062182)
			(xy 87.641938 -278.179022) (xy 87.680292 -278.20112)
		)
		(stroke
			(width 0)
			(type solid)
		)
		(fill yes)
		(layer "In4.Cu")
		(net "M_C_CPU1_SA_DQ<7>")
	)
	(gr_poly
		(pts
			(xy 87.858346 -237.61573) (xy 87.811356 -237.46333) (xy 87.549736 -237.46333) (xy 87.502746 -237.61573)
			(xy 87.502746 -237.66018) (xy 87.858346 -237.66018)
		)
		(stroke
			(width 0)
			(type solid)
		)
		(fill yes)
		(layer "In4.Cu")
		(net "M_C_CPU1_SB_CB<3>")
	)
	(gr_poly
		(pts
			(xy 87.859108 -244.126766) (xy 87.812118 -243.974366) (xy 87.550498 -243.974366) (xy 87.503508 -244.126766)
			(xy 87.503508 -244.171216) (xy 87.859108 -244.171216)
		)
		(stroke
			(width 0)
			(type solid)
		)
		(fill yes)
		(layer "In4.Cu")
		(net "M_C_CPU1_SB_CS_N<0>")
	)
	(gr_poly
		(pts
			(xy 87.861648 -245.346474) (xy 87.861648 -245.302278) (xy 87.506048 -245.302278) (xy 87.506048 -245.346474)
			(xy 87.553038 -245.498874) (xy 87.814658 -245.498874)
		)
		(stroke
			(width 0)
			(type solid)
		)
		(fill yes)
		(layer "In4.Cu")
		(net "M_C_CPU1_SB_CA<6>")
	)
	(gr_poly
		(pts
			(xy 87.861648 -240.46307) (xy 87.861648 -240.418874) (xy 87.506048 -240.418874) (xy 87.506048 -240.46307)
			(xy 87.553038 -240.61547) (xy 87.814658 -240.61547)
		)
		(stroke
			(width 0)
			(type solid)
		)
		(fill yes)
		(layer "In4.Cu")
		(net "M_C_CPU1_SB_DQS_DP<9>")
	)
	(gr_poly
		(pts
			(xy 87.861648 -239.243362) (xy 87.814658 -239.090962) (xy 87.553038 -239.090962) (xy 87.506048 -239.243362)
			(xy 87.506048 -239.287812) (xy 87.861648 -239.287812)
		)
		(stroke
			(width 0)
			(type solid)
		)
		(fill yes)
		(layer "In4.Cu")
		(net "M_C_CPU1_SB_DQS_DP<4>")
	)
	(gr_poly
		(pts
			(xy 87.861648 -235.579666) (xy 87.861648 -235.53547) (xy 87.506048 -235.53547) (xy 87.506048 -235.579666)
			(xy 87.553038 -235.732066) (xy 87.814658 -235.732066)
		)
		(stroke
			(width 0)
			(type solid)
		)
		(fill yes)
		(layer "In4.Cu")
		(net "M_B_CPU1_SB_DQS_DP<0>")
	)
	(gr_poly
		(pts
			(xy 87.861648 -234.360466) (xy 87.814658 -234.208066) (xy 87.553038 -234.208066) (xy 87.506048 -234.360466)
			(xy 87.506048 -234.404662) (xy 87.861648 -234.404662)
		)
		(stroke
			(width 0)
			(type solid)
		)
		(fill yes)
		(layer "In4.Cu")
		(net "M_B_CPU1_SB_DQS_DP<5>")
	)
	(gr_poly
		(pts
			(xy 87.861648 -230.696262) (xy 87.861648 -230.652066) (xy 87.506048 -230.652066) (xy 87.506048 -230.696262)
			(xy 87.553038 -230.848662) (xy 87.814658 -230.848662)
		)
		(stroke
			(width 0)
			(type solid)
		)
		(fill yes)
		(layer "In4.Cu")
		(net "M_C_CPU1_SB_DQS_DP<2>")
	)
	(gr_poly
		(pts
			(xy 87.861648 -229.477062) (xy 87.814658 -229.324662) (xy 87.553038 -229.324662) (xy 87.506048 -229.477062)
			(xy 87.506048 -229.521258) (xy 87.861648 -229.521258)
		)
		(stroke
			(width 0)
			(type solid)
		)
		(fill yes)
		(layer "In4.Cu")
		(net "M_C_CPU1_SB_DQS_DP<7>")
	)
	(gr_poly
		(pts
			(xy 87.92718 -242.56873) (xy 87.818722 -242.45189) (xy 87.780368 -242.429792) (xy 87.602568 -242.73764)
			(xy 87.640922 -242.759738) (xy 87.79637 -242.795298)
		)
		(stroke
			(width 0)
			(type solid)
		)
		(fill yes)
		(layer "In4.Cu")
		(net "M_C_CPU1_SB_CB<4>")
	)
	(gr_poly
		(pts
			(xy 87.928196 -247.450102) (xy 87.819738 -247.333262) (xy 87.781384 -247.311164) (xy 87.603584 -247.619012)
			(xy 87.641938 -247.64111) (xy 87.797386 -247.67667)
		)
		(stroke
			(width 0)
			(type solid)
		)
		(fill yes)
		(layer "In4.Cu")
		(net "M_C_CPU1_SB_CA<2>")
	)
	(gr_poly
		(pts
			(xy 87.962994 -287.898586) (xy 87.962994 -287.85439) (xy 87.607394 -287.85439) (xy 87.607394 -287.898586)
			(xy 87.654384 -288.050986) (xy 87.916004 -288.050986)
		)
		(stroke
			(width 0)
			(type solid)
		)
		(fill yes)
		(layer "In4.Cu")
		(net "M_C_CPU1_SA_DQ<0>")
	)
	(gr_poly
		(pts
			(xy 87.962994 -286.270954) (xy 87.962994 -286.226758) (xy 87.607394 -286.226758) (xy 87.607394 -286.270954)
			(xy 87.654384 -286.423354) (xy 87.916004 -286.423354)
		)
		(stroke
			(width 0)
			(type solid)
		)
		(fill yes)
		(layer "In4.Cu")
		(net "M_C_CPU1_SA_DQ<1>")
	)
	(gr_poly
		(pts
			(xy 87.962994 -273.657314) (xy 87.916004 -273.504914) (xy 87.654384 -273.504914) (xy 87.607394 -273.657314)
			(xy 87.607394 -273.701764) (xy 87.962994 -273.701764)
		)
		(stroke
			(width 0)
			(type solid)
		)
		(fill yes)
		(layer "In4.Cu")
		(net "M_B_CPU1_SA_DQ<11>")
	)
	(gr_poly
		(pts
			(xy 87.962994 -273.248882) (xy 87.962994 -273.204432) (xy 87.607394 -273.204432) (xy 87.607394 -273.248882)
			(xy 87.654384 -273.401282) (xy 87.916004 -273.401282)
		)
		(stroke
			(width 0)
			(type solid)
		)
		(fill yes)
		(layer "In4.Cu")
		(net "M_B_CPU1_SA_DQS_DP<1>")
	)
	(gr_poly
		(pts
			(xy 87.962994 -272.029682) (xy 87.916004 -271.877282) (xy 87.654384 -271.877282) (xy 87.607394 -272.029682)
			(xy 87.607394 -272.073878) (xy 87.962994 -272.073878)
		)
		(stroke
			(width 0)
			(type solid)
		)
		(fill yes)
		(layer "In4.Cu")
		(net "M_B_CPU1_SA_DQS_DP<6>")
	)
	(gr_poly
		(pts
			(xy 87.962994 -271.620742) (xy 87.962994 -271.576546) (xy 87.607394 -271.576546) (xy 87.607394 -271.620742)
			(xy 87.654384 -271.773142) (xy 87.916004 -271.773142)
		)
		(stroke
			(width 0)
			(type solid)
		)
		(fill yes)
		(layer "In4.Cu")
		(net "M_B_CPU1_SA_DQ<12>")
	)
	(gr_poly
		(pts
			(xy 87.962994 -270.40205) (xy 87.916004 -270.24965) (xy 87.654384 -270.24965) (xy 87.607394 -270.40205)
			(xy 87.607394 -270.446246) (xy 87.962994 -270.446246)
		)
		(stroke
			(width 0)
			(type solid)
		)
		(fill yes)
		(layer "In4.Cu")
		(net "M_B_CPU1_SA_DQ<15>")
	)
	(gr_poly
		(pts
			(xy 87.962994 -269.99311) (xy 87.962994 -269.948914) (xy 87.607394 -269.948914) (xy 87.607394 -269.99311)
			(xy 87.654384 -270.14551) (xy 87.916004 -270.14551)
		)
		(stroke
			(width 0)
			(type solid)
		)
		(fill yes)
		(layer "In4.Cu")
		(net "M_C_CPU1_SA_DQ<16>")
	)
	(gr_poly
		(pts
			(xy 87.962994 -268.77391) (xy 87.916004 -268.62151) (xy 87.654384 -268.62151) (xy 87.607394 -268.77391)
			(xy 87.607394 -268.81836) (xy 87.962994 -268.81836)
		)
		(stroke
			(width 0)
			(type solid)
		)
		(fill yes)
		(layer "In4.Cu")
		(net "M_C_CPU1_SA_DQ<19>")
	)
	(gr_poly
		(pts
			(xy 87.962994 -268.365478) (xy 87.962994 -268.321028) (xy 87.607394 -268.321028) (xy 87.607394 -268.365478)
			(xy 87.654384 -268.517878) (xy 87.916004 -268.517878)
		)
		(stroke
			(width 0)
			(type solid)
		)
		(fill yes)
		(layer "In4.Cu")
		(net "M_C_CPU1_SA_DQS_DP<2>")
	)
	(gr_poly
		(pts
			(xy 87.962994 -267.146278) (xy 87.916004 -266.993878) (xy 87.654384 -266.993878) (xy 87.607394 -267.146278)
			(xy 87.607394 -267.190474) (xy 87.962994 -267.190474)
		)
		(stroke
			(width 0)
			(type solid)
		)
		(fill yes)
		(layer "In4.Cu")
		(net "M_C_CPU1_SA_DQS_DP<7>")
	)
	(gr_poly
		(pts
			(xy 87.962994 -266.737846) (xy 87.962994 -266.693396) (xy 87.607394 -266.693396) (xy 87.607394 -266.737846)
			(xy 87.654384 -266.890246) (xy 87.916004 -266.890246)
		)
		(stroke
			(width 0)
			(type solid)
		)
		(fill yes)
		(layer "In4.Cu")
		(net "M_C_CPU1_SA_DQ<20>")
	)
	(gr_poly
		(pts
			(xy 87.962994 -265.518646) (xy 87.916004 -265.366246) (xy 87.654384 -265.366246) (xy 87.607394 -265.518646)
			(xy 87.607394 -265.562842) (xy 87.962994 -265.562842)
		)
		(stroke
			(width 0)
			(type solid)
		)
		(fill yes)
		(layer "In4.Cu")
		(net "M_C_CPU1_SA_DQ<23>")
	)
	(gr_poly
		(pts
			(xy 87.962994 -265.109706) (xy 87.962994 -265.06551) (xy 87.607394 -265.06551) (xy 87.607394 -265.109706)
			(xy 87.654384 -265.262106) (xy 87.916004 -265.262106)
		)
		(stroke
			(width 0)
			(type solid)
		)
		(fill yes)
		(layer "In4.Cu")
		(net "M_B_CPU1_SA_DQ<26>")
	)
	(gr_poly
		(pts
			(xy 87.962994 -263.891014) (xy 87.916004 -263.738614) (xy 87.654384 -263.738614) (xy 87.607394 -263.891014)
			(xy 87.607394 -263.93521) (xy 87.962994 -263.93521)
		)
		(stroke
			(width 0)
			(type solid)
		)
		(fill yes)
		(layer "In4.Cu")
		(net "M_B_CPU1_SA_DQ<27>")
	)
	(gr_poly
		(pts
			(xy 87.962994 -263.482074) (xy 87.962994 -263.437878) (xy 87.607394 -263.437878) (xy 87.607394 -263.482074)
			(xy 87.654384 -263.634474) (xy 87.916004 -263.634474)
		)
		(stroke
			(width 0)
			(type solid)
		)
		(fill yes)
		(layer "In4.Cu")
		(net "M_B_CPU1_SA_DQS_DP<3>")
	)
	(gr_poly
		(pts
			(xy 87.962994 -262.262874) (xy 87.916004 -262.110474) (xy 87.654384 -262.110474) (xy 87.607394 -262.262874)
			(xy 87.607394 -262.307324) (xy 87.962994 -262.307324)
		)
		(stroke
			(width 0)
			(type solid)
		)
		(fill yes)
		(layer "In4.Cu")
		(net "M_B_CPU1_SA_DQS_DP<8>")
	)
	(gr_poly
		(pts
			(xy 87.962994 -261.854442) (xy 87.962994 -261.809992) (xy 87.607394 -261.809992) (xy 87.607394 -261.854442)
			(xy 87.654384 -262.006842) (xy 87.916004 -262.006842)
		)
		(stroke
			(width 0)
			(type solid)
		)
		(fill yes)
		(layer "In4.Cu")
		(net "M_B_CPU1_SA_DQ<28>")
	)
	(gr_poly
		(pts
			(xy 87.962994 -260.635242) (xy 87.916004 -260.482842) (xy 87.654384 -260.482842) (xy 87.607394 -260.635242)
			(xy 87.607394 -260.679438) (xy 87.962994 -260.679438)
		)
		(stroke
			(width 0)
			(type solid)
		)
		(fill yes)
		(layer "In4.Cu")
		(net "M_B_CPU1_SA_DQ<31>")
	)
	(gr_poly
		(pts
			(xy 87.962994 -258.59867) (xy 87.962994 -258.554474) (xy 87.607394 -258.554474) (xy 87.607394 -258.59867)
			(xy 87.654384 -258.75107) (xy 87.916004 -258.75107)
		)
		(stroke
			(width 0)
			(type solid)
		)
		(fill yes)
		(layer "In4.Cu")
		(net "M_C_CPU1_SA_CS_N<0>")
	)
	(gr_poly
		(pts
			(xy 87.962994 -257.37947) (xy 87.916004 -257.22707) (xy 87.654384 -257.22707) (xy 87.607394 -257.37947)
			(xy 87.607394 -257.42392) (xy 87.962994 -257.42392)
		)
		(stroke
			(width 0)
			(type solid)
		)
		(fill yes)
		(layer "In4.Cu")
		(net "M_C_CPU1_SA_CS_N<3>")
	)
	(gr_poly
		(pts
			(xy 87.962994 -256.971038) (xy 87.962994 -256.926588) (xy 87.607394 -256.926588) (xy 87.607394 -256.971038)
			(xy 87.654384 -257.123438) (xy 87.916004 -257.123438)
		)
		(stroke
			(width 0)
			(type solid)
		)
		(fill yes)
		(layer "In4.Cu")
		(net "M_C_CPU1_SA_CA<0>")
	)
	(gr_poly
		(pts
			(xy 87.962994 -255.751838) (xy 87.916004 -255.599438) (xy 87.654384 -255.599438) (xy 87.607394 -255.751838)
			(xy 87.607394 -255.796288) (xy 87.962994 -255.796288)
		)
		(stroke
			(width 0)
			(type solid)
		)
		(fill yes)
		(layer "In4.Cu")
		(net "M_C_CPU1_SA_CA<3>")
	)
	(gr_poly
		(pts
			(xy 87.962994 -255.343406) (xy 87.962994 -255.298956) (xy 87.607394 -255.298956) (xy 87.607394 -255.343406)
			(xy 87.654384 -255.495806) (xy 87.916004 -255.495806)
		)
		(stroke
			(width 0)
			(type solid)
		)
		(fill yes)
		(layer "In4.Cu")
		(net "M_C_CPU1_SA_CA<4>")
	)
	(gr_poly
		(pts
			(xy 87.962994 -254.124206) (xy 87.916004 -253.971806) (xy 87.654384 -253.971806) (xy 87.607394 -254.124206)
			(xy 87.607394 -254.168402) (xy 87.962994 -254.168402)
		)
		(stroke
			(width 0)
			(type solid)
		)
		(fill yes)
		(layer "In4.Cu")
		(net "M_C_CPU1_SA_PAR")
	)
	(gr_poly
		(pts
			(xy 87.96909 -281.79649) (xy 87.9221 -281.64409) (xy 87.66048 -281.64409) (xy 87.61349 -281.79649)
			(xy 87.61349 -281.840686) (xy 87.96909 -281.840686)
		)
		(stroke
			(width 0)
			(type solid)
		)
		(fill yes)
		(layer "In4.Cu")
		(net "M_C_CPU1_SA_DQS_DP<5>")
	)
	(gr_poly
		(pts
			(xy 87.96909 -281.38755) (xy 87.96909 -281.343354) (xy 87.61349 -281.343354) (xy 87.61349 -281.38755)
			(xy 87.66048 -281.53995) (xy 87.9221 -281.53995)
		)
		(stroke
			(width 0)
			(type solid)
		)
		(fill yes)
		(layer "In4.Cu")
		(net "M_C_CPU1_SA_DQ<4>")
	)
	(gr_poly
		(pts
			(xy 88.036908 -278.610822) (xy 87.92845 -278.493982) (xy 87.890096 -278.471884) (xy 87.712296 -278.779732)
			(xy 87.75065 -278.80183) (xy 87.906098 -278.83739)
		)
		(stroke
			(width 0)
			(type solid)
		)
		(fill yes)
		(layer "In4.Cu")
		(net "M_C_CPU1_SA_DQ<5>")
	)
	(gr_poly
		(pts
			(xy 88.037924 -285.119318) (xy 87.929466 -285.002478) (xy 87.891112 -284.98038) (xy 87.713312 -285.288228)
			(xy 87.751666 -285.310326) (xy 87.907114 -285.345886)
		)
		(stroke
			(width 0)
			(type solid)
		)
		(fill yes)
		(layer "In4.Cu")
		(net "M_C_CPU1_SA_DQS_DP<0>")
	)
	(gr_poly
		(pts
			(xy 88.038432 -275.351748) (xy 87.929974 -275.234908) (xy 87.89162 -275.21281) (xy 87.71382 -275.520658)
			(xy 87.752174 -275.542756) (xy 87.907622 -275.578316)
		)
		(stroke
			(width 0)
			(type solid)
		)
		(fill yes)
		(layer "In4.Cu")
		(net "M_B_CPU1_SA_DQ<8>")
	)
	(gr_poly
		(pts
			(xy 88.31453 -244.940582) (xy 88.26754 -244.788182) (xy 88.00592 -244.788182) (xy 87.95893 -244.940582)
			(xy 87.95893 -244.985032) (xy 88.31453 -244.985032)
		)
		(stroke
			(width 0)
			(type solid)
		)
		(fill yes)
		(layer "In4.Cu")
		(net "M_C_CPU1_SB_PAR")
	)
	(gr_poly
		(pts
			(xy 88.31453 -244.532658) (xy 88.31453 -244.488208) (xy 87.95893 -244.488208) (xy 87.95893 -244.532658)
			(xy 88.00592 -244.685058) (xy 88.26754 -244.685058)
		)
		(stroke
			(width 0)
			(type solid)
		)
		(fill yes)
		(layer "In4.Cu")
		(net "M_C_CPU1_SB_CS_N<2>")
	)
	(gr_poly
		(pts
			(xy 88.31453 -240.057178) (xy 88.26754 -239.904778) (xy 88.00592 -239.904778) (xy 87.95893 -240.057178)
			(xy 87.95893 -240.101628) (xy 88.31453 -240.101628)
		)
		(stroke
			(width 0)
			(type solid)
		)
		(fill yes)
		(layer "In4.Cu")
		(net "M_C_CPU1_SB_DQS_DN<9>")
	)
	(gr_poly
		(pts
			(xy 88.31453 -239.649254) (xy 88.31453 -239.604804) (xy 87.95893 -239.604804) (xy 87.95893 -239.649254)
			(xy 88.00592 -239.801654) (xy 88.26754 -239.801654)
		)
		(stroke
			(width 0)
			(type solid)
		)
		(fill yes)
		(layer "In4.Cu")
		(net "M_C_CPU1_SB_DQS_DN<4>")
	)
	(gr_poly
		(pts
			(xy 88.31453 -235.174282) (xy 88.26754 -235.021882) (xy 88.00592 -235.021882) (xy 87.95893 -235.174282)
			(xy 87.95893 -235.218478) (xy 88.31453 -235.218478)
		)
		(stroke
			(width 0)
			(type solid)
		)
		(fill yes)
		(layer "In4.Cu")
		(net "M_B_CPU1_SB_DQS_DN<0>")
	)
	(gr_poly
		(pts
			(xy 88.31453 -234.76585) (xy 88.31453 -234.721654) (xy 87.95893 -234.721654) (xy 87.95893 -234.76585)
			(xy 88.00592 -234.91825) (xy 88.26754 -234.91825)
		)
		(stroke
			(width 0)
			(type solid)
		)
		(fill yes)
		(layer "In4.Cu")
		(net "M_B_CPU1_SB_DQS_DN<5>")
	)
	(gr_poly
		(pts
			(xy 88.31453 -230.290878) (xy 88.26754 -230.138478) (xy 88.00592 -230.138478) (xy 87.95893 -230.290878)
			(xy 87.95893 -230.335074) (xy 88.31453 -230.335074)
		)
		(stroke
			(width 0)
			(type solid)
		)
		(fill yes)
		(layer "In4.Cu")
		(net "M_C_CPU1_SB_DQS_DN<2>")
	)
	(gr_poly
		(pts
			(xy 88.31453 -229.882446) (xy 88.31453 -229.83825) (xy 87.95893 -229.83825) (xy 87.95893 -229.882446)
			(xy 88.00592 -230.034846) (xy 88.26754 -230.034846)
		)
		(stroke
			(width 0)
			(type solid)
		)
		(fill yes)
		(layer "In4.Cu")
		(net "M_C_CPU1_SB_DQS_DN<7>")
	)
	(gr_poly
		(pts
			(xy 88.31707 -246.568722) (xy 88.27008 -246.416322) (xy 88.00846 -246.416322) (xy 87.96147 -246.568722)
			(xy 87.96147 -246.613172) (xy 88.31707 -246.613172)
		)
		(stroke
			(width 0)
			(type solid)
		)
		(fill yes)
		(layer "In4.Cu")
		(net "M_C_CPU1_SB_CA<3>")
	)
	(gr_poly
		(pts
			(xy 88.31707 -246.16029) (xy 88.31707 -246.11584) (xy 87.96147 -246.11584) (xy 87.96147 -246.16029)
			(xy 88.00846 -246.31269) (xy 88.27008 -246.31269)
		)
		(stroke
			(width 0)
			(type solid)
		)
		(fill yes)
		(layer "In4.Cu")
		(net "M_C_CPU1_SB_CA<4>")
	)
	(gr_poly
		(pts
			(xy 88.31707 -243.313458) (xy 88.27008 -243.161058) (xy 88.00846 -243.161058) (xy 87.96147 -243.313458)
			(xy 87.96147 -243.357654) (xy 88.31707 -243.357654)
		)
		(stroke
			(width 0)
			(type solid)
		)
		(fill yes)
		(layer "In4.Cu")
		(net "M_C_CPU1_SB_CS_N<1>")
	)
	(gr_poly
		(pts
			(xy 88.31707 -241.685318) (xy 88.27008 -241.532918) (xy 88.00846 -241.532918) (xy 87.96147 -241.685318)
			(xy 87.96147 -241.729768) (xy 88.31707 -241.729768)
		)
		(stroke
			(width 0)
			(type solid)
		)
		(fill yes)
		(layer "In4.Cu")
		(net "M_C_CPU1_SB_CB<6>")
	)
	(gr_poly
		(pts
			(xy 88.31707 -241.276886) (xy 88.31707 -241.232436) (xy 87.96147 -241.232436) (xy 87.96147 -241.276886)
			(xy 88.00846 -241.429286) (xy 88.27008 -241.429286)
		)
		(stroke
			(width 0)
			(type solid)
		)
		(fill yes)
		(layer "In4.Cu")
		(net "M_C_CPU1_SB_CB<5>")
	)
	(gr_poly
		(pts
			(xy 88.31707 -238.430054) (xy 88.27008 -238.277654) (xy 88.00846 -238.277654) (xy 87.96147 -238.430054)
			(xy 87.96147 -238.47425) (xy 88.31707 -238.47425)
		)
		(stroke
			(width 0)
			(type solid)
		)
		(fill yes)
		(layer "In4.Cu")
		(net "M_C_CPU1_SB_CB<2>")
	)
	(gr_poly
		(pts
			(xy 88.31707 -233.54665) (xy 88.27008 -233.39425) (xy 88.00846 -233.39425) (xy 87.96147 -233.54665)
			(xy 87.96147 -233.590846) (xy 88.31707 -233.590846)
		)
		(stroke
			(width 0)
			(type solid)
		)
		(fill yes)
		(layer "In4.Cu")
		(net "M_B_CPU1_SB_DQ<6>")
	)
	(gr_poly
		(pts
			(xy 88.31707 -228.254814) (xy 88.31707 -228.210364) (xy 87.96147 -228.210364) (xy 87.96147 -228.254814)
			(xy 88.00846 -228.407214) (xy 88.27008 -228.407214)
		)
		(stroke
			(width 0)
			(type solid)
		)
		(fill yes)
		(layer "In4.Cu")
		(net "M_C_CPU1_SB_DQ<21>")
	)
	(gr_poly
		(pts
			(xy 88.322658 -283.600398) (xy 88.284304 -283.5783) (xy 88.128856 -283.54274) (xy 87.998046 -283.769308)
			(xy 88.106504 -283.886148) (xy 88.144858 -283.908246)
		)
		(stroke
			(width 0)
			(type solid)
		)
		(fill yes)
		(layer "In4.Cu")
		(net "M_C_CPU1_SA_DQS_DN<0>")
	)
	(gr_poly
		(pts
			(xy 88.322912 -238.021114) (xy 88.322912 -237.976664) (xy 87.967312 -237.976664) (xy 87.967312 -238.021114)
			(xy 88.014302 -238.173514) (xy 88.275922 -238.173514)
		)
		(stroke
			(width 0)
			(type solid)
		)
		(fill yes)
		(layer "In4.Cu")
		(net "M_C_CPU1_SB_CB<1>")
	)
	(gr_poly
		(pts
			(xy 88.322912 -233.13771) (xy 88.322912 -233.093514) (xy 87.967312 -233.093514) (xy 87.967312 -233.13771)
			(xy 88.014302 -233.29011) (xy 88.275922 -233.29011)
		)
		(stroke
			(width 0)
			(type solid)
		)
		(fill yes)
		(layer "In4.Cu")
		(net "M_B_CPU1_SB_DQ<5>")
	)
	(gr_poly
		(pts
			(xy 88.322912 -231.919018) (xy 88.275922 -231.766618) (xy 88.014302 -231.766618) (xy 87.967312 -231.919018)
			(xy 87.967312 -231.963214) (xy 88.322912 -231.963214)
		)
		(stroke
			(width 0)
			(type solid)
		)
		(fill yes)
		(layer "In4.Cu")
		(net "M_C_CPU1_SB_DQ<18>")
	)
	(gr_poly
		(pts
			(xy 88.322912 -231.510078) (xy 88.322912 -231.465628) (xy 87.967312 -231.465628) (xy 87.967312 -231.510078)
			(xy 88.014302 -231.662478) (xy 88.275922 -231.662478)
		)
		(stroke
			(width 0)
			(type solid)
		)
		(fill yes)
		(layer "In4.Cu")
		(net "M_C_CPU1_SB_DQ<17>")
	)
	(gr_poly
		(pts
			(xy 88.322912 -228.663246) (xy 88.275922 -228.510846) (xy 88.014302 -228.510846) (xy 87.967312 -228.663246)
			(xy 87.967312 -228.707696) (xy 88.322912 -228.707696)
		)
		(stroke
			(width 0)
			(type solid)
		)
		(fill yes)
		(layer "In4.Cu")
		(net "M_C_CPU1_SB_DQ<22>")
	)
	(gr_poly
		(pts
			(xy 88.323166 -236.801914) (xy 88.276176 -236.649514) (xy 88.014556 -236.649514) (xy 87.967566 -236.801914)
			(xy 87.967566 -236.846364) (xy 88.323166 -236.846364)
		)
		(stroke
			(width 0)
			(type solid)
		)
		(fill yes)
		(layer "In4.Cu")
		(net "M_B_CPU1_SB_DQ<0>")
	)
	(gr_poly
		(pts
			(xy 88.323166 -236.393482) (xy 88.323166 -236.349286) (xy 87.967566 -236.349286) (xy 87.967566 -236.393482)
			(xy 88.014556 -236.545882) (xy 88.276176 -236.545882)
		)
		(stroke
			(width 0)
			(type solid)
		)
		(fill yes)
		(layer "In4.Cu")
		(net "M_B_CPU1_SB_DQ<1>")
	)
	(gr_poly
		(pts
			(xy 88.326976 -286.84855) (xy 88.288622 -286.826452) (xy 88.133174 -286.790892) (xy 88.002364 -287.01746)
			(xy 88.110822 -287.1343) (xy 88.149176 -287.156398)
		)
		(stroke
			(width 0)
			(type solid)
		)
		(fill yes)
		(layer "In4.Cu")
		(net "M_C_CPU1_SA_DQ<2>")
	)
	(gr_poly
		(pts
			(xy 88.326976 -285.220664) (xy 88.288622 -285.198566) (xy 88.133174 -285.163006) (xy 88.002364 -285.389574)
			(xy 88.110822 -285.506414) (xy 88.149176 -285.528512)
		)
		(stroke
			(width 0)
			(type solid)
		)
		(fill yes)
		(layer "In4.Cu")
		(net "M_C_CPU1_SA_DQ<3>")
	)
	(gr_poly
		(pts
			(xy 88.326976 -278.709628) (xy 88.288622 -278.68753) (xy 88.133174 -278.65197) (xy 88.002364 -278.878538)
			(xy 88.110822 -278.995378) (xy 88.149176 -279.017476)
		)
		(stroke
			(width 0)
			(type solid)
		)
		(fill yes)
		(layer "In4.Cu")
		(net "M_C_CPU1_SA_DQ<6>")
	)
	(gr_poly
		(pts
			(xy 88.327992 -277.07971) (xy 88.289638 -277.057612) (xy 88.13419 -277.022052) (xy 88.00338 -277.24862)
			(xy 88.111838 -277.36546) (xy 88.150192 -277.387558)
		)
		(stroke
			(width 0)
			(type solid)
		)
		(fill yes)
		(layer "In4.Cu")
		(net "M_C_CPU1_SA_DQ<7>")
	)
	(gr_poly
		(pts
			(xy 88.397334 -280.6192) (xy 88.505792 -280.50236) (xy 88.374982 -280.275792) (xy 88.219534 -280.311352)
			(xy 88.18118 -280.33345) (xy 88.35898 -280.641298)
		)
		(stroke
			(width 0)
			(type solid)
		)
		(fill yes)
		(layer "In4.Cu")
		(net "M_C_CPU1_SA_DQ<4>")
	)
	(gr_poly
		(pts
			(xy 88.432894 -274.47113) (xy 88.385904 -274.31873) (xy 88.124284 -274.31873) (xy 88.077294 -274.47113)
			(xy 88.077294 -274.51558) (xy 88.432894 -274.51558)
		)
		(stroke
			(width 0)
			(type solid)
		)
		(fill yes)
		(layer "In4.Cu")
		(net "M_B_CPU1_SA_DQ<10>")
	)
	(gr_poly
		(pts
			(xy 88.432894 -274.062698) (xy 88.432894 -274.018248) (xy 88.077294 -274.018248) (xy 88.077294 -274.062698)
			(xy 88.124284 -274.215098) (xy 88.385904 -274.215098)
		)
		(stroke
			(width 0)
			(type solid)
		)
		(fill yes)
		(layer "In4.Cu")
		(net "M_B_CPU1_SA_DQ<9>")
	)
	(gr_poly
		(pts
			(xy 88.432894 -271.215866) (xy 88.385904 -271.063466) (xy 88.124284 -271.063466) (xy 88.077294 -271.215866)
			(xy 88.077294 -271.260062) (xy 88.432894 -271.260062)
		)
		(stroke
			(width 0)
			(type solid)
		)
		(fill yes)
		(layer "In4.Cu")
		(net "M_B_CPU1_SA_DQ<14>")
	)
	(gr_poly
		(pts
			(xy 88.432894 -269.587726) (xy 88.385904 -269.435326) (xy 88.124284 -269.435326) (xy 88.077294 -269.587726)
			(xy 88.077294 -269.632176) (xy 88.432894 -269.632176)
		)
		(stroke
			(width 0)
			(type solid)
		)
		(fill yes)
		(layer "In4.Cu")
		(net "M_C_CPU1_SA_DQ<18>")
	)
	(gr_poly
		(pts
			(xy 88.432894 -267.960094) (xy 88.385904 -267.807694) (xy 88.124284 -267.807694) (xy 88.077294 -267.960094)
			(xy 88.077294 -268.004544) (xy 88.432894 -268.004544)
		)
		(stroke
			(width 0)
			(type solid)
		)
		(fill yes)
		(layer "In4.Cu")
		(net "M_C_CPU1_SA_DQS_DN<2>")
	)
	(gr_poly
		(pts
			(xy 88.432894 -267.551662) (xy 88.432894 -267.507212) (xy 88.077294 -267.507212) (xy 88.077294 -267.551662)
			(xy 88.124284 -267.704062) (xy 88.385904 -267.704062)
		)
		(stroke
			(width 0)
			(type solid)
		)
		(fill yes)
		(layer "In4.Cu")
		(net "M_C_CPU1_SA_DQS_DN<7>")
	)
	(gr_poly
		(pts
			(xy 88.432894 -266.332462) (xy 88.385904 -266.180062) (xy 88.124284 -266.180062) (xy 88.077294 -266.332462)
			(xy 88.077294 -266.376658) (xy 88.432894 -266.376658)
		)
		(stroke
			(width 0)
			(type solid)
		)
		(fill yes)
		(layer "In4.Cu")
		(net "M_C_CPU1_SA_DQ<22>")
	)
	(gr_poly
		(pts
			(xy 88.432894 -265.92403) (xy 88.432894 -265.87958) (xy 88.077294 -265.87958) (xy 88.077294 -265.92403)
			(xy 88.124284 -266.07643) (xy 88.385904 -266.07643)
		)
		(stroke
			(width 0)
			(type solid)
		)
		(fill yes)
		(layer "In4.Cu")
		(net "M_C_CPU1_SA_DQ<21>")
	)
	(gr_poly
		(pts
			(xy 88.432894 -264.70483) (xy 88.385904 -264.55243) (xy 88.124284 -264.55243) (xy 88.077294 -264.70483)
			(xy 88.077294 -264.749026) (xy 88.432894 -264.749026)
		)
		(stroke
			(width 0)
			(type solid)
		)
		(fill yes)
		(layer "In4.Cu")
		(net "M_B_CPU1_SA_DQ<24>")
	)
	(gr_poly
		(pts
			(xy 88.432894 -264.29589) (xy 88.432894 -264.251694) (xy 88.077294 -264.251694) (xy 88.077294 -264.29589)
			(xy 88.124284 -264.44829) (xy 88.385904 -264.44829)
		)
		(stroke
			(width 0)
			(type solid)
		)
		(fill yes)
		(layer "In4.Cu")
		(net "M_B_CPU1_SA_DQ<25>")
	)
	(gr_poly
		(pts
			(xy 88.432894 -263.07669) (xy 88.385904 -262.92429) (xy 88.124284 -262.92429) (xy 88.077294 -263.07669)
			(xy 88.077294 -263.12114) (xy 88.432894 -263.12114)
		)
		(stroke
			(width 0)
			(type solid)
		)
		(fill yes)
		(layer "In4.Cu")
		(net "M_B_CPU1_SA_DQS_DN<3>")
	)
	(gr_poly
		(pts
			(xy 88.432894 -262.668258) (xy 88.432894 -262.623808) (xy 88.077294 -262.623808) (xy 88.077294 -262.668258)
			(xy 88.124284 -262.820658) (xy 88.385904 -262.820658)
		)
		(stroke
			(width 0)
			(type solid)
		)
		(fill yes)
		(layer "In4.Cu")
		(net "M_B_CPU1_SA_DQS_DN<8>")
	)
	(gr_poly
		(pts
			(xy 88.432894 -261.449058) (xy 88.385904 -261.296658) (xy 88.124284 -261.296658) (xy 88.077294 -261.449058)
			(xy 88.077294 -261.493508) (xy 88.432894 -261.493508)
		)
		(stroke
			(width 0)
			(type solid)
		)
		(fill yes)
		(layer "In4.Cu")
		(net "M_B_CPU1_SA_DQ<30>")
	)
	(gr_poly
		(pts
			(xy 88.432894 -261.040626) (xy 88.432894 -260.996176) (xy 88.077294 -260.996176) (xy 88.077294 -261.040626)
			(xy 88.124284 -261.193026) (xy 88.385904 -261.193026)
		)
		(stroke
			(width 0)
			(type solid)
		)
		(fill yes)
		(layer "In4.Cu")
		(net "M_B_CPU1_SA_DQ<29>")
	)
	(gr_poly
		(pts
			(xy 88.432894 -258.193286) (xy 88.385904 -258.040886) (xy 88.124284 -258.040886) (xy 88.077294 -258.193286)
			(xy 88.077294 -258.237736) (xy 88.432894 -258.237736)
		)
		(stroke
			(width 0)
			(type solid)
		)
		(fill yes)
		(layer "In4.Cu")
		(net "M_C_CPU1_SA_CS_N<2>")
	)
	(gr_poly
		(pts
			(xy 88.432894 -257.784854) (xy 88.432894 -257.740404) (xy 88.077294 -257.740404) (xy 88.077294 -257.784854)
			(xy 88.124284 -257.937254) (xy 88.385904 -257.937254)
		)
		(stroke
			(width 0)
			(type solid)
		)
		(fill yes)
		(layer "In4.Cu")
		(net "M_C_CPU1_SA_CS_N<1>")
	)
	(gr_poly
		(pts
			(xy 88.432894 -256.565654) (xy 88.385904 -256.413254) (xy 88.124284 -256.413254) (xy 88.077294 -256.565654)
			(xy 88.077294 -256.610104) (xy 88.432894 -256.610104)
		)
		(stroke
			(width 0)
			(type solid)
		)
		(fill yes)
		(layer "In4.Cu")
		(net "M_C_CPU1_SA_CA<1>")
	)
	(gr_poly
		(pts
			(xy 88.432894 -256.157222) (xy 88.432894 -256.112772) (xy 88.077294 -256.112772) (xy 88.077294 -256.157222)
			(xy 88.124284 -256.309622) (xy 88.385904 -256.309622)
		)
		(stroke
			(width 0)
			(type solid)
		)
		(fill yes)
		(layer "In4.Cu")
		(net "M_C_CPU1_SA_CA<2>")
	)
	(gr_poly
		(pts
			(xy 88.432894 -254.938022) (xy 88.385904 -254.785622) (xy 88.124284 -254.785622) (xy 88.077294 -254.938022)
			(xy 88.077294 -254.982218) (xy 88.432894 -254.982218)
		)
		(stroke
			(width 0)
			(type solid)
		)
		(fill yes)
		(layer "In4.Cu")
		(net "M_C_CPU1_SA_CA<5>")
	)
	(gr_poly
		(pts
			(xy 88.432894 -254.529082) (xy 88.432894 -254.484886) (xy 88.077294 -254.484886) (xy 88.077294 -254.529082)
			(xy 88.124284 -254.681482) (xy 88.385904 -254.681482)
		)
		(stroke
			(width 0)
			(type solid)
		)
		(fill yes)
		(layer "In4.Cu")
		(net "M_C_CPU1_SA_CA<6>")
	)
	(gr_poly
		(pts
			(xy 88.43518 -270.806926) (xy 88.43518 -270.76273) (xy 88.07958 -270.76273) (xy 88.07958 -270.806926)
			(xy 88.12657 -270.959326) (xy 88.38819 -270.959326)
		)
		(stroke
			(width 0)
			(type solid)
		)
		(fill yes)
		(layer "In4.Cu")
		(net "M_B_CPU1_SA_DQ<13>")
	)
	(gr_poly
		(pts
			(xy 88.43518 -269.179294) (xy 88.43518 -269.134844) (xy 88.07958 -269.134844) (xy 88.07958 -269.179294)
			(xy 88.12657 -269.331694) (xy 88.38819 -269.331694)
		)
		(stroke
			(width 0)
			(type solid)
		)
		(fill yes)
		(layer "In4.Cu")
		(net "M_C_CPU1_SA_DQ<17>")
	)
	(gr_poly
		(pts
			(xy 88.43899 -282.201874) (xy 88.43899 -282.157424) (xy 88.08339 -282.157424) (xy 88.08339 -282.201874)
			(xy 88.13038 -282.354274) (xy 88.392 -282.354274)
		)
		(stroke
			(width 0)
			(type solid)
		)
		(fill yes)
		(layer "In4.Cu")
		(net "M_C_CPU1_SA_DQS_DN<5>")
	)
	(gr_poly
		(pts
			(xy 88.43899 -272.843498) (xy 88.392 -272.691098) (xy 88.13038 -272.691098) (xy 88.08339 -272.843498)
			(xy 88.08339 -272.887694) (xy 88.43899 -272.887694)
		)
		(stroke
			(width 0)
			(type solid)
		)
		(fill yes)
		(layer "In4.Cu")
		(net "M_B_CPU1_SA_DQS_DN<1>")
	)
	(gr_poly
		(pts
			(xy 88.43899 -272.435066) (xy 88.43899 -272.39087) (xy 88.08339 -272.39087) (xy 88.08339 -272.435066)
			(xy 88.13038 -272.587466) (xy 88.392 -272.587466)
		)
		(stroke
			(width 0)
			(type solid)
		)
		(fill yes)
		(layer "In4.Cu")
		(net "M_B_CPU1_SA_DQS_DN<6>")
	)
	(gr_poly
		(pts
			(xy 88.505792 -285.937198) (xy 88.397334 -285.820358) (xy 88.35898 -285.79826) (xy 88.18118 -286.106108)
			(xy 88.219534 -286.128206) (xy 88.374982 -286.163766)
		)
		(stroke
			(width 0)
			(type solid)
		)
		(fill yes)
		(layer "In4.Cu")
		(net "M_C_CPU1_SA_DQ<1>")
	)
	(gr_poly
		(pts
			(xy 88.506554 -277.797006) (xy 88.398096 -277.680166) (xy 88.359742 -277.658068) (xy 88.181942 -277.965916)
			(xy 88.220296 -277.988014) (xy 88.375744 -278.023574)
		)
		(stroke
			(width 0)
			(type solid)
		)
		(fill yes)
		(layer "In4.Cu")
		(net "M_C_CPU1_SA_DQ<5>")
	)
	(gr_poly
		(pts
			(xy 88.507824 -287.56102) (xy 88.399366 -287.44418) (xy 88.361012 -287.422082) (xy 88.183212 -287.72993)
			(xy 88.221566 -287.752028) (xy 88.377014 -287.787588)
		)
		(stroke
			(width 0)
			(type solid)
		)
		(fill yes)
		(layer "In4.Cu")
		(net "M_C_CPU1_SA_DQ<0>")
	)
	(gr_poly
		(pts
			(xy 88.507824 -281.049984) (xy 88.399366 -280.933144) (xy 88.361012 -280.911046) (xy 88.183212 -281.218894)
			(xy 88.221566 -281.240992) (xy 88.377014 -281.276552)
		)
		(stroke
			(width 0)
			(type solid)
		)
		(fill yes)
		(layer "In4.Cu")
		(net "M_C_CPU1_SA_DQ<4>")
	)
	(gr_poly
		(pts
			(xy 88.507824 -279.422098) (xy 88.399366 -279.305258) (xy 88.361012 -279.28316) (xy 88.183212 -279.591008)
			(xy 88.221566 -279.613106) (xy 88.377014 -279.648666)
		)
		(stroke
			(width 0)
			(type solid)
		)
		(fill yes)
		(layer "In4.Cu")
		(net "M_C_CPU1_SA_DQ<4>")
	)
	(gr_poly
		(pts
			(xy 88.514174 -284.295342) (xy 88.405716 -284.178502) (xy 88.367362 -284.156404) (xy 88.189562 -284.464252)
			(xy 88.227916 -284.48635) (xy 88.383364 -284.52191)
		)
		(stroke
			(width 0)
			(type solid)
		)
		(fill yes)
		(layer "In4.Cu")
		(net "M_C_CPU1_SA_DQS_DP<0>")
	)
	(gr_poly
		(pts
			(xy 88.760554 -280.430986) (xy 88.798908 -280.408888) (xy 88.621108 -280.10104) (xy 88.582754 -280.123138)
			(xy 88.474296 -280.239978) (xy 88.605106 -280.466546)
		)
		(stroke
			(width 0)
			(type solid)
		)
		(fill yes)
		(layer "In4.Cu")
		(net "M_C_CPU1_SA_DQS_DP<5>")
	)
	(gr_poly
		(pts
			(xy 88.78697 -245.346474) (xy 88.78697 -245.302024) (xy 88.43137 -245.302024) (xy 88.43137 -245.346474)
			(xy 88.47836 -245.498874) (xy 88.73998 -245.498874)
		)
		(stroke
			(width 0)
			(type solid)
		)
		(fill yes)
		(layer "In4.Cu")
		(net "M_C_CPU1_SB_CA<6>")
	)
	(gr_poly
		(pts
			(xy 88.789764 -229.068122) (xy 88.789764 -229.023926) (xy 88.434164 -229.023926) (xy 88.434164 -229.068122)
			(xy 88.481154 -229.220522) (xy 88.742774 -229.220522)
		)
		(stroke
			(width 0)
			(type solid)
		)
		(fill yes)
		(layer "In4.Cu")
		(net "M_C_CPU1_SB_DQ<20>")
	)
	(gr_poly
		(pts
			(xy 88.790272 -240.871502) (xy 88.743282 -240.719102) (xy 88.481662 -240.719102) (xy 88.434672 -240.871502)
			(xy 88.434672 -240.915952) (xy 88.790272 -240.915952)
		)
		(stroke
			(width 0)
			(type solid)
		)
		(fill yes)
		(layer "In4.Cu")
		(net "M_C_CPU1_SB_CB<7>")
	)
	(gr_poly
		(pts
			(xy 88.790272 -240.46307) (xy 88.790272 -240.41862) (xy 88.434672 -240.41862) (xy 88.434672 -240.46307)
			(xy 88.481662 -240.61547) (xy 88.743282 -240.61547)
		)
		(stroke
			(width 0)
			(type solid)
		)
		(fill yes)
		(layer "In4.Cu")
		(net "M_C_CPU1_SB_DQS_DP<9>")
	)
	(gr_poly
		(pts
			(xy 88.790272 -238.83493) (xy 88.790272 -238.790734) (xy 88.434672 -238.790734) (xy 88.434672 -238.83493)
			(xy 88.481662 -238.98733) (xy 88.743282 -238.98733)
		)
		(stroke
			(width 0)
			(type solid)
		)
		(fill yes)
		(layer "In4.Cu")
		(net "M_C_CPU1_SB_CB<0>")
	)
	(gr_poly
		(pts
			(xy 88.790272 -237.616238) (xy 88.743282 -237.463838) (xy 88.481662 -237.463838) (xy 88.434672 -237.616238)
			(xy 88.434672 -237.660434) (xy 88.790272 -237.660434)
		)
		(stroke
			(width 0)
			(type solid)
		)
		(fill yes)
		(layer "In4.Cu")
		(net "M_C_CPU1_SB_CB<3>")
	)
	(gr_poly
		(pts
			(xy 88.790272 -235.988606) (xy 88.743282 -235.836206) (xy 88.481662 -235.836206) (xy 88.434672 -235.988606)
			(xy 88.434672 -236.032802) (xy 88.790272 -236.032802)
		)
		(stroke
			(width 0)
			(type solid)
		)
		(fill yes)
		(layer "In4.Cu")
		(net "M_B_CPU1_SB_DQ<3>")
	)
	(gr_poly
		(pts
			(xy 88.790272 -233.951526) (xy 88.790272 -233.90733) (xy 88.434672 -233.90733) (xy 88.434672 -233.951526)
			(xy 88.481662 -234.103926) (xy 88.743282 -234.103926)
		)
		(stroke
			(width 0)
			(type solid)
		)
		(fill yes)
		(layer "In4.Cu")
		(net "M_B_CPU1_SB_DQ<4>")
	)
	(gr_poly
		(pts
			(xy 88.790272 -232.732834) (xy 88.743282 -232.580434) (xy 88.481662 -232.580434) (xy 88.434672 -232.732834)
			(xy 88.434672 -232.77703) (xy 88.790272 -232.77703)
		)
		(stroke
			(width 0)
			(type solid)
		)
		(fill yes)
		(layer "In4.Cu")
		(net "M_B_CPU1_SB_DQ<7>")
	)
	(gr_poly
		(pts
			(xy 88.790272 -232.323894) (xy 88.790272 -232.279698) (xy 88.434672 -232.279698) (xy 88.434672 -232.323894)
			(xy 88.481662 -232.476294) (xy 88.743282 -232.476294)
		)
		(stroke
			(width 0)
			(type solid)
		)
		(fill yes)
		(layer "In4.Cu")
		(net "M_C_CPU1_SB_DQ<16>")
	)
	(gr_poly
		(pts
			(xy 88.790272 -231.105202) (xy 88.743282 -230.952802) (xy 88.481662 -230.952802) (xy 88.434672 -231.105202)
			(xy 88.434672 -231.149398) (xy 88.790272 -231.149398)
		)
		(stroke
			(width 0)
			(type solid)
		)
		(fill yes)
		(layer "In4.Cu")
		(net "M_C_CPU1_SB_DQ<19>")
	)
	(gr_poly
		(pts
			(xy 88.790272 -230.696262) (xy 88.790272 -230.651812) (xy 88.434672 -230.651812) (xy 88.434672 -230.696262)
			(xy 88.481662 -230.848662) (xy 88.743282 -230.848662)
		)
		(stroke
			(width 0)
			(type solid)
		)
		(fill yes)
		(layer "In4.Cu")
		(net "M_C_CPU1_SB_DQS_DP<2>")
	)
	(gr_poly
		(pts
			(xy 88.790272 -229.477062) (xy 88.743282 -229.324662) (xy 88.481662 -229.324662) (xy 88.434672 -229.477062)
			(xy 88.434672 -229.521512) (xy 88.790272 -229.521512)
		)
		(stroke
			(width 0)
			(type solid)
		)
		(fill yes)
		(layer "In4.Cu")
		(net "M_C_CPU1_SB_DQS_DP<7>")
	)
	(gr_poly
		(pts
			(xy 88.792558 -284.41396) (xy 88.754204 -284.391862) (xy 88.598756 -284.356302) (xy 88.467946 -284.58287)
			(xy 88.576404 -284.69971) (xy 88.614758 -284.721808)
		)
		(stroke
			(width 0)
			(type solid)
		)
		(fill yes)
		(layer "In4.Cu")
		(net "M_C_CPU1_SA_DQ<3>")
	)
	(gr_poly
		(pts
			(xy 88.792558 -281.158696) (xy 88.754204 -281.136598) (xy 88.598756 -281.101038) (xy 88.467946 -281.327606)
			(xy 88.576404 -281.444446) (xy 88.614758 -281.466544)
		)
		(stroke
			(width 0)
			(type solid)
		)
		(fill yes)
		(layer "In4.Cu")
		(net "M_C_CPU1_SA_DQS_DP<5>")
	)
	(gr_poly
		(pts
			(xy 88.793066 -237.207298) (xy 88.793066 -237.163102) (xy 88.437466 -237.163102) (xy 88.437466 -237.207298)
			(xy 88.484456 -237.359698) (xy 88.746076 -237.359698)
		)
		(stroke
			(width 0)
			(type solid)
		)
		(fill yes)
		(layer "In4.Cu")
		(net "M_B_CPU1_SB_DQ<2>")
	)
	(gr_poly
		(pts
			(xy 88.796876 -279.523444) (xy 88.758522 -279.501346) (xy 88.603074 -279.465786) (xy 88.472264 -279.692354)
			(xy 88.580722 -279.809194) (xy 88.619076 -279.831292)
		)
		(stroke
			(width 0)
			(type solid)
		)
		(fill yes)
		(layer "In4.Cu")
		(net "M_C_CPU1_SA_DQS_DP<5>")
	)
	(gr_poly
		(pts
			(xy 88.796876 -276.267926) (xy 88.758522 -276.245828) (xy 88.603074 -276.210268) (xy 88.472264 -276.436836)
			(xy 88.580722 -276.553676) (xy 88.619076 -276.575774)
		)
		(stroke
			(width 0)
			(type solid)
		)
		(fill yes)
		(layer "In4.Cu")
		(net "M_C_CPU1_SA_DQ<7>")
	)
	(gr_poly
		(pts
			(xy 88.797892 -286.032702) (xy 88.759538 -286.010604) (xy 88.60409 -285.975044) (xy 88.47328 -286.201612)
			(xy 88.581738 -286.318452) (xy 88.620092 -286.34055)
		)
		(stroke
			(width 0)
			(type solid)
		)
		(fill yes)
		(layer "In4.Cu")
		(net "M_C_CPU1_SA_DQ<2>")
	)
	(gr_poly
		(pts
			(xy 88.797892 -282.777184) (xy 88.759538 -282.755086) (xy 88.60409 -282.719526) (xy 88.47328 -282.946094)
			(xy 88.581738 -283.062934) (xy 88.620092 -283.085032)
		)
		(stroke
			(width 0)
			(type solid)
		)
		(fill yes)
		(layer "In4.Cu")
		(net "M_C_CPU1_SA_DQS_DN<0>")
	)
	(gr_poly
		(pts
			(xy 88.797892 -277.89378) (xy 88.759538 -277.871682) (xy 88.60409 -277.836122) (xy 88.47328 -278.06269)
			(xy 88.581738 -278.17953) (xy 88.620092 -278.201628)
		)
		(stroke
			(width 0)
			(type solid)
		)
		(fill yes)
		(layer "In4.Cu")
		(net "M_C_CPU1_SA_DQ<6>")
	)
	(gr_poly
		(pts
			(xy 88.801448 -246.974106) (xy 88.801448 -246.92991) (xy 88.445848 -246.92991) (xy 88.445848 -246.974106)
			(xy 88.492838 -247.126506) (xy 88.754458 -247.126506)
		)
		(stroke
			(width 0)
			(type solid)
		)
		(fill yes)
		(layer "In4.Cu")
		(net "M_C_CPU1_SB_CA<2>")
	)
	(gr_poly
		(pts
			(xy 88.801448 -245.754906) (xy 88.754458 -245.602506) (xy 88.492838 -245.602506) (xy 88.445848 -245.754906)
			(xy 88.445848 -245.799102) (xy 88.801448 -245.799102)
		)
		(stroke
			(width 0)
			(type solid)
		)
		(fill yes)
		(layer "In4.Cu")
		(net "M_C_CPU1_SB_CA<5>")
	)
	(gr_poly
		(pts
			(xy 88.801448 -244.126766) (xy 88.754458 -243.974366) (xy 88.492838 -243.974366) (xy 88.445848 -244.126766)
			(xy 88.445848 -244.171216) (xy 88.801448 -244.171216)
		)
		(stroke
			(width 0)
			(type solid)
		)
		(fill yes)
		(layer "In4.Cu")
		(net "M_C_CPU1_SB_CS_N<0>")
	)
	(gr_poly
		(pts
			(xy 88.801448 -243.718842) (xy 88.801448 -243.674392) (xy 88.445848 -243.674392) (xy 88.445848 -243.718842)
			(xy 88.492838 -243.871242) (xy 88.754458 -243.871242)
		)
		(stroke
			(width 0)
			(type solid)
		)
		(fill yes)
		(layer "In4.Cu")
		(net "M_C_CPU1_SB_CS_N<3>")
	)
	(gr_poly
		(pts
			(xy 88.801448 -242.090702) (xy 88.801448 -242.046506) (xy 88.445848 -242.046506) (xy 88.445848 -242.090702)
			(xy 88.492838 -242.243102) (xy 88.754458 -242.243102)
		)
		(stroke
			(width 0)
			(type solid)
		)
		(fill yes)
		(layer "In4.Cu")
		(net "M_C_CPU1_SB_CB<4>")
	)
	(gr_poly
		(pts
			(xy 88.801448 -239.243362) (xy 88.754458 -239.090962) (xy 88.492838 -239.090962) (xy 88.445848 -239.243362)
			(xy 88.445848 -239.287812) (xy 88.801448 -239.287812)
		)
		(stroke
			(width 0)
			(type solid)
		)
		(fill yes)
		(layer "In4.Cu")
		(net "M_C_CPU1_SB_DQS_DP<4>")
	)
	(gr_poly
		(pts
			(xy 88.801448 -235.579666) (xy 88.801448 -235.53547) (xy 88.445848 -235.53547) (xy 88.445848 -235.579666)
			(xy 88.492838 -235.732066) (xy 88.754458 -235.732066)
		)
		(stroke
			(width 0)
			(type solid)
		)
		(fill yes)
		(layer "In4.Cu")
		(net "M_B_CPU1_SB_DQS_DP<0>")
	)
	(gr_poly
		(pts
			(xy 88.801448 -234.360466) (xy 88.754458 -234.208066) (xy 88.492838 -234.208066) (xy 88.445848 -234.360466)
			(xy 88.445848 -234.404662) (xy 88.801448 -234.404662)
		)
		(stroke
			(width 0)
			(type solid)
		)
		(fill yes)
		(layer "In4.Cu")
		(net "M_B_CPU1_SB_DQS_DP<5>")
	)
	(gr_poly
		(pts
			(xy 88.801448 -227.848922) (xy 88.754458 -227.696522) (xy 88.492838 -227.696522) (xy 88.445848 -227.848922)
			(xy 88.445848 -227.893372) (xy 88.801448 -227.893372)
		)
		(stroke
			(width 0)
			(type solid)
		)
		(fill yes)
		(layer "In4.Cu")
		(net "M_C_CPU1_SB_DQ<23>")
	)
	(gr_poly
		(pts
			(xy 88.894412 -273.248882) (xy 88.894412 -273.204686) (xy 88.538812 -273.204686) (xy 88.538812 -273.248882)
			(xy 88.585802 -273.401282) (xy 88.847422 -273.401282)
		)
		(stroke
			(width 0)
			(type solid)
		)
		(fill yes)
		(layer "In4.Cu")
		(net "M_B_CPU1_SA_DQS_DP<1>")
	)
	(gr_poly
		(pts
			(xy 88.896952 -272.029174) (xy 88.849962 -271.876774) (xy 88.588342 -271.876774) (xy 88.541352 -272.029174)
			(xy 88.541352 -272.073624) (xy 88.896952 -272.073624)
		)
		(stroke
			(width 0)
			(type solid)
		)
		(fill yes)
		(layer "In4.Cu")
		(net "M_B_CPU1_SA_DQS_DP<6>")
	)
	(gr_poly
		(pts
			(xy 88.899492 -271.620742) (xy 88.899492 -271.576546) (xy 88.543892 -271.576546) (xy 88.543892 -271.620742)
			(xy 88.590882 -271.773142) (xy 88.852502 -271.773142)
		)
		(stroke
			(width 0)
			(type solid)
		)
		(fill yes)
		(layer "In4.Cu")
		(net "M_B_CPU1_SA_DQ<12>")
	)
	(gr_poly
		(pts
			(xy 88.899492 -270.40205) (xy 88.852502 -270.24965) (xy 88.590882 -270.24965) (xy 88.543892 -270.40205)
			(xy 88.543892 -270.446246) (xy 88.899492 -270.446246)
		)
		(stroke
			(width 0)
			(type solid)
		)
		(fill yes)
		(layer "In4.Cu")
		(net "M_B_CPU1_SA_DQ<15>")
	)
	(gr_poly
		(pts
			(xy 88.899492 -268.77391) (xy 88.852502 -268.62151) (xy 88.590882 -268.62151) (xy 88.543892 -268.77391)
			(xy 88.543892 -268.81836) (xy 88.899492 -268.81836)
		)
		(stroke
			(width 0)
			(type solid)
		)
		(fill yes)
		(layer "In4.Cu")
		(net "M_C_CPU1_SA_DQ<19>")
	)
	(gr_poly
		(pts
			(xy 88.899492 -268.365478) (xy 88.899492 -268.321028) (xy 88.543892 -268.321028) (xy 88.543892 -268.365478)
			(xy 88.590882 -268.517878) (xy 88.852502 -268.517878)
		)
		(stroke
			(width 0)
			(type solid)
		)
		(fill yes)
		(layer "In4.Cu")
		(net "M_C_CPU1_SA_DQS_DP<2>")
	)
	(gr_poly
		(pts
			(xy 88.899492 -265.518646) (xy 88.852502 -265.366246) (xy 88.590882 -265.366246) (xy 88.543892 -265.518646)
			(xy 88.543892 -265.563096) (xy 88.899492 -265.563096)
		)
		(stroke
			(width 0)
			(type solid)
		)
		(fill yes)
		(layer "In4.Cu")
		(net "M_C_CPU1_SA_DQ<23>")
	)
	(gr_poly
		(pts
			(xy 88.902794 -274.876514) (xy 88.902794 -274.832064) (xy 88.547194 -274.832064) (xy 88.547194 -274.876514)
			(xy 88.594184 -275.028914) (xy 88.855804 -275.028914)
		)
		(stroke
			(width 0)
			(type solid)
		)
		(fill yes)
		(layer "In4.Cu")
		(net "M_B_CPU1_SA_DQ<8>")
	)
	(gr_poly
		(pts
			(xy 88.902794 -273.657314) (xy 88.855804 -273.504914) (xy 88.594184 -273.504914) (xy 88.547194 -273.657314)
			(xy 88.547194 -273.701764) (xy 88.902794 -273.701764)
		)
		(stroke
			(width 0)
			(type solid)
		)
		(fill yes)
		(layer "In4.Cu")
		(net "M_B_CPU1_SA_DQ<11>")
	)
	(gr_poly
		(pts
			(xy 88.902794 -269.99311) (xy 88.902794 -269.948914) (xy 88.547194 -269.948914) (xy 88.547194 -269.99311)
			(xy 88.594184 -270.14551) (xy 88.855804 -270.14551)
		)
		(stroke
			(width 0)
			(type solid)
		)
		(fill yes)
		(layer "In4.Cu")
		(net "M_C_CPU1_SA_DQ<16>")
	)
	(gr_poly
		(pts
			(xy 88.902794 -267.146278) (xy 88.855804 -266.993878) (xy 88.594184 -266.993878) (xy 88.547194 -267.146278)
			(xy 88.547194 -267.190474) (xy 88.902794 -267.190474)
		)
		(stroke
			(width 0)
			(type solid)
		)
		(fill yes)
		(layer "In4.Cu")
		(net "M_C_CPU1_SA_DQS_DP<7>")
	)
	(gr_poly
		(pts
			(xy 88.902794 -266.737846) (xy 88.902794 -266.693396) (xy 88.547194 -266.693396) (xy 88.547194 -266.737846)
			(xy 88.594184 -266.890246) (xy 88.855804 -266.890246)
		)
		(stroke
			(width 0)
			(type solid)
		)
		(fill yes)
		(layer "In4.Cu")
		(net "M_C_CPU1_SA_DQ<20>")
	)
	(gr_poly
		(pts
			(xy 88.902794 -265.109706) (xy 88.902794 -265.06551) (xy 88.547194 -265.06551) (xy 88.547194 -265.109706)
			(xy 88.594184 -265.262106) (xy 88.855804 -265.262106)
		)
		(stroke
			(width 0)
			(type solid)
		)
		(fill yes)
		(layer "In4.Cu")
		(net "M_B_CPU1_SA_DQ<26>")
	)
	(gr_poly
		(pts
			(xy 88.902794 -263.891014) (xy 88.855804 -263.738614) (xy 88.594184 -263.738614) (xy 88.547194 -263.891014)
			(xy 88.547194 -263.93521) (xy 88.902794 -263.93521)
		)
		(stroke
			(width 0)
			(type solid)
		)
		(fill yes)
		(layer "In4.Cu")
		(net "M_B_CPU1_SA_DQ<27>")
	)
	(gr_poly
		(pts
			(xy 88.902794 -263.482074) (xy 88.902794 -263.437878) (xy 88.547194 -263.437878) (xy 88.547194 -263.482074)
			(xy 88.594184 -263.634474) (xy 88.855804 -263.634474)
		)
		(stroke
			(width 0)
			(type solid)
		)
		(fill yes)
		(layer "In4.Cu")
		(net "M_B_CPU1_SA_DQS_DP<3>")
	)
	(gr_poly
		(pts
			(xy 88.902794 -261.854442) (xy 88.902794 -261.809992) (xy 88.547194 -261.809992) (xy 88.547194 -261.854442)
			(xy 88.594184 -262.006842) (xy 88.855804 -262.006842)
		)
		(stroke
			(width 0)
			(type solid)
		)
		(fill yes)
		(layer "In4.Cu")
		(net "M_B_CPU1_SA_DQ<28>")
	)
	(gr_poly
		(pts
			(xy 88.902794 -258.59867) (xy 88.902794 -258.554474) (xy 88.547194 -258.554474) (xy 88.547194 -258.59867)
			(xy 88.594184 -258.75107) (xy 88.855804 -258.75107)
		)
		(stroke
			(width 0)
			(type solid)
		)
		(fill yes)
		(layer "In4.Cu")
		(net "M_C_CPU1_SA_CS_N<0>")
	)
	(gr_poly
		(pts
			(xy 88.902794 -257.37947) (xy 88.855804 -257.22707) (xy 88.594184 -257.22707) (xy 88.547194 -257.37947)
			(xy 88.547194 -257.42392) (xy 88.902794 -257.42392)
		)
		(stroke
			(width 0)
			(type solid)
		)
		(fill yes)
		(layer "In4.Cu")
		(net "M_C_CPU1_SA_CS_N<3>")
	)
	(gr_poly
		(pts
			(xy 88.902794 -256.971038) (xy 88.902794 -256.926588) (xy 88.547194 -256.926588) (xy 88.547194 -256.971038)
			(xy 88.594184 -257.123438) (xy 88.855804 -257.123438)
		)
		(stroke
			(width 0)
			(type solid)
		)
		(fill yes)
		(layer "In4.Cu")
		(net "M_C_CPU1_SA_CA<0>")
	)
	(gr_poly
		(pts
			(xy 88.902794 -254.124206) (xy 88.855804 -253.971806) (xy 88.594184 -253.971806) (xy 88.547194 -254.124206)
			(xy 88.547194 -254.168402) (xy 88.902794 -254.168402)
		)
		(stroke
			(width 0)
			(type solid)
		)
		(fill yes)
		(layer "In4.Cu")
		(net "M_C_CPU1_SA_PAR")
	)
	(gr_poly
		(pts
			(xy 88.90889 -262.262874) (xy 88.8619 -262.110474) (xy 88.60028 -262.110474) (xy 88.55329 -262.262874)
			(xy 88.55329 -262.30707) (xy 88.90889 -262.30707)
		)
		(stroke
			(width 0)
			(type solid)
		)
		(fill yes)
		(layer "In4.Cu")
		(net "M_B_CPU1_SA_DQS_DP<8>")
	)
	(gr_poly
		(pts
			(xy 88.90889 -260.634734) (xy 88.8619 -260.482334) (xy 88.60028 -260.482334) (xy 88.55329 -260.634734)
			(xy 88.55329 -260.679184) (xy 88.90889 -260.679184)
		)
		(stroke
			(width 0)
			(type solid)
		)
		(fill yes)
		(layer "In4.Cu")
		(net "M_B_CPU1_SA_DQ<31>")
	)
	(gr_poly
		(pts
			(xy 88.90889 -255.751838) (xy 88.8619 -255.599438) (xy 88.60028 -255.599438) (xy 88.55329 -255.751838)
			(xy 88.55329 -255.796034) (xy 88.90889 -255.796034)
		)
		(stroke
			(width 0)
			(type solid)
		)
		(fill yes)
		(layer "In4.Cu")
		(net "M_C_CPU1_SA_CA<3>")
	)
	(gr_poly
		(pts
			(xy 88.90889 -255.343406) (xy 88.90889 -255.29921) (xy 88.55329 -255.29921) (xy 88.55329 -255.343406)
			(xy 88.60028 -255.495806) (xy 88.8619 -255.495806)
		)
		(stroke
			(width 0)
			(type solid)
		)
		(fill yes)
		(layer "In4.Cu")
		(net "M_C_CPU1_SA_CA<4>")
	)
	(gr_poly
		(pts
			(xy 88.976708 -283.494226) (xy 88.86825 -283.377386) (xy 88.829896 -283.355288) (xy 88.652096 -283.663136)
			(xy 88.69045 -283.685234) (xy 88.845898 -283.720794)
		)
		(stroke
			(width 0)
			(type solid)
		)
		(fill yes)
		(layer "In4.Cu")
		(net "M_C_CPU1_SA_DQS_DP<0>")
	)
	(gr_poly
		(pts
			(xy 88.976708 -276.982428) (xy 88.86825 -276.865588) (xy 88.829896 -276.84349) (xy 88.652096 -277.151338)
			(xy 88.69045 -277.173436) (xy 88.845898 -277.208996)
		)
		(stroke
			(width 0)
			(type solid)
		)
		(fill yes)
		(layer "In4.Cu")
		(net "M_C_CPU1_SA_DQ<5>")
	)
	(gr_poly
		(pts
			(xy 88.977724 -285.119318) (xy 88.869266 -285.002478) (xy 88.830912 -284.98038) (xy 88.653112 -285.288228)
			(xy 88.691466 -285.310326) (xy 88.846914 -285.345886)
		)
		(stroke
			(width 0)
			(type solid)
		)
		(fill yes)
		(layer "In4.Cu")
		(net "M_C_CPU1_SA_DQ<1>")
	)
	(gr_poly
		(pts
			(xy 88.977724 -278.608282) (xy 88.869266 -278.491442) (xy 88.830912 -278.469344) (xy 88.653112 -278.777192)
			(xy 88.691466 -278.79929) (xy 88.846914 -278.83485)
		)
		(stroke
			(width 0)
			(type solid)
		)
		(fill yes)
		(layer "In4.Cu")
		(net "M_C_CPU1_SA_DQ<4>")
	)
	(gr_poly
		(pts
			(xy 88.982296 -281.856434) (xy 88.873838 -281.739594) (xy 88.835484 -281.717496) (xy 88.657684 -282.025344)
			(xy 88.696038 -282.047442) (xy 88.851486 -282.083002)
		)
		(stroke
			(width 0)
			(type solid)
		)
		(fill yes)
		(layer "In4.Cu")
		(net "M_C_CPU1_SA_DQS_DN<5>")
	)
	(gr_poly
		(pts
			(xy 88.984074 -286.737044) (xy 88.875616 -286.620204) (xy 88.837262 -286.598106) (xy 88.659462 -286.905954)
			(xy 88.697816 -286.928052) (xy 88.853264 -286.963612)
		)
		(stroke
			(width 0)
			(type solid)
		)
		(fill yes)
		(layer "In4.Cu")
		(net "M_C_CPU1_SA_DQ<0>")
	)
	(gr_poly
		(pts
			(xy 89.25433 -246.568722) (xy 89.20734 -246.416322) (xy 88.94572 -246.416322) (xy 88.89873 -246.568722)
			(xy 88.89873 -246.612918) (xy 89.25433 -246.612918)
		)
		(stroke
			(width 0)
			(type solid)
		)
		(fill yes)
		(layer "In4.Cu")
		(net "M_C_CPU1_SB_CA<3>")
	)
	(gr_poly
		(pts
			(xy 89.25433 -246.16029) (xy 89.25433 -246.116094) (xy 88.89873 -246.116094) (xy 88.89873 -246.16029)
			(xy 88.94572 -246.31269) (xy 89.20734 -246.31269)
		)
		(stroke
			(width 0)
			(type solid)
		)
		(fill yes)
		(layer "In4.Cu")
		(net "M_C_CPU1_SB_CA<4>")
	)
	(gr_poly
		(pts
			(xy 89.25433 -244.940582) (xy 89.20734 -244.788182) (xy 88.94572 -244.788182) (xy 88.89873 -244.940582)
			(xy 88.89873 -244.985032) (xy 89.25433 -244.985032)
		)
		(stroke
			(width 0)
			(type solid)
		)
		(fill yes)
		(layer "In4.Cu")
		(net "M_C_CPU1_SB_PAR")
	)
	(gr_poly
		(pts
			(xy 89.25433 -244.532658) (xy 89.25433 -244.488208) (xy 88.89873 -244.488208) (xy 88.89873 -244.532658)
			(xy 88.94572 -244.685058) (xy 89.20734 -244.685058)
		)
		(stroke
			(width 0)
			(type solid)
		)
		(fill yes)
		(layer "In4.Cu")
		(net "M_C_CPU1_SB_CS_N<2>")
	)
	(gr_poly
		(pts
			(xy 89.25433 -243.31295) (xy 89.20734 -243.16055) (xy 88.94572 -243.16055) (xy 88.89873 -243.31295)
			(xy 88.89873 -243.3574) (xy 89.25433 -243.3574)
		)
		(stroke
			(width 0)
			(type solid)
		)
		(fill yes)
		(layer "In4.Cu")
		(net "M_C_CPU1_SB_CS_N<1>")
	)
	(gr_poly
		(pts
			(xy 89.25433 -241.685318) (xy 89.20734 -241.532918) (xy 88.94572 -241.532918) (xy 88.89873 -241.685318)
			(xy 88.89873 -241.729514) (xy 89.25433 -241.729514)
		)
		(stroke
			(width 0)
			(type solid)
		)
		(fill yes)
		(layer "In4.Cu")
		(net "M_C_CPU1_SB_CB<6>")
	)
	(gr_poly
		(pts
			(xy 89.25433 -239.649254) (xy 89.25433 -239.604804) (xy 88.89873 -239.604804) (xy 88.89873 -239.649254)
			(xy 88.94572 -239.801654) (xy 89.20734 -239.801654)
		)
		(stroke
			(width 0)
			(type solid)
		)
		(fill yes)
		(layer "In4.Cu")
		(net "M_C_CPU1_SB_DQS_DN<4>")
	)
	(gr_poly
		(pts
			(xy 89.25433 -235.174282) (xy 89.20734 -235.021882) (xy 88.94572 -235.021882) (xy 88.89873 -235.174282)
			(xy 88.89873 -235.218478) (xy 89.25433 -235.218478)
		)
		(stroke
			(width 0)
			(type solid)
		)
		(fill yes)
		(layer "In4.Cu")
		(net "M_B_CPU1_SB_DQS_DN<0>")
	)
	(gr_poly
		(pts
			(xy 89.25433 -234.76585) (xy 89.25433 -234.721654) (xy 88.89873 -234.721654) (xy 88.89873 -234.76585)
			(xy 88.94572 -234.91825) (xy 89.20734 -234.91825)
		)
		(stroke
			(width 0)
			(type solid)
		)
		(fill yes)
		(layer "In4.Cu")
		(net "M_B_CPU1_SB_DQS_DN<5>")
	)
	(gr_poly
		(pts
			(xy 89.25433 -228.254814) (xy 89.25433 -228.210618) (xy 88.89873 -228.210618) (xy 88.89873 -228.254814)
			(xy 88.94572 -228.407214) (xy 89.20734 -228.407214)
		)
		(stroke
			(width 0)
			(type solid)
		)
		(fill yes)
		(layer "In4.Cu")
		(net "M_C_CPU1_SB_DQ<21>")
	)
	(gr_poly
		(pts
			(xy 89.25687 -236.801914) (xy 89.20988 -236.649514) (xy 88.94826 -236.649514) (xy 88.90127 -236.801914)
			(xy 88.90127 -236.846364) (xy 89.25687 -236.846364)
		)
		(stroke
			(width 0)
			(type solid)
		)
		(fill yes)
		(layer "In4.Cu")
		(net "M_B_CPU1_SB_DQ<0>")
	)
	(gr_poly
		(pts
			(xy 89.266268 -241.276886) (xy 89.266268 -241.232436) (xy 88.910668 -241.232436) (xy 88.910668 -241.276886)
			(xy 88.957658 -241.429286) (xy 89.219278 -241.429286)
		)
		(stroke
			(width 0)
			(type solid)
		)
		(fill yes)
		(layer "In4.Cu")
		(net "M_C_CPU1_SB_CB<5>")
	)
	(gr_poly
		(pts
			(xy 89.266268 -240.057686) (xy 89.219278 -239.905286) (xy 88.957658 -239.905286) (xy 88.910668 -240.057686)
			(xy 88.910668 -240.102136) (xy 89.266268 -240.102136)
		)
		(stroke
			(width 0)
			(type solid)
		)
		(fill yes)
		(layer "In4.Cu")
		(net "M_C_CPU1_SB_DQS_DN<9>")
	)
	(gr_poly
		(pts
			(xy 89.266268 -238.021114) (xy 89.266268 -237.976664) (xy 88.910668 -237.976664) (xy 88.910668 -238.021114)
			(xy 88.957658 -238.173514) (xy 89.219278 -238.173514)
		)
		(stroke
			(width 0)
			(type solid)
		)
		(fill yes)
		(layer "In4.Cu")
		(net "M_C_CPU1_SB_CB<1>")
	)
	(gr_poly
		(pts
			(xy 89.266268 -233.13771) (xy 89.266268 -233.093514) (xy 88.910668 -233.093514) (xy 88.910668 -233.13771)
			(xy 88.957658 -233.29011) (xy 89.219278 -233.29011)
		)
		(stroke
			(width 0)
			(type solid)
		)
		(fill yes)
		(layer "In4.Cu")
		(net "M_B_CPU1_SB_DQ<5>")
	)
	(gr_poly
		(pts
			(xy 89.266268 -231.919018) (xy 89.219278 -231.766618) (xy 88.957658 -231.766618) (xy 88.910668 -231.919018)
			(xy 88.910668 -231.963214) (xy 89.266268 -231.963214)
		)
		(stroke
			(width 0)
			(type solid)
		)
		(fill yes)
		(layer "In4.Cu")
		(net "M_C_CPU1_SB_DQ<18>")
	)
	(gr_poly
		(pts
			(xy 89.266268 -230.290878) (xy 89.219278 -230.138478) (xy 88.957658 -230.138478) (xy 88.910668 -230.290878)
			(xy 88.910668 -230.335328) (xy 89.266268 -230.335328)
		)
		(stroke
			(width 0)
			(type solid)
		)
		(fill yes)
		(layer "In4.Cu")
		(net "M_C_CPU1_SB_DQS_DN<2>")
	)
	(gr_poly
		(pts
			(xy 89.266268 -229.882446) (xy 89.266268 -229.837996) (xy 88.910668 -229.837996) (xy 88.910668 -229.882446)
			(xy 88.957658 -230.034846) (xy 89.219278 -230.034846)
		)
		(stroke
			(width 0)
			(type solid)
		)
		(fill yes)
		(layer "In4.Cu")
		(net "M_C_CPU1_SB_DQS_DN<7>")
	)
	(gr_poly
		(pts
			(xy 89.266776 -285.220664) (xy 89.228422 -285.198566) (xy 89.072974 -285.163006) (xy 88.942164 -285.389574)
			(xy 89.050622 -285.506414) (xy 89.088976 -285.528512)
		)
		(stroke
			(width 0)
			(type solid)
		)
		(fill yes)
		(layer "In4.Cu")
		(net "M_C_CPU1_SA_DQ<2>")
	)
	(gr_poly
		(pts
			(xy 89.266776 -283.593032) (xy 89.228422 -283.570934) (xy 89.072974 -283.535374) (xy 88.942164 -283.761942)
			(xy 89.050622 -283.878782) (xy 89.088976 -283.90088)
		)
		(stroke
			(width 0)
			(type solid)
		)
		(fill yes)
		(layer "In4.Cu")
		(net "M_C_CPU1_SA_DQ<3>")
	)
	(gr_poly
		(pts
			(xy 89.266776 -278.709628) (xy 89.228422 -278.68753) (xy 89.072974 -278.65197) (xy 88.942164 -278.878538)
			(xy 89.050622 -278.995378) (xy 89.088976 -279.017476)
		)
		(stroke
			(width 0)
			(type solid)
		)
		(fill yes)
		(layer "In4.Cu")
		(net "M_C_CPU1_SA_DQS_DP<5>")
	)
	(gr_poly
		(pts
			(xy 89.266776 -277.081742) (xy 89.228422 -277.059644) (xy 89.072974 -277.024084) (xy 88.942164 -277.250652)
			(xy 89.050622 -277.367492) (xy 89.088976 -277.38959)
		)
		(stroke
			(width 0)
			(type solid)
		)
		(fill yes)
		(layer "In4.Cu")
		(net "M_C_CPU1_SA_DQ<6>")
	)
	(gr_poly
		(pts
			(xy 89.26703 -238.430054) (xy 89.22004 -238.277654) (xy 88.95842 -238.277654) (xy 88.91143 -238.430054)
			(xy 88.91143 -238.47425) (xy 89.26703 -238.47425)
		)
		(stroke
			(width 0)
			(type solid)
		)
		(fill yes)
		(layer "In4.Cu")
		(net "M_C_CPU1_SB_CB<2>")
	)
	(gr_poly
		(pts
			(xy 89.26703 -236.393482) (xy 89.26703 -236.349032) (xy 88.91143 -236.349032) (xy 88.91143 -236.393482)
			(xy 88.95842 -236.545882) (xy 89.22004 -236.545882)
		)
		(stroke
			(width 0)
			(type solid)
		)
		(fill yes)
		(layer "In4.Cu")
		(net "M_B_CPU1_SB_DQ<1>")
	)
	(gr_poly
		(pts
			(xy 89.26703 -233.54665) (xy 89.22004 -233.39425) (xy 88.95842 -233.39425) (xy 88.91143 -233.54665)
			(xy 88.91143 -233.5911) (xy 89.26703 -233.5911)
		)
		(stroke
			(width 0)
			(type solid)
		)
		(fill yes)
		(layer "In4.Cu")
		(net "M_B_CPU1_SB_DQ<6>")
	)
	(gr_poly
		(pts
			(xy 89.26703 -231.510078) (xy 89.26703 -231.465628) (xy 88.91143 -231.465628) (xy 88.91143 -231.510078)
			(xy 88.95842 -231.662478) (xy 89.22004 -231.662478)
		)
		(stroke
			(width 0)
			(type solid)
		)
		(fill yes)
		(layer "In4.Cu")
		(net "M_C_CPU1_SB_DQ<17>")
	)
	(gr_poly
		(pts
			(xy 89.26703 -228.663246) (xy 89.22004 -228.510846) (xy 88.95842 -228.510846) (xy 88.91143 -228.663246)
			(xy 88.91143 -228.707696) (xy 89.26703 -228.707696)
		)
		(stroke
			(width 0)
			(type solid)
		)
		(fill yes)
		(layer "In4.Cu")
		(net "M_C_CPU1_SB_DQ<22>")
	)
	(gr_poly
		(pts
			(xy 89.268808 -275.450046) (xy 89.230454 -275.427948) (xy 89.075006 -275.392388) (xy 88.944196 -275.618956)
			(xy 89.052654 -275.735796) (xy 89.091008 -275.757894)
		)
		(stroke
			(width 0)
			(type solid)
		)
		(fill yes)
		(layer "In4.Cu")
		(net "M_C_CPU1_SA_DQ<7>")
	)
	(gr_poly
		(pts
			(xy 89.337134 -280.6192) (xy 89.445592 -280.50236) (xy 89.314782 -280.275792) (xy 89.159334 -280.311352)
			(xy 89.12098 -280.33345) (xy 89.29878 -280.641298)
		)
		(stroke
			(width 0)
			(type solid)
		)
		(fill yes)
		(layer "In4.Cu")
		(net "M_C_CPU1_SA_DQS_DN<5>")
	)
	(gr_poly
		(pts
			(xy 89.364312 -261.040626) (xy 89.364312 -260.99643) (xy 89.008712 -260.99643) (xy 89.008712 -261.040626)
			(xy 89.055702 -261.193026) (xy 89.317322 -261.193026)
		)
		(stroke
			(width 0)
			(type solid)
		)
		(fill yes)
		(layer "In4.Cu")
		(net "M_B_CPU1_SA_DQ<29>")
	)
	(gr_poly
		(pts
			(xy 89.364312 -256.157222) (xy 89.364312 -256.113026) (xy 89.008712 -256.113026) (xy 89.008712 -256.157222)
			(xy 89.055702 -256.309622) (xy 89.317322 -256.309622)
		)
		(stroke
			(width 0)
			(type solid)
		)
		(fill yes)
		(layer "In4.Cu")
		(net "M_C_CPU1_SA_CA<2>")
	)
	(gr_poly
		(pts
			(xy 89.364312 -254.937514) (xy 89.317322 -254.785114) (xy 89.055702 -254.785114) (xy 89.008712 -254.937514)
			(xy 89.008712 -254.981964) (xy 89.364312 -254.981964)
		)
		(stroke
			(width 0)
			(type solid)
		)
		(fill yes)
		(layer "In4.Cu")
		(net "M_C_CPU1_SA_CA<5>")
	)
	(gr_poly
		(pts
			(xy 89.366852 -272.435066) (xy 89.366852 -272.390616) (xy 89.011252 -272.390616) (xy 89.011252 -272.435066)
			(xy 89.058242 -272.587466) (xy 89.319862 -272.587466)
		)
		(stroke
			(width 0)
			(type solid)
		)
		(fill yes)
		(layer "In4.Cu")
		(net "M_B_CPU1_SA_DQS_DN<6>")
	)
	(gr_poly
		(pts
			(xy 89.372694 -274.47113) (xy 89.325704 -274.31873) (xy 89.064084 -274.31873) (xy 89.017094 -274.47113)
			(xy 89.017094 -274.51558) (xy 89.372694 -274.51558)
		)
		(stroke
			(width 0)
			(type solid)
		)
		(fill yes)
		(layer "In4.Cu")
		(net "M_B_CPU1_SA_DQ<10>")
	)
	(gr_poly
		(pts
			(xy 89.372694 -274.062698) (xy 89.372694 -274.018248) (xy 89.017094 -274.018248) (xy 89.017094 -274.062698)
			(xy 89.064084 -274.215098) (xy 89.325704 -274.215098)
		)
		(stroke
			(width 0)
			(type solid)
		)
		(fill yes)
		(layer "In4.Cu")
		(net "M_B_CPU1_SA_DQ<9>")
	)
	(gr_poly
		(pts
			(xy 89.372694 -269.587726) (xy 89.325704 -269.435326) (xy 89.064084 -269.435326) (xy 89.017094 -269.587726)
			(xy 89.017094 -269.632176) (xy 89.372694 -269.632176)
		)
		(stroke
			(width 0)
			(type solid)
		)
		(fill yes)
		(layer "In4.Cu")
		(net "M_C_CPU1_SA_DQ<18>")
	)
	(gr_poly
		(pts
			(xy 89.372694 -264.70483) (xy 89.325704 -264.55243) (xy 89.064084 -264.55243) (xy 89.017094 -264.70483)
			(xy 89.017094 -264.749026) (xy 89.372694 -264.749026)
		)
		(stroke
			(width 0)
			(type solid)
		)
		(fill yes)
		(layer "In4.Cu")
		(net "M_B_CPU1_SA_DQ<24>")
	)
	(gr_poly
		(pts
			(xy 89.372694 -263.07669) (xy 89.325704 -262.92429) (xy 89.064084 -262.92429) (xy 89.017094 -263.07669)
			(xy 89.017094 -263.12114) (xy 89.372694 -263.12114)
		)
		(stroke
			(width 0)
			(type solid)
		)
		(fill yes)
		(layer "In4.Cu")
		(net "M_B_CPU1_SA_DQS_DN<3>")
	)
	(gr_poly
		(pts
			(xy 89.372694 -261.449058) (xy 89.325704 -261.296658) (xy 89.064084 -261.296658) (xy 89.017094 -261.449058)
			(xy 89.017094 -261.493508) (xy 89.372694 -261.493508)
		)
		(stroke
			(width 0)
			(type solid)
		)
		(fill yes)
		(layer "In4.Cu")
		(net "M_B_CPU1_SA_DQ<30>")
	)
	(gr_poly
		(pts
			(xy 89.372694 -258.193286) (xy 89.325704 -258.040886) (xy 89.064084 -258.040886) (xy 89.017094 -258.193286)
			(xy 89.017094 -258.237736) (xy 89.372694 -258.237736)
		)
		(stroke
			(width 0)
			(type solid)
		)
		(fill yes)
		(layer "In4.Cu")
		(net "M_C_CPU1_SA_CS_N<2>")
	)
	(gr_poly
		(pts
			(xy 89.372694 -257.784854) (xy 89.372694 -257.740404) (xy 89.017094 -257.740404) (xy 89.017094 -257.784854)
			(xy 89.064084 -257.937254) (xy 89.325704 -257.937254)
		)
		(stroke
			(width 0)
			(type solid)
		)
		(fill yes)
		(layer "In4.Cu")
		(net "M_C_CPU1_SA_CS_N<1>")
	)
	(gr_poly
		(pts
			(xy 89.372694 -256.565654) (xy 89.325704 -256.413254) (xy 89.064084 -256.413254) (xy 89.017094 -256.565654)
			(xy 89.017094 -256.610104) (xy 89.372694 -256.610104)
		)
		(stroke
			(width 0)
			(type solid)
		)
		(fill yes)
		(layer "In4.Cu")
		(net "M_C_CPU1_SA_CA<1>")
	)
	(gr_poly
		(pts
			(xy 89.372694 -254.529082) (xy 89.372694 -254.484886) (xy 89.017094 -254.484886) (xy 89.017094 -254.529082)
			(xy 89.064084 -254.681482) (xy 89.325704 -254.681482)
		)
		(stroke
			(width 0)
			(type solid)
		)
		(fill yes)
		(layer "In4.Cu")
		(net "M_C_CPU1_SA_CA<6>")
	)
	(gr_poly
		(pts
			(xy 89.37498 -266.332462) (xy 89.32799 -266.180062) (xy 89.06637 -266.180062) (xy 89.01938 -266.332462)
			(xy 89.01938 -266.376912) (xy 89.37498 -266.376912)
		)
		(stroke
			(width 0)
			(type solid)
		)
		(fill yes)
		(layer "In4.Cu")
		(net "M_C_CPU1_SA_DQ<22>")
	)
	(gr_poly
		(pts
			(xy 89.375488 -271.215866) (xy 89.328498 -271.063466) (xy 89.066878 -271.063466) (xy 89.019888 -271.215866)
			(xy 89.019888 -271.260062) (xy 89.375488 -271.260062)
		)
		(stroke
			(width 0)
			(type solid)
		)
		(fill yes)
		(layer "In4.Cu")
		(net "M_B_CPU1_SA_DQ<14>")
	)
	(gr_poly
		(pts
			(xy 89.375488 -270.806926) (xy 89.375488 -270.76273) (xy 89.019888 -270.76273) (xy 89.019888 -270.806926)
			(xy 89.066878 -270.959326) (xy 89.328498 -270.959326)
		)
		(stroke
			(width 0)
			(type solid)
		)
		(fill yes)
		(layer "In4.Cu")
		(net "M_B_CPU1_SA_DQ<13>")
	)
	(gr_poly
		(pts
			(xy 89.375488 -269.179294) (xy 89.375488 -269.134844) (xy 89.019888 -269.134844) (xy 89.019888 -269.179294)
			(xy 89.066878 -269.331694) (xy 89.328498 -269.331694)
		)
		(stroke
			(width 0)
			(type solid)
		)
		(fill yes)
		(layer "In4.Cu")
		(net "M_C_CPU1_SA_DQ<17>")
	)
	(gr_poly
		(pts
			(xy 89.375488 -267.960094) (xy 89.328498 -267.807694) (xy 89.066878 -267.807694) (xy 89.019888 -267.960094)
			(xy 89.019888 -268.004544) (xy 89.375488 -268.004544)
		)
		(stroke
			(width 0)
			(type solid)
		)
		(fill yes)
		(layer "In4.Cu")
		(net "M_C_CPU1_SA_DQS_DN<2>")
	)
	(gr_poly
		(pts
			(xy 89.375488 -267.551154) (xy 89.375488 -267.506958) (xy 89.019888 -267.506958) (xy 89.019888 -267.551154)
			(xy 89.066878 -267.703554) (xy 89.328498 -267.703554)
		)
		(stroke
			(width 0)
			(type solid)
		)
		(fill yes)
		(layer "In4.Cu")
		(net "M_C_CPU1_SA_DQS_DN<7>")
	)
	(gr_poly
		(pts
			(xy 89.375488 -265.923522) (xy 89.375488 -265.879326) (xy 89.019888 -265.879326) (xy 89.019888 -265.923522)
			(xy 89.066878 -266.075922) (xy 89.328498 -266.075922)
		)
		(stroke
			(width 0)
			(type solid)
		)
		(fill yes)
		(layer "In4.Cu")
		(net "M_C_CPU1_SA_DQ<21>")
	)
	(gr_poly
		(pts
			(xy 89.375488 -264.29589) (xy 89.375488 -264.25144) (xy 89.019888 -264.25144) (xy 89.019888 -264.29589)
			(xy 89.066878 -264.44829) (xy 89.328498 -264.44829)
		)
		(stroke
			(width 0)
			(type solid)
		)
		(fill yes)
		(layer "In4.Cu")
		(net "M_B_CPU1_SA_DQ<25>")
	)
	(gr_poly
		(pts
			(xy 89.375488 -262.668258) (xy 89.375488 -262.623808) (xy 89.019888 -262.623808) (xy 89.019888 -262.668258)
			(xy 89.066878 -262.820658) (xy 89.328498 -262.820658)
		)
		(stroke
			(width 0)
			(type solid)
		)
		(fill yes)
		(layer "In4.Cu")
		(net "M_B_CPU1_SA_DQS_DN<8>")
	)
	(gr_poly
		(pts
			(xy 89.37879 -272.843498) (xy 89.3318 -272.691098) (xy 89.07018 -272.691098) (xy 89.02319 -272.843498)
			(xy 89.02319 -272.887948) (xy 89.37879 -272.887948)
		)
		(stroke
			(width 0)
			(type solid)
		)
		(fill yes)
		(layer "In4.Cu")
		(net "M_B_CPU1_SA_DQS_DN<1>")
	)
	(gr_poly
		(pts
			(xy 89.38133 -282.610052) (xy 89.33434 -282.457652) (xy 89.07272 -282.457652) (xy 89.02573 -282.610052)
			(xy 89.02573 -282.654248) (xy 89.38133 -282.654248)
		)
		(stroke
			(width 0)
			(type solid)
		)
		(fill yes)
		(layer "In4.Cu")
		(net "M_C_CPU1_SA_DQS_DN<0>")
	)
	(gr_poly
		(pts
			(xy 89.44483 -285.937198) (xy 89.336372 -285.820358) (xy 89.298018 -285.79826) (xy 89.120218 -286.106108)
			(xy 89.158572 -286.128206) (xy 89.31402 -286.163766)
		)
		(stroke
			(width 0)
			(type solid)
		)
		(fill yes)
		(layer "In4.Cu")
		(net "M_C_CPU1_SA_DQ<0>")
	)
	(gr_poly
		(pts
			(xy 89.446608 -281.052524) (xy 89.33815 -280.935684) (xy 89.299796 -280.913586) (xy 89.121996 -281.221434)
			(xy 89.16035 -281.243532) (xy 89.315798 -281.279092)
		)
		(stroke
			(width 0)
			(type solid)
		)
		(fill yes)
		(layer "In4.Cu")
		(net "M_C_CPU1_SA_DQS_DN<5>")
	)
	(gr_poly
		(pts
			(xy 89.446862 -277.796244) (xy 89.338404 -277.679404) (xy 89.30005 -277.657306) (xy 89.12225 -277.965154)
			(xy 89.160604 -277.987252) (xy 89.316052 -278.022812)
		)
		(stroke
			(width 0)
			(type solid)
		)
		(fill yes)
		(layer "In4.Cu")
		(net "M_C_CPU1_SA_DQ<4>")
	)
	(gr_poly
		(pts
			(xy 89.447624 -279.422098) (xy 89.339166 -279.305258) (xy 89.300812 -279.28316) (xy 89.123012 -279.591008)
			(xy 89.161366 -279.613106) (xy 89.316814 -279.648666)
		)
		(stroke
			(width 0)
			(type solid)
		)
		(fill yes)
		(layer "In4.Cu")
		(net "M_C_CPU1_SA_DQS_DN<5>")
	)
	(gr_poly
		(pts
			(xy 89.447624 -276.16658) (xy 89.339166 -276.04974) (xy 89.300812 -276.027642) (xy 89.123012 -276.33549)
			(xy 89.161366 -276.357588) (xy 89.316814 -276.393148)
		)
		(stroke
			(width 0)
			(type solid)
		)
		(fill yes)
		(layer "In4.Cu")
		(net "M_C_CPU1_SA_DQ<5>")
	)
	(gr_poly
		(pts
			(xy 89.452196 -284.29839) (xy 89.343738 -284.18155) (xy 89.305384 -284.159452) (xy 89.127584 -284.4673)
			(xy 89.165938 -284.489398) (xy 89.321386 -284.524958)
		)
		(stroke
			(width 0)
			(type solid)
		)
		(fill yes)
		(layer "In4.Cu")
		(net "M_C_CPU1_SA_DQ<1>")
	)
	(gr_poly
		(pts
			(xy 89.694004 -282.047696) (xy 89.732358 -282.025598) (xy 89.554558 -281.71775) (xy 89.516204 -281.739848)
			(xy 89.407746 -281.856688) (xy 89.538556 -282.083256)
		)
		(stroke
			(width 0)
			(type solid)
		)
		(fill yes)
		(layer "In4.Cu")
		(net "M_C_CPU1_SA_DQS_DN<0>")
	)
	(gr_poly
		(pts
			(xy 89.728548 -238.83493) (xy 89.728548 -238.790734) (xy 89.372948 -238.790734) (xy 89.372948 -238.83493)
			(xy 89.419938 -238.98733) (xy 89.681558 -238.98733)
		)
		(stroke
			(width 0)
			(type solid)
		)
		(fill yes)
		(layer "In4.Cu")
		(net "M_C_CPU1_SB_CB<0>")
	)
	(gr_poly
		(pts
			(xy 89.728548 -235.988606) (xy 89.681558 -235.836206) (xy 89.419938 -235.836206) (xy 89.372948 -235.988606)
			(xy 89.372948 -236.032802) (xy 89.728548 -236.032802)
		)
		(stroke
			(width 0)
			(type solid)
		)
		(fill yes)
		(layer "In4.Cu")
		(net "M_B_CPU1_SB_DQ<3>")
	)
	(gr_poly
		(pts
			(xy 89.728548 -233.951526) (xy 89.728548 -233.90733) (xy 89.372948 -233.90733) (xy 89.372948 -233.951526)
			(xy 89.419938 -234.103926) (xy 89.681558 -234.103926)
		)
		(stroke
			(width 0)
			(type solid)
		)
		(fill yes)
		(layer "In4.Cu")
		(net "M_B_CPU1_SB_DQ<4>")
	)
	(gr_poly
		(pts
			(xy 89.728548 -231.105202) (xy 89.681558 -230.952802) (xy 89.419938 -230.952802) (xy 89.372948 -231.105202)
			(xy 89.372948 -231.149398) (xy 89.728548 -231.149398)
		)
		(stroke
			(width 0)
			(type solid)
		)
		(fill yes)
		(layer "In4.Cu")
		(net "M_C_CPU1_SB_DQ<19>")
	)
	(gr_poly
		(pts
			(xy 89.728548 -229.068122) (xy 89.728548 -229.023926) (xy 89.372948 -229.023926) (xy 89.372948 -229.068122)
			(xy 89.419938 -229.220522) (xy 89.681558 -229.220522)
		)
		(stroke
			(width 0)
			(type solid)
		)
		(fill yes)
		(layer "In4.Cu")
		(net "M_C_CPU1_SB_DQ<20>")
	)
	(gr_poly
		(pts
			(xy 89.72931 -240.871502) (xy 89.68232 -240.719102) (xy 89.4207 -240.719102) (xy 89.37371 -240.871502)
			(xy 89.37371 -240.915952) (xy 89.72931 -240.915952)
		)
		(stroke
			(width 0)
			(type solid)
		)
		(fill yes)
		(layer "In4.Cu")
		(net "M_C_CPU1_SB_CB<7>")
	)
	(gr_poly
		(pts
			(xy 89.72931 -237.616238) (xy 89.68232 -237.463838) (xy 89.4207 -237.463838) (xy 89.37371 -237.616238)
			(xy 89.37371 -237.660434) (xy 89.72931 -237.660434)
		)
		(stroke
			(width 0)
			(type solid)
		)
		(fill yes)
		(layer "In4.Cu")
		(net "M_C_CPU1_SB_CB<3>")
	)
	(gr_poly
		(pts
			(xy 89.72931 -232.732834) (xy 89.68232 -232.580434) (xy 89.4207 -232.580434) (xy 89.37371 -232.732834)
			(xy 89.37371 -232.77703) (xy 89.72931 -232.77703)
		)
		(stroke
			(width 0)
			(type solid)
		)
		(fill yes)
		(layer "In4.Cu")
		(net "M_B_CPU1_SB_DQ<7>")
	)
	(gr_poly
		(pts
			(xy 89.72931 -232.323894) (xy 89.72931 -232.279698) (xy 89.37371 -232.279698) (xy 89.37371 -232.323894)
			(xy 89.4207 -232.476294) (xy 89.68232 -232.476294)
		)
		(stroke
			(width 0)
			(type solid)
		)
		(fill yes)
		(layer "In4.Cu")
		(net "M_C_CPU1_SB_DQ<16>")
	)
	(gr_poly
		(pts
			(xy 89.72931 -229.477062) (xy 89.68232 -229.324662) (xy 89.4207 -229.324662) (xy 89.37371 -229.477062)
			(xy 89.37371 -229.521512) (xy 89.72931 -229.521512)
		)
		(stroke
			(width 0)
			(type solid)
		)
		(fill yes)
		(layer "In4.Cu")
		(net "M_C_CPU1_SB_DQS_DP<7>")
	)
	(gr_poly
		(pts
			(xy 89.73312 -243.718334) (xy 89.73312 -243.674138) (xy 89.37752 -243.674138) (xy 89.37752 -243.718334)
			(xy 89.42451 -243.870734) (xy 89.68613 -243.870734)
		)
		(stroke
			(width 0)
			(type solid)
		)
		(fill yes)
		(layer "In4.Cu")
		(net "M_C_CPU1_SB_CS_N<3>")
	)
	(gr_poly
		(pts
			(xy 89.734136 -281.155394) (xy 89.695782 -281.133296) (xy 89.540334 -281.097736) (xy 89.409524 -281.324304)
			(xy 89.517982 -281.441144) (xy 89.556336 -281.463242)
		)
		(stroke
			(width 0)
			(type solid)
		)
		(fill yes)
		(layer "In4.Cu")
		(net "M_C_CPU1_SA_DQS_DN<0>")
	)
	(gr_poly
		(pts
			(xy 89.736676 -284.406848) (xy 89.698322 -284.38475) (xy 89.542874 -284.34919) (xy 89.412064 -284.575758)
			(xy 89.520522 -284.692598) (xy 89.558876 -284.714696)
		)
		(stroke
			(width 0)
			(type solid)
		)
		(fill yes)
		(layer "In4.Cu")
		(net "M_C_CPU1_SA_DQ<2>")
	)
	(gr_poly
		(pts
			(xy 89.736676 -276.267926) (xy 89.698322 -276.245828) (xy 89.542874 -276.210268) (xy 89.412064 -276.436836)
			(xy 89.520522 -276.553676) (xy 89.558876 -276.575774)
		)
		(stroke
			(width 0)
			(type solid)
		)
		(fill yes)
		(layer "In4.Cu")
		(net "M_C_CPU1_SA_DQ<6>")
	)
	(gr_poly
		(pts
			(xy 89.738708 -277.891748) (xy 89.700354 -277.86965) (xy 89.544906 -277.83409) (xy 89.414096 -278.060658)
			(xy 89.522554 -278.177498) (xy 89.560908 -278.199596)
		)
		(stroke
			(width 0)
			(type solid)
		)
		(fill yes)
		(layer "In4.Cu")
		(net "M_C_CPU1_SA_DQS_DP<5>")
	)
	(gr_poly
		(pts
			(xy 89.738708 -246.974106) (xy 89.738708 -246.929656) (xy 89.383108 -246.929656) (xy 89.383108 -246.974106)
			(xy 89.430098 -247.126506) (xy 89.691718 -247.126506)
		)
		(stroke
			(width 0)
			(type solid)
		)
		(fill yes)
		(layer "In4.Cu")
		(net "M_C_CPU1_SB_CA<2>")
	)
	(gr_poly
		(pts
			(xy 89.741248 -245.754906) (xy 89.694258 -245.602506) (xy 89.432638 -245.602506) (xy 89.385648 -245.754906)
			(xy 89.385648 -245.799102) (xy 89.741248 -245.799102)
		)
		(stroke
			(width 0)
			(type solid)
		)
		(fill yes)
		(layer "In4.Cu")
		(net "M_C_CPU1_SB_CA<5>")
	)
	(gr_poly
		(pts
			(xy 89.741248 -245.346474) (xy 89.741248 -245.302278) (xy 89.385648 -245.302278) (xy 89.385648 -245.346474)
			(xy 89.432638 -245.498874) (xy 89.694258 -245.498874)
		)
		(stroke
			(width 0)
			(type solid)
		)
		(fill yes)
		(layer "In4.Cu")
		(net "M_C_CPU1_SB_CA<6>")
	)
	(gr_poly
		(pts
			(xy 89.741248 -244.126766) (xy 89.694258 -243.974366) (xy 89.432638 -243.974366) (xy 89.385648 -244.126766)
			(xy 89.385648 -244.171216) (xy 89.741248 -244.171216)
		)
		(stroke
			(width 0)
			(type solid)
		)
		(fill yes)
		(layer "In4.Cu")
		(net "M_C_CPU1_SB_CS_N<0>")
	)
	(gr_poly
		(pts
			(xy 89.741248 -242.090702) (xy 89.741248 -242.046506) (xy 89.385648 -242.046506) (xy 89.385648 -242.090702)
			(xy 89.432638 -242.243102) (xy 89.694258 -242.243102)
		)
		(stroke
			(width 0)
			(type solid)
		)
		(fill yes)
		(layer "In4.Cu")
		(net "M_C_CPU1_SB_CB<4>")
	)
	(gr_poly
		(pts
			(xy 89.741248 -240.46307) (xy 89.741248 -240.418874) (xy 89.385648 -240.418874) (xy 89.385648 -240.46307)
			(xy 89.432638 -240.61547) (xy 89.694258 -240.61547)
		)
		(stroke
			(width 0)
			(type solid)
		)
		(fill yes)
		(layer "In4.Cu")
		(net "M_C_CPU1_SB_DQS_DP<9>")
	)
	(gr_poly
		(pts
			(xy 89.741248 -239.243362) (xy 89.694258 -239.090962) (xy 89.432638 -239.090962) (xy 89.385648 -239.243362)
			(xy 89.385648 -239.287812) (xy 89.741248 -239.287812)
		)
		(stroke
			(width 0)
			(type solid)
		)
		(fill yes)
		(layer "In4.Cu")
		(net "M_C_CPU1_SB_DQS_DP<4>")
	)
	(gr_poly
		(pts
			(xy 89.741248 -237.207806) (xy 89.741248 -237.163356) (xy 89.385648 -237.163356) (xy 89.385648 -237.207806)
			(xy 89.432638 -237.360206) (xy 89.694258 -237.360206)
		)
		(stroke
			(width 0)
			(type solid)
		)
		(fill yes)
		(layer "In4.Cu")
		(net "M_B_CPU1_SB_DQ<2>")
	)
	(gr_poly
		(pts
			(xy 89.741248 -235.579666) (xy 89.741248 -235.53547) (xy 89.385648 -235.53547) (xy 89.385648 -235.579666)
			(xy 89.432638 -235.732066) (xy 89.694258 -235.732066)
		)
		(stroke
			(width 0)
			(type solid)
		)
		(fill yes)
		(layer "In4.Cu")
		(net "M_B_CPU1_SB_DQS_DP<0>")
	)
	(gr_poly
		(pts
			(xy 89.741248 -234.360466) (xy 89.694258 -234.208066) (xy 89.432638 -234.208066) (xy 89.385648 -234.360466)
			(xy 89.385648 -234.404662) (xy 89.741248 -234.404662)
		)
		(stroke
			(width 0)
			(type solid)
		)
		(fill yes)
		(layer "In4.Cu")
		(net "M_B_CPU1_SB_DQS_DP<5>")
	)
	(gr_poly
		(pts
			(xy 89.741248 -230.696262) (xy 89.741248 -230.652066) (xy 89.385648 -230.652066) (xy 89.385648 -230.696262)
			(xy 89.432638 -230.848662) (xy 89.694258 -230.848662)
		)
		(stroke
			(width 0)
			(type solid)
		)
		(fill yes)
		(layer "In4.Cu")
		(net "M_C_CPU1_SB_DQS_DP<2>")
	)
	(gr_poly
		(pts
			(xy 89.741248 -227.848922) (xy 89.694258 -227.696522) (xy 89.432638 -227.696522) (xy 89.385648 -227.848922)
			(xy 89.385648 -227.893372) (xy 89.741248 -227.893372)
		)
		(stroke
			(width 0)
			(type solid)
		)
		(fill yes)
		(layer "In4.Cu")
		(net "M_C_CPU1_SB_DQ<23>")
	)
	(gr_poly
		(pts
			(xy 89.834212 -283.01569) (xy 89.834212 -282.971494) (xy 89.478612 -282.971494) (xy 89.478612 -283.01569)
			(xy 89.525602 -283.16809) (xy 89.787222 -283.16809)
		)
		(stroke
			(width 0)
			(type solid)
		)
		(fill yes)
		(layer "In4.Cu")
		(net "M_C_CPU1_SA_DQS_DP<0>")
	)
	(gr_poly
		(pts
			(xy 89.842594 -283.424122) (xy 89.795604 -283.271722) (xy 89.533984 -283.271722) (xy 89.486994 -283.424122)
			(xy 89.486994 -283.468572) (xy 89.842594 -283.468572)
		)
		(stroke
			(width 0)
			(type solid)
		)
		(fill yes)
		(layer "In4.Cu")
		(net "M_C_CPU1_SA_DQ<3>")
	)
	(gr_poly
		(pts
			(xy 89.842594 -275.284946) (xy 89.795604 -275.132546) (xy 89.533984 -275.132546) (xy 89.486994 -275.284946)
			(xy 89.486994 -275.329396) (xy 89.842594 -275.329396)
		)
		(stroke
			(width 0)
			(type solid)
		)
		(fill yes)
		(layer "In4.Cu")
		(net "M_C_CPU1_SA_DQ<7>")
	)
	(gr_poly
		(pts
			(xy 89.842594 -274.876514) (xy 89.842594 -274.832064) (xy 89.486994 -274.832064) (xy 89.486994 -274.876514)
			(xy 89.533984 -275.028914) (xy 89.795604 -275.028914)
		)
		(stroke
			(width 0)
			(type solid)
		)
		(fill yes)
		(layer "In4.Cu")
		(net "M_B_CPU1_SA_DQ<8>")
	)
	(gr_poly
		(pts
			(xy 89.842594 -273.657314) (xy 89.795604 -273.504914) (xy 89.533984 -273.504914) (xy 89.486994 -273.657314)
			(xy 89.486994 -273.701764) (xy 89.842594 -273.701764)
		)
		(stroke
			(width 0)
			(type solid)
		)
		(fill yes)
		(layer "In4.Cu")
		(net "M_B_CPU1_SA_DQ<11>")
	)
	(gr_poly
		(pts
			(xy 89.842594 -273.248882) (xy 89.842594 -273.204432) (xy 89.486994 -273.204432) (xy 89.486994 -273.248882)
			(xy 89.533984 -273.401282) (xy 89.795604 -273.401282)
		)
		(stroke
			(width 0)
			(type solid)
		)
		(fill yes)
		(layer "In4.Cu")
		(net "M_B_CPU1_SA_DQS_DP<1>")
	)
	(gr_poly
		(pts
			(xy 89.842594 -269.99311) (xy 89.842594 -269.948914) (xy 89.486994 -269.948914) (xy 89.486994 -269.99311)
			(xy 89.533984 -270.14551) (xy 89.795604 -270.14551)
		)
		(stroke
			(width 0)
			(type solid)
		)
		(fill yes)
		(layer "In4.Cu")
		(net "M_C_CPU1_SA_DQ<16>")
	)
	(gr_poly
		(pts
			(xy 89.842594 -266.737846) (xy 89.842594 -266.693396) (xy 89.486994 -266.693396) (xy 89.486994 -266.737846)
			(xy 89.533984 -266.890246) (xy 89.795604 -266.890246)
		)
		(stroke
			(width 0)
			(type solid)
		)
		(fill yes)
		(layer "In4.Cu")
		(net "M_C_CPU1_SA_DQ<20>")
	)
	(gr_poly
		(pts
			(xy 89.842594 -265.109706) (xy 89.842594 -265.06551) (xy 89.486994 -265.06551) (xy 89.486994 -265.109706)
			(xy 89.533984 -265.262106) (xy 89.795604 -265.262106)
		)
		(stroke
			(width 0)
			(type solid)
		)
		(fill yes)
		(layer "In4.Cu")
		(net "M_B_CPU1_SA_DQ<26>")
	)
	(gr_poly
		(pts
			(xy 89.842594 -263.482074) (xy 89.842594 -263.437878) (xy 89.486994 -263.437878) (xy 89.486994 -263.482074)
			(xy 89.533984 -263.634474) (xy 89.795604 -263.634474)
		)
		(stroke
			(width 0)
			(type solid)
		)
		(fill yes)
		(layer "In4.Cu")
		(net "M_B_CPU1_SA_DQS_DP<3>")
	)
	(gr_poly
		(pts
			(xy 89.842594 -261.854442) (xy 89.842594 -261.809992) (xy 89.486994 -261.809992) (xy 89.486994 -261.854442)
			(xy 89.533984 -262.006842) (xy 89.795604 -262.006842)
		)
		(stroke
			(width 0)
			(type solid)
		)
		(fill yes)
		(layer "In4.Cu")
		(net "M_B_CPU1_SA_DQ<28>")
	)
	(gr_poly
		(pts
			(xy 89.842594 -258.59867) (xy 89.842594 -258.554474) (xy 89.486994 -258.554474) (xy 89.486994 -258.59867)
			(xy 89.533984 -258.75107) (xy 89.795604 -258.75107)
		)
		(stroke
			(width 0)
			(type solid)
		)
		(fill yes)
		(layer "In4.Cu")
		(net "M_C_CPU1_SA_CS_N<0>")
	)
	(gr_poly
		(pts
			(xy 89.842594 -257.37947) (xy 89.795604 -257.22707) (xy 89.533984 -257.22707) (xy 89.486994 -257.37947)
			(xy 89.486994 -257.42392) (xy 89.842594 -257.42392)
		)
		(stroke
			(width 0)
			(type solid)
		)
		(fill yes)
		(layer "In4.Cu")
		(net "M_C_CPU1_SA_CS_N<3>")
	)
	(gr_poly
		(pts
			(xy 89.842594 -256.971038) (xy 89.842594 -256.926588) (xy 89.486994 -256.926588) (xy 89.486994 -256.971038)
			(xy 89.533984 -257.123438) (xy 89.795604 -257.123438)
		)
		(stroke
			(width 0)
			(type solid)
		)
		(fill yes)
		(layer "In4.Cu")
		(net "M_C_CPU1_SA_CA<0>")
	)
	(gr_poly
		(pts
			(xy 89.842594 -254.124206) (xy 89.795604 -253.971806) (xy 89.533984 -253.971806) (xy 89.486994 -254.124206)
			(xy 89.486994 -254.168402) (xy 89.842594 -254.168402)
		)
		(stroke
			(width 0)
			(type solid)
		)
		(fill yes)
		(layer "In4.Cu")
		(net "M_C_CPU1_SA_PAR")
	)
	(gr_poly
		(pts
			(xy 89.842848 -271.620742) (xy 89.842848 -271.576546) (xy 89.487248 -271.576546) (xy 89.487248 -271.620742)
			(xy 89.534238 -271.773142) (xy 89.795858 -271.773142)
		)
		(stroke
			(width 0)
			(type solid)
		)
		(fill yes)
		(layer "In4.Cu")
		(net "M_B_CPU1_SA_DQ<12>")
	)
	(gr_poly
		(pts
			(xy 89.842848 -270.40205) (xy 89.795858 -270.24965) (xy 89.534238 -270.24965) (xy 89.487248 -270.40205)
			(xy 89.487248 -270.446246) (xy 89.842848 -270.446246)
		)
		(stroke
			(width 0)
			(type solid)
		)
		(fill yes)
		(layer "In4.Cu")
		(net "M_B_CPU1_SA_DQ<15>")
	)
	(gr_poly
		(pts
			(xy 89.842848 -268.77391) (xy 89.795858 -268.62151) (xy 89.534238 -268.62151) (xy 89.487248 -268.77391)
			(xy 89.487248 -268.81836) (xy 89.842848 -268.81836)
		)
		(stroke
			(width 0)
			(type solid)
		)
		(fill yes)
		(layer "In4.Cu")
		(net "M_C_CPU1_SA_DQ<19>")
	)
	(gr_poly
		(pts
			(xy 89.842848 -268.365478) (xy 89.842848 -268.321028) (xy 89.487248 -268.321028) (xy 89.487248 -268.365478)
			(xy 89.534238 -268.517878) (xy 89.795858 -268.517878)
		)
		(stroke
			(width 0)
			(type solid)
		)
		(fill yes)
		(layer "In4.Cu")
		(net "M_C_CPU1_SA_DQS_DP<2>")
	)
	(gr_poly
		(pts
			(xy 89.842848 -267.146278) (xy 89.795858 -266.993878) (xy 89.534238 -266.993878) (xy 89.487248 -267.146278)
			(xy 89.487248 -267.190728) (xy 89.842848 -267.190728)
		)
		(stroke
			(width 0)
			(type solid)
		)
		(fill yes)
		(layer "In4.Cu")
		(net "M_C_CPU1_SA_DQS_DP<7>")
	)
	(gr_poly
		(pts
			(xy 89.842848 -265.518646) (xy 89.795858 -265.366246) (xy 89.534238 -265.366246) (xy 89.487248 -265.518646)
			(xy 89.487248 -265.563096) (xy 89.842848 -265.563096)
		)
		(stroke
			(width 0)
			(type solid)
		)
		(fill yes)
		(layer "In4.Cu")
		(net "M_C_CPU1_SA_DQ<23>")
	)
	(gr_poly
		(pts
			(xy 89.842848 -263.891014) (xy 89.795858 -263.738614) (xy 89.534238 -263.738614) (xy 89.487248 -263.891014)
			(xy 89.487248 -263.93521) (xy 89.842848 -263.93521)
		)
		(stroke
			(width 0)
			(type solid)
		)
		(fill yes)
		(layer "In4.Cu")
		(net "M_B_CPU1_SA_DQ<27>")
	)
	(gr_poly
		(pts
			(xy 89.842848 -262.262874) (xy 89.795858 -262.110474) (xy 89.534238 -262.110474) (xy 89.487248 -262.262874)
			(xy 89.487248 -262.307324) (xy 89.842848 -262.307324)
		)
		(stroke
			(width 0)
			(type solid)
		)
		(fill yes)
		(layer "In4.Cu")
		(net "M_B_CPU1_SA_DQS_DP<8>")
	)
	(gr_poly
		(pts
			(xy 89.84869 -272.029682) (xy 89.8017 -271.877282) (xy 89.54008 -271.877282) (xy 89.49309 -272.029682)
			(xy 89.49309 -272.073878) (xy 89.84869 -272.073878)
		)
		(stroke
			(width 0)
			(type solid)
		)
		(fill yes)
		(layer "In4.Cu")
		(net "M_B_CPU1_SA_DQS_DP<6>")
	)
	(gr_poly
		(pts
			(xy 89.84869 -260.635242) (xy 89.8017 -260.482842) (xy 89.54008 -260.482842) (xy 89.49309 -260.635242)
			(xy 89.49309 -260.679438) (xy 89.84869 -260.679438)
		)
		(stroke
			(width 0)
			(type solid)
		)
		(fill yes)
		(layer "In4.Cu")
		(net "M_B_CPU1_SA_DQ<31>")
	)
	(gr_poly
		(pts
			(xy 89.84869 -255.751838) (xy 89.8017 -255.599438) (xy 89.54008 -255.599438) (xy 89.49309 -255.751838)
			(xy 89.49309 -255.796288) (xy 89.84869 -255.796288)
		)
		(stroke
			(width 0)
			(type solid)
		)
		(fill yes)
		(layer "In4.Cu")
		(net "M_C_CPU1_SA_CA<3>")
	)
	(gr_poly
		(pts
			(xy 89.84869 -255.343406) (xy 89.84869 -255.298956) (xy 89.49309 -255.298956) (xy 89.49309 -255.343406)
			(xy 89.54008 -255.495806) (xy 89.8017 -255.495806)
		)
		(stroke
			(width 0)
			(type solid)
		)
		(fill yes)
		(layer "In4.Cu")
		(net "M_C_CPU1_SA_CA<4>")
	)
	(gr_poly
		(pts
			(xy 89.917524 -285.119318) (xy 89.809066 -285.002478) (xy 89.770712 -284.98038) (xy 89.592912 -285.288228)
			(xy 89.631266 -285.310326) (xy 89.786714 -285.345886)
		)
		(stroke
			(width 0)
			(type solid)
		)
		(fill yes)
		(layer "In4.Cu")
		(net "M_C_CPU1_SA_DQ<0>")
	)
	(gr_poly
		(pts
			(xy 89.917524 -278.608282) (xy 89.809066 -278.491442) (xy 89.770712 -278.469344) (xy 89.592912 -278.777192)
			(xy 89.631266 -278.79929) (xy 89.786714 -278.83485)
		)
		(stroke
			(width 0)
			(type solid)
		)
		(fill yes)
		(layer "In4.Cu")
		(net "M_C_CPU1_SA_DQS_DN<5>")
	)
	(gr_poly
		(pts
			(xy 89.917524 -276.980396) (xy 89.809066 -276.863556) (xy 89.770712 -276.841458) (xy 89.592912 -277.149306)
			(xy 89.631266 -277.171404) (xy 89.786714 -277.206964)
		)
		(stroke
			(width 0)
			(type solid)
		)
		(fill yes)
		(layer "In4.Cu")
		(net "M_C_CPU1_SA_DQ<4>")
	)
	(gr_poly
		(pts
			(xy 90.168222 -279.613106) (xy 90.206576 -279.591008) (xy 90.028776 -279.28316) (xy 89.990422 -279.305258)
			(xy 89.881964 -279.422098) (xy 90.012774 -279.648666)
		)
		(stroke
			(width 0)
			(type solid)
		)
		(fill yes)
		(layer "In4.Cu")
		(net "M_C_CPU1_SA_DQS_DN<0>")
	)
	(gr_poly
		(pts
			(xy 90.19413 -246.16029) (xy 90.19413 -246.116094) (xy 89.83853 -246.116094) (xy 89.83853 -246.16029)
			(xy 89.88552 -246.31269) (xy 90.14714 -246.31269)
		)
		(stroke
			(width 0)
			(type solid)
		)
		(fill yes)
		(layer "In4.Cu")
		(net "M_C_CPU1_SB_CA<4>")
	)
	(gr_poly
		(pts
			(xy 90.19413 -241.685318) (xy 90.14714 -241.532918) (xy 89.88552 -241.532918) (xy 89.83853 -241.685318)
			(xy 89.83853 -241.729514) (xy 90.19413 -241.729514)
		)
		(stroke
			(width 0)
			(type solid)
		)
		(fill yes)
		(layer "In4.Cu")
		(net "M_C_CPU1_SB_CB<6>")
	)
	(gr_poly
		(pts
			(xy 90.19413 -236.801914) (xy 90.14714 -236.649514) (xy 89.88552 -236.649514) (xy 89.83853 -236.801914)
			(xy 89.83853 -236.84611) (xy 90.19413 -236.84611)
		)
		(stroke
			(width 0)
			(type solid)
		)
		(fill yes)
		(layer "In4.Cu")
		(net "M_B_CPU1_SB_DQ<0>")
	)
	(gr_poly
		(pts
			(xy 90.19413 -228.254814) (xy 90.19413 -228.210618) (xy 89.83853 -228.210618) (xy 89.83853 -228.254814)
			(xy 89.88552 -228.407214) (xy 90.14714 -228.407214)
		)
		(stroke
			(width 0)
			(type solid)
		)
		(fill yes)
		(layer "In4.Cu")
		(net "M_C_CPU1_SB_DQ<21>")
	)
	(gr_poly
		(pts
			(xy 90.19667 -244.940582) (xy 90.14968 -244.788182) (xy 89.88806 -244.788182) (xy 89.84107 -244.940582)
			(xy 89.84107 -244.985032) (xy 90.19667 -244.985032)
		)
		(stroke
			(width 0)
			(type solid)
		)
		(fill yes)
		(layer "In4.Cu")
		(net "M_C_CPU1_SB_PAR")
	)
	(gr_poly
		(pts
			(xy 90.19667 -240.057178) (xy 90.14968 -239.904778) (xy 89.88806 -239.904778) (xy 89.84107 -240.057178)
			(xy 89.84107 -240.101628) (xy 90.19667 -240.101628)
		)
		(stroke
			(width 0)
			(type solid)
		)
		(fill yes)
		(layer "In4.Cu")
		(net "M_C_CPU1_SB_DQS_DN<9>")
	)
	(gr_poly
		(pts
			(xy 90.19667 -239.649254) (xy 90.19667 -239.604804) (xy 89.84107 -239.604804) (xy 89.84107 -239.649254)
			(xy 89.88806 -239.801654) (xy 90.14968 -239.801654)
		)
		(stroke
			(width 0)
			(type solid)
		)
		(fill yes)
		(layer "In4.Cu")
		(net "M_C_CPU1_SB_DQS_DN<4>")
	)
	(gr_poly
		(pts
			(xy 90.19667 -235.174282) (xy 90.14968 -235.021882) (xy 89.88806 -235.021882) (xy 89.84107 -235.174282)
			(xy 89.84107 -235.218478) (xy 90.19667 -235.218478)
		)
		(stroke
			(width 0)
			(type solid)
		)
		(fill yes)
		(layer "In4.Cu")
		(net "M_B_CPU1_SB_DQS_DN<0>")
	)
	(gr_poly
		(pts
			(xy 90.19667 -234.76585) (xy 90.19667 -234.721654) (xy 89.84107 -234.721654) (xy 89.84107 -234.76585)
			(xy 89.88806 -234.91825) (xy 90.14968 -234.91825)
		)
		(stroke
			(width 0)
			(type solid)
		)
		(fill yes)
		(layer "In4.Cu")
		(net "M_B_CPU1_SB_DQS_DN<5>")
	)
	(gr_poly
		(pts
			(xy 90.19667 -230.290878) (xy 90.14968 -230.138478) (xy 89.88806 -230.138478) (xy 89.84107 -230.290878)
			(xy 89.84107 -230.335074) (xy 90.19667 -230.335074)
		)
		(stroke
			(width 0)
			(type solid)
		)
		(fill yes)
		(layer "In4.Cu")
		(net "M_C_CPU1_SB_DQS_DN<2>")
	)
	(gr_poly
		(pts
			(xy 90.202258 -277.089108) (xy 90.163904 -277.06701) (xy 90.008456 -277.03145) (xy 89.877646 -277.258018)
			(xy 89.986104 -277.374858) (xy 90.024458 -277.396956)
		)
		(stroke
			(width 0)
			(type solid)
		)
		(fill yes)
		(layer "In4.Cu")
		(net "M_C_CPU1_SA_DQS_DP<5>")
	)
	(gr_poly
		(pts
			(xy 90.202512 -246.568722) (xy 90.155522 -246.416322) (xy 89.893902 -246.416322) (xy 89.846912 -246.568722)
			(xy 89.846912 -246.613172) (xy 90.202512 -246.613172)
		)
		(stroke
			(width 0)
			(type solid)
		)
		(fill yes)
		(layer "In4.Cu")
		(net "M_C_CPU1_SB_CA<3>")
	)
	(gr_poly
		(pts
			(xy 90.202512 -244.53215) (xy 90.202512 -244.487954) (xy 89.846912 -244.487954) (xy 89.846912 -244.53215)
			(xy 89.893902 -244.68455) (xy 90.155522 -244.68455)
		)
		(stroke
			(width 0)
			(type solid)
		)
		(fill yes)
		(layer "In4.Cu")
		(net "M_C_CPU1_SB_CS_N<2>")
	)
	(gr_poly
		(pts
			(xy 90.206068 -241.276886) (xy 90.206068 -241.232436) (xy 89.850468 -241.232436) (xy 89.850468 -241.276886)
			(xy 89.897458 -241.429286) (xy 90.159078 -241.429286)
		)
		(stroke
			(width 0)
			(type solid)
		)
		(fill yes)
		(layer "In4.Cu")
		(net "M_C_CPU1_SB_CB<5>")
	)
	(gr_poly
		(pts
			(xy 90.206068 -238.021114) (xy 90.206068 -237.976664) (xy 89.850468 -237.976664) (xy 89.850468 -238.021114)
			(xy 89.897458 -238.173514) (xy 90.159078 -238.173514)
		)
		(stroke
			(width 0)
			(type solid)
		)
		(fill yes)
		(layer "In4.Cu")
		(net "M_C_CPU1_SB_CB<1>")
	)
	(gr_poly
		(pts
			(xy 90.206068 -233.13771) (xy 90.206068 -233.093514) (xy 89.850468 -233.093514) (xy 89.850468 -233.13771)
			(xy 89.897458 -233.29011) (xy 90.159078 -233.29011)
		)
		(stroke
			(width 0)
			(type solid)
		)
		(fill yes)
		(layer "In4.Cu")
		(net "M_B_CPU1_SB_DQ<5>")
	)
	(gr_poly
		(pts
			(xy 90.206068 -231.919018) (xy 90.159078 -231.766618) (xy 89.897458 -231.766618) (xy 89.850468 -231.919018)
			(xy 89.850468 -231.963214) (xy 90.206068 -231.963214)
		)
		(stroke
			(width 0)
			(type solid)
		)
		(fill yes)
		(layer "In4.Cu")
		(net "M_C_CPU1_SB_DQ<18>")
	)
	(gr_poly
		(pts
			(xy 90.206068 -229.882446) (xy 90.206068 -229.837996) (xy 89.850468 -229.837996) (xy 89.850468 -229.882446)
			(xy 89.897458 -230.034846) (xy 90.159078 -230.034846)
		)
		(stroke
			(width 0)
			(type solid)
		)
		(fill yes)
		(layer "In4.Cu")
		(net "M_C_CPU1_SB_DQS_DN<7>")
	)
	(gr_poly
		(pts
			(xy 90.206576 -278.709628) (xy 90.168222 -278.68753) (xy 90.012774 -278.65197) (xy 89.881964 -278.878538)
			(xy 89.990422 -278.995378) (xy 90.028776 -279.017476)
		)
		(stroke
			(width 0)
			(type solid)
		)
		(fill yes)
		(layer "In4.Cu")
		(net "M_C_CPU1_SA_DQS_DN<0>")
	)
	(gr_poly
		(pts
			(xy 90.20683 -238.430054) (xy 90.15984 -238.277654) (xy 89.89822 -238.277654) (xy 89.85123 -238.430054)
			(xy 89.85123 -238.47425) (xy 90.20683 -238.47425)
		)
		(stroke
			(width 0)
			(type solid)
		)
		(fill yes)
		(layer "In4.Cu")
		(net "M_C_CPU1_SB_CB<2>")
	)
	(gr_poly
		(pts
			(xy 90.20683 -236.393482) (xy 90.20683 -236.349032) (xy 89.85123 -236.349032) (xy 89.85123 -236.393482)
			(xy 89.89822 -236.545882) (xy 90.15984 -236.545882)
		)
		(stroke
			(width 0)
			(type solid)
		)
		(fill yes)
		(layer "In4.Cu")
		(net "M_B_CPU1_SB_DQ<1>")
	)
	(gr_poly
		(pts
			(xy 90.20683 -233.54665) (xy 90.15984 -233.39425) (xy 89.89822 -233.39425) (xy 89.85123 -233.54665)
			(xy 89.85123 -233.5911) (xy 90.20683 -233.5911)
		)
		(stroke
			(width 0)
			(type solid)
		)
		(fill yes)
		(layer "In4.Cu")
		(net "M_B_CPU1_SB_DQ<6>")
	)
	(gr_poly
		(pts
			(xy 90.20683 -231.510078) (xy 90.20683 -231.465628) (xy 89.85123 -231.465628) (xy 89.85123 -231.510078)
			(xy 89.89822 -231.662478) (xy 90.15984 -231.662478)
		)
		(stroke
			(width 0)
			(type solid)
		)
		(fill yes)
		(layer "In4.Cu")
		(net "M_C_CPU1_SB_DQ<17>")
	)
	(gr_poly
		(pts
			(xy 90.20683 -228.663246) (xy 90.15984 -228.510846) (xy 89.89822 -228.510846) (xy 89.85123 -228.663246)
			(xy 89.85123 -228.707696) (xy 90.20683 -228.707696)
		)
		(stroke
			(width 0)
			(type solid)
		)
		(fill yes)
		(layer "In4.Cu")
		(net "M_C_CPU1_SB_DQ<22>")
	)
	(gr_poly
		(pts
			(xy 90.208608 -280.33345) (xy 90.170254 -280.311352) (xy 90.014806 -280.275792) (xy 89.883996 -280.50236)
			(xy 89.992454 -280.6192) (xy 90.030808 -280.641298)
		)
		(stroke
			(width 0)
			(type solid)
		)
		(fill yes)
		(layer "In4.Cu")
		(net "M_C_CPU1_SA_DQS_DN<0>")
	)
	(gr_poly
		(pts
			(xy 90.283538 -282.258008) (xy 90.391996 -282.141168) (xy 90.261186 -281.9146) (xy 90.105738 -281.95016)
			(xy 90.067384 -281.972258) (xy 90.245184 -282.280106)
		)
		(stroke
			(width 0)
			(type solid)
		)
		(fill yes)
		(layer "In4.Cu")
		(net "M_C_CPU1_SA_DQS_DP<0>")
	)
	(gr_poly
		(pts
			(xy 90.312494 -284.237938) (xy 90.265504 -284.085538) (xy 90.003884 -284.085538) (xy 89.956894 -284.237938)
			(xy 89.956894 -284.282388) (xy 90.312494 -284.282388)
		)
		(stroke
			(width 0)
			(type solid)
		)
		(fill yes)
		(layer "In4.Cu")
		(net "M_C_CPU1_SA_DQ<2>")
	)
	(gr_poly
		(pts
			(xy 90.312494 -283.829506) (xy 90.312494 -283.785056) (xy 89.956894 -283.785056) (xy 89.956894 -283.829506)
			(xy 90.003884 -283.981906) (xy 90.265504 -283.981906)
		)
		(stroke
			(width 0)
			(type solid)
		)
		(fill yes)
		(layer "In4.Cu")
		(net "M_C_CPU1_SA_DQ<1>")
	)
	(gr_poly
		(pts
			(xy 90.312494 -276.09927) (xy 90.265504 -275.94687) (xy 90.003884 -275.94687) (xy 89.956894 -276.09927)
			(xy 89.956894 -276.143466) (xy 90.312494 -276.143466)
		)
		(stroke
			(width 0)
			(type solid)
		)
		(fill yes)
		(layer "In4.Cu")
		(net "M_C_CPU1_SA_DQ<6>")
	)
	(gr_poly
		(pts
			(xy 90.312494 -275.690584) (xy 90.312494 -275.646134) (xy 89.956894 -275.646134) (xy 89.956894 -275.690584)
			(xy 90.003884 -275.842984) (xy 90.265504 -275.842984)
		)
		(stroke
			(width 0)
			(type solid)
		)
		(fill yes)
		(layer "In4.Cu")
		(net "M_C_CPU1_SA_DQ<5>")
	)
	(gr_poly
		(pts
			(xy 90.312494 -274.47113) (xy 90.265504 -274.31873) (xy 90.003884 -274.31873) (xy 89.956894 -274.47113)
			(xy 89.956894 -274.51558) (xy 90.312494 -274.51558)
		)
		(stroke
			(width 0)
			(type solid)
		)
		(fill yes)
		(layer "In4.Cu")
		(net "M_B_CPU1_SA_DQ<10>")
	)
	(gr_poly
		(pts
			(xy 90.312494 -274.062698) (xy 90.312494 -274.018248) (xy 89.956894 -274.018248) (xy 89.956894 -274.062698)
			(xy 90.003884 -274.215098) (xy 90.265504 -274.215098)
		)
		(stroke
			(width 0)
			(type solid)
		)
		(fill yes)
		(layer "In4.Cu")
		(net "M_B_CPU1_SA_DQ<9>")
	)
	(gr_poly
		(pts
			(xy 90.312494 -269.587726) (xy 90.265504 -269.435326) (xy 90.003884 -269.435326) (xy 89.956894 -269.587726)
			(xy 89.956894 -269.632176) (xy 90.312494 -269.632176)
		)
		(stroke
			(width 0)
			(type solid)
		)
		(fill yes)
		(layer "In4.Cu")
		(net "M_C_CPU1_SA_DQ<18>")
	)
	(gr_poly
		(pts
			(xy 90.312494 -266.332462) (xy 90.265504 -266.180062) (xy 90.003884 -266.180062) (xy 89.956894 -266.332462)
			(xy 89.956894 -266.376658) (xy 90.312494 -266.376658)
		)
		(stroke
			(width 0)
			(type solid)
		)
		(fill yes)
		(layer "In4.Cu")
		(net "M_C_CPU1_SA_DQ<22>")
	)
	(gr_poly
		(pts
			(xy 90.312494 -264.70483) (xy 90.265504 -264.55243) (xy 90.003884 -264.55243) (xy 89.956894 -264.70483)
			(xy 89.956894 -264.749026) (xy 90.312494 -264.749026)
		)
		(stroke
			(width 0)
			(type solid)
		)
		(fill yes)
		(layer "In4.Cu")
		(net "M_B_CPU1_SA_DQ<24>")
	)
	(gr_poly
		(pts
			(xy 90.312494 -261.449058) (xy 90.265504 -261.296658) (xy 90.003884 -261.296658) (xy 89.956894 -261.449058)
			(xy 89.956894 -261.493508) (xy 90.312494 -261.493508)
		)
		(stroke
			(width 0)
			(type solid)
		)
		(fill yes)
		(layer "In4.Cu")
		(net "M_B_CPU1_SA_DQ<30>")
	)
	(gr_poly
		(pts
			(xy 90.312494 -261.040626) (xy 90.312494 -260.996176) (xy 89.956894 -260.996176) (xy 89.956894 -261.040626)
			(xy 90.003884 -261.193026) (xy 90.265504 -261.193026)
		)
		(stroke
			(width 0)
			(type solid)
		)
		(fill yes)
		(layer "In4.Cu")
		(net "M_B_CPU1_SA_DQ<29>")
	)
	(gr_poly
		(pts
			(xy 90.312494 -256.565654) (xy 90.265504 -256.413254) (xy 90.003884 -256.413254) (xy 89.956894 -256.565654)
			(xy 89.956894 -256.610104) (xy 90.312494 -256.610104)
		)
		(stroke
			(width 0)
			(type solid)
		)
		(fill yes)
		(layer "In4.Cu")
		(net "M_C_CPU1_SA_CA<1>")
	)
	(gr_poly
		(pts
			(xy 90.312494 -256.157222) (xy 90.312494 -256.112772) (xy 89.956894 -256.112772) (xy 89.956894 -256.157222)
			(xy 90.003884 -256.309622) (xy 90.265504 -256.309622)
		)
		(stroke
			(width 0)
			(type solid)
		)
		(fill yes)
		(layer "In4.Cu")
		(net "M_C_CPU1_SA_CA<2>")
	)
	(gr_poly
		(pts
			(xy 90.312494 -254.938022) (xy 90.265504 -254.785622) (xy 90.003884 -254.785622) (xy 89.956894 -254.938022)
			(xy 89.956894 -254.982218) (xy 90.312494 -254.982218)
		)
		(stroke
			(width 0)
			(type solid)
		)
		(fill yes)
		(layer "In4.Cu")
		(net "M_C_CPU1_SA_CA<5>")
	)
	(gr_poly
		(pts
			(xy 90.312494 -254.529082) (xy 90.312494 -254.484886) (xy 89.956894 -254.484886) (xy 89.956894 -254.529082)
			(xy 90.003884 -254.681482) (xy 90.265504 -254.681482)
		)
		(stroke
			(width 0)
			(type solid)
		)
		(fill yes)
		(layer "In4.Cu")
		(net "M_C_CPU1_SA_CA<6>")
	)
	(gr_poly
		(pts
			(xy 90.31478 -271.215866) (xy 90.26779 -271.063466) (xy 90.00617 -271.063466) (xy 89.95918 -271.215866)
			(xy 89.95918 -271.260062) (xy 90.31478 -271.260062)
		)
		(stroke
			(width 0)
			(type solid)
		)
		(fill yes)
		(layer "In4.Cu")
		(net "M_B_CPU1_SA_DQ<14>")
	)
	(gr_poly
		(pts
			(xy 90.31478 -270.806926) (xy 90.31478 -270.76273) (xy 89.95918 -270.76273) (xy 89.95918 -270.806926)
			(xy 90.00617 -270.959326) (xy 90.26779 -270.959326)
		)
		(stroke
			(width 0)
			(type solid)
		)
		(fill yes)
		(layer "In4.Cu")
		(net "M_B_CPU1_SA_DQ<13>")
	)
	(gr_poly
		(pts
			(xy 90.31478 -269.179294) (xy 90.31478 -269.134844) (xy 89.95918 -269.134844) (xy 89.95918 -269.179294)
			(xy 90.00617 -269.331694) (xy 90.26779 -269.331694)
		)
		(stroke
			(width 0)
			(type solid)
		)
		(fill yes)
		(layer "In4.Cu")
		(net "M_C_CPU1_SA_DQ<17>")
	)
	(gr_poly
		(pts
			(xy 90.31478 -267.960094) (xy 90.26779 -267.807694) (xy 90.00617 -267.807694) (xy 89.95918 -267.960094)
			(xy 89.95918 -268.004544) (xy 90.31478 -268.004544)
		)
		(stroke
			(width 0)
			(type solid)
		)
		(fill yes)
		(layer "In4.Cu")
		(net "M_C_CPU1_SA_DQS_DN<2>")
	)
	(gr_poly
		(pts
			(xy 90.31478 -265.92403) (xy 90.31478 -265.87958) (xy 89.95918 -265.87958) (xy 89.95918 -265.92403)
			(xy 90.00617 -266.07643) (xy 90.26779 -266.07643)
		)
		(stroke
			(width 0)
			(type solid)
		)
		(fill yes)
		(layer "In4.Cu")
		(net "M_C_CPU1_SA_DQ<21>")
	)
	(gr_poly
		(pts
			(xy 90.31478 -264.29589) (xy 90.31478 -264.251694) (xy 89.95918 -264.251694) (xy 89.95918 -264.29589)
			(xy 90.00617 -264.44829) (xy 90.26779 -264.44829)
		)
		(stroke
			(width 0)
			(type solid)
		)
		(fill yes)
		(layer "In4.Cu")
		(net "M_B_CPU1_SA_DQ<25>")
	)
	(gr_poly
		(pts
			(xy 90.31478 -262.668258) (xy 90.31478 -262.623808) (xy 89.95918 -262.623808) (xy 89.95918 -262.668258)
			(xy 90.00617 -262.820658) (xy 90.26779 -262.820658)
		)
		(stroke
			(width 0)
			(type solid)
		)
		(fill yes)
		(layer "In4.Cu")
		(net "M_B_CPU1_SA_DQS_DN<8>")
	)
	(gr_poly
		(pts
			(xy 90.315796 -267.551154) (xy 90.315796 -267.506958) (xy 89.960196 -267.506958) (xy 89.960196 -267.551154)
			(xy 90.007186 -267.703554) (xy 90.268806 -267.703554)
		)
		(stroke
			(width 0)
			(type solid)
		)
		(fill yes)
		(layer "In4.Cu")
		(net "M_C_CPU1_SA_DQS_DN<7>")
	)
	(gr_poly
		(pts
			(xy 90.31859 -272.843498) (xy 90.2716 -272.691098) (xy 90.00998 -272.691098) (xy 89.96299 -272.843498)
			(xy 89.96299 -272.887694) (xy 90.31859 -272.887694)
		)
		(stroke
			(width 0)
			(type solid)
		)
		(fill yes)
		(layer "In4.Cu")
		(net "M_B_CPU1_SA_DQS_DN<1>")
	)
	(gr_poly
		(pts
			(xy 90.31859 -272.435066) (xy 90.31859 -272.39087) (xy 89.96299 -272.39087) (xy 89.96299 -272.435066)
			(xy 90.00998 -272.587466) (xy 90.2716 -272.587466)
		)
		(stroke
			(width 0)
			(type solid)
		)
		(fill yes)
		(layer "In4.Cu")
		(net "M_B_CPU1_SA_DQS_DN<6>")
	)
	(gr_poly
		(pts
			(xy 90.31859 -263.07669) (xy 90.2716 -262.92429) (xy 90.00998 -262.92429) (xy 89.96299 -263.07669)
			(xy 89.96299 -263.120886) (xy 90.31859 -263.120886)
		)
		(stroke
			(width 0)
			(type solid)
		)
		(fill yes)
		(layer "In4.Cu")
		(net "M_B_CPU1_SA_DQS_DN<3>")
	)
	(gr_poly
		(pts
			(xy 90.31859 -258.193286) (xy 90.2716 -258.040886) (xy 90.00998 -258.040886) (xy 89.96299 -258.193286)
			(xy 89.96299 -258.237482) (xy 90.31859 -258.237482)
		)
		(stroke
			(width 0)
			(type solid)
		)
		(fill yes)
		(layer "In4.Cu")
		(net "M_C_CPU1_SA_CS_N<2>")
	)
	(gr_poly
		(pts
			(xy 90.31859 -257.784854) (xy 90.31859 -257.740658) (xy 89.96299 -257.740658) (xy 89.96299 -257.784854)
			(xy 90.00998 -257.937254) (xy 90.2716 -257.937254)
		)
		(stroke
			(width 0)
			(type solid)
		)
		(fill yes)
		(layer "In4.Cu")
		(net "M_C_CPU1_SA_CS_N<1>")
	)
	(gr_poly
		(pts
			(xy 90.386662 -282.679648) (xy 90.278204 -282.562808) (xy 90.23985 -282.54071) (xy 90.06205 -282.848558)
			(xy 90.100404 -282.870656) (xy 90.255852 -282.906216)
		)
		(stroke
			(width 0)
			(type solid)
		)
		(fill yes)
		(layer "In4.Cu")
		(net "M_C_CPU1_SA_DQS_DP<0>")
	)
	(gr_poly
		(pts
			(xy 90.387424 -281.049984) (xy 90.278966 -280.933144) (xy 90.240612 -280.911046) (xy 90.062812 -281.218894)
			(xy 90.101166 -281.240992) (xy 90.256614 -281.276552)
		)
		(stroke
			(width 0)
			(type solid)
		)
		(fill yes)
		(layer "In4.Cu")
		(net "M_C_CPU1_SA_DQS_DP<0>")
	)
	(gr_poly
		(pts
			(xy 90.388186 -277.79345) (xy 90.279728 -277.67661) (xy 90.241374 -277.654512) (xy 90.063574 -277.96236)
			(xy 90.101928 -277.984458) (xy 90.257376 -278.020018)
		)
		(stroke
			(width 0)
			(type solid)
		)
		(fill yes)
		(layer "In4.Cu")
		(net "M_C_CPU1_SA_DQS_DN<5>")
	)
	(gr_poly
		(pts
			(xy 90.633804 -282.047696) (xy 90.672158 -282.025598) (xy 90.494358 -281.71775) (xy 90.456004 -281.739848)
			(xy 90.347546 -281.856688) (xy 90.478356 -282.083256)
		)
		(stroke
			(width 0)
			(type solid)
		)
		(fill yes)
		(layer "In4.Cu")
		(net "M_C_CPU1_SA_DQ<3>")
	)
	(gr_poly
		(pts
			(xy 90.633804 -259.258562) (xy 90.672158 -259.236464) (xy 90.494358 -258.928616) (xy 90.456004 -258.950714)
			(xy 90.347546 -259.067554) (xy 90.478356 -259.294122)
		)
		(stroke
			(width 0)
			(type solid)
		)
		(fill yes)
		(layer "In4.Cu")
		(net "M_C_CPU1_SA_CS_N<0>")
	)
	(gr_poly
		(pts
			(xy 90.664284 -235.579666) (xy 90.664284 -235.53547) (xy 90.308684 -235.53547) (xy 90.308684 -235.579666)
			(xy 90.355674 -235.732066) (xy 90.617294 -235.732066)
		)
		(stroke
			(width 0)
			(type solid)
		)
		(fill yes)
		(layer "In4.Cu")
		(net "M_B_CPU1_SB_DQS_DP<0>")
	)
	(gr_poly
		(pts
			(xy 90.664284 -230.696262) (xy 90.664284 -230.652066) (xy 90.308684 -230.652066) (xy 90.308684 -230.696262)
			(xy 90.355674 -230.848662) (xy 90.617294 -230.848662)
		)
		(stroke
			(width 0)
			(type solid)
		)
		(fill yes)
		(layer "In4.Cu")
		(net "M_C_CPU1_SB_DQS_DP<2>")
	)
	(gr_poly
		(pts
			(xy 90.66657 -245.346474) (xy 90.66657 -245.302024) (xy 90.31097 -245.302024) (xy 90.31097 -245.346474)
			(xy 90.35796 -245.498874) (xy 90.61958 -245.498874)
		)
		(stroke
			(width 0)
			(type solid)
		)
		(fill yes)
		(layer "In4.Cu")
		(net "M_C_CPU1_SB_CA<6>")
	)
	(gr_poly
		(pts
			(xy 90.668348 -238.83493) (xy 90.668348 -238.790734) (xy 90.312748 -238.790734) (xy 90.312748 -238.83493)
			(xy 90.359738 -238.98733) (xy 90.621358 -238.98733)
		)
		(stroke
			(width 0)
			(type solid)
		)
		(fill yes)
		(layer "In4.Cu")
		(net "M_C_CPU1_SB_CB<0>")
	)
	(gr_poly
		(pts
			(xy 90.668348 -235.988606) (xy 90.621358 -235.836206) (xy 90.359738 -235.836206) (xy 90.312748 -235.988606)
			(xy 90.312748 -236.032802) (xy 90.668348 -236.032802)
		)
		(stroke
			(width 0)
			(type solid)
		)
		(fill yes)
		(layer "In4.Cu")
		(net "M_B_CPU1_SB_DQ<3>")
	)
	(gr_poly
		(pts
			(xy 90.668348 -233.951526) (xy 90.668348 -233.90733) (xy 90.312748 -233.90733) (xy 90.312748 -233.951526)
			(xy 90.359738 -234.103926) (xy 90.621358 -234.103926)
		)
		(stroke
			(width 0)
			(type solid)
		)
		(fill yes)
		(layer "In4.Cu")
		(net "M_B_CPU1_SB_DQ<4>")
	)
	(gr_poly
		(pts
			(xy 90.668348 -231.105202) (xy 90.621358 -230.952802) (xy 90.359738 -230.952802) (xy 90.312748 -231.105202)
			(xy 90.312748 -231.149398) (xy 90.668348 -231.149398)
		)
		(stroke
			(width 0)
			(type solid)
		)
		(fill yes)
		(layer "In4.Cu")
		(net "M_C_CPU1_SB_DQ<19>")
	)
	(gr_poly
		(pts
			(xy 90.668348 -229.068122) (xy 90.668348 -229.023926) (xy 90.312748 -229.023926) (xy 90.312748 -229.068122)
			(xy 90.359738 -229.220522) (xy 90.621358 -229.220522)
		)
		(stroke
			(width 0)
			(type solid)
		)
		(fill yes)
		(layer "In4.Cu")
		(net "M_C_CPU1_SB_DQ<20>")
	)
	(gr_poly
		(pts
			(xy 90.66911 -240.871502) (xy 90.62212 -240.719102) (xy 90.3605 -240.719102) (xy 90.31351 -240.871502)
			(xy 90.31351 -240.915952) (xy 90.66911 -240.915952)
		)
		(stroke
			(width 0)
			(type solid)
		)
		(fill yes)
		(layer "In4.Cu")
		(net "M_C_CPU1_SB_CB<7>")
	)
	(gr_poly
		(pts
			(xy 90.66911 -237.616238) (xy 90.62212 -237.463838) (xy 90.3605 -237.463838) (xy 90.31351 -237.616238)
			(xy 90.31351 -237.660434) (xy 90.66911 -237.660434)
		)
		(stroke
			(width 0)
			(type solid)
		)
		(fill yes)
		(layer "In4.Cu")
		(net "M_C_CPU1_SB_CB<3>")
	)
	(gr_poly
		(pts
			(xy 90.66911 -232.732834) (xy 90.62212 -232.580434) (xy 90.3605 -232.580434) (xy 90.31351 -232.732834)
			(xy 90.31351 -232.77703) (xy 90.66911 -232.77703)
		)
		(stroke
			(width 0)
			(type solid)
		)
		(fill yes)
		(layer "In4.Cu")
		(net "M_B_CPU1_SB_DQ<7>")
	)
	(gr_poly
		(pts
			(xy 90.66911 -232.323894) (xy 90.66911 -232.279698) (xy 90.31351 -232.279698) (xy 90.31351 -232.323894)
			(xy 90.3605 -232.476294) (xy 90.62212 -232.476294)
		)
		(stroke
			(width 0)
			(type solid)
		)
		(fill yes)
		(layer "In4.Cu")
		(net "M_C_CPU1_SB_DQ<16>")
	)
	(gr_poly
		(pts
			(xy 90.66911 -229.477062) (xy 90.62212 -229.324662) (xy 90.3605 -229.324662) (xy 90.31351 -229.477062)
			(xy 90.31351 -229.521512) (xy 90.66911 -229.521512)
		)
		(stroke
			(width 0)
			(type solid)
		)
		(fill yes)
		(layer "In4.Cu")
		(net "M_C_CPU1_SB_DQS_DP<7>")
	)
	(gr_poly
		(pts
			(xy 90.672666 -239.24387) (xy 90.625676 -239.09147) (xy 90.364056 -239.09147) (xy 90.317066 -239.24387)
			(xy 90.317066 -239.288066) (xy 90.672666 -239.288066)
		)
		(stroke
			(width 0)
			(type solid)
		)
		(fill yes)
		(layer "In4.Cu")
		(net "M_C_CPU1_SB_DQS_DP<4>")
	)
	(gr_poly
		(pts
			(xy 90.672666 -234.360466) (xy 90.625676 -234.208066) (xy 90.364056 -234.208066) (xy 90.317066 -234.360466)
			(xy 90.317066 -234.404916) (xy 90.672666 -234.404916)
		)
		(stroke
			(width 0)
			(type solid)
		)
		(fill yes)
		(layer "In4.Cu")
		(net "M_B_CPU1_SB_DQS_DP<5>")
	)
	(gr_poly
		(pts
			(xy 90.676476 -281.15133) (xy 90.638122 -281.129232) (xy 90.482674 -281.093672) (xy 90.351864 -281.32024)
			(xy 90.460322 -281.43708) (xy 90.498676 -281.459178)
		)
		(stroke
			(width 0)
			(type solid)
		)
		(fill yes)
		(layer "In4.Cu")
		(net "M_C_CPU1_SA_DQ<3>")
	)
	(gr_poly
		(pts
			(xy 90.677492 -282.777184) (xy 90.639138 -282.755086) (xy 90.48369 -282.719526) (xy 90.35288 -282.946094)
			(xy 90.461338 -283.062934) (xy 90.499692 -283.085032)
		)
		(stroke
			(width 0)
			(type solid)
		)
		(fill yes)
		(layer "In4.Cu")
		(net "M_C_CPU1_SA_DQ<3>")
	)
	(gr_poly
		(pts
			(xy 90.677492 -277.89378) (xy 90.639138 -277.871682) (xy 90.48369 -277.836122) (xy 90.35288 -278.06269)
			(xy 90.461338 -278.17953) (xy 90.499692 -278.201628)
		)
		(stroke
			(width 0)
			(type solid)
		)
		(fill yes)
		(layer "In4.Cu")
		(net "M_C_CPU1_SA_DQS_DN<0>")
	)
	(gr_poly
		(pts
			(xy 90.678508 -246.974106) (xy 90.678508 -246.92991) (xy 90.322908 -246.92991) (xy 90.322908 -246.974106)
			(xy 90.369898 -247.126506) (xy 90.631518 -247.126506)
		)
		(stroke
			(width 0)
			(type solid)
		)
		(fill yes)
		(layer "In4.Cu")
		(net "M_C_CPU1_SB_CA<2>")
	)
	(gr_poly
		(pts
			(xy 90.678508 -245.754906) (xy 90.631518 -245.602506) (xy 90.369898 -245.602506) (xy 90.322908 -245.754906)
			(xy 90.322908 -245.799356) (xy 90.678508 -245.799356)
		)
		(stroke
			(width 0)
			(type solid)
		)
		(fill yes)
		(layer "In4.Cu")
		(net "M_C_CPU1_SB_CA<5>")
	)
	(gr_poly
		(pts
			(xy 90.681048 -242.090702) (xy 90.681048 -242.046506) (xy 90.325448 -242.046506) (xy 90.325448 -242.090702)
			(xy 90.372438 -242.243102) (xy 90.634058 -242.243102)
		)
		(stroke
			(width 0)
			(type solid)
		)
		(fill yes)
		(layer "In4.Cu")
		(net "M_C_CPU1_SB_CB<4>")
	)
	(gr_poly
		(pts
			(xy 90.681048 -237.207806) (xy 90.681048 -237.163356) (xy 90.325448 -237.163356) (xy 90.325448 -237.207806)
			(xy 90.372438 -237.360206) (xy 90.634058 -237.360206)
		)
		(stroke
			(width 0)
			(type solid)
		)
		(fill yes)
		(layer "In4.Cu")
		(net "M_B_CPU1_SB_DQ<2>")
	)
	(gr_poly
		(pts
			(xy 90.681048 -227.848922) (xy 90.634058 -227.696522) (xy 90.372438 -227.696522) (xy 90.325448 -227.848922)
			(xy 90.325448 -227.893372) (xy 90.681048 -227.893372)
		)
		(stroke
			(width 0)
			(type solid)
		)
		(fill yes)
		(layer "In4.Cu")
		(net "M_C_CPU1_SB_DQ<23>")
	)
	(gr_poly
		(pts
			(xy 90.748104 -258.646168) (xy 90.856562 -258.529328) (xy 90.725752 -258.30276) (xy 90.570304 -258.33832)
			(xy 90.53195 -258.360418) (xy 90.70975 -258.668266)
		)
		(stroke
			(width 0)
			(type solid)
		)
		(fill yes)
		(layer "In4.Cu")
		(net "M_C_CPU1_SA_CS_N<2>")
	)
	(gr_poly
		(pts
			(xy 90.755216 -279.819354) (xy 90.863674 -279.702514) (xy 90.732864 -279.475946) (xy 90.577416 -279.511506)
			(xy 90.539062 -279.533604) (xy 90.716862 -279.841452)
		)
		(stroke
			(width 0)
			(type solid)
		)
		(fill yes)
		(layer "In4.Cu")
		(net "M_C_CPU1_SA_DQS_DP<0>")
	)
	(gr_poly
		(pts
			(xy 90.774012 -276.912578) (xy 90.727022 -276.760178) (xy 90.465402 -276.760178) (xy 90.418412 -276.912578)
			(xy 90.418412 -276.957028) (xy 90.774012 -276.957028)
		)
		(stroke
			(width 0)
			(type solid)
		)
		(fill yes)
		(layer "In4.Cu")
		(net "M_C_CPU1_SA_DQS_DP<5>")
	)
	(gr_poly
		(pts
			(xy 90.774012 -272.029174) (xy 90.727022 -271.876774) (xy 90.465402 -271.876774) (xy 90.418412 -272.029174)
			(xy 90.418412 -272.073624) (xy 90.774012 -272.073624)
		)
		(stroke
			(width 0)
			(type solid)
		)
		(fill yes)
		(layer "In4.Cu")
		(net "M_B_CPU1_SA_DQS_DP<6>")
	)
	(gr_poly
		(pts
			(xy 90.774012 -257.37947) (xy 90.727022 -257.22707) (xy 90.465402 -257.22707) (xy 90.418412 -257.37947)
			(xy 90.418412 -257.423666) (xy 90.774012 -257.423666)
		)
		(stroke
			(width 0)
			(type solid)
		)
		(fill yes)
		(layer "In4.Cu")
		(net "M_C_CPU1_SA_CS_N<3>")
	)
	(gr_poly
		(pts
			(xy 90.774266 -273.248882) (xy 90.774266 -273.204686) (xy 90.418666 -273.204686) (xy 90.418666 -273.248882)
			(xy 90.465656 -273.401282) (xy 90.727276 -273.401282)
		)
		(stroke
			(width 0)
			(type solid)
		)
		(fill yes)
		(layer "In4.Cu")
		(net "M_B_CPU1_SA_DQS_DP<1>")
	)
	(gr_poly
		(pts
			(xy 90.774266 -268.365478) (xy 90.774266 -268.321282) (xy 90.418666 -268.321282) (xy 90.418666 -268.365478)
			(xy 90.465656 -268.517878) (xy 90.727276 -268.517878)
		)
		(stroke
			(width 0)
			(type solid)
		)
		(fill yes)
		(layer "In4.Cu")
		(net "M_C_CPU1_SA_DQS_DP<2>")
	)
	(gr_poly
		(pts
			(xy 90.77833 -267.146278) (xy 90.73134 -266.993878) (xy 90.46972 -266.993878) (xy 90.42273 -267.146278)
			(xy 90.42273 -267.190728) (xy 90.77833 -267.190728)
		)
		(stroke
			(width 0)
			(type solid)
		)
		(fill yes)
		(layer "In4.Cu")
		(net "M_C_CPU1_SA_DQS_DP<7>")
	)
	(gr_poly
		(pts
			(xy 90.779092 -271.620742) (xy 90.779092 -271.576546) (xy 90.423492 -271.576546) (xy 90.423492 -271.620742)
			(xy 90.470482 -271.773142) (xy 90.732102 -271.773142)
		)
		(stroke
			(width 0)
			(type solid)
		)
		(fill yes)
		(layer "In4.Cu")
		(net "M_B_CPU1_SA_DQ<12>")
	)
	(gr_poly
		(pts
			(xy 90.779092 -270.40205) (xy 90.732102 -270.24965) (xy 90.470482 -270.24965) (xy 90.423492 -270.40205)
			(xy 90.423492 -270.446246) (xy 90.779092 -270.446246)
		)
		(stroke
			(width 0)
			(type solid)
		)
		(fill yes)
		(layer "In4.Cu")
		(net "M_B_CPU1_SA_DQ<15>")
	)
	(gr_poly
		(pts
			(xy 90.779092 -268.77391) (xy 90.732102 -268.62151) (xy 90.470482 -268.62151) (xy 90.423492 -268.77391)
			(xy 90.423492 -268.81836) (xy 90.779092 -268.81836)
		)
		(stroke
			(width 0)
			(type solid)
		)
		(fill yes)
		(layer "In4.Cu")
		(net "M_C_CPU1_SA_DQ<19>")
	)
	(gr_poly
		(pts
			(xy 90.779092 -265.518646) (xy 90.732102 -265.366246) (xy 90.470482 -265.366246) (xy 90.423492 -265.518646)
			(xy 90.423492 -265.563096) (xy 90.779092 -265.563096)
		)
		(stroke
			(width 0)
			(type solid)
		)
		(fill yes)
		(layer "In4.Cu")
		(net "M_C_CPU1_SA_DQ<23>")
	)
	(gr_poly
		(pts
			(xy 90.779092 -263.891014) (xy 90.732102 -263.738614) (xy 90.470482 -263.738614) (xy 90.423492 -263.891014)
			(xy 90.423492 -263.93521) (xy 90.779092 -263.93521)
		)
		(stroke
			(width 0)
			(type solid)
		)
		(fill yes)
		(layer "In4.Cu")
		(net "M_B_CPU1_SA_DQ<27>")
	)
	(gr_poly
		(pts
			(xy 90.779092 -262.262874) (xy 90.732102 -262.110474) (xy 90.470482 -262.110474) (xy 90.423492 -262.262874)
			(xy 90.423492 -262.307324) (xy 90.779092 -262.307324)
		)
		(stroke
			(width 0)
			(type solid)
		)
		(fill yes)
		(layer "In4.Cu")
		(net "M_B_CPU1_SA_DQS_DP<8>")
	)
	(gr_poly
		(pts
			(xy 90.782394 -284.643068) (xy 90.782394 -284.598872) (xy 90.426794 -284.598872) (xy 90.426794 -284.643068)
			(xy 90.473784 -284.795468) (xy 90.735404 -284.795468)
		)
		(stroke
			(width 0)
			(type solid)
		)
		(fill yes)
		(layer "In4.Cu")
		(net "M_C_CPU1_SA_DQ<0>")
	)
	(gr_poly
		(pts
			(xy 90.782394 -276.504146) (xy 90.782394 -276.45995) (xy 90.426794 -276.45995) (xy 90.426794 -276.504146)
			(xy 90.473784 -276.656546) (xy 90.735404 -276.656546)
		)
		(stroke
			(width 0)
			(type solid)
		)
		(fill yes)
		(layer "In4.Cu")
		(net "M_C_CPU1_SA_DQ<4>")
	)
	(gr_poly
		(pts
			(xy 90.782394 -266.737846) (xy 90.782394 -266.693396) (xy 90.426794 -266.693396) (xy 90.426794 -266.737846)
			(xy 90.473784 -266.890246) (xy 90.735404 -266.890246)
		)
		(stroke
			(width 0)
			(type solid)
		)
		(fill yes)
		(layer "In4.Cu")
		(net "M_C_CPU1_SA_DQ<20>")
	)
	(gr_poly
		(pts
			(xy 90.782394 -261.854442) (xy 90.782394 -261.809992) (xy 90.426794 -261.809992) (xy 90.426794 -261.854442)
			(xy 90.473784 -262.006842) (xy 90.735404 -262.006842)
		)
		(stroke
			(width 0)
			(type solid)
		)
		(fill yes)
		(layer "In4.Cu")
		(net "M_B_CPU1_SA_DQ<28>")
	)
	(gr_poly
		(pts
			(xy 90.782394 -256.971038) (xy 90.782394 -256.926588) (xy 90.426794 -256.926588) (xy 90.426794 -256.971038)
			(xy 90.473784 -257.123438) (xy 90.735404 -257.123438)
		)
		(stroke
			(width 0)
			(type solid)
		)
		(fill yes)
		(layer "In4.Cu")
		(net "M_C_CPU1_SA_CA<0>")
	)
	(gr_poly
		(pts
			(xy 90.78849 -275.284946) (xy 90.7415 -275.132546) (xy 90.47988 -275.132546) (xy 90.43289 -275.284946)
			(xy 90.43289 -275.329142) (xy 90.78849 -275.329142)
		)
		(stroke
			(width 0)
			(type solid)
		)
		(fill yes)
		(layer "In4.Cu")
		(net "M_C_CPU1_SA_DQ<7>")
	)
	(gr_poly
		(pts
			(xy 90.78849 -274.876514) (xy 90.78849 -274.832318) (xy 90.43289 -274.832318) (xy 90.43289 -274.876514)
			(xy 90.47988 -275.028914) (xy 90.7415 -275.028914)
		)
		(stroke
			(width 0)
			(type solid)
		)
		(fill yes)
		(layer "In4.Cu")
		(net "M_B_CPU1_SA_DQ<8>")
	)
	(gr_poly
		(pts
			(xy 90.78849 -273.657314) (xy 90.7415 -273.504914) (xy 90.47988 -273.504914) (xy 90.43289 -273.657314)
			(xy 90.43289 -273.70151) (xy 90.78849 -273.70151)
		)
		(stroke
			(width 0)
			(type solid)
		)
		(fill yes)
		(layer "In4.Cu")
		(net "M_B_CPU1_SA_DQ<11>")
	)
	(gr_poly
		(pts
			(xy 90.78849 -269.993618) (xy 90.78849 -269.949168) (xy 90.43289 -269.949168) (xy 90.43289 -269.993618)
			(xy 90.47988 -270.146018) (xy 90.7415 -270.146018)
		)
		(stroke
			(width 0)
			(type solid)
		)
		(fill yes)
		(layer "In4.Cu")
		(net "M_C_CPU1_SA_DQ<16>")
	)
	(gr_poly
		(pts
			(xy 90.78849 -265.110214) (xy 90.78849 -265.065764) (xy 90.43289 -265.065764) (xy 90.43289 -265.110214)
			(xy 90.47988 -265.262614) (xy 90.7415 -265.262614)
		)
		(stroke
			(width 0)
			(type solid)
		)
		(fill yes)
		(layer "In4.Cu")
		(net "M_B_CPU1_SA_DQ<26>")
	)
	(gr_poly
		(pts
			(xy 90.78849 -260.634734) (xy 90.7415 -260.482334) (xy 90.47988 -260.482334) (xy 90.43289 -260.634734)
			(xy 90.43289 -260.679184) (xy 90.78849 -260.679184)
		)
		(stroke
			(width 0)
			(type solid)
		)
		(fill yes)
		(layer "In4.Cu")
		(net "M_B_CPU1_SA_DQ<31>")
	)
	(gr_poly
		(pts
			(xy 90.78849 -255.751838) (xy 90.7415 -255.599438) (xy 90.47988 -255.599438) (xy 90.43289 -255.751838)
			(xy 90.43289 -255.796034) (xy 90.78849 -255.796034)
		)
		(stroke
			(width 0)
			(type solid)
		)
		(fill yes)
		(layer "In4.Cu")
		(net "M_C_CPU1_SA_CA<3>")
	)
	(gr_poly
		(pts
			(xy 90.78849 -255.343406) (xy 90.78849 -255.29921) (xy 90.43289 -255.29921) (xy 90.43289 -255.343406)
			(xy 90.47988 -255.495806) (xy 90.7415 -255.495806)
		)
		(stroke
			(width 0)
			(type solid)
		)
		(fill yes)
		(layer "In4.Cu")
		(net "M_C_CPU1_SA_CA<4>")
	)
	(gr_poly
		(pts
			(xy 90.78849 -254.123698) (xy 90.7415 -253.971298) (xy 90.47988 -253.971298) (xy 90.43289 -254.123698)
			(xy 90.43289 -254.168148) (xy 90.78849 -254.168148)
		)
		(stroke
			(width 0)
			(type solid)
		)
		(fill yes)
		(layer "In4.Cu")
		(net "M_C_CPU1_SA_PAR")
	)
	(gr_poly
		(pts
			(xy 90.857324 -278.608282) (xy 90.748866 -278.491442) (xy 90.710512 -278.469344) (xy 90.532712 -278.777192)
			(xy 90.571066 -278.79929) (xy 90.726514 -278.83485)
		)
		(stroke
			(width 0)
			(type solid)
		)
		(fill yes)
		(layer "In4.Cu")
		(net "M_C_CPU1_SA_DQS_DP<0>")
	)
	(gr_poly
		(pts
			(xy 90.858086 -280.235152) (xy 90.749628 -280.118312) (xy 90.711274 -280.096214) (xy 90.533474 -280.404062)
			(xy 90.571828 -280.42616) (xy 90.727276 -280.46172)
		)
		(stroke
			(width 0)
			(type solid)
		)
		(fill yes)
		(layer "In4.Cu")
		(net "M_C_CPU1_SA_DQS_DP<0>")
	)
	(gr_poly
		(pts
			(xy 90.863674 -283.481526) (xy 90.755216 -283.364686) (xy 90.716862 -283.342588) (xy 90.539062 -283.650436)
			(xy 90.577416 -283.672534) (xy 90.732864 -283.708094)
		)
		(stroke
			(width 0)
			(type solid)
		)
		(fill yes)
		(layer "In4.Cu")
		(net "M_C_CPU1_SA_DQ<1>")
	)
	(gr_poly
		(pts
			(xy 91.103704 -279.605994) (xy 91.142058 -279.583896) (xy 90.964258 -279.276048) (xy 90.925904 -279.298146)
			(xy 90.817446 -279.414986) (xy 90.948256 -279.641554)
		)
		(stroke
			(width 0)
			(type solid)
		)
		(fill yes)
		(layer "In4.Cu")
		(net "M_C_CPU1_SA_DQ<3>")
	)
	(gr_poly
		(pts
			(xy 91.13393 -246.568722) (xy 91.08694 -246.416322) (xy 90.82532 -246.416322) (xy 90.77833 -246.568722)
			(xy 90.77833 -246.612918) (xy 91.13393 -246.612918)
		)
		(stroke
			(width 0)
			(type solid)
		)
		(fill yes)
		(layer "In4.Cu")
		(net "M_C_CPU1_SB_CA<3>")
	)
	(gr_poly
		(pts
			(xy 91.13393 -241.685318) (xy 91.08694 -241.532918) (xy 90.82532 -241.532918) (xy 90.77833 -241.685318)
			(xy 90.77833 -241.729514) (xy 91.13393 -241.729514)
		)
		(stroke
			(width 0)
			(type solid)
		)
		(fill yes)
		(layer "In4.Cu")
		(net "M_C_CPU1_SB_CB<6>")
	)
	(gr_poly
		(pts
			(xy 91.13393 -236.801914) (xy 91.08694 -236.649514) (xy 90.82532 -236.649514) (xy 90.77833 -236.801914)
			(xy 90.77833 -236.84611) (xy 91.13393 -236.84611)
		)
		(stroke
			(width 0)
			(type solid)
		)
		(fill yes)
		(layer "In4.Cu")
		(net "M_B_CPU1_SB_DQ<0>")
	)
	(gr_poly
		(pts
			(xy 91.13647 -239.648746) (xy 91.13647 -239.60455) (xy 90.78087 -239.60455) (xy 90.78087 -239.648746)
			(xy 90.82786 -239.801146) (xy 91.08948 -239.801146)
		)
		(stroke
			(width 0)
			(type solid)
		)
		(fill yes)
		(layer "In4.Cu")
		(net "M_C_CPU1_SB_DQS_DN<4>")
	)
	(gr_poly
		(pts
			(xy 91.13647 -234.76585) (xy 91.13647 -234.7214) (xy 90.78087 -234.7214) (xy 90.78087 -234.76585)
			(xy 90.82786 -234.91825) (xy 91.08948 -234.91825)
		)
		(stroke
			(width 0)
			(type solid)
		)
		(fill yes)
		(layer "In4.Cu")
		(net "M_B_CPU1_SB_DQS_DN<5>")
	)
	(gr_poly
		(pts
			(xy 91.13647 -228.254814) (xy 91.13647 -228.210618) (xy 90.78087 -228.210618) (xy 90.78087 -228.254814)
			(xy 90.82786 -228.407214) (xy 91.08948 -228.407214)
		)
		(stroke
			(width 0)
			(type solid)
		)
		(fill yes)
		(layer "In4.Cu")
		(net "M_C_CPU1_SB_DQ<21>")
	)
	(gr_poly
		(pts
			(xy 91.142312 -246.16029) (xy 91.142312 -246.11584) (xy 90.786712 -246.11584) (xy 90.786712 -246.16029)
			(xy 90.833702 -246.31269) (xy 91.095322 -246.31269)
		)
		(stroke
			(width 0)
			(type solid)
		)
		(fill yes)
		(layer "In4.Cu")
		(net "M_C_CPU1_SB_CA<4>")
	)
	(gr_poly
		(pts
			(xy 91.145868 -238.021114) (xy 91.145868 -237.976664) (xy 90.790268 -237.976664) (xy 90.790268 -238.021114)
			(xy 90.837258 -238.173514) (xy 91.098878 -238.173514)
		)
		(stroke
			(width 0)
			(type solid)
		)
		(fill yes)
		(layer "In4.Cu")
		(net "M_C_CPU1_SB_CB<1>")
	)
	(gr_poly
		(pts
			(xy 91.145868 -233.13771) (xy 91.145868 -233.093514) (xy 90.790268 -233.093514) (xy 90.790268 -233.13771)
			(xy 90.837258 -233.29011) (xy 91.098878 -233.29011)
		)
		(stroke
			(width 0)
			(type solid)
		)
		(fill yes)
		(layer "In4.Cu")
		(net "M_B_CPU1_SB_DQ<5>")
	)
	(gr_poly
		(pts
			(xy 91.145868 -231.919018) (xy 91.098878 -231.766618) (xy 90.837258 -231.766618) (xy 90.790268 -231.919018)
			(xy 90.790268 -231.963214) (xy 91.145868 -231.963214)
		)
		(stroke
			(width 0)
			(type solid)
		)
		(fill yes)
		(layer "In4.Cu")
		(net "M_C_CPU1_SB_DQ<18>")
	)
	(gr_poly
		(pts
			(xy 91.145868 -229.882446) (xy 91.145868 -229.837996) (xy 90.790268 -229.837996) (xy 90.790268 -229.882446)
			(xy 90.837258 -230.034846) (xy 91.098878 -230.034846)
		)
		(stroke
			(width 0)
			(type solid)
		)
		(fill yes)
		(layer "In4.Cu")
		(net "M_C_CPU1_SB_DQS_DN<7>")
	)
	(gr_poly
		(pts
			(xy 91.146376 -283.593032) (xy 91.108022 -283.570934) (xy 90.952574 -283.535374) (xy 90.821764 -283.761942)
			(xy 90.930222 -283.878782) (xy 90.968576 -283.90088)
		)
		(stroke
			(width 0)
			(type solid)
		)
		(fill yes)
		(layer "In4.Cu")
		(net "M_C_CPU1_SA_DQ<2>")
	)
	(gr_poly
		(pts
			(xy 91.146376 -278.709628) (xy 91.108022 -278.68753) (xy 90.952574 -278.65197) (xy 90.821764 -278.878538)
			(xy 90.930222 -278.995378) (xy 90.968576 -279.017476)
		)
		(stroke
			(width 0)
			(type solid)
		)
		(fill yes)
		(layer "In4.Cu")
		(net "M_C_CPU1_SA_DQ<3>")
	)
	(gr_poly
		(pts
			(xy 91.14663 -238.430054) (xy 91.09964 -238.277654) (xy 90.83802 -238.277654) (xy 90.79103 -238.430054)
			(xy 90.79103 -238.47425) (xy 91.14663 -238.47425)
		)
		(stroke
			(width 0)
			(type solid)
		)
		(fill yes)
		(layer "In4.Cu")
		(net "M_C_CPU1_SB_CB<2>")
	)
	(gr_poly
		(pts
			(xy 91.14663 -236.393482) (xy 91.14663 -236.349032) (xy 90.79103 -236.349032) (xy 90.79103 -236.393482)
			(xy 90.83802 -236.545882) (xy 91.09964 -236.545882)
		)
		(stroke
			(width 0)
			(type solid)
		)
		(fill yes)
		(layer "In4.Cu")
		(net "M_B_CPU1_SB_DQ<1>")
	)
	(gr_poly
		(pts
			(xy 91.14663 -233.54665) (xy 91.09964 -233.39425) (xy 90.83802 -233.39425) (xy 90.79103 -233.54665)
			(xy 90.79103 -233.5911) (xy 91.14663 -233.5911)
		)
		(stroke
			(width 0)
			(type solid)
		)
		(fill yes)
		(layer "In4.Cu")
		(net "M_B_CPU1_SB_DQ<6>")
	)
	(gr_poly
		(pts
			(xy 91.14663 -231.510078) (xy 91.14663 -231.465628) (xy 90.79103 -231.465628) (xy 90.79103 -231.510078)
			(xy 90.83802 -231.662478) (xy 91.09964 -231.662478)
		)
		(stroke
			(width 0)
			(type solid)
		)
		(fill yes)
		(layer "In4.Cu")
		(net "M_C_CPU1_SB_DQ<17>")
	)
	(gr_poly
		(pts
			(xy 91.14663 -228.663246) (xy 91.09964 -228.510846) (xy 90.83802 -228.510846) (xy 90.79103 -228.663246)
			(xy 90.79103 -228.707696) (xy 91.14663 -228.707696)
		)
		(stroke
			(width 0)
			(type solid)
		)
		(fill yes)
		(layer "In4.Cu")
		(net "M_C_CPU1_SB_DQ<22>")
	)
	(gr_poly
		(pts
			(xy 91.147392 -280.335482) (xy 91.109038 -280.313384) (xy 90.95359 -280.277824) (xy 90.82278 -280.504392)
			(xy 90.931238 -280.621232) (xy 90.969592 -280.64333)
		)
		(stroke
			(width 0)
			(type solid)
		)
		(fill yes)
		(layer "In4.Cu")
		(net "M_C_CPU1_SA_DQ<3>")
	)
	(gr_poly
		(pts
			(xy 91.223338 -282.258008) (xy 91.331796 -282.141168) (xy 91.200986 -281.9146) (xy 91.045538 -281.95016)
			(xy 91.007184 -281.972258) (xy 91.184984 -282.280106)
		)
		(stroke
			(width 0)
			(type solid)
		)
		(fill yes)
		(layer "In4.Cu")
		(net "M_C_CPU1_SA_DQ<1>")
	)
	(gr_poly
		(pts
			(xy 91.223338 -257.841242) (xy 91.331796 -257.724402) (xy 91.200986 -257.497834) (xy 91.045538 -257.533394)
			(xy 91.007184 -257.555492) (xy 91.184984 -257.86334)
		)
		(stroke
			(width 0)
			(type solid)
		)
		(fill yes)
		(layer "In4.Cu")
		(net "M_C_CPU1_SA_CS_N<3>")
	)
	(gr_poly
		(pts
			(xy 91.243912 -275.690584) (xy 91.243912 -275.646388) (xy 90.888312 -275.646388) (xy 90.888312 -275.690584)
			(xy 90.935302 -275.842984) (xy 91.196922 -275.842984)
		)
		(stroke
			(width 0)
			(type solid)
		)
		(fill yes)
		(layer "In4.Cu")
		(net "M_C_CPU1_SA_DQ<5>")
	)
	(gr_poly
		(pts
			(xy 91.243912 -261.040626) (xy 91.243912 -260.99643) (xy 90.888312 -260.99643) (xy 90.888312 -261.040626)
			(xy 90.935302 -261.193026) (xy 91.196922 -261.193026)
		)
		(stroke
			(width 0)
			(type solid)
		)
		(fill yes)
		(layer "In4.Cu")
		(net "M_B_CPU1_SA_DQ<29>")
	)
	(gr_poly
		(pts
			(xy 91.243912 -256.157222) (xy 91.243912 -256.113026) (xy 90.888312 -256.113026) (xy 90.888312 -256.157222)
			(xy 90.935302 -256.309622) (xy 91.196922 -256.309622)
		)
		(stroke
			(width 0)
			(type solid)
		)
		(fill yes)
		(layer "In4.Cu")
		(net "M_C_CPU1_SA_CA<2>")
	)
	(gr_poly
		(pts
			(xy 91.246452 -274.47113) (xy 91.199462 -274.31873) (xy 90.937842 -274.31873) (xy 90.890852 -274.47113)
			(xy 90.890852 -274.515326) (xy 91.246452 -274.515326)
		)
		(stroke
			(width 0)
			(type solid)
		)
		(fill yes)
		(layer "In4.Cu")
		(net "M_B_CPU1_SA_DQ<10>")
	)
	(gr_poly
		(pts
			(xy 91.246452 -274.062698) (xy 91.246452 -274.018502) (xy 90.890852 -274.018502) (xy 90.890852 -274.062698)
			(xy 90.937842 -274.215098) (xy 91.199462 -274.215098)
		)
		(stroke
			(width 0)
			(type solid)
		)
		(fill yes)
		(layer "In4.Cu")
		(net "M_B_CPU1_SA_DQ<9>")
	)
	(gr_poly
		(pts
			(xy 91.246452 -269.587726) (xy 91.199462 -269.435326) (xy 90.937842 -269.435326) (xy 90.890852 -269.587726)
			(xy 90.890852 -269.631922) (xy 91.246452 -269.631922)
		)
		(stroke
			(width 0)
			(type solid)
		)
		(fill yes)
		(layer "In4.Cu")
		(net "M_C_CPU1_SA_DQ<18>")
	)
	(gr_poly
		(pts
			(xy 91.246452 -264.704322) (xy 91.199462 -264.551922) (xy 90.937842 -264.551922) (xy 90.890852 -264.704322)
			(xy 90.890852 -264.748772) (xy 91.246452 -264.748772)
		)
		(stroke
			(width 0)
			(type solid)
		)
		(fill yes)
		(layer "In4.Cu")
		(net "M_B_CPU1_SA_DQ<24>")
	)
	(gr_poly
		(pts
			(xy 91.246452 -259.412994) (xy 91.246452 -259.368544) (xy 90.890852 -259.368544) (xy 90.890852 -259.412994)
			(xy 90.937842 -259.565394) (xy 91.199462 -259.565394)
		)
		(stroke
			(width 0)
			(type solid)
		)
		(fill yes)
		(layer "In4.Cu")
		(net "M_C_CPU1_SA_CS_N<0>")
	)
	(gr_poly
		(pts
			(xy 91.246452 -254.937514) (xy 91.199462 -254.785114) (xy 90.937842 -254.785114) (xy 90.890852 -254.937514)
			(xy 90.890852 -254.981964) (xy 91.246452 -254.981964)
		)
		(stroke
			(width 0)
			(type solid)
		)
		(fill yes)
		(layer "In4.Cu")
		(net "M_C_CPU1_SA_CA<5>")
	)
	(gr_poly
		(pts
			(xy 91.252294 -276.09927) (xy 91.205304 -275.94687) (xy 90.943684 -275.94687) (xy 90.896694 -276.09927)
			(xy 90.896694 -276.143466) (xy 91.252294 -276.143466)
		)
		(stroke
			(width 0)
			(type solid)
		)
		(fill yes)
		(layer "In4.Cu")
		(net "M_C_CPU1_SA_DQ<6>")
	)
	(gr_poly
		(pts
			(xy 91.252294 -261.449058) (xy 91.205304 -261.296658) (xy 90.943684 -261.296658) (xy 90.896694 -261.449058)
			(xy 90.896694 -261.493508) (xy 91.252294 -261.493508)
		)
		(stroke
			(width 0)
			(type solid)
		)
		(fill yes)
		(layer "In4.Cu")
		(net "M_B_CPU1_SA_DQ<30>")
	)
	(gr_poly
		(pts
			(xy 91.252294 -256.565654) (xy 91.205304 -256.413254) (xy 90.943684 -256.413254) (xy 90.896694 -256.565654)
			(xy 90.896694 -256.610104) (xy 91.252294 -256.610104)
		)
		(stroke
			(width 0)
			(type solid)
		)
		(fill yes)
		(layer "In4.Cu")
		(net "M_C_CPU1_SA_CA<1>")
	)
	(gr_poly
		(pts
			(xy 91.25585 -270.806926) (xy 91.25585 -270.76273) (xy 90.90025 -270.76273) (xy 90.90025 -270.806926)
			(xy 90.94724 -270.959326) (xy 91.20886 -270.959326)
		)
		(stroke
			(width 0)
			(type solid)
		)
		(fill yes)
		(layer "In4.Cu")
		(net "M_B_CPU1_SA_DQ<13>")
	)
	(gr_poly
		(pts
			(xy 91.25585 -269.179294) (xy 91.25585 -269.134844) (xy 90.90025 -269.134844) (xy 90.90025 -269.179294)
			(xy 90.94724 -269.331694) (xy 91.20886 -269.331694)
		)
		(stroke
			(width 0)
			(type solid)
		)
		(fill yes)
		(layer "In4.Cu")
		(net "M_C_CPU1_SA_DQ<17>")
	)
	(gr_poly
		(pts
			(xy 91.25585 -266.332462) (xy 91.20886 -266.180062) (xy 90.94724 -266.180062) (xy 90.90025 -266.332462)
			(xy 90.90025 -266.376658) (xy 91.25585 -266.376658)
		)
		(stroke
			(width 0)
			(type solid)
		)
		(fill yes)
		(layer "In4.Cu")
		(net "M_C_CPU1_SA_DQ<22>")
	)
	(gr_poly
		(pts
			(xy 91.25585 -265.923522) (xy 91.25585 -265.879326) (xy 90.90025 -265.879326) (xy 90.90025 -265.923522)
			(xy 90.94724 -266.075922) (xy 91.20886 -266.075922)
		)
		(stroke
			(width 0)
			(type solid)
		)
		(fill yes)
		(layer "In4.Cu")
		(net "M_C_CPU1_SA_DQ<21>")
	)
	(gr_poly
		(pts
			(xy 91.25585 -264.29589) (xy 91.25585 -264.25144) (xy 90.90025 -264.25144) (xy 90.90025 -264.29589)
			(xy 90.94724 -264.44829) (xy 91.20886 -264.44829)
		)
		(stroke
			(width 0)
			(type solid)
		)
		(fill yes)
		(layer "In4.Cu")
		(net "M_B_CPU1_SA_DQ<25>")
	)
	(gr_poly
		(pts
			(xy 91.25585 -262.668258) (xy 91.25585 -262.623808) (xy 90.90025 -262.623808) (xy 90.90025 -262.668258)
			(xy 90.94724 -262.820658) (xy 91.20886 -262.820658)
		)
		(stroke
			(width 0)
			(type solid)
		)
		(fill yes)
		(layer "In4.Cu")
		(net "M_B_CPU1_SA_DQS_DN<8>")
	)
	(gr_poly
		(pts
			(xy 91.256612 -267.551154) (xy 91.256612 -267.506958) (xy 90.901012 -267.506958) (xy 90.901012 -267.551154)
			(xy 90.948002 -267.703554) (xy 91.209622 -267.703554)
		)
		(stroke
			(width 0)
			(type solid)
		)
		(fill yes)
		(layer "In4.Cu")
		(net "M_C_CPU1_SA_DQS_DN<7>")
	)
	(gr_poly
		(pts
			(xy 91.25839 -277.317962) (xy 91.25839 -277.273766) (xy 90.90279 -277.273766) (xy 90.90279 -277.317962)
			(xy 90.94978 -277.470362) (xy 91.2114 -277.470362)
		)
		(stroke
			(width 0)
			(type solid)
		)
		(fill yes)
		(layer "In4.Cu")
		(net "M_C_CPU1_SA_DQS_DN<5>")
	)
	(gr_poly
		(pts
			(xy 91.25839 -272.435066) (xy 91.25839 -272.390616) (xy 90.90279 -272.390616) (xy 90.90279 -272.435066)
			(xy 90.94978 -272.587466) (xy 91.2114 -272.587466)
		)
		(stroke
			(width 0)
			(type solid)
		)
		(fill yes)
		(layer "In4.Cu")
		(net "M_B_CPU1_SA_DQS_DN<6>")
	)
	(gr_poly
		(pts
			(xy 91.26093 -254.52959) (xy 91.26093 -254.48514) (xy 90.90533 -254.48514) (xy 90.90533 -254.52959)
			(xy 90.95232 -254.68199) (xy 91.21394 -254.68199)
		)
		(stroke
			(width 0)
			(type solid)
		)
		(fill yes)
		(layer "In4.Cu")
		(net "M_C_CPU1_SA_CA<6>")
	)
	(gr_poly
		(pts
			(xy 91.326208 -281.052524) (xy 91.21775 -280.935684) (xy 91.179396 -280.913586) (xy 91.001596 -281.221434)
			(xy 91.03995 -281.243532) (xy 91.195398 -281.279092)
		)
		(stroke
			(width 0)
			(type solid)
		)
		(fill yes)
		(layer "In4.Cu")
		(net "M_C_CPU1_SA_DQ<1>")
	)
	(gr_poly
		(pts
			(xy 91.326462 -282.679648) (xy 91.218004 -282.562808) (xy 91.17965 -282.54071) (xy 91.00185 -282.848558)
			(xy 91.040204 -282.870656) (xy 91.195652 -282.906216)
		)
		(stroke
			(width 0)
			(type solid)
		)
		(fill yes)
		(layer "In4.Cu")
		(net "M_C_CPU1_SA_DQ<1>")
	)
	(gr_poly
		(pts
			(xy 91.327224 -284.305502) (xy 91.218766 -284.188662) (xy 91.180412 -284.166564) (xy 91.002612 -284.474412)
			(xy 91.040966 -284.49651) (xy 91.196414 -284.53207)
		)
		(stroke
			(width 0)
			(type solid)
		)
		(fill yes)
		(layer "In4.Cu")
		(net "M_C_CPU1_SA_DQ<0>")
	)
	(gr_poly
		(pts
			(xy 91.60637 -227.84943) (xy 91.55938 -227.69703) (xy 91.29776 -227.69703) (xy 91.25077 -227.84943)
			(xy 91.25077 -227.893626) (xy 91.60637 -227.893626)
		)
		(stroke
			(width 0)
			(type solid)
		)
		(fill yes)
		(layer "In4.Cu")
		(net "M_C_CPU1_SB_DQ<23>")
	)
	(gr_poly
		(pts
			(xy 91.60891 -237.616238) (xy 91.56192 -237.463838) (xy 91.3003 -237.463838) (xy 91.25331 -237.616238)
			(xy 91.25331 -237.660434) (xy 91.60891 -237.660434)
		)
		(stroke
			(width 0)
			(type solid)
		)
		(fill yes)
		(layer "In4.Cu")
		(net "M_C_CPU1_SB_CB<3>")
	)
	(gr_poly
		(pts
			(xy 91.60891 -237.207298) (xy 91.60891 -237.163102) (xy 91.25331 -237.163102) (xy 91.25331 -237.207298)
			(xy 91.3003 -237.359698) (xy 91.56192 -237.359698)
		)
		(stroke
			(width 0)
			(type solid)
		)
		(fill yes)
		(layer "In4.Cu")
		(net "M_B_CPU1_SB_DQ<2>")
	)
	(gr_poly
		(pts
			(xy 91.60891 -232.732834) (xy 91.56192 -232.580434) (xy 91.3003 -232.580434) (xy 91.25331 -232.732834)
			(xy 91.25331 -232.77703) (xy 91.60891 -232.77703)
		)
		(stroke
			(width 0)
			(type solid)
		)
		(fill yes)
		(layer "In4.Cu")
		(net "M_B_CPU1_SB_DQ<7>")
	)
	(gr_poly
		(pts
			(xy 91.60891 -232.323894) (xy 91.60891 -232.279698) (xy 91.25331 -232.279698) (xy 91.25331 -232.323894)
			(xy 91.3003 -232.476294) (xy 91.56192 -232.476294)
		)
		(stroke
			(width 0)
			(type solid)
		)
		(fill yes)
		(layer "In4.Cu")
		(net "M_C_CPU1_SB_DQ<16>")
	)
	(gr_poly
		(pts
			(xy 91.61272 -244.127274) (xy 91.56573 -243.974874) (xy 91.30411 -243.974874) (xy 91.25712 -244.127274)
			(xy 91.25712 -244.17147) (xy 91.61272 -244.17147)
		)
		(stroke
			(width 0)
			(type solid)
		)
		(fill yes)
		(layer "In4.Cu")
		(net "M_C_CPU1_SB_CS_N<2>")
	)
	(gr_poly
		(pts
			(xy 91.617292 -282.777184) (xy 91.578938 -282.755086) (xy 91.42349 -282.719526) (xy 91.29268 -282.946094)
			(xy 91.401138 -283.062934) (xy 91.439492 -283.085032)
		)
		(stroke
			(width 0)
			(type solid)
		)
		(fill yes)
		(layer "In4.Cu")
		(net "M_C_CPU1_SA_DQ<2>")
	)
	(gr_poly
		(pts
			(xy 91.618308 -246.974106) (xy 91.618308 -246.929656) (xy 91.262708 -246.929656) (xy 91.262708 -246.974106)
			(xy 91.309698 -247.126506) (xy 91.571318 -247.126506)
		)
		(stroke
			(width 0)
			(type solid)
		)
		(fill yes)
		(layer "In4.Cu")
		(net "M_C_CPU1_SB_CA<2>")
	)
	(gr_poly
		(pts
			(xy 91.620848 -234.360466) (xy 91.573858 -234.208066) (xy 91.312238 -234.208066) (xy 91.265248 -234.360466)
			(xy 91.265248 -234.404662) (xy 91.620848 -234.404662)
		)
		(stroke
			(width 0)
			(type solid)
		)
		(fill yes)
		(layer "In4.Cu")
		(net "M_B_CPU1_SB_DQS_DP<5>")
	)
	(gr_poly
		(pts
			(xy 91.693238 -279.816306) (xy 91.801696 -279.699466) (xy 91.670886 -279.472898) (xy 91.515438 -279.508458)
			(xy 91.477084 -279.530556) (xy 91.654884 -279.838404)
		)
		(stroke
			(width 0)
			(type solid)
		)
		(fill yes)
		(layer "In4.Cu")
		(net "M_C_CPU1_SA_DQ<1>")
	)
	(gr_poly
		(pts
			(xy 91.716352 -274.876514) (xy 91.716352 -274.832064) (xy 91.360752 -274.832064) (xy 91.360752 -274.876514)
			(xy 91.407742 -275.028914) (xy 91.669362 -275.028914)
		)
		(stroke
			(width 0)
			(type solid)
		)
		(fill yes)
		(layer "In4.Cu")
		(net "M_B_CPU1_SA_DQ<8>")
	)
	(gr_poly
		(pts
			(xy 91.716352 -269.99311) (xy 91.716352 -269.948914) (xy 91.360752 -269.948914) (xy 91.360752 -269.99311)
			(xy 91.407742 -270.14551) (xy 91.669362 -270.14551)
		)
		(stroke
			(width 0)
			(type solid)
		)
		(fill yes)
		(layer "In4.Cu")
		(net "M_C_CPU1_SA_DQ<16>")
	)
	(gr_poly
		(pts
			(xy 91.716352 -265.109706) (xy 91.716352 -265.06551) (xy 91.360752 -265.06551) (xy 91.360752 -265.109706)
			(xy 91.407742 -265.262106) (xy 91.669362 -265.262106)
		)
		(stroke
			(width 0)
			(type solid)
		)
		(fill yes)
		(layer "In4.Cu")
		(net "M_B_CPU1_SA_DQ<26>")
	)
	(gr_poly
		(pts
			(xy 91.716352 -255.343406) (xy 91.716352 -255.298956) (xy 91.360752 -255.298956) (xy 91.360752 -255.343406)
			(xy 91.407742 -255.495806) (xy 91.669362 -255.495806)
		)
		(stroke
			(width 0)
			(type solid)
		)
		(fill yes)
		(layer "In4.Cu")
		(net "M_C_CPU1_SA_CA<4>")
	)
	(gr_poly
		(pts
			(xy 91.718892 -270.40205) (xy 91.671902 -270.24965) (xy 91.410282 -270.24965) (xy 91.363292 -270.40205)
			(xy 91.363292 -270.446246) (xy 91.718892 -270.446246)
		)
		(stroke
			(width 0)
			(type solid)
		)
		(fill yes)
		(layer "In4.Cu")
		(net "M_B_CPU1_SA_DQ<15>")
	)
	(gr_poly
		(pts
			(xy 91.718892 -265.518646) (xy 91.671902 -265.366246) (xy 91.410282 -265.366246) (xy 91.363292 -265.518646)
			(xy 91.363292 -265.563096) (xy 91.718892 -265.563096)
		)
		(stroke
			(width 0)
			(type solid)
		)
		(fill yes)
		(layer "In4.Cu")
		(net "M_C_CPU1_SA_DQ<23>")
	)
	(gr_poly
		(pts
			(xy 91.722448 -259.00761) (xy 91.675458 -258.85521) (xy 91.413838 -258.85521) (xy 91.366848 -259.00761)
			(xy 91.366848 -259.051806) (xy 91.722448 -259.051806)
		)
		(stroke
			(width 0)
			(type solid)
		)
		(fill yes)
		(layer "In4.Cu")
		(net "M_C_CPU1_SA_CS_N<2>")
	)
	(gr_poly
		(pts
			(xy 91.72829 -275.284946) (xy 91.6813 -275.132546) (xy 91.41968 -275.132546) (xy 91.37269 -275.284946)
			(xy 91.37269 -275.329396) (xy 91.72829 -275.329396)
		)
		(stroke
			(width 0)
			(type solid)
		)
		(fill yes)
		(layer "In4.Cu")
		(net "M_C_CPU1_SA_DQ<7>")
	)
	(gr_poly
		(pts
			(xy 91.72829 -260.635242) (xy 91.6813 -260.482842) (xy 91.41968 -260.482842) (xy 91.37269 -260.635242)
			(xy 91.37269 -260.679438) (xy 91.72829 -260.679438)
		)
		(stroke
			(width 0)
			(type solid)
		)
		(fill yes)
		(layer "In4.Cu")
		(net "M_B_CPU1_SA_DQ<31>")
	)
	(gr_poly
		(pts
			(xy 91.72829 -255.751838) (xy 91.6813 -255.599438) (xy 91.41968 -255.599438) (xy 91.37269 -255.751838)
			(xy 91.37269 -255.796288) (xy 91.72829 -255.796288)
		)
		(stroke
			(width 0)
			(type solid)
		)
		(fill yes)
		(layer "In4.Cu")
		(net "M_C_CPU1_SA_CA<3>")
	)
	(gr_poly
		(pts
			(xy 91.796362 -280.237946) (xy 91.687904 -280.121106) (xy 91.64955 -280.099008) (xy 91.47175 -280.406856)
			(xy 91.510104 -280.428954) (xy 91.665552 -280.464514)
		)
		(stroke
			(width 0)
			(type solid)
		)
		(fill yes)
		(layer "In4.Cu")
		(net "M_C_CPU1_SA_DQ<1>")
	)
	(gr_poly
		(pts
			(xy 91.797124 -283.491686) (xy 91.688666 -283.374846) (xy 91.650312 -283.352748) (xy 91.472512 -283.660596)
			(xy 91.510866 -283.682694) (xy 91.666314 -283.718254)
		)
		(stroke
			(width 0)
			(type solid)
		)
		(fill yes)
		(layer "In4.Cu")
		(net "M_C_CPU1_SA_DQ<0>")
	)
	(gr_poly
		(pts
			(xy 91.971876 -245.930928) (xy 91.933522 -245.90883) (xy 91.778074 -245.87327) (xy 91.647264 -246.099838)
			(xy 91.755722 -246.216678) (xy 91.794076 -246.238776)
		)
		(stroke
			(width 0)
			(type solid)
		)
		(fill yes)
		(layer "In4.Cu")
		(net "M_C_CPU1_SB_CA<3>")
	)
	(gr_poly
		(pts
			(xy 92.049092 -281.243532) (xy 92.087446 -281.221434) (xy 91.909646 -280.913586) (xy 91.871292 -280.935684)
			(xy 91.762834 -281.052524) (xy 91.893644 -281.279092)
		)
		(stroke
			(width 0)
			(type solid)
		)
		(fill yes)
		(layer "In4.Cu")
		(net "M_C_CPU1_SA_DQ<2>")
	)
	(gr_poly
		(pts
			(xy 92.07627 -244.532658) (xy 92.07627 -244.488208) (xy 91.72067 -244.488208) (xy 91.72067 -244.532658)
			(xy 91.76766 -244.685058) (xy 92.02928 -244.685058)
		)
		(stroke
			(width 0)
			(type solid)
		)
		(fill yes)
		(layer "In4.Cu")
		(net "M_C_CPU1_SB_PAR")
	)
	(gr_poly
		(pts
			(xy 92.07627 -243.313458) (xy 92.02928 -243.161058) (xy 91.76766 -243.161058) (xy 91.72067 -243.313458)
			(xy 91.72067 -243.357654) (xy 92.07627 -243.357654)
		)
		(stroke
			(width 0)
			(type solid)
		)
		(fill yes)
		(layer "In4.Cu")
		(net "M_C_CPU1_SB_CS_N<3>")
	)
	(gr_poly
		(pts
			(xy 92.081858 -268.949932) (xy 92.043504 -268.927834) (xy 91.888056 -268.892274) (xy 91.757246 -269.118842)
			(xy 91.865704 -269.235682) (xy 91.904058 -269.25778)
		)
		(stroke
			(width 0)
			(type solid)
		)
		(fill yes)
		(layer "In4.Cu")
		(net "M_C_CPU1_SA_DQ<18>")
	)
	(gr_poly
		(pts
			(xy 92.085668 -233.13771) (xy 92.085668 -233.093514) (xy 91.730068 -233.093514) (xy 91.730068 -233.13771)
			(xy 91.777058 -233.29011) (xy 92.038678 -233.29011)
		)
		(stroke
			(width 0)
			(type solid)
		)
		(fill yes)
		(layer "In4.Cu")
		(net "M_B_CPU1_SB_DQ<5>")
	)
	(gr_poly
		(pts
			(xy 92.08643 -233.54665) (xy 92.03944 -233.39425) (xy 91.77782 -233.39425) (xy 91.73083 -233.54665)
			(xy 91.73083 -233.5911) (xy 92.08643 -233.5911)
		)
		(stroke
			(width 0)
			(type solid)
		)
		(fill yes)
		(layer "In4.Cu")
		(net "M_B_CPU1_SB_DQ<6>")
	)
	(gr_poly
		(pts
			(xy 92.08643 -228.663246) (xy 92.03944 -228.510846) (xy 91.77782 -228.510846) (xy 91.73083 -228.663246)
			(xy 91.73083 -228.707696) (xy 92.08643 -228.707696)
		)
		(stroke
			(width 0)
			(type solid)
		)
		(fill yes)
		(layer "In4.Cu")
		(net "M_C_CPU1_SB_DQ<22>")
	)
	(gr_poly
		(pts
			(xy 92.087446 -281.962606) (xy 92.049092 -281.940508) (xy 91.893644 -281.904948) (xy 91.762834 -282.131516)
			(xy 91.871292 -282.248356) (xy 91.909646 -282.270454)
		)
		(stroke
			(width 0)
			(type solid)
		)
		(fill yes)
		(layer "In4.Cu")
		(net "M_C_CPU1_SA_DQ<2>")
	)
	(gr_poly
		(pts
			(xy 92.088208 -228.254814) (xy 92.088208 -228.210364) (xy 91.732608 -228.210364) (xy 91.732608 -228.254814)
			(xy 91.779598 -228.407214) (xy 92.041218 -228.407214)
		)
		(stroke
			(width 0)
			(type solid)
		)
		(fill yes)
		(layer "In4.Cu")
		(net "M_C_CPU1_SB_DQ<21>")
	)
	(gr_poly
		(pts
			(xy 92.088462 -280.33345) (xy 92.050108 -280.311352) (xy 91.89466 -280.275792) (xy 91.76385 -280.50236)
			(xy 91.872308 -280.6192) (xy 91.910662 -280.641298)
		)
		(stroke
			(width 0)
			(type solid)
		)
		(fill yes)
		(layer "In4.Cu")
		(net "M_C_CPU1_SA_DQ<2>")
	)
	(gr_poly
		(pts
			(xy 92.157042 -246.636286) (xy 92.048584 -246.519446) (xy 92.01023 -246.497348) (xy 91.83243 -246.805196)
			(xy 91.870784 -246.827294) (xy 92.026232 -246.862854)
		)
		(stroke
			(width 0)
			(type solid)
		)
		(fill yes)
		(layer "In4.Cu")
		(net "M_C_CPU1_SB_CA<2>")
	)
	(gr_poly
		(pts
			(xy 92.183712 -276.098762) (xy 92.136722 -275.946362) (xy 91.875102 -275.946362) (xy 91.828112 -276.098762)
			(xy 91.828112 -276.143212) (xy 92.183712 -276.143212)
		)
		(stroke
			(width 0)
			(type solid)
		)
		(fill yes)
		(layer "In4.Cu")
		(net "M_C_CPU1_SA_DQ<6>")
	)
	(gr_poly
		(pts
			(xy 92.183712 -261.449058) (xy 92.136722 -261.296658) (xy 91.875102 -261.296658) (xy 91.828112 -261.449058)
			(xy 91.828112 -261.493254) (xy 92.183712 -261.493254)
		)
		(stroke
			(width 0)
			(type solid)
		)
		(fill yes)
		(layer "In4.Cu")
		(net "M_B_CPU1_SA_DQ<30>")
	)
	(gr_poly
		(pts
			(xy 92.186252 -259.412486) (xy 92.186252 -259.36829) (xy 91.830652 -259.36829) (xy 91.830652 -259.412486)
			(xy 91.877642 -259.564886) (xy 92.139262 -259.564886)
		)
		(stroke
			(width 0)
			(type solid)
		)
		(fill yes)
		(layer "In4.Cu")
		(net "M_C_CPU1_SA_CS_N<0>")
	)
	(gr_poly
		(pts
			(xy 92.192094 -275.690584) (xy 92.192094 -275.646134) (xy 91.836494 -275.646134) (xy 91.836494 -275.690584)
			(xy 91.883484 -275.842984) (xy 92.145104 -275.842984)
		)
		(stroke
			(width 0)
			(type solid)
		)
		(fill yes)
		(layer "In4.Cu")
		(net "M_C_CPU1_SA_DQ<5>")
	)
	(gr_poly
		(pts
			(xy 92.192094 -261.040626) (xy 92.192094 -260.996176) (xy 91.836494 -260.996176) (xy 91.836494 -261.040626)
			(xy 91.883484 -261.193026) (xy 92.145104 -261.193026)
		)
		(stroke
			(width 0)
			(type solid)
		)
		(fill yes)
		(layer "In4.Cu")
		(net "M_B_CPU1_SA_DQ<29>")
	)
	(gr_poly
		(pts
			(xy 92.19565 -270.806926) (xy 92.19565 -270.76273) (xy 91.84005 -270.76273) (xy 91.84005 -270.806926)
			(xy 91.88704 -270.959326) (xy 92.14866 -270.959326)
		)
		(stroke
			(width 0)
			(type solid)
		)
		(fill yes)
		(layer "In4.Cu")
		(net "M_B_CPU1_SA_DQ<13>")
	)
	(gr_poly
		(pts
			(xy 92.266262 -282.679648) (xy 92.157804 -282.562808) (xy 92.11945 -282.54071) (xy 91.94165 -282.848558)
			(xy 91.980004 -282.870656) (xy 92.135452 -282.906216)
		)
		(stroke
			(width 0)
			(type solid)
		)
		(fill yes)
		(layer "In4.Cu")
		(net "M_C_CPU1_SA_DQ<0>")
	)
	(gr_poly
		(pts
			(xy 92.266262 -269.657322) (xy 92.157804 -269.540482) (xy 92.11945 -269.518384) (xy 91.94165 -269.826232)
			(xy 91.980004 -269.84833) (xy 92.135452 -269.88389)
		)
		(stroke
			(width 0)
			(type solid)
		)
		(fill yes)
		(layer "In4.Cu")
		(net "M_C_CPU1_SA_DQ<16>")
	)
	(gr_poly
		(pts
			(xy 92.513404 -256.003044) (xy 92.551758 -255.980946) (xy 92.373958 -255.673098) (xy 92.335604 -255.695196)
			(xy 92.227146 -255.812036) (xy 92.357956 -256.038604)
		)
		(stroke
			(width 0)
			(type solid)
		)
		(fill yes)
		(layer "In4.Cu")
		(net "M_C_CPU1_SA_CA<4>")
	)
	(gr_poly
		(pts
			(xy 92.518992 -254.385064) (xy 92.557346 -254.362966) (xy 92.379546 -254.055118) (xy 92.341192 -254.077216)
			(xy 92.232734 -254.194056) (xy 92.363544 -254.420624)
		)
		(stroke
			(width 0)
			(type solid)
		)
		(fill yes)
		(layer "In4.Cu")
		(net "M_C_CPU1_CLK_DP<1>")
	)
	(gr_poly
		(pts
			(xy 92.552266 -244.127274) (xy 92.505276 -243.974874) (xy 92.243656 -243.974874) (xy 92.196666 -244.127274)
			(xy 92.196666 -244.17147) (xy 92.552266 -244.17147)
		)
		(stroke
			(width 0)
			(type solid)
		)
		(fill yes)
		(layer "In4.Cu")
		(net "M_C_CPU1_SB_CS_N<2>")
	)
	(gr_poly
		(pts
			(xy 92.558108 -245.754906) (xy 92.511118 -245.602506) (xy 92.249498 -245.602506) (xy 92.202508 -245.754906)
			(xy 92.202508 -245.799356) (xy 92.558108 -245.799356)
		)
		(stroke
			(width 0)
			(type solid)
		)
		(fill yes)
		(layer "In4.Cu")
		(net "M_C_CPU1_SB_CA<3>")
	)
	(gr_poly
		(pts
			(xy 92.558108 -227.848922) (xy 92.511118 -227.696522) (xy 92.249498 -227.696522) (xy 92.202508 -227.848922)
			(xy 92.202508 -227.893372) (xy 92.558108 -227.893372)
		)
		(stroke
			(width 0)
			(type solid)
		)
		(fill yes)
		(layer "In4.Cu")
		(net "M_C_CPU1_SB_DQ<23>")
	)
	(gr_poly
		(pts
			(xy 92.62745 -281.43454) (xy 92.735908 -281.3177) (xy 92.605098 -281.091132) (xy 92.44965 -281.126692)
			(xy 92.411296 -281.14879) (xy 92.589096 -281.456638)
		)
		(stroke
			(width 0)
			(type solid)
		)
		(fill yes)
		(layer "In4.Cu")
		(net "M_C_CPU1_SA_DQ<0>")
	)
	(gr_poly
		(pts
			(xy 92.629228 -255.393444) (xy 92.737686 -255.276604) (xy 92.606876 -255.050036) (xy 92.451428 -255.085596)
			(xy 92.413074 -255.107694) (xy 92.590874 -255.415542)
		)
		(stroke
			(width 0)
			(type solid)
		)
		(fill yes)
		(layer "In4.Cu")
		(net "M_C_CPU1_SA_CA<5>")
	)
	(gr_poly
		(pts
			(xy 92.658692 -270.40205) (xy 92.611702 -270.24965) (xy 92.350082 -270.24965) (xy 92.303092 -270.40205)
			(xy 92.303092 -270.446246) (xy 92.658692 -270.446246)
		)
		(stroke
			(width 0)
			(type solid)
		)
		(fill yes)
		(layer "In4.Cu")
		(net "M_B_CPU1_SA_DQ<15>")
	)
	(gr_poly
		(pts
			(xy 92.66809 -275.284946) (xy 92.6211 -275.132546) (xy 92.35948 -275.132546) (xy 92.31249 -275.284946)
			(xy 92.31249 -275.329142) (xy 92.66809 -275.329142)
		)
		(stroke
			(width 0)
			(type solid)
		)
		(fill yes)
		(layer "In4.Cu")
		(net "M_C_CPU1_SA_DQ<7>")
	)
	(gr_poly
		(pts
			(xy 92.66809 -260.634734) (xy 92.6211 -260.482334) (xy 92.35948 -260.482334) (xy 92.31249 -260.634734)
			(xy 92.31249 -260.679184) (xy 92.66809 -260.679184)
		)
		(stroke
			(width 0)
			(type solid)
		)
		(fill yes)
		(layer "In4.Cu")
		(net "M_B_CPU1_SA_DQ<31>")
	)
	(gr_poly
		(pts
			(xy 92.67063 -268.77391) (xy 92.62364 -268.62151) (xy 92.36202 -268.62151) (xy 92.31503 -268.77391)
			(xy 92.31503 -268.818106) (xy 92.67063 -268.818106)
		)
		(stroke
			(width 0)
			(type solid)
		)
		(fill yes)
		(layer "In4.Cu")
		(net "M_C_CPU1_SA_DQ<18>")
	)
	(gr_poly
		(pts
			(xy 92.67063 -259.007102) (xy 92.62364 -258.854702) (xy 92.36202 -258.854702) (xy 92.31503 -259.007102)
			(xy 92.31503 -259.051552) (xy 92.67063 -259.051552)
		)
		(stroke
			(width 0)
			(type solid)
		)
		(fill yes)
		(layer "In4.Cu")
		(net "M_C_CPU1_SA_CS_N<2>")
	)
	(gr_poly
		(pts
			(xy 92.735146 -280.239978) (xy 92.626688 -280.123138) (xy 92.588334 -280.10104) (xy 92.410534 -280.408888)
			(xy 92.448888 -280.430986) (xy 92.604336 -280.466546)
		)
		(stroke
			(width 0)
			(type solid)
		)
		(fill yes)
		(layer "In4.Cu")
		(net "M_C_CPU1_SA_DQ<0>")
	)
	(gr_poly
		(pts
			(xy 92.735908 -281.86634) (xy 92.62745 -281.7495) (xy 92.589096 -281.727402) (xy 92.411296 -282.03525)
			(xy 92.44965 -282.057348) (xy 92.605098 -282.092908)
		)
		(stroke
			(width 0)
			(type solid)
		)
		(fill yes)
		(layer "In4.Cu")
		(net "M_C_CPU1_SA_DQ<0>")
	)
	(gr_poly
		(pts
			(xy 92.988638 -255.198372) (xy 93.026992 -255.176274) (xy 92.849192 -254.868426) (xy 92.810838 -254.890524)
			(xy 92.70238 -255.007364) (xy 92.83319 -255.233932)
		)
		(stroke
			(width 0)
			(type solid)
		)
		(fill yes)
		(layer "In4.Cu")
		(net "M_C_CPU1_CLK_DP<1>")
	)
	(gr_poly
		(pts
			(xy 93.021912 -244.53215) (xy 93.021912 -244.487954) (xy 92.666312 -244.487954) (xy 92.666312 -244.53215)
			(xy 92.713302 -244.68455) (xy 92.974922 -244.68455)
		)
		(stroke
			(width 0)
			(type solid)
		)
		(fill yes)
		(layer "In4.Cu")
		(net "M_C_CPU1_SB_PAR")
	)
	(gr_poly
		(pts
			(xy 93.09735 -254.576072) (xy 93.205808 -254.459232) (xy 93.074998 -254.232664) (xy 92.91955 -254.268224)
			(xy 92.881196 -254.290322) (xy 93.058996 -254.59817)
		)
		(stroke
			(width 0)
			(type solid)
		)
		(fill yes)
		(layer "In4.Cu")
		(net "M_C_CPU1_CLK_DN<1>")
	)
	(gr_poly
		(pts
			(xy 93.458792 -256.01295) (xy 93.497146 -255.990852) (xy 93.319346 -255.683004) (xy 93.280992 -255.705102)
			(xy 93.172534 -255.821942) (xy 93.303344 -256.04851)
		)
		(stroke
			(width 0)
			(type solid)
		)
		(fill yes)
		(layer "In4.Cu")
		(net "M_C_CPU1_CLK_DP<1>")
	)
	(gr_poly
		(pts
			(xy 93.458792 -254.385064) (xy 93.497146 -254.362966) (xy 93.319346 -254.055118) (xy 93.280992 -254.077216)
			(xy 93.172534 -254.194056) (xy 93.303344 -254.420624)
		)
		(stroke
			(width 0)
			(type solid)
		)
		(fill yes)
		(layer "In4.Cu")
		(net "M_C_CPU1_CLK_DP<0>")
	)
	(gr_poly
		(pts
			(xy 93.567504 -255.39065) (xy 93.675962 -255.27381) (xy 93.545152 -255.047242) (xy 93.389704 -255.082802)
			(xy 93.35135 -255.1049) (xy 93.52915 -255.412748)
		)
		(stroke
			(width 0)
			(type solid)
		)
		(fill yes)
		(layer "In4.Cu")
		(net "M_C_CPU1_CLK_DN<1>")
	)
	(gr_poly
		(pts
			(xy 93.921326 -256.814066) (xy 93.95968 -256.791968) (xy 93.78188 -256.48412) (xy 93.743526 -256.506218)
			(xy 93.635068 -256.623058) (xy 93.765878 -256.849626)
		)
		(stroke
			(width 0)
			(type solid)
		)
		(fill yes)
		(layer "In4.Cu")
		(net "M_C_CPU1_CLK_DP<1>")
	)
	(gr_poly
		(pts
			(xy 93.928438 -255.198372) (xy 93.966792 -255.176274) (xy 93.788992 -254.868426) (xy 93.750638 -254.890524)
			(xy 93.64218 -255.007364) (xy 93.77299 -255.233932)
		)
		(stroke
			(width 0)
			(type solid)
		)
		(fill yes)
		(layer "In4.Cu")
		(net "M_C_CPU1_CLK_DP<0>")
	)
	(gr_poly
		(pts
			(xy 94.042738 -256.213864) (xy 94.151196 -256.097024) (xy 94.020386 -255.870456) (xy 93.864938 -255.906016)
			(xy 93.826584 -255.928114) (xy 94.004384 -256.235962)
		)
		(stroke
			(width 0)
			(type solid)
		)
		(fill yes)
		(layer "In4.Cu")
		(net "M_C_CPU1_CLK_DN<1>")
	)
	(gr_poly
		(pts
			(xy 94.397576 -256.01041) (xy 94.43593 -255.988312) (xy 94.25813 -255.680464) (xy 94.219776 -255.702562)
			(xy 94.111318 -255.819402) (xy 94.242128 -256.04597)
		)
		(stroke
			(width 0)
			(type solid)
		)
		(fill yes)
		(layer "In4.Cu")
		(net "M_C_CPU1_CLK_DP<0>")
	)
	(gr_poly
		(pts
			(xy 94.507304 -255.39065) (xy 94.615762 -255.27381) (xy 94.484952 -255.047242) (xy 94.329504 -255.082802)
			(xy 94.29115 -255.1049) (xy 94.46895 -255.412748)
		)
		(stroke
			(width 0)
			(type solid)
		)
		(fill yes)
		(layer "In4.Cu")
		(net "M_C_CPU1_CLK_DN<0>")
	)
	(gr_poly
		(pts
			(xy 94.541848 -256.971038) (xy 94.541848 -256.926588) (xy 94.186248 -256.926588) (xy 94.186248 -256.971038)
			(xy 94.233238 -257.123438) (xy 94.494858 -257.123438)
		)
		(stroke
			(width 0)
			(type solid)
		)
		(fill yes)
		(layer "In4.Cu")
		(net "M_C_CPU1_CLK_DP<1>")
	)
	(gr_poly
		(pts
			(xy 95.005652 -256.565654) (xy 94.958662 -256.413254) (xy 94.697042 -256.413254) (xy 94.650052 -256.565654)
			(xy 94.650052 -256.610104) (xy 95.005652 -256.610104)
		)
		(stroke
			(width 0)
			(type solid)
		)
		(fill yes)
		(layer "In4.Cu")
		(net "M_C_CPU1_CLK_DN<1>")
	)
	(gr_poly
		(pts
			(xy 95.005652 -256.157222) (xy 95.005652 -256.112772) (xy 94.650052 -256.112772) (xy 94.650052 -256.157222)
			(xy 94.697042 -256.309622) (xy 94.958662 -256.309622)
		)
		(stroke
			(width 0)
			(type solid)
		)
		(fill yes)
		(layer "In4.Cu")
		(net "M_C_CPU1_CLK_DP<0>")
	)
	(gr_poly
		(pts
			(xy 95.49003 -256.971038) (xy 95.49003 -256.926842) (xy 95.13443 -256.926842) (xy 95.13443 -256.971038)
			(xy 95.18142 -257.123438) (xy 95.44304 -257.123438)
		)
		(stroke
			(width 0)
			(type solid)
		)
		(fill yes)
		(layer "In4.Cu")
		(net "M_C_CPU1_CLK_DP<1>")
	)
	(gr_poly
		(pts
			(xy 95.942912 -256.565654) (xy 95.895922 -256.413254) (xy 95.634302 -256.413254) (xy 95.587312 -256.565654)
			(xy 95.587312 -256.60985) (xy 95.942912 -256.60985)
		)
		(stroke
			(width 0)
			(type solid)
		)
		(fill yes)
		(layer "In4.Cu")
		(net "M_C_CPU1_CLK_DN<1>")
	)
	(gr_poly
		(pts
			(xy 96.42983 -256.971038) (xy 96.42983 -256.926842) (xy 96.07423 -256.926842) (xy 96.07423 -256.971038)
			(xy 96.12122 -257.123438) (xy 96.38284 -257.123438)
		)
		(stroke
			(width 0)
			(type solid)
		)
		(fill yes)
		(layer "In4.Cu")
		(net "M_C_CPU1_CLK_DP<1>")
	)
	(gr_poly
		(pts
			(xy 96.780858 -255.92786) (xy 96.742504 -255.905762) (xy 96.587056 -255.870202) (xy 96.456246 -256.09677)
			(xy 96.564704 -256.21361) (xy 96.603058 -256.235708)
		)
		(stroke
			(width 0)
			(type solid)
		)
		(fill yes)
		(layer "In4.Cu")
		(net "M_C_CPU1_CLK_DN<1>")
	)
	(gr_poly
		(pts
			(xy 96.965008 -256.635758) (xy 96.85655 -256.518918) (xy 96.818196 -256.49682) (xy 96.640396 -256.804668)
			(xy 96.67875 -256.826766) (xy 96.834198 -256.862326)
		)
		(stroke
			(width 0)
			(type solid)
		)
		(fill yes)
		(layer "In4.Cu")
		(net "M_C_CPU1_CLK_DP<1>")
	)
	(gr_poly
		(pts
			(xy 130.60807 -247.787922) (xy 130.60807 -247.743726) (xy 130.25247 -247.743726) (xy 130.25247 -247.787922)
			(xy 130.29946 -247.940322) (xy 130.56108 -247.940322)
		)
		(stroke
			(width 0)
			(type solid)
		)
		(fill yes)
		(layer "In4.Cu")
		(net "M_G_CPU1_SB_CA<6>")
	)
	(gr_poly
		(pts
			(xy 131.083812 -246.974106) (xy 131.083812 -246.929656) (xy 130.728212 -246.929656) (xy 130.728212 -246.974106)
			(xy 130.775202 -247.126506) (xy 131.036822 -247.126506)
		)
		(stroke
			(width 0)
			(type solid)
		)
		(fill yes)
		(layer "In4.Cu")
		(net "M_G_CPU1_SB_CS_N<2>")
	)
	(gr_poly
		(pts
			(xy 131.084066 -248.506742) (xy 131.084066 -248.462292) (xy 130.728466 -248.462292) (xy 130.728466 -248.506742)
			(xy 130.775456 -248.659142) (xy 131.037076 -248.659142)
		)
		(stroke
			(width 0)
			(type solid)
		)
		(fill yes)
		(layer "In4.Cu")
		(net "M_G_CPU1_SB_CA<4>")
	)
	(gr_poly
		(pts
			(xy 131.20243 -255.751838) (xy 131.15544 -255.599438) (xy 130.89382 -255.599438) (xy 130.84683 -255.751838)
			(xy 130.84683 -255.796034) (xy 131.20243 -255.796034)
		)
		(stroke
			(width 0)
			(type solid)
		)
		(fill yes)
		(layer "In4.Cu")
		(net "M_G_CPU1_SA_CA<0>")
	)
	(gr_poly
		(pts
			(xy 131.20243 -255.343406) (xy 131.20243 -255.29921) (xy 130.84683 -255.29921) (xy 130.84683 -255.343406)
			(xy 130.89382 -255.495806) (xy 131.15544 -255.495806)
		)
		(stroke
			(width 0)
			(type solid)
		)
		(fill yes)
		(layer "In4.Cu")
		(net "M_G_CPU1_SA_CA<3>")
	)
	(gr_poly
		(pts
			(xy 131.54787 -249.416062) (xy 131.54787 -249.371612) (xy 131.19227 -249.371612) (xy 131.19227 -249.416062)
			(xy 131.23926 -249.568462) (xy 131.50088 -249.568462)
		)
		(stroke
			(width 0)
			(type solid)
		)
		(fill yes)
		(layer "In4.Cu")
		(net "M_G_CPU1_SB_CA<2>")
	)
	(gr_poly
		(pts
			(xy 131.559808 -247.787922) (xy 131.559808 -247.743472) (xy 131.204208 -247.743472) (xy 131.204208 -247.787922)
			(xy 131.251198 -247.940322) (xy 131.512818 -247.940322)
		)
		(stroke
			(width 0)
			(type solid)
		)
		(fill yes)
		(layer "In4.Cu")
		(net "M_G_CPU1_SB_CA<6>")
	)
	(gr_poly
		(pts
			(xy 131.655312 -274.062698) (xy 131.655312 -274.018502) (xy 131.299712 -274.018502) (xy 131.299712 -274.062698)
			(xy 131.346702 -274.215098) (xy 131.608322 -274.215098)
		)
		(stroke
			(width 0)
			(type solid)
		)
		(fill yes)
		(layer "In4.Cu")
		(net "M_G_CPU1_SA_DQ<5>")
	)
	(gr_poly
		(pts
			(xy 131.655312 -256.565654) (xy 131.608322 -256.413254) (xy 131.346702 -256.413254) (xy 131.299712 -256.565654)
			(xy 131.299712 -256.60985) (xy 131.655312 -256.60985)
		)
		(stroke
			(width 0)
			(type solid)
		)
		(fill yes)
		(layer "In4.Cu")
		(net "M_G_CPU1_SA_CS_N<3>")
	)
	(gr_poly
		(pts
			(xy 131.655312 -256.157222) (xy 131.655312 -256.113026) (xy 131.299712 -256.113026) (xy 131.299712 -256.157222)
			(xy 131.346702 -256.309622) (xy 131.608322 -256.309622)
		)
		(stroke
			(width 0)
			(type solid)
		)
		(fill yes)
		(layer "In4.Cu")
		(net "M_G_CPU1_SA_CA<1>")
	)
	(gr_poly
		(pts
			(xy 131.655312 -254.937514) (xy 131.608322 -254.785114) (xy 131.346702 -254.785114) (xy 131.299712 -254.937514)
			(xy 131.299712 -254.981964) (xy 131.655312 -254.981964)
		)
		(stroke
			(width 0)
			(type solid)
		)
		(fill yes)
		(layer "In4.Cu")
		(net "M_G_CPU1_SA_CA<2>")
	)
	(gr_poly
		(pts
			(xy 131.657852 -277.317962) (xy 131.657852 -277.273766) (xy 131.302252 -277.273766) (xy 131.302252 -277.317962)
			(xy 131.349242 -277.470362) (xy 131.610862 -277.470362)
		)
		(stroke
			(width 0)
			(type solid)
		)
		(fill yes)
		(layer "In4.Cu")
		(net "M_G_CPU1_SA_DQ<0>")
	)
	(gr_poly
		(pts
			(xy 131.657852 -257.784854) (xy 131.657852 -257.740658) (xy 131.302252 -257.740658) (xy 131.302252 -257.784854)
			(xy 131.349242 -257.937254) (xy 131.610862 -257.937254)
		)
		(stroke
			(width 0)
			(type solid)
		)
		(fill yes)
		(layer "In4.Cu")
		(net "M_G_CPU1_SA_CS_N<0>")
	)
	(gr_poly
		(pts
			(xy 131.918964 -223.946212) (xy 131.88061 -223.924114) (xy 131.725162 -223.888554) (xy 131.594352 -224.115122)
			(xy 131.70281 -224.231962) (xy 131.741164 -224.25406)
		)
		(stroke
			(width 0)
			(type solid)
		)
		(fill yes)
		(layer "In4.Cu")
		(net "M_F_CPU1_SB_DQ<28>")
	)
	(gr_poly
		(pts
			(xy 132.01523 -246.974106) (xy 132.01523 -246.92991) (xy 131.65963 -246.92991) (xy 131.65963 -246.974106)
			(xy 131.70662 -247.126506) (xy 131.96824 -247.126506)
		)
		(stroke
			(width 0)
			(type solid)
		)
		(fill yes)
		(layer "In4.Cu")
		(net "M_G_CPU1_SB_CS_N<2>")
	)
	(gr_poly
		(pts
			(xy 132.019548 -244.127274) (xy 131.972558 -243.974874) (xy 131.710938 -243.974874) (xy 131.663948 -244.127274)
			(xy 131.663948 -244.171724) (xy 132.019548 -244.171724)
		)
		(stroke
			(width 0)
			(type solid)
		)
		(fill yes)
		(layer "In4.Cu")
		(net "M_G_CPU1_SB_CB<6>")
	)
	(gr_poly
		(pts
			(xy 132.019548 -238.83493) (xy 132.019548 -238.790734) (xy 131.663948 -238.790734) (xy 131.663948 -238.83493)
			(xy 131.710938 -238.98733) (xy 131.972558 -238.98733)
		)
		(stroke
			(width 0)
			(type solid)
		)
		(fill yes)
		(layer "In4.Cu")
		(net "M_F_CPU1_SB_DQ<1>")
	)
	(gr_poly
		(pts
			(xy 132.02031 -243.718334) (xy 132.02031 -243.674138) (xy 131.66471 -243.674138) (xy 131.66471 -243.718334)
			(xy 131.7117 -243.870734) (xy 131.97332 -243.870734)
		)
		(stroke
			(width 0)
			(type solid)
		)
		(fill yes)
		(layer "In4.Cu")
		(net "M_G_CPU1_SB_CB<5>")
	)
	(gr_poly
		(pts
			(xy 132.02031 -239.24387) (xy 131.97332 -239.09147) (xy 131.7117 -239.09147) (xy 131.66471 -239.24387)
			(xy 131.66471 -239.28832) (xy 132.02031 -239.28832)
		)
		(stroke
			(width 0)
			(type solid)
		)
		(fill yes)
		(layer "In4.Cu")
		(net "M_F_CPU1_SB_DQ<2>")
	)
	(gr_poly
		(pts
			(xy 132.023866 -249.010678) (xy 131.976876 -248.858278) (xy 131.715256 -248.858278) (xy 131.668266 -249.010678)
			(xy 131.668266 -249.054874) (xy 132.023866 -249.054874)
		)
		(stroke
			(width 0)
			(type solid)
		)
		(fill yes)
		(layer "In4.Cu")
		(net "M_G_CPU1_SB_CA<3>")
	)
	(gr_poly
		(pts
			(xy 132.023866 -234.360466) (xy 131.976876 -234.208066) (xy 131.715256 -234.208066) (xy 131.668266 -234.360466)
			(xy 131.668266 -234.404916) (xy 132.023866 -234.404916)
		)
		(stroke
			(width 0)
			(type solid)
		)
		(fill yes)
		(layer "In4.Cu")
		(net "M_G_CPU1_SB_DQ<18>")
	)
	(gr_poly
		(pts
			(xy 132.03174 -248.506742) (xy 132.03174 -248.462292) (xy 131.67614 -248.462292) (xy 131.67614 -248.506742)
			(xy 131.72313 -248.659142) (xy 131.98475 -248.659142)
		)
		(stroke
			(width 0)
			(type solid)
		)
		(fill yes)
		(layer "In4.Cu")
		(net "M_G_CPU1_SB_CA<4>")
	)
	(gr_poly
		(pts
			(xy 132.032248 -222.557594) (xy 132.032248 -222.513144) (xy 131.676648 -222.513144) (xy 131.676648 -222.557594)
			(xy 131.723638 -222.709994) (xy 131.985258 -222.709994)
		)
		(stroke
			(width 0)
			(type solid)
		)
		(fill yes)
		(layer "In4.Cu")
		(net "M_F_CPU1_SB_DQ<29>")
	)
	(gr_poly
		(pts
			(xy 132.127752 -257.37947) (xy 132.080762 -257.22707) (xy 131.819142 -257.22707) (xy 131.772152 -257.37947)
			(xy 131.772152 -257.42392) (xy 132.127752 -257.42392)
		)
		(stroke
			(width 0)
			(type solid)
		)
		(fill yes)
		(layer "In4.Cu")
		(net "M_G_CPU1_SA_CS_N<1>")
	)
	(gr_poly
		(pts
			(xy 132.12953 -267.146278) (xy 132.08254 -266.993878) (xy 131.82092 -266.993878) (xy 131.77393 -267.146278)
			(xy 131.77393 -267.190728) (xy 132.12953 -267.190728)
		)
		(stroke
			(width 0)
			(type solid)
		)
		(fill yes)
		(layer "In4.Cu")
		(net "M_G_CPU1_SA_DQ<18>")
	)
	(gr_poly
		(pts
			(xy 132.12953 -261.854442) (xy 132.12953 -261.809992) (xy 131.77393 -261.809992) (xy 131.77393 -261.854442)
			(xy 131.82092 -262.006842) (xy 132.08254 -262.006842)
		)
		(stroke
			(width 0)
			(type solid)
		)
		(fill yes)
		(layer "In4.Cu")
		(net "M_F_CPU1_SA_DQ<25>")
	)
	(gr_poly
		(pts
			(xy 132.130292 -276.504146) (xy 132.130292 -276.45995) (xy 131.774692 -276.45995) (xy 131.774692 -276.504146)
			(xy 131.821682 -276.656546) (xy 132.083302 -276.656546)
		)
		(stroke
			(width 0)
			(type solid)
		)
		(fill yes)
		(layer "In4.Cu")
		(net "M_G_CPU1_SA_DQ<1>")
	)
	(gr_poly
		(pts
			(xy 132.130292 -271.620742) (xy 132.130292 -271.576546) (xy 131.774692 -271.576546) (xy 131.774692 -271.620742)
			(xy 131.821682 -271.773142) (xy 132.083302 -271.773142)
		)
		(stroke
			(width 0)
			(type solid)
		)
		(fill yes)
		(layer "In4.Cu")
		(net "M_F_CPU1_SA_DQ<9>")
	)
	(gr_poly
		(pts
			(xy 132.130292 -266.737338) (xy 132.130292 -266.693142) (xy 131.774692 -266.693142) (xy 131.774692 -266.737338)
			(xy 131.821682 -266.889738) (xy 132.083302 -266.889738)
		)
		(stroke
			(width 0)
			(type solid)
		)
		(fill yes)
		(layer "In4.Cu")
		(net "M_G_CPU1_SA_DQ<17>")
	)
	(gr_poly
		(pts
			(xy 132.13969 -276.913086) (xy 132.0927 -276.760686) (xy 131.83108 -276.760686) (xy 131.78409 -276.913086)
			(xy 131.78409 -276.957282) (xy 132.13969 -276.957282)
		)
		(stroke
			(width 0)
			(type solid)
		)
		(fill yes)
		(layer "In4.Cu")
		(net "M_G_CPU1_SA_DQ<2>")
	)
	(gr_poly
		(pts
			(xy 132.13969 -256.971038) (xy 132.13969 -256.926588) (xy 131.78409 -256.926588) (xy 131.78409 -256.971038)
			(xy 131.83108 -257.123438) (xy 132.0927 -257.123438)
		)
		(stroke
			(width 0)
			(type solid)
		)
		(fill yes)
		(layer "In4.Cu")
		(net "M_G_CPU1_SA_CS_N<2>")
	)
	(gr_poly
		(pts
			(xy 132.13969 -255.751838) (xy 132.0927 -255.599438) (xy 131.83108 -255.599438) (xy 131.78409 -255.751838)
			(xy 131.78409 -255.796288) (xy 132.13969 -255.796288)
		)
		(stroke
			(width 0)
			(type solid)
		)
		(fill yes)
		(layer "In4.Cu")
		(net "M_G_CPU1_SA_CA<0>")
	)
	(gr_poly
		(pts
			(xy 132.14223 -255.343406) (xy 132.14223 -255.29921) (xy 131.78663 -255.29921) (xy 131.78663 -255.343406)
			(xy 131.83362 -255.495806) (xy 132.09524 -255.495806)
		)
		(stroke
			(width 0)
			(type solid)
		)
		(fill yes)
		(layer "In4.Cu")
		(net "M_G_CPU1_SA_CA<3>")
	)
	(gr_poly
		(pts
			(xy 132.213096 -273.717766) (xy 132.104638 -273.600926) (xy 132.066284 -273.578828) (xy 131.888484 -273.886676)
			(xy 131.926838 -273.908774) (xy 132.082286 -273.944334)
		)
		(stroke
			(width 0)
			(type solid)
		)
		(fill yes)
		(layer "In4.Cu")
		(net "M_G_CPU1_SA_DQ<5>")
	)
	(gr_poly
		(pts
			(xy 132.383276 -221.514162) (xy 132.344922 -221.492064) (xy 132.189474 -221.456504) (xy 132.058664 -221.683072)
			(xy 132.167122 -221.799912) (xy 132.205476 -221.82201)
		)
		(stroke
			(width 0)
			(type solid)
		)
		(fill yes)
		(layer "In4.Cu")
		(net "M_F_CPU1_SB_DQ<31>")
	)
	(gr_poly
		(pts
			(xy 132.387086 -223.135698) (xy 132.348732 -223.1136) (xy 132.193284 -223.07804) (xy 132.062474 -223.304608)
			(xy 132.170932 -223.421448) (xy 132.209286 -223.443546)
		)
		(stroke
			(width 0)
			(type solid)
		)
		(fill yes)
		(layer "In4.Cu")
		(net "M_F_CPU1_SB_DQ<28>")
	)
	(gr_poly
		(pts
			(xy 132.48767 -234.76585) (xy 132.48767 -234.7214) (xy 132.13207 -234.7214) (xy 132.13207 -234.76585)
			(xy 132.17906 -234.91825) (xy 132.44068 -234.91825)
		)
		(stroke
			(width 0)
			(type solid)
		)
		(fill yes)
		(layer "In4.Cu")
		(net "M_G_CPU1_SB_DQ<16>")
	)
	(gr_poly
		(pts
			(xy 132.49148 -246.160798) (xy 132.49148 -246.116348) (xy 132.13588 -246.116348) (xy 132.13588 -246.160798)
			(xy 132.18287 -246.313198) (xy 132.44449 -246.313198)
		)
		(stroke
			(width 0)
			(type solid)
		)
		(fill yes)
		(layer "In4.Cu")
		(net "M_G_CPU1_SB_CS_N<3>")
	)
	(gr_poly
		(pts
			(xy 132.493766 -249.415554) (xy 132.493766 -249.371358) (xy 132.138166 -249.371358) (xy 132.138166 -249.415554)
			(xy 132.185156 -249.567954) (xy 132.446776 -249.567954)
		)
		(stroke
			(width 0)
			(type solid)
		)
		(fill yes)
		(layer "In4.Cu")
		(net "M_G_CPU1_SB_CA<2>")
	)
	(gr_poly
		(pts
			(xy 132.497068 -240.057686) (xy 132.450078 -239.905286) (xy 132.188458 -239.905286) (xy 132.141468 -240.057686)
			(xy 132.141468 -240.102136) (xy 132.497068 -240.102136)
		)
		(stroke
			(width 0)
			(type solid)
		)
		(fill yes)
		(layer "In4.Cu")
		(net "M_G_CPU1_SB_CB<3>")
	)
	(gr_poly
		(pts
			(xy 132.497068 -239.648746) (xy 132.497068 -239.60455) (xy 132.141468 -239.60455) (xy 132.141468 -239.648746)
			(xy 132.188458 -239.801146) (xy 132.450078 -239.801146)
		)
		(stroke
			(width 0)
			(type solid)
		)
		(fill yes)
		(layer "In4.Cu")
		(net "M_F_CPU1_SB_DQ<0>")
	)
	(gr_poly
		(pts
			(xy 132.497068 -235.174282) (xy 132.450078 -235.021882) (xy 132.188458 -235.021882) (xy 132.141468 -235.174282)
			(xy 132.141468 -235.218732) (xy 132.497068 -235.218732)
		)
		(stroke
			(width 0)
			(type solid)
		)
		(fill yes)
		(layer "In4.Cu")
		(net "M_F_CPU1_SB_DQ<7>")
	)
	(gr_poly
		(pts
			(xy 132.49783 -244.53215) (xy 132.49783 -244.487954) (xy 132.14223 -244.487954) (xy 132.14223 -244.53215)
			(xy 132.18922 -244.68455) (xy 132.45084 -244.68455)
		)
		(stroke
			(width 0)
			(type solid)
		)
		(fill yes)
		(layer "In4.Cu")
		(net "M_G_CPU1_SB_CB<4>")
	)
	(gr_poly
		(pts
			(xy 132.567426 -222.22206) (xy 132.458968 -222.10522) (xy 132.420614 -222.083122) (xy 132.242814 -222.39097)
			(xy 132.281168 -222.413068) (xy 132.436616 -222.448628)
		)
		(stroke
			(width 0)
			(type solid)
		)
		(fill yes)
		(layer "In4.Cu")
		(net "M_F_CPU1_SB_DQ<29>")
	)
	(gr_poly
		(pts
			(xy 132.573014 -223.84004) (xy 132.464556 -223.7232) (xy 132.426202 -223.701102) (xy 132.248402 -224.00895)
			(xy 132.286756 -224.031048) (xy 132.442204 -224.066608)
		)
		(stroke
			(width 0)
			(type solid)
		)
		(fill yes)
		(layer "In4.Cu")
		(net "M_F_CPU1_SB_DQ<30>")
	)
	(gr_poly
		(pts
			(xy 132.595112 -265.92403) (xy 132.595112 -265.87958) (xy 132.239512 -265.87958) (xy 132.239512 -265.92403)
			(xy 132.286502 -266.07643) (xy 132.548122 -266.07643)
		)
		(stroke
			(width 0)
			(type solid)
		)
		(fill yes)
		(layer "In4.Cu")
		(net "M_G_CPU1_SA_DQS_DP<2>")
	)
	(gr_poly
		(pts
			(xy 132.595366 -254.937514) (xy 132.548376 -254.785114) (xy 132.286756 -254.785114) (xy 132.239766 -254.937514)
			(xy 132.239766 -254.981964) (xy 132.595366 -254.981964)
		)
		(stroke
			(width 0)
			(type solid)
		)
		(fill yes)
		(layer "In4.Cu")
		(net "M_G_CPU1_SA_CA<2>")
	)
	(gr_poly
		(pts
			(xy 132.597652 -272.843498) (xy 132.550662 -272.691098) (xy 132.289042 -272.691098) (xy 132.242052 -272.843498)
			(xy 132.242052 -272.887948) (xy 132.597652 -272.887948)
		)
		(stroke
			(width 0)
			(type solid)
		)
		(fill yes)
		(layer "In4.Cu")
		(net "M_G_CPU1_SA_DQ<7>")
	)
	(gr_poly
		(pts
			(xy 132.597652 -267.960094) (xy 132.550662 -267.807694) (xy 132.289042 -267.807694) (xy 132.242052 -267.960094)
			(xy 132.242052 -268.004544) (xy 132.597652 -268.004544)
		)
		(stroke
			(width 0)
			(type solid)
		)
		(fill yes)
		(layer "In4.Cu")
		(net "M_F_CPU1_SA_DQ<13>")
	)
	(gr_poly
		(pts
			(xy 132.597652 -258.193286) (xy 132.550662 -258.040886) (xy 132.289042 -258.040886) (xy 132.242052 -258.193286)
			(xy 132.242052 -258.237736) (xy 132.597652 -258.237736)
		)
		(stroke
			(width 0)
			(type solid)
		)
		(fill yes)
		(layer "In4.Cu")
		(net "M_F_CPU1_SA_DQ<31>")
	)
	(gr_poly
		(pts
			(xy 132.603494 -277.317962) (xy 132.603494 -277.273766) (xy 132.247894 -277.273766) (xy 132.247894 -277.317962)
			(xy 132.294884 -277.470362) (xy 132.556504 -277.470362)
		)
		(stroke
			(width 0)
			(type solid)
		)
		(fill yes)
		(layer "In4.Cu")
		(net "M_G_CPU1_SA_DQ<0>")
	)
	(gr_poly
		(pts
			(xy 132.603494 -256.565654) (xy 132.556504 -256.413254) (xy 132.294884 -256.413254) (xy 132.247894 -256.565654)
			(xy 132.247894 -256.610104) (xy 132.603494 -256.610104)
		)
		(stroke
			(width 0)
			(type solid)
		)
		(fill yes)
		(layer "In4.Cu")
		(net "M_G_CPU1_SA_CS_N<3>")
	)
	(gr_poly
		(pts
			(xy 132.603494 -256.157222) (xy 132.603494 -256.112772) (xy 132.247894 -256.112772) (xy 132.247894 -256.157222)
			(xy 132.294884 -256.309622) (xy 132.556504 -256.309622)
		)
		(stroke
			(width 0)
			(type solid)
		)
		(fill yes)
		(layer "In4.Cu")
		(net "M_G_CPU1_SA_CA<1>")
	)
	(gr_poly
		(pts
			(xy 132.60705 -263.077198) (xy 132.56006 -262.924798) (xy 132.29844 -262.924798) (xy 132.25145 -263.077198)
			(xy 132.25145 -263.121394) (xy 132.60705 -263.121394)
		)
		(stroke
			(width 0)
			(type solid)
		)
		(fill yes)
		(layer "In4.Cu")
		(net "M_G_CPU1_SA_DQ<23>")
	)
	(gr_poly
		(pts
			(xy 132.607812 -272.434558) (xy 132.607812 -272.390362) (xy 132.252212 -272.390362) (xy 132.252212 -272.434558)
			(xy 132.299202 -272.586958) (xy 132.560822 -272.586958)
		)
		(stroke
			(width 0)
			(type solid)
		)
		(fill yes)
		(layer "In4.Cu")
		(net "M_F_CPU1_SA_DQ<8>")
	)
	(gr_poly
		(pts
			(xy 132.607812 -267.551154) (xy 132.607812 -267.506958) (xy 132.252212 -267.506958) (xy 132.252212 -267.551154)
			(xy 132.299202 -267.703554) (xy 132.560822 -267.703554)
		)
		(stroke
			(width 0)
			(type solid)
		)
		(fill yes)
		(layer "In4.Cu")
		(net "M_G_CPU1_SA_DQ<16>")
	)
	(gr_poly
		(pts
			(xy 132.60959 -257.784854) (xy 132.60959 -257.740404) (xy 132.25399 -257.740404) (xy 132.25399 -257.784854)
			(xy 132.30098 -257.937254) (xy 132.5626 -257.937254)
		)
		(stroke
			(width 0)
			(type solid)
		)
		(fill yes)
		(layer "In4.Cu")
		(net "M_G_CPU1_SA_CS_N<0>")
	)
	(gr_poly
		(pts
			(xy 132.61086 -270.806926) (xy 132.61086 -270.76273) (xy 132.25526 -270.76273) (xy 132.25526 -270.806926)
			(xy 132.30225 -270.959326) (xy 132.56387 -270.959326)
		)
		(stroke
			(width 0)
			(type solid)
		)
		(fill yes)
		(layer "In4.Cu")
		(net "M_F_CPU1_SA_DQS_DP<1>")
	)
	(gr_poly
		(pts
			(xy 132.858764 -222.318326) (xy 132.82041 -222.296228) (xy 132.664962 -222.260668) (xy 132.534152 -222.487236)
			(xy 132.64261 -222.604076) (xy 132.680964 -222.626174)
		)
		(stroke
			(width 0)
			(type solid)
		)
		(fill yes)
		(layer "In4.Cu")
		(net "M_F_CPU1_SB_DQ<28>")
	)
	(gr_poly
		(pts
			(xy 132.85978 -220.68917) (xy 132.821426 -220.667072) (xy 132.665978 -220.631512) (xy 132.535168 -220.85808)
			(xy 132.643626 -220.97492) (xy 132.68198 -220.997018)
		)
		(stroke
			(width 0)
			(type solid)
		)
		(fill yes)
		(layer "In4.Cu")
		(net "M_F_CPU1_SB_DQ<31>")
	)
	(gr_poly
		(pts
			(xy 132.95503 -245.754906) (xy 132.90804 -245.602506) (xy 132.64642 -245.602506) (xy 132.59943 -245.754906)
			(xy 132.59943 -245.799102) (xy 132.95503 -245.799102)
		)
		(stroke
			(width 0)
			(type solid)
		)
		(fill yes)
		(layer "In4.Cu")
		(net "M_G_CPU1_SB_CS_N<1>")
	)
	(gr_poly
		(pts
			(xy 132.95757 -237.616238) (xy 132.91058 -237.463838) (xy 132.64896 -237.463838) (xy 132.60197 -237.616238)
			(xy 132.60197 -237.660434) (xy 132.95757 -237.660434)
		)
		(stroke
			(width 0)
			(type solid)
		)
		(fill yes)
		(layer "In4.Cu")
		(net "M_F_CPU1_SB_DQS_DN<0>")
	)
	(gr_poly
		(pts
			(xy 132.95757 -232.732834) (xy 132.91058 -232.580434) (xy 132.64896 -232.580434) (xy 132.60197 -232.732834)
			(xy 132.60197 -232.77703) (xy 132.95757 -232.77703)
		)
		(stroke
			(width 0)
			(type solid)
		)
		(fill yes)
		(layer "In4.Cu")
		(net "M_G_CPU1_SB_DQS_DN<2>")
	)
	(gr_poly
		(pts
			(xy 132.959348 -244.127274) (xy 132.912358 -243.974874) (xy 132.650738 -243.974874) (xy 132.603748 -244.127274)
			(xy 132.603748 -244.171724) (xy 132.959348 -244.171724)
		)
		(stroke
			(width 0)
			(type solid)
		)
		(fill yes)
		(layer "In4.Cu")
		(net "M_G_CPU1_SB_CB<6>")
	)
	(gr_poly
		(pts
			(xy 132.959348 -238.83493) (xy 132.959348 -238.790734) (xy 132.603748 -238.790734) (xy 132.603748 -238.83493)
			(xy 132.650738 -238.98733) (xy 132.912358 -238.98733)
		)
		(stroke
			(width 0)
			(type solid)
		)
		(fill yes)
		(layer "In4.Cu")
		(net "M_F_CPU1_SB_DQ<1>")
	)
	(gr_poly
		(pts
			(xy 132.959348 -235.988606) (xy 132.912358 -235.836206) (xy 132.650738 -235.836206) (xy 132.603748 -235.988606)
			(xy 132.603748 -236.032802) (xy 132.959348 -236.032802)
		)
		(stroke
			(width 0)
			(type solid)
		)
		(fill yes)
		(layer "In4.Cu")
		(net "M_F_CPU1_SB_DQ<6>")
	)
	(gr_poly
		(pts
			(xy 132.959348 -233.951526) (xy 132.959348 -233.90733) (xy 132.603748 -233.90733) (xy 132.603748 -233.951526)
			(xy 132.650738 -234.103926) (xy 132.912358 -234.103926)
		)
		(stroke
			(width 0)
			(type solid)
		)
		(fill yes)
		(layer "In4.Cu")
		(net "M_G_CPU1_SB_DQ<17>")
	)
	(gr_poly
		(pts
			(xy 132.959348 -231.105202) (xy 132.912358 -230.952802) (xy 132.650738 -230.952802) (xy 132.603748 -231.105202)
			(xy 132.603748 -231.149398) (xy 132.959348 -231.149398)
		)
		(stroke
			(width 0)
			(type solid)
		)
		(fill yes)
		(layer "In4.Cu")
		(net "M_G_CPU1_SB_DQ<22>")
	)
	(gr_poly
		(pts
			(xy 132.96011 -243.718334) (xy 132.96011 -243.674138) (xy 132.60451 -243.674138) (xy 132.60451 -243.718334)
			(xy 132.6515 -243.870734) (xy 132.91312 -243.870734)
		)
		(stroke
			(width 0)
			(type solid)
		)
		(fill yes)
		(layer "In4.Cu")
		(net "M_G_CPU1_SB_CB<5>")
	)
	(gr_poly
		(pts
			(xy 132.96011 -240.871502) (xy 132.91312 -240.719102) (xy 132.6515 -240.719102) (xy 132.60451 -240.871502)
			(xy 132.60451 -240.915952) (xy 132.96011 -240.915952)
		)
		(stroke
			(width 0)
			(type solid)
		)
		(fill yes)
		(layer "In4.Cu")
		(net "M_G_CPU1_SB_CB<2>")
	)
	(gr_poly
		(pts
			(xy 132.96011 -240.462562) (xy 132.96011 -240.418366) (xy 132.60451 -240.418366) (xy 132.60451 -240.462562)
			(xy 132.6515 -240.614962) (xy 132.91312 -240.614962)
		)
		(stroke
			(width 0)
			(type solid)
		)
		(fill yes)
		(layer "In4.Cu")
		(net "M_G_CPU1_SB_CB<1>")
	)
	(gr_poly
		(pts
			(xy 132.96011 -239.24387) (xy 132.91312 -239.09147) (xy 132.6515 -239.09147) (xy 132.60451 -239.24387)
			(xy 132.60451 -239.28832) (xy 132.96011 -239.28832)
		)
		(stroke
			(width 0)
			(type solid)
		)
		(fill yes)
		(layer "In4.Cu")
		(net "M_F_CPU1_SB_DQ<2>")
	)
	(gr_poly
		(pts
			(xy 132.96011 -235.579666) (xy 132.96011 -235.535216) (xy 132.60451 -235.535216) (xy 132.60451 -235.579666)
			(xy 132.6515 -235.732066) (xy 132.91312 -235.732066)
		)
		(stroke
			(width 0)
			(type solid)
		)
		(fill yes)
		(layer "In4.Cu")
		(net "M_F_CPU1_SB_DQ<5>")
	)
	(gr_poly
		(pts
			(xy 132.96011 -230.696262) (xy 132.96011 -230.651812) (xy 132.60451 -230.651812) (xy 132.60451 -230.696262)
			(xy 132.6515 -230.848662) (xy 132.91312 -230.848662)
		)
		(stroke
			(width 0)
			(type solid)
		)
		(fill yes)
		(layer "In4.Cu")
		(net "M_G_CPU1_SB_DQ<21>")
	)
	(gr_poly
		(pts
			(xy 132.963666 -249.010678) (xy 132.916676 -248.858278) (xy 132.655056 -248.858278) (xy 132.608066 -249.010678)
			(xy 132.608066 -249.054874) (xy 132.963666 -249.054874)
		)
		(stroke
			(width 0)
			(type solid)
		)
		(fill yes)
		(layer "In4.Cu")
		(net "M_G_CPU1_SB_CA<3>")
	)
	(gr_poly
		(pts
			(xy 132.963666 -248.601738) (xy 132.963666 -248.557542) (xy 132.608066 -248.557542) (xy 132.608066 -248.601738)
			(xy 132.655056 -248.754138) (xy 132.916676 -248.754138)
		)
		(stroke
			(width 0)
			(type solid)
		)
		(fill yes)
		(layer "In4.Cu")
		(net "M_G_CPU1_SB_CA<4>")
	)
	(gr_poly
		(pts
			(xy 132.963666 -242.499642) (xy 132.916676 -242.347242) (xy 132.655056 -242.347242) (xy 132.608066 -242.499642)
			(xy 132.608066 -242.544092) (xy 132.963666 -242.544092)
		)
		(stroke
			(width 0)
			(type solid)
		)
		(fill yes)
		(layer "In4.Cu")
		(net "M_G_CPU1_SB_DQS_DN<9>")
	)
	(gr_poly
		(pts
			(xy 132.972048 -234.360466) (xy 132.925058 -234.208066) (xy 132.663438 -234.208066) (xy 132.616448 -234.360466)
			(xy 132.616448 -234.404662) (xy 132.972048 -234.404662)
		)
		(stroke
			(width 0)
			(type solid)
		)
		(fill yes)
		(layer "In4.Cu")
		(net "M_G_CPU1_SB_DQ<18>")
	)
	(gr_poly
		(pts
			(xy 133.036564 -223.0374) (xy 132.928106 -222.92056) (xy 132.889752 -222.898462) (xy 132.711952 -223.20631)
			(xy 132.750306 -223.228408) (xy 132.905754 -223.263968)
		)
		(stroke
			(width 0)
			(type solid)
		)
		(fill yes)
		(layer "In4.Cu")
		(net "M_F_CPU1_SB_DQ<30>")
	)
	(gr_poly
		(pts
			(xy 133.042914 -221.398592) (xy 132.934456 -221.281752) (xy 132.896102 -221.259654) (xy 132.718302 -221.567502)
			(xy 132.756656 -221.5896) (xy 132.912104 -221.62516)
		)
		(stroke
			(width 0)
			(type solid)
		)
		(fill yes)
		(layer "In4.Cu")
		(net "M_F_CPU1_SB_DQ<29>")
	)
	(gr_poly
		(pts
			(xy 133.069076 -270.40205) (xy 133.022086 -270.24965) (xy 132.760466 -270.24965) (xy 132.713476 -270.40205)
			(xy 132.713476 -270.446246) (xy 133.069076 -270.446246)
		)
		(stroke
			(width 0)
			(type solid)
		)
		(fill yes)
		(layer "In4.Cu")
		(net "M_F_CPU1_SA_DQS_DN<1>")
	)
	(gr_poly
		(pts
			(xy 133.06933 -272.029682) (xy 133.02234 -271.877282) (xy 132.76072 -271.877282) (xy 132.71373 -272.029682)
			(xy 132.71373 -272.074132) (xy 133.06933 -272.074132)
		)
		(stroke
			(width 0)
			(type solid)
		)
		(fill yes)
		(layer "In4.Cu")
		(net "M_F_CPU1_SA_DQ<10>")
	)
	(gr_poly
		(pts
			(xy 133.06933 -267.146278) (xy 133.02234 -266.993878) (xy 132.76072 -266.993878) (xy 132.71373 -267.146278)
			(xy 132.71373 -267.190728) (xy 133.06933 -267.190728)
		)
		(stroke
			(width 0)
			(type solid)
		)
		(fill yes)
		(layer "In4.Cu")
		(net "M_G_CPU1_SA_DQ<18>")
	)
	(gr_poly
		(pts
			(xy 133.06933 -261.854442) (xy 133.06933 -261.809992) (xy 132.71373 -261.809992) (xy 132.71373 -261.854442)
			(xy 132.76072 -262.006842) (xy 133.02234 -262.006842)
		)
		(stroke
			(width 0)
			(type solid)
		)
		(fill yes)
		(layer "In4.Cu")
		(net "M_F_CPU1_SA_DQ<25>")
	)
	(gr_poly
		(pts
			(xy 133.070092 -273.657314) (xy 133.023102 -273.504914) (xy 132.761482 -273.504914) (xy 132.714492 -273.657314)
			(xy 132.714492 -273.701764) (xy 133.070092 -273.701764)
		)
		(stroke
			(width 0)
			(type solid)
		)
		(fill yes)
		(layer "In4.Cu")
		(net "M_G_CPU1_SA_DQ<6>")
	)
	(gr_poly
		(pts
			(xy 133.070092 -271.620742) (xy 133.070092 -271.576546) (xy 132.714492 -271.576546) (xy 132.714492 -271.620742)
			(xy 132.761482 -271.773142) (xy 133.023102 -271.773142)
		)
		(stroke
			(width 0)
			(type solid)
		)
		(fill yes)
		(layer "In4.Cu")
		(net "M_F_CPU1_SA_DQ<9>")
	)
	(gr_poly
		(pts
			(xy 133.070092 -268.77391) (xy 133.023102 -268.62151) (xy 132.761482 -268.62151) (xy 132.714492 -268.77391)
			(xy 132.714492 -268.81836) (xy 133.070092 -268.81836)
		)
		(stroke
			(width 0)
			(type solid)
		)
		(fill yes)
		(layer "In4.Cu")
		(net "M_F_CPU1_SA_DQ<14>")
	)
	(gr_poly
		(pts
			(xy 133.070092 -266.737338) (xy 133.070092 -266.693142) (xy 132.714492 -266.693142) (xy 132.714492 -266.737338)
			(xy 132.761482 -266.889738) (xy 133.023102 -266.889738)
		)
		(stroke
			(width 0)
			(type solid)
		)
		(fill yes)
		(layer "In4.Cu")
		(net "M_G_CPU1_SA_DQ<17>")
	)
	(gr_poly
		(pts
			(xy 133.070092 -263.891014) (xy 133.023102 -263.738614) (xy 132.761482 -263.738614) (xy 132.714492 -263.891014)
			(xy 132.714492 -263.93521) (xy 133.070092 -263.93521)
		)
		(stroke
			(width 0)
			(type solid)
		)
		(fill yes)
		(layer "In4.Cu")
		(net "M_G_CPU1_SA_DQ<22>")
	)
	(gr_poly
		(pts
			(xy 133.070092 -263.482074) (xy 133.070092 -263.437624) (xy 132.714492 -263.437624) (xy 132.714492 -263.482074)
			(xy 132.761482 -263.634474) (xy 133.023102 -263.634474)
		)
		(stroke
			(width 0)
			(type solid)
		)
		(fill yes)
		(layer "In4.Cu")
		(net "M_G_CPU1_SA_DQ<21>")
	)
	(gr_poly
		(pts
			(xy 133.073394 -255.751838) (xy 133.026404 -255.599438) (xy 132.764784 -255.599438) (xy 132.717794 -255.751838)
			(xy 132.717794 -255.796288) (xy 133.073394 -255.796288)
		)
		(stroke
			(width 0)
			(type solid)
		)
		(fill yes)
		(layer "In4.Cu")
		(net "M_G_CPU1_SA_CA<0>")
	)
	(gr_poly
		(pts
			(xy 133.073648 -255.343406) (xy 133.073648 -255.298956) (xy 132.718048 -255.298956) (xy 132.718048 -255.343406)
			(xy 132.765038 -255.495806) (xy 133.026658 -255.495806)
		)
		(stroke
			(width 0)
			(type solid)
		)
		(fill yes)
		(layer "In4.Cu")
		(net "M_G_CPU1_SA_CA<3>")
	)
	(gr_poly
		(pts
			(xy 133.07949 -276.912578) (xy 133.0325 -276.760178) (xy 132.77088 -276.760178) (xy 132.72389 -276.912578)
			(xy 132.72389 -276.957028) (xy 133.07949 -276.957028)
		)
		(stroke
			(width 0)
			(type solid)
		)
		(fill yes)
		(layer "In4.Cu")
		(net "M_G_CPU1_SA_DQ<2>")
	)
	(gr_poly
		(pts
			(xy 133.07949 -276.5044) (xy 133.07949 -276.460204) (xy 132.72389 -276.460204) (xy 132.72389 -276.5044)
			(xy 132.77088 -276.6568) (xy 133.0325 -276.6568)
		)
		(stroke
			(width 0)
			(type solid)
		)
		(fill yes)
		(layer "In4.Cu")
		(net "M_G_CPU1_SA_DQ<1>")
	)
	(gr_poly
		(pts
			(xy 133.07949 -275.284946) (xy 133.0325 -275.132546) (xy 132.77088 -275.132546) (xy 132.72389 -275.284946)
			(xy 132.72389 -275.329396) (xy 133.07949 -275.329396)
		)
		(stroke
			(width 0)
			(type solid)
		)
		(fill yes)
		(layer "In4.Cu")
		(net "M_G_CPU1_SA_DQS_DN<0>")
	)
	(gr_poly
		(pts
			(xy 133.07949 -265.518646) (xy 133.0325 -265.366246) (xy 132.77088 -265.366246) (xy 132.72389 -265.518646)
			(xy 132.72389 -265.562842) (xy 133.07949 -265.562842)
		)
		(stroke
			(width 0)
			(type solid)
		)
		(fill yes)
		(layer "In4.Cu")
		(net "M_G_CPU1_SA_DQS_DN<2>")
	)
	(gr_poly
		(pts
			(xy 133.07949 -260.635242) (xy 133.0325 -260.482842) (xy 132.77088 -260.482842) (xy 132.72389 -260.635242)
			(xy 132.72389 -260.679438) (xy 133.07949 -260.679438)
		)
		(stroke
			(width 0)
			(type solid)
		)
		(fill yes)
		(layer "In4.Cu")
		(net "M_F_CPU1_SA_DQS_DN<3>")
	)
	(gr_poly
		(pts
			(xy 133.07949 -257.37947) (xy 133.0325 -257.22707) (xy 132.77088 -257.22707) (xy 132.72389 -257.37947)
			(xy 132.72389 -257.423666) (xy 133.07949 -257.423666)
		)
		(stroke
			(width 0)
			(type solid)
		)
		(fill yes)
		(layer "In4.Cu")
		(net "M_G_CPU1_SA_CS_N<1>")
	)
	(gr_poly
		(pts
			(xy 133.07949 -256.971038) (xy 133.07949 -256.926842) (xy 132.72389 -256.926842) (xy 132.72389 -256.971038)
			(xy 132.77088 -257.123438) (xy 133.0325 -257.123438)
		)
		(stroke
			(width 0)
			(type solid)
		)
		(fill yes)
		(layer "In4.Cu")
		(net "M_G_CPU1_SA_CS_N<2>")
	)
	(gr_poly
		(pts
			(xy 133.08203 -273.248882) (xy 133.08203 -273.204686) (xy 132.72643 -273.204686) (xy 132.72643 -273.248882)
			(xy 132.77342 -273.401282) (xy 133.03504 -273.401282)
		)
		(stroke
			(width 0)
			(type solid)
		)
		(fill yes)
		(layer "In4.Cu")
		(net "M_G_CPU1_SA_DQ<5>")
	)
	(gr_poly
		(pts
			(xy 133.08203 -268.365478) (xy 133.08203 -268.321282) (xy 132.72643 -268.321282) (xy 132.72643 -268.365478)
			(xy 132.77342 -268.517878) (xy 133.03504 -268.517878)
		)
		(stroke
			(width 0)
			(type solid)
		)
		(fill yes)
		(layer "In4.Cu")
		(net "M_F_CPU1_SA_DQ<15>")
	)
	(gr_poly
		(pts
			(xy 133.08203 -258.599178) (xy 133.08203 -258.554728) (xy 132.72643 -258.554728) (xy 132.72643 -258.599178)
			(xy 132.77342 -258.751578) (xy 133.03504 -258.751578)
		)
		(stroke
			(width 0)
			(type solid)
		)
		(fill yes)
		(layer "In4.Cu")
		(net "M_F_CPU1_SA_DQ<29>")
	)
	(gr_poly
		(pts
			(xy 133.321298 -226.400614) (xy 133.282944 -226.378516) (xy 133.127496 -226.342956) (xy 132.996686 -226.569524)
			(xy 133.105144 -226.686364) (xy 133.143498 -226.708462)
		)
		(stroke
			(width 0)
			(type solid)
		)
		(fill yes)
		(layer "In4.Cu")
		(net "M_F_CPU1_SB_DQS_DN<3>")
	)
	(gr_poly
		(pts
			(xy 133.327648 -219.879164) (xy 133.289294 -219.857066) (xy 133.133846 -219.821506) (xy 133.003036 -220.048074)
			(xy 133.111494 -220.164914) (xy 133.149848 -220.187012)
		)
		(stroke
			(width 0)
			(type solid)
		)
		(fill yes)
		(layer "In4.Cu")
		(net "M_F_CPU1_SB_DQ<31>")
	)
	(gr_poly
		(pts
			(xy 133.42747 -241.685318) (xy 133.38048 -241.532918) (xy 133.11886 -241.532918) (xy 133.07187 -241.685318)
			(xy 133.07187 -241.729514) (xy 133.42747 -241.729514)
		)
		(stroke
			(width 0)
			(type solid)
		)
		(fill yes)
		(layer "In4.Cu")
		(net "M_G_CPU1_SB_DQS_DP<4>")
	)
	(gr_poly
		(pts
			(xy 133.42747 -234.76585) (xy 133.42747 -234.721654) (xy 133.07187 -234.721654) (xy 133.07187 -234.76585)
			(xy 133.11886 -234.91825) (xy 133.38048 -234.91825)
		)
		(stroke
			(width 0)
			(type solid)
		)
		(fill yes)
		(layer "In4.Cu")
		(net "M_G_CPU1_SB_DQ<16>")
	)
	(gr_poly
		(pts
			(xy 133.42747 -222.151702) (xy 133.38048 -221.999302) (xy 133.11886 -221.999302) (xy 133.07187 -222.151702)
			(xy 133.07187 -222.196152) (xy 133.42747 -222.196152)
		)
		(stroke
			(width 0)
			(type solid)
		)
		(fill yes)
		(layer "In4.Cu")
		(net "M_F_CPU1_SB_DQ<28>")
	)
	(gr_poly
		(pts
			(xy 133.433566 -249.415554) (xy 133.433566 -249.371358) (xy 133.077966 -249.371358) (xy 133.077966 -249.415554)
			(xy 133.124956 -249.567954) (xy 133.386576 -249.567954)
		)
		(stroke
			(width 0)
			(type solid)
		)
		(fill yes)
		(layer "In4.Cu")
		(net "M_G_CPU1_SB_CA<2>")
	)
	(gr_poly
		(pts
			(xy 133.433566 -248.196354) (xy 133.386576 -248.043954) (xy 133.124956 -248.043954) (xy 133.077966 -248.196354)
			(xy 133.077966 -248.240804) (xy 133.433566 -248.240804)
		)
		(stroke
			(width 0)
			(type solid)
		)
		(fill yes)
		(layer "In4.Cu")
		(net "M_G_CPU1_SB_CA<5>")
	)
	(gr_poly
		(pts
			(xy 133.433566 -228.254814) (xy 133.433566 -228.210364) (xy 133.077966 -228.210364) (xy 133.077966 -228.254814)
			(xy 133.124956 -228.407214) (xy 133.386576 -228.407214)
		)
		(stroke
			(width 0)
			(type solid)
		)
		(fill yes)
		(layer "In4.Cu")
		(net "M_F_CPU1_SB_DQS_DN<8>")
	)
	(gr_poly
		(pts
			(xy 133.436868 -243.313458) (xy 133.389878 -243.161058) (xy 133.128258 -243.161058) (xy 133.081268 -243.313458)
			(xy 133.081268 -243.357654) (xy 133.436868 -243.357654)
		)
		(stroke
			(width 0)
			(type solid)
		)
		(fill yes)
		(layer "In4.Cu")
		(net "M_G_CPU1_SB_CB<7>")
	)
	(gr_poly
		(pts
			(xy 133.436868 -241.276886) (xy 133.436868 -241.232436) (xy 133.081268 -241.232436) (xy 133.081268 -241.276886)
			(xy 133.128258 -241.429286) (xy 133.389878 -241.429286)
		)
		(stroke
			(width 0)
			(type solid)
		)
		(fill yes)
		(layer "In4.Cu")
		(net "M_G_CPU1_SB_CB<0>")
	)
	(gr_poly
		(pts
			(xy 133.436868 -240.057686) (xy 133.389878 -239.905286) (xy 133.128258 -239.905286) (xy 133.081268 -240.057686)
			(xy 133.081268 -240.102136) (xy 133.436868 -240.102136)
		)
		(stroke
			(width 0)
			(type solid)
		)
		(fill yes)
		(layer "In4.Cu")
		(net "M_G_CPU1_SB_CB<3>")
	)
	(gr_poly
		(pts
			(xy 133.436868 -239.648746) (xy 133.436868 -239.60455) (xy 133.081268 -239.60455) (xy 133.081268 -239.648746)
			(xy 133.128258 -239.801146) (xy 133.389878 -239.801146)
		)
		(stroke
			(width 0)
			(type solid)
		)
		(fill yes)
		(layer "In4.Cu")
		(net "M_F_CPU1_SB_DQ<0>")
	)
	(gr_poly
		(pts
			(xy 133.436868 -235.174282) (xy 133.389878 -235.021882) (xy 133.128258 -235.021882) (xy 133.081268 -235.174282)
			(xy 133.081268 -235.218732) (xy 133.436868 -235.218732)
		)
		(stroke
			(width 0)
			(type solid)
		)
		(fill yes)
		(layer "In4.Cu")
		(net "M_F_CPU1_SB_DQ<7>")
	)
	(gr_poly
		(pts
			(xy 133.436868 -230.290878) (xy 133.389878 -230.138478) (xy 133.128258 -230.138478) (xy 133.081268 -230.290878)
			(xy 133.081268 -230.335328) (xy 133.436868 -230.335328)
		)
		(stroke
			(width 0)
			(type solid)
		)
		(fill yes)
		(layer "In4.Cu")
		(net "M_G_CPU1_SB_DQ<23>")
	)
	(gr_poly
		(pts
			(xy 133.436868 -229.882446) (xy 133.436868 -229.837996) (xy 133.081268 -229.837996) (xy 133.081268 -229.882446)
			(xy 133.128258 -230.034846) (xy 133.389878 -230.034846)
		)
		(stroke
			(width 0)
			(type solid)
		)
		(fill yes)
		(layer "In4.Cu")
		(net "M_F_CPU1_SB_DQ<26>")
	)
	(gr_poly
		(pts
			(xy 133.43763 -244.53215) (xy 133.43763 -244.487954) (xy 133.08203 -244.487954) (xy 133.08203 -244.53215)
			(xy 133.12902 -244.68455) (xy 133.39064 -244.68455)
		)
		(stroke
			(width 0)
			(type solid)
		)
		(fill yes)
		(layer "In4.Cu")
		(net "M_G_CPU1_SB_CB<4>")
	)
	(gr_poly
		(pts
			(xy 133.43763 -238.430054) (xy 133.39064 -238.277654) (xy 133.12902 -238.277654) (xy 133.08203 -238.430054)
			(xy 133.08203 -238.47425) (xy 133.43763 -238.47425)
		)
		(stroke
			(width 0)
			(type solid)
		)
		(fill yes)
		(layer "In4.Cu")
		(net "M_F_CPU1_SB_DQ<3>")
	)
	(gr_poly
		(pts
			(xy 133.43763 -236.393482) (xy 133.43763 -236.349032) (xy 133.08203 -236.349032) (xy 133.08203 -236.393482)
			(xy 133.12902 -236.545882) (xy 133.39064 -236.545882)
		)
		(stroke
			(width 0)
			(type solid)
		)
		(fill yes)
		(layer "In4.Cu")
		(net "M_F_CPU1_SB_DQ<4>")
	)
	(gr_poly
		(pts
			(xy 133.43763 -233.54665) (xy 133.39064 -233.39425) (xy 133.12902 -233.39425) (xy 133.08203 -233.54665)
			(xy 133.08203 -233.5911) (xy 133.43763 -233.5911)
		)
		(stroke
			(width 0)
			(type solid)
		)
		(fill yes)
		(layer "In4.Cu")
		(net "M_G_CPU1_SB_DQ<19>")
	)
	(gr_poly
		(pts
			(xy 133.43763 -231.510078) (xy 133.43763 -231.465628) (xy 133.08203 -231.465628) (xy 133.08203 -231.510078)
			(xy 133.12902 -231.662478) (xy 133.39064 -231.662478)
		)
		(stroke
			(width 0)
			(type solid)
		)
		(fill yes)
		(layer "In4.Cu")
		(net "M_G_CPU1_SB_DQ<20>")
	)
	(gr_poly
		(pts
			(xy 133.439408 -236.801914) (xy 133.392418 -236.649514) (xy 133.130798 -236.649514) (xy 133.083808 -236.801914)
			(xy 133.083808 -236.84611) (xy 133.439408 -236.84611)
		)
		(stroke
			(width 0)
			(type solid)
		)
		(fill yes)
		(layer "In4.Cu")
		(net "M_F_CPU1_SB_DQS_DP<5>")
	)
	(gr_poly
		(pts
			(xy 133.439408 -231.91851) (xy 133.392418 -231.76611) (xy 133.130798 -231.76611) (xy 133.083808 -231.91851)
			(xy 133.083808 -231.96296) (xy 133.439408 -231.96296)
		)
		(stroke
			(width 0)
			(type solid)
		)
		(fill yes)
		(layer "In4.Cu")
		(net "M_G_CPU1_SB_DQS_DP<7>")
	)
	(gr_poly
		(pts
			(xy 133.441948 -247.787922) (xy 133.441948 -247.743726) (xy 133.086348 -247.743726) (xy 133.086348 -247.787922)
			(xy 133.133338 -247.940322) (xy 133.394958 -247.940322)
		)
		(stroke
			(width 0)
			(type solid)
		)
		(fill yes)
		(layer "In4.Cu")
		(net "M_G_CPU1_SB_CA<6>")
	)
	(gr_poly
		(pts
			(xy 133.441948 -246.568722) (xy 133.394958 -246.416322) (xy 133.133338 -246.416322) (xy 133.086348 -246.568722)
			(xy 133.086348 -246.612918) (xy 133.441948 -246.612918)
		)
		(stroke
			(width 0)
			(type solid)
		)
		(fill yes)
		(layer "In4.Cu")
		(net "M_G_CPU1_SB_CS_N<0>")
	)
	(gr_poly
		(pts
			(xy 133.441948 -246.16029) (xy 133.441948 -246.116094) (xy 133.086348 -246.116094) (xy 133.086348 -246.16029)
			(xy 133.133338 -246.31269) (xy 133.394958 -246.31269)
		)
		(stroke
			(width 0)
			(type solid)
		)
		(fill yes)
		(layer "In4.Cu")
		(net "M_G_CPU1_SB_CS_N<3>")
	)
	(gr_poly
		(pts
			(xy 133.441948 -242.905026) (xy 133.441948 -242.860576) (xy 133.086348 -242.860576) (xy 133.086348 -242.905026)
			(xy 133.133338 -243.057426) (xy 133.394958 -243.057426)
		)
		(stroke
			(width 0)
			(type solid)
		)
		(fill yes)
		(layer "In4.Cu")
		(net "M_G_CPU1_SB_DQS_DP<9>")
	)
	(gr_poly
		(pts
			(xy 133.441948 -238.021622) (xy 133.441948 -237.977172) (xy 133.086348 -237.977172) (xy 133.086348 -238.021622)
			(xy 133.133338 -238.174022) (xy 133.394958 -238.174022)
		)
		(stroke
			(width 0)
			(type solid)
		)
		(fill yes)
		(layer "In4.Cu")
		(net "M_F_CPU1_SB_DQS_DP<0>")
	)
	(gr_poly
		(pts
			(xy 133.441948 -233.138218) (xy 133.441948 -233.093768) (xy 133.086348 -233.093768) (xy 133.086348 -233.138218)
			(xy 133.133338 -233.290618) (xy 133.394958 -233.290618)
		)
		(stroke
			(width 0)
			(type solid)
		)
		(fill yes)
		(layer "In4.Cu")
		(net "M_G_CPU1_SB_DQS_DP<2>")
	)
	(gr_poly
		(pts
			(xy 133.506464 -220.595698) (xy 133.398006 -220.478858) (xy 133.359652 -220.45676) (xy 133.181852 -220.764608)
			(xy 133.220206 -220.786706) (xy 133.375654 -220.822266)
		)
		(stroke
			(width 0)
			(type solid)
		)
		(fill yes)
		(layer "In4.Cu")
		(net "M_F_CPU1_SB_DQ<29>")
	)
	(gr_poly
		(pts
			(xy 133.512814 -227.095558) (xy 133.404356 -226.978718) (xy 133.366002 -226.95662) (xy 133.188202 -227.264468)
			(xy 133.226556 -227.286566) (xy 133.382004 -227.322126)
		)
		(stroke
			(width 0)
			(type solid)
		)
		(fill yes)
		(layer "In4.Cu")
		(net "M_F_CPU1_SB_DQS_DP<3>")
	)
	(gr_poly
		(pts
			(xy 133.534912 -277.318216) (xy 133.534912 -277.27402) (xy 133.179312 -277.27402) (xy 133.179312 -277.318216)
			(xy 133.226302 -277.470616) (xy 133.487922 -277.470616)
		)
		(stroke
			(width 0)
			(type solid)
		)
		(fill yes)
		(layer "In4.Cu")
		(net "M_G_CPU1_SA_DQ<0>")
	)
	(gr_poly
		(pts
			(xy 133.534912 -276.098762) (xy 133.487922 -275.946362) (xy 133.226302 -275.946362) (xy 133.179312 -276.098762)
			(xy 133.179312 -276.143212) (xy 133.534912 -276.143212)
		)
		(stroke
			(width 0)
			(type solid)
		)
		(fill yes)
		(layer "In4.Cu")
		(net "M_G_CPU1_SA_DQ<3>")
	)
	(gr_poly
		(pts
			(xy 133.534912 -272.843498) (xy 133.487922 -272.691098) (xy 133.226302 -272.691098) (xy 133.179312 -272.843498)
			(xy 133.179312 -272.887694) (xy 133.534912 -272.887694)
		)
		(stroke
			(width 0)
			(type solid)
		)
		(fill yes)
		(layer "In4.Cu")
		(net "M_G_CPU1_SA_DQ<7>")
	)
	(gr_poly
		(pts
			(xy 133.534912 -256.565654) (xy 133.487922 -256.413254) (xy 133.226302 -256.413254) (xy 133.179312 -256.565654)
			(xy 133.179312 -256.60985) (xy 133.534912 -256.60985)
		)
		(stroke
			(width 0)
			(type solid)
		)
		(fill yes)
		(layer "In4.Cu")
		(net "M_G_CPU1_SA_CS_N<3>")
	)
	(gr_poly
		(pts
			(xy 133.537452 -258.193286) (xy 133.490462 -258.040886) (xy 133.228842 -258.040886) (xy 133.181852 -258.193286)
			(xy 133.181852 -258.237482) (xy 133.537452 -258.237482)
		)
		(stroke
			(width 0)
			(type solid)
		)
		(fill yes)
		(layer "In4.Cu")
		(net "M_F_CPU1_SA_DQ<31>")
	)
	(gr_poly
		(pts
			(xy 133.537452 -257.784854) (xy 133.537452 -257.740658) (xy 133.181852 -257.740658) (xy 133.181852 -257.784854)
			(xy 133.228842 -257.937254) (xy 133.490462 -257.937254)
		)
		(stroke
			(width 0)
			(type solid)
		)
		(fill yes)
		(layer "In4.Cu")
		(net "M_G_CPU1_SA_CS_N<0>")
	)
	(gr_poly
		(pts
			(xy 133.543294 -275.690584) (xy 133.543294 -275.646134) (xy 133.187694 -275.646134) (xy 133.187694 -275.690584)
			(xy 133.234684 -275.842984) (xy 133.496304 -275.842984)
		)
		(stroke
			(width 0)
			(type solid)
		)
		(fill yes)
		(layer "In4.Cu")
		(net "M_G_CPU1_SA_DQS_DP<0>")
	)
	(gr_poly
		(pts
			(xy 133.543294 -269.588234) (xy 133.496304 -269.435834) (xy 133.234684 -269.435834) (xy 133.187694 -269.588234)
			(xy 133.187694 -269.632684) (xy 133.543294 -269.632684)
		)
		(stroke
			(width 0)
			(type solid)
		)
		(fill yes)
		(layer "In4.Cu")
		(net "M_F_CPU1_SA_DQS_DP<6>")
	)
	(gr_poly
		(pts
			(xy 133.543294 -265.923522) (xy 133.543294 -265.879326) (xy 133.187694 -265.879326) (xy 133.187694 -265.923522)
			(xy 133.234684 -266.075922) (xy 133.496304 -266.075922)
		)
		(stroke
			(width 0)
			(type solid)
		)
		(fill yes)
		(layer "In4.Cu")
		(net "M_G_CPU1_SA_DQS_DP<2>")
	)
	(gr_poly
		(pts
			(xy 133.543294 -261.040626) (xy 133.543294 -260.996176) (xy 133.187694 -260.996176) (xy 133.187694 -261.040626)
			(xy 133.234684 -261.193026) (xy 133.496304 -261.193026)
		)
		(stroke
			(width 0)
			(type solid)
		)
		(fill yes)
		(layer "In4.Cu")
		(net "M_F_CPU1_SA_DQS_DP<3>")
	)
	(gr_poly
		(pts
			(xy 133.543294 -256.157222) (xy 133.543294 -256.112772) (xy 133.187694 -256.112772) (xy 133.187694 -256.157222)
			(xy 133.234684 -256.309622) (xy 133.496304 -256.309622)
		)
		(stroke
			(width 0)
			(type solid)
		)
		(fill yes)
		(layer "In4.Cu")
		(net "M_G_CPU1_SA_CA<1>")
	)
	(gr_poly
		(pts
			(xy 133.543548 -264.70483) (xy 133.496558 -264.55243) (xy 133.234938 -264.55243) (xy 133.187948 -264.70483)
			(xy 133.187948 -264.74928) (xy 133.543548 -264.74928)
		)
		(stroke
			(width 0)
			(type solid)
		)
		(fill yes)
		(layer "In4.Cu")
		(net "M_G_CPU1_SA_DQS_DP<7>")
	)
	(gr_poly
		(pts
			(xy 133.543548 -259.821426) (xy 133.496558 -259.669026) (xy 133.234938 -259.669026) (xy 133.187948 -259.821426)
			(xy 133.187948 -259.865876) (xy 133.543548 -259.865876)
		)
		(stroke
			(width 0)
			(type solid)
		)
		(fill yes)
		(layer "In4.Cu")
		(net "M_F_CPU1_SA_DQS_DP<8>")
	)
	(gr_poly
		(pts
			(xy 133.543802 -274.471638) (xy 133.496812 -274.319238) (xy 133.235192 -274.319238) (xy 133.188202 -274.471638)
			(xy 133.188202 -274.515834) (xy 133.543802 -274.515834)
		)
		(stroke
			(width 0)
			(type solid)
		)
		(fill yes)
		(layer "In4.Cu")
		(net "M_G_CPU1_SA_DQS_DP<5>")
	)
	(gr_poly
		(pts
			(xy 133.54685 -274.062698) (xy 133.54685 -274.018248) (xy 133.19125 -274.018248) (xy 133.19125 -274.062698)
			(xy 133.23824 -274.215098) (xy 133.49986 -274.215098)
		)
		(stroke
			(width 0)
			(type solid)
		)
		(fill yes)
		(layer "In4.Cu")
		(net "M_G_CPU1_SA_DQ<4>")
	)
	(gr_poly
		(pts
			(xy 133.54685 -271.215866) (xy 133.49986 -271.063466) (xy 133.23824 -271.063466) (xy 133.19125 -271.215866)
			(xy 133.19125 -271.260062) (xy 133.54685 -271.260062)
		)
		(stroke
			(width 0)
			(type solid)
		)
		(fill yes)
		(layer "In4.Cu")
		(net "M_F_CPU1_SA_DQ<11>")
	)
	(gr_poly
		(pts
			(xy 133.54685 -270.806926) (xy 133.54685 -270.76273) (xy 133.19125 -270.76273) (xy 133.19125 -270.806926)
			(xy 133.23824 -270.959326) (xy 133.49986 -270.959326)
		)
		(stroke
			(width 0)
			(type solid)
		)
		(fill yes)
		(layer "In4.Cu")
		(net "M_F_CPU1_SA_DQS_DP<1>")
	)
	(gr_poly
		(pts
			(xy 133.54685 -269.179294) (xy 133.54685 -269.134844) (xy 133.19125 -269.134844) (xy 133.19125 -269.179294)
			(xy 133.23824 -269.331694) (xy 133.49986 -269.331694)
		)
		(stroke
			(width 0)
			(type solid)
		)
		(fill yes)
		(layer "In4.Cu")
		(net "M_F_CPU1_SA_DQ<12>")
	)
	(gr_poly
		(pts
			(xy 133.54685 -267.960094) (xy 133.49986 -267.807694) (xy 133.23824 -267.807694) (xy 133.19125 -267.960094)
			(xy 133.19125 -268.004544) (xy 133.54685 -268.004544)
		)
		(stroke
			(width 0)
			(type solid)
		)
		(fill yes)
		(layer "In4.Cu")
		(net "M_F_CPU1_SA_DQ<13>")
	)
	(gr_poly
		(pts
			(xy 133.54685 -266.332462) (xy 133.49986 -266.180062) (xy 133.23824 -266.180062) (xy 133.19125 -266.332462)
			(xy 133.19125 -266.376658) (xy 133.54685 -266.376658)
		)
		(stroke
			(width 0)
			(type solid)
		)
		(fill yes)
		(layer "In4.Cu")
		(net "M_G_CPU1_SA_DQ<19>")
	)
	(gr_poly
		(pts
			(xy 133.54685 -264.29589) (xy 133.54685 -264.25144) (xy 133.19125 -264.25144) (xy 133.19125 -264.29589)
			(xy 133.23824 -264.44829) (xy 133.49986 -264.44829)
		)
		(stroke
			(width 0)
			(type solid)
		)
		(fill yes)
		(layer "In4.Cu")
		(net "M_G_CPU1_SA_DQ<20>")
	)
	(gr_poly
		(pts
			(xy 133.54685 -263.077198) (xy 133.49986 -262.924798) (xy 133.23824 -262.924798) (xy 133.19125 -263.077198)
			(xy 133.19125 -263.121394) (xy 133.54685 -263.121394)
		)
		(stroke
			(width 0)
			(type solid)
		)
		(fill yes)
		(layer "In4.Cu")
		(net "M_G_CPU1_SA_DQ<23>")
	)
	(gr_poly
		(pts
			(xy 133.54685 -262.668258) (xy 133.54685 -262.623808) (xy 133.19125 -262.623808) (xy 133.19125 -262.668258)
			(xy 133.23824 -262.820658) (xy 133.49986 -262.820658)
		)
		(stroke
			(width 0)
			(type solid)
		)
		(fill yes)
		(layer "In4.Cu")
		(net "M_F_CPU1_SA_DQ<24>")
	)
	(gr_poly
		(pts
			(xy 133.547612 -272.434558) (xy 133.547612 -272.390362) (xy 133.192012 -272.390362) (xy 133.192012 -272.434558)
			(xy 133.239002 -272.586958) (xy 133.500622 -272.586958)
		)
		(stroke
			(width 0)
			(type solid)
		)
		(fill yes)
		(layer "In4.Cu")
		(net "M_F_CPU1_SA_DQ<8>")
	)
	(gr_poly
		(pts
			(xy 133.547612 -267.551154) (xy 133.547612 -267.506958) (xy 133.192012 -267.506958) (xy 133.192012 -267.551154)
			(xy 133.239002 -267.703554) (xy 133.500622 -267.703554)
		)
		(stroke
			(width 0)
			(type solid)
		)
		(fill yes)
		(layer "In4.Cu")
		(net "M_G_CPU1_SA_DQ<16>")
	)
	(gr_poly
		(pts
			(xy 133.547612 -261.449058) (xy 133.500622 -261.296658) (xy 133.239002 -261.296658) (xy 133.192012 -261.449058)
			(xy 133.192012 -261.493508) (xy 133.547612 -261.493508)
		)
		(stroke
			(width 0)
			(type solid)
		)
		(fill yes)
		(layer "In4.Cu")
		(net "M_F_CPU1_SA_DQ<27>")
	)
	(gr_poly
		(pts
			(xy 133.547612 -259.412486) (xy 133.547612 -259.368036) (xy 133.192012 -259.368036) (xy 133.192012 -259.412486)
			(xy 133.239002 -259.564886) (xy 133.500622 -259.564886)
		)
		(stroke
			(width 0)
			(type solid)
		)
		(fill yes)
		(layer "In4.Cu")
		(net "M_F_CPU1_SA_DQ<28>")
	)
	(gr_poly
		(pts
			(xy 133.54939 -254.938022) (xy 133.5024 -254.785622) (xy 133.24078 -254.785622) (xy 133.19379 -254.938022)
			(xy 133.19379 -254.982218) (xy 133.54939 -254.982218)
		)
		(stroke
			(width 0)
			(type solid)
		)
		(fill yes)
		(layer "In4.Cu")
		(net "M_G_CPU1_SA_CA<2>")
	)
	(gr_poly
		(pts
			(xy 133.759194 -224.85223) (xy 133.797548 -224.830132) (xy 133.619748 -224.522284) (xy 133.581394 -224.544382)
			(xy 133.472936 -224.661222) (xy 133.603746 -224.88779)
		)
		(stroke
			(width 0)
			(type solid)
		)
		(fill yes)
		(layer "In4.Cu")
		(net "M_F_CPU1_SB_DQS_DN<3>")
	)
	(gr_poly
		(pts
			(xy 133.797548 -227.20427) (xy 133.759194 -227.182172) (xy 133.603746 -227.146612) (xy 133.472936 -227.37318)
			(xy 133.581394 -227.49002) (xy 133.619748 -227.512118)
		)
		(stroke
			(width 0)
			(type solid)
		)
		(fill yes)
		(layer "In4.Cu")
		(net "M_F_CPU1_SB_DQS_DP<8>")
	)
	(gr_poly
		(pts
			(xy 133.797548 -223.948752) (xy 133.759194 -223.926654) (xy 133.603746 -223.891094) (xy 133.472936 -224.117662)
			(xy 133.581394 -224.234502) (xy 133.619748 -224.2566)
		)
		(stroke
			(width 0)
			(type solid)
		)
		(fill yes)
		(layer "In4.Cu")
		(net "M_F_CPU1_SB_DQS_DN<3>")
	)
	(gr_poly
		(pts
			(xy 133.79958 -225.572574) (xy 133.761226 -225.550476) (xy 133.605778 -225.514916) (xy 133.474968 -225.741484)
			(xy 133.583426 -225.858324) (xy 133.62178 -225.880422)
		)
		(stroke
			(width 0)
			(type solid)
		)
		(fill yes)
		(layer "In4.Cu")
		(net "M_F_CPU1_SB_DQS_DN<3>")
	)
	(gr_poly
		(pts
			(xy 133.895084 -247.382538) (xy 133.848094 -247.230138) (xy 133.586474 -247.230138) (xy 133.539484 -247.382538)
			(xy 133.539484 -247.426734) (xy 133.895084 -247.426734)
		)
		(stroke
			(width 0)
			(type solid)
		)
		(fill yes)
		(layer "In4.Cu")
		(net "M_G_CPU1_SB_PAR")
	)
	(gr_poly
		(pts
			(xy 133.89737 -246.974106) (xy 133.89737 -246.92991) (xy 133.54177 -246.92991) (xy 133.54177 -246.974106)
			(xy 133.58876 -247.126506) (xy 133.85038 -247.126506)
		)
		(stroke
			(width 0)
			(type solid)
		)
		(fill yes)
		(layer "In4.Cu")
		(net "M_G_CPU1_SB_CS_N<2>")
	)
	(gr_poly
		(pts
			(xy 133.89737 -237.61573) (xy 133.85038 -237.46333) (xy 133.58876 -237.46333) (xy 133.54177 -237.61573)
			(xy 133.54177 -237.66018) (xy 133.89737 -237.66018)
		)
		(stroke
			(width 0)
			(type solid)
		)
		(fill yes)
		(layer "In4.Cu")
		(net "M_F_CPU1_SB_DQS_DN<0>")
	)
	(gr_poly
		(pts
			(xy 133.89737 -237.207806) (xy 133.89737 -237.163356) (xy 133.54177 -237.163356) (xy 133.54177 -237.207806)
			(xy 133.58876 -237.360206) (xy 133.85038 -237.360206)
		)
		(stroke
			(width 0)
			(type solid)
		)
		(fill yes)
		(layer "In4.Cu")
		(net "M_F_CPU1_SB_DQS_DN<5>")
	)
	(gr_poly
		(pts
			(xy 133.89737 -232.732326) (xy 133.85038 -232.579926) (xy 133.58876 -232.579926) (xy 133.54177 -232.732326)
			(xy 133.54177 -232.776776) (xy 133.89737 -232.776776)
		)
		(stroke
			(width 0)
			(type solid)
		)
		(fill yes)
		(layer "In4.Cu")
		(net "M_G_CPU1_SB_DQS_DN<2>")
	)
	(gr_poly
		(pts
			(xy 133.89737 -232.324402) (xy 133.89737 -232.279952) (xy 133.54177 -232.279952) (xy 133.54177 -232.324402)
			(xy 133.58876 -232.476802) (xy 133.85038 -232.476802)
		)
		(stroke
			(width 0)
			(type solid)
		)
		(fill yes)
		(layer "In4.Cu")
		(net "M_G_CPU1_SB_DQS_DN<7>")
	)
	(gr_poly
		(pts
			(xy 133.900164 -244.127274) (xy 133.853174 -243.974874) (xy 133.591554 -243.974874) (xy 133.544564 -244.127274)
			(xy 133.544564 -244.17147) (xy 133.900164 -244.17147)
		)
		(stroke
			(width 0)
			(type solid)
		)
		(fill yes)
		(layer "In4.Cu")
		(net "M_G_CPU1_SB_CB<6>")
	)
	(gr_poly
		(pts
			(xy 133.900164 -238.83493) (xy 133.900164 -238.790734) (xy 133.544564 -238.790734) (xy 133.544564 -238.83493)
			(xy 133.591554 -238.98733) (xy 133.853174 -238.98733)
		)
		(stroke
			(width 0)
			(type solid)
		)
		(fill yes)
		(layer "In4.Cu")
		(net "M_F_CPU1_SB_DQ<1>")
	)
	(gr_poly
		(pts
			(xy 133.900164 -235.988606) (xy 133.853174 -235.836206) (xy 133.591554 -235.836206) (xy 133.544564 -235.988606)
			(xy 133.544564 -236.032802) (xy 133.900164 -236.032802)
		)
		(stroke
			(width 0)
			(type solid)
		)
		(fill yes)
		(layer "In4.Cu")
		(net "M_F_CPU1_SB_DQ<6>")
	)
	(gr_poly
		(pts
			(xy 133.900164 -233.951526) (xy 133.900164 -233.90733) (xy 133.544564 -233.90733) (xy 133.544564 -233.951526)
			(xy 133.591554 -234.103926) (xy 133.853174 -234.103926)
		)
		(stroke
			(width 0)
			(type solid)
		)
		(fill yes)
		(layer "In4.Cu")
		(net "M_G_CPU1_SB_DQ<17>")
	)
	(gr_poly
		(pts
			(xy 133.900164 -231.105202) (xy 133.853174 -230.952802) (xy 133.591554 -230.952802) (xy 133.544564 -231.105202)
			(xy 133.544564 -231.149398) (xy 133.900164 -231.149398)
		)
		(stroke
			(width 0)
			(type solid)
		)
		(fill yes)
		(layer "In4.Cu")
		(net "M_G_CPU1_SB_DQ<22>")
	)
	(gr_poly
		(pts
			(xy 133.90118 -243.718334) (xy 133.90118 -243.674138) (xy 133.54558 -243.674138) (xy 133.54558 -243.718334)
			(xy 133.59257 -243.870734) (xy 133.85419 -243.870734)
		)
		(stroke
			(width 0)
			(type solid)
		)
		(fill yes)
		(layer "In4.Cu")
		(net "M_G_CPU1_SB_CB<5>")
	)
	(gr_poly
		(pts
			(xy 133.90118 -240.871502) (xy 133.85419 -240.719102) (xy 133.59257 -240.719102) (xy 133.54558 -240.871502)
			(xy 133.54558 -240.915952) (xy 133.90118 -240.915952)
		)
		(stroke
			(width 0)
			(type solid)
		)
		(fill yes)
		(layer "In4.Cu")
		(net "M_G_CPU1_SB_CB<2>")
	)
	(gr_poly
		(pts
			(xy 133.90118 -240.46307) (xy 133.90118 -240.41862) (xy 133.54558 -240.41862) (xy 133.54558 -240.46307)
			(xy 133.59257 -240.61547) (xy 133.85419 -240.61547)
		)
		(stroke
			(width 0)
			(type solid)
		)
		(fill yes)
		(layer "In4.Cu")
		(net "M_G_CPU1_SB_CB<1>")
	)
	(gr_poly
		(pts
			(xy 133.90118 -239.24387) (xy 133.85419 -239.09147) (xy 133.59257 -239.09147) (xy 133.54558 -239.24387)
			(xy 133.54558 -239.288066) (xy 133.90118 -239.288066)
		)
		(stroke
			(width 0)
			(type solid)
		)
		(fill yes)
		(layer "In4.Cu")
		(net "M_F_CPU1_SB_DQ<2>")
	)
	(gr_poly
		(pts
			(xy 133.90118 -235.579666) (xy 133.90118 -235.535216) (xy 133.54558 -235.535216) (xy 133.54558 -235.579666)
			(xy 133.59257 -235.732066) (xy 133.85419 -235.732066)
		)
		(stroke
			(width 0)
			(type solid)
		)
		(fill yes)
		(layer "In4.Cu")
		(net "M_F_CPU1_SB_DQ<5>")
	)
	(gr_poly
		(pts
			(xy 133.90118 -230.696262) (xy 133.90118 -230.651812) (xy 133.54558 -230.651812) (xy 133.54558 -230.696262)
			(xy 133.59257 -230.848662) (xy 133.85419 -230.848662)
		)
		(stroke
			(width 0)
			(type solid)
		)
		(fill yes)
		(layer "In4.Cu")
		(net "M_G_CPU1_SB_DQ<21>")
	)
	(gr_poly
		(pts
			(xy 133.903466 -249.010678) (xy 133.856476 -248.858278) (xy 133.594856 -248.858278) (xy 133.547866 -249.010678)
			(xy 133.547866 -249.054874) (xy 133.903466 -249.054874)
		)
		(stroke
			(width 0)
			(type solid)
		)
		(fill yes)
		(layer "In4.Cu")
		(net "M_G_CPU1_SB_CA<3>")
	)
	(gr_poly
		(pts
			(xy 133.903466 -248.601738) (xy 133.903466 -248.557542) (xy 133.547866 -248.557542) (xy 133.547866 -248.601738)
			(xy 133.594856 -248.754138) (xy 133.856476 -248.754138)
		)
		(stroke
			(width 0)
			(type solid)
		)
		(fill yes)
		(layer "In4.Cu")
		(net "M_G_CPU1_SB_CA<4>")
	)
	(gr_poly
		(pts
			(xy 133.903466 -245.754906) (xy 133.856476 -245.602506) (xy 133.594856 -245.602506) (xy 133.547866 -245.754906)
			(xy 133.547866 -245.799356) (xy 133.903466 -245.799356)
		)
		(stroke
			(width 0)
			(type solid)
		)
		(fill yes)
		(layer "In4.Cu")
		(net "M_G_CPU1_SB_CS_N<1>")
	)
	(gr_poly
		(pts
			(xy 133.903466 -242.499642) (xy 133.856476 -242.347242) (xy 133.594856 -242.347242) (xy 133.547866 -242.499642)
			(xy 133.547866 -242.544092) (xy 133.903466 -242.544092)
		)
		(stroke
			(width 0)
			(type solid)
		)
		(fill yes)
		(layer "In4.Cu")
		(net "M_G_CPU1_SB_DQS_DN<9>")
	)
	(gr_poly
		(pts
			(xy 133.903466 -242.090702) (xy 133.903466 -242.046252) (xy 133.547866 -242.046252) (xy 133.547866 -242.090702)
			(xy 133.594856 -242.243102) (xy 133.856476 -242.243102)
		)
		(stroke
			(width 0)
			(type solid)
		)
		(fill yes)
		(layer "In4.Cu")
		(net "M_G_CPU1_SB_DQS_DN<4>")
	)
	(gr_poly
		(pts
			(xy 133.903466 -234.360466) (xy 133.856476 -234.208066) (xy 133.594856 -234.208066) (xy 133.547866 -234.360466)
			(xy 133.547866 -234.404916) (xy 133.903466 -234.404916)
		)
		(stroke
			(width 0)
			(type solid)
		)
		(fill yes)
		(layer "In4.Cu")
		(net "M_G_CPU1_SB_DQ<18>")
	)
	(gr_poly
		(pts
			(xy 133.903466 -229.06863) (xy 133.903466 -229.02418) (xy 133.547866 -229.02418) (xy 133.547866 -229.06863)
			(xy 133.594856 -229.22103) (xy 133.856476 -229.22103)
		)
		(stroke
			(width 0)
			(type solid)
		)
		(fill yes)
		(layer "In4.Cu")
		(net "M_F_CPU1_SB_DQ<27>")
	)
	(gr_poly
		(pts
			(xy 133.903466 -222.557086) (xy 133.903466 -222.51289) (xy 133.547866 -222.51289) (xy 133.547866 -222.557086)
			(xy 133.594856 -222.709486) (xy 133.856476 -222.709486)
		)
		(stroke
			(width 0)
			(type solid)
		)
		(fill yes)
		(layer "In4.Cu")
		(net "M_F_CPU1_SB_DQ<30>")
	)
	(gr_poly
		(pts
			(xy 133.903466 -219.710254) (xy 133.856476 -219.557854) (xy 133.594856 -219.557854) (xy 133.547866 -219.710254)
			(xy 133.547866 -219.754704) (xy 133.903466 -219.754704)
		)
		(stroke
			(width 0)
			(type solid)
		)
		(fill yes)
		(layer "In4.Cu")
		(net "M_F_CPU1_SB_DQ<31>")
	)
	(gr_poly
		(pts
			(xy 133.976364 -227.920804) (xy 133.867906 -227.803964) (xy 133.829552 -227.781866) (xy 133.651752 -228.089714)
			(xy 133.690106 -228.111812) (xy 133.845554 -228.147372)
		)
		(stroke
			(width 0)
			(type solid)
		)
		(fill yes)
		(layer "In4.Cu")
		(net "M_F_CPU1_SB_DQS_DN<8>")
	)
	(gr_poly
		(pts
			(xy 133.978396 -226.289108) (xy 133.869938 -226.172268) (xy 133.831584 -226.15017) (xy 133.653784 -226.458018)
			(xy 133.692138 -226.480116) (xy 133.847586 -226.515676)
		)
		(stroke
			(width 0)
			(type solid)
		)
		(fill yes)
		(layer "In4.Cu")
		(net "M_F_CPU1_SB_DQS_DP<3>")
	)
	(gr_poly
		(pts
			(xy 134.007352 -257.37947) (xy 133.960362 -257.22707) (xy 133.698742 -257.22707) (xy 133.651752 -257.37947)
			(xy 133.651752 -257.42392) (xy 134.007352 -257.42392)
		)
		(stroke
			(width 0)
			(type solid)
		)
		(fill yes)
		(layer "In4.Cu")
		(net "M_G_CPU1_SA_CS_N<1>")
	)
	(gr_poly
		(pts
			(xy 134.00913 -272.029682) (xy 133.96214 -271.877282) (xy 133.70052 -271.877282) (xy 133.65353 -272.029682)
			(xy 133.65353 -272.074132) (xy 134.00913 -272.074132)
		)
		(stroke
			(width 0)
			(type solid)
		)
		(fill yes)
		(layer "In4.Cu")
		(net "M_F_CPU1_SA_DQ<10>")
	)
	(gr_poly
		(pts
			(xy 134.00913 -267.146278) (xy 133.96214 -266.993878) (xy 133.70052 -266.993878) (xy 133.65353 -267.146278)
			(xy 133.65353 -267.190728) (xy 134.00913 -267.190728)
		)
		(stroke
			(width 0)
			(type solid)
		)
		(fill yes)
		(layer "In4.Cu")
		(net "M_G_CPU1_SA_DQ<18>")
	)
	(gr_poly
		(pts
			(xy 134.00913 -261.854442) (xy 134.00913 -261.809992) (xy 133.65353 -261.809992) (xy 133.65353 -261.854442)
			(xy 133.70052 -262.006842) (xy 133.96214 -262.006842)
		)
		(stroke
			(width 0)
			(type solid)
		)
		(fill yes)
		(layer "In4.Cu")
		(net "M_F_CPU1_SA_DQ<25>")
	)
	(gr_poly
		(pts
			(xy 134.00913 -259.00761) (xy 133.96214 -258.85521) (xy 133.70052 -258.85521) (xy 133.65353 -259.00761)
			(xy 133.65353 -259.051806) (xy 134.00913 -259.051806)
		)
		(stroke
			(width 0)
			(type solid)
		)
		(fill yes)
		(layer "In4.Cu")
		(net "M_F_CPU1_SA_DQ<30>")
	)
	(gr_poly
		(pts
			(xy 134.009892 -273.657314) (xy 133.962902 -273.504914) (xy 133.701282 -273.504914) (xy 133.654292 -273.657314)
			(xy 133.654292 -273.701764) (xy 134.009892 -273.701764)
		)
		(stroke
			(width 0)
			(type solid)
		)
		(fill yes)
		(layer "In4.Cu")
		(net "M_G_CPU1_SA_DQ<6>")
	)
	(gr_poly
		(pts
			(xy 134.009892 -271.620742) (xy 134.009892 -271.576546) (xy 133.654292 -271.576546) (xy 133.654292 -271.620742)
			(xy 133.701282 -271.773142) (xy 133.962902 -271.773142)
		)
		(stroke
			(width 0)
			(type solid)
		)
		(fill yes)
		(layer "In4.Cu")
		(net "M_F_CPU1_SA_DQ<9>")
	)
	(gr_poly
		(pts
			(xy 134.009892 -268.77391) (xy 133.962902 -268.62151) (xy 133.701282 -268.62151) (xy 133.654292 -268.77391)
			(xy 133.654292 -268.81836) (xy 134.009892 -268.81836)
		)
		(stroke
			(width 0)
			(type solid)
		)
		(fill yes)
		(layer "In4.Cu")
		(net "M_F_CPU1_SA_DQ<14>")
	)
	(gr_poly
		(pts
			(xy 134.009892 -268.365478) (xy 134.009892 -268.321028) (xy 133.654292 -268.321028) (xy 133.654292 -268.365478)
			(xy 133.701282 -268.517878) (xy 133.962902 -268.517878)
		)
		(stroke
			(width 0)
			(type solid)
		)
		(fill yes)
		(layer "In4.Cu")
		(net "M_F_CPU1_SA_DQ<15>")
	)
	(gr_poly
		(pts
			(xy 134.009892 -266.737338) (xy 134.009892 -266.693142) (xy 133.654292 -266.693142) (xy 133.654292 -266.737338)
			(xy 133.701282 -266.889738) (xy 133.962902 -266.889738)
		)
		(stroke
			(width 0)
			(type solid)
		)
		(fill yes)
		(layer "In4.Cu")
		(net "M_G_CPU1_SA_DQ<17>")
	)
	(gr_poly
		(pts
			(xy 134.009892 -263.891014) (xy 133.962902 -263.738614) (xy 133.701282 -263.738614) (xy 133.654292 -263.891014)
			(xy 133.654292 -263.93521) (xy 134.009892 -263.93521)
		)
		(stroke
			(width 0)
			(type solid)
		)
		(fill yes)
		(layer "In4.Cu")
		(net "M_G_CPU1_SA_DQ<22>")
	)
	(gr_poly
		(pts
			(xy 134.009892 -263.482074) (xy 134.009892 -263.437624) (xy 133.654292 -263.437624) (xy 133.654292 -263.482074)
			(xy 133.701282 -263.634474) (xy 133.962902 -263.634474)
		)
		(stroke
			(width 0)
			(type solid)
		)
		(fill yes)
		(layer "In4.Cu")
		(net "M_G_CPU1_SA_DQ<21>")
	)
	(gr_poly
		(pts
			(xy 134.009892 -262.262874) (xy 133.962902 -262.110474) (xy 133.701282 -262.110474) (xy 133.654292 -262.262874)
			(xy 133.654292 -262.307324) (xy 134.009892 -262.307324)
		)
		(stroke
			(width 0)
			(type solid)
		)
		(fill yes)
		(layer "In4.Cu")
		(net "M_F_CPU1_SA_DQ<26>")
	)
	(gr_poly
		(pts
			(xy 134.013448 -270.40205) (xy 133.966458 -270.24965) (xy 133.704838 -270.24965) (xy 133.657848 -270.40205)
			(xy 133.657848 -270.446246) (xy 134.013448 -270.446246)
		)
		(stroke
			(width 0)
			(type solid)
		)
		(fill yes)
		(layer "In4.Cu")
		(net "M_F_CPU1_SA_DQS_DN<1>")
	)
	(gr_poly
		(pts
			(xy 134.013448 -258.59867) (xy 134.013448 -258.554474) (xy 133.657848 -258.554474) (xy 133.657848 -258.59867)
			(xy 133.704838 -258.75107) (xy 133.966458 -258.75107)
		)
		(stroke
			(width 0)
			(type solid)
		)
		(fill yes)
		(layer "In4.Cu")
		(net "M_F_CPU1_SA_DQ<29>")
	)
	(gr_poly
		(pts
			(xy 134.01929 -275.284946) (xy 133.9723 -275.132546) (xy 133.71068 -275.132546) (xy 133.66369 -275.284946)
			(xy 133.66369 -275.329142) (xy 134.01929 -275.329142)
		)
		(stroke
			(width 0)
			(type solid)
		)
		(fill yes)
		(layer "In4.Cu")
		(net "M_G_CPU1_SA_DQS_DN<0>")
	)
	(gr_poly
		(pts
			(xy 134.01929 -274.876514) (xy 134.01929 -274.832318) (xy 133.66369 -274.832318) (xy 133.66369 -274.876514)
			(xy 133.71068 -275.028914) (xy 133.9723 -275.028914)
		)
		(stroke
			(width 0)
			(type solid)
		)
		(fill yes)
		(layer "In4.Cu")
		(net "M_G_CPU1_SA_DQS_DN<5>")
	)
	(gr_poly
		(pts
			(xy 134.01929 -269.993618) (xy 134.01929 -269.949168) (xy 133.66369 -269.949168) (xy 133.66369 -269.993618)
			(xy 133.71068 -270.146018) (xy 133.9723 -270.146018)
		)
		(stroke
			(width 0)
			(type solid)
		)
		(fill yes)
		(layer "In4.Cu")
		(net "M_F_CPU1_SA_DQS_DN<6>")
	)
	(gr_poly
		(pts
			(xy 134.01929 -265.518138) (xy 133.9723 -265.365738) (xy 133.71068 -265.365738) (xy 133.66369 -265.518138)
			(xy 133.66369 -265.562588) (xy 134.01929 -265.562588)
		)
		(stroke
			(width 0)
			(type solid)
		)
		(fill yes)
		(layer "In4.Cu")
		(net "M_G_CPU1_SA_DQS_DN<2>")
	)
	(gr_poly
		(pts
			(xy 134.01929 -265.110214) (xy 134.01929 -265.065764) (xy 133.66369 -265.065764) (xy 133.66369 -265.110214)
			(xy 133.71068 -265.262614) (xy 133.9723 -265.262614)
		)
		(stroke
			(width 0)
			(type solid)
		)
		(fill yes)
		(layer "In4.Cu")
		(net "M_G_CPU1_SA_DQS_DN<7>")
	)
	(gr_poly
		(pts
			(xy 134.01929 -260.634734) (xy 133.9723 -260.482334) (xy 133.71068 -260.482334) (xy 133.66369 -260.634734)
			(xy 133.66369 -260.679184) (xy 134.01929 -260.679184)
		)
		(stroke
			(width 0)
			(type solid)
		)
		(fill yes)
		(layer "In4.Cu")
		(net "M_F_CPU1_SA_DQS_DN<3>")
	)
	(gr_poly
		(pts
			(xy 134.01929 -260.22681) (xy 134.01929 -260.18236) (xy 133.66369 -260.18236) (xy 133.66369 -260.22681)
			(xy 133.71068 -260.37921) (xy 133.9723 -260.37921)
		)
		(stroke
			(width 0)
			(type solid)
		)
		(fill yes)
		(layer "In4.Cu")
		(net "M_F_CPU1_SA_DQS_DN<8>")
	)
	(gr_poly
		(pts
			(xy 134.01929 -256.971038) (xy 134.01929 -256.926588) (xy 133.66369 -256.926588) (xy 133.66369 -256.971038)
			(xy 133.71068 -257.123438) (xy 133.9723 -257.123438)
		)
		(stroke
			(width 0)
			(type solid)
		)
		(fill yes)
		(layer "In4.Cu")
		(net "M_G_CPU1_SA_CS_N<2>")
	)
	(gr_poly
		(pts
			(xy 134.01929 -255.751838) (xy 133.9723 -255.599438) (xy 133.71068 -255.599438) (xy 133.66369 -255.751838)
			(xy 133.66369 -255.796034) (xy 134.01929 -255.796034)
		)
		(stroke
			(width 0)
			(type solid)
		)
		(fill yes)
		(layer "In4.Cu")
		(net "M_G_CPU1_SA_CA<0>")
	)
	(gr_poly
		(pts
			(xy 134.01929 -255.343406) (xy 134.01929 -255.29921) (xy 133.66369 -255.29921) (xy 133.66369 -255.343406)
			(xy 133.71068 -255.495806) (xy 133.9723 -255.495806)
		)
		(stroke
			(width 0)
			(type solid)
		)
		(fill yes)
		(layer "In4.Cu")
		(net "M_G_CPU1_SA_CA<3>")
	)
	(gr_poly
		(pts
			(xy 134.02183 -276.912578) (xy 133.97484 -276.760178) (xy 133.71322 -276.760178) (xy 133.66623 -276.912578)
			(xy 133.66623 -276.957028) (xy 134.02183 -276.957028)
		)
		(stroke
			(width 0)
			(type solid)
		)
		(fill yes)
		(layer "In4.Cu")
		(net "M_G_CPU1_SA_DQ<2>")
	)
	(gr_poly
		(pts
			(xy 134.02183 -276.5044) (xy 134.02183 -276.460204) (xy 133.66623 -276.460204) (xy 133.66623 -276.5044)
			(xy 133.71322 -276.6568) (xy 133.97484 -276.6568)
		)
		(stroke
			(width 0)
			(type solid)
		)
		(fill yes)
		(layer "In4.Cu")
		(net "M_G_CPU1_SA_DQ<1>")
	)
	(gr_poly
		(pts
			(xy 134.02183 -273.248882) (xy 134.02183 -273.204686) (xy 133.66623 -273.204686) (xy 133.66623 -273.248882)
			(xy 133.71322 -273.401282) (xy 133.97484 -273.401282)
		)
		(stroke
			(width 0)
			(type solid)
		)
		(fill yes)
		(layer "In4.Cu")
		(net "M_G_CPU1_SA_DQ<5>")
	)
	(gr_poly
		(pts
			(xy 134.262876 -226.397566) (xy 134.224522 -226.375468) (xy 134.069074 -226.339908) (xy 133.938264 -226.566476)
			(xy 134.046722 -226.683316) (xy 134.085076 -226.705414)
		)
		(stroke
			(width 0)
			(type solid)
		)
		(fill yes)
		(layer "In4.Cu")
		(net "M_F_CPU1_SB_DQS_DP<8>")
	)
	(gr_poly
		(pts
			(xy 134.262876 -221.514162) (xy 134.224522 -221.492064) (xy 134.069074 -221.456504) (xy 133.938264 -221.683072)
			(xy 134.046722 -221.799912) (xy 134.085076 -221.82201)
		)
		(stroke
			(width 0)
			(type solid)
		)
		(fill yes)
		(layer "In4.Cu")
		(net "M_F_CPU1_SB_DQ<28>")
	)
	(gr_poly
		(pts
			(xy 134.26821 -228.016308) (xy 134.229856 -227.99421) (xy 134.074408 -227.95865) (xy 133.943598 -228.185218)
			(xy 134.052056 -228.302058) (xy 134.09041 -228.324156)
		)
		(stroke
			(width 0)
			(type solid)
		)
		(fill yes)
		(layer "In4.Cu")
		(net "M_F_CPU1_SB_DQ<25>")
	)
	(gr_poly
		(pts
			(xy 134.26948 -223.130872) (xy 134.231126 -223.108774) (xy 134.075678 -223.073214) (xy 133.944868 -223.299782)
			(xy 134.053326 -223.416622) (xy 134.09168 -223.43872)
		)
		(stroke
			(width 0)
			(type solid)
		)
		(fill yes)
		(layer "In4.Cu")
		(net "M_F_CPU1_SB_DQS_DN<3>")
	)
	(gr_poly
		(pts
			(xy 134.339838 -225.048318) (xy 134.448296 -224.931478) (xy 134.317486 -224.70491) (xy 134.162038 -224.74047)
			(xy 134.123684 -224.762568) (xy 134.301484 -225.070416)
		)
		(stroke
			(width 0)
			(type solid)
		)
		(fill yes)
		(layer "In4.Cu")
		(net "M_F_CPU1_SB_DQS_DP<3>")
	)
	(gr_poly
		(pts
			(xy 134.340854 -277.989284) (xy 134.379208 -277.967186) (xy 134.201408 -277.659338) (xy 134.163054 -277.681436)
			(xy 134.054596 -277.798276) (xy 134.185406 -278.024844)
		)
		(stroke
			(width 0)
			(type solid)
		)
		(fill yes)
		(layer "In4.Cu")
		(net "M_G_CPU1_SA_DQ<0>")
	)
	(gr_poly
		(pts
			(xy 134.36727 -242.904518) (xy 134.36727 -242.860322) (xy 134.01167 -242.860322) (xy 134.01167 -242.904518)
			(xy 134.05866 -243.056918) (xy 134.32028 -243.056918)
		)
		(stroke
			(width 0)
			(type solid)
		)
		(fill yes)
		(layer "In4.Cu")
		(net "M_G_CPU1_SB_DQS_DP<9>")
	)
	(gr_poly
		(pts
			(xy 134.36727 -220.115638) (xy 134.36727 -220.071188) (xy 134.01167 -220.071188) (xy 134.01167 -220.115638)
			(xy 134.05866 -220.268038) (xy 134.32028 -220.268038)
		)
		(stroke
			(width 0)
			(type solid)
		)
		(fill yes)
		(layer "In4.Cu")
		(net "M_F_CPU1_SB_DQ<29>")
	)
	(gr_poly
		(pts
			(xy 134.373112 -244.53215) (xy 134.373112 -244.487954) (xy 134.017512 -244.487954) (xy 134.017512 -244.53215)
			(xy 134.064502 -244.68455) (xy 134.326122 -244.68455)
		)
		(stroke
			(width 0)
			(type solid)
		)
		(fill yes)
		(layer "In4.Cu")
		(net "M_G_CPU1_SB_CB<4>")
	)
	(gr_poly
		(pts
			(xy 134.373112 -243.313458) (xy 134.326122 -243.161058) (xy 134.064502 -243.161058) (xy 134.017512 -243.313458)
			(xy 134.017512 -243.357654) (xy 134.373112 -243.357654)
		)
		(stroke
			(width 0)
			(type solid)
		)
		(fill yes)
		(layer "In4.Cu")
		(net "M_G_CPU1_SB_CB<7>")
	)
	(gr_poly
		(pts
			(xy 134.373112 -241.276886) (xy 134.373112 -241.232436) (xy 134.017512 -241.232436) (xy 134.017512 -241.276886)
			(xy 134.064502 -241.429286) (xy 134.326122 -241.429286)
		)
		(stroke
			(width 0)
			(type solid)
		)
		(fill yes)
		(layer "In4.Cu")
		(net "M_G_CPU1_SB_CB<0>")
	)
	(gr_poly
		(pts
			(xy 134.373112 -240.057686) (xy 134.326122 -239.905286) (xy 134.064502 -239.905286) (xy 134.017512 -240.057686)
			(xy 134.017512 -240.102136) (xy 134.373112 -240.102136)
		)
		(stroke
			(width 0)
			(type solid)
		)
		(fill yes)
		(layer "In4.Cu")
		(net "M_G_CPU1_SB_CB<3>")
	)
	(gr_poly
		(pts
			(xy 134.373112 -239.648746) (xy 134.373112 -239.60455) (xy 134.017512 -239.60455) (xy 134.017512 -239.648746)
			(xy 134.064502 -239.801146) (xy 134.326122 -239.801146)
		)
		(stroke
			(width 0)
			(type solid)
		)
		(fill yes)
		(layer "In4.Cu")
		(net "M_F_CPU1_SB_DQ<0>")
	)
	(gr_poly
		(pts
			(xy 134.373112 -238.430054) (xy 134.326122 -238.277654) (xy 134.064502 -238.277654) (xy 134.017512 -238.430054)
			(xy 134.017512 -238.47425) (xy 134.373112 -238.47425)
		)
		(stroke
			(width 0)
			(type solid)
		)
		(fill yes)
		(layer "In4.Cu")
		(net "M_F_CPU1_SB_DQ<3>")
	)
	(gr_poly
		(pts
			(xy 134.373112 -236.393482) (xy 134.373112 -236.349032) (xy 134.017512 -236.349032) (xy 134.017512 -236.393482)
			(xy 134.064502 -236.545882) (xy 134.326122 -236.545882)
		)
		(stroke
			(width 0)
			(type solid)
		)
		(fill yes)
		(layer "In4.Cu")
		(net "M_F_CPU1_SB_DQ<4>")
	)
	(gr_poly
		(pts
			(xy 134.373112 -235.174282) (xy 134.326122 -235.021882) (xy 134.064502 -235.021882) (xy 134.017512 -235.174282)
			(xy 134.017512 -235.218732) (xy 134.373112 -235.218732)
		)
		(stroke
			(width 0)
			(type solid)
		)
		(fill yes)
		(layer "In4.Cu")
		(net "M_F_CPU1_SB_DQ<7>")
	)
	(gr_poly
		(pts
			(xy 134.373112 -233.54665) (xy 134.326122 -233.39425) (xy 134.064502 -233.39425) (xy 134.017512 -233.54665)
			(xy 134.017512 -233.5911) (xy 134.373112 -233.5911)
		)
		(stroke
			(width 0)
			(type solid)
		)
		(fill yes)
		(layer "In4.Cu")
		(net "M_G_CPU1_SB_DQ<19>")
	)
	(gr_poly
		(pts
			(xy 134.373112 -231.510078) (xy 134.373112 -231.465628) (xy 134.017512 -231.465628) (xy 134.017512 -231.510078)
			(xy 134.064502 -231.662478) (xy 134.326122 -231.662478)
		)
		(stroke
			(width 0)
			(type solid)
		)
		(fill yes)
		(layer "In4.Cu")
		(net "M_G_CPU1_SB_DQ<20>")
	)
	(gr_poly
		(pts
			(xy 134.373112 -230.290878) (xy 134.326122 -230.138478) (xy 134.064502 -230.138478) (xy 134.017512 -230.290878)
			(xy 134.017512 -230.335328) (xy 134.373112 -230.335328)
		)
		(stroke
			(width 0)
			(type solid)
		)
		(fill yes)
		(layer "In4.Cu")
		(net "M_G_CPU1_SB_DQ<23>")
	)
	(gr_poly
		(pts
			(xy 134.373112 -229.882446) (xy 134.373112 -229.837996) (xy 134.017512 -229.837996) (xy 134.017512 -229.882446)
			(xy 134.064502 -230.034846) (xy 134.326122 -230.034846)
		)
		(stroke
			(width 0)
			(type solid)
		)
		(fill yes)
		(layer "In4.Cu")
		(net "M_F_CPU1_SB_DQ<26>")
	)
	(gr_poly
		(pts
			(xy 134.373366 -249.415554) (xy 134.373366 -249.371358) (xy 134.017766 -249.371358) (xy 134.017766 -249.415554)
			(xy 134.064756 -249.567954) (xy 134.326376 -249.567954)
		)
		(stroke
			(width 0)
			(type solid)
		)
		(fill yes)
		(layer "In4.Cu")
		(net "M_G_CPU1_SB_CA<2>")
	)
	(gr_poly
		(pts
			(xy 134.373366 -248.196354) (xy 134.326376 -248.043954) (xy 134.064756 -248.043954) (xy 134.017766 -248.196354)
			(xy 134.017766 -248.240804) (xy 134.373366 -248.240804)
		)
		(stroke
			(width 0)
			(type solid)
		)
		(fill yes)
		(layer "In4.Cu")
		(net "M_G_CPU1_SB_CA<5>")
	)
	(gr_poly
		(pts
			(xy 134.373366 -246.568722) (xy 134.326376 -246.416322) (xy 134.064756 -246.416322) (xy 134.017766 -246.568722)
			(xy 134.017766 -246.613172) (xy 134.373366 -246.613172)
		)
		(stroke
			(width 0)
			(type solid)
		)
		(fill yes)
		(layer "In4.Cu")
		(net "M_G_CPU1_SB_CS_N<0>")
	)
	(gr_poly
		(pts
			(xy 134.373366 -246.16029) (xy 134.373366 -246.11584) (xy 134.017766 -246.11584) (xy 134.017766 -246.16029)
			(xy 134.064756 -246.31269) (xy 134.326376 -246.31269)
		)
		(stroke
			(width 0)
			(type solid)
		)
		(fill yes)
		(layer "In4.Cu")
		(net "M_G_CPU1_SB_CS_N<3>")
	)
	(gr_poly
		(pts
			(xy 134.373366 -238.021114) (xy 134.373366 -237.976918) (xy 134.017766 -237.976918) (xy 134.017766 -238.021114)
			(xy 134.064756 -238.173514) (xy 134.326376 -238.173514)
		)
		(stroke
			(width 0)
			(type solid)
		)
		(fill yes)
		(layer "In4.Cu")
		(net "M_F_CPU1_SB_DQS_DP<0>")
	)
	(gr_poly
		(pts
			(xy 134.373366 -236.801914) (xy 134.326376 -236.649514) (xy 134.064756 -236.649514) (xy 134.017766 -236.801914)
			(xy 134.017766 -236.846364) (xy 134.373366 -236.846364)
		)
		(stroke
			(width 0)
			(type solid)
		)
		(fill yes)
		(layer "In4.Cu")
		(net "M_F_CPU1_SB_DQS_DP<5>")
	)
	(gr_poly
		(pts
			(xy 134.373366 -234.76585) (xy 134.373366 -234.7214) (xy 134.017766 -234.7214) (xy 134.017766 -234.76585)
			(xy 134.064756 -234.91825) (xy 134.326376 -234.91825)
		)
		(stroke
			(width 0)
			(type solid)
		)
		(fill yes)
		(layer "In4.Cu")
		(net "M_G_CPU1_SB_DQ<16>")
	)
	(gr_poly
		(pts
			(xy 134.373366 -233.13771) (xy 134.373366 -233.093514) (xy 134.017766 -233.093514) (xy 134.017766 -233.13771)
			(xy 134.064756 -233.29011) (xy 134.326376 -233.29011)
		)
		(stroke
			(width 0)
			(type solid)
		)
		(fill yes)
		(layer "In4.Cu")
		(net "M_G_CPU1_SB_DQS_DP<2>")
	)
	(gr_poly
		(pts
			(xy 134.373366 -231.919018) (xy 134.326376 -231.766618) (xy 134.064756 -231.766618) (xy 134.017766 -231.919018)
			(xy 134.017766 -231.963214) (xy 134.373366 -231.963214)
		)
		(stroke
			(width 0)
			(type solid)
		)
		(fill yes)
		(layer "In4.Cu")
		(net "M_G_CPU1_SB_DQS_DP<7>")
	)
	(gr_poly
		(pts
			(xy 134.373874 -241.685826) (xy 134.326884 -241.533426) (xy 134.065264 -241.533426) (xy 134.018274 -241.685826)
			(xy 134.018274 -241.730022) (xy 134.373874 -241.730022)
		)
		(stroke
			(width 0)
			(type solid)
		)
		(fill yes)
		(layer "In4.Cu")
		(net "M_G_CPU1_SB_DQS_DP<4>")
	)
	(gr_poly
		(pts
			(xy 134.382002 -247.787922) (xy 134.382002 -247.743726) (xy 134.026402 -247.743726) (xy 134.026402 -247.787922)
			(xy 134.073392 -247.940322) (xy 134.335012 -247.940322)
		)
		(stroke
			(width 0)
			(type solid)
		)
		(fill yes)
		(layer "In4.Cu")
		(net "M_G_CPU1_SB_CA<6>")
	)
	(gr_poly
		(pts
			(xy 134.446264 -225.479102) (xy 134.337806 -225.362262) (xy 134.299452 -225.340164) (xy 134.121652 -225.648012)
			(xy 134.160006 -225.67011) (xy 134.315454 -225.70567)
		)
		(stroke
			(width 0)
			(type solid)
		)
		(fill yes)
		(layer "In4.Cu")
		(net "M_F_CPU1_SB_DQS_DP<3>")
	)
	(gr_poly
		(pts
			(xy 134.448296 -228.73081) (xy 134.339838 -228.61397) (xy 134.301484 -228.591872) (xy 134.123684 -228.89972)
			(xy 134.162038 -228.921818) (xy 134.317486 -228.957378)
		)
		(stroke
			(width 0)
			(type solid)
		)
		(fill yes)
		(layer "In4.Cu")
		(net "M_F_CPU1_SB_DQ<27>")
	)
	(gr_poly
		(pts
			(xy 134.448296 -227.102924) (xy 134.339838 -226.986084) (xy 134.301484 -226.963986) (xy 134.123684 -227.271834)
			(xy 134.162038 -227.293932) (xy 134.317486 -227.329492)
		)
		(stroke
			(width 0)
			(type solid)
		)
		(fill yes)
		(layer "In4.Cu")
		(net "M_F_CPU1_SB_DQS_DN<8>")
	)
	(gr_poly
		(pts
			(xy 134.448296 -223.847406) (xy 134.339838 -223.730566) (xy 134.301484 -223.708468) (xy 134.123684 -224.016316)
			(xy 134.162038 -224.038414) (xy 134.317486 -224.073974)
		)
		(stroke
			(width 0)
			(type solid)
		)
		(fill yes)
		(layer "In4.Cu")
		(net "M_F_CPU1_SB_DQS_DP<3>")
	)
	(gr_poly
		(pts
			(xy 134.448296 -222.21952) (xy 134.339838 -222.10268) (xy 134.301484 -222.080582) (xy 134.123684 -222.38843)
			(xy 134.162038 -222.410528) (xy 134.317486 -222.446088)
		)
		(stroke
			(width 0)
			(type solid)
		)
		(fill yes)
		(layer "In4.Cu")
		(net "M_F_CPU1_SB_DQ<30>")
	)
	(gr_poly
		(pts
			(xy 134.44855 -277.364952) (xy 134.557008 -277.248112) (xy 134.426198 -277.021544) (xy 134.27075 -277.057104)
			(xy 134.232396 -277.079202) (xy 134.410196 -277.38705)
		)
		(stroke
			(width 0)
			(type solid)
		)
		(fill yes)
		(layer "In4.Cu")
		(net "M_G_CPU1_SA_DQ<2>")
	)
	(gr_poly
		(pts
			(xy 134.474712 -276.098762) (xy 134.427722 -275.946362) (xy 134.166102 -275.946362) (xy 134.119112 -276.098762)
			(xy 134.119112 -276.143212) (xy 134.474712 -276.143212)
		)
		(stroke
			(width 0)
			(type solid)
		)
		(fill yes)
		(layer "In4.Cu")
		(net "M_G_CPU1_SA_DQ<3>")
	)
	(gr_poly
		(pts
			(xy 134.474712 -275.690584) (xy 134.474712 -275.646388) (xy 134.119112 -275.646388) (xy 134.119112 -275.690584)
			(xy 134.166102 -275.842984) (xy 134.427722 -275.842984)
		)
		(stroke
			(width 0)
			(type solid)
		)
		(fill yes)
		(layer "In4.Cu")
		(net "M_G_CPU1_SA_DQS_DP<0>")
	)
	(gr_poly
		(pts
			(xy 134.474712 -274.47113) (xy 134.427722 -274.31873) (xy 134.166102 -274.31873) (xy 134.119112 -274.47113)
			(xy 134.119112 -274.515326) (xy 134.474712 -274.515326)
		)
		(stroke
			(width 0)
			(type solid)
		)
		(fill yes)
		(layer "In4.Cu")
		(net "M_G_CPU1_SA_DQS_DP<5>")
	)
	(gr_poly
		(pts
			(xy 134.474712 -272.843498) (xy 134.427722 -272.691098) (xy 134.166102 -272.691098) (xy 134.119112 -272.843498)
			(xy 134.119112 -272.887694) (xy 134.474712 -272.887694)
		)
		(stroke
			(width 0)
			(type solid)
		)
		(fill yes)
		(layer "In4.Cu")
		(net "M_G_CPU1_SA_DQ<7>")
	)
	(gr_poly
		(pts
			(xy 134.474712 -270.807434) (xy 134.474712 -270.762984) (xy 134.119112 -270.762984) (xy 134.119112 -270.807434)
			(xy 134.166102 -270.959834) (xy 134.427722 -270.959834)
		)
		(stroke
			(width 0)
			(type solid)
		)
		(fill yes)
		(layer "In4.Cu")
		(net "M_F_CPU1_SA_DQS_DP<1>")
	)
	(gr_poly
		(pts
			(xy 134.474712 -265.92403) (xy 134.474712 -265.87958) (xy 134.119112 -265.87958) (xy 134.119112 -265.92403)
			(xy 134.166102 -266.07643) (xy 134.427722 -266.07643)
		)
		(stroke
			(width 0)
			(type solid)
		)
		(fill yes)
		(layer "In4.Cu")
		(net "M_G_CPU1_SA_DQS_DP<2>")
	)
	(gr_poly
		(pts
			(xy 134.474712 -261.040626) (xy 134.474712 -260.99643) (xy 134.119112 -260.99643) (xy 134.119112 -261.040626)
			(xy 134.166102 -261.193026) (xy 134.427722 -261.193026)
		)
		(stroke
			(width 0)
			(type solid)
		)
		(fill yes)
		(layer "In4.Cu")
		(net "M_F_CPU1_SA_DQS_DP<3>")
	)
	(gr_poly
		(pts
			(xy 134.474712 -259.820918) (xy 134.427722 -259.668518) (xy 134.166102 -259.668518) (xy 134.119112 -259.820918)
			(xy 134.119112 -259.865368) (xy 134.474712 -259.865368)
		)
		(stroke
			(width 0)
			(type solid)
		)
		(fill yes)
		(layer "In4.Cu")
		(net "M_F_CPU1_SA_DQS_DP<8>")
	)
	(gr_poly
		(pts
			(xy 134.474712 -256.157222) (xy 134.474712 -256.113026) (xy 134.119112 -256.113026) (xy 134.119112 -256.157222)
			(xy 134.166102 -256.309622) (xy 134.427722 -256.309622)
		)
		(stroke
			(width 0)
			(type solid)
		)
		(fill yes)
		(layer "In4.Cu")
		(net "M_G_CPU1_SA_CA<1>")
	)
	(gr_poly
		(pts
			(xy 134.474712 -254.937514) (xy 134.427722 -254.785114) (xy 134.166102 -254.785114) (xy 134.119112 -254.937514)
			(xy 134.119112 -254.981964) (xy 134.474712 -254.981964)
		)
		(stroke
			(width 0)
			(type solid)
		)
		(fill yes)
		(layer "In4.Cu")
		(net "M_G_CPU1_SA_CA<2>")
	)
	(gr_poly
		(pts
			(xy 134.477252 -258.193286) (xy 134.430262 -258.040886) (xy 134.168642 -258.040886) (xy 134.121652 -258.193286)
			(xy 134.121652 -258.237736) (xy 134.477252 -258.237736)
		)
		(stroke
			(width 0)
			(type solid)
		)
		(fill yes)
		(layer "In4.Cu")
		(net "M_F_CPU1_SA_DQ<31>")
	)
	(gr_poly
		(pts
			(xy 134.483094 -256.565654) (xy 134.436104 -256.413254) (xy 134.174484 -256.413254) (xy 134.127494 -256.565654)
			(xy 134.127494 -256.610104) (xy 134.483094 -256.610104)
		)
		(stroke
			(width 0)
			(type solid)
		)
		(fill yes)
		(layer "In4.Cu")
		(net "M_G_CPU1_SA_CS_N<3>")
	)
	(gr_poly
		(pts
			(xy 134.48665 -274.062698) (xy 134.48665 -274.018248) (xy 134.13105 -274.018248) (xy 134.13105 -274.062698)
			(xy 134.17804 -274.215098) (xy 134.43966 -274.215098)
		)
		(stroke
			(width 0)
			(type solid)
		)
		(fill yes)
		(layer "In4.Cu")
		(net "M_G_CPU1_SA_DQ<4>")
	)
	(gr_poly
		(pts
			(xy 134.48665 -271.215866) (xy 134.43966 -271.063466) (xy 134.17804 -271.063466) (xy 134.13105 -271.215866)
			(xy 134.13105 -271.260062) (xy 134.48665 -271.260062)
		)
		(stroke
			(width 0)
			(type solid)
		)
		(fill yes)
		(layer "In4.Cu")
		(net "M_F_CPU1_SA_DQ<11>")
	)
	(gr_poly
		(pts
			(xy 134.48665 -269.179294) (xy 134.48665 -269.134844) (xy 134.13105 -269.134844) (xy 134.13105 -269.179294)
			(xy 134.17804 -269.331694) (xy 134.43966 -269.331694)
		)
		(stroke
			(width 0)
			(type solid)
		)
		(fill yes)
		(layer "In4.Cu")
		(net "M_F_CPU1_SA_DQ<12>")
	)
	(gr_poly
		(pts
			(xy 134.48665 -267.960094) (xy 134.43966 -267.807694) (xy 134.17804 -267.807694) (xy 134.13105 -267.960094)
			(xy 134.13105 -268.004544) (xy 134.48665 -268.004544)
		)
		(stroke
			(width 0)
			(type solid)
		)
		(fill yes)
		(layer "In4.Cu")
		(net "M_F_CPU1_SA_DQ<13>")
	)
	(gr_poly
		(pts
			(xy 134.48665 -266.332462) (xy 134.43966 -266.180062) (xy 134.17804 -266.180062) (xy 134.13105 -266.332462)
			(xy 134.13105 -266.376658) (xy 134.48665 -266.376658)
		)
		(stroke
			(width 0)
			(type solid)
		)
		(fill yes)
		(layer "In4.Cu")
		(net "M_G_CPU1_SA_DQ<19>")
	)
	(gr_poly
		(pts
			(xy 134.48665 -264.29589) (xy 134.48665 -264.25144) (xy 134.13105 -264.25144) (xy 134.13105 -264.29589)
			(xy 134.17804 -264.44829) (xy 134.43966 -264.44829)
		)
		(stroke
			(width 0)
			(type solid)
		)
		(fill yes)
		(layer "In4.Cu")
		(net "M_G_CPU1_SA_DQ<20>")
	)
	(gr_poly
		(pts
			(xy 134.48665 -263.077198) (xy 134.43966 -262.924798) (xy 134.17804 -262.924798) (xy 134.13105 -263.077198)
			(xy 134.13105 -263.121394) (xy 134.48665 -263.121394)
		)
		(stroke
			(width 0)
			(type solid)
		)
		(fill yes)
		(layer "In4.Cu")
		(net "M_G_CPU1_SA_DQ<23>")
	)
	(gr_poly
		(pts
			(xy 134.48665 -262.668258) (xy 134.48665 -262.623808) (xy 134.13105 -262.623808) (xy 134.13105 -262.668258)
			(xy 134.17804 -262.820658) (xy 134.43966 -262.820658)
		)
		(stroke
			(width 0)
			(type solid)
		)
		(fill yes)
		(layer "In4.Cu")
		(net "M_F_CPU1_SA_DQ<24>")
	)
	(gr_poly
		(pts
			(xy 134.487412 -272.434558) (xy 134.487412 -272.390362) (xy 134.131812 -272.390362) (xy 134.131812 -272.434558)
			(xy 134.178802 -272.586958) (xy 134.440422 -272.586958)
		)
		(stroke
			(width 0)
			(type solid)
		)
		(fill yes)
		(layer "In4.Cu")
		(net "M_F_CPU1_SA_DQ<8>")
	)
	(gr_poly
		(pts
			(xy 134.487412 -269.588234) (xy 134.440422 -269.435834) (xy 134.178802 -269.435834) (xy 134.131812 -269.588234)
			(xy 134.131812 -269.63243) (xy 134.487412 -269.63243)
		)
		(stroke
			(width 0)
			(type solid)
		)
		(fill yes)
		(layer "In4.Cu")
		(net "M_F_CPU1_SA_DQS_DP<6>")
	)
	(gr_poly
		(pts
			(xy 134.487412 -267.551154) (xy 134.487412 -267.506958) (xy 134.131812 -267.506958) (xy 134.131812 -267.551154)
			(xy 134.178802 -267.703554) (xy 134.440422 -267.703554)
		)
		(stroke
			(width 0)
			(type solid)
		)
		(fill yes)
		(layer "In4.Cu")
		(net "M_G_CPU1_SA_DQ<16>")
	)
	(gr_poly
		(pts
			(xy 134.487412 -264.70483) (xy 134.440422 -264.55243) (xy 134.178802 -264.55243) (xy 134.131812 -264.70483)
			(xy 134.131812 -264.749026) (xy 134.487412 -264.749026)
		)
		(stroke
			(width 0)
			(type solid)
		)
		(fill yes)
		(layer "In4.Cu")
		(net "M_G_CPU1_SA_DQS_DP<7>")
	)
	(gr_poly
		(pts
			(xy 134.487412 -261.449058) (xy 134.440422 -261.296658) (xy 134.178802 -261.296658) (xy 134.131812 -261.449058)
			(xy 134.131812 -261.493508) (xy 134.487412 -261.493508)
		)
		(stroke
			(width 0)
			(type solid)
		)
		(fill yes)
		(layer "In4.Cu")
		(net "M_F_CPU1_SA_DQ<27>")
	)
	(gr_poly
		(pts
			(xy 134.487412 -259.412486) (xy 134.487412 -259.368036) (xy 134.131812 -259.368036) (xy 134.131812 -259.412486)
			(xy 134.178802 -259.564886) (xy 134.440422 -259.564886)
		)
		(stroke
			(width 0)
			(type solid)
		)
		(fill yes)
		(layer "In4.Cu")
		(net "M_F_CPU1_SA_DQ<28>")
	)
	(gr_poly
		(pts
			(xy 134.48919 -257.784854) (xy 134.48919 -257.740404) (xy 134.13359 -257.740404) (xy 134.13359 -257.784854)
			(xy 134.18058 -257.937254) (xy 134.4422 -257.937254)
		)
		(stroke
			(width 0)
			(type solid)
		)
		(fill yes)
		(layer "In4.Cu")
		(net "M_G_CPU1_SA_CS_N<0>")
	)
	(gr_poly
		(pts
			(xy 134.737348 -219.065348) (xy 134.698994 -219.04325) (xy 134.543546 -219.00769) (xy 134.412736 -219.234258)
			(xy 134.521194 -219.351098) (xy 134.559548 -219.373196)
		)
		(stroke
			(width 0)
			(type solid)
		)
		(fill yes)
		(layer "In4.Cu")
		(net "M_F_CPU1_SB_DQ<31>")
	)
	(gr_poly
		(pts
			(xy 134.738364 -228.829616) (xy 134.70001 -228.807518) (xy 134.544562 -228.771958) (xy 134.413752 -228.998526)
			(xy 134.52221 -229.115366) (xy 134.560564 -229.137464)
		)
		(stroke
			(width 0)
			(type solid)
		)
		(fill yes)
		(layer "In4.Cu")
		(net "M_F_CPU1_SB_DQ<24>")
	)
	(gr_poly
		(pts
			(xy 134.738364 -227.20173) (xy 134.70001 -227.179632) (xy 134.544562 -227.144072) (xy 134.413752 -227.37064)
			(xy 134.52221 -227.48748) (xy 134.560564 -227.509578)
		)
		(stroke
			(width 0)
			(type solid)
		)
		(fill yes)
		(layer "In4.Cu")
		(net "M_F_CPU1_SB_DQ<25>")
	)
	(gr_poly
		(pts
			(xy 134.738364 -222.318326) (xy 134.70001 -222.296228) (xy 134.544562 -222.260668) (xy 134.413752 -222.487236)
			(xy 134.52221 -222.604076) (xy 134.560564 -222.626174)
		)
		(stroke
			(width 0)
			(type solid)
		)
		(fill yes)
		(layer "In4.Cu")
		(net "M_F_CPU1_SB_DQS_DN<3>")
	)
	(gr_poly
		(pts
			(xy 134.73938 -225.572574) (xy 134.701026 -225.550476) (xy 134.545578 -225.514916) (xy 134.414768 -225.741484)
			(xy 134.523226 -225.858324) (xy 134.56158 -225.880422)
		)
		(stroke
			(width 0)
			(type solid)
		)
		(fill yes)
		(layer "In4.Cu")
		(net "M_F_CPU1_SB_DQS_DP<8>")
	)
	(gr_poly
		(pts
			(xy 134.740142 -220.68917) (xy 134.701788 -220.667072) (xy 134.54634 -220.631512) (xy 134.41553 -220.85808)
			(xy 134.523988 -220.97492) (xy 134.562342 -220.997018)
		)
		(stroke
			(width 0)
			(type solid)
		)
		(fill yes)
		(layer "In4.Cu")
		(net "M_F_CPU1_SB_DQ<28>")
	)
	(gr_poly
		(pts
			(xy 134.808722 -278.79929) (xy 134.847076 -278.777192) (xy 134.669276 -278.469344) (xy 134.630922 -278.491442)
			(xy 134.522464 -278.608282) (xy 134.653274 -278.83485)
		)
		(stroke
			(width 0)
			(type solid)
		)
		(fill yes)
		(layer "In4.Cu")
		(net "M_G_CPU1_SA_DQ<0>")
	)
	(gr_poly
		(pts
			(xy 134.809992 -277.173944) (xy 134.848346 -277.151846) (xy 134.670546 -276.843998) (xy 134.632192 -276.866096)
			(xy 134.523734 -276.982936) (xy 134.654544 -277.209504)
		)
		(stroke
			(width 0)
			(type solid)
		)
		(fill yes)
		(layer "In4.Cu")
		(net "M_G_CPU1_SA_DQ<1>")
	)
	(gr_poly
		(pts
			(xy 134.834884 -247.382538) (xy 134.787894 -247.230138) (xy 134.526274 -247.230138) (xy 134.479284 -247.382538)
			(xy 134.479284 -247.426734) (xy 134.834884 -247.426734)
		)
		(stroke
			(width 0)
			(type solid)
		)
		(fill yes)
		(layer "In4.Cu")
		(net "M_G_CPU1_SB_PAR")
	)
	(gr_poly
		(pts
			(xy 134.83717 -246.974106) (xy 134.83717 -246.929656) (xy 134.48157 -246.929656) (xy 134.48157 -246.974106)
			(xy 134.52856 -247.126506) (xy 134.79018 -247.126506)
		)
		(stroke
			(width 0)
			(type solid)
		)
		(fill yes)
		(layer "In4.Cu")
		(net "M_G_CPU1_SB_CS_N<2>")
	)
	(gr_poly
		(pts
			(xy 134.83717 -245.754906) (xy 134.79018 -245.602506) (xy 134.52856 -245.602506) (xy 134.48157 -245.754906)
			(xy 134.48157 -245.799356) (xy 134.83717 -245.799356)
		)
		(stroke
			(width 0)
			(type solid)
		)
		(fill yes)
		(layer "In4.Cu")
		(net "M_G_CPU1_SB_CS_N<1>")
	)
	(gr_poly
		(pts
			(xy 134.837424 -248.602246) (xy 134.837424 -248.557796) (xy 134.481824 -248.557796) (xy 134.481824 -248.602246)
			(xy 134.528814 -248.754646) (xy 134.790434 -248.754646)
		)
		(stroke
			(width 0)
			(type solid)
		)
		(fill yes)
		(layer "In4.Cu")
		(net "M_G_CPU1_SB_CA<4>")
	)
	(gr_poly
		(pts
			(xy 134.840472 -244.127274) (xy 134.793482 -243.974874) (xy 134.531862 -243.974874) (xy 134.484872 -244.127274)
			(xy 134.484872 -244.171724) (xy 134.840472 -244.171724)
		)
		(stroke
			(width 0)
			(type solid)
		)
		(fill yes)
		(layer "In4.Cu")
		(net "M_G_CPU1_SB_CB<6>")
	)
	(gr_poly
		(pts
			(xy 134.840472 -243.718334) (xy 134.840472 -243.674138) (xy 134.484872 -243.674138) (xy 134.484872 -243.718334)
			(xy 134.531862 -243.870734) (xy 134.793482 -243.870734)
		)
		(stroke
			(width 0)
			(type solid)
		)
		(fill yes)
		(layer "In4.Cu")
		(net "M_G_CPU1_SB_CB<5>")
	)
	(gr_poly
		(pts
			(xy 134.840472 -240.871502) (xy 134.793482 -240.719102) (xy 134.531862 -240.719102) (xy 134.484872 -240.871502)
			(xy 134.484872 -240.915952) (xy 134.840472 -240.915952)
		)
		(stroke
			(width 0)
			(type solid)
		)
		(fill yes)
		(layer "In4.Cu")
		(net "M_G_CPU1_SB_CB<2>")
	)
	(gr_poly
		(pts
			(xy 134.840472 -240.46307) (xy 134.840472 -240.41862) (xy 134.484872 -240.41862) (xy 134.484872 -240.46307)
			(xy 134.531862 -240.61547) (xy 134.793482 -240.61547)
		)
		(stroke
			(width 0)
			(type solid)
		)
		(fill yes)
		(layer "In4.Cu")
		(net "M_G_CPU1_SB_CB<1>")
	)
	(gr_poly
		(pts
			(xy 134.840472 -239.24387) (xy 134.793482 -239.09147) (xy 134.531862 -239.09147) (xy 134.484872 -239.24387)
			(xy 134.484872 -239.28832) (xy 134.840472 -239.28832)
		)
		(stroke
			(width 0)
			(type solid)
		)
		(fill yes)
		(layer "In4.Cu")
		(net "M_F_CPU1_SB_DQ<2>")
	)
	(gr_poly
		(pts
			(xy 134.840472 -238.83493) (xy 134.840472 -238.790734) (xy 134.484872 -238.790734) (xy 134.484872 -238.83493)
			(xy 134.531862 -238.98733) (xy 134.793482 -238.98733)
		)
		(stroke
			(width 0)
			(type solid)
		)
		(fill yes)
		(layer "In4.Cu")
		(net "M_F_CPU1_SB_DQ<1>")
	)
	(gr_poly
		(pts
			(xy 134.840472 -235.988606) (xy 134.793482 -235.836206) (xy 134.531862 -235.836206) (xy 134.484872 -235.988606)
			(xy 134.484872 -236.032802) (xy 134.840472 -236.032802)
		)
		(stroke
			(width 0)
			(type solid)
		)
		(fill yes)
		(layer "In4.Cu")
		(net "M_F_CPU1_SB_DQ<6>")
	)
	(gr_poly
		(pts
			(xy 134.840472 -235.579666) (xy 134.840472 -235.535216) (xy 134.484872 -235.535216) (xy 134.484872 -235.579666)
			(xy 134.531862 -235.732066) (xy 134.793482 -235.732066)
		)
		(stroke
			(width 0)
			(type solid)
		)
		(fill yes)
		(layer "In4.Cu")
		(net "M_F_CPU1_SB_DQ<5>")
	)
	(gr_poly
		(pts
			(xy 134.840472 -233.951526) (xy 134.840472 -233.90733) (xy 134.484872 -233.90733) (xy 134.484872 -233.951526)
			(xy 134.531862 -234.103926) (xy 134.793482 -234.103926)
		)
		(stroke
			(width 0)
			(type solid)
		)
		(fill yes)
		(layer "In4.Cu")
		(net "M_G_CPU1_SB_DQ<17>")
	)
	(gr_poly
		(pts
			(xy 134.840472 -231.105202) (xy 134.793482 -230.952802) (xy 134.531862 -230.952802) (xy 134.484872 -231.105202)
			(xy 134.484872 -231.149398) (xy 134.840472 -231.149398)
		)
		(stroke
			(width 0)
			(type solid)
		)
		(fill yes)
		(layer "In4.Cu")
		(net "M_G_CPU1_SB_DQ<22>")
	)
	(gr_poly
		(pts
			(xy 134.840472 -230.696262) (xy 134.840472 -230.651812) (xy 134.484872 -230.651812) (xy 134.484872 -230.696262)
			(xy 134.531862 -230.848662) (xy 134.793482 -230.848662)
		)
		(stroke
			(width 0)
			(type solid)
		)
		(fill yes)
		(layer "In4.Cu")
		(net "M_G_CPU1_SB_DQ<21>")
	)
	(gr_poly
		(pts
			(xy 134.842758 -242.499642) (xy 134.795768 -242.347242) (xy 134.534148 -242.347242) (xy 134.487158 -242.499642)
			(xy 134.487158 -242.544092) (xy 134.842758 -242.544092)
		)
		(stroke
			(width 0)
			(type solid)
		)
		(fill yes)
		(layer "In4.Cu")
		(net "M_G_CPU1_SB_DQS_DN<9>")
	)
	(gr_poly
		(pts
			(xy 134.843266 -249.010678) (xy 134.796276 -248.858278) (xy 134.534656 -248.858278) (xy 134.487666 -249.010678)
			(xy 134.487666 -249.054874) (xy 134.843266 -249.054874)
		)
		(stroke
			(width 0)
			(type solid)
		)
		(fill yes)
		(layer "In4.Cu")
		(net "M_G_CPU1_SB_CA<3>")
	)
	(gr_poly
		(pts
			(xy 134.843266 -237.616238) (xy 134.796276 -237.463838) (xy 134.534656 -237.463838) (xy 134.487666 -237.616238)
			(xy 134.487666 -237.660434) (xy 134.843266 -237.660434)
		)
		(stroke
			(width 0)
			(type solid)
		)
		(fill yes)
		(layer "In4.Cu")
		(net "M_F_CPU1_SB_DQS_DN<0>")
	)
	(gr_poly
		(pts
			(xy 134.843266 -237.207298) (xy 134.843266 -237.163102) (xy 134.487666 -237.163102) (xy 134.487666 -237.207298)
			(xy 134.534656 -237.359698) (xy 134.796276 -237.359698)
		)
		(stroke
			(width 0)
			(type solid)
		)
		(fill yes)
		(layer "In4.Cu")
		(net "M_F_CPU1_SB_DQS_DN<5>")
	)
	(gr_poly
		(pts
			(xy 134.843266 -234.360466) (xy 134.796276 -234.208066) (xy 134.534656 -234.208066) (xy 134.487666 -234.360466)
			(xy 134.487666 -234.404916) (xy 134.843266 -234.404916)
		)
		(stroke
			(width 0)
			(type solid)
		)
		(fill yes)
		(layer "In4.Cu")
		(net "M_G_CPU1_SB_DQ<18>")
	)
	(gr_poly
		(pts
			(xy 134.843266 -232.732834) (xy 134.796276 -232.580434) (xy 134.534656 -232.580434) (xy 134.487666 -232.732834)
			(xy 134.487666 -232.77703) (xy 134.843266 -232.77703)
		)
		(stroke
			(width 0)
			(type solid)
		)
		(fill yes)
		(layer "In4.Cu")
		(net "M_G_CPU1_SB_DQS_DN<2>")
	)
	(gr_poly
		(pts
			(xy 134.843266 -232.323894) (xy 134.843266 -232.279698) (xy 134.487666 -232.279698) (xy 134.487666 -232.323894)
			(xy 134.534656 -232.476294) (xy 134.796276 -232.476294)
		)
		(stroke
			(width 0)
			(type solid)
		)
		(fill yes)
		(layer "In4.Cu")
		(net "M_G_CPU1_SB_DQS_DN<7>")
	)
	(gr_poly
		(pts
			(xy 134.851648 -242.090702) (xy 134.851648 -242.046506) (xy 134.496048 -242.046506) (xy 134.496048 -242.090702)
			(xy 134.543038 -242.243102) (xy 134.804658 -242.243102)
		)
		(stroke
			(width 0)
			(type solid)
		)
		(fill yes)
		(layer "In4.Cu")
		(net "M_G_CPU1_SB_DQS_DN<4>")
	)
	(gr_poly
		(pts
			(xy 134.916164 -223.0374) (xy 134.807706 -222.92056) (xy 134.769352 -222.898462) (xy 134.591552 -223.20631)
			(xy 134.629906 -223.228408) (xy 134.785354 -223.263968)
		)
		(stroke
			(width 0)
			(type solid)
		)
		(fill yes)
		(layer "In4.Cu")
		(net "M_F_CPU1_SB_DQS_DP<3>")
	)
	(gr_poly
		(pts
			(xy 134.91718 -227.918772) (xy 134.808722 -227.801932) (xy 134.770368 -227.779834) (xy 134.592568 -228.087682)
			(xy 134.630922 -228.10978) (xy 134.78637 -228.14534)
		)
		(stroke
			(width 0)
			(type solid)
		)
		(fill yes)
		(layer "In4.Cu")
		(net "M_F_CPU1_SB_DQ<27>")
	)
	(gr_poly
		(pts
			(xy 134.917434 -278.177498) (xy 135.025892 -278.060658) (xy 134.895082 -277.83409) (xy 134.739634 -277.86965)
			(xy 134.70128 -277.891748) (xy 134.87908 -278.199596)
		)
		(stroke
			(width 0)
			(type solid)
		)
		(fill yes)
		(layer "In4.Cu")
		(net "M_G_CPU1_SA_DQ<2>")
	)
	(gr_poly
		(pts
			(xy 134.918196 -229.544626) (xy 134.809738 -229.427786) (xy 134.771384 -229.405688) (xy 134.593584 -229.713536)
			(xy 134.631938 -229.735634) (xy 134.787386 -229.771194)
		)
		(stroke
			(width 0)
			(type solid)
		)
		(fill yes)
		(layer "In4.Cu")
		(net "M_F_CPU1_SB_DQ<26>")
	)
	(gr_poly
		(pts
			(xy 134.922514 -226.281996) (xy 134.814056 -226.165156) (xy 134.775702 -226.143058) (xy 134.597902 -226.450906)
			(xy 134.636256 -226.473004) (xy 134.791704 -226.508564)
		)
		(stroke
			(width 0)
			(type solid)
		)
		(fill yes)
		(layer "In4.Cu")
		(net "M_F_CPU1_SB_DQS_DN<8>")
	)
	(gr_poly
		(pts
			(xy 134.922514 -221.398592) (xy 134.814056 -221.281752) (xy 134.775702 -221.259654) (xy 134.597902 -221.567502)
			(xy 134.636256 -221.5896) (xy 134.791704 -221.62516)
		)
		(stroke
			(width 0)
			(type solid)
		)
		(fill yes)
		(layer "In4.Cu")
		(net "M_F_CPU1_SB_DQ<30>")
	)
	(gr_poly
		(pts
			(xy 134.922514 -219.770706) (xy 134.814056 -219.653866) (xy 134.775702 -219.631768) (xy 134.597902 -219.939616)
			(xy 134.636256 -219.961714) (xy 134.791704 -219.997274)
		)
		(stroke
			(width 0)
			(type solid)
		)
		(fill yes)
		(layer "In4.Cu")
		(net "M_F_CPU1_SB_DQ<29>")
	)
	(gr_poly
		(pts
			(xy 134.924038 -276.560788) (xy 135.032496 -276.443948) (xy 134.901686 -276.21738) (xy 134.746238 -276.25294)
			(xy 134.707884 -276.275038) (xy 134.885684 -276.582886)
		)
		(stroke
			(width 0)
			(type solid)
		)
		(fill yes)
		(layer "In4.Cu")
		(net "M_G_CPU1_SA_DQ<3>")
	)
	(gr_poly
		(pts
			(xy 134.94893 -272.029682) (xy 134.90194 -271.877282) (xy 134.64032 -271.877282) (xy 134.59333 -272.029682)
			(xy 134.59333 -272.074132) (xy 134.94893 -272.074132)
		)
		(stroke
			(width 0)
			(type solid)
		)
		(fill yes)
		(layer "In4.Cu")
		(net "M_F_CPU1_SA_DQ<10>")
	)
	(gr_poly
		(pts
			(xy 134.94893 -269.99311) (xy 134.94893 -269.94866) (xy 134.59333 -269.94866) (xy 134.59333 -269.99311)
			(xy 134.64032 -270.14551) (xy 134.90194 -270.14551)
		)
		(stroke
			(width 0)
			(type solid)
		)
		(fill yes)
		(layer "In4.Cu")
		(net "M_F_CPU1_SA_DQS_DN<6>")
	)
	(gr_poly
		(pts
			(xy 134.94893 -267.146278) (xy 134.90194 -266.993878) (xy 134.64032 -266.993878) (xy 134.59333 -267.146278)
			(xy 134.59333 -267.190728) (xy 134.94893 -267.190728)
		)
		(stroke
			(width 0)
			(type solid)
		)
		(fill yes)
		(layer "In4.Cu")
		(net "M_G_CPU1_SA_DQ<18>")
	)
	(gr_poly
		(pts
			(xy 134.94893 -261.854442) (xy 134.94893 -261.809992) (xy 134.59333 -261.809992) (xy 134.59333 -261.854442)
			(xy 134.64032 -262.006842) (xy 134.90194 -262.006842)
		)
		(stroke
			(width 0)
			(type solid)
		)
		(fill yes)
		(layer "In4.Cu")
		(net "M_F_CPU1_SA_DQ<25>")
	)
	(gr_poly
		(pts
			(xy 134.94893 -259.00761) (xy 134.90194 -258.85521) (xy 134.64032 -258.85521) (xy 134.59333 -259.00761)
			(xy 134.59333 -259.051806) (xy 134.94893 -259.051806)
		)
		(stroke
			(width 0)
			(type solid)
		)
		(fill yes)
		(layer "In4.Cu")
		(net "M_F_CPU1_SA_DQ<30>")
	)
	(gr_poly
		(pts
			(xy 134.949692 -273.657314) (xy 134.902702 -273.504914) (xy 134.641082 -273.504914) (xy 134.594092 -273.657314)
			(xy 134.594092 -273.701764) (xy 134.949692 -273.701764)
		)
		(stroke
			(width 0)
			(type solid)
		)
		(fill yes)
		(layer "In4.Cu")
		(net "M_G_CPU1_SA_DQ<6>")
	)
	(gr_poly
		(pts
			(xy 134.949692 -271.620742) (xy 134.949692 -271.576546) (xy 134.594092 -271.576546) (xy 134.594092 -271.620742)
			(xy 134.641082 -271.773142) (xy 134.902702 -271.773142)
		)
		(stroke
			(width 0)
			(type solid)
		)
		(fill yes)
		(layer "In4.Cu")
		(net "M_F_CPU1_SA_DQ<9>")
	)
	(gr_poly
		(pts
			(xy 134.949692 -268.77391) (xy 134.902702 -268.62151) (xy 134.641082 -268.62151) (xy 134.594092 -268.77391)
			(xy 134.594092 -268.81836) (xy 134.949692 -268.81836)
		)
		(stroke
			(width 0)
			(type solid)
		)
		(fill yes)
		(layer "In4.Cu")
		(net "M_F_CPU1_SA_DQ<14>")
	)
	(gr_poly
		(pts
			(xy 134.949692 -268.365478) (xy 134.949692 -268.321028) (xy 134.594092 -268.321028) (xy 134.594092 -268.365478)
			(xy 134.641082 -268.517878) (xy 134.902702 -268.517878)
		)
		(stroke
			(width 0)
			(type solid)
		)
		(fill yes)
		(layer "In4.Cu")
		(net "M_F_CPU1_SA_DQ<15>")
	)
	(gr_poly
		(pts
			(xy 134.949692 -266.737338) (xy 134.949692 -266.693142) (xy 134.594092 -266.693142) (xy 134.594092 -266.737338)
			(xy 134.641082 -266.889738) (xy 134.902702 -266.889738)
		)
		(stroke
			(width 0)
			(type solid)
		)
		(fill yes)
		(layer "In4.Cu")
		(net "M_G_CPU1_SA_DQ<17>")
	)
	(gr_poly
		(pts
			(xy 134.949692 -263.482074) (xy 134.949692 -263.437624) (xy 134.594092 -263.437624) (xy 134.594092 -263.482074)
			(xy 134.641082 -263.634474) (xy 134.902702 -263.634474)
		)
		(stroke
			(width 0)
			(type solid)
		)
		(fill yes)
		(layer "In4.Cu")
		(net "M_G_CPU1_SA_DQ<21>")
	)
	(gr_poly
		(pts
			(xy 134.949692 -262.262874) (xy 134.902702 -262.110474) (xy 134.641082 -262.110474) (xy 134.594092 -262.262874)
			(xy 134.594092 -262.307324) (xy 134.949692 -262.307324)
		)
		(stroke
			(width 0)
			(type solid)
		)
		(fill yes)
		(layer "In4.Cu")
		(net "M_F_CPU1_SA_DQ<26>")
	)
	(gr_poly
		(pts
			(xy 134.95274 -270.40205) (xy 134.90575 -270.24965) (xy 134.64413 -270.24965) (xy 134.59714 -270.40205)
			(xy 134.59714 -270.446246) (xy 134.95274 -270.446246)
		)
		(stroke
			(width 0)
			(type solid)
		)
		(fill yes)
		(layer "In4.Cu")
		(net "M_F_CPU1_SA_DQS_DN<1>")
	)
	(gr_poly
		(pts
			(xy 134.952994 -257.37947) (xy 134.906004 -257.22707) (xy 134.644384 -257.22707) (xy 134.597394 -257.37947)
			(xy 134.597394 -257.42392) (xy 134.952994 -257.42392)
		)
		(stroke
			(width 0)
			(type solid)
		)
		(fill yes)
		(layer "In4.Cu")
		(net "M_G_CPU1_SA_CS_N<1>")
	)
	(gr_poly
		(pts
			(xy 134.952994 -256.971038) (xy 134.952994 -256.926588) (xy 134.597394 -256.926588) (xy 134.597394 -256.971038)
			(xy 134.644384 -257.123438) (xy 134.906004 -257.123438)
		)
		(stroke
			(width 0)
			(type solid)
		)
		(fill yes)
		(layer "In4.Cu")
		(net "M_G_CPU1_SA_CS_N<2>")
	)
	(gr_poly
		(pts
			(xy 134.95655 -275.284946) (xy 134.90956 -275.132546) (xy 134.64794 -275.132546) (xy 134.60095 -275.284946)
			(xy 134.60095 -275.329396) (xy 134.95655 -275.329396)
		)
		(stroke
			(width 0)
			(type solid)
		)
		(fill yes)
		(layer "In4.Cu")
		(net "M_G_CPU1_SA_DQS_DN<0>")
	)
	(gr_poly
		(pts
			(xy 134.95909 -263.891014) (xy 134.9121 -263.738614) (xy 134.65048 -263.738614) (xy 134.60349 -263.891014)
			(xy 134.60349 -263.93521) (xy 134.95909 -263.93521)
		)
		(stroke
			(width 0)
			(type solid)
		)
		(fill yes)
		(layer "In4.Cu")
		(net "M_G_CPU1_SA_DQ<22>")
	)
	(gr_poly
		(pts
			(xy 134.95909 -260.635242) (xy 134.9121 -260.482842) (xy 134.65048 -260.482842) (xy 134.60349 -260.635242)
			(xy 134.60349 -260.679438) (xy 134.95909 -260.679438)
		)
		(stroke
			(width 0)
			(type solid)
		)
		(fill yes)
		(layer "In4.Cu")
		(net "M_F_CPU1_SA_DQS_DN<3>")
	)
	(gr_poly
		(pts
			(xy 134.95909 -260.226302) (xy 134.95909 -260.182106) (xy 134.60349 -260.182106) (xy 134.60349 -260.226302)
			(xy 134.65048 -260.378702) (xy 134.9121 -260.378702)
		)
		(stroke
			(width 0)
			(type solid)
		)
		(fill yes)
		(layer "In4.Cu")
		(net "M_F_CPU1_SA_DQS_DN<8>")
	)
	(gr_poly
		(pts
			(xy 134.95909 -258.59867) (xy 134.95909 -258.554474) (xy 134.60349 -258.554474) (xy 134.60349 -258.59867)
			(xy 134.65048 -258.75107) (xy 134.9121 -258.75107)
		)
		(stroke
			(width 0)
			(type solid)
		)
		(fill yes)
		(layer "In4.Cu")
		(net "M_F_CPU1_SA_DQ<29>")
	)
	(gr_poly
		(pts
			(xy 134.95909 -255.751838) (xy 134.9121 -255.599438) (xy 134.65048 -255.599438) (xy 134.60349 -255.751838)
			(xy 134.60349 -255.796288) (xy 134.95909 -255.796288)
		)
		(stroke
			(width 0)
			(type solid)
		)
		(fill yes)
		(layer "In4.Cu")
		(net "M_G_CPU1_SA_CA<0>")
	)
	(gr_poly
		(pts
			(xy 134.95909 -255.343406) (xy 134.95909 -255.298956) (xy 134.60349 -255.298956) (xy 134.60349 -255.343406)
			(xy 134.65048 -255.495806) (xy 134.9121 -255.495806)
		)
		(stroke
			(width 0)
			(type solid)
		)
		(fill yes)
		(layer "In4.Cu")
		(net "M_G_CPU1_SA_CA<3>")
	)
	(gr_poly
		(pts
			(xy 134.96163 -273.248882) (xy 134.96163 -273.204686) (xy 134.60603 -273.204686) (xy 134.60603 -273.248882)
			(xy 134.65302 -273.401282) (xy 134.91464 -273.401282)
		)
		(stroke
			(width 0)
			(type solid)
		)
		(fill yes)
		(layer "In4.Cu")
		(net "M_G_CPU1_SA_DQ<5>")
	)
	(gr_poly
		(pts
			(xy 134.96163 -265.518138) (xy 134.91464 -265.365738) (xy 134.65302 -265.365738) (xy 134.60603 -265.518138)
			(xy 134.60603 -265.562588) (xy 134.96163 -265.562588)
		)
		(stroke
			(width 0)
			(type solid)
		)
		(fill yes)
		(layer "In4.Cu")
		(net "M_G_CPU1_SA_DQS_DN<2>")
	)
	(gr_poly
		(pts
			(xy 134.96163 -265.110214) (xy 134.96163 -265.065764) (xy 134.60603 -265.065764) (xy 134.60603 -265.110214)
			(xy 134.65302 -265.262614) (xy 134.91464 -265.262614)
		)
		(stroke
			(width 0)
			(type solid)
		)
		(fill yes)
		(layer "In4.Cu")
		(net "M_G_CPU1_SA_DQS_DN<7>")
	)
	(gr_poly
		(pts
			(xy 134.962646 -274.876514) (xy 134.962646 -274.832318) (xy 134.607046 -274.832318) (xy 134.607046 -274.876514)
			(xy 134.654036 -275.028914) (xy 134.915656 -275.028914)
		)
		(stroke
			(width 0)
			(type solid)
		)
		(fill yes)
		(layer "In4.Cu")
		(net "M_G_CPU1_SA_DQS_DN<5>")
	)
	(gr_poly
		(pts
			(xy 135.200898 -226.400614) (xy 135.162544 -226.378516) (xy 135.007096 -226.342956) (xy 134.876286 -226.569524)
			(xy 134.984744 -226.686364) (xy 135.023098 -226.708462)
		)
		(stroke
			(width 0)
			(type solid)
		)
		(fill yes)
		(layer "In4.Cu")
		(net "M_F_CPU1_SB_DQ<25>")
	)
	(gr_poly
		(pts
			(xy 135.200898 -221.51721) (xy 135.162544 -221.495112) (xy 135.007096 -221.459552) (xy 134.876286 -221.68612)
			(xy 134.984744 -221.80296) (xy 135.023098 -221.825058)
		)
		(stroke
			(width 0)
			(type solid)
		)
		(fill yes)
		(layer "In4.Cu")
		(net "M_F_CPU1_SB_DQS_DN<3>")
	)
	(gr_poly
		(pts
			(xy 135.200898 -219.889324) (xy 135.162544 -219.867226) (xy 135.007096 -219.831666) (xy 134.876286 -220.058234)
			(xy 134.984744 -220.175074) (xy 135.023098 -220.197172)
		)
		(stroke
			(width 0)
			(type solid)
		)
		(fill yes)
		(layer "In4.Cu")
		(net "M_F_CPU1_SB_DQ<28>")
	)
	(gr_poly
		(pts
			(xy 135.206486 -228.019102) (xy 135.168132 -227.997004) (xy 135.012684 -227.961444) (xy 134.881874 -228.188012)
			(xy 134.990332 -228.304852) (xy 135.028686 -228.32695)
		)
		(stroke
			(width 0)
			(type solid)
		)
		(fill yes)
		(layer "In4.Cu")
		(net "M_F_CPU1_SB_DQ<24>")
	)
	(gr_poly
		(pts
			(xy 135.208264 -224.760028) (xy 135.16991 -224.73793) (xy 135.014462 -224.70237) (xy 134.883652 -224.928938)
			(xy 134.99211 -225.045778) (xy 135.030464 -225.067876)
		)
		(stroke
			(width 0)
			(type solid)
		)
		(fill yes)
		(layer "In4.Cu")
		(net "M_F_CPU1_SB_DQS_DP<8>")
	)
	(gr_poly
		(pts
			(xy 135.274304 -276.350476) (xy 135.312658 -276.328378) (xy 135.134858 -276.02053) (xy 135.096504 -276.042628)
			(xy 134.988046 -276.159468) (xy 135.118856 -276.386036)
		)
		(stroke
			(width 0)
			(type solid)
		)
		(fill yes)
		(layer "In4.Cu")
		(net "M_G_CPU1_SA_DQS_DP<0>")
	)
	(gr_poly
		(pts
			(xy 135.279638 -279.615646) (xy 135.317992 -279.593548) (xy 135.140192 -279.2857) (xy 135.101838 -279.307798)
			(xy 134.99338 -279.424638) (xy 135.12419 -279.651206)
		)
		(stroke
			(width 0)
			(type solid)
		)
		(fill yes)
		(layer "In4.Cu")
		(net "M_G_CPU1_SA_DQ<0>")
	)
	(gr_poly
		(pts
			(xy 135.30707 -242.905026) (xy 135.30707 -242.860576) (xy 134.95147 -242.860576) (xy 134.95147 -242.905026)
			(xy 134.99846 -243.057426) (xy 135.26008 -243.057426)
		)
		(stroke
			(width 0)
			(type solid)
		)
		(fill yes)
		(layer "In4.Cu")
		(net "M_G_CPU1_SB_DQS_DP<9>")
	)
	(gr_poly
		(pts
			(xy 135.30707 -236.801914) (xy 135.26008 -236.649514) (xy 134.99846 -236.649514) (xy 134.95147 -236.801914)
			(xy 134.95147 -236.846364) (xy 135.30707 -236.846364)
		)
		(stroke
			(width 0)
			(type solid)
		)
		(fill yes)
		(layer "In4.Cu")
		(net "M_F_CPU1_SB_DQS_DP<5>")
	)
	(gr_poly
		(pts
			(xy 135.307324 -248.196354) (xy 135.260334 -248.043954) (xy 134.998714 -248.043954) (xy 134.951724 -248.196354)
			(xy 134.951724 -248.240804) (xy 135.307324 -248.240804)
		)
		(stroke
			(width 0)
			(type solid)
		)
		(fill yes)
		(layer "In4.Cu")
		(net "M_G_CPU1_SB_CA<5>")
	)
	(gr_poly
		(pts
			(xy 135.313166 -246.568722) (xy 135.266176 -246.416322) (xy 135.004556 -246.416322) (xy 134.957566 -246.568722)
			(xy 134.957566 -246.613172) (xy 135.313166 -246.613172)
		)
		(stroke
			(width 0)
			(type solid)
		)
		(fill yes)
		(layer "In4.Cu")
		(net "M_G_CPU1_SB_CS_N<0>")
	)
	(gr_poly
		(pts
			(xy 135.313166 -246.16029) (xy 135.313166 -246.11584) (xy 134.957566 -246.11584) (xy 134.957566 -246.16029)
			(xy 135.004556 -246.31269) (xy 135.266176 -246.31269)
		)
		(stroke
			(width 0)
			(type solid)
		)
		(fill yes)
		(layer "In4.Cu")
		(net "M_G_CPU1_SB_CS_N<3>")
	)
	(gr_poly
		(pts
			(xy 135.313166 -238.021114) (xy 135.313166 -237.976918) (xy 134.957566 -237.976918) (xy 134.957566 -238.021114)
			(xy 135.004556 -238.173514) (xy 135.266176 -238.173514)
		)
		(stroke
			(width 0)
			(type solid)
		)
		(fill yes)
		(layer "In4.Cu")
		(net "M_F_CPU1_SB_DQS_DP<0>")
	)
	(gr_poly
		(pts
			(xy 135.313166 -234.76585) (xy 135.313166 -234.7214) (xy 134.957566 -234.7214) (xy 134.957566 -234.76585)
			(xy 135.004556 -234.91825) (xy 135.266176 -234.91825)
		)
		(stroke
			(width 0)
			(type solid)
		)
		(fill yes)
		(layer "In4.Cu")
		(net "M_G_CPU1_SB_DQ<16>")
	)
	(gr_poly
		(pts
			(xy 135.313166 -233.13771) (xy 135.313166 -233.093514) (xy 134.957566 -233.093514) (xy 134.957566 -233.13771)
			(xy 135.004556 -233.29011) (xy 135.266176 -233.29011)
		)
		(stroke
			(width 0)
			(type solid)
		)
		(fill yes)
		(layer "In4.Cu")
		(net "M_G_CPU1_SB_DQS_DP<2>")
	)
	(gr_poly
		(pts
			(xy 135.313166 -231.919018) (xy 135.266176 -231.766618) (xy 135.004556 -231.766618) (xy 134.957566 -231.919018)
			(xy 134.957566 -231.963214) (xy 135.313166 -231.963214)
		)
		(stroke
			(width 0)
			(type solid)
		)
		(fill yes)
		(layer "In4.Cu")
		(net "M_G_CPU1_SB_DQS_DP<7>")
	)
	(gr_poly
		(pts
			(xy 135.313166 -218.896438) (xy 135.266176 -218.744038) (xy 135.004556 -218.744038) (xy 134.957566 -218.896438)
			(xy 134.957566 -218.940888) (xy 135.313166 -218.940888)
		)
		(stroke
			(width 0)
			(type solid)
		)
		(fill yes)
		(layer "In4.Cu")
		(net "M_F_CPU1_SB_DQ<31>")
	)
	(gr_poly
		(pts
			(xy 135.315706 -241.685826) (xy 135.268716 -241.533426) (xy 135.007096 -241.533426) (xy 134.960106 -241.685826)
			(xy 134.960106 -241.730022) (xy 135.315706 -241.730022)
		)
		(stroke
			(width 0)
			(type solid)
		)
		(fill yes)
		(layer "In4.Cu")
		(net "M_G_CPU1_SB_DQS_DP<4>")
	)
	(gr_poly
		(pts
			(xy 135.316468 -243.313458) (xy 135.269478 -243.161058) (xy 135.007858 -243.161058) (xy 134.960868 -243.313458)
			(xy 134.960868 -243.357654) (xy 135.316468 -243.357654)
		)
		(stroke
			(width 0)
			(type solid)
		)
		(fill yes)
		(layer "In4.Cu")
		(net "M_G_CPU1_SB_CB<7>")
	)
	(gr_poly
		(pts
			(xy 135.316468 -241.276886) (xy 135.316468 -241.232436) (xy 134.960868 -241.232436) (xy 134.960868 -241.276886)
			(xy 135.007858 -241.429286) (xy 135.269478 -241.429286)
		)
		(stroke
			(width 0)
			(type solid)
		)
		(fill yes)
		(layer "In4.Cu")
		(net "M_G_CPU1_SB_CB<0>")
	)
	(gr_poly
		(pts
			(xy 135.316468 -240.057686) (xy 135.269478 -239.905286) (xy 135.007858 -239.905286) (xy 134.960868 -240.057686)
			(xy 134.960868 -240.102136) (xy 135.316468 -240.102136)
		)
		(stroke
			(width 0)
			(type solid)
		)
		(fill yes)
		(layer "In4.Cu")
		(net "M_G_CPU1_SB_CB<3>")
	)
	(gr_poly
		(pts
			(xy 135.316468 -239.648746) (xy 135.316468 -239.60455) (xy 134.960868 -239.60455) (xy 134.960868 -239.648746)
			(xy 135.007858 -239.801146) (xy 135.269478 -239.801146)
		)
		(stroke
			(width 0)
			(type solid)
		)
		(fill yes)
		(layer "In4.Cu")
		(net "M_F_CPU1_SB_DQ<0>")
	)
	(gr_poly
		(pts
			(xy 135.316468 -235.174282) (xy 135.269478 -235.021882) (xy 135.007858 -235.021882) (xy 134.960868 -235.174282)
			(xy 134.960868 -235.218732) (xy 135.316468 -235.218732)
		)
		(stroke
			(width 0)
			(type solid)
		)
		(fill yes)
		(layer "In4.Cu")
		(net "M_F_CPU1_SB_DQ<7>")
	)
	(gr_poly
		(pts
			(xy 135.316468 -230.290878) (xy 135.269478 -230.138478) (xy 135.007858 -230.138478) (xy 134.960868 -230.290878)
			(xy 134.960868 -230.335328) (xy 135.316468 -230.335328)
		)
		(stroke
			(width 0)
			(type solid)
		)
		(fill yes)
		(layer "In4.Cu")
		(net "M_G_CPU1_SB_DQ<23>")
	)
	(gr_poly
		(pts
			(xy 135.31723 -244.53215) (xy 135.31723 -244.487954) (xy 134.96163 -244.487954) (xy 134.96163 -244.53215)
			(xy 135.00862 -244.68455) (xy 135.27024 -244.68455)
		)
		(stroke
			(width 0)
			(type solid)
		)
		(fill yes)
		(layer "In4.Cu")
		(net "M_G_CPU1_SB_CB<4>")
	)
	(gr_poly
		(pts
			(xy 135.31723 -238.430054) (xy 135.27024 -238.277654) (xy 135.00862 -238.277654) (xy 134.96163 -238.430054)
			(xy 134.96163 -238.47425) (xy 135.31723 -238.47425)
		)
		(stroke
			(width 0)
			(type solid)
		)
		(fill yes)
		(layer "In4.Cu")
		(net "M_F_CPU1_SB_DQ<3>")
	)
	(gr_poly
		(pts
			(xy 135.31723 -236.393482) (xy 135.31723 -236.349032) (xy 134.96163 -236.349032) (xy 134.96163 -236.393482)
			(xy 135.00862 -236.545882) (xy 135.27024 -236.545882)
		)
		(stroke
			(width 0)
			(type solid)
		)
		(fill yes)
		(layer "In4.Cu")
		(net "M_F_CPU1_SB_DQ<4>")
	)
	(gr_poly
		(pts
			(xy 135.31723 -233.54665) (xy 135.27024 -233.39425) (xy 135.00862 -233.39425) (xy 134.96163 -233.54665)
			(xy 134.96163 -233.5911) (xy 135.31723 -233.5911)
		)
		(stroke
			(width 0)
			(type solid)
		)
		(fill yes)
		(layer "In4.Cu")
		(net "M_G_CPU1_SB_DQ<19>")
	)
	(gr_poly
		(pts
			(xy 135.31723 -231.510078) (xy 135.31723 -231.465628) (xy 134.96163 -231.465628) (xy 134.96163 -231.510078)
			(xy 135.00862 -231.662478) (xy 135.27024 -231.662478)
		)
		(stroke
			(width 0)
			(type solid)
		)
		(fill yes)
		(layer "In4.Cu")
		(net "M_G_CPU1_SB_DQ<20>")
	)
	(gr_poly
		(pts
			(xy 135.319262 -247.787922) (xy 135.319262 -247.743472) (xy 134.963662 -247.743472) (xy 134.963662 -247.787922)
			(xy 135.010652 -247.940322) (xy 135.272272 -247.940322)
		)
		(stroke
			(width 0)
			(type solid)
		)
		(fill yes)
		(layer "In4.Cu")
		(net "M_G_CPU1_SB_CA<6>")
	)
	(gr_poly
		(pts
			(xy 135.386064 -225.479102) (xy 135.277606 -225.362262) (xy 135.239252 -225.340164) (xy 135.061452 -225.648012)
			(xy 135.099806 -225.67011) (xy 135.255254 -225.70567)
		)
		(stroke
			(width 0)
			(type solid)
		)
		(fill yes)
		(layer "In4.Cu")
		(net "M_F_CPU1_SB_DQS_DN<8>")
	)
	(gr_poly
		(pts
			(xy 135.38708 -220.593666) (xy 135.278622 -220.476826) (xy 135.240268 -220.454728) (xy 135.062468 -220.762576)
			(xy 135.100822 -220.784674) (xy 135.25627 -220.820234)
		)
		(stroke
			(width 0)
			(type solid)
		)
		(fill yes)
		(layer "In4.Cu")
		(net "M_F_CPU1_SB_DQ<30>")
	)
	(gr_poly
		(pts
			(xy 135.38835 -275.73732) (xy 135.496808 -275.62048) (xy 135.365998 -275.393912) (xy 135.21055 -275.429472)
			(xy 135.172196 -275.45157) (xy 135.349996 -275.759418)
		)
		(stroke
			(width 0)
			(type solid)
		)
		(fill yes)
		(layer "In4.Cu")
		(net "M_G_CPU1_SA_DQS_DN<0>")
	)
	(gr_poly
		(pts
			(xy 135.389366 -278.995378) (xy 135.497824 -278.878538) (xy 135.367014 -278.65197) (xy 135.211566 -278.68753)
			(xy 135.173212 -278.709628) (xy 135.351012 -279.017476)
		)
		(stroke
			(width 0)
			(type solid)
		)
		(fill yes)
		(layer "In4.Cu")
		(net "M_G_CPU1_SA_DQ<2>")
	)
	(gr_poly
		(pts
			(xy 135.392414 -228.723444) (xy 135.283956 -228.606604) (xy 135.245602 -228.584506) (xy 135.067802 -228.892354)
			(xy 135.106156 -228.914452) (xy 135.261604 -228.950012)
		)
		(stroke
			(width 0)
			(type solid)
		)
		(fill yes)
		(layer "In4.Cu")
		(net "M_F_CPU1_SB_DQ<26>")
	)
	(gr_poly
		(pts
			(xy 135.392414 -227.095558) (xy 135.283956 -226.978718) (xy 135.245602 -226.95662) (xy 135.067802 -227.264468)
			(xy 135.106156 -227.286566) (xy 135.261604 -227.322126)
		)
		(stroke
			(width 0)
			(type solid)
		)
		(fill yes)
		(layer "In4.Cu")
		(net "M_F_CPU1_SB_DQ<27>")
	)
	(gr_poly
		(pts
			(xy 135.392414 -222.212154) (xy 135.283956 -222.095314) (xy 135.245602 -222.073216) (xy 135.067802 -222.381064)
			(xy 135.106156 -222.403162) (xy 135.261604 -222.438722)
		)
		(stroke
			(width 0)
			(type solid)
		)
		(fill yes)
		(layer "In4.Cu")
		(net "M_F_CPU1_SB_DQS_DP<3>")
	)
	(gr_poly
		(pts
			(xy 135.414512 -277.318216) (xy 135.414512 -277.27402) (xy 135.058912 -277.27402) (xy 135.058912 -277.318216)
			(xy 135.105902 -277.470616) (xy 135.367522 -277.470616)
		)
		(stroke
			(width 0)
			(type solid)
		)
		(fill yes)
		(layer "In4.Cu")
		(net "M_G_CPU1_SA_DQ<1>")
	)
	(gr_poly
		(pts
			(xy 135.414512 -272.843498) (xy 135.367522 -272.691098) (xy 135.105902 -272.691098) (xy 135.058912 -272.843498)
			(xy 135.058912 -272.887694) (xy 135.414512 -272.887694)
		)
		(stroke
			(width 0)
			(type solid)
		)
		(fill yes)
		(layer "In4.Cu")
		(net "M_G_CPU1_SA_DQ<7>")
	)
	(gr_poly
		(pts
			(xy 135.414512 -270.807434) (xy 135.414512 -270.762984) (xy 135.058912 -270.762984) (xy 135.058912 -270.807434)
			(xy 135.105902 -270.959834) (xy 135.367522 -270.959834)
		)
		(stroke
			(width 0)
			(type solid)
		)
		(fill yes)
		(layer "In4.Cu")
		(net "M_F_CPU1_SA_DQS_DP<1>")
	)
	(gr_poly
		(pts
			(xy 135.414512 -265.92403) (xy 135.414512 -265.87958) (xy 135.058912 -265.87958) (xy 135.058912 -265.92403)
			(xy 135.105902 -266.07643) (xy 135.367522 -266.07643)
		)
		(stroke
			(width 0)
			(type solid)
		)
		(fill yes)
		(layer "In4.Cu")
		(net "M_G_CPU1_SA_DQS_DP<2>")
	)
	(gr_poly
		(pts
			(xy 135.414512 -264.704322) (xy 135.367522 -264.551922) (xy 135.105902 -264.551922) (xy 135.058912 -264.704322)
			(xy 135.058912 -264.748772) (xy 135.414512 -264.748772)
		)
		(stroke
			(width 0)
			(type solid)
		)
		(fill yes)
		(layer "In4.Cu")
		(net "M_G_CPU1_SA_DQS_DP<7>")
	)
	(gr_poly
		(pts
			(xy 135.414766 -261.449058) (xy 135.367776 -261.296658) (xy 135.106156 -261.296658) (xy 135.059166 -261.449058)
			(xy 135.059166 -261.493508) (xy 135.414766 -261.493508)
		)
		(stroke
			(width 0)
			(type solid)
		)
		(fill yes)
		(layer "In4.Cu")
		(net "M_F_CPU1_SA_DQ<27>")
	)
	(gr_poly
		(pts
			(xy 135.416798 -259.821426) (xy 135.369808 -259.669026) (xy 135.108188 -259.669026) (xy 135.061198 -259.821426)
			(xy 135.061198 -259.865622) (xy 135.416798 -259.865622)
		)
		(stroke
			(width 0)
			(type solid)
		)
		(fill yes)
		(layer "In4.Cu")
		(net "M_F_CPU1_SA_DQS_DP<8>")
	)
	(gr_poly
		(pts
			(xy 135.419338 -259.412486) (xy 135.419338 -259.368036) (xy 135.063738 -259.368036) (xy 135.063738 -259.412486)
			(xy 135.110728 -259.564886) (xy 135.372348 -259.564886)
		)
		(stroke
			(width 0)
			(type solid)
		)
		(fill yes)
		(layer "In4.Cu")
		(net "M_F_CPU1_SA_DQ<28>")
	)
	(gr_poly
		(pts
			(xy 135.422894 -274.471638) (xy 135.375904 -274.319238) (xy 135.114284 -274.319238) (xy 135.067294 -274.471638)
			(xy 135.067294 -274.516088) (xy 135.422894 -274.516088)
		)
		(stroke
			(width 0)
			(type solid)
		)
		(fill yes)
		(layer "In4.Cu")
		(net "M_G_CPU1_SA_DQS_DP<5>")
	)
	(gr_poly
		(pts
			(xy 135.422894 -264.29589) (xy 135.422894 -264.251694) (xy 135.067294 -264.251694) (xy 135.067294 -264.29589)
			(xy 135.114284 -264.44829) (xy 135.375904 -264.44829)
		)
		(stroke
			(width 0)
			(type solid)
		)
		(fill yes)
		(layer "In4.Cu")
		(net "M_G_CPU1_SA_DQ<20>")
	)
	(gr_poly
		(pts
			(xy 135.422894 -261.040626) (xy 135.422894 -260.996176) (xy 135.067294 -260.996176) (xy 135.067294 -261.040626)
			(xy 135.114284 -261.193026) (xy 135.375904 -261.193026)
		)
		(stroke
			(width 0)
			(type solid)
		)
		(fill yes)
		(layer "In4.Cu")
		(net "M_F_CPU1_SA_DQS_DP<3>")
	)
	(gr_poly
		(pts
			(xy 135.422894 -258.193286) (xy 135.375904 -258.040886) (xy 135.114284 -258.040886) (xy 135.067294 -258.193286)
			(xy 135.067294 -258.237736) (xy 135.422894 -258.237736)
		)
		(stroke
			(width 0)
			(type solid)
		)
		(fill yes)
		(layer "In4.Cu")
		(net "M_F_CPU1_SA_DQ<31>")
	)
	(gr_poly
		(pts
			(xy 135.422894 -257.784854) (xy 135.422894 -257.740404) (xy 135.067294 -257.740404) (xy 135.067294 -257.784854)
			(xy 135.114284 -257.937254) (xy 135.375904 -257.937254)
		)
		(stroke
			(width 0)
			(type solid)
		)
		(fill yes)
		(layer "In4.Cu")
		(net "M_G_CPU1_SA_CS_N<0>")
	)
	(gr_poly
		(pts
			(xy 135.422894 -256.565654) (xy 135.375904 -256.413254) (xy 135.114284 -256.413254) (xy 135.067294 -256.565654)
			(xy 135.067294 -256.610104) (xy 135.422894 -256.610104)
		)
		(stroke
			(width 0)
			(type solid)
		)
		(fill yes)
		(layer "In4.Cu")
		(net "M_G_CPU1_SA_CS_N<3>")
	)
	(gr_poly
		(pts
			(xy 135.422894 -256.157222) (xy 135.422894 -256.112772) (xy 135.067294 -256.112772) (xy 135.067294 -256.157222)
			(xy 135.114284 -256.309622) (xy 135.375904 -256.309622)
		)
		(stroke
			(width 0)
			(type solid)
		)
		(fill yes)
		(layer "In4.Cu")
		(net "M_G_CPU1_SA_CA<1>")
	)
	(gr_poly
		(pts
			(xy 135.422894 -254.938022) (xy 135.375904 -254.785622) (xy 135.114284 -254.785622) (xy 135.067294 -254.938022)
			(xy 135.067294 -254.982218) (xy 135.422894 -254.982218)
		)
		(stroke
			(width 0)
			(type solid)
		)
		(fill yes)
		(layer "In4.Cu")
		(net "M_G_CPU1_SA_CA<2>")
	)
	(gr_poly
		(pts
			(xy 135.42518 -266.332462) (xy 135.37819 -266.180062) (xy 135.11657 -266.180062) (xy 135.06958 -266.332462)
			(xy 135.06958 -266.376912) (xy 135.42518 -266.376912)
		)
		(stroke
			(width 0)
			(type solid)
		)
		(fill yes)
		(layer "In4.Cu")
		(net "M_G_CPU1_SA_DQ<19>")
	)
	(gr_poly
		(pts
			(xy 135.425688 -274.062698) (xy 135.425688 -274.018248) (xy 135.070088 -274.018248) (xy 135.070088 -274.062698)
			(xy 135.117078 -274.215098) (xy 135.378698 -274.215098)
		)
		(stroke
			(width 0)
			(type solid)
		)
		(fill yes)
		(layer "In4.Cu")
		(net "M_G_CPU1_SA_DQ<4>")
	)
	(gr_poly
		(pts
			(xy 135.425688 -272.434558) (xy 135.425688 -272.390362) (xy 135.070088 -272.390362) (xy 135.070088 -272.434558)
			(xy 135.117078 -272.586958) (xy 135.378698 -272.586958)
		)
		(stroke
			(width 0)
			(type solid)
		)
		(fill yes)
		(layer "In4.Cu")
		(net "M_F_CPU1_SA_DQ<8>")
	)
	(gr_poly
		(pts
			(xy 135.425688 -271.215866) (xy 135.378698 -271.063466) (xy 135.117078 -271.063466) (xy 135.070088 -271.215866)
			(xy 135.070088 -271.260062) (xy 135.425688 -271.260062)
		)
		(stroke
			(width 0)
			(type solid)
		)
		(fill yes)
		(layer "In4.Cu")
		(net "M_F_CPU1_SA_DQ<11>")
	)
	(gr_poly
		(pts
			(xy 135.425688 -269.588234) (xy 135.378698 -269.435834) (xy 135.117078 -269.435834) (xy 135.070088 -269.588234)
			(xy 135.070088 -269.63243) (xy 135.425688 -269.63243)
		)
		(stroke
			(width 0)
			(type solid)
		)
		(fill yes)
		(layer "In4.Cu")
		(net "M_F_CPU1_SA_DQS_DP<6>")
	)
	(gr_poly
		(pts
			(xy 135.425688 -269.179294) (xy 135.425688 -269.134844) (xy 135.070088 -269.134844) (xy 135.070088 -269.179294)
			(xy 135.117078 -269.331694) (xy 135.378698 -269.331694)
		)
		(stroke
			(width 0)
			(type solid)
		)
		(fill yes)
		(layer "In4.Cu")
		(net "M_F_CPU1_SA_DQ<12>")
	)
	(gr_poly
		(pts
			(xy 135.425688 -267.960094) (xy 135.378698 -267.807694) (xy 135.117078 -267.807694) (xy 135.070088 -267.960094)
			(xy 135.070088 -268.004544) (xy 135.425688 -268.004544)
		)
		(stroke
			(width 0)
			(type solid)
		)
		(fill yes)
		(layer "In4.Cu")
		(net "M_F_CPU1_SA_DQ<13>")
	)
	(gr_poly
		(pts
			(xy 135.425688 -267.551154) (xy 135.425688 -267.506958) (xy 135.070088 -267.506958) (xy 135.070088 -267.551154)
			(xy 135.117078 -267.703554) (xy 135.378698 -267.703554)
		)
		(stroke
			(width 0)
			(type solid)
		)
		(fill yes)
		(layer "In4.Cu")
		(net "M_G_CPU1_SA_DQ<16>")
	)
	(gr_poly
		(pts
			(xy 135.425688 -263.07669) (xy 135.378698 -262.92429) (xy 135.117078 -262.92429) (xy 135.070088 -263.07669)
			(xy 135.070088 -263.12114) (xy 135.425688 -263.12114)
		)
		(stroke
			(width 0)
			(type solid)
		)
		(fill yes)
		(layer "In4.Cu")
		(net "M_G_CPU1_SA_DQ<23>")
	)
	(gr_poly
		(pts
			(xy 135.425688 -262.668258) (xy 135.425688 -262.623808) (xy 135.070088 -262.623808) (xy 135.070088 -262.668258)
			(xy 135.117078 -262.820658) (xy 135.378698 -262.820658)
		)
		(stroke
			(width 0)
			(type solid)
		)
		(fill yes)
		(layer "In4.Cu")
		(net "M_F_CPU1_SA_DQ<24>")
	)
	(gr_poly
		(pts
			(xy 135.640826 -223.228408) (xy 135.67918 -223.20631) (xy 135.50138 -222.898462) (xy 135.463026 -222.92056)
			(xy 135.354568 -223.0374) (xy 135.485378 -223.263968)
		)
		(stroke
			(width 0)
			(type solid)
		)
		(fill yes)
		(layer "In4.Cu")
		(net "M_F_CPU1_SB_DQS_DP<8>")
	)
	(gr_poly
		(pts
			(xy 135.670798 -223.958912) (xy 135.632444 -223.936814) (xy 135.476996 -223.901254) (xy 135.346186 -224.127822)
			(xy 135.454644 -224.244662) (xy 135.492998 -224.26676)
		)
		(stroke
			(width 0)
			(type solid)
		)
		(fill yes)
		(layer "In4.Cu")
		(net "M_F_CPU1_SB_DQS_DP<8>")
	)
	(gr_poly
		(pts
			(xy 135.677148 -227.20427) (xy 135.638794 -227.182172) (xy 135.483346 -227.146612) (xy 135.352536 -227.37318)
			(xy 135.460994 -227.49002) (xy 135.499348 -227.512118)
		)
		(stroke
			(width 0)
			(type solid)
		)
		(fill yes)
		(layer "In4.Cu")
		(net "M_F_CPU1_SB_DQ<24>")
	)
	(gr_poly
		(pts
			(xy 135.677148 -222.320866) (xy 135.638794 -222.298768) (xy 135.483346 -222.263208) (xy 135.352536 -222.489776)
			(xy 135.460994 -222.606616) (xy 135.499348 -222.628714)
		)
		(stroke
			(width 0)
			(type solid)
		)
		(fill yes)
		(layer "In4.Cu")
		(net "M_F_CPU1_SB_DQS_DP<8>")
	)
	(gr_poly
		(pts
			(xy 135.67918 -225.572574) (xy 135.640826 -225.550476) (xy 135.485378 -225.514916) (xy 135.354568 -225.741484)
			(xy 135.463026 -225.858324) (xy 135.50138 -225.880422)
		)
		(stroke
			(width 0)
			(type solid)
		)
		(fill yes)
		(layer "In4.Cu")
		(net "M_F_CPU1_SB_DQ<25>")
	)
	(gr_poly
		(pts
			(xy 135.749792 -275.546312) (xy 135.788146 -275.524214) (xy 135.610346 -275.216366) (xy 135.571992 -275.238464)
			(xy 135.463534 -275.355304) (xy 135.594344 -275.581872)
		)
		(stroke
			(width 0)
			(type solid)
		)
		(fill yes)
		(layer "In4.Cu")
		(net "M_G_CPU1_SA_DQS_DN<5>")
	)
	(gr_poly
		(pts
			(xy 135.779764 -244.127274) (xy 135.732774 -243.974874) (xy 135.471154 -243.974874) (xy 135.424164 -244.127274)
			(xy 135.424164 -244.17147) (xy 135.779764 -244.17147)
		)
		(stroke
			(width 0)
			(type solid)
		)
		(fill yes)
		(layer "In4.Cu")
		(net "M_G_CPU1_SB_CB<6>")
	)
	(gr_poly
		(pts
			(xy 135.779764 -238.83493) (xy 135.779764 -238.790734) (xy 135.424164 -238.790734) (xy 135.424164 -238.83493)
			(xy 135.471154 -238.98733) (xy 135.732774 -238.98733)
		)
		(stroke
			(width 0)
			(type solid)
		)
		(fill yes)
		(layer "In4.Cu")
		(net "M_F_CPU1_SB_DQ<1>")
	)
	(gr_poly
		(pts
			(xy 135.779764 -235.988606) (xy 135.732774 -235.836206) (xy 135.471154 -235.836206) (xy 135.424164 -235.988606)
			(xy 135.424164 -236.032802) (xy 135.779764 -236.032802)
		)
		(stroke
			(width 0)
			(type solid)
		)
		(fill yes)
		(layer "In4.Cu")
		(net "M_F_CPU1_SB_DQ<6>")
	)
	(gr_poly
		(pts
			(xy 135.779764 -233.951526) (xy 135.779764 -233.90733) (xy 135.424164 -233.90733) (xy 135.424164 -233.951526)
			(xy 135.471154 -234.103926) (xy 135.732774 -234.103926)
		)
		(stroke
			(width 0)
			(type solid)
		)
		(fill yes)
		(layer "In4.Cu")
		(net "M_G_CPU1_SB_DQ<17>")
	)
	(gr_poly
		(pts
			(xy 135.779764 -231.105202) (xy 135.732774 -230.952802) (xy 135.471154 -230.952802) (xy 135.424164 -231.105202)
			(xy 135.424164 -231.149398) (xy 135.779764 -231.149398)
		)
		(stroke
			(width 0)
			(type solid)
		)
		(fill yes)
		(layer "In4.Cu")
		(net "M_G_CPU1_SB_DQ<22>")
	)
	(gr_poly
		(pts
			(xy 135.78078 -243.718334) (xy 135.78078 -243.674138) (xy 135.42518 -243.674138) (xy 135.42518 -243.718334)
			(xy 135.47217 -243.870734) (xy 135.73379 -243.870734)
		)
		(stroke
			(width 0)
			(type solid)
		)
		(fill yes)
		(layer "In4.Cu")
		(net "M_G_CPU1_SB_CB<5>")
	)
	(gr_poly
		(pts
			(xy 135.78078 -240.871502) (xy 135.73379 -240.719102) (xy 135.47217 -240.719102) (xy 135.42518 -240.871502)
			(xy 135.42518 -240.915952) (xy 135.78078 -240.915952)
		)
		(stroke
			(width 0)
			(type solid)
		)
		(fill yes)
		(layer "In4.Cu")
		(net "M_G_CPU1_SB_CB<2>")
	)
	(gr_poly
		(pts
			(xy 135.78078 -240.46307) (xy 135.78078 -240.41862) (xy 135.42518 -240.41862) (xy 135.42518 -240.46307)
			(xy 135.47217 -240.61547) (xy 135.73379 -240.61547)
		)
		(stroke
			(width 0)
			(type solid)
		)
		(fill yes)
		(layer "In4.Cu")
		(net "M_G_CPU1_SB_CB<1>")
	)
	(gr_poly
		(pts
			(xy 135.78078 -239.24387) (xy 135.73379 -239.09147) (xy 135.47217 -239.09147) (xy 135.42518 -239.24387)
			(xy 135.42518 -239.288066) (xy 135.78078 -239.288066)
		)
		(stroke
			(width 0)
			(type solid)
		)
		(fill yes)
		(layer "In4.Cu")
		(net "M_F_CPU1_SB_DQ<2>")
	)
	(gr_poly
		(pts
			(xy 135.78078 -235.579666) (xy 135.78078 -235.535216) (xy 135.42518 -235.535216) (xy 135.42518 -235.579666)
			(xy 135.47217 -235.732066) (xy 135.73379 -235.732066)
		)
		(stroke
			(width 0)
			(type solid)
		)
		(fill yes)
		(layer "In4.Cu")
		(net "M_F_CPU1_SB_DQ<5>")
	)
	(gr_poly
		(pts
			(xy 135.78078 -230.696262) (xy 135.78078 -230.651812) (xy 135.42518 -230.651812) (xy 135.42518 -230.696262)
			(xy 135.47217 -230.848662) (xy 135.73379 -230.848662)
		)
		(stroke
			(width 0)
			(type solid)
		)
		(fill yes)
		(layer "In4.Cu")
		(net "M_G_CPU1_SB_DQ<21>")
	)
	(gr_poly
		(pts
			(xy 135.783066 -247.382538) (xy 135.736076 -247.230138) (xy 135.474456 -247.230138) (xy 135.427466 -247.382538)
			(xy 135.427466 -247.426988) (xy 135.783066 -247.426988)
		)
		(stroke
			(width 0)
			(type solid)
		)
		(fill yes)
		(layer "In4.Cu")
		(net "M_G_CPU1_SB_PAR")
	)
	(gr_poly
		(pts
			(xy 135.783066 -246.974106) (xy 135.783066 -246.929656) (xy 135.427466 -246.929656) (xy 135.427466 -246.974106)
			(xy 135.474456 -247.126506) (xy 135.736076 -247.126506)
		)
		(stroke
			(width 0)
			(type solid)
		)
		(fill yes)
		(layer "In4.Cu")
		(net "M_G_CPU1_SB_CS_N<2>")
	)
	(gr_poly
		(pts
			(xy 135.783066 -245.754906) (xy 135.736076 -245.602506) (xy 135.474456 -245.602506) (xy 135.427466 -245.754906)
			(xy 135.427466 -245.799356) (xy 135.783066 -245.799356)
		)
		(stroke
			(width 0)
			(type solid)
		)
		(fill yes)
		(layer "In4.Cu")
		(net "M_G_CPU1_SB_CS_N<1>")
	)
	(gr_poly
		(pts
			(xy 135.783066 -242.499134) (xy 135.736076 -242.346734) (xy 135.474456 -242.346734) (xy 135.427466 -242.499134)
			(xy 135.427466 -242.543584) (xy 135.783066 -242.543584)
		)
		(stroke
			(width 0)
			(type solid)
		)
		(fill yes)
		(layer "In4.Cu")
		(net "M_G_CPU1_SB_DQS_DN<9>")
	)
	(gr_poly
		(pts
			(xy 135.783066 -242.090702) (xy 135.783066 -242.046252) (xy 135.427466 -242.046252) (xy 135.427466 -242.090702)
			(xy 135.474456 -242.243102) (xy 135.736076 -242.243102)
		)
		(stroke
			(width 0)
			(type solid)
		)
		(fill yes)
		(layer "In4.Cu")
		(net "M_G_CPU1_SB_DQS_DN<4>")
	)
	(gr_poly
		(pts
			(xy 135.783066 -237.61573) (xy 135.736076 -237.46333) (xy 135.474456 -237.46333) (xy 135.427466 -237.61573)
			(xy 135.427466 -237.66018) (xy 135.783066 -237.66018)
		)
		(stroke
			(width 0)
			(type solid)
		)
		(fill yes)
		(layer "In4.Cu")
		(net "M_F_CPU1_SB_DQS_DN<0>")
	)
	(gr_poly
		(pts
			(xy 135.783066 -234.360466) (xy 135.736076 -234.208066) (xy 135.474456 -234.208066) (xy 135.427466 -234.360466)
			(xy 135.427466 -234.404916) (xy 135.783066 -234.404916)
		)
		(stroke
			(width 0)
			(type solid)
		)
		(fill yes)
		(layer "In4.Cu")
		(net "M_G_CPU1_SB_DQ<18>")
	)
	(gr_poly
		(pts
			(xy 135.783066 -232.732834) (xy 135.736076 -232.580434) (xy 135.474456 -232.580434) (xy 135.427466 -232.732834)
			(xy 135.427466 -232.77703) (xy 135.783066 -232.77703)
		)
		(stroke
			(width 0)
			(type solid)
		)
		(fill yes)
		(layer "In4.Cu")
		(net "M_G_CPU1_SB_DQS_DN<2>")
	)
	(gr_poly
		(pts
			(xy 135.783066 -232.323894) (xy 135.783066 -232.279698) (xy 135.427466 -232.279698) (xy 135.427466 -232.323894)
			(xy 135.474456 -232.476294) (xy 135.736076 -232.476294)
		)
		(stroke
			(width 0)
			(type solid)
		)
		(fill yes)
		(layer "In4.Cu")
		(net "M_G_CPU1_SB_DQS_DN<7>")
	)
	(gr_poly
		(pts
			(xy 135.783066 -221.338394) (xy 135.736076 -221.185994) (xy 135.474456 -221.185994) (xy 135.427466 -221.338394)
			(xy 135.427466 -221.38259) (xy 135.783066 -221.38259)
		)
		(stroke
			(width 0)
			(type solid)
		)
		(fill yes)
		(layer "In4.Cu")
		(net "M_F_CPU1_SB_DQS_DN<3>")
	)
	(gr_poly
		(pts
			(xy 135.783066 -219.710254) (xy 135.736076 -219.557854) (xy 135.474456 -219.557854) (xy 135.427466 -219.710254)
			(xy 135.427466 -219.754704) (xy 135.783066 -219.754704)
		)
		(stroke
			(width 0)
			(type solid)
		)
		(fill yes)
		(layer "In4.Cu")
		(net "M_F_CPU1_SB_DQ<28>")
	)
	(gr_poly
		(pts
			(xy 135.783066 -219.301822) (xy 135.783066 -219.257372) (xy 135.427466 -219.257372) (xy 135.427466 -219.301822)
			(xy 135.474456 -219.454222) (xy 135.736076 -219.454222)
		)
		(stroke
			(width 0)
			(type solid)
		)
		(fill yes)
		(layer "In4.Cu")
		(net "M_F_CPU1_SB_DQ<29>")
	)
	(gr_poly
		(pts
			(xy 135.791448 -237.207806) (xy 135.791448 -237.163356) (xy 135.435848 -237.163356) (xy 135.435848 -237.207806)
			(xy 135.482838 -237.360206) (xy 135.744458 -237.360206)
		)
		(stroke
			(width 0)
			(type solid)
		)
		(fill yes)
		(layer "In4.Cu")
		(net "M_F_CPU1_SB_DQS_DN<5>")
	)
	(gr_poly
		(pts
			(xy 135.855964 -227.920804) (xy 135.747506 -227.803964) (xy 135.709152 -227.781866) (xy 135.531352 -228.089714)
			(xy 135.569706 -228.111812) (xy 135.725154 -228.147372)
		)
		(stroke
			(width 0)
			(type solid)
		)
		(fill yes)
		(layer "In4.Cu")
		(net "M_F_CPU1_SB_DQ<26>")
	)
	(gr_poly
		(pts
			(xy 135.857996 -226.289108) (xy 135.749538 -226.172268) (xy 135.711184 -226.15017) (xy 135.533384 -226.458018)
			(xy 135.571738 -226.480116) (xy 135.727186 -226.515676)
		)
		(stroke
			(width 0)
			(type solid)
		)
		(fill yes)
		(layer "In4.Cu")
		(net "M_F_CPU1_SB_DQ<27>")
	)
	(gr_poly
		(pts
			(xy 135.858504 -274.924012) (xy 135.966962 -274.807172) (xy 135.836152 -274.580604) (xy 135.680704 -274.616164)
			(xy 135.64235 -274.638262) (xy 135.82015 -274.94611)
		)
		(stroke
			(width 0)
			(type solid)
		)
		(fill yes)
		(layer "In4.Cu")
		(net "M_G_CPU1_SA_DQS_DP<5>")
	)
	(gr_poly
		(pts
			(xy 135.862314 -224.653856) (xy 135.753856 -224.537016) (xy 135.715502 -224.514918) (xy 135.537702 -224.822766)
			(xy 135.576056 -224.844864) (xy 135.731504 -224.880424)
		)
		(stroke
			(width 0)
			(type solid)
		)
		(fill yes)
		(layer "In4.Cu")
		(net "M_F_CPU1_SB_DQS_DN<8>")
	)
	(gr_poly
		(pts
			(xy 135.886698 -279.759918) (xy 135.886698 -279.715722) (xy 135.531098 -279.715722) (xy 135.531098 -279.759918)
			(xy 135.578088 -279.912318) (xy 135.839708 -279.912318)
		)
		(stroke
			(width 0)
			(type solid)
		)
		(fill yes)
		(layer "In4.Cu")
		(net "M_G_CPU1_SA_DQ<0>")
	)
	(gr_poly
		(pts
			(xy 135.892794 -263.891014) (xy 135.845804 -263.738614) (xy 135.584184 -263.738614) (xy 135.537194 -263.891014)
			(xy 135.537194 -263.93521) (xy 135.892794 -263.93521)
		)
		(stroke
			(width 0)
			(type solid)
		)
		(fill yes)
		(layer "In4.Cu")
		(net "M_G_CPU1_SA_DQ<22>")
	)
	(gr_poly
		(pts
			(xy 135.892794 -260.635242) (xy 135.845804 -260.482842) (xy 135.584184 -260.482842) (xy 135.537194 -260.635242)
			(xy 135.537194 -260.679438) (xy 135.892794 -260.679438)
		)
		(stroke
			(width 0)
			(type solid)
		)
		(fill yes)
		(layer "In4.Cu")
		(net "M_F_CPU1_SA_DQS_DN<3>")
	)
	(gr_poly
		(pts
			(xy 135.892794 -258.59867) (xy 135.892794 -258.554474) (xy 135.537194 -258.554474) (xy 135.537194 -258.59867)
			(xy 135.584184 -258.75107) (xy 135.845804 -258.75107)
		)
		(stroke
			(width 0)
			(type solid)
		)
		(fill yes)
		(layer "In4.Cu")
		(net "M_F_CPU1_SA_DQ<29>")
	)
	(gr_poly
		(pts
			(xy 135.892794 -257.37947) (xy 135.845804 -257.22707) (xy 135.584184 -257.22707) (xy 135.537194 -257.37947)
			(xy 135.537194 -257.42392) (xy 135.892794 -257.42392)
		)
		(stroke
			(width 0)
			(type solid)
		)
		(fill yes)
		(layer "In4.Cu")
		(net "M_G_CPU1_SA_CS_N<1>")
	)
	(gr_poly
		(pts
			(xy 135.892794 -256.971038) (xy 135.892794 -256.926588) (xy 135.537194 -256.926588) (xy 135.537194 -256.971038)
			(xy 135.584184 -257.123438) (xy 135.845804 -257.123438)
		)
		(stroke
			(width 0)
			(type solid)
		)
		(fill yes)
		(layer "In4.Cu")
		(net "M_G_CPU1_SA_CS_N<2>")
	)
	(gr_poly
		(pts
			(xy 135.892794 -255.751838) (xy 135.845804 -255.599438) (xy 135.584184 -255.599438) (xy 135.537194 -255.751838)
			(xy 135.537194 -255.796288) (xy 135.892794 -255.796288)
		)
		(stroke
			(width 0)
			(type solid)
		)
		(fill yes)
		(layer "In4.Cu")
		(net "M_G_CPU1_SA_CA<0>")
	)
	(gr_poly
		(pts
			(xy 135.892794 -255.343406) (xy 135.892794 -255.298956) (xy 135.537194 -255.298956) (xy 135.537194 -255.343406)
			(xy 135.584184 -255.495806) (xy 135.845804 -255.495806)
		)
		(stroke
			(width 0)
			(type solid)
		)
		(fill yes)
		(layer "In4.Cu")
		(net "M_G_CPU1_SA_CA<3>")
	)
	(gr_poly
		(pts
			(xy 135.893048 -273.657314) (xy 135.846058 -273.504914) (xy 135.584438 -273.504914) (xy 135.537448 -273.657314)
			(xy 135.537448 -273.701764) (xy 135.893048 -273.701764)
		)
		(stroke
			(width 0)
			(type solid)
		)
		(fill yes)
		(layer "In4.Cu")
		(net "M_G_CPU1_SA_DQ<6>")
	)
	(gr_poly
		(pts
			(xy 135.893048 -272.029682) (xy 135.846058 -271.877282) (xy 135.584438 -271.877282) (xy 135.537448 -272.029682)
			(xy 135.537448 -272.074132) (xy 135.893048 -272.074132)
		)
		(stroke
			(width 0)
			(type solid)
		)
		(fill yes)
		(layer "In4.Cu")
		(net "M_F_CPU1_SA_DQ<10>")
	)
	(gr_poly
		(pts
			(xy 135.893048 -268.77391) (xy 135.846058 -268.62151) (xy 135.584438 -268.62151) (xy 135.537448 -268.77391)
			(xy 135.537448 -268.81836) (xy 135.893048 -268.81836)
		)
		(stroke
			(width 0)
			(type solid)
		)
		(fill yes)
		(layer "In4.Cu")
		(net "M_F_CPU1_SA_DQ<14>")
	)
	(gr_poly
		(pts
			(xy 135.893048 -267.146278) (xy 135.846058 -266.993878) (xy 135.584438 -266.993878) (xy 135.537448 -267.146278)
			(xy 135.537448 -267.190728) (xy 135.893048 -267.190728)
		)
		(stroke
			(width 0)
			(type solid)
		)
		(fill yes)
		(layer "In4.Cu")
		(net "M_G_CPU1_SA_DQ<18>")
	)
	(gr_poly
		(pts
			(xy 135.893048 -266.737338) (xy 135.893048 -266.693142) (xy 135.537448 -266.693142) (xy 135.537448 -266.737338)
			(xy 135.584438 -266.889738) (xy 135.846058 -266.889738)
		)
		(stroke
			(width 0)
			(type solid)
		)
		(fill yes)
		(layer "In4.Cu")
		(net "M_G_CPU1_SA_DQ<17>")
	)
	(gr_poly
		(pts
			(xy 135.893048 -263.482074) (xy 135.893048 -263.437624) (xy 135.537448 -263.437624) (xy 135.537448 -263.482074)
			(xy 135.584438 -263.634474) (xy 135.846058 -263.634474)
		)
		(stroke
			(width 0)
			(type solid)
		)
		(fill yes)
		(layer "In4.Cu")
		(net "M_G_CPU1_SA_DQ<21>")
	)
	(gr_poly
		(pts
			(xy 135.893048 -262.262874) (xy 135.846058 -262.110474) (xy 135.584438 -262.110474) (xy 135.537448 -262.262874)
			(xy 135.537448 -262.307324) (xy 135.893048 -262.307324)
		)
		(stroke
			(width 0)
			(type solid)
		)
		(fill yes)
		(layer "In4.Cu")
		(net "M_F_CPU1_SA_DQ<26>")
	)
	(gr_poly
		(pts
			(xy 135.89889 -276.913086) (xy 135.8519 -276.760686) (xy 135.59028 -276.760686) (xy 135.54329 -276.913086)
			(xy 135.54329 -276.957282) (xy 135.89889 -276.957282)
		)
		(stroke
			(width 0)
			(type solid)
		)
		(fill yes)
		(layer "In4.Cu")
		(net "M_G_CPU1_SA_DQ<3>")
	)
	(gr_poly
		(pts
			(xy 135.89889 -276.504146) (xy 135.89889 -276.45995) (xy 135.54329 -276.45995) (xy 135.54329 -276.504146)
			(xy 135.59028 -276.656546) (xy 135.8519 -276.656546)
		)
		(stroke
			(width 0)
			(type solid)
		)
		(fill yes)
		(layer "In4.Cu")
		(net "M_G_CPU1_SA_DQS_DP<0>")
	)
	(gr_poly
		(pts
			(xy 135.89889 -273.248882) (xy 135.89889 -273.204432) (xy 135.54329 -273.204432) (xy 135.54329 -273.248882)
			(xy 135.59028 -273.401282) (xy 135.8519 -273.401282)
		)
		(stroke
			(width 0)
			(type solid)
		)
		(fill yes)
		(layer "In4.Cu")
		(net "M_G_CPU1_SA_DQ<5>")
	)
	(gr_poly
		(pts
			(xy 135.89889 -268.365478) (xy 135.89889 -268.321028) (xy 135.54329 -268.321028) (xy 135.54329 -268.365478)
			(xy 135.59028 -268.517878) (xy 135.8519 -268.517878)
		)
		(stroke
			(width 0)
			(type solid)
		)
		(fill yes)
		(layer "In4.Cu")
		(net "M_F_CPU1_SA_DQ<15>")
	)
	(gr_poly
		(pts
			(xy 135.900922 -261.854442) (xy 135.900922 -261.809992) (xy 135.545322 -261.809992) (xy 135.545322 -261.854442)
			(xy 135.592312 -262.006842) (xy 135.853932 -262.006842)
		)
		(stroke
			(width 0)
			(type solid)
		)
		(fill yes)
		(layer "In4.Cu")
		(net "M_F_CPU1_SA_DQ<25>")
	)
	(gr_poly
		(pts
			(xy 135.901176 -260.22681) (xy 135.901176 -260.18236) (xy 135.545576 -260.18236) (xy 135.545576 -260.22681)
			(xy 135.592566 -260.37921) (xy 135.854186 -260.37921)
		)
		(stroke
			(width 0)
			(type solid)
		)
		(fill yes)
		(layer "In4.Cu")
		(net "M_F_CPU1_SA_DQS_DN<8>")
	)
	(gr_poly
		(pts
			(xy 135.901176 -259.007102) (xy 135.854186 -258.854702) (xy 135.592566 -258.854702) (xy 135.545576 -259.007102)
			(xy 135.545576 -259.051552) (xy 135.901176 -259.051552)
		)
		(stroke
			(width 0)
			(type solid)
		)
		(fill yes)
		(layer "In4.Cu")
		(net "M_F_CPU1_SA_DQ<30>")
	)
	(gr_poly
		(pts
			(xy 135.90143 -271.62125) (xy 135.90143 -271.5768) (xy 135.54583 -271.5768) (xy 135.54583 -271.62125)
			(xy 135.59282 -271.77365) (xy 135.85444 -271.77365)
		)
		(stroke
			(width 0)
			(type solid)
		)
		(fill yes)
		(layer "In4.Cu")
		(net "M_F_CPU1_SA_DQ<9>")
	)
	(gr_poly
		(pts
			(xy 135.90143 -270.401542) (xy 135.85444 -270.249142) (xy 135.59282 -270.249142) (xy 135.54583 -270.401542)
			(xy 135.54583 -270.445992) (xy 135.90143 -270.445992)
		)
		(stroke
			(width 0)
			(type solid)
		)
		(fill yes)
		(layer "In4.Cu")
		(net "M_F_CPU1_SA_DQS_DN<1>")
	)
	(gr_poly
		(pts
			(xy 135.90143 -269.993618) (xy 135.90143 -269.949168) (xy 135.54583 -269.949168) (xy 135.54583 -269.993618)
			(xy 135.59282 -270.146018) (xy 135.85444 -270.146018)
		)
		(stroke
			(width 0)
			(type solid)
		)
		(fill yes)
		(layer "In4.Cu")
		(net "M_F_CPU1_SA_DQS_DN<6>")
	)
	(gr_poly
		(pts
			(xy 135.90143 -265.518138) (xy 135.85444 -265.365738) (xy 135.59282 -265.365738) (xy 135.54583 -265.518138)
			(xy 135.54583 -265.562588) (xy 135.90143 -265.562588)
		)
		(stroke
			(width 0)
			(type solid)
		)
		(fill yes)
		(layer "In4.Cu")
		(net "M_G_CPU1_SA_DQS_DN<2>")
	)
	(gr_poly
		(pts
			(xy 135.90143 -265.110214) (xy 135.90143 -265.065764) (xy 135.54583 -265.065764) (xy 135.54583 -265.110214)
			(xy 135.59282 -265.262614) (xy 135.85444 -265.262614)
		)
		(stroke
			(width 0)
			(type solid)
		)
		(fill yes)
		(layer "In4.Cu")
		(net "M_G_CPU1_SA_DQS_DN<7>")
	)
	(gr_poly
		(pts
			(xy 136.147048 -229.645972) (xy 136.108694 -229.623874) (xy 135.953246 -229.588314) (xy 135.822436 -229.814882)
			(xy 135.930894 -229.931722) (xy 135.969248 -229.95382)
		)
		(stroke
			(width 0)
			(type solid)
		)
		(fill yes)
		(layer "In4.Cu")
		(net "M_G_CPU1_SB_DQ<23>")
	)
	(gr_poly
		(pts
			(xy 136.147048 -226.390454) (xy 136.108694 -226.368356) (xy 135.953246 -226.332796) (xy 135.822436 -226.559364)
			(xy 135.930894 -226.676204) (xy 135.969248 -226.698302)
		)
		(stroke
			(width 0)
			(type solid)
		)
		(fill yes)
		(layer "In4.Cu")
		(net "M_F_CPU1_SB_DQ<24>")
	)
	(gr_poly
		(pts
			(xy 136.147048 -224.762568) (xy 136.108694 -224.74047) (xy 135.953246 -224.70491) (xy 135.822436 -224.931478)
			(xy 135.930894 -225.048318) (xy 135.969248 -225.070416)
		)
		(stroke
			(width 0)
			(type solid)
		)
		(fill yes)
		(layer "In4.Cu")
		(net "M_F_CPU1_SB_DQ<25>")
	)
	(gr_poly
		(pts
			(xy 136.217406 -223.416622) (xy 136.325864 -223.299782) (xy 136.195054 -223.073214) (xy 136.039606 -223.108774)
			(xy 136.001252 -223.130872) (xy 136.179052 -223.43872)
		)
		(stroke
			(width 0)
			(type solid)
		)
		(fill yes)
		(layer "In4.Cu")
		(net "M_F_CPU1_SB_DQS_DN<8>")
	)
	(gr_poly
		(pts
			(xy 136.21766 -277.984458) (xy 136.256014 -277.96236) (xy 136.078214 -277.654512) (xy 136.03986 -277.67661)
			(xy 135.931402 -277.79345) (xy 136.062212 -278.020018)
		)
		(stroke
			(width 0)
			(type solid)
		)
		(fill yes)
		(layer "In4.Cu")
		(net "M_G_CPU1_SA_DQ<1>")
	)
	(gr_poly
		(pts
			(xy 136.219438 -274.731734) (xy 136.257792 -274.709636) (xy 136.079992 -274.401788) (xy 136.041638 -274.423886)
			(xy 135.93318 -274.540726) (xy 136.06399 -274.767294)
		)
		(stroke
			(width 0)
			(type solid)
		)
		(fill yes)
		(layer "In4.Cu")
		(net "M_G_CPU1_SA_DQ<4>")
	)
	(gr_poly
		(pts
			(xy 136.24433 -236.801914) (xy 136.19734 -236.649514) (xy 135.93572 -236.649514) (xy 135.88873 -236.801914)
			(xy 135.88873 -236.84611) (xy 136.24433 -236.84611)
		)
		(stroke
			(width 0)
			(type solid)
		)
		(fill yes)
		(layer "In4.Cu")
		(net "M_F_CPU1_SB_DQS_DP<5>")
	)
	(gr_poly
		(pts
			(xy 136.24433 -236.39399) (xy 136.24433 -236.34954) (xy 135.88873 -236.34954) (xy 135.88873 -236.39399)
			(xy 135.93572 -236.54639) (xy 136.19734 -236.54639)
		)
		(stroke
			(width 0)
			(type solid)
		)
		(fill yes)
		(layer "In4.Cu")
		(net "M_F_CPU1_SB_DQ<4>")
	)
	(gr_poly
		(pts
			(xy 136.24687 -239.648746) (xy 136.24687 -239.60455) (xy 135.89127 -239.60455) (xy 135.89127 -239.648746)
			(xy 135.93826 -239.801146) (xy 136.19988 -239.801146)
		)
		(stroke
			(width 0)
			(type solid)
		)
		(fill yes)
		(layer "In4.Cu")
		(net "M_F_CPU1_SB_DQ<0>")
	)
	(gr_poly
		(pts
			(xy 136.24687 -234.76585) (xy 136.24687 -234.7214) (xy 135.89127 -234.7214) (xy 135.89127 -234.76585)
			(xy 135.93826 -234.91825) (xy 136.19988 -234.91825)
		)
		(stroke
			(width 0)
			(type solid)
		)
		(fill yes)
		(layer "In4.Cu")
		(net "M_G_CPU1_SB_DQ<16>")
	)
	(gr_poly
		(pts
			(xy 136.24687 -222.15221) (xy 136.19988 -221.99981) (xy 135.93826 -221.99981) (xy 135.89127 -222.15221)
			(xy 135.89127 -222.196406) (xy 136.24687 -222.196406)
		)
		(stroke
			(width 0)
			(type solid)
		)
		(fill yes)
		(layer "In4.Cu")
		(net "M_F_CPU1_SB_DQS_DP<8>")
	)
	(gr_poly
		(pts
			(xy 136.24687 -221.74327) (xy 136.24687 -221.699074) (xy 135.89127 -221.699074) (xy 135.89127 -221.74327)
			(xy 135.93826 -221.89567) (xy 136.19988 -221.89567)
		)
		(stroke
			(width 0)
			(type solid)
		)
		(fill yes)
		(layer "In4.Cu")
		(net "M_F_CPU1_SB_DQS_DP<3>")
	)
	(gr_poly
		(pts
			(xy 136.252712 -240.057686) (xy 136.205722 -239.905286) (xy 135.944102 -239.905286) (xy 135.897112 -240.057686)
			(xy 135.897112 -240.102136) (xy 136.252712 -240.102136)
		)
		(stroke
			(width 0)
			(type solid)
		)
		(fill yes)
		(layer "In4.Cu")
		(net "M_G_CPU1_SB_CB<3>")
	)
	(gr_poly
		(pts
			(xy 136.252712 -235.174282) (xy 136.205722 -235.021882) (xy 135.944102 -235.021882) (xy 135.897112 -235.174282)
			(xy 135.897112 -235.218732) (xy 136.252712 -235.218732)
		)
		(stroke
			(width 0)
			(type solid)
		)
		(fill yes)
		(layer "In4.Cu")
		(net "M_F_CPU1_SB_DQ<7>")
	)
	(gr_poly
		(pts
			(xy 136.252712 -233.138218) (xy 136.252712 -233.093768) (xy 135.897112 -233.093768) (xy 135.897112 -233.138218)
			(xy 135.944102 -233.290618) (xy 136.205722 -233.290618)
		)
		(stroke
			(width 0)
			(type solid)
		)
		(fill yes)
		(layer "In4.Cu")
		(net "M_G_CPU1_SB_DQS_DP<2>")
	)
	(gr_poly
		(pts
			(xy 136.252966 -246.568722) (xy 136.205976 -246.416322) (xy 135.944356 -246.416322) (xy 135.897366 -246.568722)
			(xy 135.897366 -246.613172) (xy 136.252966 -246.613172)
		)
		(stroke
			(width 0)
			(type solid)
		)
		(fill yes)
		(layer "In4.Cu")
		(net "M_G_CPU1_SB_CS_N<0>")
	)
	(gr_poly
		(pts
			(xy 136.252966 -246.16029) (xy 136.252966 -246.11584) (xy 135.897366 -246.11584) (xy 135.897366 -246.16029)
			(xy 135.944356 -246.31269) (xy 136.205976 -246.31269)
		)
		(stroke
			(width 0)
			(type solid)
		)
		(fill yes)
		(layer "In4.Cu")
		(net "M_G_CPU1_SB_CS_N<3>")
	)
	(gr_poly
		(pts
			(xy 136.252966 -244.53215) (xy 136.252966 -244.487954) (xy 135.897366 -244.487954) (xy 135.897366 -244.53215)
			(xy 135.944356 -244.68455) (xy 136.205976 -244.68455)
		)
		(stroke
			(width 0)
			(type solid)
		)
		(fill yes)
		(layer "In4.Cu")
		(net "M_G_CPU1_SB_CB<4>")
	)
	(gr_poly
		(pts
			(xy 136.252966 -243.313458) (xy 136.205976 -243.161058) (xy 135.944356 -243.161058) (xy 135.897366 -243.313458)
			(xy 135.897366 -243.357654) (xy 136.252966 -243.357654)
		)
		(stroke
			(width 0)
			(type solid)
		)
		(fill yes)
		(layer "In4.Cu")
		(net "M_G_CPU1_SB_CB<7>")
	)
	(gr_poly
		(pts
			(xy 136.252966 -242.904518) (xy 136.252966 -242.860322) (xy 135.897366 -242.860322) (xy 135.897366 -242.904518)
			(xy 135.944356 -243.056918) (xy 136.205976 -243.056918)
		)
		(stroke
			(width 0)
			(type solid)
		)
		(fill yes)
		(layer "In4.Cu")
		(net "M_G_CPU1_SB_DQS_DP<9>")
	)
	(gr_poly
		(pts
			(xy 136.252966 -241.685318) (xy 136.205976 -241.532918) (xy 135.944356 -241.532918) (xy 135.897366 -241.685318)
			(xy 135.897366 -241.729768) (xy 136.252966 -241.729768)
		)
		(stroke
			(width 0)
			(type solid)
		)
		(fill yes)
		(layer "In4.Cu")
		(net "M_G_CPU1_SB_DQS_DP<4>")
	)
	(gr_poly
		(pts
			(xy 136.252966 -241.276886) (xy 136.252966 -241.232436) (xy 135.897366 -241.232436) (xy 135.897366 -241.276886)
			(xy 135.944356 -241.429286) (xy 136.205976 -241.429286)
		)
		(stroke
			(width 0)
			(type solid)
		)
		(fill yes)
		(layer "In4.Cu")
		(net "M_G_CPU1_SB_CB<0>")
	)
	(gr_poly
		(pts
			(xy 136.252966 -238.430054) (xy 136.205976 -238.277654) (xy 135.944356 -238.277654) (xy 135.897366 -238.430054)
			(xy 135.897366 -238.47425) (xy 136.252966 -238.47425)
		)
		(stroke
			(width 0)
			(type solid)
		)
		(fill yes)
		(layer "In4.Cu")
		(net "M_F_CPU1_SB_DQ<3>")
	)
	(gr_poly
		(pts
			(xy 136.252966 -238.021114) (xy 136.252966 -237.976918) (xy 135.897366 -237.976918) (xy 135.897366 -238.021114)
			(xy 135.944356 -238.173514) (xy 136.205976 -238.173514)
		)
		(stroke
			(width 0)
			(type solid)
		)
		(fill yes)
		(layer "In4.Cu")
		(net "M_F_CPU1_SB_DQS_DP<0>")
	)
	(gr_poly
		(pts
			(xy 136.252966 -233.54665) (xy 136.205976 -233.39425) (xy 135.944356 -233.39425) (xy 135.897366 -233.54665)
			(xy 135.897366 -233.590846) (xy 136.252966 -233.590846)
		)
		(stroke
			(width 0)
			(type solid)
		)
		(fill yes)
		(layer "In4.Cu")
		(net "M_G_CPU1_SB_DQ<19>")
	)
	(gr_poly
		(pts
			(xy 136.252966 -231.919018) (xy 136.205976 -231.766618) (xy 135.944356 -231.766618) (xy 135.897366 -231.919018)
			(xy 135.897366 -231.963214) (xy 136.252966 -231.963214)
		)
		(stroke
			(width 0)
			(type solid)
		)
		(fill yes)
		(layer "In4.Cu")
		(net "M_G_CPU1_SB_DQS_DP<7>")
	)
	(gr_poly
		(pts
			(xy 136.252966 -231.510078) (xy 136.252966 -231.465882) (xy 135.897366 -231.465882) (xy 135.897366 -231.510078)
			(xy 135.944356 -231.662478) (xy 136.205976 -231.662478)
		)
		(stroke
			(width 0)
			(type solid)
		)
		(fill yes)
		(layer "In4.Cu")
		(net "M_G_CPU1_SB_DQ<20>")
	)
	(gr_poly
		(pts
			(xy 136.252966 -220.115638) (xy 136.252966 -220.071188) (xy 135.897366 -220.071188) (xy 135.897366 -220.115638)
			(xy 135.944356 -220.268038) (xy 136.205976 -220.268038)
		)
		(stroke
			(width 0)
			(type solid)
		)
		(fill yes)
		(layer "In4.Cu")
		(net "M_F_CPU1_SB_DQ<30>")
	)
	(gr_poly
		(pts
			(xy 136.252966 -218.896438) (xy 136.205976 -218.744038) (xy 135.944356 -218.744038) (xy 135.897366 -218.896438)
			(xy 135.897366 -218.940888) (xy 136.252966 -218.940888)
		)
		(stroke
			(width 0)
			(type solid)
		)
		(fill yes)
		(layer "In4.Cu")
		(net "M_F_CPU1_SB_DQ<31>")
	)
	(gr_poly
		(pts
			(xy 136.325864 -225.479102) (xy 136.217406 -225.362262) (xy 136.179052 -225.340164) (xy 136.001252 -225.648012)
			(xy 136.039606 -225.67011) (xy 136.195054 -225.70567)
		)
		(stroke
			(width 0)
			(type solid)
		)
		(fill yes)
		(layer "In4.Cu")
		(net "M_F_CPU1_SB_DQ<27>")
	)
	(gr_poly
		(pts
			(xy 136.327896 -230.358442) (xy 136.219438 -230.241602) (xy 136.181084 -230.219504) (xy 136.003284 -230.527352)
			(xy 136.041638 -230.54945) (xy 136.197086 -230.58501)
		)
		(stroke
			(width 0)
			(type solid)
		)
		(fill yes)
		(layer "In4.Cu")
		(net "M_G_CPU1_SB_DQ<21>")
	)
	(gr_poly
		(pts
			(xy 136.327896 -227.102924) (xy 136.219438 -226.986084) (xy 136.181084 -226.963986) (xy 136.003284 -227.271834)
			(xy 136.041638 -227.293932) (xy 136.197086 -227.329492)
		)
		(stroke
			(width 0)
			(type solid)
		)
		(fill yes)
		(layer "In4.Cu")
		(net "M_F_CPU1_SB_DQ<26>")
	)
	(gr_poly
		(pts
			(xy 136.327896 -223.847406) (xy 136.219438 -223.730566) (xy 136.181084 -223.708468) (xy 136.003284 -224.016316)
			(xy 136.041638 -224.038414) (xy 136.197086 -224.073974)
		)
		(stroke
			(width 0)
			(type solid)
		)
		(fill yes)
		(layer "In4.Cu")
		(net "M_F_CPU1_SB_DQS_DN<8>")
	)
	(gr_poly
		(pts
			(xy 136.329166 -277.367492) (xy 136.437624 -277.250652) (xy 136.306814 -277.024084) (xy 136.151366 -277.059644)
			(xy 136.113012 -277.081742) (xy 136.290812 -277.38959)
		)
		(stroke
			(width 0)
			(type solid)
		)
		(fill yes)
		(layer "In4.Cu")
		(net "M_G_CPU1_SA_DQ<3>")
	)
	(gr_poly
		(pts
			(xy 136.329166 -274.111974) (xy 136.437624 -273.995134) (xy 136.306814 -273.768566) (xy 136.151366 -273.804126)
			(xy 136.113012 -273.826224) (xy 136.290812 -274.134072)
		)
		(stroke
			(width 0)
			(type solid)
		)
		(fill yes)
		(layer "In4.Cu")
		(net "M_G_CPU1_SA_DQ<6>")
	)
	(gr_poly
		(pts
			(xy 136.354058 -259.820918) (xy 136.307068 -259.668518) (xy 136.045448 -259.668518) (xy 135.998458 -259.820918)
			(xy 135.998458 -259.865368) (xy 136.354058 -259.865368)
		)
		(stroke
			(width 0)
			(type solid)
		)
		(fill yes)
		(layer "In4.Cu")
		(net "M_F_CPU1_SA_DQS_DP<8>")
	)
	(gr_poly
		(pts
			(xy 136.354058 -259.412994) (xy 136.354058 -259.368544) (xy 135.998458 -259.368544) (xy 135.998458 -259.412994)
			(xy 136.045448 -259.565394) (xy 136.307068 -259.565394)
		)
		(stroke
			(width 0)
			(type solid)
		)
		(fill yes)
		(layer "In4.Cu")
		(net "M_F_CPU1_SA_DQ<28>")
	)
	(gr_poly
		(pts
			(xy 136.354312 -275.690584) (xy 136.354312 -275.646388) (xy 135.998712 -275.646388) (xy 135.998712 -275.690584)
			(xy 136.045702 -275.842984) (xy 136.307322 -275.842984)
		)
		(stroke
			(width 0)
			(type solid)
		)
		(fill yes)
		(layer "In4.Cu")
		(net "M_G_CPU1_SA_DQS_DN<5>")
	)
	(gr_poly
		(pts
			(xy 136.354312 -272.435066) (xy 136.354312 -272.39087) (xy 135.998712 -272.39087) (xy 135.998712 -272.435066)
			(xy 136.045702 -272.587466) (xy 136.307322 -272.587466)
		)
		(stroke
			(width 0)
			(type solid)
		)
		(fill yes)
		(layer "In4.Cu")
		(net "M_F_CPU1_SA_DQ<8>")
	)
	(gr_poly
		(pts
			(xy 136.354312 -271.215358) (xy 136.307322 -271.062958) (xy 136.045702 -271.062958) (xy 135.998712 -271.215358)
			(xy 135.998712 -271.259808) (xy 136.354312 -271.259808)
		)
		(stroke
			(width 0)
			(type solid)
		)
		(fill yes)
		(layer "In4.Cu")
		(net "M_F_CPU1_SA_DQ<11>")
	)
	(gr_poly
		(pts
			(xy 136.354312 -270.807434) (xy 136.354312 -270.762984) (xy 135.998712 -270.762984) (xy 135.998712 -270.807434)
			(xy 136.045702 -270.959834) (xy 136.307322 -270.959834)
		)
		(stroke
			(width 0)
			(type solid)
		)
		(fill yes)
		(layer "In4.Cu")
		(net "M_F_CPU1_SA_DQS_DP<1>")
	)
	(gr_poly
		(pts
			(xy 136.354312 -269.587726) (xy 136.307322 -269.435326) (xy 136.045702 -269.435326) (xy 135.998712 -269.587726)
			(xy 135.998712 -269.631922) (xy 136.354312 -269.631922)
		)
		(stroke
			(width 0)
			(type solid)
		)
		(fill yes)
		(layer "In4.Cu")
		(net "M_F_CPU1_SA_DQS_DP<6>")
	)
	(gr_poly
		(pts
			(xy 136.354312 -265.92403) (xy 136.354312 -265.879834) (xy 135.998712 -265.879834) (xy 135.998712 -265.92403)
			(xy 136.045702 -266.07643) (xy 136.307322 -266.07643)
		)
		(stroke
			(width 0)
			(type solid)
		)
		(fill yes)
		(layer "In4.Cu")
		(net "M_G_CPU1_SA_DQS_DP<2>")
	)
	(gr_poly
		(pts
			(xy 136.354312 -264.704322) (xy 136.307322 -264.551922) (xy 136.045702 -264.551922) (xy 135.998712 -264.704322)
			(xy 135.998712 -264.748772) (xy 136.354312 -264.748772)
		)
		(stroke
			(width 0)
			(type solid)
		)
		(fill yes)
		(layer "In4.Cu")
		(net "M_G_CPU1_SA_DQS_DP<7>")
	)
	(gr_poly
		(pts
			(xy 136.356598 -261.449058) (xy 136.309608 -261.296658) (xy 136.047988 -261.296658) (xy 136.000998 -261.449058)
			(xy 136.000998 -261.493508) (xy 136.356598 -261.493508)
		)
		(stroke
			(width 0)
			(type solid)
		)
		(fill yes)
		(layer "In4.Cu")
		(net "M_F_CPU1_SA_DQ<27>")
	)
	(gr_poly
		(pts
			(xy 136.356598 -261.040626) (xy 136.356598 -260.996176) (xy 136.000998 -260.996176) (xy 136.000998 -261.040626)
			(xy 136.047988 -261.193026) (xy 136.309608 -261.193026)
		)
		(stroke
			(width 0)
			(type solid)
		)
		(fill yes)
		(layer "In4.Cu")
		(net "M_F_CPU1_SA_DQS_DP<3>")
	)
	(gr_poly
		(pts
			(xy 136.362694 -279.354788) (xy 136.315704 -279.202388) (xy 136.054084 -279.202388) (xy 136.007094 -279.354788)
			(xy 136.007094 -279.398984) (xy 136.362694 -279.398984)
		)
		(stroke
			(width 0)
			(type solid)
		)
		(fill yes)
		(layer "In4.Cu")
		(net "M_G_CPU1_SA_DQ<2>")
	)
	(gr_poly
		(pts
			(xy 136.362694 -276.09927) (xy 136.315704 -275.94687) (xy 136.054084 -275.94687) (xy 136.007094 -276.09927)
			(xy 136.007094 -276.143466) (xy 136.362694 -276.143466)
		)
		(stroke
			(width 0)
			(type solid)
		)
		(fill yes)
		(layer "In4.Cu")
		(net "M_G_CPU1_SA_DQS_DN<0>")
	)
	(gr_poly
		(pts
			(xy 136.362694 -272.843498) (xy 136.315704 -272.691098) (xy 136.054084 -272.691098) (xy 136.007094 -272.843498)
			(xy 136.007094 -272.887948) (xy 136.362694 -272.887948)
		)
		(stroke
			(width 0)
			(type solid)
		)
		(fill yes)
		(layer "In4.Cu")
		(net "M_G_CPU1_SA_DQ<7>")
	)
	(gr_poly
		(pts
			(xy 136.362694 -269.179294) (xy 136.362694 -269.134844) (xy 136.007094 -269.134844) (xy 136.007094 -269.179294)
			(xy 136.054084 -269.331694) (xy 136.315704 -269.331694)
		)
		(stroke
			(width 0)
			(type solid)
		)
		(fill yes)
		(layer "In4.Cu")
		(net "M_F_CPU1_SA_DQ<12>")
	)
	(gr_poly
		(pts
			(xy 136.362694 -267.960094) (xy 136.315704 -267.807694) (xy 136.054084 -267.807694) (xy 136.007094 -267.960094)
			(xy 136.007094 -268.004544) (xy 136.362694 -268.004544)
		)
		(stroke
			(width 0)
			(type solid)
		)
		(fill yes)
		(layer "In4.Cu")
		(net "M_F_CPU1_SA_DQ<13>")
	)
	(gr_poly
		(pts
			(xy 136.362694 -266.332462) (xy 136.315704 -266.180062) (xy 136.054084 -266.180062) (xy 136.007094 -266.332462)
			(xy 136.007094 -266.376658) (xy 136.362694 -266.376658)
		)
		(stroke
			(width 0)
			(type solid)
		)
		(fill yes)
		(layer "In4.Cu")
		(net "M_G_CPU1_SA_DQ<19>")
	)
	(gr_poly
		(pts
			(xy 136.362694 -264.29589) (xy 136.362694 -264.251694) (xy 136.007094 -264.251694) (xy 136.007094 -264.29589)
			(xy 136.054084 -264.44829) (xy 136.315704 -264.44829)
		)
		(stroke
			(width 0)
			(type solid)
		)
		(fill yes)
		(layer "In4.Cu")
		(net "M_G_CPU1_SA_DQ<20>")
	)
	(gr_poly
		(pts
			(xy 136.362694 -262.668258) (xy 136.362694 -262.623808) (xy 136.007094 -262.623808) (xy 136.007094 -262.668258)
			(xy 136.054084 -262.820658) (xy 136.315704 -262.820658)
		)
		(stroke
			(width 0)
			(type solid)
		)
		(fill yes)
		(layer "In4.Cu")
		(net "M_F_CPU1_SA_DQ<24>")
	)
	(gr_poly
		(pts
			(xy 136.36498 -263.07669) (xy 136.31799 -262.92429) (xy 136.05637 -262.92429) (xy 136.00938 -263.07669)
			(xy 136.00938 -263.12114) (xy 136.36498 -263.12114)
		)
		(stroke
			(width 0)
			(type solid)
		)
		(fill yes)
		(layer "In4.Cu")
		(net "M_G_CPU1_SA_DQ<23>")
	)
	(gr_poly
		(pts
			(xy 136.365996 -267.551154) (xy 136.365996 -267.506958) (xy 136.010396 -267.506958) (xy 136.010396 -267.551154)
			(xy 136.057386 -267.703554) (xy 136.319006 -267.703554)
		)
		(stroke
			(width 0)
			(type solid)
		)
		(fill yes)
		(layer "In4.Cu")
		(net "M_G_CPU1_SA_DQ<16>")
	)
	(gr_poly
		(pts
			(xy 136.36879 -258.193286) (xy 136.3218 -258.040886) (xy 136.06018 -258.040886) (xy 136.01319 -258.193286)
			(xy 136.01319 -258.237482) (xy 136.36879 -258.237482)
		)
		(stroke
			(width 0)
			(type solid)
		)
		(fill yes)
		(layer "In4.Cu")
		(net "M_F_CPU1_SA_DQ<31>")
	)
	(gr_poly
		(pts
			(xy 136.36879 -257.784854) (xy 136.36879 -257.740658) (xy 136.01319 -257.740658) (xy 136.01319 -257.784854)
			(xy 136.06018 -257.937254) (xy 136.3218 -257.937254)
		)
		(stroke
			(width 0)
			(type solid)
		)
		(fill yes)
		(layer "In4.Cu")
		(net "M_G_CPU1_SA_CS_N<0>")
	)
	(gr_poly
		(pts
			(xy 136.612376 -228.839268) (xy 136.574022 -228.81717) (xy 136.418574 -228.78161) (xy 136.287764 -229.008178)
			(xy 136.396222 -229.125018) (xy 136.434576 -229.147116)
		)
		(stroke
			(width 0)
			(type solid)
		)
		(fill yes)
		(layer "In4.Cu")
		(net "M_G_CPU1_SB_DQ<23>")
	)
	(gr_poly
		(pts
			(xy 136.616948 -230.459788) (xy 136.578594 -230.43769) (xy 136.423146 -230.40213) (xy 136.292336 -230.628698)
			(xy 136.400794 -230.745538) (xy 136.439148 -230.767636)
		)
		(stroke
			(width 0)
			(type solid)
		)
		(fill yes)
		(layer "In4.Cu")
		(net "M_G_CPU1_SB_DQ<22>")
	)
	(gr_poly
		(pts
			(xy 136.61771 -225.574606) (xy 136.579356 -225.552508) (xy 136.423908 -225.516948) (xy 136.293098 -225.743516)
			(xy 136.401556 -225.860356) (xy 136.43991 -225.882454)
		)
		(stroke
			(width 0)
			(type solid)
		)
		(fill yes)
		(layer "In4.Cu")
		(net "M_F_CPU1_SB_DQ<24>")
	)
	(gr_poly
		(pts
			(xy 136.617964 -223.946212) (xy 136.57961 -223.924114) (xy 136.424162 -223.888554) (xy 136.293352 -224.115122)
			(xy 136.40181 -224.231962) (xy 136.440164 -224.25406)
		)
		(stroke
			(width 0)
			(type solid)
		)
		(fill yes)
		(layer "In4.Cu")
		(net "M_F_CPU1_SB_DQ<25>")
	)
	(gr_poly
		(pts
			(xy 136.61898 -220.68917) (xy 136.580626 -220.667072) (xy 136.425178 -220.631512) (xy 136.294368 -220.85808)
			(xy 136.402826 -220.97492) (xy 136.44118 -220.997018)
		)
		(stroke
			(width 0)
			(type solid)
		)
		(fill yes)
		(layer "In4.Cu")
		(net "M_F_CPU1_SB_DQS_DN<3>")
	)
	(gr_poly
		(pts
			(xy 136.685782 -278.795226) (xy 136.724136 -278.773128) (xy 136.546336 -278.46528) (xy 136.507982 -278.487378)
			(xy 136.399524 -278.604218) (xy 136.530334 -278.830786)
		)
		(stroke
			(width 0)
			(type solid)
		)
		(fill yes)
		(layer "In4.Cu")
		(net "M_G_CPU1_SA_DQ<1>")
	)
	(gr_poly
		(pts
			(xy 136.688322 -277.171404) (xy 136.726676 -277.149306) (xy 136.548876 -276.841458) (xy 136.510522 -276.863556)
			(xy 136.402064 -276.980396) (xy 136.532874 -277.206964)
		)
		(stroke
			(width 0)
			(type solid)
		)
		(fill yes)
		(layer "In4.Cu")
		(net "M_G_CPU1_SA_DQS_DP<0>")
	)
	(gr_poly
		(pts
			(xy 136.688322 -273.915886) (xy 136.726676 -273.893788) (xy 136.548876 -273.58594) (xy 136.510522 -273.608038)
			(xy 136.402064 -273.724878) (xy 136.532874 -273.951446)
		)
		(stroke
			(width 0)
			(type solid)
		)
		(fill yes)
		(layer "In4.Cu")
		(net "M_G_CPU1_SA_DQ<5>")
	)
	(gr_poly
		(pts
			(xy 136.71677 -219.710254) (xy 136.66978 -219.557854) (xy 136.40816 -219.557854) (xy 136.36117 -219.710254)
			(xy 136.36117 -219.754704) (xy 136.71677 -219.754704)
		)
		(stroke
			(width 0)
			(type solid)
		)
		(fill yes)
		(layer "In4.Cu")
		(net "M_F_CPU1_SB_DQ<28>")
	)
	(gr_poly
		(pts
			(xy 136.71677 -219.301822) (xy 136.71677 -219.257372) (xy 136.36117 -219.257372) (xy 136.36117 -219.301822)
			(xy 136.40816 -219.454222) (xy 136.66978 -219.454222)
		)
		(stroke
			(width 0)
			(type solid)
		)
		(fill yes)
		(layer "In4.Cu")
		(net "M_F_CPU1_SB_DQ<29>")
	)
	(gr_poly
		(pts
			(xy 136.722866 -246.974106) (xy 136.722866 -246.929656) (xy 136.367266 -246.929656) (xy 136.367266 -246.974106)
			(xy 136.414256 -247.126506) (xy 136.675876 -247.126506)
		)
		(stroke
			(width 0)
			(type solid)
		)
		(fill yes)
		(layer "In4.Cu")
		(net "M_G_CPU1_SB_CS_N<2>")
	)
	(gr_poly
		(pts
			(xy 136.722866 -244.127274) (xy 136.675876 -243.974874) (xy 136.414256 -243.974874) (xy 136.367266 -244.127274)
			(xy 136.367266 -244.17147) (xy 136.722866 -244.17147)
		)
		(stroke
			(width 0)
			(type solid)
		)
		(fill yes)
		(layer "In4.Cu")
		(net "M_G_CPU1_SB_CB<6>")
	)
	(gr_poly
		(pts
			(xy 136.722866 -243.718334) (xy 136.722866 -243.674138) (xy 136.367266 -243.674138) (xy 136.367266 -243.718334)
			(xy 136.414256 -243.870734) (xy 136.675876 -243.870734)
		)
		(stroke
			(width 0)
			(type solid)
		)
		(fill yes)
		(layer "In4.Cu")
		(net "M_G_CPU1_SB_CB<5>")
	)
	(gr_poly
		(pts
			(xy 136.722866 -242.499134) (xy 136.675876 -242.346734) (xy 136.414256 -242.346734) (xy 136.367266 -242.499134)
			(xy 136.367266 -242.543584) (xy 136.722866 -242.543584)
		)
		(stroke
			(width 0)
			(type solid)
		)
		(fill yes)
		(layer "In4.Cu")
		(net "M_G_CPU1_SB_DQS_DN<9>")
	)
	(gr_poly
		(pts
			(xy 136.722866 -242.090702) (xy 136.722866 -242.046252) (xy 136.367266 -242.046252) (xy 136.367266 -242.090702)
			(xy 136.414256 -242.243102) (xy 136.675876 -242.243102)
		)
		(stroke
			(width 0)
			(type solid)
		)
		(fill yes)
		(layer "In4.Cu")
		(net "M_G_CPU1_SB_DQS_DN<4>")
	)
	(gr_poly
		(pts
			(xy 136.722866 -240.871502) (xy 136.675876 -240.719102) (xy 136.414256 -240.719102) (xy 136.367266 -240.871502)
			(xy 136.367266 -240.915952) (xy 136.722866 -240.915952)
		)
		(stroke
			(width 0)
			(type solid)
		)
		(fill yes)
		(layer "In4.Cu")
		(net "M_G_CPU1_SB_CB<2>")
	)
	(gr_poly
		(pts
			(xy 136.722866 -238.83493) (xy 136.722866 -238.790734) (xy 136.367266 -238.790734) (xy 136.367266 -238.83493)
			(xy 136.414256 -238.98733) (xy 136.675876 -238.98733)
		)
		(stroke
			(width 0)
			(type solid)
		)
		(fill yes)
		(layer "In4.Cu")
		(net "M_F_CPU1_SB_DQ<1>")
	)
	(gr_poly
		(pts
			(xy 136.722866 -237.61573) (xy 136.675876 -237.46333) (xy 136.414256 -237.46333) (xy 136.367266 -237.61573)
			(xy 136.367266 -237.66018) (xy 136.722866 -237.66018)
		)
		(stroke
			(width 0)
			(type solid)
		)
		(fill yes)
		(layer "In4.Cu")
		(net "M_F_CPU1_SB_DQS_DN<0>")
	)
	(gr_poly
		(pts
			(xy 136.722866 -233.952034) (xy 136.722866 -233.907584) (xy 136.367266 -233.907584) (xy 136.367266 -233.952034)
			(xy 136.414256 -234.104434) (xy 136.675876 -234.104434)
		)
		(stroke
			(width 0)
			(type solid)
		)
		(fill yes)
		(layer "In4.Cu")
		(net "M_G_CPU1_SB_DQ<17>")
	)
	(gr_poly
		(pts
			(xy 136.722866 -232.732834) (xy 136.675876 -232.580434) (xy 136.414256 -232.580434) (xy 136.367266 -232.732834)
			(xy 136.367266 -232.77703) (xy 136.722866 -232.77703)
		)
		(stroke
			(width 0)
			(type solid)
		)
		(fill yes)
		(layer "In4.Cu")
		(net "M_G_CPU1_SB_DQS_DN<2>")
	)
	(gr_poly
		(pts
			(xy 136.722866 -232.323894) (xy 136.722866 -232.279698) (xy 136.367266 -232.279698) (xy 136.367266 -232.323894)
			(xy 136.414256 -232.476294) (xy 136.675876 -232.476294)
		)
		(stroke
			(width 0)
			(type solid)
		)
		(fill yes)
		(layer "In4.Cu")
		(net "M_G_CPU1_SB_DQS_DN<7>")
	)
	(gr_poly
		(pts
			(xy 136.728708 -222.557086) (xy 136.728708 -222.51289) (xy 136.373108 -222.51289) (xy 136.373108 -222.557086)
			(xy 136.420098 -222.709486) (xy 136.681718 -222.709486)
		)
		(stroke
			(width 0)
			(type solid)
		)
		(fill yes)
		(layer "In4.Cu")
		(net "M_F_CPU1_SB_DQS_DN<8>")
	)
	(gr_poly
		(pts
			(xy 136.731248 -240.46307) (xy 136.731248 -240.418874) (xy 136.375648 -240.418874) (xy 136.375648 -240.46307)
			(xy 136.422638 -240.61547) (xy 136.684258 -240.61547)
		)
		(stroke
			(width 0)
			(type solid)
		)
		(fill yes)
		(layer "In4.Cu")
		(net "M_G_CPU1_SB_CB<1>")
	)
	(gr_poly
		(pts
			(xy 136.731248 -239.243362) (xy 136.684258 -239.090962) (xy 136.422638 -239.090962) (xy 136.375648 -239.243362)
			(xy 136.375648 -239.287812) (xy 136.731248 -239.287812)
		)
		(stroke
			(width 0)
			(type solid)
		)
		(fill yes)
		(layer "In4.Cu")
		(net "M_F_CPU1_SB_DQ<2>")
	)
	(gr_poly
		(pts
			(xy 136.731248 -237.207806) (xy 136.731248 -237.163356) (xy 136.375648 -237.163356) (xy 136.375648 -237.207806)
			(xy 136.422638 -237.360206) (xy 136.684258 -237.360206)
		)
		(stroke
			(width 0)
			(type solid)
		)
		(fill yes)
		(layer "In4.Cu")
		(net "M_F_CPU1_SB_DQS_DN<5>")
	)
	(gr_poly
		(pts
			(xy 136.731248 -235.988098) (xy 136.684258 -235.835698) (xy 136.422638 -235.835698) (xy 136.375648 -235.988098)
			(xy 136.375648 -236.032294) (xy 136.731248 -236.032294)
		)
		(stroke
			(width 0)
			(type solid)
		)
		(fill yes)
		(layer "In4.Cu")
		(net "M_F_CPU1_SB_DQ<6>")
	)
	(gr_poly
		(pts
			(xy 136.731248 -235.579666) (xy 136.731248 -235.53547) (xy 136.375648 -235.53547) (xy 136.375648 -235.579666)
			(xy 136.422638 -235.732066) (xy 136.684258 -235.732066)
		)
		(stroke
			(width 0)
			(type solid)
		)
		(fill yes)
		(layer "In4.Cu")
		(net "M_F_CPU1_SB_DQ<5>")
	)
	(gr_poly
		(pts
			(xy 136.731248 -234.360466) (xy 136.684258 -234.208066) (xy 136.422638 -234.208066) (xy 136.375648 -234.360466)
			(xy 136.375648 -234.404662) (xy 136.731248 -234.404662)
		)
		(stroke
			(width 0)
			(type solid)
		)
		(fill yes)
		(layer "In4.Cu")
		(net "M_G_CPU1_SB_DQ<18>")
	)
	(gr_poly
		(pts
			(xy 136.795764 -231.176322) (xy 136.687306 -231.059482) (xy 136.648952 -231.037384) (xy 136.471152 -231.345232)
			(xy 136.509506 -231.36733) (xy 136.664954 -231.40289)
		)
		(stroke
			(width 0)
			(type solid)
		)
		(fill yes)
		(layer "In4.Cu")
		(net "M_G_CPU1_SB_DQ<20>")
	)
	(gr_poly
		(pts
			(xy 136.797034 -278.177498) (xy 136.905492 -278.060658) (xy 136.774682 -277.83409) (xy 136.619234 -277.86965)
			(xy 136.58088 -277.891748) (xy 136.75868 -278.199596)
		)
		(stroke
			(width 0)
			(type solid)
		)
		(fill yes)
		(layer "In4.Cu")
		(net "M_G_CPU1_SA_DQ<3>")
	)
	(gr_poly
		(pts
			(xy 136.797796 -229.544626) (xy 136.689338 -229.427786) (xy 136.650984 -229.405688) (xy 136.473184 -229.713536)
			(xy 136.511538 -229.735634) (xy 136.666986 -229.771194)
		)
		(stroke
			(width 0)
			(type solid)
		)
		(fill yes)
		(layer "In4.Cu")
		(net "M_G_CPU1_SB_DQ<21>")
	)
	(gr_poly
		(pts
			(xy 136.797796 -226.289108) (xy 136.689338 -226.172268) (xy 136.650984 -226.15017) (xy 136.473184 -226.458018)
			(xy 136.511538 -226.480116) (xy 136.666986 -226.515676)
		)
		(stroke
			(width 0)
			(type solid)
		)
		(fill yes)
		(layer "In4.Cu")
		(net "M_F_CPU1_SB_DQ<26>")
	)
	(gr_poly
		(pts
			(xy 136.797796 -224.661222) (xy 136.689338 -224.544382) (xy 136.650984 -224.522284) (xy 136.473184 -224.830132)
			(xy 136.511538 -224.85223) (xy 136.666986 -224.88779)
		)
		(stroke
			(width 0)
			(type solid)
		)
		(fill yes)
		(layer "In4.Cu")
		(net "M_F_CPU1_SB_DQ<27>")
	)
	(gr_poly
		(pts
			(xy 136.799066 -276.553676) (xy 136.907524 -276.436836) (xy 136.776714 -276.210268) (xy 136.621266 -276.245828)
			(xy 136.582912 -276.267926) (xy 136.760712 -276.575774)
		)
		(stroke
			(width 0)
			(type solid)
		)
		(fill yes)
		(layer "In4.Cu")
		(net "M_G_CPU1_SA_DQS_DN<0>")
	)
	(gr_poly
		(pts
			(xy 136.799066 -273.298158) (xy 136.907524 -273.181318) (xy 136.776714 -272.95475) (xy 136.621266 -272.99031)
			(xy 136.582912 -273.012408) (xy 136.760712 -273.320256)
		)
		(stroke
			(width 0)
			(type solid)
		)
		(fill yes)
		(layer "In4.Cu")
		(net "M_G_CPU1_SA_DQ<7>")
	)
	(gr_poly
		(pts
			(xy 136.802114 -221.398592) (xy 136.693656 -221.281752) (xy 136.655302 -221.259654) (xy 136.477502 -221.567502)
			(xy 136.515856 -221.5896) (xy 136.671304 -221.62516)
		)
		(stroke
			(width 0)
			(type solid)
		)
		(fill yes)
		(layer "In4.Cu")
		(net "M_F_CPU1_SB_DQS_DP<3>")
	)
	(gr_poly
		(pts
			(xy 136.824212 -258.599178) (xy 136.824212 -258.554728) (xy 136.468612 -258.554728) (xy 136.468612 -258.599178)
			(xy 136.515602 -258.751578) (xy 136.777222 -258.751578)
		)
		(stroke
			(width 0)
			(type solid)
		)
		(fill yes)
		(layer "In4.Cu")
		(net "M_F_CPU1_SA_DQ<29>")
	)
	(gr_poly
		(pts
			(xy 136.832594 -279.759664) (xy 136.832594 -279.715468) (xy 136.476994 -279.715468) (xy 136.476994 -279.759664)
			(xy 136.523984 -279.912064) (xy 136.785604 -279.912064)
		)
		(stroke
			(width 0)
			(type solid)
		)
		(fill yes)
		(layer "In4.Cu")
		(net "M_G_CPU1_SA_DQ<0>")
	)
	(gr_poly
		(pts
			(xy 136.832594 -268.77391) (xy 136.785604 -268.62151) (xy 136.523984 -268.62151) (xy 136.476994 -268.77391)
			(xy 136.476994 -268.81836) (xy 136.832594 -268.81836)
		)
		(stroke
			(width 0)
			(type solid)
		)
		(fill yes)
		(layer "In4.Cu")
		(net "M_F_CPU1_SA_DQ<14>")
	)
	(gr_poly
		(pts
			(xy 136.832594 -268.365478) (xy 136.832594 -268.321028) (xy 136.476994 -268.321028) (xy 136.476994 -268.365478)
			(xy 136.523984 -268.517878) (xy 136.785604 -268.517878)
		)
		(stroke
			(width 0)
			(type solid)
		)
		(fill yes)
		(layer "In4.Cu")
		(net "M_F_CPU1_SA_DQ<15>")
	)
	(gr_poly
		(pts
			(xy 136.832594 -267.146278) (xy 136.785604 -266.993878) (xy 136.523984 -266.993878) (xy 136.476994 -267.146278)
			(xy 136.476994 -267.190474) (xy 136.832594 -267.190474)
		)
		(stroke
			(width 0)
			(type solid)
		)
		(fill yes)
		(layer "In4.Cu")
		(net "M_G_CPU1_SA_DQ<18>")
	)
	(gr_poly
		(pts
			(xy 136.832594 -266.737846) (xy 136.832594 -266.693396) (xy 136.476994 -266.693396) (xy 136.476994 -266.737846)
			(xy 136.523984 -266.890246) (xy 136.785604 -266.890246)
		)
		(stroke
			(width 0)
			(type solid)
		)
		(fill yes)
		(layer "In4.Cu")
		(net "M_G_CPU1_SA_DQ<17>")
	)
	(gr_poly
		(pts
			(xy 136.832594 -263.891014) (xy 136.785604 -263.738614) (xy 136.523984 -263.738614) (xy 136.476994 -263.891014)
			(xy 136.476994 -263.93521) (xy 136.832594 -263.93521)
		)
		(stroke
			(width 0)
			(type solid)
		)
		(fill yes)
		(layer "In4.Cu")
		(net "M_G_CPU1_SA_DQ<22>")
	)
	(gr_poly
		(pts
			(xy 136.832594 -263.482074) (xy 136.832594 -263.437878) (xy 136.476994 -263.437878) (xy 136.476994 -263.482074)
			(xy 136.523984 -263.634474) (xy 136.785604 -263.634474)
		)
		(stroke
			(width 0)
			(type solid)
		)
		(fill yes)
		(layer "In4.Cu")
		(net "M_G_CPU1_SA_DQ<21>")
	)
	(gr_poly
		(pts
			(xy 136.832594 -262.262874) (xy 136.785604 -262.110474) (xy 136.523984 -262.110474) (xy 136.476994 -262.262874)
			(xy 136.476994 -262.307324) (xy 136.832594 -262.307324)
		)
		(stroke
			(width 0)
			(type solid)
		)
		(fill yes)
		(layer "In4.Cu")
		(net "M_F_CPU1_SA_DQ<26>")
	)
	(gr_poly
		(pts
			(xy 136.838436 -261.854442) (xy 136.838436 -261.809992) (xy 136.482836 -261.809992) (xy 136.482836 -261.854442)
			(xy 136.529826 -262.006842) (xy 136.791446 -262.006842)
		)
		(stroke
			(width 0)
			(type solid)
		)
		(fill yes)
		(layer "In4.Cu")
		(net "M_F_CPU1_SA_DQ<25>")
	)
	(gr_poly
		(pts
			(xy 136.838436 -260.635242) (xy 136.791446 -260.482842) (xy 136.529826 -260.482842) (xy 136.482836 -260.635242)
			(xy 136.482836 -260.679438) (xy 136.838436 -260.679438)
		)
		(stroke
			(width 0)
			(type solid)
		)
		(fill yes)
		(layer "In4.Cu")
		(net "M_F_CPU1_SA_DQS_DN<3>")
	)
	(gr_poly
		(pts
			(xy 136.840722 -260.22681) (xy 136.840722 -260.18236) (xy 136.485122 -260.18236) (xy 136.485122 -260.22681)
			(xy 136.532112 -260.37921) (xy 136.793732 -260.37921)
		)
		(stroke
			(width 0)
			(type solid)
		)
		(fill yes)
		(layer "In4.Cu")
		(net "M_F_CPU1_SA_DQS_DN<8>")
	)
	(gr_poly
		(pts
			(xy 136.840722 -259.007102) (xy 136.793732 -258.854702) (xy 136.532112 -258.854702) (xy 136.485122 -259.007102)
			(xy 136.485122 -259.051552) (xy 136.840722 -259.051552)
		)
		(stroke
			(width 0)
			(type solid)
		)
		(fill yes)
		(layer "In4.Cu")
		(net "M_F_CPU1_SA_DQ<30>")
	)
	(gr_poly
		(pts
			(xy 136.84123 -275.284946) (xy 136.79424 -275.132546) (xy 136.53262 -275.132546) (xy 136.48563 -275.284946)
			(xy 136.48563 -275.329396) (xy 136.84123 -275.329396)
		)
		(stroke
			(width 0)
			(type solid)
		)
		(fill yes)
		(layer "In4.Cu")
		(net "M_G_CPU1_SA_DQS_DP<5>")
	)
	(gr_poly
		(pts
			(xy 136.84123 -274.876768) (xy 136.84123 -274.832572) (xy 136.48563 -274.832572) (xy 136.48563 -274.876768)
			(xy 136.53262 -275.029168) (xy 136.79424 -275.029168)
		)
		(stroke
			(width 0)
			(type solid)
		)
		(fill yes)
		(layer "In4.Cu")
		(net "M_G_CPU1_SA_DQ<4>")
	)
	(gr_poly
		(pts
			(xy 136.84123 -272.029174) (xy 136.79424 -271.876774) (xy 136.53262 -271.876774) (xy 136.48563 -272.029174)
			(xy 136.48563 -272.073624) (xy 136.84123 -272.073624)
		)
		(stroke
			(width 0)
			(type solid)
		)
		(fill yes)
		(layer "In4.Cu")
		(net "M_F_CPU1_SA_DQ<10>")
	)
	(gr_poly
		(pts
			(xy 136.84123 -271.62125) (xy 136.84123 -271.5768) (xy 136.48563 -271.5768) (xy 136.48563 -271.62125)
			(xy 136.53262 -271.77365) (xy 136.79424 -271.77365)
		)
		(stroke
			(width 0)
			(type solid)
		)
		(fill yes)
		(layer "In4.Cu")
		(net "M_F_CPU1_SA_DQ<9>")
	)
	(gr_poly
		(pts
			(xy 136.84123 -270.401542) (xy 136.79424 -270.249142) (xy 136.53262 -270.249142) (xy 136.48563 -270.401542)
			(xy 136.48563 -270.445992) (xy 136.84123 -270.445992)
		)
		(stroke
			(width 0)
			(type solid)
		)
		(fill yes)
		(layer "In4.Cu")
		(net "M_F_CPU1_SA_DQS_DN<1>")
	)
	(gr_poly
		(pts
			(xy 136.84123 -269.993618) (xy 136.84123 -269.949168) (xy 136.48563 -269.949168) (xy 136.48563 -269.993618)
			(xy 136.53262 -270.146018) (xy 136.79424 -270.146018)
		)
		(stroke
			(width 0)
			(type solid)
		)
		(fill yes)
		(layer "In4.Cu")
		(net "M_F_CPU1_SA_DQS_DN<6>")
	)
	(gr_poly
		(pts
			(xy 136.84123 -265.518138) (xy 136.79424 -265.365738) (xy 136.53262 -265.365738) (xy 136.48563 -265.518138)
			(xy 136.48563 -265.562588) (xy 136.84123 -265.562588)
		)
		(stroke
			(width 0)
			(type solid)
		)
		(fill yes)
		(layer "In4.Cu")
		(net "M_G_CPU1_SA_DQS_DN<2>")
	)
	(gr_poly
		(pts
			(xy 136.84123 -265.110214) (xy 136.84123 -265.065764) (xy 136.48563 -265.065764) (xy 136.48563 -265.110214)
			(xy 136.53262 -265.262614) (xy 136.79424 -265.262614)
		)
		(stroke
			(width 0)
			(type solid)
		)
		(fill yes)
		(layer "In4.Cu")
		(net "M_G_CPU1_SA_DQS_DN<7>")
	)
	(gr_poly
		(pts
			(xy 137.080498 -221.51721) (xy 137.042144 -221.495112) (xy 136.886696 -221.459552) (xy 136.755886 -221.68612)
			(xy 136.864344 -221.80296) (xy 136.902698 -221.825058)
		)
		(stroke
			(width 0)
			(type solid)
		)
		(fill yes)
		(layer "In4.Cu")
		(net "M_F_CPU1_SB_DQS_DP<8>")
	)
	(gr_poly
		(pts
			(xy 137.086848 -224.762568) (xy 137.048494 -224.74047) (xy 136.893046 -224.70491) (xy 136.762236 -224.931478)
			(xy 136.870694 -225.048318) (xy 136.909048 -225.070416)
		)
		(stroke
			(width 0)
			(type solid)
		)
		(fill yes)
		(layer "In4.Cu")
		(net "M_F_CPU1_SB_DQ<24>")
	)
	(gr_poly
		(pts
			(xy 137.08761 -228.015546) (xy 137.049256 -227.993448) (xy 136.893808 -227.957888) (xy 136.762998 -228.184456)
			(xy 136.871456 -228.301296) (xy 136.90981 -228.323394)
		)
		(stroke
			(width 0)
			(type solid)
		)
		(fill yes)
		(layer "In4.Cu")
		(net "M_G_CPU1_SB_DQ<23>")
	)
	(gr_poly
		(pts
			(xy 137.08761 -223.132904) (xy 137.049256 -223.110806) (xy 136.893808 -223.075246) (xy 136.762998 -223.301814)
			(xy 136.871456 -223.418654) (xy 136.90981 -223.440752)
		)
		(stroke
			(width 0)
			(type solid)
		)
		(fill yes)
		(layer "In4.Cu")
		(net "M_F_CPU1_SB_DQ<25>")
	)
	(gr_poly
		(pts
			(xy 137.087864 -229.643432) (xy 137.04951 -229.621334) (xy 136.894062 -229.585774) (xy 136.763252 -229.812342)
			(xy 136.87171 -229.929182) (xy 136.910064 -229.95128)
		)
		(stroke
			(width 0)
			(type solid)
		)
		(fill yes)
		(layer "In4.Cu")
		(net "M_G_CPU1_SB_DQ<22>")
	)
	(gr_poly
		(pts
			(xy 137.08888 -231.269794) (xy 137.050526 -231.247696) (xy 136.895078 -231.212136) (xy 136.764268 -231.438704)
			(xy 136.872726 -231.555544) (xy 136.91108 -231.577642)
		)
		(stroke
			(width 0)
			(type solid)
		)
		(fill yes)
		(layer "In4.Cu")
		(net "M_G_CPU1_SB_DQS_DP<7>")
	)
	(gr_poly
		(pts
			(xy 137.158222 -276.357588) (xy 137.196576 -276.33549) (xy 137.018776 -276.027642) (xy 136.980422 -276.04974)
			(xy 136.871964 -276.16658) (xy 137.002774 -276.393148)
		)
		(stroke
			(width 0)
			(type solid)
		)
		(fill yes)
		(layer "In4.Cu")
		(net "M_G_CPU1_SA_DQS_DN<5>")
	)
	(gr_poly
		(pts
			(xy 137.158222 -273.10207) (xy 137.196576 -273.079972) (xy 137.018776 -272.772124) (xy 136.980422 -272.794222)
			(xy 136.871964 -272.911062) (xy 137.002774 -273.13763)
		)
		(stroke
			(width 0)
			(type solid)
		)
		(fill yes)
		(layer "In4.Cu")
		(net "M_F_CPU1_SA_DQ<8>")
	)
	(gr_poly
		(pts
			(xy 137.160254 -277.989284) (xy 137.198608 -277.967186) (xy 137.020808 -277.659338) (xy 136.982454 -277.681436)
			(xy 136.873996 -277.798276) (xy 137.004806 -278.024844)
		)
		(stroke
			(width 0)
			(type solid)
		)
		(fill yes)
		(layer "In4.Cu")
		(net "M_G_CPU1_SA_DQS_DP<0>")
	)
	(gr_poly
		(pts
			(xy 137.18413 -240.057178) (xy 137.13714 -239.904778) (xy 136.87552 -239.904778) (xy 136.82853 -240.057178)
			(xy 136.82853 -240.101628) (xy 137.18413 -240.101628)
		)
		(stroke
			(width 0)
			(type solid)
		)
		(fill yes)
		(layer "In4.Cu")
		(net "M_G_CPU1_SB_CB<3>")
	)
	(gr_poly
		(pts
			(xy 137.18413 -239.649254) (xy 137.18413 -239.604804) (xy 136.82853 -239.604804) (xy 136.82853 -239.649254)
			(xy 136.87552 -239.801654) (xy 137.13714 -239.801654)
		)
		(stroke
			(width 0)
			(type solid)
		)
		(fill yes)
		(layer "In4.Cu")
		(net "M_F_CPU1_SB_DQ<0>")
	)
	(gr_poly
		(pts
			(xy 137.18413 -236.39399) (xy 137.18413 -236.34954) (xy 136.82853 -236.34954) (xy 136.82853 -236.39399)
			(xy 136.87552 -236.54639) (xy 137.13714 -236.54639)
		)
		(stroke
			(width 0)
			(type solid)
		)
		(fill yes)
		(layer "In4.Cu")
		(net "M_F_CPU1_SB_DQ<4>")
	)
	(gr_poly
		(pts
			(xy 137.18413 -235.174282) (xy 137.13714 -235.021882) (xy 136.87552 -235.021882) (xy 136.82853 -235.174282)
			(xy 136.82853 -235.218478) (xy 137.18413 -235.218478)
		)
		(stroke
			(width 0)
			(type solid)
		)
		(fill yes)
		(layer "In4.Cu")
		(net "M_F_CPU1_SB_DQ<7>")
	)
	(gr_poly
		(pts
			(xy 137.18413 -234.76585) (xy 137.18413 -234.721654) (xy 136.82853 -234.721654) (xy 136.82853 -234.76585)
			(xy 136.87552 -234.91825) (xy 137.13714 -234.91825)
		)
		(stroke
			(width 0)
			(type solid)
		)
		(fill yes)
		(layer "In4.Cu")
		(net "M_G_CPU1_SB_DQ<16>")
	)
	(gr_poly
		(pts
			(xy 137.18667 -236.801914) (xy 137.13968 -236.649514) (xy 136.87806 -236.649514) (xy 136.83107 -236.801914)
			(xy 136.83107 -236.84611) (xy 137.18667 -236.84611)
		)
		(stroke
			(width 0)
			(type solid)
		)
		(fill yes)
		(layer "In4.Cu")
		(net "M_F_CPU1_SB_DQS_DP<5>")
	)
	(gr_poly
		(pts
			(xy 137.192766 -246.568722) (xy 137.145776 -246.416322) (xy 136.884156 -246.416322) (xy 136.837166 -246.568722)
			(xy 136.837166 -246.613172) (xy 137.192766 -246.613172)
		)
		(stroke
			(width 0)
			(type solid)
		)
		(fill yes)
		(layer "In4.Cu")
		(net "M_G_CPU1_SB_CS_N<0>")
	)
	(gr_poly
		(pts
			(xy 137.192766 -244.53215) (xy 137.192766 -244.487954) (xy 136.837166 -244.487954) (xy 136.837166 -244.53215)
			(xy 136.884156 -244.68455) (xy 137.145776 -244.68455)
		)
		(stroke
			(width 0)
			(type solid)
		)
		(fill yes)
		(layer "In4.Cu")
		(net "M_G_CPU1_SB_CB<4>")
	)
	(gr_poly
		(pts
			(xy 137.192766 -243.313458) (xy 137.145776 -243.161058) (xy 136.884156 -243.161058) (xy 136.837166 -243.313458)
			(xy 136.837166 -243.357654) (xy 137.192766 -243.357654)
		)
		(stroke
			(width 0)
			(type solid)
		)
		(fill yes)
		(layer "In4.Cu")
		(net "M_G_CPU1_SB_CB<7>")
	)
	(gr_poly
		(pts
			(xy 137.192766 -242.904518) (xy 137.192766 -242.860322) (xy 136.837166 -242.860322) (xy 136.837166 -242.904518)
			(xy 136.884156 -243.056918) (xy 137.145776 -243.056918)
		)
		(stroke
			(width 0)
			(type solid)
		)
		(fill yes)
		(layer "In4.Cu")
		(net "M_G_CPU1_SB_DQS_DP<9>")
	)
	(gr_poly
		(pts
			(xy 137.192766 -241.685318) (xy 137.145776 -241.532918) (xy 136.884156 -241.532918) (xy 136.837166 -241.685318)
			(xy 136.837166 -241.729768) (xy 137.192766 -241.729768)
		)
		(stroke
			(width 0)
			(type solid)
		)
		(fill yes)
		(layer "In4.Cu")
		(net "M_G_CPU1_SB_DQS_DP<4>")
	)
	(gr_poly
		(pts
			(xy 137.192766 -241.276886) (xy 137.192766 -241.232436) (xy 136.837166 -241.232436) (xy 136.837166 -241.276886)
			(xy 136.884156 -241.429286) (xy 137.145776 -241.429286)
		)
		(stroke
			(width 0)
			(type solid)
		)
		(fill yes)
		(layer "In4.Cu")
		(net "M_G_CPU1_SB_CB<0>")
	)
	(gr_poly
		(pts
			(xy 137.192766 -238.430054) (xy 137.145776 -238.277654) (xy 136.884156 -238.277654) (xy 136.837166 -238.430054)
			(xy 136.837166 -238.47425) (xy 137.192766 -238.47425)
		)
		(stroke
			(width 0)
			(type solid)
		)
		(fill yes)
		(layer "In4.Cu")
		(net "M_F_CPU1_SB_DQ<3>")
	)
	(gr_poly
		(pts
			(xy 137.192766 -238.021114) (xy 137.192766 -237.976918) (xy 136.837166 -237.976918) (xy 136.837166 -238.021114)
			(xy 136.884156 -238.173514) (xy 137.145776 -238.173514)
		)
		(stroke
			(width 0)
			(type solid)
		)
		(fill yes)
		(layer "In4.Cu")
		(net "M_F_CPU1_SB_DQS_DP<0>")
	)
	(gr_poly
		(pts
			(xy 137.192766 -233.54665) (xy 137.145776 -233.39425) (xy 136.884156 -233.39425) (xy 136.837166 -233.54665)
			(xy 136.837166 -233.590846) (xy 137.192766 -233.590846)
		)
		(stroke
			(width 0)
			(type solid)
		)
		(fill yes)
		(layer "In4.Cu")
		(net "M_G_CPU1_SB_DQ<19>")
	)
	(gr_poly
		(pts
			(xy 137.192766 -233.13771) (xy 137.192766 -233.093514) (xy 136.837166 -233.093514) (xy 136.837166 -233.13771)
			(xy 136.884156 -233.29011) (xy 137.145776 -233.29011)
		)
		(stroke
			(width 0)
			(type solid)
		)
		(fill yes)
		(layer "In4.Cu")
		(net "M_G_CPU1_SB_DQS_DP<2>")
	)
	(gr_poly
		(pts
			(xy 137.192766 -220.52407) (xy 137.145776 -220.37167) (xy 136.884156 -220.37167) (xy 136.837166 -220.52407)
			(xy 136.837166 -220.56852) (xy 137.192766 -220.56852)
		)
		(stroke
			(width 0)
			(type solid)
		)
		(fill yes)
		(layer "In4.Cu")
		(net "M_F_CPU1_SB_DQS_DN<3>")
	)
	(gr_poly
		(pts
			(xy 137.201148 -220.115638) (xy 137.201148 -220.071442) (xy 136.845548 -220.071442) (xy 136.845548 -220.115638)
			(xy 136.892538 -220.268038) (xy 137.154158 -220.268038)
		)
		(stroke
			(width 0)
			(type solid)
		)
		(fill yes)
		(layer "In4.Cu")
		(net "M_F_CPU1_SB_DQ<30>")
	)
	(gr_poly
		(pts
			(xy 137.201148 -218.896438) (xy 137.154158 -218.744038) (xy 136.892538 -218.744038) (xy 136.845548 -218.896438)
			(xy 136.845548 -218.940634) (xy 137.201148 -218.940634)
		)
		(stroke
			(width 0)
			(type solid)
		)
		(fill yes)
		(layer "In4.Cu")
		(net "M_F_CPU1_SB_DQ<31>")
	)
	(gr_poly
		(pts
			(xy 137.265664 -231.990392) (xy 137.157206 -231.873552) (xy 137.118852 -231.851454) (xy 136.941052 -232.159302)
			(xy 136.979406 -232.1814) (xy 137.134854 -232.21696)
		)
		(stroke
			(width 0)
			(type solid)
		)
		(fill yes)
		(layer "In4.Cu")
		(net "M_G_CPU1_SB_DQS_DN<7>")
	)
	(gr_poly
		(pts
			(xy 137.266172 -272.479008) (xy 137.37463 -272.362168) (xy 137.24382 -272.1356) (xy 137.088372 -272.17116)
			(xy 137.050018 -272.193258) (xy 137.227818 -272.501106)
		)
		(stroke
			(width 0)
			(type solid)
		)
		(fill yes)
		(layer "In4.Cu")
		(net "M_F_CPU1_SA_DQ<10>")
	)
	(gr_poly
		(pts
			(xy 137.26668 -225.47707) (xy 137.158222 -225.36023) (xy 137.119868 -225.338132) (xy 136.942068 -225.64598)
			(xy 136.980422 -225.668078) (xy 137.13587 -225.703638)
		)
		(stroke
			(width 0)
			(type solid)
		)
		(fill yes)
		(layer "In4.Cu")
		(net "M_F_CPU1_SB_DQ<26>")
	)
	(gr_poly
		(pts
			(xy 137.267696 -230.358442) (xy 137.159238 -230.241602) (xy 137.120884 -230.219504) (xy 136.943084 -230.527352)
			(xy 136.981438 -230.54945) (xy 137.136886 -230.58501)
		)
		(stroke
			(width 0)
			(type solid)
		)
		(fill yes)
		(layer "In4.Cu")
		(net "M_G_CPU1_SB_DQ<20>")
	)
	(gr_poly
		(pts
			(xy 137.26795 -275.73732) (xy 137.376408 -275.62048) (xy 137.245598 -275.393912) (xy 137.09015 -275.429472)
			(xy 137.051796 -275.45157) (xy 137.229596 -275.759418)
		)
		(stroke
			(width 0)
			(type solid)
		)
		(fill yes)
		(layer "In4.Cu")
		(net "M_G_CPU1_SA_DQS_DP<5>")
	)
	(gr_poly
		(pts
			(xy 137.268966 -277.367492) (xy 137.377424 -277.250652) (xy 137.246614 -277.024084) (xy 137.091166 -277.059644)
			(xy 137.052812 -277.081742) (xy 137.230612 -277.38959)
		)
		(stroke
			(width 0)
			(type solid)
		)
		(fill yes)
		(layer "In4.Cu")
		(net "M_G_CPU1_SA_DQS_DN<0>")
	)
	(gr_poly
		(pts
			(xy 137.272014 -228.723698) (xy 137.163556 -228.606858) (xy 137.125202 -228.58476) (xy 136.947402 -228.892608)
			(xy 136.985756 -228.914706) (xy 137.141204 -228.950266)
		)
		(stroke
			(width 0)
			(type solid)
		)
		(fill yes)
		(layer "In4.Cu")
		(net "M_G_CPU1_SB_DQ<21>")
	)
	(gr_poly
		(pts
			(xy 137.272014 -223.84004) (xy 137.163556 -223.7232) (xy 137.125202 -223.701102) (xy 136.947402 -224.00895)
			(xy 136.985756 -224.031048) (xy 137.141204 -224.066608)
		)
		(stroke
			(width 0)
			(type solid)
		)
		(fill yes)
		(layer "In4.Cu")
		(net "M_F_CPU1_SB_DQ<27>")
	)
	(gr_poly
		(pts
			(xy 137.273792 -222.20936) (xy 137.165334 -222.09252) (xy 137.12698 -222.070422) (xy 136.94918 -222.37827)
			(xy 136.987534 -222.400368) (xy 137.142982 -222.435928)
		)
		(stroke
			(width 0)
			(type solid)
		)
		(fill yes)
		(layer "In4.Cu")
		(net "M_F_CPU1_SB_DQS_DN<8>")
	)
	(gr_poly
		(pts
			(xy 137.293604 -259.820918) (xy 137.246614 -259.668518) (xy 136.984994 -259.668518) (xy 136.938004 -259.820918)
			(xy 136.938004 -259.865368) (xy 137.293604 -259.865368)
		)
		(stroke
			(width 0)
			(type solid)
		)
		(fill yes)
		(layer "In4.Cu")
		(net "M_F_CPU1_SA_DQS_DP<8>")
	)
	(gr_poly
		(pts
			(xy 137.293858 -259.412994) (xy 137.293858 -259.368544) (xy 136.938258 -259.368544) (xy 136.938258 -259.412994)
			(xy 136.985248 -259.565394) (xy 137.246868 -259.565394)
		)
		(stroke
			(width 0)
			(type solid)
		)
		(fill yes)
		(layer "In4.Cu")
		(net "M_F_CPU1_SA_DQ<28>")
	)
	(gr_poly
		(pts
			(xy 137.294112 -274.47113) (xy 137.247122 -274.31873) (xy 136.985502 -274.31873) (xy 136.938512 -274.47113)
			(xy 136.938512 -274.515326) (xy 137.294112 -274.515326)
		)
		(stroke
			(width 0)
			(type solid)
		)
		(fill yes)
		(layer "In4.Cu")
		(net "M_G_CPU1_SA_DQ<6>")
	)
	(gr_poly
		(pts
			(xy 137.294112 -271.215358) (xy 137.247122 -271.062958) (xy 136.985502 -271.062958) (xy 136.938512 -271.215358)
			(xy 136.938512 -271.259808) (xy 137.294112 -271.259808)
		)
		(stroke
			(width 0)
			(type solid)
		)
		(fill yes)
		(layer "In4.Cu")
		(net "M_F_CPU1_SA_DQ<11>")
	)
	(gr_poly
		(pts
			(xy 137.294112 -270.807434) (xy 137.294112 -270.762984) (xy 136.938512 -270.762984) (xy 136.938512 -270.807434)
			(xy 136.985502 -270.959834) (xy 137.247122 -270.959834)
		)
		(stroke
			(width 0)
			(type solid)
		)
		(fill yes)
		(layer "In4.Cu")
		(net "M_F_CPU1_SA_DQS_DP<1>")
	)
	(gr_poly
		(pts
			(xy 137.294112 -269.587726) (xy 137.247122 -269.435326) (xy 136.985502 -269.435326) (xy 136.938512 -269.587726)
			(xy 136.938512 -269.631922) (xy 137.294112 -269.631922)
		)
		(stroke
			(width 0)
			(type solid)
		)
		(fill yes)
		(layer "In4.Cu")
		(net "M_F_CPU1_SA_DQS_DP<6>")
	)
	(gr_poly
		(pts
			(xy 137.294112 -264.704322) (xy 137.247122 -264.551922) (xy 136.985502 -264.551922) (xy 136.938512 -264.704322)
			(xy 136.938512 -264.748772) (xy 137.294112 -264.748772)
		)
		(stroke
			(width 0)
			(type solid)
		)
		(fill yes)
		(layer "In4.Cu")
		(net "M_G_CPU1_SA_DQS_DP<7>")
	)
	(gr_poly
		(pts
			(xy 137.30224 -261.449058) (xy 137.25525 -261.296658) (xy 136.99363 -261.296658) (xy 136.94664 -261.449058)
			(xy 136.94664 -261.493508) (xy 137.30224 -261.493508)
		)
		(stroke
			(width 0)
			(type solid)
		)
		(fill yes)
		(layer "In4.Cu")
		(net "M_F_CPU1_SA_DQ<27>")
	)
	(gr_poly
		(pts
			(xy 137.30224 -261.040626) (xy 137.30224 -260.996176) (xy 136.94664 -260.996176) (xy 136.94664 -261.040626)
			(xy 136.99363 -261.193026) (xy 137.25525 -261.193026)
		)
		(stroke
			(width 0)
			(type solid)
		)
		(fill yes)
		(layer "In4.Cu")
		(net "M_F_CPU1_SA_DQS_DP<3>")
	)
	(gr_poly
		(pts
			(xy 137.302494 -279.354788) (xy 137.255504 -279.202388) (xy 136.993884 -279.202388) (xy 136.946894 -279.354788)
			(xy 136.946894 -279.398984) (xy 137.302494 -279.398984)
		)
		(stroke
			(width 0)
			(type solid)
		)
		(fill yes)
		(layer "In4.Cu")
		(net "M_G_CPU1_SA_DQ<2>")
	)
	(gr_poly
		(pts
			(xy 137.302494 -278.945848) (xy 137.302494 -278.901652) (xy 136.946894 -278.901652) (xy 136.946894 -278.945848)
			(xy 136.993884 -279.098248) (xy 137.255504 -279.098248)
		)
		(stroke
			(width 0)
			(type solid)
		)
		(fill yes)
		(layer "In4.Cu")
		(net "M_G_CPU1_SA_DQ<1>")
	)
	(gr_poly
		(pts
			(xy 137.302494 -274.062698) (xy 137.302494 -274.018248) (xy 136.946894 -274.018248) (xy 136.946894 -274.062698)
			(xy 136.993884 -274.215098) (xy 137.255504 -274.215098)
		)
		(stroke
			(width 0)
			(type solid)
		)
		(fill yes)
		(layer "In4.Cu")
		(net "M_G_CPU1_SA_DQ<5>")
	)
	(gr_poly
		(pts
			(xy 137.302494 -269.179294) (xy 137.302494 -269.134844) (xy 136.946894 -269.134844) (xy 136.946894 -269.179294)
			(xy 136.993884 -269.331694) (xy 137.255504 -269.331694)
		)
		(stroke
			(width 0)
			(type solid)
		)
		(fill yes)
		(layer "In4.Cu")
		(net "M_F_CPU1_SA_DQ<12>")
	)
	(gr_poly
		(pts
			(xy 137.302494 -267.960094) (xy 137.255504 -267.807694) (xy 136.993884 -267.807694) (xy 136.946894 -267.960094)
			(xy 136.946894 -268.004544) (xy 137.302494 -268.004544)
		)
		(stroke
			(width 0)
			(type solid)
		)
		(fill yes)
		(layer "In4.Cu")
		(net "M_F_CPU1_SA_DQ<13>")
	)
	(gr_poly
		(pts
			(xy 137.302494 -267.551662) (xy 137.302494 -267.507212) (xy 136.946894 -267.507212) (xy 136.946894 -267.551662)
			(xy 136.993884 -267.704062) (xy 137.255504 -267.704062)
		)
		(stroke
			(width 0)
			(type solid)
		)
		(fill yes)
		(layer "In4.Cu")
		(net "M_G_CPU1_SA_DQ<16>")
	)
	(gr_poly
		(pts
			(xy 137.302494 -266.332462) (xy 137.255504 -266.180062) (xy 136.993884 -266.180062) (xy 136.946894 -266.332462)
			(xy 136.946894 -266.376658) (xy 137.302494 -266.376658)
		)
		(stroke
			(width 0)
			(type solid)
		)
		(fill yes)
		(layer "In4.Cu")
		(net "M_G_CPU1_SA_DQ<19>")
	)
	(gr_poly
		(pts
			(xy 137.302494 -264.29589) (xy 137.302494 -264.251694) (xy 136.946894 -264.251694) (xy 136.946894 -264.29589)
			(xy 136.993884 -264.44829) (xy 137.255504 -264.44829)
		)
		(stroke
			(width 0)
			(type solid)
		)
		(fill yes)
		(layer "In4.Cu")
		(net "M_G_CPU1_SA_DQ<20>")
	)
	(gr_poly
		(pts
			(xy 137.302494 -263.07669) (xy 137.255504 -262.92429) (xy 136.993884 -262.92429) (xy 136.946894 -263.07669)
			(xy 136.946894 -263.12114) (xy 137.302494 -263.12114)
		)
		(stroke
			(width 0)
			(type solid)
		)
		(fill yes)
		(layer "In4.Cu")
		(net "M_G_CPU1_SA_DQ<23>")
	)
	(gr_poly
		(pts
			(xy 137.302494 -262.668258) (xy 137.302494 -262.623808) (xy 136.946894 -262.623808) (xy 136.946894 -262.668258)
			(xy 136.993884 -262.820658) (xy 137.255504 -262.820658)
		)
		(stroke
			(width 0)
			(type solid)
		)
		(fill yes)
		(layer "In4.Cu")
		(net "M_F_CPU1_SA_DQ<24>")
	)
	(gr_poly
		(pts
			(xy 137.303256 -265.923522) (xy 137.303256 -265.879072) (xy 136.947656 -265.879072) (xy 136.947656 -265.923522)
			(xy 136.994646 -266.075922) (xy 137.256266 -266.075922)
		)
		(stroke
			(width 0)
			(type solid)
		)
		(fill yes)
		(layer "In4.Cu")
		(net "M_G_CPU1_SA_DQS_DP<2>")
	)
	(gr_poly
		(pts
			(xy 137.31113 -258.193286) (xy 137.26414 -258.040886) (xy 137.00252 -258.040886) (xy 136.95553 -258.193286)
			(xy 136.95553 -258.237482) (xy 137.31113 -258.237482)
		)
		(stroke
			(width 0)
			(type solid)
		)
		(fill yes)
		(layer "In4.Cu")
		(net "M_F_CPU1_SA_DQ<31>")
	)
	(gr_poly
		(pts
			(xy 137.550398 -228.842316) (xy 137.512044 -228.820218) (xy 137.356596 -228.784658) (xy 137.225786 -229.011226)
			(xy 137.334244 -229.128066) (xy 137.372598 -229.150164)
		)
		(stroke
			(width 0)
			(type solid)
		)
		(fill yes)
		(layer "In4.Cu")
		(net "M_G_CPU1_SB_DQ<22>")
	)
	(gr_poly
		(pts
			(xy 137.550398 -222.331026) (xy 137.512044 -222.308928) (xy 137.356596 -222.273368) (xy 137.225786 -222.499936)
			(xy 137.334244 -222.616776) (xy 137.372598 -222.638874)
		)
		(stroke
			(width 0)
			(type solid)
		)
		(fill yes)
		(layer "In4.Cu")
		(net "M_F_CPU1_SB_DQ<25>")
	)
	(gr_poly
		(pts
			(xy 137.556748 -230.459788) (xy 137.518394 -230.43769) (xy 137.362946 -230.40213) (xy 137.232136 -230.628698)
			(xy 137.340594 -230.745538) (xy 137.378948 -230.767636)
		)
		(stroke
			(width 0)
			(type solid)
		)
		(fill yes)
		(layer "In4.Cu")
		(net "M_G_CPU1_SB_DQS_DP<7>")
	)
	(gr_poly
		(pts
			(xy 137.556748 -227.20427) (xy 137.518394 -227.182172) (xy 137.362946 -227.146612) (xy 137.232136 -227.37318)
			(xy 137.340594 -227.49002) (xy 137.378948 -227.512118)
		)
		(stroke
			(width 0)
			(type solid)
		)
		(fill yes)
		(layer "In4.Cu")
		(net "M_G_CPU1_SB_DQ<23>")
	)
	(gr_poly
		(pts
			(xy 137.556748 -223.948752) (xy 137.518394 -223.926654) (xy 137.362946 -223.891094) (xy 137.232136 -224.117662)
			(xy 137.340594 -224.234502) (xy 137.378948 -224.2566)
		)
		(stroke
			(width 0)
			(type solid)
		)
		(fill yes)
		(layer "In4.Cu")
		(net "M_F_CPU1_SB_DQ<24>")
	)
	(gr_poly
		(pts
			(xy 137.557764 -232.085134) (xy 137.51941 -232.063036) (xy 137.363962 -232.027476) (xy 137.233152 -232.254044)
			(xy 137.34161 -232.370884) (xy 137.379964 -232.392982)
		)
		(stroke
			(width 0)
			(type solid)
		)
		(fill yes)
		(layer "In4.Cu")
		(net "M_G_CPU1_SB_DQS_DN<2>")
	)
	(gr_poly
		(pts
			(xy 137.628122 -277.171404) (xy 137.666476 -277.149306) (xy 137.488676 -276.841458) (xy 137.450322 -276.863556)
			(xy 137.341864 -276.980396) (xy 137.472674 -277.206964)
		)
		(stroke
			(width 0)
			(type solid)
		)
		(fill yes)
		(layer "In4.Cu")
		(net "M_G_CPU1_SA_DQS_DN<5>")
	)
	(gr_poly
		(pts
			(xy 137.629392 -275.546312) (xy 137.667746 -275.524214) (xy 137.489946 -275.216366) (xy 137.451592 -275.238464)
			(xy 137.343134 -275.355304) (xy 137.473944 -275.581872)
		)
		(stroke
			(width 0)
			(type solid)
		)
		(fill yes)
		(layer "In4.Cu")
		(net "M_G_CPU1_SA_DQ<4>")
	)
	(gr_poly
		(pts
			(xy 137.63117 -272.293334) (xy 137.669524 -272.271236) (xy 137.491724 -271.963388) (xy 137.45337 -271.985486)
			(xy 137.344912 -272.102326) (xy 137.475722 -272.328894)
		)
		(stroke
			(width 0)
			(type solid)
		)
		(fill yes)
		(layer "In4.Cu")
		(net "M_F_CPU1_SA_DQ<9>")
	)
	(gr_poly
		(pts
			(xy 137.65403 -219.710254) (xy 137.60704 -219.557854) (xy 137.34542 -219.557854) (xy 137.29843 -219.710254)
			(xy 137.29843 -219.75445) (xy 137.65403 -219.75445)
		)
		(stroke
			(width 0)
			(type solid)
		)
		(fill yes)
		(layer "In4.Cu")
		(net "M_F_CPU1_SB_DQ<28>")
	)
	(gr_poly
		(pts
			(xy 137.65403 -219.301822) (xy 137.65403 -219.257626) (xy 137.29843 -219.257626) (xy 137.29843 -219.301822)
			(xy 137.34542 -219.454222) (xy 137.60704 -219.454222)
		)
		(stroke
			(width 0)
			(type solid)
		)
		(fill yes)
		(layer "In4.Cu")
		(net "M_F_CPU1_SB_DQ<29>")
	)
	(gr_poly
		(pts
			(xy 137.662412 -237.207806) (xy 137.662412 -237.163356) (xy 137.306812 -237.163356) (xy 137.306812 -237.207806)
			(xy 137.353802 -237.360206) (xy 137.615422 -237.360206)
		)
		(stroke
			(width 0)
			(type solid)
		)
		(fill yes)
		(layer "In4.Cu")
		(net "M_F_CPU1_SB_DQS_DN<5>")
	)
	(gr_poly
		(pts
			(xy 137.662666 -244.127274) (xy 137.615676 -243.974874) (xy 137.354056 -243.974874) (xy 137.307066 -244.127274)
			(xy 137.307066 -244.17147) (xy 137.662666 -244.17147)
		)
		(stroke
			(width 0)
			(type solid)
		)
		(fill yes)
		(layer "In4.Cu")
		(net "M_G_CPU1_SB_CB<6>")
	)
	(gr_poly
		(pts
			(xy 137.662666 -242.499134) (xy 137.615676 -242.346734) (xy 137.354056 -242.346734) (xy 137.307066 -242.499134)
			(xy 137.307066 -242.543584) (xy 137.662666 -242.543584)
		)
		(stroke
			(width 0)
			(type solid)
		)
		(fill yes)
		(layer "In4.Cu")
		(net "M_G_CPU1_SB_DQS_DN<9>")
	)
	(gr_poly
		(pts
			(xy 137.662666 -242.090702) (xy 137.662666 -242.046252) (xy 137.307066 -242.046252) (xy 137.307066 -242.090702)
			(xy 137.354056 -242.243102) (xy 137.615676 -242.243102)
		)
		(stroke
			(width 0)
			(type solid)
		)
		(fill yes)
		(layer "In4.Cu")
		(net "M_G_CPU1_SB_DQS_DN<4>")
	)
	(gr_poly
		(pts
			(xy 137.662666 -240.871502) (xy 137.615676 -240.719102) (xy 137.354056 -240.719102) (xy 137.307066 -240.871502)
			(xy 137.307066 -240.915952) (xy 137.662666 -240.915952)
		)
		(stroke
			(width 0)
			(type solid)
		)
		(fill yes)
		(layer "In4.Cu")
		(net "M_G_CPU1_SB_CB<2>")
	)
	(gr_poly
		(pts
			(xy 137.662666 -238.83493) (xy 137.662666 -238.790734) (xy 137.307066 -238.790734) (xy 137.307066 -238.83493)
			(xy 137.354056 -238.98733) (xy 137.615676 -238.98733)
		)
		(stroke
			(width 0)
			(type solid)
		)
		(fill yes)
		(layer "In4.Cu")
		(net "M_F_CPU1_SB_DQ<1>")
	)
	(gr_poly
		(pts
			(xy 137.662666 -237.61573) (xy 137.615676 -237.46333) (xy 137.354056 -237.46333) (xy 137.307066 -237.61573)
			(xy 137.307066 -237.66018) (xy 137.662666 -237.66018)
		)
		(stroke
			(width 0)
			(type solid)
		)
		(fill yes)
		(layer "In4.Cu")
		(net "M_F_CPU1_SB_DQS_DN<0>")
	)
	(gr_poly
		(pts
			(xy 137.662666 -233.952034) (xy 137.662666 -233.907584) (xy 137.307066 -233.907584) (xy 137.307066 -233.952034)
			(xy 137.354056 -234.104434) (xy 137.615676 -234.104434)
		)
		(stroke
			(width 0)
			(type solid)
		)
		(fill yes)
		(layer "In4.Cu")
		(net "M_G_CPU1_SB_DQ<17>")
	)
	(gr_poly
		(pts
			(xy 137.662666 -221.338394) (xy 137.615676 -221.185994) (xy 137.354056 -221.185994) (xy 137.307066 -221.338394)
			(xy 137.307066 -221.38259) (xy 137.662666 -221.38259)
		)
		(stroke
			(width 0)
			(type solid)
		)
		(fill yes)
		(layer "In4.Cu")
		(net "M_F_CPU1_SB_DQS_DP<8>")
	)
	(gr_poly
		(pts
			(xy 137.662666 -220.929454) (xy 137.662666 -220.885258) (xy 137.307066 -220.885258) (xy 137.307066 -220.929454)
			(xy 137.354056 -221.081854) (xy 137.615676 -221.081854)
		)
		(stroke
			(width 0)
			(type solid)
		)
		(fill yes)
		(layer "In4.Cu")
		(net "M_F_CPU1_SB_DQS_DP<3>")
	)
	(gr_poly
		(pts
			(xy 137.671048 -240.46307) (xy 137.671048 -240.418874) (xy 137.315448 -240.418874) (xy 137.315448 -240.46307)
			(xy 137.362438 -240.61547) (xy 137.624058 -240.61547)
		)
		(stroke
			(width 0)
			(type solid)
		)
		(fill yes)
		(layer "In4.Cu")
		(net "M_G_CPU1_SB_CB<1>")
	)
	(gr_poly
		(pts
			(xy 137.671048 -239.243362) (xy 137.624058 -239.090962) (xy 137.362438 -239.090962) (xy 137.315448 -239.243362)
			(xy 137.315448 -239.287812) (xy 137.671048 -239.287812)
		)
		(stroke
			(width 0)
			(type solid)
		)
		(fill yes)
		(layer "In4.Cu")
		(net "M_F_CPU1_SB_DQ<2>")
	)
	(gr_poly
		(pts
			(xy 137.671048 -235.988098) (xy 137.624058 -235.835698) (xy 137.362438 -235.835698) (xy 137.315448 -235.988098)
			(xy 137.315448 -236.032294) (xy 137.671048 -236.032294)
		)
		(stroke
			(width 0)
			(type solid)
		)
		(fill yes)
		(layer "In4.Cu")
		(net "M_F_CPU1_SB_DQ<6>")
	)
	(gr_poly
		(pts
			(xy 137.671048 -235.579666) (xy 137.671048 -235.53547) (xy 137.315448 -235.53547) (xy 137.315448 -235.579666)
			(xy 137.362438 -235.732066) (xy 137.624058 -235.732066)
		)
		(stroke
			(width 0)
			(type solid)
		)
		(fill yes)
		(layer "In4.Cu")
		(net "M_F_CPU1_SB_DQ<5>")
	)
	(gr_poly
		(pts
			(xy 137.671048 -234.360466) (xy 137.624058 -234.208066) (xy 137.362438 -234.208066) (xy 137.315448 -234.360466)
			(xy 137.315448 -234.404662) (xy 137.671048 -234.404662)
		)
		(stroke
			(width 0)
			(type solid)
		)
		(fill yes)
		(layer "In4.Cu")
		(net "M_G_CPU1_SB_DQ<18>")
	)
	(gr_poly
		(pts
			(xy 137.735564 -231.176322) (xy 137.627106 -231.059482) (xy 137.588752 -231.037384) (xy 137.410952 -231.345232)
			(xy 137.449306 -231.36733) (xy 137.604754 -231.40289)
		)
		(stroke
			(width 0)
			(type solid)
		)
		(fill yes)
		(layer "In4.Cu")
		(net "M_G_CPU1_SB_DQS_DN<7>")
	)
	(gr_poly
		(pts
			(xy 137.73658 -223.035368) (xy 137.628122 -222.918528) (xy 137.589768 -222.89643) (xy 137.411968 -223.204278)
			(xy 137.450322 -223.226376) (xy 137.60577 -223.261936)
		)
		(stroke
			(width 0)
			(type solid)
		)
		(fill yes)
		(layer "In4.Cu")
		(net "M_F_CPU1_SB_DQ<27>")
	)
	(gr_poly
		(pts
			(xy 137.737596 -232.800144) (xy 137.629138 -232.683304) (xy 137.590784 -232.661206) (xy 137.412984 -232.969054)
			(xy 137.451338 -232.991152) (xy 137.606786 -233.026712)
		)
		(stroke
			(width 0)
			(type solid)
		)
		(fill yes)
		(layer "In4.Cu")
		(net "M_G_CPU1_SB_DQS_DP<2>")
	)
	(gr_poly
		(pts
			(xy 137.737596 -224.661222) (xy 137.629138 -224.544382) (xy 137.590784 -224.522284) (xy 137.412984 -224.830132)
			(xy 137.451338 -224.85223) (xy 137.606786 -224.88779)
		)
		(stroke
			(width 0)
			(type solid)
		)
		(fill yes)
		(layer "In4.Cu")
		(net "M_F_CPU1_SB_DQ<26>")
	)
	(gr_poly
		(pts
			(xy 137.738866 -276.553676) (xy 137.847324 -276.436836) (xy 137.716514 -276.210268) (xy 137.561066 -276.245828)
			(xy 137.522712 -276.267926) (xy 137.700512 -276.575774)
		)
		(stroke
			(width 0)
			(type solid)
		)
		(fill yes)
		(layer "In4.Cu")
		(net "M_G_CPU1_SA_DQS_DP<5>")
	)
	(gr_poly
		(pts
			(xy 137.741914 -229.53726) (xy 137.633456 -229.42042) (xy 137.595102 -229.398322) (xy 137.417302 -229.70617)
			(xy 137.455656 -229.728268) (xy 137.611104 -229.763828)
		)
		(stroke
			(width 0)
			(type solid)
		)
		(fill yes)
		(layer "In4.Cu")
		(net "M_G_CPU1_SB_DQ<20>")
	)
	(gr_poly
		(pts
			(xy 137.743438 -271.677384) (xy 137.851896 -271.560544) (xy 137.721086 -271.333976) (xy 137.565638 -271.369536)
			(xy 137.527284 -271.391634) (xy 137.705084 -271.699482)
		)
		(stroke
			(width 0)
			(type solid)
		)
		(fill yes)
		(layer "In4.Cu")
		(net "M_F_CPU1_SA_DQ<11>")
	)
	(gr_poly
		(pts
			(xy 137.744708 -227.904548) (xy 137.63625 -227.787708) (xy 137.597896 -227.76561) (xy 137.420096 -228.073458)
			(xy 137.45845 -228.095556) (xy 137.613898 -228.131116)
		)
		(stroke
			(width 0)
			(type solid)
		)
		(fill yes)
		(layer "In4.Cu")
		(net "M_G_CPU1_SB_DQ<21>")
	)
	(gr_poly
		(pts
			(xy 137.764012 -258.599178) (xy 137.764012 -258.554728) (xy 137.408412 -258.554728) (xy 137.408412 -258.599178)
			(xy 137.455402 -258.751578) (xy 137.717022 -258.751578)
		)
		(stroke
			(width 0)
			(type solid)
		)
		(fill yes)
		(layer "In4.Cu")
		(net "M_F_CPU1_SA_DQ<29>")
	)
	(gr_poly
		(pts
			(xy 137.77214 -261.854442) (xy 137.77214 -261.809992) (xy 137.41654 -261.809992) (xy 137.41654 -261.854442)
			(xy 137.46353 -262.006842) (xy 137.72515 -262.006842)
		)
		(stroke
			(width 0)
			(type solid)
		)
		(fill yes)
		(layer "In4.Cu")
		(net "M_F_CPU1_SA_DQ<25>")
	)
	(gr_poly
		(pts
			(xy 137.77214 -260.635242) (xy 137.72515 -260.482842) (xy 137.46353 -260.482842) (xy 137.41654 -260.635242)
			(xy 137.41654 -260.679438) (xy 137.77214 -260.679438)
		)
		(stroke
			(width 0)
			(type solid)
		)
		(fill yes)
		(layer "In4.Cu")
		(net "M_F_CPU1_SA_DQS_DN<3>")
	)
	(gr_poly
		(pts
			(xy 137.772394 -278.540718) (xy 137.725404 -278.388318) (xy 137.463784 -278.388318) (xy 137.416794 -278.540718)
			(xy 137.416794 -278.585168) (xy 137.772394 -278.585168)
		)
		(stroke
			(width 0)
			(type solid)
		)
		(fill yes)
		(layer "In4.Cu")
		(net "M_G_CPU1_SA_DQ<3>")
	)
	(gr_poly
		(pts
			(xy 137.772394 -278.132032) (xy 137.772394 -278.087836) (xy 137.416794 -278.087836) (xy 137.416794 -278.132032)
			(xy 137.463784 -278.284432) (xy 137.725404 -278.284432)
		)
		(stroke
			(width 0)
			(type solid)
		)
		(fill yes)
		(layer "In4.Cu")
		(net "M_G_CPU1_SA_DQS_DP<0>")
	)
	(gr_poly
		(pts
			(xy 137.772394 -273.657314) (xy 137.725404 -273.504914) (xy 137.463784 -273.504914) (xy 137.416794 -273.657314)
			(xy 137.416794 -273.701764) (xy 137.772394 -273.701764)
		)
		(stroke
			(width 0)
			(type solid)
		)
		(fill yes)
		(layer "In4.Cu")
		(net "M_G_CPU1_SA_DQ<7>")
	)
	(gr_poly
		(pts
			(xy 137.772394 -273.248882) (xy 137.772394 -273.204432) (xy 137.416794 -273.204432) (xy 137.416794 -273.248882)
			(xy 137.463784 -273.401282) (xy 137.725404 -273.401282)
		)
		(stroke
			(width 0)
			(type solid)
		)
		(fill yes)
		(layer "In4.Cu")
		(net "M_F_CPU1_SA_DQ<8>")
	)
	(gr_poly
		(pts
			(xy 137.772394 -268.77391) (xy 137.725404 -268.62151) (xy 137.463784 -268.62151) (xy 137.416794 -268.77391)
			(xy 137.416794 -268.81836) (xy 137.772394 -268.81836)
		)
		(stroke
			(width 0)
			(type solid)
		)
		(fill yes)
		(layer "In4.Cu")
		(net "M_F_CPU1_SA_DQ<14>")
	)
	(gr_poly
		(pts
			(xy 137.772394 -268.365478) (xy 137.772394 -268.321028) (xy 137.416794 -268.321028) (xy 137.416794 -268.365478)
			(xy 137.463784 -268.517878) (xy 137.725404 -268.517878)
		)
		(stroke
			(width 0)
			(type solid)
		)
		(fill yes)
		(layer "In4.Cu")
		(net "M_F_CPU1_SA_DQ<15>")
	)
	(gr_poly
		(pts
			(xy 137.772394 -262.262874) (xy 137.725404 -262.110474) (xy 137.463784 -262.110474) (xy 137.416794 -262.262874)
			(xy 137.416794 -262.307324) (xy 137.772394 -262.307324)
		)
		(stroke
			(width 0)
			(type solid)
		)
		(fill yes)
		(layer "In4.Cu")
		(net "M_F_CPU1_SA_DQ<26>")
	)
	(gr_poly
		(pts
			(xy 137.780522 -260.22681) (xy 137.780522 -260.18236) (xy 137.424922 -260.18236) (xy 137.424922 -260.22681)
			(xy 137.471912 -260.37921) (xy 137.733532 -260.37921)
		)
		(stroke
			(width 0)
			(type solid)
		)
		(fill yes)
		(layer "In4.Cu")
		(net "M_F_CPU1_SA_DQS_DN<8>")
	)
	(gr_poly
		(pts
			(xy 137.780522 -259.007102) (xy 137.733532 -258.854702) (xy 137.471912 -258.854702) (xy 137.424922 -259.007102)
			(xy 137.424922 -259.051552) (xy 137.780522 -259.051552)
		)
		(stroke
			(width 0)
			(type solid)
		)
		(fill yes)
		(layer "In4.Cu")
		(net "M_F_CPU1_SA_DQ<30>")
	)
	(gr_poly
		(pts
			(xy 137.78103 -270.401542) (xy 137.73404 -270.249142) (xy 137.47242 -270.249142) (xy 137.42543 -270.401542)
			(xy 137.42543 -270.445992) (xy 137.78103 -270.445992)
		)
		(stroke
			(width 0)
			(type solid)
		)
		(fill yes)
		(layer "In4.Cu")
		(net "M_F_CPU1_SA_DQS_DN<1>")
	)
	(gr_poly
		(pts
			(xy 137.78103 -269.993618) (xy 137.78103 -269.949168) (xy 137.42543 -269.949168) (xy 137.42543 -269.993618)
			(xy 137.47242 -270.146018) (xy 137.73404 -270.146018)
		)
		(stroke
			(width 0)
			(type solid)
		)
		(fill yes)
		(layer "In4.Cu")
		(net "M_F_CPU1_SA_DQS_DN<6>")
	)
	(gr_poly
		(pts
			(xy 138.026648 -232.90149) (xy 137.988294 -232.879392) (xy 137.832846 -232.843832) (xy 137.702036 -233.0704)
			(xy 137.810494 -233.18724) (xy 137.848848 -233.209338)
		)
		(stroke
			(width 0)
			(type solid)
		)
		(fill yes)
		(layer "In4.Cu")
		(net "M_G_CPU1_SB_DQ<19>")
	)
	(gr_poly
		(pts
			(xy 138.026648 -229.645972) (xy 137.988294 -229.623874) (xy 137.832846 -229.588314) (xy 137.702036 -229.814882)
			(xy 137.810494 -229.931722) (xy 137.848848 -229.95382)
		)
		(stroke
			(width 0)
			(type solid)
		)
		(fill yes)
		(layer "In4.Cu")
		(net "M_G_CPU1_SB_DQS_DP<7>")
	)
	(gr_poly
		(pts
			(xy 138.026648 -226.390454) (xy 137.988294 -226.368356) (xy 137.832846 -226.332796) (xy 137.702036 -226.559364)
			(xy 137.810494 -226.676204) (xy 137.848848 -226.698302)
		)
		(stroke
			(width 0)
			(type solid)
		)
		(fill yes)
		(layer "In4.Cu")
		(net "M_G_CPU1_SB_DQ<23>")
	)
	(gr_poly
		(pts
			(xy 138.02741 -231.271826) (xy 137.989056 -231.249728) (xy 137.833608 -231.214168) (xy 137.702798 -231.440736)
			(xy 137.811256 -231.557576) (xy 137.84961 -231.579674)
		)
		(stroke
			(width 0)
			(type solid)
		)
		(fill yes)
		(layer "In4.Cu")
		(net "M_G_CPU1_SB_DQS_DN<2>")
	)
	(gr_poly
		(pts
			(xy 138.02868 -228.014276) (xy 137.990326 -227.992178) (xy 137.834878 -227.956618) (xy 137.704068 -228.183186)
			(xy 137.812526 -228.300026) (xy 137.85088 -228.322124)
		)
		(stroke
			(width 0)
			(type solid)
		)
		(fill yes)
		(layer "In4.Cu")
		(net "M_G_CPU1_SB_DQ<22>")
	)
	(gr_poly
		(pts
			(xy 138.02868 -223.130872) (xy 137.990326 -223.108774) (xy 137.834878 -223.073214) (xy 137.704068 -223.299782)
			(xy 137.812526 -223.416622) (xy 137.85088 -223.43872)
		)
		(stroke
			(width 0)
			(type solid)
		)
		(fill yes)
		(layer "In4.Cu")
		(net "M_F_CPU1_SB_DQ<24>")
	)
	(gr_poly
		(pts
			(xy 138.093704 -271.467072) (xy 138.132058 -271.444974) (xy 137.954258 -271.137126) (xy 137.915904 -271.159224)
			(xy 137.807446 -271.276064) (xy 137.938256 -271.502632)
		)
		(stroke
			(width 0)
			(type solid)
		)
		(fill yes)
		(layer "In4.Cu")
		(net "M_F_CPU1_SA_DQS_DP<1>")
	)
	(gr_poly
		(pts
			(xy 138.098022 -276.357588) (xy 138.136376 -276.33549) (xy 137.958576 -276.027642) (xy 137.920222 -276.04974)
			(xy 137.811764 -276.16658) (xy 137.942574 -276.393148)
		)
		(stroke
			(width 0)
			(type solid)
		)
		(fill yes)
		(layer "In4.Cu")
		(net "M_G_CPU1_SA_DQ<4>")
	)
	(gr_poly
		(pts
			(xy 138.099038 -274.731734) (xy 138.137392 -274.709636) (xy 137.959592 -274.401788) (xy 137.921238 -274.423886)
			(xy 137.81278 -274.540726) (xy 137.94359 -274.767294)
		)
		(stroke
			(width 0)
			(type solid)
		)
		(fill yes)
		(layer "In4.Cu")
		(net "M_G_CPU1_SA_DQ<5>")
	)
	(gr_poly
		(pts
			(xy 138.12393 -240.057178) (xy 138.07694 -239.904778) (xy 137.81532 -239.904778) (xy 137.76833 -240.057178)
			(xy 137.76833 -240.101628) (xy 138.12393 -240.101628)
		)
		(stroke
			(width 0)
			(type solid)
		)
		(fill yes)
		(layer "In4.Cu")
		(net "M_G_CPU1_SB_CB<3>")
	)
	(gr_poly
		(pts
			(xy 138.12393 -239.649254) (xy 138.12393 -239.604804) (xy 137.76833 -239.604804) (xy 137.76833 -239.649254)
			(xy 137.81532 -239.801654) (xy 138.07694 -239.801654)
		)
		(stroke
			(width 0)
			(type solid)
		)
		(fill yes)
		(layer "In4.Cu")
		(net "M_F_CPU1_SB_DQ<0>")
	)
	(gr_poly
		(pts
			(xy 138.12393 -236.801914) (xy 138.07694 -236.649514) (xy 137.81532 -236.649514) (xy 137.76833 -236.801914)
			(xy 137.76833 -236.84611) (xy 138.12393 -236.84611)
		)
		(stroke
			(width 0)
			(type solid)
		)
		(fill yes)
		(layer "In4.Cu")
		(net "M_F_CPU1_SB_DQS_DP<5>")
	)
	(gr_poly
		(pts
			(xy 138.12393 -236.39399) (xy 138.12393 -236.34954) (xy 137.76833 -236.34954) (xy 137.76833 -236.39399)
			(xy 137.81532 -236.54639) (xy 138.07694 -236.54639)
		)
		(stroke
			(width 0)
			(type solid)
		)
		(fill yes)
		(layer "In4.Cu")
		(net "M_F_CPU1_SB_DQ<4>")
	)
	(gr_poly
		(pts
			(xy 138.12393 -235.174282) (xy 138.07694 -235.021882) (xy 137.81532 -235.021882) (xy 137.76833 -235.174282)
			(xy 137.76833 -235.218478) (xy 138.12393 -235.218478)
		)
		(stroke
			(width 0)
			(type solid)
		)
		(fill yes)
		(layer "In4.Cu")
		(net "M_F_CPU1_SB_DQ<7>")
	)
	(gr_poly
		(pts
			(xy 138.12393 -234.76585) (xy 138.12393 -234.721654) (xy 137.76833 -234.721654) (xy 137.76833 -234.76585)
			(xy 137.81532 -234.91825) (xy 138.07694 -234.91825)
		)
		(stroke
			(width 0)
			(type solid)
		)
		(fill yes)
		(layer "In4.Cu")
		(net "M_G_CPU1_SB_DQ<16>")
	)
	(gr_poly
		(pts
			(xy 138.132566 -244.53215) (xy 138.132566 -244.487954) (xy 137.776966 -244.487954) (xy 137.776966 -244.53215)
			(xy 137.823956 -244.68455) (xy 138.085576 -244.68455)
		)
		(stroke
			(width 0)
			(type solid)
		)
		(fill yes)
		(layer "In4.Cu")
		(net "M_G_CPU1_SB_CB<4>")
	)
	(gr_poly
		(pts
			(xy 138.132566 -242.904518) (xy 138.132566 -242.860322) (xy 137.776966 -242.860322) (xy 137.776966 -242.904518)
			(xy 137.823956 -243.056918) (xy 138.085576 -243.056918)
		)
		(stroke
			(width 0)
			(type solid)
		)
		(fill yes)
		(layer "In4.Cu")
		(net "M_G_CPU1_SB_DQS_DP<9>")
	)
	(gr_poly
		(pts
			(xy 138.132566 -241.685318) (xy 138.085576 -241.532918) (xy 137.823956 -241.532918) (xy 137.776966 -241.685318)
			(xy 137.776966 -241.729768) (xy 138.132566 -241.729768)
		)
		(stroke
			(width 0)
			(type solid)
		)
		(fill yes)
		(layer "In4.Cu")
		(net "M_G_CPU1_SB_DQS_DP<4>")
	)
	(gr_poly
		(pts
			(xy 138.132566 -241.276886) (xy 138.132566 -241.232436) (xy 137.776966 -241.232436) (xy 137.776966 -241.276886)
			(xy 137.823956 -241.429286) (xy 138.085576 -241.429286)
		)
		(stroke
			(width 0)
			(type solid)
		)
		(fill yes)
		(layer "In4.Cu")
		(net "M_G_CPU1_SB_CB<0>")
	)
	(gr_poly
		(pts
			(xy 138.132566 -238.430054) (xy 138.085576 -238.277654) (xy 137.823956 -238.277654) (xy 137.776966 -238.430054)
			(xy 137.776966 -238.47425) (xy 138.132566 -238.47425)
		)
		(stroke
			(width 0)
			(type solid)
		)
		(fill yes)
		(layer "In4.Cu")
		(net "M_F_CPU1_SB_DQ<3>")
	)
	(gr_poly
		(pts
			(xy 138.132566 -238.021114) (xy 138.132566 -237.976918) (xy 137.776966 -237.976918) (xy 137.776966 -238.021114)
			(xy 137.823956 -238.173514) (xy 138.085576 -238.173514)
		)
		(stroke
			(width 0)
			(type solid)
		)
		(fill yes)
		(layer "In4.Cu")
		(net "M_F_CPU1_SB_DQS_DP<0>")
	)
	(gr_poly
		(pts
			(xy 138.132566 -222.15221) (xy 138.085576 -221.99981) (xy 137.823956 -221.99981) (xy 137.776966 -222.15221)
			(xy 137.776966 -222.196406) (xy 138.132566 -222.196406)
		)
		(stroke
			(width 0)
			(type solid)
		)
		(fill yes)
		(layer "In4.Cu")
		(net "M_F_CPU1_SB_DQ<25>")
	)
	(gr_poly
		(pts
			(xy 138.132566 -221.74327) (xy 138.132566 -221.699074) (xy 137.776966 -221.699074) (xy 137.776966 -221.74327)
			(xy 137.823956 -221.89567) (xy 138.085576 -221.89567)
		)
		(stroke
			(width 0)
			(type solid)
		)
		(fill yes)
		(layer "In4.Cu")
		(net "M_F_CPU1_SB_DQS_DN<8>")
	)
	(gr_poly
		(pts
			(xy 138.132566 -220.52407) (xy 138.085576 -220.37167) (xy 137.823956 -220.37167) (xy 137.776966 -220.52407)
			(xy 137.776966 -220.56852) (xy 138.132566 -220.56852)
		)
		(stroke
			(width 0)
			(type solid)
		)
		(fill yes)
		(layer "In4.Cu")
		(net "M_F_CPU1_SB_DQS_DN<3>")
	)
	(gr_poly
		(pts
			(xy 138.140948 -220.115638) (xy 138.140948 -220.071442) (xy 137.785348 -220.071442) (xy 137.785348 -220.115638)
			(xy 137.832338 -220.268038) (xy 138.093958 -220.268038)
		)
		(stroke
			(width 0)
			(type solid)
		)
		(fill yes)
		(layer "In4.Cu")
		(net "M_F_CPU1_SB_DQ<30>")
	)
	(gr_poly
		(pts
			(xy 138.140948 -218.896438) (xy 138.093958 -218.744038) (xy 137.832338 -218.744038) (xy 137.785348 -218.896438)
			(xy 137.785348 -218.940634) (xy 138.140948 -218.940634)
		)
		(stroke
			(width 0)
			(type solid)
		)
		(fill yes)
		(layer "In4.Cu")
		(net "M_F_CPU1_SB_DQ<31>")
	)
	(gr_poly
		(pts
			(xy 138.207496 -233.61396) (xy 138.099038 -233.49712) (xy 138.060684 -233.475022) (xy 137.882884 -233.78287)
			(xy 137.921238 -233.804968) (xy 138.076686 -233.840528)
		)
		(stroke
			(width 0)
			(type solid)
		)
		(fill yes)
		(layer "In4.Cu")
		(net "M_G_CPU1_SB_DQ<17>")
	)
	(gr_poly
		(pts
			(xy 138.207496 -230.358442) (xy 138.099038 -230.241602) (xy 138.060684 -230.219504) (xy 137.882884 -230.527352)
			(xy 137.921238 -230.54945) (xy 138.076686 -230.58501)
		)
		(stroke
			(width 0)
			(type solid)
		)
		(fill yes)
		(layer "In4.Cu")
		(net "M_G_CPU1_SB_DQS_DN<7>")
	)
	(gr_poly
		(pts
			(xy 138.207496 -228.73081) (xy 138.099038 -228.61397) (xy 138.060684 -228.591872) (xy 137.882884 -228.89972)
			(xy 137.921238 -228.921818) (xy 138.076686 -228.957378)
		)
		(stroke
			(width 0)
			(type solid)
		)
		(fill yes)
		(layer "In4.Cu")
		(net "M_G_CPU1_SB_DQ<20>")
	)
	(gr_poly
		(pts
			(xy 138.207496 -227.102924) (xy 138.099038 -226.986084) (xy 138.060684 -226.963986) (xy 137.882884 -227.271834)
			(xy 137.921238 -227.293932) (xy 138.076686 -227.329492)
		)
		(stroke
			(width 0)
			(type solid)
		)
		(fill yes)
		(layer "In4.Cu")
		(net "M_G_CPU1_SB_DQ<21>")
	)
	(gr_poly
		(pts
			(xy 138.207496 -223.847406) (xy 138.099038 -223.730566) (xy 138.060684 -223.708468) (xy 137.882884 -224.016316)
			(xy 137.921238 -224.038414) (xy 138.076686 -224.073974)
		)
		(stroke
			(width 0)
			(type solid)
		)
		(fill yes)
		(layer "In4.Cu")
		(net "M_F_CPU1_SB_DQ<26>")
	)
	(gr_poly
		(pts
			(xy 138.20775 -275.73732) (xy 138.316208 -275.62048) (xy 138.185398 -275.393912) (xy 138.02995 -275.429472)
			(xy 137.991596 -275.45157) (xy 138.169396 -275.759418)
		)
		(stroke
			(width 0)
			(type solid)
		)
		(fill yes)
		(layer "In4.Cu")
		(net "M_G_CPU1_SA_DQ<6>")
	)
	(gr_poly
		(pts
			(xy 138.20775 -270.853916) (xy 138.316208 -270.737076) (xy 138.185398 -270.510508) (xy 138.02995 -270.546068)
			(xy 137.991596 -270.568166) (xy 138.169396 -270.876014)
		)
		(stroke
			(width 0)
			(type solid)
		)
		(fill yes)
		(layer "In4.Cu")
		(net "M_F_CPU1_SA_DQS_DN<1>")
	)
	(gr_poly
		(pts
			(xy 138.208766 -274.111974) (xy 138.317224 -273.995134) (xy 138.186414 -273.768566) (xy 138.030966 -273.804126)
			(xy 137.992612 -273.826224) (xy 138.170412 -274.134072)
		)
		(stroke
			(width 0)
			(type solid)
		)
		(fill yes)
		(layer "In4.Cu")
		(net "M_G_CPU1_SA_DQ<7>")
	)
	(gr_poly
		(pts
			(xy 138.211814 -231.978962) (xy 138.103356 -231.862122) (xy 138.065002 -231.840024) (xy 137.887202 -232.147872)
			(xy 137.925556 -232.16997) (xy 138.081004 -232.20553)
		)
		(stroke
			(width 0)
			(type solid)
		)
		(fill yes)
		(layer "In4.Cu")
		(net "M_G_CPU1_SB_DQS_DP<2>")
	)
	(gr_poly
		(pts
			(xy 138.233658 -259.412994) (xy 138.233658 -259.368544) (xy 137.878058 -259.368544) (xy 137.878058 -259.412994)
			(xy 137.925048 -259.565394) (xy 138.186668 -259.565394)
		)
		(stroke
			(width 0)
			(type solid)
		)
		(fill yes)
		(layer "In4.Cu")
		(net "M_F_CPU1_SA_DQ<28>")
	)
	(gr_poly
		(pts
			(xy 138.233912 -272.435066) (xy 138.233912 -272.39087) (xy 137.878312 -272.39087) (xy 137.878312 -272.435066)
			(xy 137.925302 -272.587466) (xy 138.186922 -272.587466)
		)
		(stroke
			(width 0)
			(type solid)
		)
		(fill yes)
		(layer "In4.Cu")
		(net "M_F_CPU1_SA_DQ<9>")
	)
	(gr_poly
		(pts
			(xy 138.233912 -269.587726) (xy 138.186922 -269.435326) (xy 137.925302 -269.435326) (xy 137.878312 -269.587726)
			(xy 137.878312 -269.631922) (xy 138.233912 -269.631922)
		)
		(stroke
			(width 0)
			(type solid)
		)
		(fill yes)
		(layer "In4.Cu")
		(net "M_F_CPU1_SA_DQS_DP<6>")
	)
	(gr_poly
		(pts
			(xy 138.24204 -261.040118) (xy 138.24204 -260.995668) (xy 137.88644 -260.995668) (xy 137.88644 -261.040118)
			(xy 137.93343 -261.192518) (xy 138.19505 -261.192518)
		)
		(stroke
			(width 0)
			(type solid)
		)
		(fill yes)
		(layer "In4.Cu")
		(net "M_F_CPU1_SA_DQS_DP<3>")
	)
	(gr_poly
		(pts
			(xy 138.24204 -259.821934) (xy 138.19505 -259.669534) (xy 137.93343 -259.669534) (xy 137.88644 -259.821934)
			(xy 137.88644 -259.86613) (xy 138.24204 -259.86613)
		)
		(stroke
			(width 0)
			(type solid)
		)
		(fill yes)
		(layer "In4.Cu")
		(net "M_F_CPU1_SA_DQS_DP<8>")
	)
	(gr_poly
		(pts
			(xy 138.242294 -277.726902) (xy 138.195304 -277.574502) (xy 137.933684 -277.574502) (xy 137.886694 -277.726902)
			(xy 137.886694 -277.771098) (xy 138.242294 -277.771098)
		)
		(stroke
			(width 0)
			(type solid)
		)
		(fill yes)
		(layer "In4.Cu")
		(net "M_G_CPU1_SA_DQS_DN<0>")
	)
	(gr_poly
		(pts
			(xy 138.242294 -277.317962) (xy 138.242294 -277.273766) (xy 137.886694 -277.273766) (xy 137.886694 -277.317962)
			(xy 137.933684 -277.470362) (xy 138.195304 -277.470362)
		)
		(stroke
			(width 0)
			(type solid)
		)
		(fill yes)
		(layer "In4.Cu")
		(net "M_G_CPU1_SA_DQS_DN<5>")
	)
	(gr_poly
		(pts
			(xy 138.242294 -272.843498) (xy 138.195304 -272.691098) (xy 137.933684 -272.691098) (xy 137.886694 -272.843498)
			(xy 137.886694 -272.887948) (xy 138.242294 -272.887948)
		)
		(stroke
			(width 0)
			(type solid)
		)
		(fill yes)
		(layer "In4.Cu")
		(net "M_F_CPU1_SA_DQ<10>")
	)
	(gr_poly
		(pts
			(xy 138.242294 -269.179294) (xy 138.242294 -269.134844) (xy 137.886694 -269.134844) (xy 137.886694 -269.179294)
			(xy 137.933684 -269.331694) (xy 138.195304 -269.331694)
		)
		(stroke
			(width 0)
			(type solid)
		)
		(fill yes)
		(layer "In4.Cu")
		(net "M_F_CPU1_SA_DQ<12>")
	)
	(gr_poly
		(pts
			(xy 138.242294 -267.960094) (xy 138.195304 -267.807694) (xy 137.933684 -267.807694) (xy 137.886694 -267.960094)
			(xy 137.886694 -268.004544) (xy 138.242294 -268.004544)
		)
		(stroke
			(width 0)
			(type solid)
		)
		(fill yes)
		(layer "In4.Cu")
		(net "M_F_CPU1_SA_DQ<13>")
	)
	(gr_poly
		(pts
			(xy 138.242294 -261.449058) (xy 138.195304 -261.296658) (xy 137.933684 -261.296658) (xy 137.886694 -261.449058)
			(xy 137.886694 -261.493508) (xy 138.242294 -261.493508)
		)
		(stroke
			(width 0)
			(type solid)
		)
		(fill yes)
		(layer "In4.Cu")
		(net "M_F_CPU1_SA_DQ<27>")
	)
	(gr_poly
		(pts
			(xy 138.24839 -262.668258) (xy 138.24839 -262.624062) (xy 137.89279 -262.624062) (xy 137.89279 -262.668258)
			(xy 137.93978 -262.820658) (xy 138.2014 -262.820658)
		)
		(stroke
			(width 0)
			(type solid)
		)
		(fill yes)
		(layer "In4.Cu")
		(net "M_F_CPU1_SA_DQ<24>")
	)
	(gr_poly
		(pts
			(xy 138.25093 -258.193286) (xy 138.20394 -258.040886) (xy 137.94232 -258.040886) (xy 137.89533 -258.193286)
			(xy 137.89533 -258.237482) (xy 138.25093 -258.237482)
		)
		(stroke
			(width 0)
			(type solid)
		)
		(fill yes)
		(layer "In4.Cu")
		(net "M_F_CPU1_SA_DQ<31>")
	)
	(gr_poly
		(pts
			(xy 138.490198 -230.469948) (xy 138.451844 -230.44785) (xy 138.296396 -230.41229) (xy 138.165586 -230.638858)
			(xy 138.274044 -230.755698) (xy 138.312398 -230.777796)
		)
		(stroke
			(width 0)
			(type solid)
		)
		(fill yes)
		(layer "In4.Cu")
		(net "M_G_CPU1_SB_DQS_DN<2>")
	)
	(gr_poly
		(pts
			(xy 138.491976 -227.211382) (xy 138.453622 -227.189284) (xy 138.298174 -227.153724) (xy 138.167364 -227.380292)
			(xy 138.275822 -227.497132) (xy 138.314176 -227.51923)
		)
		(stroke
			(width 0)
			(type solid)
		)
		(fill yes)
		(layer "In4.Cu")
		(net "M_G_CPU1_SB_DQ<22>")
	)
	(gr_poly
		(pts
			(xy 138.496294 -228.831902) (xy 138.45794 -228.809804) (xy 138.302492 -228.774244) (xy 138.171682 -229.000812)
			(xy 138.28014 -229.117652) (xy 138.318494 -229.13975)
		)
		(stroke
			(width 0)
			(type solid)
		)
		(fill yes)
		(layer "In4.Cu")
		(net "M_G_CPU1_SB_DQS_DP<7>")
	)
	(gr_poly
		(pts
			(xy 138.496548 -232.087674) (xy 138.458194 -232.065576) (xy 138.302746 -232.030016) (xy 138.171936 -232.256584)
			(xy 138.280394 -232.373424) (xy 138.318748 -232.395522)
		)
		(stroke
			(width 0)
			(type solid)
		)
		(fill yes)
		(layer "In4.Cu")
		(net "M_G_CPU1_SB_DQ<19>")
	)
	(gr_poly
		(pts
			(xy 138.49858 -233.711496) (xy 138.460226 -233.689398) (xy 138.304778 -233.653838) (xy 138.173968 -233.880406)
			(xy 138.282426 -233.997246) (xy 138.32078 -234.019344)
		)
		(stroke
			(width 0)
			(type solid)
		)
		(fill yes)
		(layer "In4.Cu")
		(net "M_G_CPU1_SB_DQ<18>")
	)
	(gr_poly
		(pts
			(xy 138.569192 -270.662908) (xy 138.607546 -270.64081) (xy 138.429746 -270.332962) (xy 138.391392 -270.35506)
			(xy 138.282934 -270.4719) (xy 138.413744 -270.698468)
		)
		(stroke
			(width 0)
			(type solid)
		)
		(fill yes)
		(layer "In4.Cu")
		(net "M_F_CPU1_SA_DQS_DN<6>")
	)
	(gr_poly
		(pts
			(xy 138.59383 -219.710254) (xy 138.54684 -219.557854) (xy 138.28522 -219.557854) (xy 138.23823 -219.710254)
			(xy 138.23823 -219.75445) (xy 138.59383 -219.75445)
		)
		(stroke
			(width 0)
			(type solid)
		)
		(fill yes)
		(layer "In4.Cu")
		(net "M_F_CPU1_SB_DQ<28>")
	)
	(gr_poly
		(pts
			(xy 138.59383 -219.301822) (xy 138.59383 -219.257626) (xy 138.23823 -219.257626) (xy 138.23823 -219.301822)
			(xy 138.28522 -219.454222) (xy 138.54684 -219.454222)
		)
		(stroke
			(width 0)
			(type solid)
		)
		(fill yes)
		(layer "In4.Cu")
		(net "M_F_CPU1_SB_DQ<29>")
	)
	(gr_poly
		(pts
			(xy 138.59637 -222.966026) (xy 138.54938 -222.813626) (xy 138.28776 -222.813626) (xy 138.24077 -222.966026)
			(xy 138.24077 -223.010222) (xy 138.59637 -223.010222)
		)
		(stroke
			(width 0)
			(type solid)
		)
		(fill yes)
		(layer "In4.Cu")
		(net "M_F_CPU1_SB_DQ<24>")
	)
	(gr_poly
		(pts
			(xy 138.59637 -222.557086) (xy 138.59637 -222.51289) (xy 138.24077 -222.51289) (xy 138.24077 -222.557086)
			(xy 138.28776 -222.709486) (xy 138.54938 -222.709486)
		)
		(stroke
			(width 0)
			(type solid)
		)
		(fill yes)
		(layer "In4.Cu")
		(net "M_F_CPU1_SB_DQ<27>")
	)
	(gr_poly
		(pts
			(xy 138.602212 -221.338394) (xy 138.555222 -221.185994) (xy 138.293602 -221.185994) (xy 138.246612 -221.338394)
			(xy 138.246612 -221.382844) (xy 138.602212 -221.382844)
		)
		(stroke
			(width 0)
			(type solid)
		)
		(fill yes)
		(layer "In4.Cu")
		(net "M_F_CPU1_SB_DQS_DP<8>")
	)
	(gr_poly
		(pts
			(xy 138.602466 -242.090702) (xy 138.602466 -242.046252) (xy 138.246866 -242.046252) (xy 138.246866 -242.090702)
			(xy 138.293856 -242.243102) (xy 138.555476 -242.243102)
		)
		(stroke
			(width 0)
			(type solid)
		)
		(fill yes)
		(layer "In4.Cu")
		(net "M_G_CPU1_SB_DQS_DN<4>")
	)
	(gr_poly
		(pts
			(xy 138.602466 -238.83493) (xy 138.602466 -238.790734) (xy 138.246866 -238.790734) (xy 138.246866 -238.83493)
			(xy 138.293856 -238.98733) (xy 138.555476 -238.98733)
		)
		(stroke
			(width 0)
			(type solid)
		)
		(fill yes)
		(layer "In4.Cu")
		(net "M_F_CPU1_SB_DQ<1>")
	)
	(gr_poly
		(pts
			(xy 138.602466 -237.61573) (xy 138.555476 -237.46333) (xy 138.293856 -237.46333) (xy 138.246866 -237.61573)
			(xy 138.246866 -237.66018) (xy 138.602466 -237.66018)
		)
		(stroke
			(width 0)
			(type solid)
		)
		(fill yes)
		(layer "In4.Cu")
		(net "M_F_CPU1_SB_DQS_DN<0>")
	)
	(gr_poly
		(pts
			(xy 138.602466 -220.929454) (xy 138.602466 -220.885258) (xy 138.246866 -220.885258) (xy 138.246866 -220.929454)
			(xy 138.293856 -221.081854) (xy 138.555476 -221.081854)
		)
		(stroke
			(width 0)
			(type solid)
		)
		(fill yes)
		(layer "In4.Cu")
		(net "M_F_CPU1_SB_DQS_DP<3>")
	)
	(gr_poly
		(pts
			(xy 138.610848 -240.46307) (xy 138.610848 -240.418874) (xy 138.255248 -240.418874) (xy 138.255248 -240.46307)
			(xy 138.302238 -240.61547) (xy 138.563858 -240.61547)
		)
		(stroke
			(width 0)
			(type solid)
		)
		(fill yes)
		(layer "In4.Cu")
		(net "M_G_CPU1_SB_CB<1>")
	)
	(gr_poly
		(pts
			(xy 138.610848 -239.243362) (xy 138.563858 -239.090962) (xy 138.302238 -239.090962) (xy 138.255248 -239.243362)
			(xy 138.255248 -239.287812) (xy 138.610848 -239.287812)
		)
		(stroke
			(width 0)
			(type solid)
		)
		(fill yes)
		(layer "In4.Cu")
		(net "M_F_CPU1_SB_DQ<2>")
	)
	(gr_poly
		(pts
			(xy 138.610848 -237.207806) (xy 138.610848 -237.163356) (xy 138.255248 -237.163356) (xy 138.255248 -237.207806)
			(xy 138.302238 -237.360206) (xy 138.563858 -237.360206)
		)
		(stroke
			(width 0)
			(type solid)
		)
		(fill yes)
		(layer "In4.Cu")
		(net "M_F_CPU1_SB_DQS_DN<5>")
	)
	(gr_poly
		(pts
			(xy 138.610848 -235.988098) (xy 138.563858 -235.835698) (xy 138.302238 -235.835698) (xy 138.255248 -235.988098)
			(xy 138.255248 -236.032294) (xy 138.610848 -236.032294)
		)
		(stroke
			(width 0)
			(type solid)
		)
		(fill yes)
		(layer "In4.Cu")
		(net "M_F_CPU1_SB_DQ<6>")
	)
	(gr_poly
		(pts
			(xy 138.610848 -235.579666) (xy 138.610848 -235.53547) (xy 138.255248 -235.53547) (xy 138.255248 -235.579666)
			(xy 138.302238 -235.732066) (xy 138.563858 -235.732066)
		)
		(stroke
			(width 0)
			(type solid)
		)
		(fill yes)
		(layer "In4.Cu")
		(net "M_F_CPU1_SB_DQ<5>")
	)
	(gr_poly
		(pts
			(xy 138.675364 -227.920804) (xy 138.566906 -227.803964) (xy 138.528552 -227.781866) (xy 138.350752 -228.089714)
			(xy 138.389106 -228.111812) (xy 138.544554 -228.147372)
		)
		(stroke
			(width 0)
			(type solid)
		)
		(fill yes)
		(layer "In4.Cu")
		(net "M_G_CPU1_SB_DQ<20>")
	)
	(gr_poly
		(pts
			(xy 138.67638 -231.17429) (xy 138.567922 -231.05745) (xy 138.529568 -231.035352) (xy 138.351768 -231.3432)
			(xy 138.390122 -231.365298) (xy 138.54557 -231.400858)
		)
		(stroke
			(width 0)
			(type solid)
		)
		(fill yes)
		(layer "In4.Cu")
		(net "M_G_CPU1_SB_DQS_DP<2>")
	)
	(gr_poly
		(pts
			(xy 138.676634 -278.177498) (xy 138.785092 -278.060658) (xy 138.654282 -277.83409) (xy 138.498834 -277.86965)
			(xy 138.46048 -277.891748) (xy 138.63828 -278.199596)
		)
		(stroke
			(width 0)
			(type solid)
		)
		(fill yes)
		(layer "In4.Cu")
		(net "M_G_CPU1_SA_DQS_DN<0>")
	)
	(gr_poly
		(pts
			(xy 138.677396 -232.800144) (xy 138.568938 -232.683304) (xy 138.530584 -232.661206) (xy 138.352784 -232.969054)
			(xy 138.391138 -232.991152) (xy 138.546586 -233.026712)
		)
		(stroke
			(width 0)
			(type solid)
		)
		(fill yes)
		(layer "In4.Cu")
		(net "M_G_CPU1_SB_DQ<17>")
	)
	(gr_poly
		(pts
			(xy 138.677396 -229.544626) (xy 138.568938 -229.427786) (xy 138.530584 -229.405688) (xy 138.352784 -229.713536)
			(xy 138.391138 -229.735634) (xy 138.546586 -229.771194)
		)
		(stroke
			(width 0)
			(type solid)
		)
		(fill yes)
		(layer "In4.Cu")
		(net "M_G_CPU1_SB_DQS_DN<7>")
	)
	(gr_poly
		(pts
			(xy 138.677396 -226.289108) (xy 138.568938 -226.172268) (xy 138.530584 -226.15017) (xy 138.352784 -226.458018)
			(xy 138.391138 -226.480116) (xy 138.546586 -226.515676)
		)
		(stroke
			(width 0)
			(type solid)
		)
		(fill yes)
		(layer "In4.Cu")
		(net "M_G_CPU1_SB_DQ<21>")
	)
	(gr_poly
		(pts
			(xy 138.677904 -274.924012) (xy 138.786362 -274.807172) (xy 138.655552 -274.580604) (xy 138.500104 -274.616164)
			(xy 138.46175 -274.638262) (xy 138.63955 -274.94611)
		)
		(stroke
			(width 0)
			(type solid)
		)
		(fill yes)
		(layer "In4.Cu")
		(net "M_G_CPU1_SA_DQ<7>")
	)
	(gr_poly
		(pts
			(xy 138.677904 -270.040608) (xy 138.786362 -269.923768) (xy 138.655552 -269.6972) (xy 138.500104 -269.73276)
			(xy 138.46175 -269.754858) (xy 138.63955 -270.062706)
		)
		(stroke
			(width 0)
			(type solid)
		)
		(fill yes)
		(layer "In4.Cu")
		(net "M_F_CPU1_SA_DQS_DP<6>")
	)
	(gr_poly
		(pts
			(xy 138.681714 -234.420918) (xy 138.573256 -234.304078) (xy 138.534902 -234.28198) (xy 138.357102 -234.589828)
			(xy 138.395456 -234.611926) (xy 138.550904 -234.647486)
		)
		(stroke
			(width 0)
			(type solid)
		)
		(fill yes)
		(layer "In4.Cu")
		(net "M_G_CPU1_SB_DQ<16>")
	)
	(gr_poly
		(pts
			(xy 138.703812 -262.262874) (xy 138.656822 -262.110474) (xy 138.395202 -262.110474) (xy 138.348212 -262.262874)
			(xy 138.348212 -262.30707) (xy 138.703812 -262.30707)
		)
		(stroke
			(width 0)
			(type solid)
		)
		(fill yes)
		(layer "In4.Cu")
		(net "M_F_CPU1_SA_DQ<26>")
	)
	(gr_poly
		(pts
			(xy 138.712194 -268.77391) (xy 138.665204 -268.62151) (xy 138.403584 -268.62151) (xy 138.356594 -268.77391)
			(xy 138.356594 -268.81836) (xy 138.712194 -268.81836)
		)
		(stroke
			(width 0)
			(type solid)
		)
		(fill yes)
		(layer "In4.Cu")
		(net "M_F_CPU1_SA_DQ<14>")
	)
	(gr_poly
		(pts
			(xy 138.72083 -272.029174) (xy 138.67384 -271.876774) (xy 138.41222 -271.876774) (xy 138.36523 -272.029174)
			(xy 138.36523 -272.073624) (xy 138.72083 -272.073624)
		)
		(stroke
			(width 0)
			(type solid)
		)
		(fill yes)
		(layer "In4.Cu")
		(net "M_F_CPU1_SA_DQ<11>")
	)
	(gr_poly
		(pts
			(xy 138.72083 -271.62125) (xy 138.72083 -271.5768) (xy 138.36523 -271.5768) (xy 138.36523 -271.62125)
			(xy 138.41222 -271.77365) (xy 138.67384 -271.77365)
		)
		(stroke
			(width 0)
			(type solid)
		)
		(fill yes)
		(layer "In4.Cu")
		(net "M_F_CPU1_SA_DQS_DP<1>")
	)
	(gr_poly
		(pts
			(xy 138.961876 -234.536488) (xy 138.923522 -234.51439) (xy 138.768074 -234.47883) (xy 138.637264 -234.705398)
			(xy 138.745722 -234.822238) (xy 138.784076 -234.844336)
		)
		(stroke
			(width 0)
			(type solid)
		)
		(fill yes)
		(layer "In4.Cu")
		(net "M_F_CPU1_SB_DQ<7>")
	)
	(gr_poly
		(pts
			(xy 138.962638 -229.652576) (xy 138.924284 -229.630478) (xy 138.768836 -229.594918) (xy 138.638026 -229.821486)
			(xy 138.746484 -229.938326) (xy 138.784838 -229.960424)
		)
		(stroke
			(width 0)
			(type solid)
		)
		(fill yes)
		(layer "In4.Cu")
		(net "M_G_CPU1_SB_DQS_DN<2>")
	)
	(gr_poly
		(pts
			(xy 138.966448 -232.90149) (xy 138.928094 -232.879392) (xy 138.772646 -232.843832) (xy 138.641836 -233.0704)
			(xy 138.750294 -233.18724) (xy 138.788648 -233.209338)
		)
		(stroke
			(width 0)
			(type solid)
		)
		(fill yes)
		(layer "In4.Cu")
		(net "M_G_CPU1_SB_DQ<18>")
	)
	(gr_poly
		(pts
			(xy 138.96848 -231.269794) (xy 138.930126 -231.247696) (xy 138.774678 -231.212136) (xy 138.643868 -231.438704)
			(xy 138.752326 -231.555544) (xy 138.79068 -231.577642)
		)
		(stroke
			(width 0)
			(type solid)
		)
		(fill yes)
		(layer "In4.Cu")
		(net "M_G_CPU1_SB_DQ<19>")
	)
	(gr_poly
		(pts
			(xy 139.06373 -239.649254) (xy 139.06373 -239.604804) (xy 138.70813 -239.604804) (xy 138.70813 -239.649254)
			(xy 138.75512 -239.801654) (xy 139.01674 -239.801654)
		)
		(stroke
			(width 0)
			(type solid)
		)
		(fill yes)
		(layer "In4.Cu")
		(net "M_F_CPU1_SB_DQ<0>")
	)
	(gr_poly
		(pts
			(xy 139.06373 -236.801914) (xy 139.01674 -236.649514) (xy 138.75512 -236.649514) (xy 138.70813 -236.801914)
			(xy 138.70813 -236.84611) (xy 139.06373 -236.84611)
		)
		(stroke
			(width 0)
			(type solid)
		)
		(fill yes)
		(layer "In4.Cu")
		(net "M_F_CPU1_SB_DQS_DP<5>")
	)
	(gr_poly
		(pts
			(xy 139.06373 -236.39399) (xy 139.06373 -236.34954) (xy 138.70813 -236.34954) (xy 138.70813 -236.39399)
			(xy 138.75512 -236.54639) (xy 139.01674 -236.54639)
		)
		(stroke
			(width 0)
			(type solid)
		)
		(fill yes)
		(layer "In4.Cu")
		(net "M_F_CPU1_SB_DQ<4>")
	)
	(gr_poly
		(pts
			(xy 139.072366 -238.021114) (xy 139.072366 -237.976918) (xy 138.716766 -237.976918) (xy 138.716766 -238.021114)
			(xy 138.763756 -238.173514) (xy 139.025376 -238.173514)
		)
		(stroke
			(width 0)
			(type solid)
		)
		(fill yes)
		(layer "In4.Cu")
		(net "M_F_CPU1_SB_DQS_DP<0>")
	)
	(gr_poly
		(pts
			(xy 139.080748 -220.115638) (xy 139.080748 -220.071442) (xy 138.725148 -220.071442) (xy 138.725148 -220.115638)
			(xy 138.772138 -220.268038) (xy 139.033758 -220.268038)
		)
		(stroke
			(width 0)
			(type solid)
		)
		(fill yes)
		(layer "In4.Cu")
		(net "M_F_CPU1_SB_DQ<30>")
	)
	(gr_poly
		(pts
			(xy 139.145264 -233.618024) (xy 139.036806 -233.501184) (xy 138.998452 -233.479086) (xy 138.820652 -233.786934)
			(xy 138.859006 -233.809032) (xy 139.014454 -233.844592)
		)
		(stroke
			(width 0)
			(type solid)
		)
		(fill yes)
		(layer "In4.Cu")
		(net "M_G_CPU1_SB_DQ<16>")
	)
	(gr_poly
		(pts
			(xy 139.146026 -235.244386) (xy 139.037568 -235.127546) (xy 138.999214 -235.105448) (xy 138.821414 -235.413296)
			(xy 138.859768 -235.435394) (xy 139.015216 -235.470954)
		)
		(stroke
			(width 0)
			(type solid)
		)
		(fill yes)
		(layer "In4.Cu")
		(net "M_F_CPU1_SB_DQ<5>")
	)
	(gr_poly
		(pts
			(xy 139.146026 -227.105464) (xy 139.037568 -226.988624) (xy 138.999214 -226.966526) (xy 138.821414 -227.274374)
			(xy 138.859768 -227.296472) (xy 139.015216 -227.332032)
		)
		(stroke
			(width 0)
			(type solid)
		)
		(fill yes)
		(layer "In4.Cu")
		(net "M_G_CPU1_SB_DQ<20>")
	)
	(gr_poly
		(pts
			(xy 139.147296 -231.986328) (xy 139.038838 -231.869488) (xy 139.000484 -231.84739) (xy 138.822684 -232.155238)
			(xy 138.861038 -232.177336) (xy 139.016486 -232.212896)
		)
		(stroke
			(width 0)
			(type solid)
		)
		(fill yes)
		(layer "In4.Cu")
		(net "M_G_CPU1_SB_DQ<17>")
	)
	(gr_poly
		(pts
			(xy 139.147296 -230.358442) (xy 139.038838 -230.241602) (xy 139.000484 -230.219504) (xy 138.822684 -230.527352)
			(xy 138.861038 -230.54945) (xy 139.016486 -230.58501)
		)
		(stroke
			(width 0)
			(type solid)
		)
		(fill yes)
		(layer "In4.Cu")
		(net "M_G_CPU1_SB_DQS_DP<2>")
	)
	(gr_poly
		(pts
			(xy 139.14755 -228.73081) (xy 139.039092 -228.61397) (xy 139.000738 -228.591872) (xy 138.822938 -228.89972)
			(xy 138.861292 -228.921818) (xy 139.01674 -228.957378)
		)
		(stroke
			(width 0)
			(type solid)
		)
		(fill yes)
		(layer "In4.Cu")
		(net "M_G_CPU1_SB_DQS_DN<7>")
	)
	(gr_poly
		(pts
			(xy 139.19073 -262.668258) (xy 139.19073 -262.624062) (xy 138.83513 -262.624062) (xy 138.83513 -262.668258)
			(xy 138.88212 -262.820658) (xy 139.14374 -262.820658)
		)
		(stroke
			(width 0)
			(type solid)
		)
		(fill yes)
		(layer "In4.Cu")
		(net "M_F_CPU1_SA_DQ<24>")
	)
	(gr_poly
		(pts
			(xy 139.436348 -232.087674) (xy 139.397994 -232.065576) (xy 139.242546 -232.030016) (xy 139.111736 -232.256584)
			(xy 139.220194 -232.373424) (xy 139.258548 -232.395522)
		)
		(stroke
			(width 0)
			(type solid)
		)
		(fill yes)
		(layer "In4.Cu")
		(net "M_G_CPU1_SB_DQ<18>")
	)
	(gr_poly
		(pts
			(xy 139.436348 -230.459788) (xy 139.397994 -230.43769) (xy 139.242546 -230.40213) (xy 139.111736 -230.628698)
			(xy 139.220194 -230.745538) (xy 139.258548 -230.767636)
		)
		(stroke
			(width 0)
			(type solid)
		)
		(fill yes)
		(layer "In4.Cu")
		(net "M_G_CPU1_SB_DQ<19>")
	)
	(gr_poly
		(pts
			(xy 139.437364 -235.340652) (xy 139.39901 -235.318554) (xy 139.243562 -235.282994) (xy 139.112752 -235.509562)
			(xy 139.22121 -235.626402) (xy 139.259564 -235.6485)
		)
		(stroke
			(width 0)
			(type solid)
		)
		(fill yes)
		(layer "In4.Cu")
		(net "M_F_CPU1_SB_DQ<6>")
	)
	(gr_poly
		(pts
			(xy 139.615164 -231.176322) (xy 139.506706 -231.059482) (xy 139.468352 -231.037384) (xy 139.290552 -231.345232)
			(xy 139.328906 -231.36733) (xy 139.484354 -231.40289)
		)
		(stroke
			(width 0)
			(type solid)
		)
		(fill yes)
		(layer "In4.Cu")
		(net "M_G_CPU1_SB_DQ<17>")
	)
	(gr_poly
		(pts
			(xy 139.61618 -236.057694) (xy 139.507722 -235.940854) (xy 139.469368 -235.918756) (xy 139.291568 -236.226604)
			(xy 139.329922 -236.248702) (xy 139.48537 -236.284262)
		)
		(stroke
			(width 0)
			(type solid)
		)
		(fill yes)
		(layer "In4.Cu")
		(net "M_F_CPU1_SB_DQ<4>")
	)
	(gr_poly
		(pts
			(xy 139.617196 -232.800144) (xy 139.508738 -232.683304) (xy 139.470384 -232.661206) (xy 139.292584 -232.969054)
			(xy 139.330938 -232.991152) (xy 139.486386 -233.026712)
		)
		(stroke
			(width 0)
			(type solid)
		)
		(fill yes)
		(layer "In4.Cu")
		(net "M_G_CPU1_SB_DQ<16>")
	)
	(gr_poly
		(pts
			(xy 139.643612 -262.262874) (xy 139.596622 -262.110474) (xy 139.335002 -262.110474) (xy 139.288012 -262.262874)
			(xy 139.288012 -262.30707) (xy 139.643612 -262.30707)
		)
		(stroke
			(width 0)
			(type solid)
		)
		(fill yes)
		(layer "In4.Cu")
		(net "M_F_CPU1_SA_DQ<26>")
	)
	(gr_poly
		(pts
			(xy 332.143862 -265.109706) (xy 332.143862 -265.06551) (xy 331.788262 -265.06551) (xy 331.788262 -265.109706)
			(xy 331.835252 -265.262106) (xy 332.096872 -265.262106)
		)
		(stroke
			(width 0)
			(type solid)
		)
		(fill yes)
		(layer "In4.Cu")
		(net "M_B_CPU0_SA_DQ<26>")
	)
	(gr_poly
		(pts
			(xy 332.143862 -263.891014) (xy 332.096872 -263.738614) (xy 331.835252 -263.738614) (xy 331.788262 -263.891014)
			(xy 331.788262 -263.93521) (xy 332.143862 -263.93521)
		)
		(stroke
			(width 0)
			(type solid)
		)
		(fill yes)
		(layer "In4.Cu")
		(net "M_B_CPU0_SA_DQ<27>")
	)
	(gr_poly
		(pts
			(xy 332.143862 -263.482074) (xy 332.143862 -263.437878) (xy 331.788262 -263.437878) (xy 331.788262 -263.482074)
			(xy 331.835252 -263.634474) (xy 332.096872 -263.634474)
		)
		(stroke
			(width 0)
			(type solid)
		)
		(fill yes)
		(layer "In4.Cu")
		(net "M_B_CPU0_SA_DQS_DP<3>")
	)
	(gr_poly
		(pts
			(xy 332.143862 -262.262874) (xy 332.096872 -262.110474) (xy 331.835252 -262.110474) (xy 331.788262 -262.262874)
			(xy 331.788262 -262.307324) (xy 332.143862 -262.307324)
		)
		(stroke
			(width 0)
			(type solid)
		)
		(fill yes)
		(layer "In4.Cu")
		(net "M_B_CPU0_SA_DQS_DP<8>")
	)
	(gr_poly
		(pts
			(xy 332.143862 -261.854442) (xy 332.143862 -261.809992) (xy 331.788262 -261.809992) (xy 331.788262 -261.854442)
			(xy 331.835252 -262.006842) (xy 332.096872 -262.006842)
		)
		(stroke
			(width 0)
			(type solid)
		)
		(fill yes)
		(layer "In4.Cu")
		(net "M_B_CPU0_SA_DQ<28>")
	)
	(gr_poly
		(pts
			(xy 332.495398 -244.940582) (xy 332.448408 -244.788182) (xy 332.186788 -244.788182) (xy 332.139798 -244.940582)
			(xy 332.139798 -244.985032) (xy 332.495398 -244.985032)
		)
		(stroke
			(width 0)
			(type solid)
		)
		(fill yes)
		(layer "In4.Cu")
		(net "M_C_CPU0_SB_CS_N<1>")
	)
	(gr_poly
		(pts
			(xy 332.495398 -230.290878) (xy 332.448408 -230.138478) (xy 332.186788 -230.138478) (xy 332.139798 -230.290878)
			(xy 332.139798 -230.335074) (xy 332.495398 -230.335074)
		)
		(stroke
			(width 0)
			(type solid)
		)
		(fill yes)
		(layer "In4.Cu")
		(net "M_C_CPU0_SB_DQS_DN<2>")
	)
	(gr_poly
		(pts
			(xy 332.504034 -246.568722) (xy 332.457044 -246.416322) (xy 332.195424 -246.416322) (xy 332.148434 -246.568722)
			(xy 332.148434 -246.613172) (xy 332.504034 -246.613172)
		)
		(stroke
			(width 0)
			(type solid)
		)
		(fill yes)
		(layer "In4.Cu")
		(net "M_C_CPU0_SB_PAR")
	)
	(gr_poly
		(pts
			(xy 332.504034 -246.16029) (xy 332.504034 -246.11584) (xy 332.148434 -246.11584) (xy 332.148434 -246.16029)
			(xy 332.195424 -246.31269) (xy 332.457044 -246.31269)
		)
		(stroke
			(width 0)
			(type solid)
		)
		(fill yes)
		(layer "In4.Cu")
		(net "M_C_CPU0_SB_CS_N<2>")
	)
	(gr_poly
		(pts
			(xy 332.504034 -231.510078) (xy 332.504034 -231.465882) (xy 332.148434 -231.465882) (xy 332.148434 -231.510078)
			(xy 332.195424 -231.662478) (xy 332.457044 -231.662478)
		)
		(stroke
			(width 0)
			(type solid)
		)
		(fill yes)
		(layer "In4.Cu")
		(net "M_C_CPU0_SB_DQ<17>")
	)
	(gr_poly
		(pts
			(xy 332.504034 -228.663246) (xy 332.457044 -228.510846) (xy 332.195424 -228.510846) (xy 332.148434 -228.663246)
			(xy 332.148434 -228.707696) (xy 332.504034 -228.707696)
		)
		(stroke
			(width 0)
			(type solid)
		)
		(fill yes)
		(layer "In4.Cu")
		(net "M_C_CPU0_SB_DQ<22>")
	)
	(gr_poly
		(pts
			(xy 332.512416 -242.905026) (xy 332.512416 -242.860576) (xy 332.156816 -242.860576) (xy 332.156816 -242.905026)
			(xy 332.203806 -243.057426) (xy 332.465426 -243.057426)
		)
		(stroke
			(width 0)
			(type solid)
		)
		(fill yes)
		(layer "In4.Cu")
		(net "M_C_CPU0_SB_CB<5>")
	)
	(gr_poly
		(pts
			(xy 332.512416 -231.91851) (xy 332.465426 -231.76611) (xy 332.203806 -231.76611) (xy 332.156816 -231.91851)
			(xy 332.156816 -231.96296) (xy 332.512416 -231.96296)
		)
		(stroke
			(width 0)
			(type solid)
		)
		(fill yes)
		(layer "In4.Cu")
		(net "M_C_CPU0_SB_DQ<18>")
	)
	(gr_poly
		(pts
			(xy 332.518766 -228.255068) (xy 332.518766 -228.210618) (xy 332.163166 -228.210618) (xy 332.163166 -228.255068)
			(xy 332.210156 -228.407468) (xy 332.471776 -228.407468)
		)
		(stroke
			(width 0)
			(type solid)
		)
		(fill yes)
		(layer "In4.Cu")
		(net "M_C_CPU0_SB_DQ<21>")
	)
	(gr_poly
		(pts
			(xy 332.613762 -266.332462) (xy 332.566772 -266.180062) (xy 332.305152 -266.180062) (xy 332.258162 -266.332462)
			(xy 332.258162 -266.376658) (xy 332.613762 -266.376658)
		)
		(stroke
			(width 0)
			(type solid)
		)
		(fill yes)
		(layer "In4.Cu")
		(net "M_C_CPU0_SA_DQ<22>")
	)
	(gr_poly
		(pts
			(xy 332.613762 -265.92403) (xy 332.613762 -265.87958) (xy 332.258162 -265.87958) (xy 332.258162 -265.92403)
			(xy 332.305152 -266.07643) (xy 332.566772 -266.07643)
		)
		(stroke
			(width 0)
			(type solid)
		)
		(fill yes)
		(layer "In4.Cu")
		(net "M_C_CPU0_SA_DQ<21>")
	)
	(gr_poly
		(pts
			(xy 332.613762 -264.70483) (xy 332.566772 -264.55243) (xy 332.305152 -264.55243) (xy 332.258162 -264.70483)
			(xy 332.258162 -264.749026) (xy 332.613762 -264.749026)
		)
		(stroke
			(width 0)
			(type solid)
		)
		(fill yes)
		(layer "In4.Cu")
		(net "M_B_CPU0_SA_DQ<24>")
	)
	(gr_poly
		(pts
			(xy 332.613762 -264.29589) (xy 332.613762 -264.251694) (xy 332.258162 -264.251694) (xy 332.258162 -264.29589)
			(xy 332.305152 -264.44829) (xy 332.566772 -264.44829)
		)
		(stroke
			(width 0)
			(type solid)
		)
		(fill yes)
		(layer "In4.Cu")
		(net "M_B_CPU0_SA_DQ<25>")
	)
	(gr_poly
		(pts
			(xy 332.613762 -263.07669) (xy 332.566772 -262.92429) (xy 332.305152 -262.92429) (xy 332.258162 -263.07669)
			(xy 332.258162 -263.12114) (xy 332.613762 -263.12114)
		)
		(stroke
			(width 0)
			(type solid)
		)
		(fill yes)
		(layer "In4.Cu")
		(net "M_B_CPU0_SA_DQS_DN<3>")
	)
	(gr_poly
		(pts
			(xy 332.613762 -262.668258) (xy 332.613762 -262.623808) (xy 332.258162 -262.623808) (xy 332.258162 -262.668258)
			(xy 332.305152 -262.820658) (xy 332.566772 -262.820658)
		)
		(stroke
			(width 0)
			(type solid)
		)
		(fill yes)
		(layer "In4.Cu")
		(net "M_B_CPU0_SA_DQS_DN<8>")
	)
	(gr_poly
		(pts
			(xy 332.613762 -261.449058) (xy 332.566772 -261.296658) (xy 332.305152 -261.296658) (xy 332.258162 -261.449058)
			(xy 332.258162 -261.493508) (xy 332.613762 -261.493508)
		)
		(stroke
			(width 0)
			(type solid)
		)
		(fill yes)
		(layer "In4.Cu")
		(net "M_B_CPU0_SA_DQ<30>")
	)
	(gr_poly
		(pts
			(xy 332.613762 -261.040626) (xy 332.613762 -260.996176) (xy 332.258162 -260.996176) (xy 332.258162 -261.040626)
			(xy 332.305152 -261.193026) (xy 332.566772 -261.193026)
		)
		(stroke
			(width 0)
			(type solid)
		)
		(fill yes)
		(layer "In4.Cu")
		(net "M_B_CPU0_SA_DQ<29>")
	)
	(gr_poly
		(pts
			(xy 332.8289 -223.223582) (xy 332.867254 -223.201484) (xy 332.689454 -222.893636) (xy 332.6511 -222.915734)
			(xy 332.542642 -223.032574) (xy 332.673452 -223.259142)
		)
		(stroke
			(width 0)
			(type solid)
		)
		(fill yes)
		(layer "In4.Cu")
		(net "M_B_CPU0_SB_DQ<30>")
	)
	(gr_poly
		(pts
			(xy 332.863444 -241.86134) (xy 332.82509 -241.839242) (xy 332.669642 -241.803682) (xy 332.538832 -242.03025)
			(xy 332.64729 -242.14709) (xy 332.685644 -242.169188)
		)
		(stroke
			(width 0)
			(type solid)
		)
		(fill yes)
		(layer "In4.Cu")
		(net "M_C_CPU0_SB_CB<7>")
	)
	(gr_poly
		(pts
			(xy 332.863444 -236.97819) (xy 332.82509 -236.956092) (xy 332.669642 -236.920532) (xy 332.538832 -237.1471)
			(xy 332.64729 -237.26394) (xy 332.685644 -237.286038)
		)
		(stroke
			(width 0)
			(type solid)
		)
		(fill yes)
		(layer "In4.Cu")
		(net "M_B_CPU0_SB_DQ<0>")
	)
	(gr_poly
		(pts
			(xy 332.939136 -224.231962) (xy 333.047594 -224.115122) (xy 332.916784 -223.888554) (xy 332.761336 -223.924114)
			(xy 332.722982 -223.946212) (xy 332.900782 -224.25406)
		)
		(stroke
			(width 0)
			(type solid)
		)
		(fill yes)
		(layer "In4.Cu")
		(net "M_B_CPU0_SB_DQS_DP<8>")
	)
	(gr_poly
		(pts
			(xy 332.939136 -222.604584) (xy 333.047594 -222.487744) (xy 332.916784 -222.261176) (xy 332.761336 -222.296736)
			(xy 332.722982 -222.318834) (xy 332.900782 -222.626682)
		)
		(stroke
			(width 0)
			(type solid)
		)
		(fill yes)
		(layer "In4.Cu")
		(net "M_B_CPU0_SB_DQ<28>")
	)
	(gr_poly
		(pts
			(xy 332.965298 -243.718842) (xy 332.965298 -243.674392) (xy 332.609698 -243.674392) (xy 332.609698 -243.718842)
			(xy 332.656688 -243.871242) (xy 332.918308 -243.871242)
		)
		(stroke
			(width 0)
			(type solid)
		)
		(fill yes)
		(layer "In4.Cu")
		(net "M_C_CPU0_SB_CB<4>")
	)
	(gr_poly
		(pts
			(xy 332.965298 -232.732326) (xy 332.918308 -232.579926) (xy 332.656688 -232.579926) (xy 332.609698 -232.732326)
			(xy 332.609698 -232.776776) (xy 332.965298 -232.776776)
		)
		(stroke
			(width 0)
			(type solid)
		)
		(fill yes)
		(layer "In4.Cu")
		(net "M_B_CPU0_SB_DQ<7>")
	)
	(gr_poly
		(pts
			(xy 332.965298 -232.324402) (xy 332.965298 -232.279952) (xy 332.609698 -232.279952) (xy 332.609698 -232.324402)
			(xy 332.656688 -232.476802) (xy 332.918308 -232.476802)
		)
		(stroke
			(width 0)
			(type solid)
		)
		(fill yes)
		(layer "In4.Cu")
		(net "M_C_CPU0_SB_DQ<16>")
	)
	(gr_poly
		(pts
			(xy 332.973934 -247.382538) (xy 332.926944 -247.230138) (xy 332.665324 -247.230138) (xy 332.618334 -247.382538)
			(xy 332.618334 -247.426988) (xy 332.973934 -247.426988)
		)
		(stroke
			(width 0)
			(type solid)
		)
		(fill yes)
		(layer "In4.Cu")
		(net "M_C_CPU0_SB_CA<5>")
	)
	(gr_poly
		(pts
			(xy 332.973934 -246.974106) (xy 332.973934 -246.929656) (xy 332.618334 -246.929656) (xy 332.618334 -246.974106)
			(xy 332.665324 -247.126506) (xy 332.926944 -247.126506)
		)
		(stroke
			(width 0)
			(type solid)
		)
		(fill yes)
		(layer "In4.Cu")
		(net "M_C_CPU0_SB_CA<6>")
	)
	(gr_poly
		(pts
			(xy 332.973934 -245.754906) (xy 332.926944 -245.602506) (xy 332.665324 -245.602506) (xy 332.618334 -245.754906)
			(xy 332.618334 -245.799356) (xy 332.973934 -245.799356)
		)
		(stroke
			(width 0)
			(type solid)
		)
		(fill yes)
		(layer "In4.Cu")
		(net "M_C_CPU0_SB_CS_N<0>")
	)
	(gr_poly
		(pts
			(xy 332.973934 -240.871502) (xy 332.926944 -240.719102) (xy 332.665324 -240.719102) (xy 332.618334 -240.871502)
			(xy 332.618334 -240.915952) (xy 332.973934 -240.915952)
		)
		(stroke
			(width 0)
			(type solid)
		)
		(fill yes)
		(layer "In4.Cu")
		(net "M_C_CPU0_SB_DQS_DN<9>")
	)
	(gr_poly
		(pts
			(xy 332.973934 -238.83493) (xy 332.973934 -238.790734) (xy 332.618334 -238.790734) (xy 332.618334 -238.83493)
			(xy 332.665324 -238.98733) (xy 332.926944 -238.98733)
		)
		(stroke
			(width 0)
			(type solid)
		)
		(fill yes)
		(layer "In4.Cu")
		(net "M_C_CPU0_SB_CB<1>")
	)
	(gr_poly
		(pts
			(xy 332.973934 -235.988098) (xy 332.926944 -235.835698) (xy 332.665324 -235.835698) (xy 332.618334 -235.988098)
			(xy 332.618334 -236.032548) (xy 332.973934 -236.032548)
		)
		(stroke
			(width 0)
			(type solid)
		)
		(fill yes)
		(layer "In4.Cu")
		(net "M_B_CPU0_SB_DQ<3>")
	)
	(gr_poly
		(pts
			(xy 332.973934 -233.952034) (xy 332.973934 -233.907584) (xy 332.618334 -233.907584) (xy 332.618334 -233.952034)
			(xy 332.665324 -234.104434) (xy 332.926944 -234.104434)
		)
		(stroke
			(width 0)
			(type solid)
		)
		(fill yes)
		(layer "In4.Cu")
		(net "M_B_CPU0_SB_DQ<4>")
	)
	(gr_poly
		(pts
			(xy 332.973934 -231.104694) (xy 332.926944 -230.952294) (xy 332.665324 -230.952294) (xy 332.618334 -231.104694)
			(xy 332.618334 -231.149144) (xy 332.973934 -231.149144)
		)
		(stroke
			(width 0)
			(type solid)
		)
		(fill yes)
		(layer "In4.Cu")
		(net "M_C_CPU0_SB_DQ<19>")
	)
	(gr_poly
		(pts
			(xy 332.973934 -229.06863) (xy 332.973934 -229.02418) (xy 332.618334 -229.02418) (xy 332.618334 -229.06863)
			(xy 332.665324 -229.22103) (xy 332.926944 -229.22103)
		)
		(stroke
			(width 0)
			(type solid)
		)
		(fill yes)
		(layer "In4.Cu")
		(net "M_C_CPU0_SB_DQ<20>")
	)
	(gr_poly
		(pts
			(xy 332.977998 -227.855018) (xy 332.931008 -227.702618) (xy 332.669388 -227.702618) (xy 332.622398 -227.855018)
			(xy 332.622398 -227.899468) (xy 332.977998 -227.899468)
		)
		(stroke
			(width 0)
			(type solid)
		)
		(fill yes)
		(layer "In4.Cu")
		(net "M_C_CPU0_SB_DQ<23>")
	)
	(gr_poly
		(pts
			(xy 332.982316 -245.346474) (xy 332.982316 -245.302278) (xy 332.626716 -245.302278) (xy 332.626716 -245.346474)
			(xy 332.673706 -245.498874) (xy 332.935326 -245.498874)
		)
		(stroke
			(width 0)
			(type solid)
		)
		(fill yes)
		(layer "In4.Cu")
		(net "M_C_CPU0_SB_CS_N<3>")
	)
	(gr_poly
		(pts
			(xy 332.982316 -239.243362) (xy 332.935326 -239.090962) (xy 332.673706 -239.090962) (xy 332.626716 -239.243362)
			(xy 332.626716 -239.287812) (xy 332.982316 -239.287812)
		)
		(stroke
			(width 0)
			(type solid)
		)
		(fill yes)
		(layer "In4.Cu")
		(net "M_C_CPU0_SB_CB<2>")
	)
	(gr_poly
		(pts
			(xy 332.982316 -235.579666) (xy 332.982316 -235.53547) (xy 332.626716 -235.53547) (xy 332.626716 -235.579666)
			(xy 332.673706 -235.732066) (xy 332.935326 -235.732066)
		)
		(stroke
			(width 0)
			(type solid)
		)
		(fill yes)
		(layer "In4.Cu")
		(net "M_B_CPU0_SB_DQS_DP<0>")
	)
	(gr_poly
		(pts
			(xy 332.982316 -234.360466) (xy 332.935326 -234.208066) (xy 332.673706 -234.208066) (xy 332.626716 -234.360466)
			(xy 332.626716 -234.404662) (xy 332.982316 -234.404662)
		)
		(stroke
			(width 0)
			(type solid)
		)
		(fill yes)
		(layer "In4.Cu")
		(net "M_B_CPU0_SB_DQS_DP<5>")
	)
	(gr_poly
		(pts
			(xy 332.982316 -230.696262) (xy 332.982316 -230.652066) (xy 332.626716 -230.652066) (xy 332.626716 -230.696262)
			(xy 332.673706 -230.848662) (xy 332.935326 -230.848662)
		)
		(stroke
			(width 0)
			(type solid)
		)
		(fill yes)
		(layer "In4.Cu")
		(net "M_C_CPU0_SB_DQS_DP<2>")
	)
	(gr_poly
		(pts
			(xy 332.982316 -229.477062) (xy 332.935326 -229.324662) (xy 332.673706 -229.324662) (xy 332.626716 -229.477062)
			(xy 332.626716 -229.521258) (xy 332.982316 -229.521258)
		)
		(stroke
			(width 0)
			(type solid)
		)
		(fill yes)
		(layer "In4.Cu")
		(net "M_C_CPU0_SB_DQS_DP<7>")
	)
	(gr_poly
		(pts
			(xy 333.045816 -242.570762) (xy 332.937358 -242.453922) (xy 332.899004 -242.431824) (xy 332.721204 -242.739672)
			(xy 332.759558 -242.76177) (xy 332.915006 -242.79733)
		)
		(stroke
			(width 0)
			(type solid)
		)
		(fill yes)
		(layer "In4.Cu")
		(net "M_C_CPU0_SB_CB<5>")
	)
	(gr_poly
		(pts
			(xy 333.047594 -237.686088) (xy 332.939136 -237.569248) (xy 332.900782 -237.54715) (xy 332.722982 -237.854998)
			(xy 332.761336 -237.877096) (xy 332.916784 -237.912656)
		)
		(stroke
			(width 0)
			(type solid)
		)
		(fill yes)
		(layer "In4.Cu")
		(net "M_B_CPU0_SB_DQ<2>")
	)
	(gr_poly
		(pts
			(xy 333.083662 -266.737846) (xy 333.083662 -266.693396) (xy 332.728062 -266.693396) (xy 332.728062 -266.737846)
			(xy 332.775052 -266.890246) (xy 333.036672 -266.890246)
		)
		(stroke
			(width 0)
			(type solid)
		)
		(fill yes)
		(layer "In4.Cu")
		(net "M_C_CPU0_SA_DQ<20>")
	)
	(gr_poly
		(pts
			(xy 333.083662 -265.518646) (xy 333.036672 -265.366246) (xy 332.775052 -265.366246) (xy 332.728062 -265.518646)
			(xy 332.728062 -265.562842) (xy 333.083662 -265.562842)
		)
		(stroke
			(width 0)
			(type solid)
		)
		(fill yes)
		(layer "In4.Cu")
		(net "M_C_CPU0_SA_DQ<23>")
	)
	(gr_poly
		(pts
			(xy 333.083662 -265.109706) (xy 333.083662 -265.06551) (xy 332.728062 -265.06551) (xy 332.728062 -265.109706)
			(xy 332.775052 -265.262106) (xy 333.036672 -265.262106)
		)
		(stroke
			(width 0)
			(type solid)
		)
		(fill yes)
		(layer "In4.Cu")
		(net "M_B_CPU0_SA_DQ<26>")
	)
	(gr_poly
		(pts
			(xy 333.083662 -263.891014) (xy 333.036672 -263.738614) (xy 332.775052 -263.738614) (xy 332.728062 -263.891014)
			(xy 332.728062 -263.93521) (xy 333.083662 -263.93521)
		)
		(stroke
			(width 0)
			(type solid)
		)
		(fill yes)
		(layer "In4.Cu")
		(net "M_B_CPU0_SA_DQ<27>")
	)
	(gr_poly
		(pts
			(xy 333.083662 -263.482074) (xy 333.083662 -263.437878) (xy 332.728062 -263.437878) (xy 332.728062 -263.482074)
			(xy 332.775052 -263.634474) (xy 333.036672 -263.634474)
		)
		(stroke
			(width 0)
			(type solid)
		)
		(fill yes)
		(layer "In4.Cu")
		(net "M_B_CPU0_SA_DQS_DP<3>")
	)
	(gr_poly
		(pts
			(xy 333.083662 -262.262874) (xy 333.036672 -262.110474) (xy 332.775052 -262.110474) (xy 332.728062 -262.262874)
			(xy 332.728062 -262.307324) (xy 333.083662 -262.307324)
		)
		(stroke
			(width 0)
			(type solid)
		)
		(fill yes)
		(layer "In4.Cu")
		(net "M_B_CPU0_SA_DQS_DP<8>")
	)
	(gr_poly
		(pts
			(xy 333.083662 -261.854442) (xy 333.083662 -261.809992) (xy 332.728062 -261.809992) (xy 332.728062 -261.854442)
			(xy 332.775052 -262.006842) (xy 333.036672 -262.006842)
		)
		(stroke
			(width 0)
			(type solid)
		)
		(fill yes)
		(layer "In4.Cu")
		(net "M_B_CPU0_SA_DQ<28>")
	)
	(gr_poly
		(pts
			(xy 333.083662 -260.635242) (xy 333.036672 -260.482842) (xy 332.775052 -260.482842) (xy 332.728062 -260.635242)
			(xy 332.728062 -260.679438) (xy 333.083662 -260.679438)
		)
		(stroke
			(width 0)
			(type solid)
		)
		(fill yes)
		(layer "In4.Cu")
		(net "M_B_CPU0_SA_DQ<31>")
	)
	(gr_poly
		(pts
			(xy 333.298546 -222.409512) (xy 333.3369 -222.387414) (xy 333.1591 -222.079566) (xy 333.120746 -222.101664)
			(xy 333.012288 -222.218504) (xy 333.143098 -222.445072)
		)
		(stroke
			(width 0)
			(type solid)
		)
		(fill yes)
		(layer "In4.Cu")
		(net "M_B_CPU0_SB_DQ<31>")
	)
	(gr_poly
		(pts
			(xy 333.337662 -244.29593) (xy 333.299308 -244.273832) (xy 333.14386 -244.238272) (xy 333.01305 -244.46484)
			(xy 333.121508 -244.58168) (xy 333.159862 -244.603778)
		)
		(stroke
			(width 0)
			(type solid)
		)
		(fill yes)
		(layer "In4.Cu")
		(net "M_C_CPU0_SB_CS_N<1>")
	)
	(gr_poly
		(pts
			(xy 333.338932 -237.782354) (xy 333.300578 -237.760256) (xy 333.14513 -237.724696) (xy 333.01432 -237.951264)
			(xy 333.122778 -238.068104) (xy 333.161132 -238.090202)
		)
		(stroke
			(width 0)
			(type solid)
		)
		(fill yes)
		(layer "In4.Cu")
		(net "M_C_CPU0_SB_CB<3>")
	)
	(gr_poly
		(pts
			(xy 333.34071 -242.664234) (xy 333.302356 -242.642136) (xy 333.146908 -242.606576) (xy 333.016098 -242.833144)
			(xy 333.124556 -242.949984) (xy 333.16291 -242.972082)
		)
		(stroke
			(width 0)
			(type solid)
		)
		(fill yes)
		(layer "In4.Cu")
		(net "M_C_CPU0_SB_CB<6>")
	)
	(gr_poly
		(pts
			(xy 333.40929 -223.418654) (xy 333.517748 -223.301814) (xy 333.386938 -223.075246) (xy 333.23149 -223.110806)
			(xy 333.193136 -223.132904) (xy 333.370936 -223.440752)
		)
		(stroke
			(width 0)
			(type solid)
		)
		(fill yes)
		(layer "In4.Cu")
		(net "M_B_CPU0_SB_DQ<28>")
	)
	(gr_poly
		(pts
			(xy 333.435198 -240.057178) (xy 333.388208 -239.904778) (xy 333.126588 -239.904778) (xy 333.079598 -240.057178)
			(xy 333.079598 -240.101628) (xy 333.435198 -240.101628)
		)
		(stroke
			(width 0)
			(type solid)
		)
		(fill yes)
		(layer "In4.Cu")
		(net "M_C_CPU0_SB_DQS_DP<4>")
	)
	(gr_poly
		(pts
			(xy 333.435198 -239.649254) (xy 333.435198 -239.604804) (xy 333.079598 -239.604804) (xy 333.079598 -239.649254)
			(xy 333.126588 -239.801654) (xy 333.388208 -239.801654)
		)
		(stroke
			(width 0)
			(type solid)
		)
		(fill yes)
		(layer "In4.Cu")
		(net "M_C_CPU0_SB_CB<0>")
	)
	(gr_poly
		(pts
			(xy 333.435198 -235.174282) (xy 333.388208 -235.021882) (xy 333.126588 -235.021882) (xy 333.079598 -235.174282)
			(xy 333.079598 -235.218478) (xy 333.435198 -235.218478)
		)
		(stroke
			(width 0)
			(type solid)
		)
		(fill yes)
		(layer "In4.Cu")
		(net "M_B_CPU0_SB_DQS_DN<0>")
	)
	(gr_poly
		(pts
			(xy 333.435198 -234.76585) (xy 333.435198 -234.721654) (xy 333.079598 -234.721654) (xy 333.079598 -234.76585)
			(xy 333.126588 -234.91825) (xy 333.388208 -234.91825)
		)
		(stroke
			(width 0)
			(type solid)
		)
		(fill yes)
		(layer "In4.Cu")
		(net "M_B_CPU0_SB_DQS_DN<5>")
	)
	(gr_poly
		(pts
			(xy 333.435198 -230.290878) (xy 333.388208 -230.138478) (xy 333.126588 -230.138478) (xy 333.079598 -230.290878)
			(xy 333.079598 -230.335074) (xy 333.435198 -230.335074)
		)
		(stroke
			(width 0)
			(type solid)
		)
		(fill yes)
		(layer "In4.Cu")
		(net "M_C_CPU0_SB_DQS_DN<2>")
	)
	(gr_poly
		(pts
			(xy 333.435198 -229.882446) (xy 333.435198 -229.83825) (xy 333.079598 -229.83825) (xy 333.079598 -229.882446)
			(xy 333.126588 -230.034846) (xy 333.388208 -230.034846)
		)
		(stroke
			(width 0)
			(type solid)
		)
		(fill yes)
		(layer "In4.Cu")
		(net "M_C_CPU0_SB_DQS_DN<7>")
	)
	(gr_poly
		(pts
			(xy 333.443326 -273.833336) (xy 333.404972 -273.811238) (xy 333.249524 -273.775678) (xy 333.118714 -274.002246)
			(xy 333.227172 -274.119086) (xy 333.265526 -274.141184)
		)
		(stroke
			(width 0)
			(type solid)
		)
		(fill yes)
		(layer "In4.Cu")
		(net "M_B_CPU0_SA_DQS_DP<6>")
	)
	(gr_poly
		(pts
			(xy 333.443834 -247.787922) (xy 333.443834 -247.743472) (xy 333.088234 -247.743472) (xy 333.088234 -247.787922)
			(xy 333.135224 -247.940322) (xy 333.396844 -247.940322)
		)
		(stroke
			(width 0)
			(type solid)
		)
		(fill yes)
		(layer "In4.Cu")
		(net "M_C_CPU0_SB_CA<4>")
	)
	(gr_poly
		(pts
			(xy 333.443834 -246.568722) (xy 333.396844 -246.416322) (xy 333.135224 -246.416322) (xy 333.088234 -246.568722)
			(xy 333.088234 -246.613172) (xy 333.443834 -246.613172)
		)
		(stroke
			(width 0)
			(type solid)
		)
		(fill yes)
		(layer "In4.Cu")
		(net "M_C_CPU0_SB_PAR")
	)
	(gr_poly
		(pts
			(xy 333.443834 -246.16029) (xy 333.443834 -246.11584) (xy 333.088234 -246.11584) (xy 333.088234 -246.16029)
			(xy 333.135224 -246.31269) (xy 333.396844 -246.31269)
		)
		(stroke
			(width 0)
			(type solid)
		)
		(fill yes)
		(layer "In4.Cu")
		(net "M_C_CPU0_SB_CS_N<2>")
	)
	(gr_poly
		(pts
			(xy 333.443834 -241.276886) (xy 333.443834 -241.232436) (xy 333.088234 -241.232436) (xy 333.088234 -241.276886)
			(xy 333.135224 -241.429286) (xy 333.396844 -241.429286)
		)
		(stroke
			(width 0)
			(type solid)
		)
		(fill yes)
		(layer "In4.Cu")
		(net "M_C_CPU0_SB_DQS_DP<9>")
	)
	(gr_poly
		(pts
			(xy 333.443834 -236.393482) (xy 333.443834 -236.349286) (xy 333.088234 -236.349286) (xy 333.088234 -236.393482)
			(xy 333.135224 -236.545882) (xy 333.396844 -236.545882)
		)
		(stroke
			(width 0)
			(type solid)
		)
		(fill yes)
		(layer "In4.Cu")
		(net "M_B_CPU0_SB_DQ<1>")
	)
	(gr_poly
		(pts
			(xy 333.443834 -233.54665) (xy 333.396844 -233.39425) (xy 333.135224 -233.39425) (xy 333.088234 -233.54665)
			(xy 333.088234 -233.590846) (xy 333.443834 -233.590846)
		)
		(stroke
			(width 0)
			(type solid)
		)
		(fill yes)
		(layer "In4.Cu")
		(net "M_B_CPU0_SB_DQ<6>")
	)
	(gr_poly
		(pts
			(xy 333.443834 -231.510078) (xy 333.443834 -231.465882) (xy 333.088234 -231.465882) (xy 333.088234 -231.510078)
			(xy 333.135224 -231.662478) (xy 333.396844 -231.662478)
		)
		(stroke
			(width 0)
			(type solid)
		)
		(fill yes)
		(layer "In4.Cu")
		(net "M_C_CPU0_SB_DQ<17>")
	)
	(gr_poly
		(pts
			(xy 333.443834 -228.663246) (xy 333.396844 -228.510846) (xy 333.135224 -228.510846) (xy 333.088234 -228.663246)
			(xy 333.088234 -228.707696) (xy 333.443834 -228.707696)
		)
		(stroke
			(width 0)
			(type solid)
		)
		(fill yes)
		(layer "In4.Cu")
		(net "M_C_CPU0_SB_DQ<22>")
	)
	(gr_poly
		(pts
			(xy 333.443834 -224.998534) (xy 333.443834 -224.954338) (xy 333.088234 -224.954338) (xy 333.088234 -224.998534)
			(xy 333.135224 -225.150934) (xy 333.396844 -225.150934)
		)
		(stroke
			(width 0)
			(type solid)
		)
		(fill yes)
		(layer "In4.Cu")
		(net "M_B_CPU0_SB_DQS_DN<8>")
	)
	(gr_poly
		(pts
			(xy 333.449422 -275.450046) (xy 333.411068 -275.427948) (xy 333.25562 -275.392388) (xy 333.12481 -275.618956)
			(xy 333.233268 -275.735796) (xy 333.271622 -275.757894)
		)
		(stroke
			(width 0)
			(type solid)
		)
		(fill yes)
		(layer "In4.Cu")
		(net "M_B_CPU0_SA_DQS_DN<1>")
	)
	(gr_poly
		(pts
			(xy 333.449676 -272.194528) (xy 333.411322 -272.17243) (xy 333.255874 -272.13687) (xy 333.125064 -272.363438)
			(xy 333.233522 -272.480278) (xy 333.271876 -272.502376)
		)
		(stroke
			(width 0)
			(type solid)
		)
		(fill yes)
		(layer "In4.Cu")
		(net "M_B_CPU0_SA_DQ<14>")
	)
	(gr_poly
		(pts
			(xy 333.449676 -226.627182) (xy 333.449676 -226.582732) (xy 333.094076 -226.582732) (xy 333.094076 -226.627182)
			(xy 333.141066 -226.779582) (xy 333.402686 -226.779582)
		)
		(stroke
			(width 0)
			(type solid)
		)
		(fill yes)
		(layer "In4.Cu")
		(net "M_B_CPU0_SB_DQ<24>")
	)
	(gr_poly
		(pts
			(xy 333.452216 -241.685318) (xy 333.405226 -241.532918) (xy 333.143606 -241.532918) (xy 333.096616 -241.685318)
			(xy 333.096616 -241.729514) (xy 333.452216 -241.729514)
		)
		(stroke
			(width 0)
			(type solid)
		)
		(fill yes)
		(layer "In4.Cu")
		(net "M_C_CPU0_SB_CB<7>")
	)
	(gr_poly
		(pts
			(xy 333.452216 -236.801914) (xy 333.405226 -236.649514) (xy 333.143606 -236.649514) (xy 333.096616 -236.801914)
			(xy 333.096616 -236.846364) (xy 333.452216 -236.846364)
		)
		(stroke
			(width 0)
			(type solid)
		)
		(fill yes)
		(layer "In4.Cu")
		(net "M_B_CPU0_SB_DQ<0>")
	)
	(gr_poly
		(pts
			(xy 333.452216 -233.138218) (xy 333.452216 -233.093768) (xy 333.096616 -233.093768) (xy 333.096616 -233.138218)
			(xy 333.143606 -233.290618) (xy 333.405226 -233.290618)
		)
		(stroke
			(width 0)
			(type solid)
		)
		(fill yes)
		(layer "In4.Cu")
		(net "M_B_CPU0_SB_DQ<5>")
	)
	(gr_poly
		(pts
			(xy 333.452216 -231.91851) (xy 333.405226 -231.76611) (xy 333.143606 -231.76611) (xy 333.096616 -231.91851)
			(xy 333.096616 -231.96296) (xy 333.452216 -231.96296)
		)
		(stroke
			(width 0)
			(type solid)
		)
		(fill yes)
		(layer "In4.Cu")
		(net "M_C_CPU0_SB_DQ<18>")
	)
	(gr_poly
		(pts
			(xy 333.452216 -228.254814) (xy 333.452216 -228.210618) (xy 333.096616 -228.210618) (xy 333.096616 -228.254814)
			(xy 333.143606 -228.407214) (xy 333.405226 -228.407214)
		)
		(stroke
			(width 0)
			(type solid)
		)
		(fill yes)
		(layer "In4.Cu")
		(net "M_C_CPU0_SB_DQ<21>")
	)
	(gr_poly
		(pts
			(xy 333.515716 -245.013734) (xy 333.407258 -244.896894) (xy 333.368904 -244.874796) (xy 333.191104 -245.182644)
			(xy 333.229458 -245.204742) (xy 333.384906 -245.240302)
		)
		(stroke
			(width 0)
			(type solid)
		)
		(fill yes)
		(layer "In4.Cu")
		(net "M_C_CPU0_SB_CS_N<3>")
	)
	(gr_poly
		(pts
			(xy 333.518764 -238.497364) (xy 333.410306 -238.380524) (xy 333.371952 -238.358426) (xy 333.194152 -238.666274)
			(xy 333.232506 -238.688372) (xy 333.387954 -238.723932)
		)
		(stroke
			(width 0)
			(type solid)
		)
		(fill yes)
		(layer "In4.Cu")
		(net "M_C_CPU0_SB_CB<1>")
	)
	(gr_poly
		(pts
			(xy 333.523082 -243.373656) (xy 333.414624 -243.256816) (xy 333.37627 -243.234718) (xy 333.19847 -243.542566)
			(xy 333.236824 -243.564664) (xy 333.392272 -243.600224)
		)
		(stroke
			(width 0)
			(type solid)
		)
		(fill yes)
		(layer "In4.Cu")
		(net "M_C_CPU0_SB_CB<4>")
	)
	(gr_poly
		(pts
			(xy 333.553562 -267.960094) (xy 333.506572 -267.807694) (xy 333.244952 -267.807694) (xy 333.197962 -267.960094)
			(xy 333.197962 -268.004544) (xy 333.553562 -268.004544)
		)
		(stroke
			(width 0)
			(type solid)
		)
		(fill yes)
		(layer "In4.Cu")
		(net "M_C_CPU0_SA_DQS_DN<2>")
	)
	(gr_poly
		(pts
			(xy 333.553562 -267.551662) (xy 333.553562 -267.507212) (xy 333.197962 -267.507212) (xy 333.197962 -267.551662)
			(xy 333.244952 -267.704062) (xy 333.506572 -267.704062)
		)
		(stroke
			(width 0)
			(type solid)
		)
		(fill yes)
		(layer "In4.Cu")
		(net "M_C_CPU0_SA_DQS_DN<7>")
	)
	(gr_poly
		(pts
			(xy 333.553562 -266.332462) (xy 333.506572 -266.180062) (xy 333.244952 -266.180062) (xy 333.197962 -266.332462)
			(xy 333.197962 -266.376658) (xy 333.553562 -266.376658)
		)
		(stroke
			(width 0)
			(type solid)
		)
		(fill yes)
		(layer "In4.Cu")
		(net "M_C_CPU0_SA_DQ<22>")
	)
	(gr_poly
		(pts
			(xy 333.553562 -265.92403) (xy 333.553562 -265.87958) (xy 333.197962 -265.87958) (xy 333.197962 -265.92403)
			(xy 333.244952 -266.07643) (xy 333.506572 -266.07643)
		)
		(stroke
			(width 0)
			(type solid)
		)
		(fill yes)
		(layer "In4.Cu")
		(net "M_C_CPU0_SA_DQ<21>")
	)
	(gr_poly
		(pts
			(xy 333.553562 -264.70483) (xy 333.506572 -264.55243) (xy 333.244952 -264.55243) (xy 333.197962 -264.70483)
			(xy 333.197962 -264.749026) (xy 333.553562 -264.749026)
		)
		(stroke
			(width 0)
			(type solid)
		)
		(fill yes)
		(layer "In4.Cu")
		(net "M_B_CPU0_SA_DQ<24>")
	)
	(gr_poly
		(pts
			(xy 333.553562 -264.29589) (xy 333.553562 -264.251694) (xy 333.197962 -264.251694) (xy 333.197962 -264.29589)
			(xy 333.244952 -264.44829) (xy 333.506572 -264.44829)
		)
		(stroke
			(width 0)
			(type solid)
		)
		(fill yes)
		(layer "In4.Cu")
		(net "M_B_CPU0_SA_DQ<25>")
	)
	(gr_poly
		(pts
			(xy 333.553562 -263.07669) (xy 333.506572 -262.92429) (xy 333.244952 -262.92429) (xy 333.197962 -263.07669)
			(xy 333.197962 -263.12114) (xy 333.553562 -263.12114)
		)
		(stroke
			(width 0)
			(type solid)
		)
		(fill yes)
		(layer "In4.Cu")
		(net "M_B_CPU0_SA_DQS_DN<3>")
	)
	(gr_poly
		(pts
			(xy 333.553562 -262.668258) (xy 333.553562 -262.623808) (xy 333.197962 -262.623808) (xy 333.197962 -262.668258)
			(xy 333.244952 -262.820658) (xy 333.506572 -262.820658)
		)
		(stroke
			(width 0)
			(type solid)
		)
		(fill yes)
		(layer "In4.Cu")
		(net "M_B_CPU0_SA_DQS_DN<8>")
	)
	(gr_poly
		(pts
			(xy 333.553562 -261.449058) (xy 333.506572 -261.296658) (xy 333.244952 -261.296658) (xy 333.197962 -261.449058)
			(xy 333.197962 -261.493508) (xy 333.553562 -261.493508)
		)
		(stroke
			(width 0)
			(type solid)
		)
		(fill yes)
		(layer "In4.Cu")
		(net "M_B_CPU0_SA_DQ<30>")
	)
	(gr_poly
		(pts
			(xy 333.553562 -261.040626) (xy 333.553562 -260.996176) (xy 333.197962 -260.996176) (xy 333.197962 -261.040626)
			(xy 333.244952 -261.193026) (xy 333.506572 -261.193026)
		)
		(stroke
			(width 0)
			(type solid)
		)
		(fill yes)
		(layer "In4.Cu")
		(net "M_B_CPU0_SA_DQ<29>")
	)
	(gr_poly
		(pts
			(xy 333.63281 -274.531582) (xy 333.524352 -274.414742) (xy 333.485998 -274.392644) (xy 333.308198 -274.700492)
			(xy 333.346552 -274.72259) (xy 333.502 -274.75815)
		)
		(stroke
			(width 0)
			(type solid)
		)
		(fill yes)
		(layer "In4.Cu")
		(net "M_B_CPU0_SA_DQS_DN<6>")
	)
	(gr_poly
		(pts
			(xy 333.7687 -223.223582) (xy 333.807054 -223.201484) (xy 333.629254 -222.893636) (xy 333.5909 -222.915734)
			(xy 333.482442 -223.032574) (xy 333.613252 -223.259142)
		)
		(stroke
			(width 0)
			(type solid)
		)
		(fill yes)
		(layer "In4.Cu")
		(net "M_B_CPU0_SB_DQ<31>")
	)
	(gr_poly
		(pts
			(xy 333.803244 -243.489226) (xy 333.76489 -243.467128) (xy 333.609442 -243.431568) (xy 333.478632 -243.658136)
			(xy 333.58709 -243.774976) (xy 333.625444 -243.797074)
		)
		(stroke
			(width 0)
			(type solid)
		)
		(fill yes)
		(layer "In4.Cu")
		(net "M_C_CPU0_SB_CS_N<1>")
	)
	(gr_poly
		(pts
			(xy 333.807816 -238.59871) (xy 333.769462 -238.576612) (xy 333.614014 -238.541052) (xy 333.483204 -238.76762)
			(xy 333.591662 -238.88446) (xy 333.630016 -238.906558)
		)
		(stroke
			(width 0)
			(type solid)
		)
		(fill yes)
		(layer "In4.Cu")
		(net "M_C_CPU0_SB_CB<2>")
	)
	(gr_poly
		(pts
			(xy 333.81061 -245.104666) (xy 333.772256 -245.082568) (xy 333.616808 -245.047008) (xy 333.485998 -245.273576)
			(xy 333.594456 -245.390416) (xy 333.63281 -245.412514)
		)
		(stroke
			(width 0)
			(type solid)
		)
		(fill yes)
		(layer "In4.Cu")
		(net "M_C_CPU0_SB_CS_N<0>")
	)
	(gr_poly
		(pts
			(xy 333.87919 -222.604584) (xy 333.987648 -222.487744) (xy 333.856838 -222.261176) (xy 333.70139 -222.296736)
			(xy 333.663036 -222.318834) (xy 333.840836 -222.626682)
		)
		(stroke
			(width 0)
			(type solid)
		)
		(fill yes)
		(layer "In4.Cu")
		(net "M_B_CPU0_SB_DQ<29>")
	)
	(gr_poly
		(pts
			(xy 333.907638 -242.499134) (xy 333.860648 -242.346734) (xy 333.599028 -242.346734) (xy 333.552038 -242.499134)
			(xy 333.552038 -242.54333) (xy 333.907638 -242.54333)
		)
		(stroke
			(width 0)
			(type solid)
		)
		(fill yes)
		(layer "In4.Cu")
		(net "M_C_CPU0_SB_CB<6>")
	)
	(gr_poly
		(pts
			(xy 333.907638 -242.090702) (xy 333.907638 -242.046506) (xy 333.552038 -242.046506) (xy 333.552038 -242.090702)
			(xy 333.599028 -242.243102) (xy 333.860648 -242.243102)
		)
		(stroke
			(width 0)
			(type solid)
		)
		(fill yes)
		(layer "In4.Cu")
		(net "M_C_CPU0_SB_CB<5>")
	)
	(gr_poly
		(pts
			(xy 333.907638 -237.61573) (xy 333.860648 -237.46333) (xy 333.599028 -237.46333) (xy 333.552038 -237.61573)
			(xy 333.552038 -237.66018) (xy 333.907638 -237.66018)
		)
		(stroke
			(width 0)
			(type solid)
		)
		(fill yes)
		(layer "In4.Cu")
		(net "M_C_CPU0_SB_CB<3>")
	)
	(gr_poly
		(pts
			(xy 333.907638 -237.207806) (xy 333.907638 -237.163356) (xy 333.552038 -237.163356) (xy 333.552038 -237.207806)
			(xy 333.599028 -237.360206) (xy 333.860648 -237.360206)
		)
		(stroke
			(width 0)
			(type solid)
		)
		(fill yes)
		(layer "In4.Cu")
		(net "M_B_CPU0_SB_DQ<2>")
	)
	(gr_poly
		(pts
			(xy 333.907638 -232.732326) (xy 333.860648 -232.579926) (xy 333.599028 -232.579926) (xy 333.552038 -232.732326)
			(xy 333.552038 -232.776776) (xy 333.907638 -232.776776)
		)
		(stroke
			(width 0)
			(type solid)
		)
		(fill yes)
		(layer "In4.Cu")
		(net "M_B_CPU0_SB_DQ<7>")
	)
	(gr_poly
		(pts
			(xy 333.907638 -232.324402) (xy 333.907638 -232.279952) (xy 333.552038 -232.279952) (xy 333.552038 -232.324402)
			(xy 333.599028 -232.476802) (xy 333.860648 -232.476802)
		)
		(stroke
			(width 0)
			(type solid)
		)
		(fill yes)
		(layer "In4.Cu")
		(net "M_C_CPU0_SB_DQ<16>")
	)
	(gr_poly
		(pts
			(xy 333.907638 -227.848922) (xy 333.860648 -227.696522) (xy 333.599028 -227.696522) (xy 333.552038 -227.848922)
			(xy 333.552038 -227.893372) (xy 333.907638 -227.893372)
		)
		(stroke
			(width 0)
			(type solid)
		)
		(fill yes)
		(layer "In4.Cu")
		(net "M_C_CPU0_SB_DQ<23>")
	)
	(gr_poly
		(pts
			(xy 333.907638 -226.22129) (xy 333.860648 -226.06889) (xy 333.599028 -226.06889) (xy 333.552038 -226.22129)
			(xy 333.552038 -226.26574) (xy 333.907638 -226.26574)
		)
		(stroke
			(width 0)
			(type solid)
		)
		(fill yes)
		(layer "In4.Cu")
		(net "M_B_CPU0_SB_DQ<26>")
	)
	(gr_poly
		(pts
			(xy 333.907638 -224.593658) (xy 333.860648 -224.441258) (xy 333.599028 -224.441258) (xy 333.552038 -224.593658)
			(xy 333.552038 -224.637854) (xy 333.907638 -224.637854)
		)
		(stroke
			(width 0)
			(type solid)
		)
		(fill yes)
		(layer "In4.Cu")
		(net "M_B_CPU0_SB_DQS_DP<8>")
	)
	(gr_poly
		(pts
			(xy 333.912972 -282.786074) (xy 333.874618 -282.763976) (xy 333.71917 -282.728416) (xy 333.58836 -282.954984)
			(xy 333.696818 -283.071824) (xy 333.735172 -283.093922)
		)
		(stroke
			(width 0)
			(type solid)
		)
		(fill yes)
		(layer "In4.Cu")
		(net "M_C_CPU0_SA_DQS_DP<5>")
	)
	(gr_poly
		(pts
			(xy 333.912972 -274.647152) (xy 333.874618 -274.625054) (xy 333.71917 -274.589494) (xy 333.58836 -274.816062)
			(xy 333.696818 -274.932902) (xy 333.735172 -274.955)
		)
		(stroke
			(width 0)
			(type solid)
		)
		(fill yes)
		(layer "In4.Cu")
		(net "M_B_CPU0_SA_DQS_DN<1>")
	)
	(gr_poly
		(pts
			(xy 333.913226 -273.019774) (xy 333.874872 -272.997676) (xy 333.719424 -272.962116) (xy 333.588614 -273.188684)
			(xy 333.697072 -273.305524) (xy 333.735426 -273.327622)
		)
		(stroke
			(width 0)
			(type solid)
		)
		(fill yes)
		(layer "In4.Cu")
		(net "M_B_CPU0_SA_DQS_DP<6>")
	)
	(gr_poly
		(pts
			(xy 333.913734 -247.382538) (xy 333.866744 -247.230138) (xy 333.605124 -247.230138) (xy 333.558134 -247.382538)
			(xy 333.558134 -247.426988) (xy 333.913734 -247.426988)
		)
		(stroke
			(width 0)
			(type solid)
		)
		(fill yes)
		(layer "In4.Cu")
		(net "M_C_CPU0_SB_CA<5>")
	)
	(gr_poly
		(pts
			(xy 333.913734 -246.974106) (xy 333.913734 -246.929656) (xy 333.558134 -246.929656) (xy 333.558134 -246.974106)
			(xy 333.605124 -247.126506) (xy 333.866744 -247.126506)
		)
		(stroke
			(width 0)
			(type solid)
		)
		(fill yes)
		(layer "In4.Cu")
		(net "M_C_CPU0_SB_CA<6>")
	)
	(gr_poly
		(pts
			(xy 333.913734 -240.871502) (xy 333.866744 -240.719102) (xy 333.605124 -240.719102) (xy 333.558134 -240.871502)
			(xy 333.558134 -240.915952) (xy 333.913734 -240.915952)
		)
		(stroke
			(width 0)
			(type solid)
		)
		(fill yes)
		(layer "In4.Cu")
		(net "M_C_CPU0_SB_DQS_DN<9>")
	)
	(gr_poly
		(pts
			(xy 333.913734 -235.988098) (xy 333.866744 -235.835698) (xy 333.605124 -235.835698) (xy 333.558134 -235.988098)
			(xy 333.558134 -236.032548) (xy 333.913734 -236.032548)
		)
		(stroke
			(width 0)
			(type solid)
		)
		(fill yes)
		(layer "In4.Cu")
		(net "M_B_CPU0_SB_DQ<3>")
	)
	(gr_poly
		(pts
			(xy 333.913734 -233.952034) (xy 333.913734 -233.907584) (xy 333.558134 -233.907584) (xy 333.558134 -233.952034)
			(xy 333.605124 -234.104434) (xy 333.866744 -234.104434)
		)
		(stroke
			(width 0)
			(type solid)
		)
		(fill yes)
		(layer "In4.Cu")
		(net "M_B_CPU0_SB_DQ<4>")
	)
	(gr_poly
		(pts
			(xy 333.913734 -231.104694) (xy 333.866744 -230.952294) (xy 333.605124 -230.952294) (xy 333.558134 -231.104694)
			(xy 333.558134 -231.149144) (xy 333.913734 -231.149144)
		)
		(stroke
			(width 0)
			(type solid)
		)
		(fill yes)
		(layer "In4.Cu")
		(net "M_C_CPU0_SB_DQ<19>")
	)
	(gr_poly
		(pts
			(xy 333.913734 -229.06863) (xy 333.913734 -229.02418) (xy 333.558134 -229.02418) (xy 333.558134 -229.06863)
			(xy 333.605124 -229.22103) (xy 333.866744 -229.22103)
		)
		(stroke
			(width 0)
			(type solid)
		)
		(fill yes)
		(layer "In4.Cu")
		(net "M_C_CPU0_SB_DQ<20>")
	)
	(gr_poly
		(pts
			(xy 333.917544 -271.384522) (xy 333.87919 -271.362424) (xy 333.723742 -271.326864) (xy 333.592932 -271.553432)
			(xy 333.70139 -271.670272) (xy 333.739744 -271.69237)
		)
		(stroke
			(width 0)
			(type solid)
		)
		(fill yes)
		(layer "In4.Cu")
		(net "M_B_CPU0_SA_DQ<14>")
	)
	(gr_poly
		(pts
			(xy 333.91856 -276.265386) (xy 333.880206 -276.243288) (xy 333.724758 -276.207728) (xy 333.593948 -276.434296)
			(xy 333.702406 -276.551136) (xy 333.74076 -276.573234)
		)
		(stroke
			(width 0)
			(type solid)
		)
		(fill yes)
		(layer "In4.Cu")
		(net "M_B_CPU0_SA_DQ<11>")
	)
	(gr_poly
		(pts
			(xy 333.922116 -240.46307) (xy 333.922116 -240.418874) (xy 333.566516 -240.418874) (xy 333.566516 -240.46307)
			(xy 333.613506 -240.61547) (xy 333.875126 -240.61547)
		)
		(stroke
			(width 0)
			(type solid)
		)
		(fill yes)
		(layer "In4.Cu")
		(net "M_C_CPU0_SB_DQS_DN<4>")
	)
	(gr_poly
		(pts
			(xy 333.922116 -235.579666) (xy 333.922116 -235.53547) (xy 333.566516 -235.53547) (xy 333.566516 -235.579666)
			(xy 333.613506 -235.732066) (xy 333.875126 -235.732066)
		)
		(stroke
			(width 0)
			(type solid)
		)
		(fill yes)
		(layer "In4.Cu")
		(net "M_B_CPU0_SB_DQS_DP<0>")
	)
	(gr_poly
		(pts
			(xy 333.922116 -234.360466) (xy 333.875126 -234.208066) (xy 333.613506 -234.208066) (xy 333.566516 -234.360466)
			(xy 333.566516 -234.404662) (xy 333.922116 -234.404662)
		)
		(stroke
			(width 0)
			(type solid)
		)
		(fill yes)
		(layer "In4.Cu")
		(net "M_B_CPU0_SB_DQS_DP<5>")
	)
	(gr_poly
		(pts
			(xy 333.922116 -230.696262) (xy 333.922116 -230.652066) (xy 333.566516 -230.652066) (xy 333.566516 -230.696262)
			(xy 333.613506 -230.848662) (xy 333.875126 -230.848662)
		)
		(stroke
			(width 0)
			(type solid)
		)
		(fill yes)
		(layer "In4.Cu")
		(net "M_C_CPU0_SB_DQS_DP<2>")
	)
	(gr_poly
		(pts
			(xy 333.922116 -229.477062) (xy 333.875126 -229.324662) (xy 333.613506 -229.324662) (xy 333.566516 -229.477062)
			(xy 333.566516 -229.521258) (xy 333.922116 -229.521258)
		)
		(stroke
			(width 0)
			(type solid)
		)
		(fill yes)
		(layer "In4.Cu")
		(net "M_C_CPU0_SB_DQS_DP<7>")
	)
	(gr_poly
		(pts
			(xy 333.98841 -244.194584) (xy 333.879952 -244.077744) (xy 333.841598 -244.055646) (xy 333.663798 -244.363494)
			(xy 333.702152 -244.385592) (xy 333.8576 -244.421152)
		)
		(stroke
			(width 0)
			(type solid)
		)
		(fill yes)
		(layer "In4.Cu")
		(net "M_C_CPU0_SB_CS_N<3>")
	)
	(gr_poly
		(pts
			(xy 333.988664 -245.82247) (xy 333.880206 -245.70563) (xy 333.841852 -245.683532) (xy 333.664052 -245.99138)
			(xy 333.702406 -246.013478) (xy 333.857854 -246.049038)
		)
		(stroke
			(width 0)
			(type solid)
		)
		(fill yes)
		(layer "In4.Cu")
		(net "M_C_CPU0_SB_CS_N<2>")
	)
	(gr_poly
		(pts
			(xy 333.992982 -239.304068) (xy 333.884524 -239.187228) (xy 333.84617 -239.16513) (xy 333.66837 -239.472978)
			(xy 333.706724 -239.495076) (xy 333.862172 -239.530636)
		)
		(stroke
			(width 0)
			(type solid)
		)
		(fill yes)
		(layer "In4.Cu")
		(net "M_C_CPU0_SB_CB<0>")
	)
	(gr_poly
		(pts
			(xy 334.023462 -285.051754) (xy 333.976472 -284.899354) (xy 333.714852 -284.899354) (xy 333.667862 -285.051754)
			(xy 333.667862 -285.096204) (xy 334.023462 -285.096204)
		)
		(stroke
			(width 0)
			(type solid)
		)
		(fill yes)
		(layer "In4.Cu")
		(net "M_C_CPU0_SA_DQS_DN<0>")
	)
	(gr_poly
		(pts
			(xy 334.023462 -270.40205) (xy 333.976472 -270.24965) (xy 333.714852 -270.24965) (xy 333.667862 -270.40205)
			(xy 333.667862 -270.446246) (xy 334.023462 -270.446246)
		)
		(stroke
			(width 0)
			(type solid)
		)
		(fill yes)
		(layer "In4.Cu")
		(net "M_B_CPU0_SA_DQ<15>")
	)
	(gr_poly
		(pts
			(xy 334.023462 -268.77391) (xy 333.976472 -268.62151) (xy 333.714852 -268.62151) (xy 333.667862 -268.77391)
			(xy 333.667862 -268.81836) (xy 334.023462 -268.81836)
		)
		(stroke
			(width 0)
			(type solid)
		)
		(fill yes)
		(layer "In4.Cu")
		(net "M_C_CPU0_SA_DQ<19>")
	)
	(gr_poly
		(pts
			(xy 334.023462 -268.365478) (xy 334.023462 -268.321028) (xy 333.667862 -268.321028) (xy 333.667862 -268.365478)
			(xy 333.714852 -268.517878) (xy 333.976472 -268.517878)
		)
		(stroke
			(width 0)
			(type solid)
		)
		(fill yes)
		(layer "In4.Cu")
		(net "M_C_CPU0_SA_DQS_DP<2>")
	)
	(gr_poly
		(pts
			(xy 334.023462 -267.146278) (xy 333.976472 -266.993878) (xy 333.714852 -266.993878) (xy 333.667862 -267.146278)
			(xy 333.667862 -267.190474) (xy 334.023462 -267.190474)
		)
		(stroke
			(width 0)
			(type solid)
		)
		(fill yes)
		(layer "In4.Cu")
		(net "M_C_CPU0_SA_DQS_DP<7>")
	)
	(gr_poly
		(pts
			(xy 334.023462 -266.737846) (xy 334.023462 -266.693396) (xy 333.667862 -266.693396) (xy 333.667862 -266.737846)
			(xy 333.714852 -266.890246) (xy 333.976472 -266.890246)
		)
		(stroke
			(width 0)
			(type solid)
		)
		(fill yes)
		(layer "In4.Cu")
		(net "M_C_CPU0_SA_DQ<20>")
	)
	(gr_poly
		(pts
			(xy 334.023462 -265.518646) (xy 333.976472 -265.366246) (xy 333.714852 -265.366246) (xy 333.667862 -265.518646)
			(xy 333.667862 -265.562842) (xy 334.023462 -265.562842)
		)
		(stroke
			(width 0)
			(type solid)
		)
		(fill yes)
		(layer "In4.Cu")
		(net "M_C_CPU0_SA_DQ<23>")
	)
	(gr_poly
		(pts
			(xy 334.023462 -265.109706) (xy 334.023462 -265.06551) (xy 333.667862 -265.06551) (xy 333.667862 -265.109706)
			(xy 333.714852 -265.262106) (xy 333.976472 -265.262106)
		)
		(stroke
			(width 0)
			(type solid)
		)
		(fill yes)
		(layer "In4.Cu")
		(net "M_B_CPU0_SA_DQ<26>")
	)
	(gr_poly
		(pts
			(xy 334.023462 -263.891014) (xy 333.976472 -263.738614) (xy 333.714852 -263.738614) (xy 333.667862 -263.891014)
			(xy 333.667862 -263.93521) (xy 334.023462 -263.93521)
		)
		(stroke
			(width 0)
			(type solid)
		)
		(fill yes)
		(layer "In4.Cu")
		(net "M_B_CPU0_SA_DQ<27>")
	)
	(gr_poly
		(pts
			(xy 334.023462 -263.482074) (xy 334.023462 -263.437878) (xy 333.667862 -263.437878) (xy 333.667862 -263.482074)
			(xy 333.714852 -263.634474) (xy 333.976472 -263.634474)
		)
		(stroke
			(width 0)
			(type solid)
		)
		(fill yes)
		(layer "In4.Cu")
		(net "M_B_CPU0_SA_DQS_DP<3>")
	)
	(gr_poly
		(pts
			(xy 334.023462 -262.262874) (xy 333.976472 -262.110474) (xy 333.714852 -262.110474) (xy 333.667862 -262.262874)
			(xy 333.667862 -262.307324) (xy 334.023462 -262.307324)
		)
		(stroke
			(width 0)
			(type solid)
		)
		(fill yes)
		(layer "In4.Cu")
		(net "M_B_CPU0_SA_DQS_DP<8>")
	)
	(gr_poly
		(pts
			(xy 334.023462 -261.854442) (xy 334.023462 -261.809992) (xy 333.667862 -261.809992) (xy 333.667862 -261.854442)
			(xy 333.714852 -262.006842) (xy 333.976472 -262.006842)
		)
		(stroke
			(width 0)
			(type solid)
		)
		(fill yes)
		(layer "In4.Cu")
		(net "M_B_CPU0_SA_DQ<28>")
	)
	(gr_poly
		(pts
			(xy 334.023462 -260.635242) (xy 333.976472 -260.482842) (xy 333.714852 -260.482842) (xy 333.667862 -260.635242)
			(xy 333.667862 -260.679438) (xy 334.023462 -260.679438)
		)
		(stroke
			(width 0)
			(type solid)
		)
		(fill yes)
		(layer "In4.Cu")
		(net "M_B_CPU0_SA_DQ<31>")
	)
	(gr_poly
		(pts
			(xy 334.023462 -258.59867) (xy 334.023462 -258.554474) (xy 333.667862 -258.554474) (xy 333.667862 -258.59867)
			(xy 333.714852 -258.75107) (xy 333.976472 -258.75107)
		)
		(stroke
			(width 0)
			(type solid)
		)
		(fill yes)
		(layer "In4.Cu")
		(net "M_C_CPU0_SA_CS_N<0>")
	)
	(gr_poly
		(pts
			(xy 334.023462 -257.37947) (xy 333.976472 -257.22707) (xy 333.714852 -257.22707) (xy 333.667862 -257.37947)
			(xy 333.667862 -257.42392) (xy 334.023462 -257.42392)
		)
		(stroke
			(width 0)
			(type solid)
		)
		(fill yes)
		(layer "In4.Cu")
		(net "M_C_CPU0_SA_CS_N<3>")
	)
	(gr_poly
		(pts
			(xy 334.023462 -256.971038) (xy 334.023462 -256.926588) (xy 333.667862 -256.926588) (xy 333.667862 -256.971038)
			(xy 333.714852 -257.123438) (xy 333.976472 -257.123438)
		)
		(stroke
			(width 0)
			(type solid)
		)
		(fill yes)
		(layer "In4.Cu")
		(net "M_C_CPU0_SA_CA<0>")
	)
	(gr_poly
		(pts
			(xy 334.023462 -255.751838) (xy 333.976472 -255.599438) (xy 333.714852 -255.599438) (xy 333.667862 -255.751838)
			(xy 333.667862 -255.796288) (xy 334.023462 -255.796288)
		)
		(stroke
			(width 0)
			(type solid)
		)
		(fill yes)
		(layer "In4.Cu")
		(net "M_C_CPU0_SA_CA<3>")
	)
	(gr_poly
		(pts
			(xy 334.09636 -272.101056) (xy 333.987902 -271.984216) (xy 333.949548 -271.962118) (xy 333.771748 -272.269966)
			(xy 333.810102 -272.292064) (xy 333.96555 -272.327624)
		)
		(stroke
			(width 0)
			(type solid)
		)
		(fill yes)
		(layer "In4.Cu")
		(net "M_B_CPU0_SA_DQ<12>")
	)
	(gr_poly
		(pts
			(xy 334.097376 -276.982428) (xy 333.988918 -276.865588) (xy 333.950564 -276.84349) (xy 333.772764 -277.151338)
			(xy 333.811118 -277.173436) (xy 333.966566 -277.208996)
		)
		(stroke
			(width 0)
			(type solid)
		)
		(fill yes)
		(layer "In4.Cu")
		(net "M_B_CPU0_SA_DQ<9>")
	)
	(gr_poly
		(pts
			(xy 334.102964 -273.717766) (xy 333.994506 -273.600926) (xy 333.956152 -273.578828) (xy 333.778352 -273.886676)
			(xy 333.816706 -273.908774) (xy 333.972154 -273.944334)
		)
		(stroke
			(width 0)
			(type solid)
		)
		(fill yes)
		(layer "In4.Cu")
		(net "M_B_CPU0_SA_DQS_DN<6>")
	)
	(gr_poly
		(pts
			(xy 334.273144 -239.419638) (xy 334.23479 -239.39754) (xy 334.079342 -239.36198) (xy 333.948532 -239.588548)
			(xy 334.05699 -239.705388) (xy 334.095344 -239.727486)
		)
		(stroke
			(width 0)
			(type solid)
		)
		(fill yes)
		(layer "In4.Cu")
		(net "M_C_CPU0_SB_DQS_DP<4>")
	)
	(gr_poly
		(pts
			(xy 334.277462 -244.29593) (xy 334.239108 -244.273832) (xy 334.08366 -244.238272) (xy 333.95285 -244.46484)
			(xy 334.061308 -244.58168) (xy 334.099662 -244.603778)
		)
		(stroke
			(width 0)
			(type solid)
		)
		(fill yes)
		(layer "In4.Cu")
		(net "M_C_CPU0_SB_CS_N<0>")
	)
	(gr_poly
		(pts
			(xy 334.277716 -245.923816) (xy 334.239362 -245.901718) (xy 334.083914 -245.866158) (xy 333.953104 -246.092726)
			(xy 334.061562 -246.209566) (xy 334.099916 -246.231664)
		)
		(stroke
			(width 0)
			(type solid)
		)
		(fill yes)
		(layer "In4.Cu")
		(net "M_C_CPU0_SB_PAR")
	)
	(gr_poly
		(pts
			(xy 334.34909 -223.418654) (xy 334.457548 -223.301814) (xy 334.326738 -223.075246) (xy 334.17129 -223.110806)
			(xy 334.132936 -223.132904) (xy 334.310736 -223.440752)
		)
		(stroke
			(width 0)
			(type solid)
		)
		(fill yes)
		(layer "In4.Cu")
		(net "M_B_CPU0_SB_DQ<29>")
	)
	(gr_poly
		(pts
			(xy 334.374998 -235.174282) (xy 334.328008 -235.021882) (xy 334.066388 -235.021882) (xy 334.019398 -235.174282)
			(xy 334.019398 -235.218478) (xy 334.374998 -235.218478)
		)
		(stroke
			(width 0)
			(type solid)
		)
		(fill yes)
		(layer "In4.Cu")
		(net "M_B_CPU0_SB_DQS_DN<0>")
	)
	(gr_poly
		(pts
			(xy 334.374998 -234.76585) (xy 334.374998 -234.721654) (xy 334.019398 -234.721654) (xy 334.019398 -234.76585)
			(xy 334.066388 -234.91825) (xy 334.328008 -234.91825)
		)
		(stroke
			(width 0)
			(type solid)
		)
		(fill yes)
		(layer "In4.Cu")
		(net "M_B_CPU0_SB_DQS_DN<5>")
	)
	(gr_poly
		(pts
			(xy 334.374998 -230.290878) (xy 334.328008 -230.138478) (xy 334.066388 -230.138478) (xy 334.019398 -230.290878)
			(xy 334.019398 -230.335074) (xy 334.374998 -230.335074)
		)
		(stroke
			(width 0)
			(type solid)
		)
		(fill yes)
		(layer "In4.Cu")
		(net "M_C_CPU0_SB_DQS_DN<2>")
	)
	(gr_poly
		(pts
			(xy 334.374998 -229.882446) (xy 334.374998 -229.83825) (xy 334.019398 -229.83825) (xy 334.019398 -229.882446)
			(xy 334.066388 -230.034846) (xy 334.328008 -230.034846)
		)
		(stroke
			(width 0)
			(type solid)
		)
		(fill yes)
		(layer "In4.Cu")
		(net "M_C_CPU0_SB_DQS_DN<7>")
	)
	(gr_poly
		(pts
			(xy 334.383126 -273.833336) (xy 334.344772 -273.811238) (xy 334.189324 -273.775678) (xy 334.058514 -274.002246)
			(xy 334.166972 -274.119086) (xy 334.205326 -274.141184)
		)
		(stroke
			(width 0)
			(type solid)
		)
		(fill yes)
		(layer "In4.Cu")
		(net "M_B_CPU0_SA_DQS_DN<1>")
	)
	(gr_poly
		(pts
			(xy 334.383634 -247.787922) (xy 334.383634 -247.743472) (xy 334.028034 -247.743472) (xy 334.028034 -247.787922)
			(xy 334.075024 -247.940322) (xy 334.336644 -247.940322)
		)
		(stroke
			(width 0)
			(type solid)
		)
		(fill yes)
		(layer "In4.Cu")
		(net "M_C_CPU0_SB_CA<4>")
	)
	(gr_poly
		(pts
			(xy 334.383634 -242.904518) (xy 334.383634 -242.860322) (xy 334.028034 -242.860322) (xy 334.028034 -242.904518)
			(xy 334.075024 -243.056918) (xy 334.336644 -243.056918)
		)
		(stroke
			(width 0)
			(type solid)
		)
		(fill yes)
		(layer "In4.Cu")
		(net "M_C_CPU0_SB_CB<4>")
	)
	(gr_poly
		(pts
			(xy 334.383634 -241.685318) (xy 334.336644 -241.532918) (xy 334.075024 -241.532918) (xy 334.028034 -241.685318)
			(xy 334.028034 -241.729768) (xy 334.383634 -241.729768)
		)
		(stroke
			(width 0)
			(type solid)
		)
		(fill yes)
		(layer "In4.Cu")
		(net "M_C_CPU0_SB_CB<7>")
	)
	(gr_poly
		(pts
			(xy 334.383634 -241.276886) (xy 334.383634 -241.232436) (xy 334.028034 -241.232436) (xy 334.028034 -241.276886)
			(xy 334.075024 -241.429286) (xy 334.336644 -241.429286)
		)
		(stroke
			(width 0)
			(type solid)
		)
		(fill yes)
		(layer "In4.Cu")
		(net "M_C_CPU0_SB_DQS_DP<9>")
	)
	(gr_poly
		(pts
			(xy 334.383634 -238.430054) (xy 334.336644 -238.277654) (xy 334.075024 -238.277654) (xy 334.028034 -238.430054)
			(xy 334.028034 -238.47425) (xy 334.383634 -238.47425)
		)
		(stroke
			(width 0)
			(type solid)
		)
		(fill yes)
		(layer "In4.Cu")
		(net "M_C_CPU0_SB_CB<2>")
	)
	(gr_poly
		(pts
			(xy 334.383634 -238.021114) (xy 334.383634 -237.976918) (xy 334.028034 -237.976918) (xy 334.028034 -238.021114)
			(xy 334.075024 -238.173514) (xy 334.336644 -238.173514)
		)
		(stroke
			(width 0)
			(type solid)
		)
		(fill yes)
		(layer "In4.Cu")
		(net "M_C_CPU0_SB_CB<1>")
	)
	(gr_poly
		(pts
			(xy 334.383634 -236.802422) (xy 334.336644 -236.650022) (xy 334.075024 -236.650022) (xy 334.028034 -236.802422)
			(xy 334.028034 -236.846618) (xy 334.383634 -236.846618)
		)
		(stroke
			(width 0)
			(type solid)
		)
		(fill yes)
		(layer "In4.Cu")
		(net "M_B_CPU0_SB_DQ<0>")
	)
	(gr_poly
		(pts
			(xy 334.383634 -236.393482) (xy 334.383634 -236.349286) (xy 334.028034 -236.349286) (xy 334.028034 -236.393482)
			(xy 334.075024 -236.545882) (xy 334.336644 -236.545882)
		)
		(stroke
			(width 0)
			(type solid)
		)
		(fill yes)
		(layer "In4.Cu")
		(net "M_B_CPU0_SB_DQ<1>")
	)
	(gr_poly
		(pts
			(xy 334.383634 -233.54665) (xy 334.336644 -233.39425) (xy 334.075024 -233.39425) (xy 334.028034 -233.54665)
			(xy 334.028034 -233.590846) (xy 334.383634 -233.590846)
		)
		(stroke
			(width 0)
			(type solid)
		)
		(fill yes)
		(layer "In4.Cu")
		(net "M_B_CPU0_SB_DQ<6>")
	)
	(gr_poly
		(pts
			(xy 334.383634 -233.13771) (xy 334.383634 -233.093514) (xy 334.028034 -233.093514) (xy 334.028034 -233.13771)
			(xy 334.075024 -233.29011) (xy 334.336644 -233.29011)
		)
		(stroke
			(width 0)
			(type solid)
		)
		(fill yes)
		(layer "In4.Cu")
		(net "M_B_CPU0_SB_DQ<5>")
	)
	(gr_poly
		(pts
			(xy 334.383634 -231.919018) (xy 334.336644 -231.766618) (xy 334.075024 -231.766618) (xy 334.028034 -231.919018)
			(xy 334.028034 -231.963214) (xy 334.383634 -231.963214)
		)
		(stroke
			(width 0)
			(type solid)
		)
		(fill yes)
		(layer "In4.Cu")
		(net "M_C_CPU0_SB_DQ<18>")
	)
	(gr_poly
		(pts
			(xy 334.383634 -231.510078) (xy 334.383634 -231.465882) (xy 334.028034 -231.465882) (xy 334.028034 -231.510078)
			(xy 334.075024 -231.662478) (xy 334.336644 -231.662478)
		)
		(stroke
			(width 0)
			(type solid)
		)
		(fill yes)
		(layer "In4.Cu")
		(net "M_C_CPU0_SB_DQ<17>")
	)
	(gr_poly
		(pts
			(xy 334.383634 -228.663246) (xy 334.336644 -228.510846) (xy 334.075024 -228.510846) (xy 334.028034 -228.663246)
			(xy 334.028034 -228.707696) (xy 334.383634 -228.707696)
		)
		(stroke
			(width 0)
			(type solid)
		)
		(fill yes)
		(layer "In4.Cu")
		(net "M_C_CPU0_SB_DQ<22>")
	)
	(gr_poly
		(pts
			(xy 334.383634 -228.254814) (xy 334.383634 -228.210364) (xy 334.028034 -228.210364) (xy 334.028034 -228.254814)
			(xy 334.075024 -228.407214) (xy 334.336644 -228.407214)
		)
		(stroke
			(width 0)
			(type solid)
		)
		(fill yes)
		(layer "In4.Cu")
		(net "M_C_CPU0_SB_DQ<21>")
	)
	(gr_poly
		(pts
			(xy 334.383634 -224.999042) (xy 334.383634 -224.954592) (xy 334.028034 -224.954592) (xy 334.028034 -224.999042)
			(xy 334.075024 -225.151442) (xy 334.336644 -225.151442)
		)
		(stroke
			(width 0)
			(type solid)
		)
		(fill yes)
		(layer "In4.Cu")
		(net "M_B_CPU0_SB_DQS_DN<8>")
	)
	(gr_poly
		(pts
			(xy 334.388206 -277.079964) (xy 334.349852 -277.057866) (xy 334.194404 -277.022306) (xy 334.063594 -277.248874)
			(xy 334.172052 -277.365714) (xy 334.210406 -277.387812)
		)
		(stroke
			(width 0)
			(type solid)
		)
		(fill yes)
		(layer "In4.Cu")
		(net "M_B_CPU0_SA_DQ<10>")
	)
	(gr_poly
		(pts
			(xy 334.38846 -272.19656) (xy 334.350106 -272.174462) (xy 334.194658 -272.138902) (xy 334.063848 -272.36547)
			(xy 334.172306 -272.48231) (xy 334.21066 -272.504408)
		)
		(stroke
			(width 0)
			(type solid)
		)
		(fill yes)
		(layer "In4.Cu")
		(net "M_B_CPU0_SA_DQS_DP<6>")
	)
	(gr_poly
		(pts
			(xy 334.389222 -275.450046) (xy 334.350868 -275.427948) (xy 334.19542 -275.392388) (xy 334.06461 -275.618956)
			(xy 334.173068 -275.735796) (xy 334.211422 -275.757894)
		)
		(stroke
			(width 0)
			(type solid)
		)
		(fill yes)
		(layer "In4.Cu")
		(net "M_B_CPU0_SA_DQ<11>")
	)
	(gr_poly
		(pts
			(xy 334.389476 -280.33345) (xy 334.351122 -280.311352) (xy 334.195674 -280.275792) (xy 334.064864 -280.50236)
			(xy 334.173322 -280.6192) (xy 334.211676 -280.641298)
		)
		(stroke
			(width 0)
			(type solid)
		)
		(fill yes)
		(layer "In4.Cu")
		(net "M_C_CPU0_SA_DQ<7>")
	)
	(gr_poly
		(pts
			(xy 334.392016 -243.31295) (xy 334.345026 -243.16055) (xy 334.083406 -243.16055) (xy 334.036416 -243.31295)
			(xy 334.036416 -243.3574) (xy 334.392016 -243.3574)
		)
		(stroke
			(width 0)
			(type solid)
		)
		(fill yes)
		(layer "In4.Cu")
		(net "M_C_CPU0_SB_CS_N<1>")
	)
	(gr_poly
		(pts
			(xy 334.455516 -245.012464) (xy 334.347058 -244.895624) (xy 334.308704 -244.873526) (xy 334.130904 -245.181374)
			(xy 334.169258 -245.203472) (xy 334.324706 -245.239032)
		)
		(stroke
			(width 0)
			(type solid)
		)
		(fill yes)
		(layer "In4.Cu")
		(net "M_C_CPU0_SB_CS_N<2>")
	)
	(gr_poly
		(pts
			(xy 334.455516 -240.13033) (xy 334.347058 -240.01349) (xy 334.308704 -239.991392) (xy 334.130904 -240.29924)
			(xy 334.169258 -240.321338) (xy 334.324706 -240.356898)
		)
		(stroke
			(width 0)
			(type solid)
		)
		(fill yes)
		(layer "In4.Cu")
		(net "M_C_CPU0_SB_DQS_DN<4>")
	)
	(gr_poly
		(pts
			(xy 334.458564 -246.636286) (xy 334.350106 -246.519446) (xy 334.311752 -246.497348) (xy 334.133952 -246.805196)
			(xy 334.172306 -246.827294) (xy 334.327754 -246.862854)
		)
		(stroke
			(width 0)
			(type solid)
		)
		(fill yes)
		(layer "In4.Cu")
		(net "M_C_CPU0_SB_CA<6>")
	)
	(gr_poly
		(pts
			(xy 334.493362 -285.86557) (xy 334.446372 -285.71317) (xy 334.184752 -285.71317) (xy 334.137762 -285.86557)
			(xy 334.137762 -285.91002) (xy 334.493362 -285.91002)
		)
		(stroke
			(width 0)
			(type solid)
		)
		(fill yes)
		(layer "In4.Cu")
		(net "M_C_CPU0_SA_DQ<3>")
	)
	(gr_poly
		(pts
			(xy 334.493362 -271.215866) (xy 334.446372 -271.063466) (xy 334.184752 -271.063466) (xy 334.137762 -271.215866)
			(xy 334.137762 -271.260062) (xy 334.493362 -271.260062)
		)
		(stroke
			(width 0)
			(type solid)
		)
		(fill yes)
		(layer "In4.Cu")
		(net "M_B_CPU0_SA_DQ<14>")
	)
	(gr_poly
		(pts
			(xy 334.493362 -270.806926) (xy 334.493362 -270.76273) (xy 334.137762 -270.76273) (xy 334.137762 -270.806926)
			(xy 334.184752 -270.959326) (xy 334.446372 -270.959326)
		)
		(stroke
			(width 0)
			(type solid)
		)
		(fill yes)
		(layer "In4.Cu")
		(net "M_B_CPU0_SA_DQ<13>")
	)
	(gr_poly
		(pts
			(xy 334.493362 -269.587726) (xy 334.446372 -269.435326) (xy 334.184752 -269.435326) (xy 334.137762 -269.587726)
			(xy 334.137762 -269.632176) (xy 334.493362 -269.632176)
		)
		(stroke
			(width 0)
			(type solid)
		)
		(fill yes)
		(layer "In4.Cu")
		(net "M_C_CPU0_SA_DQ<18>")
	)
	(gr_poly
		(pts
			(xy 334.493362 -269.179294) (xy 334.493362 -269.134844) (xy 334.137762 -269.134844) (xy 334.137762 -269.179294)
			(xy 334.184752 -269.331694) (xy 334.446372 -269.331694)
		)
		(stroke
			(width 0)
			(type solid)
		)
		(fill yes)
		(layer "In4.Cu")
		(net "M_C_CPU0_SA_DQ<17>")
	)
	(gr_poly
		(pts
			(xy 334.493362 -267.960094) (xy 334.446372 -267.807694) (xy 334.184752 -267.807694) (xy 334.137762 -267.960094)
			(xy 334.137762 -268.004544) (xy 334.493362 -268.004544)
		)
		(stroke
			(width 0)
			(type solid)
		)
		(fill yes)
		(layer "In4.Cu")
		(net "M_C_CPU0_SA_DQS_DN<2>")
	)
	(gr_poly
		(pts
			(xy 334.493362 -267.551662) (xy 334.493362 -267.507212) (xy 334.137762 -267.507212) (xy 334.137762 -267.551662)
			(xy 334.184752 -267.704062) (xy 334.446372 -267.704062)
		)
		(stroke
			(width 0)
			(type solid)
		)
		(fill yes)
		(layer "In4.Cu")
		(net "M_C_CPU0_SA_DQS_DN<7>")
	)
	(gr_poly
		(pts
			(xy 334.493362 -266.332462) (xy 334.446372 -266.180062) (xy 334.184752 -266.180062) (xy 334.137762 -266.332462)
			(xy 334.137762 -266.376658) (xy 334.493362 -266.376658)
		)
		(stroke
			(width 0)
			(type solid)
		)
		(fill yes)
		(layer "In4.Cu")
		(net "M_C_CPU0_SA_DQ<22>")
	)
	(gr_poly
		(pts
			(xy 334.493362 -265.92403) (xy 334.493362 -265.87958) (xy 334.137762 -265.87958) (xy 334.137762 -265.92403)
			(xy 334.184752 -266.07643) (xy 334.446372 -266.07643)
		)
		(stroke
			(width 0)
			(type solid)
		)
		(fill yes)
		(layer "In4.Cu")
		(net "M_C_CPU0_SA_DQ<21>")
	)
	(gr_poly
		(pts
			(xy 334.493362 -264.70483) (xy 334.446372 -264.55243) (xy 334.184752 -264.55243) (xy 334.137762 -264.70483)
			(xy 334.137762 -264.749026) (xy 334.493362 -264.749026)
		)
		(stroke
			(width 0)
			(type solid)
		)
		(fill yes)
		(layer "In4.Cu")
		(net "M_B_CPU0_SA_DQ<24>")
	)
	(gr_poly
		(pts
			(xy 334.493362 -264.29589) (xy 334.493362 -264.251694) (xy 334.137762 -264.251694) (xy 334.137762 -264.29589)
			(xy 334.184752 -264.44829) (xy 334.446372 -264.44829)
		)
		(stroke
			(width 0)
			(type solid)
		)
		(fill yes)
		(layer "In4.Cu")
		(net "M_B_CPU0_SA_DQ<25>")
	)
	(gr_poly
		(pts
			(xy 334.493362 -263.07669) (xy 334.446372 -262.92429) (xy 334.184752 -262.92429) (xy 334.137762 -263.07669)
			(xy 334.137762 -263.12114) (xy 334.493362 -263.12114)
		)
		(stroke
			(width 0)
			(type solid)
		)
		(fill yes)
		(layer "In4.Cu")
		(net "M_B_CPU0_SA_DQS_DN<3>")
	)
	(gr_poly
		(pts
			(xy 334.493362 -262.668258) (xy 334.493362 -262.623808) (xy 334.137762 -262.623808) (xy 334.137762 -262.668258)
			(xy 334.184752 -262.820658) (xy 334.446372 -262.820658)
		)
		(stroke
			(width 0)
			(type solid)
		)
		(fill yes)
		(layer "In4.Cu")
		(net "M_B_CPU0_SA_DQS_DN<8>")
	)
	(gr_poly
		(pts
			(xy 334.493362 -261.449058) (xy 334.446372 -261.296658) (xy 334.184752 -261.296658) (xy 334.137762 -261.449058)
			(xy 334.137762 -261.493508) (xy 334.493362 -261.493508)
		)
		(stroke
			(width 0)
			(type solid)
		)
		(fill yes)
		(layer "In4.Cu")
		(net "M_B_CPU0_SA_DQ<30>")
	)
	(gr_poly
		(pts
			(xy 334.493362 -261.040626) (xy 334.493362 -260.996176) (xy 334.137762 -260.996176) (xy 334.137762 -261.040626)
			(xy 334.184752 -261.193026) (xy 334.446372 -261.193026)
		)
		(stroke
			(width 0)
			(type solid)
		)
		(fill yes)
		(layer "In4.Cu")
		(net "M_B_CPU0_SA_DQ<29>")
	)
	(gr_poly
		(pts
			(xy 334.493362 -258.193286) (xy 334.446372 -258.040886) (xy 334.184752 -258.040886) (xy 334.137762 -258.193286)
			(xy 334.137762 -258.237736) (xy 334.493362 -258.237736)
		)
		(stroke
			(width 0)
			(type solid)
		)
		(fill yes)
		(layer "In4.Cu")
		(net "M_C_CPU0_SA_CS_N<2>")
	)
	(gr_poly
		(pts
			(xy 334.493362 -257.784854) (xy 334.493362 -257.740404) (xy 334.137762 -257.740404) (xy 334.137762 -257.784854)
			(xy 334.184752 -257.937254) (xy 334.446372 -257.937254)
		)
		(stroke
			(width 0)
			(type solid)
		)
		(fill yes)
		(layer "In4.Cu")
		(net "M_C_CPU0_SA_CS_N<1>")
	)
	(gr_poly
		(pts
			(xy 334.493362 -256.565654) (xy 334.446372 -256.413254) (xy 334.184752 -256.413254) (xy 334.137762 -256.565654)
			(xy 334.137762 -256.610104) (xy 334.493362 -256.610104)
		)
		(stroke
			(width 0)
			(type solid)
		)
		(fill yes)
		(layer "In4.Cu")
		(net "M_C_CPU0_SA_CA<1>")
	)
	(gr_poly
		(pts
			(xy 334.493362 -256.157222) (xy 334.493362 -256.112772) (xy 334.137762 -256.112772) (xy 334.137762 -256.157222)
			(xy 334.184752 -256.309622) (xy 334.446372 -256.309622)
		)
		(stroke
			(width 0)
			(type solid)
		)
		(fill yes)
		(layer "In4.Cu")
		(net "M_C_CPU0_SA_CA<2>")
	)
	(gr_poly
		(pts
			(xy 334.493362 -254.938022) (xy 334.446372 -254.785622) (xy 334.184752 -254.785622) (xy 334.137762 -254.938022)
			(xy 334.137762 -254.982218) (xy 334.493362 -254.982218)
		)
		(stroke
			(width 0)
			(type solid)
		)
		(fill yes)
		(layer "In4.Cu")
		(net "M_C_CPU0_SA_CA<5>")
	)
	(gr_poly
		(pts
			(xy 334.493362 -254.529082) (xy 334.493362 -254.484886) (xy 334.137762 -254.484886) (xy 334.137762 -254.529082)
			(xy 334.184752 -254.681482) (xy 334.446372 -254.681482)
		)
		(stroke
			(width 0)
			(type solid)
		)
		(fill yes)
		(layer "In4.Cu")
		(net "M_C_CPU0_SA_CA<6>")
	)
	(gr_poly
		(pts
			(xy 334.493616 -285.456884) (xy 334.493616 -285.412434) (xy 334.138016 -285.412434) (xy 334.138016 -285.456884)
			(xy 334.185006 -285.609284) (xy 334.446626 -285.609284)
		)
		(stroke
			(width 0)
			(type solid)
		)
		(fill yes)
		(layer "In4.Cu")
		(net "M_C_CPU0_SA_DQS_DP<0>")
	)
	(gr_poly
		(pts
			(xy 334.499458 -282.610052) (xy 334.452468 -282.457652) (xy 334.190848 -282.457652) (xy 334.143858 -282.610052)
			(xy 334.143858 -282.654248) (xy 334.499458 -282.654248)
		)
		(stroke
			(width 0)
			(type solid)
		)
		(fill yes)
		(layer "In4.Cu")
		(net "M_C_CPU0_SA_DQS_DP<5>")
	)
	(gr_poly
		(pts
			(xy 334.499458 -282.201874) (xy 334.499458 -282.157424) (xy 334.143858 -282.157424) (xy 334.143858 -282.201874)
			(xy 334.190848 -282.354274) (xy 334.452468 -282.354274)
		)
		(stroke
			(width 0)
			(type solid)
		)
		(fill yes)
		(layer "In4.Cu")
		(net "M_C_CPU0_SA_DQ<4>")
	)
	(gr_poly
		(pts
			(xy 334.567022 -276.16912) (xy 334.458564 -276.05228) (xy 334.42021 -276.030182) (xy 334.24241 -276.33803)
			(xy 334.280764 -276.360128) (xy 334.436212 -276.395688)
		)
		(stroke
			(width 0)
			(type solid)
		)
		(fill yes)
		(layer "In4.Cu")
		(net "M_B_CPU0_SA_DQ<9>")
	)
	(gr_poly
		(pts
			(xy 334.57261 -281.042872) (xy 334.464152 -280.926032) (xy 334.425798 -280.903934) (xy 334.247998 -281.211782)
			(xy 334.286352 -281.23388) (xy 334.4418 -281.26944)
		)
		(stroke
			(width 0)
			(type solid)
		)
		(fill yes)
		(layer "In4.Cu")
		(net "M_C_CPU0_SA_DQ<5>")
	)
	(gr_poly
		(pts
			(xy 334.57261 -274.531582) (xy 334.464152 -274.414742) (xy 334.425798 -274.392644) (xy 334.247998 -274.700492)
			(xy 334.286352 -274.72259) (xy 334.4418 -274.75815)
		)
		(stroke
			(width 0)
			(type solid)
		)
		(fill yes)
		(layer "In4.Cu")
		(net "M_B_CPU0_SA_DQS_DP<1>")
	)
	(gr_poly
		(pts
			(xy 334.572864 -272.903696) (xy 334.464406 -272.786856) (xy 334.426052 -272.764758) (xy 334.248252 -273.072606)
			(xy 334.286606 -273.094704) (xy 334.442054 -273.130264)
		)
		(stroke
			(width 0)
			(type solid)
		)
		(fill yes)
		(layer "In4.Cu")
		(net "M_B_CPU0_SA_DQS_DN<6>")
	)
	(gr_poly
		(pts
			(xy 334.747616 -246.737632) (xy 334.709262 -246.715534) (xy 334.553814 -246.679974) (xy 334.423004 -246.906542)
			(xy 334.531462 -247.023382) (xy 334.569816 -247.04548)
		)
		(stroke
			(width 0)
			(type solid)
		)
		(fill yes)
		(layer "In4.Cu")
		(net "M_C_CPU0_SB_CA<5>")
	)
	(gr_poly
		(pts
			(xy 334.75041 -245.104666) (xy 334.712056 -245.082568) (xy 334.556608 -245.047008) (xy 334.425798 -245.273576)
			(xy 334.534256 -245.390416) (xy 334.57261 -245.412514)
		)
		(stroke
			(width 0)
			(type solid)
		)
		(fill yes)
		(layer "In4.Cu")
		(net "M_C_CPU0_SB_PAR")
	)
	(gr_poly
		(pts
			(xy 334.75041 -240.221262) (xy 334.712056 -240.199164) (xy 334.556608 -240.163604) (xy 334.425798 -240.390172)
			(xy 334.534256 -240.507012) (xy 334.57261 -240.52911)
		)
		(stroke
			(width 0)
			(type solid)
		)
		(fill yes)
		(layer "In4.Cu")
		(net "M_C_CPU0_SB_DQS_DN<9>")
	)
	(gr_poly
		(pts
			(xy 334.844898 -243.718842) (xy 334.844898 -243.674392) (xy 334.489298 -243.674392) (xy 334.489298 -243.718842)
			(xy 334.536288 -243.871242) (xy 334.797908 -243.871242)
		)
		(stroke
			(width 0)
			(type solid)
		)
		(fill yes)
		(layer "In4.Cu")
		(net "M_C_CPU0_SB_CS_N<3>")
	)
	(gr_poly
		(pts
			(xy 334.847438 -242.499134) (xy 334.800448 -242.346734) (xy 334.538828 -242.346734) (xy 334.491838 -242.499134)
			(xy 334.491838 -242.543584) (xy 334.847438 -242.543584)
		)
		(stroke
			(width 0)
			(type solid)
		)
		(fill yes)
		(layer "In4.Cu")
		(net "M_C_CPU0_SB_CB<6>")
	)
	(gr_poly
		(pts
			(xy 334.847438 -242.090702) (xy 334.847438 -242.046252) (xy 334.491838 -242.046252) (xy 334.491838 -242.090702)
			(xy 334.538828 -242.243102) (xy 334.800448 -242.243102)
		)
		(stroke
			(width 0)
			(type solid)
		)
		(fill yes)
		(layer "In4.Cu")
		(net "M_C_CPU0_SB_CB<5>")
	)
	(gr_poly
		(pts
			(xy 334.847438 -237.616238) (xy 334.800448 -237.463838) (xy 334.538828 -237.463838) (xy 334.491838 -237.616238)
			(xy 334.491838 -237.660434) (xy 334.847438 -237.660434)
		)
		(stroke
			(width 0)
			(type solid)
		)
		(fill yes)
		(layer "In4.Cu")
		(net "M_C_CPU0_SB_CB<3>")
	)
	(gr_poly
		(pts
			(xy 334.847438 -237.207298) (xy 334.847438 -237.163102) (xy 334.491838 -237.163102) (xy 334.491838 -237.207298)
			(xy 334.538828 -237.359698) (xy 334.800448 -237.359698)
		)
		(stroke
			(width 0)
			(type solid)
		)
		(fill yes)
		(layer "In4.Cu")
		(net "M_B_CPU0_SB_DQ<2>")
	)
	(gr_poly
		(pts
			(xy 334.847438 -227.84943) (xy 334.800448 -227.69703) (xy 334.538828 -227.69703) (xy 334.491838 -227.84943)
			(xy 334.491838 -227.893626) (xy 334.847438 -227.893626)
		)
		(stroke
			(width 0)
			(type solid)
		)
		(fill yes)
		(layer "In4.Cu")
		(net "M_C_CPU0_SB_DQ<23>")
	)
	(gr_poly
		(pts
			(xy 334.852772 -274.647152) (xy 334.814418 -274.625054) (xy 334.65897 -274.589494) (xy 334.52816 -274.816062)
			(xy 334.636618 -274.932902) (xy 334.674972 -274.955)
		)
		(stroke
			(width 0)
			(type solid)
		)
		(fill yes)
		(layer "In4.Cu")
		(net "M_B_CPU0_SA_DQ<11>")
	)
	(gr_poly
		(pts
			(xy 334.853026 -281.158696) (xy 334.814672 -281.136598) (xy 334.659224 -281.101038) (xy 334.528414 -281.327606)
			(xy 334.636872 -281.444446) (xy 334.675226 -281.466544)
		)
		(stroke
			(width 0)
			(type solid)
		)
		(fill yes)
		(layer "In4.Cu")
		(net "M_C_CPU0_SA_DQ<6>")
	)
	(gr_poly
		(pts
			(xy 334.853026 -279.530556) (xy 334.814672 -279.508458) (xy 334.659224 -279.472898) (xy 334.528414 -279.699466)
			(xy 334.636872 -279.816306) (xy 334.675226 -279.838404)
		)
		(stroke
			(width 0)
			(type solid)
		)
		(fill yes)
		(layer "In4.Cu")
		(net "M_C_CPU0_SA_DQ<7>")
	)
	(gr_poly
		(pts
			(xy 334.853026 -273.01952) (xy 334.814672 -272.997422) (xy 334.659224 -272.961862) (xy 334.528414 -273.18843)
			(xy 334.636872 -273.30527) (xy 334.675226 -273.327368)
		)
		(stroke
			(width 0)
			(type solid)
		)
		(fill yes)
		(layer "In4.Cu")
		(net "M_B_CPU0_SA_DQS_DN<1>")
	)
	(gr_poly
		(pts
			(xy 334.85328 -244.127274) (xy 334.80629 -243.974874) (xy 334.54467 -243.974874) (xy 334.49768 -244.127274)
			(xy 334.49768 -244.17147) (xy 334.85328 -244.17147)
		)
		(stroke
			(width 0)
			(type solid)
		)
		(fill yes)
		(layer "In4.Cu")
		(net "M_C_CPU0_SB_CS_N<0>")
	)
	(gr_poly
		(pts
			(xy 334.853534 -248.601738) (xy 334.853534 -248.557542) (xy 334.497934 -248.557542) (xy 334.497934 -248.601738)
			(xy 334.544924 -248.754138) (xy 334.806544 -248.754138)
		)
		(stroke
			(width 0)
			(type solid)
		)
		(fill yes)
		(layer "In4.Cu")
		(net "M_C_CPU0_SB_CA<2>")
	)
	(gr_poly
		(pts
			(xy 334.853534 -238.83493) (xy 334.853534 -238.790734) (xy 334.497934 -238.790734) (xy 334.497934 -238.83493)
			(xy 334.544924 -238.98733) (xy 334.806544 -238.98733)
		)
		(stroke
			(width 0)
			(type solid)
		)
		(fill yes)
		(layer "In4.Cu")
		(net "M_C_CPU0_SB_CB<0>")
	)
	(gr_poly
		(pts
			(xy 334.853534 -235.988098) (xy 334.806544 -235.835698) (xy 334.544924 -235.835698) (xy 334.497934 -235.988098)
			(xy 334.497934 -236.032548) (xy 334.853534 -236.032548)
		)
		(stroke
			(width 0)
			(type solid)
		)
		(fill yes)
		(layer "In4.Cu")
		(net "M_B_CPU0_SB_DQ<3>")
	)
	(gr_poly
		(pts
			(xy 334.853534 -233.952034) (xy 334.853534 -233.907584) (xy 334.497934 -233.907584) (xy 334.497934 -233.952034)
			(xy 334.544924 -234.104434) (xy 334.806544 -234.104434)
		)
		(stroke
			(width 0)
			(type solid)
		)
		(fill yes)
		(layer "In4.Cu")
		(net "M_B_CPU0_SB_DQ<4>")
	)
	(gr_poly
		(pts
			(xy 334.853534 -232.732834) (xy 334.806544 -232.580434) (xy 334.544924 -232.580434) (xy 334.497934 -232.732834)
			(xy 334.497934 -232.77703) (xy 334.853534 -232.77703)
		)
		(stroke
			(width 0)
			(type solid)
		)
		(fill yes)
		(layer "In4.Cu")
		(net "M_B_CPU0_SB_DQ<7>")
	)
	(gr_poly
		(pts
			(xy 334.853534 -232.323894) (xy 334.853534 -232.279698) (xy 334.497934 -232.279698) (xy 334.497934 -232.323894)
			(xy 334.544924 -232.476294) (xy 334.806544 -232.476294)
		)
		(stroke
			(width 0)
			(type solid)
		)
		(fill yes)
		(layer "In4.Cu")
		(net "M_C_CPU0_SB_DQ<16>")
	)
	(gr_poly
		(pts
			(xy 334.853534 -231.104694) (xy 334.806544 -230.952294) (xy 334.544924 -230.952294) (xy 334.497934 -231.104694)
			(xy 334.497934 -231.149144) (xy 334.853534 -231.149144)
		)
		(stroke
			(width 0)
			(type solid)
		)
		(fill yes)
		(layer "In4.Cu")
		(net "M_C_CPU0_SB_DQ<19>")
	)
	(gr_poly
		(pts
			(xy 334.853534 -229.06863) (xy 334.853534 -229.02418) (xy 334.497934 -229.02418) (xy 334.497934 -229.06863)
			(xy 334.544924 -229.22103) (xy 334.806544 -229.22103)
		)
		(stroke
			(width 0)
			(type solid)
		)
		(fill yes)
		(layer "In4.Cu")
		(net "M_C_CPU0_SB_DQ<20>")
	)
	(gr_poly
		(pts
			(xy 334.85836 -276.265386) (xy 334.820006 -276.243288) (xy 334.664558 -276.207728) (xy 334.533748 -276.434296)
			(xy 334.642206 -276.551136) (xy 334.68056 -276.573234)
		)
		(stroke
			(width 0)
			(type solid)
		)
		(fill yes)
		(layer "In4.Cu")
		(net "M_B_CPU0_SA_DQ<10>")
	)
	(gr_poly
		(pts
			(xy 334.861916 -239.243362) (xy 334.814926 -239.090962) (xy 334.553306 -239.090962) (xy 334.506316 -239.243362)
			(xy 334.506316 -239.287812) (xy 334.861916 -239.287812)
		)
		(stroke
			(width 0)
			(type solid)
		)
		(fill yes)
		(layer "In4.Cu")
		(net "M_C_CPU0_SB_DQS_DP<4>")
	)
	(gr_poly
		(pts
			(xy 334.861916 -235.579666) (xy 334.861916 -235.53547) (xy 334.506316 -235.53547) (xy 334.506316 -235.579666)
			(xy 334.553306 -235.732066) (xy 334.814926 -235.732066)
		)
		(stroke
			(width 0)
			(type solid)
		)
		(fill yes)
		(layer "In4.Cu")
		(net "M_B_CPU0_SB_DQS_DP<0>")
	)
	(gr_poly
		(pts
			(xy 334.861916 -234.360466) (xy 334.814926 -234.208066) (xy 334.553306 -234.208066) (xy 334.506316 -234.360466)
			(xy 334.506316 -234.404662) (xy 334.861916 -234.404662)
		)
		(stroke
			(width 0)
			(type solid)
		)
		(fill yes)
		(layer "In4.Cu")
		(net "M_B_CPU0_SB_DQS_DP<5>")
	)
	(gr_poly
		(pts
			(xy 334.861916 -230.696262) (xy 334.861916 -230.652066) (xy 334.506316 -230.652066) (xy 334.506316 -230.696262)
			(xy 334.553306 -230.848662) (xy 334.814926 -230.848662)
		)
		(stroke
			(width 0)
			(type solid)
		)
		(fill yes)
		(layer "In4.Cu")
		(net "M_C_CPU0_SB_DQS_DP<2>")
	)
	(gr_poly
		(pts
			(xy 334.861916 -229.477062) (xy 334.814926 -229.324662) (xy 334.553306 -229.324662) (xy 334.506316 -229.477062)
			(xy 334.506316 -229.521258) (xy 334.861916 -229.521258)
		)
		(stroke
			(width 0)
			(type solid)
		)
		(fill yes)
		(layer "In4.Cu")
		(net "M_C_CPU0_SB_DQS_DP<7>")
	)
	(gr_poly
		(pts
			(xy 334.928464 -247.450102) (xy 334.820006 -247.333262) (xy 334.781652 -247.311164) (xy 334.603852 -247.619012)
			(xy 334.642206 -247.64111) (xy 334.797654 -247.67667)
		)
		(stroke
			(width 0)
			(type solid)
		)
		(fill yes)
		(layer "In4.Cu")
		(net "M_C_CPU0_SB_CA<4>")
	)
	(gr_poly
		(pts
			(xy 334.928464 -245.82247) (xy 334.820006 -245.70563) (xy 334.781652 -245.683532) (xy 334.603852 -245.99138)
			(xy 334.642206 -246.013478) (xy 334.797654 -246.049038)
		)
		(stroke
			(width 0)
			(type solid)
		)
		(fill yes)
		(layer "In4.Cu")
		(net "M_C_CPU0_SB_CA<6>")
	)
	(gr_poly
		(pts
			(xy 334.928464 -240.939066) (xy 334.820006 -240.822226) (xy 334.781652 -240.800128) (xy 334.603852 -241.107976)
			(xy 334.642206 -241.130074) (xy 334.797654 -241.165634)
		)
		(stroke
			(width 0)
			(type solid)
		)
		(fill yes)
		(layer "In4.Cu")
		(net "M_C_CPU0_SB_DQS_DP<9>")
	)
	(gr_poly
		(pts
			(xy 334.95488 -283.01569) (xy 334.95488 -282.971494) (xy 334.59928 -282.971494) (xy 334.59928 -283.01569)
			(xy 334.64627 -283.16809) (xy 334.90789 -283.16809)
		)
		(stroke
			(width 0)
			(type solid)
		)
		(fill yes)
		(layer "In4.Cu")
		(net "M_C_CPU0_SA_DQS_DN<5>")
	)
	(gr_poly
		(pts
			(xy 334.95488 -272.029174) (xy 334.90789 -271.876774) (xy 334.64627 -271.876774) (xy 334.59928 -272.029174)
			(xy 334.59928 -272.073624) (xy 334.95488 -272.073624)
		)
		(stroke
			(width 0)
			(type solid)
		)
		(fill yes)
		(layer "In4.Cu")
		(net "M_B_CPU0_SA_DQS_DP<6>")
	)
	(gr_poly
		(pts
			(xy 334.963262 -286.270954) (xy 334.963262 -286.226758) (xy 334.607662 -286.226758) (xy 334.607662 -286.270954)
			(xy 334.654652 -286.423354) (xy 334.916272 -286.423354)
		)
		(stroke
			(width 0)
			(type solid)
		)
		(fill yes)
		(layer "In4.Cu")
		(net "M_C_CPU0_SA_DQ<1>")
	)
	(gr_poly
		(pts
			(xy 334.963262 -285.051754) (xy 334.916272 -284.899354) (xy 334.654652 -284.899354) (xy 334.607662 -285.051754)
			(xy 334.607662 -285.096204) (xy 334.963262 -285.096204)
		)
		(stroke
			(width 0)
			(type solid)
		)
		(fill yes)
		(layer "In4.Cu")
		(net "M_C_CPU0_SA_DQS_DN<0>")
	)
	(gr_poly
		(pts
			(xy 334.963262 -271.620742) (xy 334.963262 -271.576546) (xy 334.607662 -271.576546) (xy 334.607662 -271.620742)
			(xy 334.654652 -271.773142) (xy 334.916272 -271.773142)
		)
		(stroke
			(width 0)
			(type solid)
		)
		(fill yes)
		(layer "In4.Cu")
		(net "M_B_CPU0_SA_DQ<12>")
	)
	(gr_poly
		(pts
			(xy 334.963262 -270.40205) (xy 334.916272 -270.24965) (xy 334.654652 -270.24965) (xy 334.607662 -270.40205)
			(xy 334.607662 -270.446246) (xy 334.963262 -270.446246)
		)
		(stroke
			(width 0)
			(type solid)
		)
		(fill yes)
		(layer "In4.Cu")
		(net "M_B_CPU0_SA_DQ<15>")
	)
	(gr_poly
		(pts
			(xy 334.963262 -269.99311) (xy 334.963262 -269.948914) (xy 334.607662 -269.948914) (xy 334.607662 -269.99311)
			(xy 334.654652 -270.14551) (xy 334.916272 -270.14551)
		)
		(stroke
			(width 0)
			(type solid)
		)
		(fill yes)
		(layer "In4.Cu")
		(net "M_C_CPU0_SA_DQ<16>")
	)
	(gr_poly
		(pts
			(xy 334.963262 -268.77391) (xy 334.916272 -268.62151) (xy 334.654652 -268.62151) (xy 334.607662 -268.77391)
			(xy 334.607662 -268.81836) (xy 334.963262 -268.81836)
		)
		(stroke
			(width 0)
			(type solid)
		)
		(fill yes)
		(layer "In4.Cu")
		(net "M_C_CPU0_SA_DQ<19>")
	)
	(gr_poly
		(pts
			(xy 334.963262 -268.365478) (xy 334.963262 -268.321028) (xy 334.607662 -268.321028) (xy 334.607662 -268.365478)
			(xy 334.654652 -268.517878) (xy 334.916272 -268.517878)
		)
		(stroke
			(width 0)
			(type solid)
		)
		(fill yes)
		(layer "In4.Cu")
		(net "M_C_CPU0_SA_DQS_DP<2>")
	)
	(gr_poly
		(pts
			(xy 334.963262 -267.146278) (xy 334.916272 -266.993878) (xy 334.654652 -266.993878) (xy 334.607662 -267.146278)
			(xy 334.607662 -267.190474) (xy 334.963262 -267.190474)
		)
		(stroke
			(width 0)
			(type solid)
		)
		(fill yes)
		(layer "In4.Cu")
		(net "M_C_CPU0_SA_DQS_DP<7>")
	)
	(gr_poly
		(pts
			(xy 334.963262 -266.737846) (xy 334.963262 -266.693396) (xy 334.607662 -266.693396) (xy 334.607662 -266.737846)
			(xy 334.654652 -266.890246) (xy 334.916272 -266.890246)
		)
		(stroke
			(width 0)
			(type solid)
		)
		(fill yes)
		(layer "In4.Cu")
		(net "M_C_CPU0_SA_DQ<20>")
	)
	(gr_poly
		(pts
			(xy 334.963262 -265.518646) (xy 334.916272 -265.366246) (xy 334.654652 -265.366246) (xy 334.607662 -265.518646)
			(xy 334.607662 -265.562842) (xy 334.963262 -265.562842)
		)
		(stroke
			(width 0)
			(type solid)
		)
		(fill yes)
		(layer "In4.Cu")
		(net "M_C_CPU0_SA_DQ<23>")
	)
	(gr_poly
		(pts
			(xy 334.963262 -265.109706) (xy 334.963262 -265.06551) (xy 334.607662 -265.06551) (xy 334.607662 -265.109706)
			(xy 334.654652 -265.262106) (xy 334.916272 -265.262106)
		)
		(stroke
			(width 0)
			(type solid)
		)
		(fill yes)
		(layer "In4.Cu")
		(net "M_B_CPU0_SA_DQ<26>")
	)
	(gr_poly
		(pts
			(xy 334.963262 -263.891014) (xy 334.916272 -263.738614) (xy 334.654652 -263.738614) (xy 334.607662 -263.891014)
			(xy 334.607662 -263.93521) (xy 334.963262 -263.93521)
		)
		(stroke
			(width 0)
			(type solid)
		)
		(fill yes)
		(layer "In4.Cu")
		(net "M_B_CPU0_SA_DQ<27>")
	)
	(gr_poly
		(pts
			(xy 334.963262 -263.482074) (xy 334.963262 -263.437878) (xy 334.607662 -263.437878) (xy 334.607662 -263.482074)
			(xy 334.654652 -263.634474) (xy 334.916272 -263.634474)
		)
		(stroke
			(width 0)
			(type solid)
		)
		(fill yes)
		(layer "In4.Cu")
		(net "M_B_CPU0_SA_DQS_DP<3>")
	)
	(gr_poly
		(pts
			(xy 334.963262 -262.262874) (xy 334.916272 -262.110474) (xy 334.654652 -262.110474) (xy 334.607662 -262.262874)
			(xy 334.607662 -262.307324) (xy 334.963262 -262.307324)
		)
		(stroke
			(width 0)
			(type solid)
		)
		(fill yes)
		(layer "In4.Cu")
		(net "M_B_CPU0_SA_DQS_DP<8>")
	)
	(gr_poly
		(pts
			(xy 334.963262 -261.854442) (xy 334.963262 -261.809992) (xy 334.607662 -261.809992) (xy 334.607662 -261.854442)
			(xy 334.654652 -262.006842) (xy 334.916272 -262.006842)
		)
		(stroke
			(width 0)
			(type solid)
		)
		(fill yes)
		(layer "In4.Cu")
		(net "M_B_CPU0_SA_DQ<28>")
	)
	(gr_poly
		(pts
			(xy 334.963262 -260.635242) (xy 334.916272 -260.482842) (xy 334.654652 -260.482842) (xy 334.607662 -260.635242)
			(xy 334.607662 -260.679438) (xy 334.963262 -260.679438)
		)
		(stroke
			(width 0)
			(type solid)
		)
		(fill yes)
		(layer "In4.Cu")
		(net "M_B_CPU0_SA_DQ<31>")
	)
	(gr_poly
		(pts
			(xy 334.963262 -258.59867) (xy 334.963262 -258.554474) (xy 334.607662 -258.554474) (xy 334.607662 -258.59867)
			(xy 334.654652 -258.75107) (xy 334.916272 -258.75107)
		)
		(stroke
			(width 0)
			(type solid)
		)
		(fill yes)
		(layer "In4.Cu")
		(net "M_C_CPU0_SA_CS_N<0>")
	)
	(gr_poly
		(pts
			(xy 334.963262 -257.37947) (xy 334.916272 -257.22707) (xy 334.654652 -257.22707) (xy 334.607662 -257.37947)
			(xy 334.607662 -257.42392) (xy 334.963262 -257.42392)
		)
		(stroke
			(width 0)
			(type solid)
		)
		(fill yes)
		(layer "In4.Cu")
		(net "M_C_CPU0_SA_CS_N<3>")
	)
	(gr_poly
		(pts
			(xy 334.963262 -256.971038) (xy 334.963262 -256.926588) (xy 334.607662 -256.926588) (xy 334.607662 -256.971038)
			(xy 334.654652 -257.123438) (xy 334.916272 -257.123438)
		)
		(stroke
			(width 0)
			(type solid)
		)
		(fill yes)
		(layer "In4.Cu")
		(net "M_C_CPU0_SA_CA<0>")
	)
	(gr_poly
		(pts
			(xy 334.963262 -255.751838) (xy 334.916272 -255.599438) (xy 334.654652 -255.599438) (xy 334.607662 -255.751838)
			(xy 334.607662 -255.796288) (xy 334.963262 -255.796288)
		)
		(stroke
			(width 0)
			(type solid)
		)
		(fill yes)
		(layer "In4.Cu")
		(net "M_C_CPU0_SA_CA<3>")
	)
	(gr_poly
		(pts
			(xy 334.963262 -255.343406) (xy 334.963262 -255.298956) (xy 334.607662 -255.298956) (xy 334.607662 -255.343406)
			(xy 334.654652 -255.495806) (xy 334.916272 -255.495806)
		)
		(stroke
			(width 0)
			(type solid)
		)
		(fill yes)
		(layer "In4.Cu")
		(net "M_C_CPU0_SA_CA<4>")
	)
	(gr_poly
		(pts
			(xy 334.963262 -254.124206) (xy 334.916272 -253.971806) (xy 334.654652 -253.971806) (xy 334.607662 -254.124206)
			(xy 334.607662 -254.168402) (xy 334.963262 -254.168402)
		)
		(stroke
			(width 0)
			(type solid)
		)
		(fill yes)
		(layer "In4.Cu")
		(net "M_C_CPU0_SA_PAR")
	)
	(gr_poly
		(pts
			(xy 335.035906 -275.356574) (xy 334.927448 -275.239734) (xy 334.889094 -275.217636) (xy 334.711294 -275.525484)
			(xy 334.749648 -275.547582) (xy 334.905096 -275.583142)
		)
		(stroke
			(width 0)
			(type solid)
		)
		(fill yes)
		(layer "In4.Cu")
		(net "M_B_CPU0_SA_DQ<9>")
	)
	(gr_poly
		(pts
			(xy 335.03616 -280.239978) (xy 334.927702 -280.123138) (xy 334.889348 -280.10104) (xy 334.711548 -280.408888)
			(xy 334.749902 -280.430986) (xy 334.90535 -280.466546)
		)
		(stroke
			(width 0)
			(type solid)
		)
		(fill yes)
		(layer "In4.Cu")
		(net "M_C_CPU0_SA_DQ<5>")
	)
	(gr_poly
		(pts
			(xy 335.042764 -281.856434) (xy 334.934306 -281.739594) (xy 334.895952 -281.717496) (xy 334.718152 -282.025344)
			(xy 334.756506 -282.047442) (xy 334.911954 -282.083002)
		)
		(stroke
			(width 0)
			(type solid)
		)
		(fill yes)
		(layer "In4.Cu")
		(net "M_C_CPU0_SA_DQ<4>")
	)
	(gr_poly
		(pts
			(xy 335.042764 -273.717766) (xy 334.934306 -273.600926) (xy 334.895952 -273.578828) (xy 334.718152 -273.886676)
			(xy 334.756506 -273.908774) (xy 334.911954 -273.944334)
		)
		(stroke
			(width 0)
			(type solid)
		)
		(fill yes)
		(layer "In4.Cu")
		(net "M_B_CPU0_SA_DQS_DP<1>")
	)
	(gr_poly
		(pts
			(xy 335.217516 -247.551448) (xy 335.179162 -247.52935) (xy 335.023714 -247.49379) (xy 334.892904 -247.720358)
			(xy 335.001362 -247.837198) (xy 335.039716 -247.859296)
		)
		(stroke
			(width 0)
			(type solid)
		)
		(fill yes)
		(layer "In4.Cu")
		(net "M_C_CPU0_SB_CA<3>")
	)
	(gr_poly
		(pts
			(xy 335.217516 -245.923816) (xy 335.179162 -245.901718) (xy 335.023714 -245.866158) (xy 334.892904 -246.092726)
			(xy 335.001362 -246.209566) (xy 335.039716 -246.231664)
		)
		(stroke
			(width 0)
			(type solid)
		)
		(fill yes)
		(layer "In4.Cu")
		(net "M_C_CPU0_SB_CA<5>")
	)
	(gr_poly
		(pts
			(xy 335.217516 -241.040412) (xy 335.179162 -241.018314) (xy 335.023714 -240.982754) (xy 334.892904 -241.209322)
			(xy 335.001362 -241.326162) (xy 335.039716 -241.34826)
		)
		(stroke
			(width 0)
			(type solid)
		)
		(fill yes)
		(layer "In4.Cu")
		(net "M_C_CPU0_SB_CB<7>")
	)
	(gr_poly
		(pts
			(xy 335.314798 -244.940582) (xy 335.267808 -244.788182) (xy 335.006188 -244.788182) (xy 334.959198 -244.940582)
			(xy 334.959198 -244.985032) (xy 335.314798 -244.985032)
		)
		(stroke
			(width 0)
			(type solid)
		)
		(fill yes)
		(layer "In4.Cu")
		(net "M_C_CPU0_SB_PAR")
	)
	(gr_poly
		(pts
			(xy 335.314798 -240.057178) (xy 335.267808 -239.904778) (xy 335.006188 -239.904778) (xy 334.959198 -240.057178)
			(xy 334.959198 -240.101628) (xy 335.314798 -240.101628)
		)
		(stroke
			(width 0)
			(type solid)
		)
		(fill yes)
		(layer "In4.Cu")
		(net "M_C_CPU0_SB_DQS_DN<9>")
	)
	(gr_poly
		(pts
			(xy 335.314798 -239.649254) (xy 335.314798 -239.604804) (xy 334.959198 -239.604804) (xy 334.959198 -239.649254)
			(xy 335.006188 -239.801654) (xy 335.267808 -239.801654)
		)
		(stroke
			(width 0)
			(type solid)
		)
		(fill yes)
		(layer "In4.Cu")
		(net "M_C_CPU0_SB_DQS_DN<4>")
	)
	(gr_poly
		(pts
			(xy 335.314798 -235.174282) (xy 335.267808 -235.021882) (xy 335.006188 -235.021882) (xy 334.959198 -235.174282)
			(xy 334.959198 -235.218478) (xy 335.314798 -235.218478)
		)
		(stroke
			(width 0)
			(type solid)
		)
		(fill yes)
		(layer "In4.Cu")
		(net "M_B_CPU0_SB_DQS_DN<0>")
	)
	(gr_poly
		(pts
			(xy 335.314798 -234.76585) (xy 335.314798 -234.721654) (xy 334.959198 -234.721654) (xy 334.959198 -234.76585)
			(xy 335.006188 -234.91825) (xy 335.267808 -234.91825)
		)
		(stroke
			(width 0)
			(type solid)
		)
		(fill yes)
		(layer "In4.Cu")
		(net "M_B_CPU0_SB_DQS_DN<5>")
	)
	(gr_poly
		(pts
			(xy 335.314798 -230.290878) (xy 335.267808 -230.138478) (xy 335.006188 -230.138478) (xy 334.959198 -230.290878)
			(xy 334.959198 -230.335074) (xy 335.314798 -230.335074)
		)
		(stroke
			(width 0)
			(type solid)
		)
		(fill yes)
		(layer "In4.Cu")
		(net "M_C_CPU0_SB_DQS_DN<2>")
	)
	(gr_poly
		(pts
			(xy 335.314798 -229.882446) (xy 335.314798 -229.83825) (xy 334.959198 -229.83825) (xy 334.959198 -229.882446)
			(xy 335.006188 -230.034846) (xy 335.267808 -230.034846)
		)
		(stroke
			(width 0)
			(type solid)
		)
		(fill yes)
		(layer "In4.Cu")
		(net "M_C_CPU0_SB_DQS_DN<7>")
	)
	(gr_poly
		(pts
			(xy 335.322926 -281.972258) (xy 335.284572 -281.95016) (xy 335.129124 -281.9146) (xy 334.998314 -282.141168)
			(xy 335.106772 -282.258008) (xy 335.145126 -282.280106)
		)
		(stroke
			(width 0)
			(type solid)
		)
		(fill yes)
		(layer "In4.Cu")
		(net "M_C_CPU0_SA_DQS_DP<5>")
	)
	(gr_poly
		(pts
			(xy 335.32318 -244.53215) (xy 335.32318 -244.487954) (xy 334.96758 -244.487954) (xy 334.96758 -244.53215)
			(xy 335.01457 -244.68455) (xy 335.27619 -244.68455)
		)
		(stroke
			(width 0)
			(type solid)
		)
		(fill yes)
		(layer "In4.Cu")
		(net "M_C_CPU0_SB_CS_N<2>")
	)
	(gr_poly
		(pts
			(xy 335.323434 -238.430054) (xy 335.276444 -238.277654) (xy 335.014824 -238.277654) (xy 334.967834 -238.430054)
			(xy 334.967834 -238.47425) (xy 335.323434 -238.47425)
		)
		(stroke
			(width 0)
			(type solid)
		)
		(fill yes)
		(layer "In4.Cu")
		(net "M_C_CPU0_SB_CB<2>")
	)
	(gr_poly
		(pts
			(xy 335.323434 -236.393482) (xy 335.323434 -236.349286) (xy 334.967834 -236.349286) (xy 334.967834 -236.393482)
			(xy 335.014824 -236.545882) (xy 335.276444 -236.545882)
		)
		(stroke
			(width 0)
			(type solid)
		)
		(fill yes)
		(layer "In4.Cu")
		(net "M_B_CPU0_SB_DQ<1>")
	)
	(gr_poly
		(pts
			(xy 335.323434 -233.54665) (xy 335.276444 -233.39425) (xy 335.014824 -233.39425) (xy 334.967834 -233.54665)
			(xy 334.967834 -233.590846) (xy 335.323434 -233.590846)
		)
		(stroke
			(width 0)
			(type solid)
		)
		(fill yes)
		(layer "In4.Cu")
		(net "M_B_CPU0_SB_DQ<6>")
	)
	(gr_poly
		(pts
			(xy 335.323434 -233.13771) (xy 335.323434 -233.093514) (xy 334.967834 -233.093514) (xy 334.967834 -233.13771)
			(xy 335.014824 -233.29011) (xy 335.276444 -233.29011)
		)
		(stroke
			(width 0)
			(type solid)
		)
		(fill yes)
		(layer "In4.Cu")
		(net "M_B_CPU0_SB_DQ<5>")
	)
	(gr_poly
		(pts
			(xy 335.323434 -231.919018) (xy 335.276444 -231.766618) (xy 335.014824 -231.766618) (xy 334.967834 -231.919018)
			(xy 334.967834 -231.963214) (xy 335.323434 -231.963214)
		)
		(stroke
			(width 0)
			(type solid)
		)
		(fill yes)
		(layer "In4.Cu")
		(net "M_C_CPU0_SB_DQ<18>")
	)
	(gr_poly
		(pts
			(xy 335.323434 -231.510078) (xy 335.323434 -231.465882) (xy 334.967834 -231.465882) (xy 334.967834 -231.510078)
			(xy 335.014824 -231.662478) (xy 335.276444 -231.662478)
		)
		(stroke
			(width 0)
			(type solid)
		)
		(fill yes)
		(layer "In4.Cu")
		(net "M_C_CPU0_SB_DQ<17>")
	)
	(gr_poly
		(pts
			(xy 335.323434 -228.663246) (xy 335.276444 -228.510846) (xy 335.014824 -228.510846) (xy 334.967834 -228.663246)
			(xy 334.967834 -228.707696) (xy 335.323434 -228.707696)
		)
		(stroke
			(width 0)
			(type solid)
		)
		(fill yes)
		(layer "In4.Cu")
		(net "M_C_CPU0_SB_DQ<22>")
	)
	(gr_poly
		(pts
			(xy 335.327244 -273.826224) (xy 335.28889 -273.804126) (xy 335.133442 -273.768566) (xy 335.002632 -273.995134)
			(xy 335.11109 -274.111974) (xy 335.149444 -274.134072)
		)
		(stroke
			(width 0)
			(type solid)
		)
		(fill yes)
		(layer "In4.Cu")
		(net "M_B_CPU0_SA_DQ<11>")
	)
	(gr_poly
		(pts
			(xy 335.328514 -278.707088) (xy 335.29016 -278.68499) (xy 335.134712 -278.64943) (xy 335.003902 -278.875998)
			(xy 335.11236 -278.992838) (xy 335.150714 -279.014936)
		)
		(stroke
			(width 0)
			(type solid)
		)
		(fill yes)
		(layer "In4.Cu")
		(net "M_C_CPU0_SA_DQ<7>")
	)
	(gr_poly
		(pts
			(xy 335.329022 -275.450046) (xy 335.290668 -275.427948) (xy 335.13522 -275.392388) (xy 335.00441 -275.618956)
			(xy 335.112868 -275.735796) (xy 335.151222 -275.757894)
		)
		(stroke
			(width 0)
			(type solid)
		)
		(fill yes)
		(layer "In4.Cu")
		(net "M_B_CPU0_SA_DQ<10>")
	)
	(gr_poly
		(pts
			(xy 335.331816 -243.31295) (xy 335.284826 -243.16055) (xy 335.023206 -243.16055) (xy 334.976216 -243.31295)
			(xy 334.976216 -243.3574) (xy 335.331816 -243.3574)
		)
		(stroke
			(width 0)
			(type solid)
		)
		(fill yes)
		(layer "In4.Cu")
		(net "M_C_CPU0_SB_CS_N<1>")
	)
	(gr_poly
		(pts
			(xy 335.331816 -242.905026) (xy 335.331816 -242.860576) (xy 334.976216 -242.860576) (xy 334.976216 -242.905026)
			(xy 335.023206 -243.057426) (xy 335.284826 -243.057426)
		)
		(stroke
			(width 0)
			(type solid)
		)
		(fill yes)
		(layer "In4.Cu")
		(net "M_C_CPU0_SB_CB<4>")
	)
	(gr_poly
		(pts
			(xy 335.331816 -238.021622) (xy 335.331816 -237.977172) (xy 334.976216 -237.977172) (xy 334.976216 -238.021622)
			(xy 335.023206 -238.174022) (xy 335.284826 -238.174022)
		)
		(stroke
			(width 0)
			(type solid)
		)
		(fill yes)
		(layer "In4.Cu")
		(net "M_C_CPU0_SB_CB<1>")
	)
	(gr_poly
		(pts
			(xy 335.331816 -236.801914) (xy 335.284826 -236.649514) (xy 335.023206 -236.649514) (xy 334.976216 -236.801914)
			(xy 334.976216 -236.846364) (xy 335.331816 -236.846364)
		)
		(stroke
			(width 0)
			(type solid)
		)
		(fill yes)
		(layer "In4.Cu")
		(net "M_B_CPU0_SB_DQ<0>")
	)
	(gr_poly
		(pts
			(xy 335.331816 -228.254814) (xy 335.331816 -228.210618) (xy 334.976216 -228.210618) (xy 334.976216 -228.254814)
			(xy 335.023206 -228.407214) (xy 335.284826 -228.407214)
		)
		(stroke
			(width 0)
			(type solid)
		)
		(fill yes)
		(layer "In4.Cu")
		(net "M_C_CPU0_SB_DQ<21>")
	)
	(gr_poly
		(pts
			(xy 335.396332 -248.267982) (xy 335.287874 -248.151142) (xy 335.24952 -248.129044) (xy 335.07172 -248.436892)
			(xy 335.110074 -248.45899) (xy 335.265522 -248.49455)
		)
		(stroke
			(width 0)
			(type solid)
		)
		(fill yes)
		(layer "In4.Cu")
		(net "M_C_CPU0_SB_CA<2>")
	)
	(gr_poly
		(pts
			(xy 335.398364 -246.636286) (xy 335.289906 -246.519446) (xy 335.251552 -246.497348) (xy 335.073752 -246.805196)
			(xy 335.112106 -246.827294) (xy 335.267554 -246.862854)
		)
		(stroke
			(width 0)
			(type solid)
		)
		(fill yes)
		(layer "In4.Cu")
		(net "M_C_CPU0_SB_CA<4>")
	)
	(gr_poly
		(pts
			(xy 335.402682 -241.74577) (xy 335.294224 -241.62893) (xy 335.25587 -241.606832) (xy 335.07807 -241.91468)
			(xy 335.116424 -241.936778) (xy 335.271872 -241.972338)
		)
		(stroke
			(width 0)
			(type solid)
		)
		(fill yes)
		(layer "In4.Cu")
		(net "M_C_CPU0_SB_CB<5>")
	)
	(gr_poly
		(pts
			(xy 335.42478 -280.98242) (xy 335.37779 -280.83002) (xy 335.11617 -280.83002) (xy 335.06918 -280.98242)
			(xy 335.06918 -281.026616) (xy 335.42478 -281.026616)
		)
		(stroke
			(width 0)
			(type solid)
		)
		(fill yes)
		(layer "In4.Cu")
		(net "M_C_CPU0_SA_DQ<6>")
	)
	(gr_poly
		(pts
			(xy 335.433162 -287.49371) (xy 335.386172 -287.34131) (xy 335.124552 -287.34131) (xy 335.077562 -287.49371)
			(xy 335.077562 -287.537906) (xy 335.433162 -287.537906)
		)
		(stroke
			(width 0)
			(type solid)
		)
		(fill yes)
		(layer "In4.Cu")
		(net "M_C_CPU0_SA_DQ<2>")
	)
	(gr_poly
		(pts
			(xy 335.433162 -285.86557) (xy 335.386172 -285.71317) (xy 335.124552 -285.71317) (xy 335.077562 -285.86557)
			(xy 335.077562 -285.91002) (xy 335.433162 -285.91002)
		)
		(stroke
			(width 0)
			(type solid)
		)
		(fill yes)
		(layer "In4.Cu")
		(net "M_C_CPU0_SA_DQ<3>")
	)
	(gr_poly
		(pts
			(xy 335.433162 -285.456884) (xy 335.433162 -285.412688) (xy 335.077562 -285.412688) (xy 335.077562 -285.456884)
			(xy 335.124552 -285.609284) (xy 335.386172 -285.609284)
		)
		(stroke
			(width 0)
			(type solid)
		)
		(fill yes)
		(layer "In4.Cu")
		(net "M_C_CPU0_SA_DQS_DP<0>")
	)
	(gr_poly
		(pts
			(xy 335.433162 -271.215866) (xy 335.386172 -271.063466) (xy 335.124552 -271.063466) (xy 335.077562 -271.215866)
			(xy 335.077562 -271.260062) (xy 335.433162 -271.260062)
		)
		(stroke
			(width 0)
			(type solid)
		)
		(fill yes)
		(layer "In4.Cu")
		(net "M_B_CPU0_SA_DQ<14>")
	)
	(gr_poly
		(pts
			(xy 335.433162 -270.806926) (xy 335.433162 -270.76273) (xy 335.077562 -270.76273) (xy 335.077562 -270.806926)
			(xy 335.124552 -270.959326) (xy 335.386172 -270.959326)
		)
		(stroke
			(width 0)
			(type solid)
		)
		(fill yes)
		(layer "In4.Cu")
		(net "M_B_CPU0_SA_DQ<13>")
	)
	(gr_poly
		(pts
			(xy 335.433162 -269.587726) (xy 335.386172 -269.435326) (xy 335.124552 -269.435326) (xy 335.077562 -269.587726)
			(xy 335.077562 -269.632176) (xy 335.433162 -269.632176)
		)
		(stroke
			(width 0)
			(type solid)
		)
		(fill yes)
		(layer "In4.Cu")
		(net "M_C_CPU0_SA_DQ<18>")
	)
	(gr_poly
		(pts
			(xy 335.433162 -269.179294) (xy 335.433162 -269.134844) (xy 335.077562 -269.134844) (xy 335.077562 -269.179294)
			(xy 335.124552 -269.331694) (xy 335.386172 -269.331694)
		)
		(stroke
			(width 0)
			(type solid)
		)
		(fill yes)
		(layer "In4.Cu")
		(net "M_C_CPU0_SA_DQ<17>")
	)
	(gr_poly
		(pts
			(xy 335.433162 -267.960094) (xy 335.386172 -267.807694) (xy 335.124552 -267.807694) (xy 335.077562 -267.960094)
			(xy 335.077562 -268.004544) (xy 335.433162 -268.004544)
		)
		(stroke
			(width 0)
			(type solid)
		)
		(fill yes)
		(layer "In4.Cu")
		(net "M_C_CPU0_SA_DQS_DN<2>")
	)
	(gr_poly
		(pts
			(xy 335.433162 -267.551662) (xy 335.433162 -267.507212) (xy 335.077562 -267.507212) (xy 335.077562 -267.551662)
			(xy 335.124552 -267.704062) (xy 335.386172 -267.704062)
		)
		(stroke
			(width 0)
			(type solid)
		)
		(fill yes)
		(layer "In4.Cu")
		(net "M_C_CPU0_SA_DQS_DN<7>")
	)
	(gr_poly
		(pts
			(xy 335.433162 -266.332462) (xy 335.386172 -266.180062) (xy 335.124552 -266.180062) (xy 335.077562 -266.332462)
			(xy 335.077562 -266.376658) (xy 335.433162 -266.376658)
		)
		(stroke
			(width 0)
			(type solid)
		)
		(fill yes)
		(layer "In4.Cu")
		(net "M_C_CPU0_SA_DQ<22>")
	)
	(gr_poly
		(pts
			(xy 335.433162 -265.92403) (xy 335.433162 -265.87958) (xy 335.077562 -265.87958) (xy 335.077562 -265.92403)
			(xy 335.124552 -266.07643) (xy 335.386172 -266.07643)
		)
		(stroke
			(width 0)
			(type solid)
		)
		(fill yes)
		(layer "In4.Cu")
		(net "M_C_CPU0_SA_DQ<21>")
	)
	(gr_poly
		(pts
			(xy 335.433162 -264.70483) (xy 335.386172 -264.55243) (xy 335.124552 -264.55243) (xy 335.077562 -264.70483)
			(xy 335.077562 -264.749026) (xy 335.433162 -264.749026)
		)
		(stroke
			(width 0)
			(type solid)
		)
		(fill yes)
		(layer "In4.Cu")
		(net "M_B_CPU0_SA_DQ<24>")
	)
	(gr_poly
		(pts
			(xy 335.433162 -264.29589) (xy 335.433162 -264.251694) (xy 335.077562 -264.251694) (xy 335.077562 -264.29589)
			(xy 335.124552 -264.44829) (xy 335.386172 -264.44829)
		)
		(stroke
			(width 0)
			(type solid)
		)
		(fill yes)
		(layer "In4.Cu")
		(net "M_B_CPU0_SA_DQ<25>")
	)
	(gr_poly
		(pts
			(xy 335.433162 -263.07669) (xy 335.386172 -262.92429) (xy 335.124552 -262.92429) (xy 335.077562 -263.07669)
			(xy 335.077562 -263.12114) (xy 335.433162 -263.12114)
		)
		(stroke
			(width 0)
			(type solid)
		)
		(fill yes)
		(layer "In4.Cu")
		(net "M_B_CPU0_SA_DQS_DN<3>")
	)
	(gr_poly
		(pts
			(xy 335.433162 -262.668258) (xy 335.433162 -262.623808) (xy 335.077562 -262.623808) (xy 335.077562 -262.668258)
			(xy 335.124552 -262.820658) (xy 335.386172 -262.820658)
		)
		(stroke
			(width 0)
			(type solid)
		)
		(fill yes)
		(layer "In4.Cu")
		(net "M_B_CPU0_SA_DQS_DN<8>")
	)
	(gr_poly
		(pts
			(xy 335.433162 -261.449058) (xy 335.386172 -261.296658) (xy 335.124552 -261.296658) (xy 335.077562 -261.449058)
			(xy 335.077562 -261.493508) (xy 335.433162 -261.493508)
		)
		(stroke
			(width 0)
			(type solid)
		)
		(fill yes)
		(layer "In4.Cu")
		(net "M_B_CPU0_SA_DQ<30>")
	)
	(gr_poly
		(pts
			(xy 335.433162 -261.040626) (xy 335.433162 -260.996176) (xy 335.077562 -260.996176) (xy 335.077562 -261.040626)
			(xy 335.124552 -261.193026) (xy 335.386172 -261.193026)
		)
		(stroke
			(width 0)
			(type solid)
		)
		(fill yes)
		(layer "In4.Cu")
		(net "M_B_CPU0_SA_DQ<29>")
	)
	(gr_poly
		(pts
			(xy 335.433162 -258.193286) (xy 335.386172 -258.040886) (xy 335.124552 -258.040886) (xy 335.077562 -258.193286)
			(xy 335.077562 -258.237736) (xy 335.433162 -258.237736)
		)
		(stroke
			(width 0)
			(type solid)
		)
		(fill yes)
		(layer "In4.Cu")
		(net "M_C_CPU0_SA_CS_N<2>")
	)
	(gr_poly
		(pts
			(xy 335.433162 -257.784854) (xy 335.433162 -257.740404) (xy 335.077562 -257.740404) (xy 335.077562 -257.784854)
			(xy 335.124552 -257.937254) (xy 335.386172 -257.937254)
		)
		(stroke
			(width 0)
			(type solid)
		)
		(fill yes)
		(layer "In4.Cu")
		(net "M_C_CPU0_SA_CS_N<1>")
	)
	(gr_poly
		(pts
			(xy 335.433162 -256.565654) (xy 335.386172 -256.413254) (xy 335.124552 -256.413254) (xy 335.077562 -256.565654)
			(xy 335.077562 -256.610104) (xy 335.433162 -256.610104)
		)
		(stroke
			(width 0)
			(type solid)
		)
		(fill yes)
		(layer "In4.Cu")
		(net "M_C_CPU0_SA_CA<1>")
	)
	(gr_poly
		(pts
			(xy 335.433162 -256.157222) (xy 335.433162 -256.112772) (xy 335.077562 -256.112772) (xy 335.077562 -256.157222)
			(xy 335.124552 -256.309622) (xy 335.386172 -256.309622)
		)
		(stroke
			(width 0)
			(type solid)
		)
		(fill yes)
		(layer "In4.Cu")
		(net "M_C_CPU0_SA_CA<2>")
	)
	(gr_poly
		(pts
			(xy 335.433162 -254.938022) (xy 335.386172 -254.785622) (xy 335.124552 -254.785622) (xy 335.077562 -254.938022)
			(xy 335.077562 -254.982218) (xy 335.433162 -254.982218)
		)
		(stroke
			(width 0)
			(type solid)
		)
		(fill yes)
		(layer "In4.Cu")
		(net "M_C_CPU0_SA_CA<5>")
	)
	(gr_poly
		(pts
			(xy 335.433162 -254.529082) (xy 335.433162 -254.484886) (xy 335.077562 -254.484886) (xy 335.077562 -254.529082)
			(xy 335.124552 -254.681482) (xy 335.386172 -254.681482)
		)
		(stroke
			(width 0)
			(type solid)
		)
		(fill yes)
		(layer "In4.Cu")
		(net "M_C_CPU0_SA_CA<6>")
	)
	(gr_poly
		(pts
			(xy 335.439258 -272.843498) (xy 335.392268 -272.691098) (xy 335.130648 -272.691098) (xy 335.083658 -272.843498)
			(xy 335.083658 -272.887948) (xy 335.439258 -272.887948)
		)
		(stroke
			(width 0)
			(type solid)
		)
		(fill yes)
		(layer "In4.Cu")
		(net "M_B_CPU0_SA_DQS_DN<1>")
	)
	(gr_poly
		(pts
			(xy 335.439258 -272.435066) (xy 335.439258 -272.390616) (xy 335.083658 -272.390616) (xy 335.083658 -272.435066)
			(xy 335.130648 -272.587466) (xy 335.392268 -272.587466)
		)
		(stroke
			(width 0)
			(type solid)
		)
		(fill yes)
		(layer "In4.Cu")
		(net "M_B_CPU0_SA_DQS_DN<6>")
	)
	(gr_poly
		(pts
			(xy 335.506822 -276.16912) (xy 335.398364 -276.05228) (xy 335.36001 -276.030182) (xy 335.18221 -276.33803)
			(xy 335.220564 -276.360128) (xy 335.376012 -276.395688)
		)
		(stroke
			(width 0)
			(type solid)
		)
		(fill yes)
		(layer "In4.Cu")
		(net "M_B_CPU0_SA_DQ<8>")
	)
	(gr_poly
		(pts
			(xy 335.50733 -282.679648) (xy 335.398872 -282.562808) (xy 335.360518 -282.54071) (xy 335.182718 -282.848558)
			(xy 335.221072 -282.870656) (xy 335.37652 -282.906216)
		)
		(stroke
			(width 0)
			(type solid)
		)
		(fill yes)
		(layer "In4.Cu")
		(net "M_C_CPU0_SA_DQS_DN<5>")
	)
	(gr_poly
		(pts
			(xy 335.51241 -274.531582) (xy 335.403952 -274.414742) (xy 335.365598 -274.392644) (xy 335.187798 -274.700492)
			(xy 335.226152 -274.72259) (xy 335.3816 -274.75815)
		)
		(stroke
			(width 0)
			(type solid)
		)
		(fill yes)
		(layer "In4.Cu")
		(net "M_B_CPU0_SA_DQ<9>")
	)
	(gr_poly
		(pts
			(xy 335.512664 -279.414986) (xy 335.404206 -279.298146) (xy 335.365852 -279.276048) (xy 335.188052 -279.583896)
			(xy 335.226406 -279.605994) (xy 335.381854 -279.641554)
		)
		(stroke
			(width 0)
			(type solid)
		)
		(fill yes)
		(layer "In4.Cu")
		(net "M_C_CPU0_SA_DQ<5>")
	)
	(gr_poly
		(pts
			(xy 335.683098 -241.861594) (xy 335.644744 -241.839496) (xy 335.489296 -241.803936) (xy 335.358486 -242.030504)
			(xy 335.466944 -242.147344) (xy 335.505298 -242.169442)
		)
		(stroke
			(width 0)
			(type solid)
		)
		(fill yes)
		(layer "In4.Cu")
		(net "M_C_CPU0_SB_CB<6>")
	)
	(gr_poly
		(pts
			(xy 335.687416 -246.737632) (xy 335.649062 -246.715534) (xy 335.493614 -246.679974) (xy 335.362804 -246.906542)
			(xy 335.471262 -247.023382) (xy 335.509616 -247.04548)
		)
		(stroke
			(width 0)
			(type solid)
		)
		(fill yes)
		(layer "In4.Cu")
		(net "M_C_CPU0_SB_CA<3>")
	)
	(gr_poly
		(pts
			(xy 335.760822 -280.430986) (xy 335.799176 -280.408888) (xy 335.621376 -280.10104) (xy 335.583022 -280.123138)
			(xy 335.474564 -280.239978) (xy 335.605374 -280.466546)
		)
		(stroke
			(width 0)
			(type solid)
		)
		(fill yes)
		(layer "In4.Cu")
		(net "M_C_CPU0_SA_DQ<6>")
	)
	(gr_poly
		(pts
			(xy 335.787238 -243.718842) (xy 335.787238 -243.674392) (xy 335.431638 -243.674392) (xy 335.431638 -243.718842)
			(xy 335.478628 -243.871242) (xy 335.740248 -243.871242)
		)
		(stroke
			(width 0)
			(type solid)
		)
		(fill yes)
		(layer "In4.Cu")
		(net "M_C_CPU0_SB_CS_N<3>")
	)
	(gr_poly
		(pts
			(xy 335.787238 -237.207806) (xy 335.787238 -237.163356) (xy 335.431638 -237.163356) (xy 335.431638 -237.207806)
			(xy 335.478628 -237.360206) (xy 335.740248 -237.360206)
		)
		(stroke
			(width 0)
			(type solid)
		)
		(fill yes)
		(layer "In4.Cu")
		(net "M_B_CPU0_SB_DQ<2>")
	)
	(gr_poly
		(pts
			(xy 335.787238 -227.848922) (xy 335.740248 -227.696522) (xy 335.478628 -227.696522) (xy 335.431638 -227.848922)
			(xy 335.431638 -227.893372) (xy 335.787238 -227.893372)
		)
		(stroke
			(width 0)
			(type solid)
		)
		(fill yes)
		(layer "In4.Cu")
		(net "M_C_CPU0_SB_DQ<23>")
	)
	(gr_poly
		(pts
			(xy 335.790286 -229.06863) (xy 335.790286 -229.02418) (xy 335.434686 -229.02418) (xy 335.434686 -229.06863)
			(xy 335.481676 -229.22103) (xy 335.743296 -229.22103)
		)
		(stroke
			(width 0)
			(type solid)
		)
		(fill yes)
		(layer "In4.Cu")
		(net "M_C_CPU0_SB_DQ<20>")
	)
	(gr_poly
		(pts
			(xy 335.790794 -274.6502) (xy 335.75244 -274.628102) (xy 335.596992 -274.592542) (xy 335.466182 -274.81911)
			(xy 335.57464 -274.93595) (xy 335.612994 -274.958048)
		)
		(stroke
			(width 0)
			(type solid)
		)
		(fill yes)
		(layer "In4.Cu")
		(net "M_B_CPU0_SA_DQ<10>")
	)
	(gr_poly
		(pts
			(xy 335.793334 -245.754906) (xy 335.746344 -245.602506) (xy 335.484724 -245.602506) (xy 335.437734 -245.754906)
			(xy 335.437734 -245.799356) (xy 335.793334 -245.799356)
		)
		(stroke
			(width 0)
			(type solid)
		)
		(fill yes)
		(layer "In4.Cu")
		(net "M_C_CPU0_SB_CA<5>")
	)
	(gr_poly
		(pts
			(xy 335.793334 -240.871502) (xy 335.746344 -240.719102) (xy 335.484724 -240.719102) (xy 335.437734 -240.871502)
			(xy 335.437734 -240.915952) (xy 335.793334 -240.915952)
		)
		(stroke
			(width 0)
			(type solid)
		)
		(fill yes)
		(layer "In4.Cu")
		(net "M_C_CPU0_SB_CB<7>")
	)
	(gr_poly
		(pts
			(xy 335.793334 -238.83493) (xy 335.793334 -238.790734) (xy 335.437734 -238.790734) (xy 335.437734 -238.83493)
			(xy 335.484724 -238.98733) (xy 335.746344 -238.98733)
		)
		(stroke
			(width 0)
			(type solid)
		)
		(fill yes)
		(layer "In4.Cu")
		(net "M_C_CPU0_SB_CB<0>")
	)
	(gr_poly
		(pts
			(xy 335.793334 -235.988098) (xy 335.746344 -235.835698) (xy 335.484724 -235.835698) (xy 335.437734 -235.988098)
			(xy 335.437734 -236.032548) (xy 335.793334 -236.032548)
		)
		(stroke
			(width 0)
			(type solid)
		)
		(fill yes)
		(layer "In4.Cu")
		(net "M_B_CPU0_SB_DQ<3>")
	)
	(gr_poly
		(pts
			(xy 335.793334 -233.952034) (xy 335.793334 -233.907584) (xy 335.437734 -233.907584) (xy 335.437734 -233.952034)
			(xy 335.484724 -234.104434) (xy 335.746344 -234.104434)
		)
		(stroke
			(width 0)
			(type solid)
		)
		(fill yes)
		(layer "In4.Cu")
		(net "M_B_CPU0_SB_DQ<4>")
	)
	(gr_poly
		(pts
			(xy 335.793334 -232.732834) (xy 335.746344 -232.580434) (xy 335.484724 -232.580434) (xy 335.437734 -232.732834)
			(xy 335.437734 -232.77703) (xy 335.793334 -232.77703)
		)
		(stroke
			(width 0)
			(type solid)
		)
		(fill yes)
		(layer "In4.Cu")
		(net "M_B_CPU0_SB_DQ<7>")
	)
	(gr_poly
		(pts
			(xy 335.793334 -232.323894) (xy 335.793334 -232.279698) (xy 335.437734 -232.279698) (xy 335.437734 -232.323894)
			(xy 335.484724 -232.476294) (xy 335.746344 -232.476294)
		)
		(stroke
			(width 0)
			(type solid)
		)
		(fill yes)
		(layer "In4.Cu")
		(net "M_C_CPU0_SB_DQ<16>")
	)
	(gr_poly
		(pts
			(xy 335.793334 -231.104694) (xy 335.746344 -230.952294) (xy 335.484724 -230.952294) (xy 335.437734 -231.104694)
			(xy 335.437734 -231.149144) (xy 335.793334 -231.149144)
		)
		(stroke
			(width 0)
			(type solid)
		)
		(fill yes)
		(layer "In4.Cu")
		(net "M_C_CPU0_SB_DQ<19>")
	)
	(gr_poly
		(pts
			(xy 335.797144 -284.406848) (xy 335.75879 -284.38475) (xy 335.603342 -284.34919) (xy 335.472532 -284.575758)
			(xy 335.58099 -284.692598) (xy 335.619344 -284.714696)
		)
		(stroke
			(width 0)
			(type solid)
		)
		(fill yes)
		(layer "In4.Cu")
		(net "M_C_CPU0_SA_DQS_DN<0>")
	)
	(gr_poly
		(pts
			(xy 335.797144 -279.523444) (xy 335.75879 -279.501346) (xy 335.603342 -279.465786) (xy 335.472532 -279.692354)
			(xy 335.58099 -279.809194) (xy 335.619344 -279.831292)
		)
		(stroke
			(width 0)
			(type solid)
		)
		(fill yes)
		(layer "In4.Cu")
		(net "M_C_CPU0_SA_DQ<6>")
	)
	(gr_poly
		(pts
			(xy 335.79816 -277.893272) (xy 335.759806 -277.871174) (xy 335.604358 -277.835614) (xy 335.473548 -278.062182)
			(xy 335.582006 -278.179022) (xy 335.62036 -278.20112)
		)
		(stroke
			(width 0)
			(type solid)
		)
		(fill yes)
		(layer "In4.Cu")
		(net "M_C_CPU0_SA_DQ<7>")
	)
	(gr_poly
		(pts
			(xy 335.798414 -237.61573) (xy 335.751424 -237.46333) (xy 335.489804 -237.46333) (xy 335.442814 -237.61573)
			(xy 335.442814 -237.66018) (xy 335.798414 -237.66018)
		)
		(stroke
			(width 0)
			(type solid)
		)
		(fill yes)
		(layer "In4.Cu")
		(net "M_C_CPU0_SB_CB<3>")
	)
	(gr_poly
		(pts
			(xy 335.799176 -244.126766) (xy 335.752186 -243.974366) (xy 335.490566 -243.974366) (xy 335.443576 -244.126766)
			(xy 335.443576 -244.171216) (xy 335.799176 -244.171216)
		)
		(stroke
			(width 0)
			(type solid)
		)
		(fill yes)
		(layer "In4.Cu")
		(net "M_C_CPU0_SB_CS_N<0>")
	)
	(gr_poly
		(pts
			(xy 335.801716 -245.346474) (xy 335.801716 -245.302278) (xy 335.446116 -245.302278) (xy 335.446116 -245.346474)
			(xy 335.493106 -245.498874) (xy 335.754726 -245.498874)
		)
		(stroke
			(width 0)
			(type solid)
		)
		(fill yes)
		(layer "In4.Cu")
		(net "M_C_CPU0_SB_CA<6>")
	)
	(gr_poly
		(pts
			(xy 335.801716 -240.46307) (xy 335.801716 -240.418874) (xy 335.446116 -240.418874) (xy 335.446116 -240.46307)
			(xy 335.493106 -240.61547) (xy 335.754726 -240.61547)
		)
		(stroke
			(width 0)
			(type solid)
		)
		(fill yes)
		(layer "In4.Cu")
		(net "M_C_CPU0_SB_DQS_DP<9>")
	)
	(gr_poly
		(pts
			(xy 335.801716 -239.243362) (xy 335.754726 -239.090962) (xy 335.493106 -239.090962) (xy 335.446116 -239.243362)
			(xy 335.446116 -239.287812) (xy 335.801716 -239.287812)
		)
		(stroke
			(width 0)
			(type solid)
		)
		(fill yes)
		(layer "In4.Cu")
		(net "M_C_CPU0_SB_DQS_DP<4>")
	)
	(gr_poly
		(pts
			(xy 335.801716 -235.579666) (xy 335.801716 -235.53547) (xy 335.446116 -235.53547) (xy 335.446116 -235.579666)
			(xy 335.493106 -235.732066) (xy 335.754726 -235.732066)
		)
		(stroke
			(width 0)
			(type solid)
		)
		(fill yes)
		(layer "In4.Cu")
		(net "M_B_CPU0_SB_DQS_DP<0>")
	)
	(gr_poly
		(pts
			(xy 335.801716 -234.360466) (xy 335.754726 -234.208066) (xy 335.493106 -234.208066) (xy 335.446116 -234.360466)
			(xy 335.446116 -234.404662) (xy 335.801716 -234.404662)
		)
		(stroke
			(width 0)
			(type solid)
		)
		(fill yes)
		(layer "In4.Cu")
		(net "M_B_CPU0_SB_DQS_DP<5>")
	)
	(gr_poly
		(pts
			(xy 335.801716 -230.696262) (xy 335.801716 -230.652066) (xy 335.446116 -230.652066) (xy 335.446116 -230.696262)
			(xy 335.493106 -230.848662) (xy 335.754726 -230.848662)
		)
		(stroke
			(width 0)
			(type solid)
		)
		(fill yes)
		(layer "In4.Cu")
		(net "M_C_CPU0_SB_DQS_DP<2>")
	)
	(gr_poly
		(pts
			(xy 335.801716 -229.477062) (xy 335.754726 -229.324662) (xy 335.493106 -229.324662) (xy 335.446116 -229.477062)
			(xy 335.446116 -229.521258) (xy 335.801716 -229.521258)
		)
		(stroke
			(width 0)
			(type solid)
		)
		(fill yes)
		(layer "In4.Cu")
		(net "M_C_CPU0_SB_DQS_DP<7>")
	)
	(gr_poly
		(pts
			(xy 335.867248 -242.56873) (xy 335.75879 -242.45189) (xy 335.720436 -242.429792) (xy 335.542636 -242.73764)
			(xy 335.58099 -242.759738) (xy 335.736438 -242.795298)
		)
		(stroke
			(width 0)
			(type solid)
		)
		(fill yes)
		(layer "In4.Cu")
		(net "M_C_CPU0_SB_CB<4>")
	)
	(gr_poly
		(pts
			(xy 335.868264 -247.450102) (xy 335.759806 -247.333262) (xy 335.721452 -247.311164) (xy 335.543652 -247.619012)
			(xy 335.582006 -247.64111) (xy 335.737454 -247.67667)
		)
		(stroke
			(width 0)
			(type solid)
		)
		(fill yes)
		(layer "In4.Cu")
		(net "M_C_CPU0_SB_CA<2>")
	)
	(gr_poly
		(pts
			(xy 335.903062 -287.898586) (xy 335.903062 -287.85439) (xy 335.547462 -287.85439) (xy 335.547462 -287.898586)
			(xy 335.594452 -288.050986) (xy 335.856072 -288.050986)
		)
		(stroke
			(width 0)
			(type solid)
		)
		(fill yes)
		(layer "In4.Cu")
		(net "M_C_CPU0_SA_DQ<0>")
	)
	(gr_poly
		(pts
			(xy 335.903062 -286.270954) (xy 335.903062 -286.226758) (xy 335.547462 -286.226758) (xy 335.547462 -286.270954)
			(xy 335.594452 -286.423354) (xy 335.856072 -286.423354)
		)
		(stroke
			(width 0)
			(type solid)
		)
		(fill yes)
		(layer "In4.Cu")
		(net "M_C_CPU0_SA_DQ<1>")
	)
	(gr_poly
		(pts
			(xy 335.903062 -273.657314) (xy 335.856072 -273.504914) (xy 335.594452 -273.504914) (xy 335.547462 -273.657314)
			(xy 335.547462 -273.701764) (xy 335.903062 -273.701764)
		)
		(stroke
			(width 0)
			(type solid)
		)
		(fill yes)
		(layer "In4.Cu")
		(net "M_B_CPU0_SA_DQ<11>")
	)
	(gr_poly
		(pts
			(xy 335.903062 -273.248882) (xy 335.903062 -273.204432) (xy 335.547462 -273.204432) (xy 335.547462 -273.248882)
			(xy 335.594452 -273.401282) (xy 335.856072 -273.401282)
		)
		(stroke
			(width 0)
			(type solid)
		)
		(fill yes)
		(layer "In4.Cu")
		(net "M_B_CPU0_SA_DQS_DP<1>")
	)
	(gr_poly
		(pts
			(xy 335.903062 -272.029682) (xy 335.856072 -271.877282) (xy 335.594452 -271.877282) (xy 335.547462 -272.029682)
			(xy 335.547462 -272.073878) (xy 335.903062 -272.073878)
		)
		(stroke
			(width 0)
			(type solid)
		)
		(fill yes)
		(layer "In4.Cu")
		(net "M_B_CPU0_SA_DQS_DP<6>")
	)
	(gr_poly
		(pts
			(xy 335.903062 -271.620742) (xy 335.903062 -271.576546) (xy 335.547462 -271.576546) (xy 335.547462 -271.620742)
			(xy 335.594452 -271.773142) (xy 335.856072 -271.773142)
		)
		(stroke
			(width 0)
			(type solid)
		)
		(fill yes)
		(layer "In4.Cu")
		(net "M_B_CPU0_SA_DQ<12>")
	)
	(gr_poly
		(pts
			(xy 335.903062 -270.40205) (xy 335.856072 -270.24965) (xy 335.594452 -270.24965) (xy 335.547462 -270.40205)
			(xy 335.547462 -270.446246) (xy 335.903062 -270.446246)
		)
		(stroke
			(width 0)
			(type solid)
		)
		(fill yes)
		(layer "In4.Cu")
		(net "M_B_CPU0_SA_DQ<15>")
	)
	(gr_poly
		(pts
			(xy 335.903062 -269.99311) (xy 335.903062 -269.948914) (xy 335.547462 -269.948914) (xy 335.547462 -269.99311)
			(xy 335.594452 -270.14551) (xy 335.856072 -270.14551)
		)
		(stroke
			(width 0)
			(type solid)
		)
		(fill yes)
		(layer "In4.Cu")
		(net "M_C_CPU0_SA_DQ<16>")
	)
	(gr_poly
		(pts
			(xy 335.903062 -268.77391) (xy 335.856072 -268.62151) (xy 335.594452 -268.62151) (xy 335.547462 -268.77391)
			(xy 335.547462 -268.81836) (xy 335.903062 -268.81836)
		)
		(stroke
			(width 0)
			(type solid)
		)
		(fill yes)
		(layer "In4.Cu")
		(net "M_C_CPU0_SA_DQ<19>")
	)
	(gr_poly
		(pts
			(xy 335.903062 -268.365478) (xy 335.903062 -268.321028) (xy 335.547462 -268.321028) (xy 335.547462 -268.365478)
			(xy 335.594452 -268.517878) (xy 335.856072 -268.517878)
		)
		(stroke
			(width 0)
			(type solid)
		)
		(fill yes)
		(layer "In4.Cu")
		(net "M_C_CPU0_SA_DQS_DP<2>")
	)
	(gr_poly
		(pts
			(xy 335.903062 -267.146278) (xy 335.856072 -266.993878) (xy 335.594452 -266.993878) (xy 335.547462 -267.146278)
			(xy 335.547462 -267.190474) (xy 335.903062 -267.190474)
		)
		(stroke
			(width 0)
			(type solid)
		)
		(fill yes)
		(layer "In4.Cu")
		(net "M_C_CPU0_SA_DQS_DP<7>")
	)
	(gr_poly
		(pts
			(xy 335.903062 -266.737846) (xy 335.903062 -266.693396) (xy 335.547462 -266.693396) (xy 335.547462 -266.737846)
			(xy 335.594452 -266.890246) (xy 335.856072 -266.890246)
		)
		(stroke
			(width 0)
			(type solid)
		)
		(fill yes)
		(layer "In4.Cu")
		(net "M_C_CPU0_SA_DQ<20>")
	)
	(gr_poly
		(pts
			(xy 335.903062 -265.518646) (xy 335.856072 -265.366246) (xy 335.594452 -265.366246) (xy 335.547462 -265.518646)
			(xy 335.547462 -265.562842) (xy 335.903062 -265.562842)
		)
		(stroke
			(width 0)
			(type solid)
		)
		(fill yes)
		(layer "In4.Cu")
		(net "M_C_CPU0_SA_DQ<23>")
	)
	(gr_poly
		(pts
			(xy 335.903062 -265.109706) (xy 335.903062 -265.06551) (xy 335.547462 -265.06551) (xy 335.547462 -265.109706)
			(xy 335.594452 -265.262106) (xy 335.856072 -265.262106)
		)
		(stroke
			(width 0)
			(type solid)
		)
		(fill yes)
		(layer "In4.Cu")
		(net "M_B_CPU0_SA_DQ<26>")
	)
	(gr_poly
		(pts
			(xy 335.903062 -263.891014) (xy 335.856072 -263.738614) (xy 335.594452 -263.738614) (xy 335.547462 -263.891014)
			(xy 335.547462 -263.93521) (xy 335.903062 -263.93521)
		)
		(stroke
			(width 0)
			(type solid)
		)
		(fill yes)
		(layer "In4.Cu")
		(net "M_B_CPU0_SA_DQ<27>")
	)
	(gr_poly
		(pts
			(xy 335.903062 -263.482074) (xy 335.903062 -263.437878) (xy 335.547462 -263.437878) (xy 335.547462 -263.482074)
			(xy 335.594452 -263.634474) (xy 335.856072 -263.634474)
		)
		(stroke
			(width 0)
			(type solid)
		)
		(fill yes)
		(layer "In4.Cu")
		(net "M_B_CPU0_SA_DQS_DP<3>")
	)
	(gr_poly
		(pts
			(xy 335.903062 -262.262874) (xy 335.856072 -262.110474) (xy 335.594452 -262.110474) (xy 335.547462 -262.262874)
			(xy 335.547462 -262.307324) (xy 335.903062 -262.307324)
		)
		(stroke
			(width 0)
			(type solid)
		)
		(fill yes)
		(layer "In4.Cu")
		(net "M_B_CPU0_SA_DQS_DP<8>")
	)
	(gr_poly
		(pts
			(xy 335.903062 -261.854442) (xy 335.903062 -261.809992) (xy 335.547462 -261.809992) (xy 335.547462 -261.854442)
			(xy 335.594452 -262.006842) (xy 335.856072 -262.006842)
		)
		(stroke
			(width 0)
			(type solid)
		)
		(fill yes)
		(layer "In4.Cu")
		(net "M_B_CPU0_SA_DQ<28>")
	)
	(gr_poly
		(pts
			(xy 335.903062 -260.635242) (xy 335.856072 -260.482842) (xy 335.594452 -260.482842) (xy 335.547462 -260.635242)
			(xy 335.547462 -260.679438) (xy 335.903062 -260.679438)
		)
		(stroke
			(width 0)
			(type solid)
		)
		(fill yes)
		(layer "In4.Cu")
		(net "M_B_CPU0_SA_DQ<31>")
	)
	(gr_poly
		(pts
			(xy 335.903062 -258.59867) (xy 335.903062 -258.554474) (xy 335.547462 -258.554474) (xy 335.547462 -258.59867)
			(xy 335.594452 -258.75107) (xy 335.856072 -258.75107)
		)
		(stroke
			(width 0)
			(type solid)
		)
		(fill yes)
		(layer "In4.Cu")
		(net "M_C_CPU0_SA_CS_N<0>")
	)
	(gr_poly
		(pts
			(xy 335.903062 -257.37947) (xy 335.856072 -257.22707) (xy 335.594452 -257.22707) (xy 335.547462 -257.37947)
			(xy 335.547462 -257.42392) (xy 335.903062 -257.42392)
		)
		(stroke
			(width 0)
			(type solid)
		)
		(fill yes)
		(layer "In4.Cu")
		(net "M_C_CPU0_SA_CS_N<3>")
	)
	(gr_poly
		(pts
			(xy 335.903062 -256.971038) (xy 335.903062 -256.926588) (xy 335.547462 -256.926588) (xy 335.547462 -256.971038)
			(xy 335.594452 -257.123438) (xy 335.856072 -257.123438)
		)
		(stroke
			(width 0)
			(type solid)
		)
		(fill yes)
		(layer "In4.Cu")
		(net "M_C_CPU0_SA_CA<0>")
	)
	(gr_poly
		(pts
			(xy 335.903062 -255.751838) (xy 335.856072 -255.599438) (xy 335.594452 -255.599438) (xy 335.547462 -255.751838)
			(xy 335.547462 -255.796288) (xy 335.903062 -255.796288)
		)
		(stroke
			(width 0)
			(type solid)
		)
		(fill yes)
		(layer "In4.Cu")
		(net "M_C_CPU0_SA_CA<3>")
	)
	(gr_poly
		(pts
			(xy 335.903062 -255.343406) (xy 335.903062 -255.298956) (xy 335.547462 -255.298956) (xy 335.547462 -255.343406)
			(xy 335.594452 -255.495806) (xy 335.856072 -255.495806)
		)
		(stroke
			(width 0)
			(type solid)
		)
		(fill yes)
		(layer "In4.Cu")
		(net "M_C_CPU0_SA_CA<4>")
	)
	(gr_poly
		(pts
			(xy 335.903062 -254.124206) (xy 335.856072 -253.971806) (xy 335.594452 -253.971806) (xy 335.547462 -254.124206)
			(xy 335.547462 -254.168402) (xy 335.903062 -254.168402)
		)
		(stroke
			(width 0)
			(type solid)
		)
		(fill yes)
		(layer "In4.Cu")
		(net "M_C_CPU0_SA_PAR")
	)
	(gr_poly
		(pts
			(xy 335.909158 -281.79649) (xy 335.862168 -281.64409) (xy 335.600548 -281.64409) (xy 335.553558 -281.79649)
			(xy 335.553558 -281.840686) (xy 335.909158 -281.840686)
		)
		(stroke
			(width 0)
			(type solid)
		)
		(fill yes)
		(layer "In4.Cu")
		(net "M_C_CPU0_SA_DQS_DP<5>")
	)
	(gr_poly
		(pts
			(xy 335.909158 -281.38755) (xy 335.909158 -281.343354) (xy 335.553558 -281.343354) (xy 335.553558 -281.38755)
			(xy 335.600548 -281.53995) (xy 335.862168 -281.53995)
		)
		(stroke
			(width 0)
			(type solid)
		)
		(fill yes)
		(layer "In4.Cu")
		(net "M_C_CPU0_SA_DQ<4>")
	)
	(gr_poly
		(pts
			(xy 335.976976 -278.610822) (xy 335.868518 -278.493982) (xy 335.830164 -278.471884) (xy 335.652364 -278.779732)
			(xy 335.690718 -278.80183) (xy 335.846166 -278.83739)
		)
		(stroke
			(width 0)
			(type solid)
		)
		(fill yes)
		(layer "In4.Cu")
		(net "M_C_CPU0_SA_DQ<5>")
	)
	(gr_poly
		(pts
			(xy 335.977992 -285.119318) (xy 335.869534 -285.002478) (xy 335.83118 -284.98038) (xy 335.65338 -285.288228)
			(xy 335.691734 -285.310326) (xy 335.847182 -285.345886)
		)
		(stroke
			(width 0)
			(type solid)
		)
		(fill yes)
		(layer "In4.Cu")
		(net "M_C_CPU0_SA_DQS_DP<0>")
	)
	(gr_poly
		(pts
			(xy 335.9785 -275.351748) (xy 335.870042 -275.234908) (xy 335.831688 -275.21281) (xy 335.653888 -275.520658)
			(xy 335.692242 -275.542756) (xy 335.84769 -275.578316)
		)
		(stroke
			(width 0)
			(type solid)
		)
		(fill yes)
		(layer "In4.Cu")
		(net "M_B_CPU0_SA_DQ<8>")
	)
	(gr_poly
		(pts
			(xy 336.254598 -244.940582) (xy 336.207608 -244.788182) (xy 335.945988 -244.788182) (xy 335.898998 -244.940582)
			(xy 335.898998 -244.985032) (xy 336.254598 -244.985032)
		)
		(stroke
			(width 0)
			(type solid)
		)
		(fill yes)
		(layer "In4.Cu")
		(net "M_C_CPU0_SB_PAR")
	)
	(gr_poly
		(pts
			(xy 336.254598 -244.532658) (xy 336.254598 -244.488208) (xy 335.898998 -244.488208) (xy 335.898998 -244.532658)
			(xy 335.945988 -244.685058) (xy 336.207608 -244.685058)
		)
		(stroke
			(width 0)
			(type solid)
		)
		(fill yes)
		(layer "In4.Cu")
		(net "M_C_CPU0_SB_CS_N<2>")
	)
	(gr_poly
		(pts
			(xy 336.254598 -240.057178) (xy 336.207608 -239.904778) (xy 335.945988 -239.904778) (xy 335.898998 -240.057178)
			(xy 335.898998 -240.101628) (xy 336.254598 -240.101628)
		)
		(stroke
			(width 0)
			(type solid)
		)
		(fill yes)
		(layer "In4.Cu")
		(net "M_C_CPU0_SB_DQS_DN<9>")
	)
	(gr_poly
		(pts
			(xy 336.254598 -239.649254) (xy 336.254598 -239.604804) (xy 335.898998 -239.604804) (xy 335.898998 -239.649254)
			(xy 335.945988 -239.801654) (xy 336.207608 -239.801654)
		)
		(stroke
			(width 0)
			(type solid)
		)
		(fill yes)
		(layer "In4.Cu")
		(net "M_C_CPU0_SB_DQS_DN<4>")
	)
	(gr_poly
		(pts
			(xy 336.254598 -235.174282) (xy 336.207608 -235.021882) (xy 335.945988 -235.021882) (xy 335.898998 -235.174282)
			(xy 335.898998 -235.218478) (xy 336.254598 -235.218478)
		)
		(stroke
			(width 0)
			(type solid)
		)
		(fill yes)
		(layer "In4.Cu")
		(net "M_B_CPU0_SB_DQS_DN<0>")
	)
	(gr_poly
		(pts
			(xy 336.254598 -234.76585) (xy 336.254598 -234.721654) (xy 335.898998 -234.721654) (xy 335.898998 -234.76585)
			(xy 335.945988 -234.91825) (xy 336.207608 -234.91825)
		)
		(stroke
			(width 0)
			(type solid)
		)
		(fill yes)
		(layer "In4.Cu")
		(net "M_B_CPU0_SB_DQS_DN<5>")
	)
	(gr_poly
		(pts
			(xy 336.254598 -230.290878) (xy 336.207608 -230.138478) (xy 335.945988 -230.138478) (xy 335.898998 -230.290878)
			(xy 335.898998 -230.335074) (xy 336.254598 -230.335074)
		)
		(stroke
			(width 0)
			(type solid)
		)
		(fill yes)
		(layer "In4.Cu")
		(net "M_C_CPU0_SB_DQS_DN<2>")
	)
	(gr_poly
		(pts
			(xy 336.254598 -229.882446) (xy 336.254598 -229.83825) (xy 335.898998 -229.83825) (xy 335.898998 -229.882446)
			(xy 335.945988 -230.034846) (xy 336.207608 -230.034846)
		)
		(stroke
			(width 0)
			(type solid)
		)
		(fill yes)
		(layer "In4.Cu")
		(net "M_C_CPU0_SB_DQS_DN<7>")
	)
	(gr_poly
		(pts
			(xy 336.257138 -246.568722) (xy 336.210148 -246.416322) (xy 335.948528 -246.416322) (xy 335.901538 -246.568722)
			(xy 335.901538 -246.613172) (xy 336.257138 -246.613172)
		)
		(stroke
			(width 0)
			(type solid)
		)
		(fill yes)
		(layer "In4.Cu")
		(net "M_C_CPU0_SB_CA<3>")
	)
	(gr_poly
		(pts
			(xy 336.257138 -246.16029) (xy 336.257138 -246.11584) (xy 335.901538 -246.11584) (xy 335.901538 -246.16029)
			(xy 335.948528 -246.31269) (xy 336.210148 -246.31269)
		)
		(stroke
			(width 0)
			(type solid)
		)
		(fill yes)
		(layer "In4.Cu")
		(net "M_C_CPU0_SB_CA<4>")
	)
	(gr_poly
		(pts
			(xy 336.257138 -243.313458) (xy 336.210148 -243.161058) (xy 335.948528 -243.161058) (xy 335.901538 -243.313458)
			(xy 335.901538 -243.357654) (xy 336.257138 -243.357654)
		)
		(stroke
			(width 0)
			(type solid)
		)
		(fill yes)
		(layer "In4.Cu")
		(net "M_C_CPU0_SB_CS_N<1>")
	)
	(gr_poly
		(pts
			(xy 336.257138 -241.685318) (xy 336.210148 -241.532918) (xy 335.948528 -241.532918) (xy 335.901538 -241.685318)
			(xy 335.901538 -241.729768) (xy 336.257138 -241.729768)
		)
		(stroke
			(width 0)
			(type solid)
		)
		(fill yes)
		(layer "In4.Cu")
		(net "M_C_CPU0_SB_CB<6>")
	)
	(gr_poly
		(pts
			(xy 336.257138 -241.276886) (xy 336.257138 -241.232436) (xy 335.901538 -241.232436) (xy 335.901538 -241.276886)
			(xy 335.948528 -241.429286) (xy 336.210148 -241.429286)
		)
		(stroke
			(width 0)
			(type solid)
		)
		(fill yes)
		(layer "In4.Cu")
		(net "M_C_CPU0_SB_CB<5>")
	)
	(gr_poly
		(pts
			(xy 336.257138 -238.430054) (xy 336.210148 -238.277654) (xy 335.948528 -238.277654) (xy 335.901538 -238.430054)
			(xy 335.901538 -238.47425) (xy 336.257138 -238.47425)
		)
		(stroke
			(width 0)
			(type solid)
		)
		(fill yes)
		(layer "In4.Cu")
		(net "M_C_CPU0_SB_CB<2>")
	)
	(gr_poly
		(pts
			(xy 336.257138 -233.54665) (xy 336.210148 -233.39425) (xy 335.948528 -233.39425) (xy 335.901538 -233.54665)
			(xy 335.901538 -233.590846) (xy 336.257138 -233.590846)
		)
		(stroke
			(width 0)
			(type solid)
		)
		(fill yes)
		(layer "In4.Cu")
		(net "M_B_CPU0_SB_DQ<6>")
	)
	(gr_poly
		(pts
			(xy 336.257138 -228.254814) (xy 336.257138 -228.210364) (xy 335.901538 -228.210364) (xy 335.901538 -228.254814)
			(xy 335.948528 -228.407214) (xy 336.210148 -228.407214)
		)
		(stroke
			(width 0)
			(type solid)
		)
		(fill yes)
		(layer "In4.Cu")
		(net "M_C_CPU0_SB_DQ<21>")
	)
	(gr_poly
		(pts
			(xy 336.262726 -283.600398) (xy 336.224372 -283.5783) (xy 336.068924 -283.54274) (xy 335.938114 -283.769308)
			(xy 336.046572 -283.886148) (xy 336.084926 -283.908246)
		)
		(stroke
			(width 0)
			(type solid)
		)
		(fill yes)
		(layer "In4.Cu")
		(net "M_C_CPU0_SA_DQS_DN<0>")
	)
	(gr_poly
		(pts
			(xy 336.26298 -238.021114) (xy 336.26298 -237.976664) (xy 335.90738 -237.976664) (xy 335.90738 -238.021114)
			(xy 335.95437 -238.173514) (xy 336.21599 -238.173514)
		)
		(stroke
			(width 0)
			(type solid)
		)
		(fill yes)
		(layer "In4.Cu")
		(net "M_C_CPU0_SB_CB<1>")
	)
	(gr_poly
		(pts
			(xy 336.26298 -233.13771) (xy 336.26298 -233.093514) (xy 335.90738 -233.093514) (xy 335.90738 -233.13771)
			(xy 335.95437 -233.29011) (xy 336.21599 -233.29011)
		)
		(stroke
			(width 0)
			(type solid)
		)
		(fill yes)
		(layer "In4.Cu")
		(net "M_B_CPU0_SB_DQ<5>")
	)
	(gr_poly
		(pts
			(xy 336.26298 -231.919018) (xy 336.21599 -231.766618) (xy 335.95437 -231.766618) (xy 335.90738 -231.919018)
			(xy 335.90738 -231.963214) (xy 336.26298 -231.963214)
		)
		(stroke
			(width 0)
			(type solid)
		)
		(fill yes)
		(layer "In4.Cu")
		(net "M_C_CPU0_SB_DQ<18>")
	)
	(gr_poly
		(pts
			(xy 336.26298 -231.510078) (xy 336.26298 -231.465628) (xy 335.90738 -231.465628) (xy 335.90738 -231.510078)
			(xy 335.95437 -231.662478) (xy 336.21599 -231.662478)
		)
		(stroke
			(width 0)
			(type solid)
		)
		(fill yes)
		(layer "In4.Cu")
		(net "M_C_CPU0_SB_DQ<17>")
	)
	(gr_poly
		(pts
			(xy 336.26298 -228.663246) (xy 336.21599 -228.510846) (xy 335.95437 -228.510846) (xy 335.90738 -228.663246)
			(xy 335.90738 -228.707696) (xy 336.26298 -228.707696)
		)
		(stroke
			(width 0)
			(type solid)
		)
		(fill yes)
		(layer "In4.Cu")
		(net "M_C_CPU0_SB_DQ<22>")
	)
	(gr_poly
		(pts
			(xy 336.263234 -236.801914) (xy 336.216244 -236.649514) (xy 335.954624 -236.649514) (xy 335.907634 -236.801914)
			(xy 335.907634 -236.846364) (xy 336.263234 -236.846364)
		)
		(stroke
			(width 0)
			(type solid)
		)
		(fill yes)
		(layer "In4.Cu")
		(net "M_B_CPU0_SB_DQ<0>")
	)
	(gr_poly
		(pts
			(xy 336.263234 -236.393482) (xy 336.263234 -236.349286) (xy 335.907634 -236.349286) (xy 335.907634 -236.393482)
			(xy 335.954624 -236.545882) (xy 336.216244 -236.545882)
		)
		(stroke
			(width 0)
			(type solid)
		)
		(fill yes)
		(layer "In4.Cu")
		(net "M_B_CPU0_SB_DQ<1>")
	)
	(gr_poly
		(pts
			(xy 336.267044 -286.84855) (xy 336.22869 -286.826452) (xy 336.073242 -286.790892) (xy 335.942432 -287.01746)
			(xy 336.05089 -287.1343) (xy 336.089244 -287.156398)
		)
		(stroke
			(width 0)
			(type solid)
		)
		(fill yes)
		(layer "In4.Cu")
		(net "M_C_CPU0_SA_DQ<2>")
	)
	(gr_poly
		(pts
			(xy 336.267044 -285.220664) (xy 336.22869 -285.198566) (xy 336.073242 -285.163006) (xy 335.942432 -285.389574)
			(xy 336.05089 -285.506414) (xy 336.089244 -285.528512)
		)
		(stroke
			(width 0)
			(type solid)
		)
		(fill yes)
		(layer "In4.Cu")
		(net "M_C_CPU0_SA_DQ<3>")
	)
	(gr_poly
		(pts
			(xy 336.267044 -278.709628) (xy 336.22869 -278.68753) (xy 336.073242 -278.65197) (xy 335.942432 -278.878538)
			(xy 336.05089 -278.995378) (xy 336.089244 -279.017476)
		)
		(stroke
			(width 0)
			(type solid)
		)
		(fill yes)
		(layer "In4.Cu")
		(net "M_C_CPU0_SA_DQ<6>")
	)
	(gr_poly
		(pts
			(xy 336.26806 -277.07971) (xy 336.229706 -277.057612) (xy 336.074258 -277.022052) (xy 335.943448 -277.24862)
			(xy 336.051906 -277.36546) (xy 336.09026 -277.387558)
		)
		(stroke
			(width 0)
			(type solid)
		)
		(fill yes)
		(layer "In4.Cu")
		(net "M_C_CPU0_SA_DQ<7>")
	)
	(gr_poly
		(pts
			(xy 336.337402 -280.6192) (xy 336.44586 -280.50236) (xy 336.31505 -280.275792) (xy 336.159602 -280.311352)
			(xy 336.121248 -280.33345) (xy 336.299048 -280.641298)
		)
		(stroke
			(width 0)
			(type solid)
		)
		(fill yes)
		(layer "In4.Cu")
		(net "M_C_CPU0_SA_DQ<4>")
	)
	(gr_poly
		(pts
			(xy 336.372962 -274.47113) (xy 336.325972 -274.31873) (xy 336.064352 -274.31873) (xy 336.017362 -274.47113)
			(xy 336.017362 -274.51558) (xy 336.372962 -274.51558)
		)
		(stroke
			(width 0)
			(type solid)
		)
		(fill yes)
		(layer "In4.Cu")
		(net "M_B_CPU0_SA_DQ<10>")
	)
	(gr_poly
		(pts
			(xy 336.372962 -274.062698) (xy 336.372962 -274.018248) (xy 336.017362 -274.018248) (xy 336.017362 -274.062698)
			(xy 336.064352 -274.215098) (xy 336.325972 -274.215098)
		)
		(stroke
			(width 0)
			(type solid)
		)
		(fill yes)
		(layer "In4.Cu")
		(net "M_B_CPU0_SA_DQ<9>")
	)
	(gr_poly
		(pts
			(xy 336.372962 -271.215866) (xy 336.325972 -271.063466) (xy 336.064352 -271.063466) (xy 336.017362 -271.215866)
			(xy 336.017362 -271.260062) (xy 336.372962 -271.260062)
		)
		(stroke
			(width 0)
			(type solid)
		)
		(fill yes)
		(layer "In4.Cu")
		(net "M_B_CPU0_SA_DQ<14>")
	)
	(gr_poly
		(pts
			(xy 336.372962 -269.587726) (xy 336.325972 -269.435326) (xy 336.064352 -269.435326) (xy 336.017362 -269.587726)
			(xy 336.017362 -269.632176) (xy 336.372962 -269.632176)
		)
		(stroke
			(width 0)
			(type solid)
		)
		(fill yes)
		(layer "In4.Cu")
		(net "M_C_CPU0_SA_DQ<18>")
	)
	(gr_poly
		(pts
			(xy 336.372962 -267.960094) (xy 336.325972 -267.807694) (xy 336.064352 -267.807694) (xy 336.017362 -267.960094)
			(xy 336.017362 -268.004544) (xy 336.372962 -268.004544)
		)
		(stroke
			(width 0)
			(type solid)
		)
		(fill yes)
		(layer "In4.Cu")
		(net "M_C_CPU0_SA_DQS_DN<2>")
	)
	(gr_poly
		(pts
			(xy 336.372962 -267.551662) (xy 336.372962 -267.507212) (xy 336.017362 -267.507212) (xy 336.017362 -267.551662)
			(xy 336.064352 -267.704062) (xy 336.325972 -267.704062)
		)
		(stroke
			(width 0)
			(type solid)
		)
		(fill yes)
		(layer "In4.Cu")
		(net "M_C_CPU0_SA_DQS_DN<7>")
	)
	(gr_poly
		(pts
			(xy 336.372962 -266.332462) (xy 336.325972 -266.180062) (xy 336.064352 -266.180062) (xy 336.017362 -266.332462)
			(xy 336.017362 -266.376658) (xy 336.372962 -266.376658)
		)
		(stroke
			(width 0)
			(type solid)
		)
		(fill yes)
		(layer "In4.Cu")
		(net "M_C_CPU0_SA_DQ<22>")
	)
	(gr_poly
		(pts
			(xy 336.372962 -265.92403) (xy 336.372962 -265.87958) (xy 336.017362 -265.87958) (xy 336.017362 -265.92403)
			(xy 336.064352 -266.07643) (xy 336.325972 -266.07643)
		)
		(stroke
			(width 0)
			(type solid)
		)
		(fill yes)
		(layer "In4.Cu")
		(net "M_C_CPU0_SA_DQ<21>")
	)
	(gr_poly
		(pts
			(xy 336.372962 -264.70483) (xy 336.325972 -264.55243) (xy 336.064352 -264.55243) (xy 336.017362 -264.70483)
			(xy 336.017362 -264.749026) (xy 336.372962 -264.749026)
		)
		(stroke
			(width 0)
			(type solid)
		)
		(fill yes)
		(layer "In4.Cu")
		(net "M_B_CPU0_SA_DQ<24>")
	)
	(gr_poly
		(pts
			(xy 336.372962 -264.29589) (xy 336.372962 -264.251694) (xy 336.017362 -264.251694) (xy 336.017362 -264.29589)
			(xy 336.064352 -264.44829) (xy 336.325972 -264.44829)
		)
		(stroke
			(width 0)
			(type solid)
		)
		(fill yes)
		(layer "In4.Cu")
		(net "M_B_CPU0_SA_DQ<25>")
	)
	(gr_poly
		(pts
			(xy 336.372962 -263.07669) (xy 336.325972 -262.92429) (xy 336.064352 -262.92429) (xy 336.017362 -263.07669)
			(xy 336.017362 -263.12114) (xy 336.372962 -263.12114)
		)
		(stroke
			(width 0)
			(type solid)
		)
		(fill yes)
		(layer "In4.Cu")
		(net "M_B_CPU0_SA_DQS_DN<3>")
	)
	(gr_poly
		(pts
			(xy 336.372962 -262.668258) (xy 336.372962 -262.623808) (xy 336.017362 -262.623808) (xy 336.017362 -262.668258)
			(xy 336.064352 -262.820658) (xy 336.325972 -262.820658)
		)
		(stroke
			(width 0)
			(type solid)
		)
		(fill yes)
		(layer "In4.Cu")
		(net "M_B_CPU0_SA_DQS_DN<8>")
	)
	(gr_poly
		(pts
			(xy 336.372962 -261.449058) (xy 336.325972 -261.296658) (xy 336.064352 -261.296658) (xy 336.017362 -261.449058)
			(xy 336.017362 -261.493508) (xy 336.372962 -261.493508)
		)
		(stroke
			(width 0)
			(type solid)
		)
		(fill yes)
		(layer "In4.Cu")
		(net "M_B_CPU0_SA_DQ<30>")
	)
	(gr_poly
		(pts
			(xy 336.372962 -261.040626) (xy 336.372962 -260.996176) (xy 336.017362 -260.996176) (xy 336.017362 -261.040626)
			(xy 336.064352 -261.193026) (xy 336.325972 -261.193026)
		)
		(stroke
			(width 0)
			(type solid)
		)
		(fill yes)
		(layer "In4.Cu")
		(net "M_B_CPU0_SA_DQ<29>")
	)
	(gr_poly
		(pts
			(xy 336.372962 -258.193286) (xy 336.325972 -258.040886) (xy 336.064352 -258.040886) (xy 336.017362 -258.193286)
			(xy 336.017362 -258.237736) (xy 336.372962 -258.237736)
		)
		(stroke
			(width 0)
			(type solid)
		)
		(fill yes)
		(layer "In4.Cu")
		(net "M_C_CPU0_SA_CS_N<2>")
	)
	(gr_poly
		(pts
			(xy 336.372962 -257.784854) (xy 336.372962 -257.740404) (xy 336.017362 -257.740404) (xy 336.017362 -257.784854)
			(xy 336.064352 -257.937254) (xy 336.325972 -257.937254)
		)
		(stroke
			(width 0)
			(type solid)
		)
		(fill yes)
		(layer "In4.Cu")
		(net "M_C_CPU0_SA_CS_N<1>")
	)
	(gr_poly
		(pts
			(xy 336.372962 -256.565654) (xy 336.325972 -256.413254) (xy 336.064352 -256.413254) (xy 336.017362 -256.565654)
			(xy 336.017362 -256.610104) (xy 336.372962 -256.610104)
		)
		(stroke
			(width 0)
			(type solid)
		)
		(fill yes)
		(layer "In4.Cu")
		(net "M_C_CPU0_SA_CA<1>")
	)
	(gr_poly
		(pts
			(xy 336.372962 -256.157222) (xy 336.372962 -256.112772) (xy 336.017362 -256.112772) (xy 336.017362 -256.157222)
			(xy 336.064352 -256.309622) (xy 336.325972 -256.309622)
		)
		(stroke
			(width 0)
			(type solid)
		)
		(fill yes)
		(layer "In4.Cu")
		(net "M_C_CPU0_SA_CA<2>")
	)
	(gr_poly
		(pts
			(xy 336.372962 -254.938022) (xy 336.325972 -254.785622) (xy 336.064352 -254.785622) (xy 336.017362 -254.938022)
			(xy 336.017362 -254.982218) (xy 336.372962 -254.982218)
		)
		(stroke
			(width 0)
			(type solid)
		)
		(fill yes)
		(layer "In4.Cu")
		(net "M_C_CPU0_SA_CA<5>")
	)
	(gr_poly
		(pts
			(xy 336.372962 -254.529082) (xy 336.372962 -254.484886) (xy 336.017362 -254.484886) (xy 336.017362 -254.529082)
			(xy 336.064352 -254.681482) (xy 336.325972 -254.681482)
		)
		(stroke
			(width 0)
			(type solid)
		)
		(fill yes)
		(layer "In4.Cu")
		(net "M_C_CPU0_SA_CA<6>")
	)
	(gr_poly
		(pts
			(xy 336.375248 -270.806926) (xy 336.375248 -270.76273) (xy 336.019648 -270.76273) (xy 336.019648 -270.806926)
			(xy 336.066638 -270.959326) (xy 336.328258 -270.959326)
		)
		(stroke
			(width 0)
			(type solid)
		)
		(fill yes)
		(layer "In4.Cu")
		(net "M_B_CPU0_SA_DQ<13>")
	)
	(gr_poly
		(pts
			(xy 336.375248 -269.179294) (xy 336.375248 -269.134844) (xy 336.019648 -269.134844) (xy 336.019648 -269.179294)
			(xy 336.066638 -269.331694) (xy 336.328258 -269.331694)
		)
		(stroke
			(width 0)
			(type solid)
		)
		(fill yes)
		(layer "In4.Cu")
		(net "M_C_CPU0_SA_DQ<17>")
	)
	(gr_poly
		(pts
			(xy 336.379058 -282.201874) (xy 336.379058 -282.157424) (xy 336.023458 -282.157424) (xy 336.023458 -282.201874)
			(xy 336.070448 -282.354274) (xy 336.332068 -282.354274)
		)
		(stroke
			(width 0)
			(type solid)
		)
		(fill yes)
		(layer "In4.Cu")
		(net "M_C_CPU0_SA_DQS_DN<5>")
	)
	(gr_poly
		(pts
			(xy 336.379058 -272.843498) (xy 336.332068 -272.691098) (xy 336.070448 -272.691098) (xy 336.023458 -272.843498)
			(xy 336.023458 -272.887694) (xy 336.379058 -272.887694)
		)
		(stroke
			(width 0)
			(type solid)
		)
		(fill yes)
		(layer "In4.Cu")
		(net "M_B_CPU0_SA_DQS_DN<1>")
	)
	(gr_poly
		(pts
			(xy 336.379058 -272.435066) (xy 336.379058 -272.39087) (xy 336.023458 -272.39087) (xy 336.023458 -272.435066)
			(xy 336.070448 -272.587466) (xy 336.332068 -272.587466)
		)
		(stroke
			(width 0)
			(type solid)
		)
		(fill yes)
		(layer "In4.Cu")
		(net "M_B_CPU0_SA_DQS_DN<6>")
	)
	(gr_poly
		(pts
			(xy 336.44586 -285.937198) (xy 336.337402 -285.820358) (xy 336.299048 -285.79826) (xy 336.121248 -286.106108)
			(xy 336.159602 -286.128206) (xy 336.31505 -286.163766)
		)
		(stroke
			(width 0)
			(type solid)
		)
		(fill yes)
		(layer "In4.Cu")
		(net "M_C_CPU0_SA_DQ<1>")
	)
	(gr_poly
		(pts
			(xy 336.446622 -277.797006) (xy 336.338164 -277.680166) (xy 336.29981 -277.658068) (xy 336.12201 -277.965916)
			(xy 336.160364 -277.988014) (xy 336.315812 -278.023574)
		)
		(stroke
			(width 0)
			(type solid)
		)
		(fill yes)
		(layer "In4.Cu")
		(net "M_C_CPU0_SA_DQ<5>")
	)
	(gr_poly
		(pts
			(xy 336.447892 -287.56102) (xy 336.339434 -287.44418) (xy 336.30108 -287.422082) (xy 336.12328 -287.72993)
			(xy 336.161634 -287.752028) (xy 336.317082 -287.787588)
		)
		(stroke
			(width 0)
			(type solid)
		)
		(fill yes)
		(layer "In4.Cu")
		(net "M_C_CPU0_SA_DQ<0>")
	)
	(gr_poly
		(pts
			(xy 336.447892 -281.049984) (xy 336.339434 -280.933144) (xy 336.30108 -280.911046) (xy 336.12328 -281.218894)
			(xy 336.161634 -281.240992) (xy 336.317082 -281.276552)
		)
		(stroke
			(width 0)
			(type solid)
		)
		(fill yes)
		(layer "In4.Cu")
		(net "M_C_CPU0_SA_DQ<4>")
	)
	(gr_poly
		(pts
			(xy 336.447892 -279.422098) (xy 336.339434 -279.305258) (xy 336.30108 -279.28316) (xy 336.12328 -279.591008)
			(xy 336.161634 -279.613106) (xy 336.317082 -279.648666)
		)
		(stroke
			(width 0)
			(type solid)
		)
		(fill yes)
		(layer "In4.Cu")
		(net "M_C_CPU0_SA_DQ<4>")
	)
	(gr_poly
		(pts
			(xy 336.454242 -284.295342) (xy 336.345784 -284.178502) (xy 336.30743 -284.156404) (xy 336.12963 -284.464252)
			(xy 336.167984 -284.48635) (xy 336.323432 -284.52191)
		)
		(stroke
			(width 0)
			(type solid)
		)
		(fill yes)
		(layer "In4.Cu")
		(net "M_C_CPU0_SA_DQS_DP<0>")
	)
	(gr_poly
		(pts
			(xy 336.700622 -280.430986) (xy 336.738976 -280.408888) (xy 336.561176 -280.10104) (xy 336.522822 -280.123138)
			(xy 336.414364 -280.239978) (xy 336.545174 -280.466546)
		)
		(stroke
			(width 0)
			(type solid)
		)
		(fill yes)
		(layer "In4.Cu")
		(net "M_C_CPU0_SA_DQS_DP<5>")
	)
	(gr_poly
		(pts
			(xy 336.727038 -245.346474) (xy 336.727038 -245.302024) (xy 336.371438 -245.302024) (xy 336.371438 -245.346474)
			(xy 336.418428 -245.498874) (xy 336.680048 -245.498874)
		)
		(stroke
			(width 0)
			(type solid)
		)
		(fill yes)
		(layer "In4.Cu")
		(net "M_C_CPU0_SB_CA<6>")
	)
	(gr_poly
		(pts
			(xy 336.729832 -229.068122) (xy 336.729832 -229.023926) (xy 336.374232 -229.023926) (xy 336.374232 -229.068122)
			(xy 336.421222 -229.220522) (xy 336.682842 -229.220522)
		)
		(stroke
			(width 0)
			(type solid)
		)
		(fill yes)
		(layer "In4.Cu")
		(net "M_C_CPU0_SB_DQ<20>")
	)
	(gr_poly
		(pts
			(xy 336.73034 -240.871502) (xy 336.68335 -240.719102) (xy 336.42173 -240.719102) (xy 336.37474 -240.871502)
			(xy 336.37474 -240.915952) (xy 336.73034 -240.915952)
		)
		(stroke
			(width 0)
			(type solid)
		)
		(fill yes)
		(layer "In4.Cu")
		(net "M_C_CPU0_SB_CB<7>")
	)
	(gr_poly
		(pts
			(xy 336.73034 -240.46307) (xy 336.73034 -240.41862) (xy 336.37474 -240.41862) (xy 336.37474 -240.46307)
			(xy 336.42173 -240.61547) (xy 336.68335 -240.61547)
		)
		(stroke
			(width 0)
			(type solid)
		)
		(fill yes)
		(layer "In4.Cu")
		(net "M_C_CPU0_SB_DQS_DP<9>")
	)
	(gr_poly
		(pts
			(xy 336.73034 -238.83493) (xy 336.73034 -238.790734) (xy 336.37474 -238.790734) (xy 336.37474 -238.83493)
			(xy 336.42173 -238.98733) (xy 336.68335 -238.98733)
		)
		(stroke
			(width 0)
			(type solid)
		)
		(fill yes)
		(layer "In4.Cu")
		(net "M_C_CPU0_SB_CB<0>")
	)
	(gr_poly
		(pts
			(xy 336.73034 -237.616238) (xy 336.68335 -237.463838) (xy 336.42173 -237.463838) (xy 336.37474 -237.616238)
			(xy 336.37474 -237.660434) (xy 336.73034 -237.660434)
		)
		(stroke
			(width 0)
			(type solid)
		)
		(fill yes)
		(layer "In4.Cu")
		(net "M_C_CPU0_SB_CB<3>")
	)
	(gr_poly
		(pts
			(xy 336.73034 -235.988606) (xy 336.68335 -235.836206) (xy 336.42173 -235.836206) (xy 336.37474 -235.988606)
			(xy 336.37474 -236.032802) (xy 336.73034 -236.032802)
		)
		(stroke
			(width 0)
			(type solid)
		)
		(fill yes)
		(layer "In4.Cu")
		(net "M_B_CPU0_SB_DQ<3>")
	)
	(gr_poly
		(pts
			(xy 336.73034 -233.951526) (xy 336.73034 -233.90733) (xy 336.37474 -233.90733) (xy 336.37474 -233.951526)
			(xy 336.42173 -234.103926) (xy 336.68335 -234.103926)
		)
		(stroke
			(width 0)
			(type solid)
		)
		(fill yes)
		(layer "In4.Cu")
		(net "M_B_CPU0_SB_DQ<4>")
	)
	(gr_poly
		(pts
			(xy 336.73034 -232.732834) (xy 336.68335 -232.580434) (xy 336.42173 -232.580434) (xy 336.37474 -232.732834)
			(xy 336.37474 -232.77703) (xy 336.73034 -232.77703)
		)
		(stroke
			(width 0)
			(type solid)
		)
		(fill yes)
		(layer "In4.Cu")
		(net "M_B_CPU0_SB_DQ<7>")
	)
	(gr_poly
		(pts
			(xy 336.73034 -232.323894) (xy 336.73034 -232.279698) (xy 336.37474 -232.279698) (xy 336.37474 -232.323894)
			(xy 336.42173 -232.476294) (xy 336.68335 -232.476294)
		)
		(stroke
			(width 0)
			(type solid)
		)
		(fill yes)
		(layer "In4.Cu")
		(net "M_C_CPU0_SB_DQ<16>")
	)
	(gr_poly
		(pts
			(xy 336.73034 -231.105202) (xy 336.68335 -230.952802) (xy 336.42173 -230.952802) (xy 336.37474 -231.105202)
			(xy 336.37474 -231.149398) (xy 336.73034 -231.149398)
		)
		(stroke
			(width 0)
			(type solid)
		)
		(fill yes)
		(layer "In4.Cu")
		(net "M_C_CPU0_SB_DQ<19>")
	)
	(gr_poly
		(pts
			(xy 336.73034 -230.696262) (xy 336.73034 -230.651812) (xy 336.37474 -230.651812) (xy 336.37474 -230.696262)
			(xy 336.42173 -230.848662) (xy 336.68335 -230.848662)
		)
		(stroke
			(width 0)
			(type solid)
		)
		(fill yes)
		(layer "In4.Cu")
		(net "M_C_CPU0_SB_DQS_DP<2>")
	)
	(gr_poly
		(pts
			(xy 336.73034 -229.477062) (xy 336.68335 -229.324662) (xy 336.42173 -229.324662) (xy 336.37474 -229.477062)
			(xy 336.37474 -229.521512) (xy 336.73034 -229.521512)
		)
		(stroke
			(width 0)
			(type solid)
		)
		(fill yes)
		(layer "In4.Cu")
		(net "M_C_CPU0_SB_DQS_DP<7>")
	)
	(gr_poly
		(pts
			(xy 336.732626 -284.41396) (xy 336.694272 -284.391862) (xy 336.538824 -284.356302) (xy 336.408014 -284.58287)
			(xy 336.516472 -284.69971) (xy 336.554826 -284.721808)
		)
		(stroke
			(width 0)
			(type solid)
		)
		(fill yes)
		(layer "In4.Cu")
		(net "M_C_CPU0_SA_DQ<3>")
	)
	(gr_poly
		(pts
			(xy 336.732626 -281.158696) (xy 336.694272 -281.136598) (xy 336.538824 -281.101038) (xy 336.408014 -281.327606)
			(xy 336.516472 -281.444446) (xy 336.554826 -281.466544)
		)
		(stroke
			(width 0)
			(type solid)
		)
		(fill yes)
		(layer "In4.Cu")
		(net "M_C_CPU0_SA_DQS_DP<5>")
	)
	(gr_poly
		(pts
			(xy 336.733134 -237.207298) (xy 336.733134 -237.163102) (xy 336.377534 -237.163102) (xy 336.377534 -237.207298)
			(xy 336.424524 -237.359698) (xy 336.686144 -237.359698)
		)
		(stroke
			(width 0)
			(type solid)
		)
		(fill yes)
		(layer "In4.Cu")
		(net "M_B_CPU0_SB_DQ<2>")
	)
	(gr_poly
		(pts
			(xy 336.736944 -279.523444) (xy 336.69859 -279.501346) (xy 336.543142 -279.465786) (xy 336.412332 -279.692354)
			(xy 336.52079 -279.809194) (xy 336.559144 -279.831292)
		)
		(stroke
			(width 0)
			(type solid)
		)
		(fill yes)
		(layer "In4.Cu")
		(net "M_C_CPU0_SA_DQS_DP<5>")
	)
	(gr_poly
		(pts
			(xy 336.736944 -276.267926) (xy 336.69859 -276.245828) (xy 336.543142 -276.210268) (xy 336.412332 -276.436836)
			(xy 336.52079 -276.553676) (xy 336.559144 -276.575774)
		)
		(stroke
			(width 0)
			(type solid)
		)
		(fill yes)
		(layer "In4.Cu")
		(net "M_C_CPU0_SA_DQ<7>")
	)
	(gr_poly
		(pts
			(xy 336.73796 -286.032702) (xy 336.699606 -286.010604) (xy 336.544158 -285.975044) (xy 336.413348 -286.201612)
			(xy 336.521806 -286.318452) (xy 336.56016 -286.34055)
		)
		(stroke
			(width 0)
			(type solid)
		)
		(fill yes)
		(layer "In4.Cu")
		(net "M_C_CPU0_SA_DQ<2>")
	)
	(gr_poly
		(pts
			(xy 336.73796 -282.777184) (xy 336.699606 -282.755086) (xy 336.544158 -282.719526) (xy 336.413348 -282.946094)
			(xy 336.521806 -283.062934) (xy 336.56016 -283.085032)
		)
		(stroke
			(width 0)
			(type solid)
		)
		(fill yes)
		(layer "In4.Cu")
		(net "M_C_CPU0_SA_DQS_DN<0>")
	)
	(gr_poly
		(pts
			(xy 336.73796 -277.89378) (xy 336.699606 -277.871682) (xy 336.544158 -277.836122) (xy 336.413348 -278.06269)
			(xy 336.521806 -278.17953) (xy 336.56016 -278.201628)
		)
		(stroke
			(width 0)
			(type solid)
		)
		(fill yes)
		(layer "In4.Cu")
		(net "M_C_CPU0_SA_DQ<6>")
	)
	(gr_poly
		(pts
			(xy 336.741516 -246.974106) (xy 336.741516 -246.92991) (xy 336.385916 -246.92991) (xy 336.385916 -246.974106)
			(xy 336.432906 -247.126506) (xy 336.694526 -247.126506)
		)
		(stroke
			(width 0)
			(type solid)
		)
		(fill yes)
		(layer "In4.Cu")
		(net "M_C_CPU0_SB_CA<2>")
	)
	(gr_poly
		(pts
			(xy 336.741516 -245.754906) (xy 336.694526 -245.602506) (xy 336.432906 -245.602506) (xy 336.385916 -245.754906)
			(xy 336.385916 -245.799102) (xy 336.741516 -245.799102)
		)
		(stroke
			(width 0)
			(type solid)
		)
		(fill yes)
		(layer "In4.Cu")
		(net "M_C_CPU0_SB_CA<5>")
	)
	(gr_poly
		(pts
			(xy 336.741516 -244.126766) (xy 336.694526 -243.974366) (xy 336.432906 -243.974366) (xy 336.385916 -244.126766)
			(xy 336.385916 -244.171216) (xy 336.741516 -244.171216)
		)
		(stroke
			(width 0)
			(type solid)
		)
		(fill yes)
		(layer "In4.Cu")
		(net "M_C_CPU0_SB_CS_N<0>")
	)
	(gr_poly
		(pts
			(xy 336.741516 -243.718842) (xy 336.741516 -243.674392) (xy 336.385916 -243.674392) (xy 336.385916 -243.718842)
			(xy 336.432906 -243.871242) (xy 336.694526 -243.871242)
		)
		(stroke
			(width 0)
			(type solid)
		)
		(fill yes)
		(layer "In4.Cu")
		(net "M_C_CPU0_SB_CS_N<3>")
	)
	(gr_poly
		(pts
			(xy 336.741516 -242.090702) (xy 336.741516 -242.046506) (xy 336.385916 -242.046506) (xy 336.385916 -242.090702)
			(xy 336.432906 -242.243102) (xy 336.694526 -242.243102)
		)
		(stroke
			(width 0)
			(type solid)
		)
		(fill yes)
		(layer "In4.Cu")
		(net "M_C_CPU0_SB_CB<4>")
	)
	(gr_poly
		(pts
			(xy 336.741516 -239.243362) (xy 336.694526 -239.090962) (xy 336.432906 -239.090962) (xy 336.385916 -239.243362)
			(xy 336.385916 -239.287812) (xy 336.741516 -239.287812)
		)
		(stroke
			(width 0)
			(type solid)
		)
		(fill yes)
		(layer "In4.Cu")
		(net "M_C_CPU0_SB_DQS_DP<4>")
	)
	(gr_poly
		(pts
			(xy 336.741516 -235.579666) (xy 336.741516 -235.53547) (xy 336.385916 -235.53547) (xy 336.385916 -235.579666)
			(xy 336.432906 -235.732066) (xy 336.694526 -235.732066)
		)
		(stroke
			(width 0)
			(type solid)
		)
		(fill yes)
		(layer "In4.Cu")
		(net "M_B_CPU0_SB_DQS_DP<0>")
	)
	(gr_poly
		(pts
			(xy 336.741516 -234.360466) (xy 336.694526 -234.208066) (xy 336.432906 -234.208066) (xy 336.385916 -234.360466)
			(xy 336.385916 -234.404662) (xy 336.741516 -234.404662)
		)
		(stroke
			(width 0)
			(type solid)
		)
		(fill yes)
		(layer "In4.Cu")
		(net "M_B_CPU0_SB_DQS_DP<5>")
	)
	(gr_poly
		(pts
			(xy 336.741516 -227.848922) (xy 336.694526 -227.696522) (xy 336.432906 -227.696522) (xy 336.385916 -227.848922)
			(xy 336.385916 -227.893372) (xy 336.741516 -227.893372)
		)
		(stroke
			(width 0)
			(type solid)
		)
		(fill yes)
		(layer "In4.Cu")
		(net "M_C_CPU0_SB_DQ<23>")
	)
	(gr_poly
		(pts
			(xy 336.83448 -273.248882) (xy 336.83448 -273.204686) (xy 336.47888 -273.204686) (xy 336.47888 -273.248882)
			(xy 336.52587 -273.401282) (xy 336.78749 -273.401282)
		)
		(stroke
			(width 0)
			(type solid)
		)
		(fill yes)
		(layer "In4.Cu")
		(net "M_B_CPU0_SA_DQS_DP<1>")
	)
	(gr_poly
		(pts
			(xy 336.83702 -272.029174) (xy 336.79003 -271.876774) (xy 336.52841 -271.876774) (xy 336.48142 -272.029174)
			(xy 336.48142 -272.073624) (xy 336.83702 -272.073624)
		)
		(stroke
			(width 0)
			(type solid)
		)
		(fill yes)
		(layer "In4.Cu")
		(net "M_B_CPU0_SA_DQS_DP<6>")
	)
	(gr_poly
		(pts
			(xy 336.83956 -271.620742) (xy 336.83956 -271.576546) (xy 336.48396 -271.576546) (xy 336.48396 -271.620742)
			(xy 336.53095 -271.773142) (xy 336.79257 -271.773142)
		)
		(stroke
			(width 0)
			(type solid)
		)
		(fill yes)
		(layer "In4.Cu")
		(net "M_B_CPU0_SA_DQ<12>")
	)
	(gr_poly
		(pts
			(xy 336.83956 -270.40205) (xy 336.79257 -270.24965) (xy 336.53095 -270.24965) (xy 336.48396 -270.40205)
			(xy 336.48396 -270.446246) (xy 336.83956 -270.446246)
		)
		(stroke
			(width 0)
			(type solid)
		)
		(fill yes)
		(layer "In4.Cu")
		(net "M_B_CPU0_SA_DQ<15>")
	)
	(gr_poly
		(pts
			(xy 336.83956 -268.77391) (xy 336.79257 -268.62151) (xy 336.53095 -268.62151) (xy 336.48396 -268.77391)
			(xy 336.48396 -268.81836) (xy 336.83956 -268.81836)
		)
		(stroke
			(width 0)
			(type solid)
		)
		(fill yes)
		(layer "In4.Cu")
		(net "M_C_CPU0_SA_DQ<19>")
	)
	(gr_poly
		(pts
			(xy 336.83956 -268.365478) (xy 336.83956 -268.321028) (xy 336.48396 -268.321028) (xy 336.48396 -268.365478)
			(xy 336.53095 -268.517878) (xy 336.79257 -268.517878)
		)
		(stroke
			(width 0)
			(type solid)
		)
		(fill yes)
		(layer "In4.Cu")
		(net "M_C_CPU0_SA_DQS_DP<2>")
	)
	(gr_poly
		(pts
			(xy 336.83956 -265.518646) (xy 336.79257 -265.366246) (xy 336.53095 -265.366246) (xy 336.48396 -265.518646)
			(xy 336.48396 -265.563096) (xy 336.83956 -265.563096)
		)
		(stroke
			(width 0)
			(type solid)
		)
		(fill yes)
		(layer "In4.Cu")
		(net "M_C_CPU0_SA_DQ<23>")
	)
	(gr_poly
		(pts
			(xy 336.842862 -274.876514) (xy 336.842862 -274.832064) (xy 336.487262 -274.832064) (xy 336.487262 -274.876514)
			(xy 336.534252 -275.028914) (xy 336.795872 -275.028914)
		)
		(stroke
			(width 0)
			(type solid)
		)
		(fill yes)
		(layer "In4.Cu")
		(net "M_B_CPU0_SA_DQ<8>")
	)
	(gr_poly
		(pts
			(xy 336.842862 -273.657314) (xy 336.795872 -273.504914) (xy 336.534252 -273.504914) (xy 336.487262 -273.657314)
			(xy 336.487262 -273.701764) (xy 336.842862 -273.701764)
		)
		(stroke
			(width 0)
			(type solid)
		)
		(fill yes)
		(layer "In4.Cu")
		(net "M_B_CPU0_SA_DQ<11>")
	)
	(gr_poly
		(pts
			(xy 336.842862 -269.99311) (xy 336.842862 -269.948914) (xy 336.487262 -269.948914) (xy 336.487262 -269.99311)
			(xy 336.534252 -270.14551) (xy 336.795872 -270.14551)
		)
		(stroke
			(width 0)
			(type solid)
		)
		(fill yes)
		(layer "In4.Cu")
		(net "M_C_CPU0_SA_DQ<16>")
	)
	(gr_poly
		(pts
			(xy 336.842862 -267.146278) (xy 336.795872 -266.993878) (xy 336.534252 -266.993878) (xy 336.487262 -267.146278)
			(xy 336.487262 -267.190474) (xy 336.842862 -267.190474)
		)
		(stroke
			(width 0)
			(type solid)
		)
		(fill yes)
		(layer "In4.Cu")
		(net "M_C_CPU0_SA_DQS_DP<7>")
	)
	(gr_poly
		(pts
			(xy 336.842862 -266.737846) (xy 336.842862 -266.693396) (xy 336.487262 -266.693396) (xy 336.487262 -266.737846)
			(xy 336.534252 -266.890246) (xy 336.795872 -266.890246)
		)
		(stroke
			(width 0)
			(type solid)
		)
		(fill yes)
		(layer "In4.Cu")
		(net "M_C_CPU0_SA_DQ<20>")
	)
	(gr_poly
		(pts
			(xy 336.842862 -265.109706) (xy 336.842862 -265.06551) (xy 336.487262 -265.06551) (xy 336.487262 -265.109706)
			(xy 336.534252 -265.262106) (xy 336.795872 -265.262106)
		)
		(stroke
			(width 0)
			(type solid)
		)
		(fill yes)
		(layer "In4.Cu")
		(net "M_B_CPU0_SA_DQ<26>")
	)
	(gr_poly
		(pts
			(xy 336.842862 -263.891014) (xy 336.795872 -263.738614) (xy 336.534252 -263.738614) (xy 336.487262 -263.891014)
			(xy 336.487262 -263.93521) (xy 336.842862 -263.93521)
		)
		(stroke
			(width 0)
			(type solid)
		)
		(fill yes)
		(layer "In4.Cu")
		(net "M_B_CPU0_SA_DQ<27>")
	)
	(gr_poly
		(pts
			(xy 336.842862 -263.482074) (xy 336.842862 -263.437878) (xy 336.487262 -263.437878) (xy 336.487262 -263.482074)
			(xy 336.534252 -263.634474) (xy 336.795872 -263.634474)
		)
		(stroke
			(width 0)
			(type solid)
		)
		(fill yes)
		(layer "In4.Cu")
		(net "M_B_CPU0_SA_DQS_DP<3>")
	)
	(gr_poly
		(pts
			(xy 336.842862 -261.854442) (xy 336.842862 -261.809992) (xy 336.487262 -261.809992) (xy 336.487262 -261.854442)
			(xy 336.534252 -262.006842) (xy 336.795872 -262.006842)
		)
		(stroke
			(width 0)
			(type solid)
		)
		(fill yes)
		(layer "In4.Cu")
		(net "M_B_CPU0_SA_DQ<28>")
	)
	(gr_poly
		(pts
			(xy 336.842862 -258.59867) (xy 336.842862 -258.554474) (xy 336.487262 -258.554474) (xy 336.487262 -258.59867)
			(xy 336.534252 -258.75107) (xy 336.795872 -258.75107)
		)
		(stroke
			(width 0)
			(type solid)
		)
		(fill yes)
		(layer "In4.Cu")
		(net "M_C_CPU0_SA_CS_N<0>")
	)
	(gr_poly
		(pts
			(xy 336.842862 -257.37947) (xy 336.795872 -257.22707) (xy 336.534252 -257.22707) (xy 336.487262 -257.37947)
			(xy 336.487262 -257.42392) (xy 336.842862 -257.42392)
		)
		(stroke
			(width 0)
			(type solid)
		)
		(fill yes)
		(layer "In4.Cu")
		(net "M_C_CPU0_SA_CS_N<3>")
	)
	(gr_poly
		(pts
			(xy 336.842862 -256.971038) (xy 336.842862 -256.926588) (xy 336.487262 -256.926588) (xy 336.487262 -256.971038)
			(xy 336.534252 -257.123438) (xy 336.795872 -257.123438)
		)
		(stroke
			(width 0)
			(type solid)
		)
		(fill yes)
		(layer "In4.Cu")
		(net "M_C_CPU0_SA_CA<0>")
	)
	(gr_poly
		(pts
			(xy 336.842862 -254.124206) (xy 336.795872 -253.971806) (xy 336.534252 -253.971806) (xy 336.487262 -254.124206)
			(xy 336.487262 -254.168402) (xy 336.842862 -254.168402)
		)
		(stroke
			(width 0)
			(type solid)
		)
		(fill yes)
		(layer "In4.Cu")
		(net "M_C_CPU0_SA_PAR")
	)
	(gr_poly
		(pts
			(xy 336.848958 -262.262874) (xy 336.801968 -262.110474) (xy 336.540348 -262.110474) (xy 336.493358 -262.262874)
			(xy 336.493358 -262.30707) (xy 336.848958 -262.30707)
		)
		(stroke
			(width 0)
			(type solid)
		)
		(fill yes)
		(layer "In4.Cu")
		(net "M_B_CPU0_SA_DQS_DP<8>")
	)
	(gr_poly
		(pts
			(xy 336.848958 -260.634734) (xy 336.801968 -260.482334) (xy 336.540348 -260.482334) (xy 336.493358 -260.634734)
			(xy 336.493358 -260.679184) (xy 336.848958 -260.679184)
		)
		(stroke
			(width 0)
			(type solid)
		)
		(fill yes)
		(layer "In4.Cu")
		(net "M_B_CPU0_SA_DQ<31>")
	)
	(gr_poly
		(pts
			(xy 336.848958 -255.751838) (xy 336.801968 -255.599438) (xy 336.540348 -255.599438) (xy 336.493358 -255.751838)
			(xy 336.493358 -255.796034) (xy 336.848958 -255.796034)
		)
		(stroke
			(width 0)
			(type solid)
		)
		(fill yes)
		(layer "In4.Cu")
		(net "M_C_CPU0_SA_CA<3>")
	)
	(gr_poly
		(pts
			(xy 336.848958 -255.343406) (xy 336.848958 -255.29921) (xy 336.493358 -255.29921) (xy 336.493358 -255.343406)
			(xy 336.540348 -255.495806) (xy 336.801968 -255.495806)
		)
		(stroke
			(width 0)
			(type solid)
		)
		(fill yes)
		(layer "In4.Cu")
		(net "M_C_CPU0_SA_CA<4>")
	)
	(gr_poly
		(pts
			(xy 336.916776 -283.494226) (xy 336.808318 -283.377386) (xy 336.769964 -283.355288) (xy 336.592164 -283.663136)
			(xy 336.630518 -283.685234) (xy 336.785966 -283.720794)
		)
		(stroke
			(width 0)
			(type solid)
		)
		(fill yes)
		(layer "In4.Cu")
		(net "M_C_CPU0_SA_DQS_DP<0>")
	)
	(gr_poly
		(pts
			(xy 336.916776 -276.982428) (xy 336.808318 -276.865588) (xy 336.769964 -276.84349) (xy 336.592164 -277.151338)
			(xy 336.630518 -277.173436) (xy 336.785966 -277.208996)
		)
		(stroke
			(width 0)
			(type solid)
		)
		(fill yes)
		(layer "In4.Cu")
		(net "M_C_CPU0_SA_DQ<5>")
	)
	(gr_poly
		(pts
			(xy 336.917792 -285.119318) (xy 336.809334 -285.002478) (xy 336.77098 -284.98038) (xy 336.59318 -285.288228)
			(xy 336.631534 -285.310326) (xy 336.786982 -285.345886)
		)
		(stroke
			(width 0)
			(type solid)
		)
		(fill yes)
		(layer "In4.Cu")
		(net "M_C_CPU0_SA_DQ<1>")
	)
	(gr_poly
		(pts
			(xy 336.917792 -278.608282) (xy 336.809334 -278.491442) (xy 336.77098 -278.469344) (xy 336.59318 -278.777192)
			(xy 336.631534 -278.79929) (xy 336.786982 -278.83485)
		)
		(stroke
			(width 0)
			(type solid)
		)
		(fill yes)
		(layer "In4.Cu")
		(net "M_C_CPU0_SA_DQ<4>")
	)
	(gr_poly
		(pts
			(xy 336.922364 -281.856434) (xy 336.813906 -281.739594) (xy 336.775552 -281.717496) (xy 336.597752 -282.025344)
			(xy 336.636106 -282.047442) (xy 336.791554 -282.083002)
		)
		(stroke
			(width 0)
			(type solid)
		)
		(fill yes)
		(layer "In4.Cu")
		(net "M_C_CPU0_SA_DQS_DN<5>")
	)
	(gr_poly
		(pts
			(xy 336.924142 -286.737044) (xy 336.815684 -286.620204) (xy 336.77733 -286.598106) (xy 336.59953 -286.905954)
			(xy 336.637884 -286.928052) (xy 336.793332 -286.963612)
		)
		(stroke
			(width 0)
			(type solid)
		)
		(fill yes)
		(layer "In4.Cu")
		(net "M_C_CPU0_SA_DQ<0>")
	)
	(gr_poly
		(pts
			(xy 337.194398 -246.568722) (xy 337.147408 -246.416322) (xy 336.885788 -246.416322) (xy 336.838798 -246.568722)
			(xy 336.838798 -246.612918) (xy 337.194398 -246.612918)
		)
		(stroke
			(width 0)
			(type solid)
		)
		(fill yes)
		(layer "In4.Cu")
		(net "M_C_CPU0_SB_CA<3>")
	)
	(gr_poly
		(pts
			(xy 337.194398 -246.16029) (xy 337.194398 -246.116094) (xy 336.838798 -246.116094) (xy 336.838798 -246.16029)
			(xy 336.885788 -246.31269) (xy 337.147408 -246.31269)
		)
		(stroke
			(width 0)
			(type solid)
		)
		(fill yes)
		(layer "In4.Cu")
		(net "M_C_CPU0_SB_CA<4>")
	)
	(gr_poly
		(pts
			(xy 337.194398 -244.940582) (xy 337.147408 -244.788182) (xy 336.885788 -244.788182) (xy 336.838798 -244.940582)
			(xy 336.838798 -244.985032) (xy 337.194398 -244.985032)
		)
		(stroke
			(width 0)
			(type solid)
		)
		(fill yes)
		(layer "In4.Cu")
		(net "M_C_CPU0_SB_PAR")
	)
	(gr_poly
		(pts
			(xy 337.194398 -244.532658) (xy 337.194398 -244.488208) (xy 336.838798 -244.488208) (xy 336.838798 -244.532658)
			(xy 336.885788 -244.685058) (xy 337.147408 -244.685058)
		)
		(stroke
			(width 0)
			(type solid)
		)
		(fill yes)
		(layer "In4.Cu")
		(net "M_C_CPU0_SB_CS_N<2>")
	)
	(gr_poly
		(pts
			(xy 337.194398 -243.31295) (xy 337.147408 -243.16055) (xy 336.885788 -243.16055) (xy 336.838798 -243.31295)
			(xy 336.838798 -243.3574) (xy 337.194398 -243.3574)
		)
		(stroke
			(width 0)
			(type solid)
		)
		(fill yes)
		(layer "In4.Cu")
		(net "M_C_CPU0_SB_CS_N<1>")
	)
	(gr_poly
		(pts
			(xy 337.194398 -241.685318) (xy 337.147408 -241.532918) (xy 336.885788 -241.532918) (xy 336.838798 -241.685318)
			(xy 336.838798 -241.729514) (xy 337.194398 -241.729514)
		)
		(stroke
			(width 0)
			(type solid)
		)
		(fill yes)
		(layer "In4.Cu")
		(net "M_C_CPU0_SB_CB<6>")
	)
	(gr_poly
		(pts
			(xy 337.194398 -239.649254) (xy 337.194398 -239.604804) (xy 336.838798 -239.604804) (xy 336.838798 -239.649254)
			(xy 336.885788 -239.801654) (xy 337.147408 -239.801654)
		)
		(stroke
			(width 0)
			(type solid)
		)
		(fill yes)
		(layer "In4.Cu")
		(net "M_C_CPU0_SB_DQS_DN<4>")
	)
	(gr_poly
		(pts
			(xy 337.194398 -235.174282) (xy 337.147408 -235.021882) (xy 336.885788 -235.021882) (xy 336.838798 -235.174282)
			(xy 336.838798 -235.218478) (xy 337.194398 -235.218478)
		)
		(stroke
			(width 0)
			(type solid)
		)
		(fill yes)
		(layer "In4.Cu")
		(net "M_B_CPU0_SB_DQS_DN<0>")
	)
	(gr_poly
		(pts
			(xy 337.194398 -234.76585) (xy 337.194398 -234.721654) (xy 336.838798 -234.721654) (xy 336.838798 -234.76585)
			(xy 336.885788 -234.91825) (xy 337.147408 -234.91825)
		)
		(stroke
			(width 0)
			(type solid)
		)
		(fill yes)
		(layer "In4.Cu")
		(net "M_B_CPU0_SB_DQS_DN<5>")
	)
	(gr_poly
		(pts
			(xy 337.194398 -228.254814) (xy 337.194398 -228.210618) (xy 336.838798 -228.210618) (xy 336.838798 -228.254814)
			(xy 336.885788 -228.407214) (xy 337.147408 -228.407214)
		)
		(stroke
			(width 0)
			(type solid)
		)
		(fill yes)
		(layer "In4.Cu")
		(net "M_C_CPU0_SB_DQ<21>")
	)
	(gr_poly
		(pts
			(xy 337.196938 -236.801914) (xy 337.149948 -236.649514) (xy 336.888328 -236.649514) (xy 336.841338 -236.801914)
			(xy 336.841338 -236.846364) (xy 337.196938 -236.846364)
		)
		(stroke
			(width 0)
			(type solid)
		)
		(fill yes)
		(layer "In4.Cu")
		(net "M_B_CPU0_SB_DQ<0>")
	)
	(gr_poly
		(pts
			(xy 337.206336 -241.276886) (xy 337.206336 -241.232436) (xy 336.850736 -241.232436) (xy 336.850736 -241.276886)
			(xy 336.897726 -241.429286) (xy 337.159346 -241.429286)
		)
		(stroke
			(width 0)
			(type solid)
		)
		(fill yes)
		(layer "In4.Cu")
		(net "M_C_CPU0_SB_CB<5>")
	)
	(gr_poly
		(pts
			(xy 337.206336 -240.057686) (xy 337.159346 -239.905286) (xy 336.897726 -239.905286) (xy 336.850736 -240.057686)
			(xy 336.850736 -240.102136) (xy 337.206336 -240.102136)
		)
		(stroke
			(width 0)
			(type solid)
		)
		(fill yes)
		(layer "In4.Cu")
		(net "M_C_CPU0_SB_DQS_DN<9>")
	)
	(gr_poly
		(pts
			(xy 337.206336 -238.021114) (xy 337.206336 -237.976664) (xy 336.850736 -237.976664) (xy 336.850736 -238.021114)
			(xy 336.897726 -238.173514) (xy 337.159346 -238.173514)
		)
		(stroke
			(width 0)
			(type solid)
		)
		(fill yes)
		(layer "In4.Cu")
		(net "M_C_CPU0_SB_CB<1>")
	)
	(gr_poly
		(pts
			(xy 337.206336 -233.13771) (xy 337.206336 -233.093514) (xy 336.850736 -233.093514) (xy 336.850736 -233.13771)
			(xy 336.897726 -233.29011) (xy 337.159346 -233.29011)
		)
		(stroke
			(width 0)
			(type solid)
		)
		(fill yes)
		(layer "In4.Cu")
		(net "M_B_CPU0_SB_DQ<5>")
	)
	(gr_poly
		(pts
			(xy 337.206336 -231.919018) (xy 337.159346 -231.766618) (xy 336.897726 -231.766618) (xy 336.850736 -231.919018)
			(xy 336.850736 -231.963214) (xy 337.206336 -231.963214)
		)
		(stroke
			(width 0)
			(type solid)
		)
		(fill yes)
		(layer "In4.Cu")
		(net "M_C_CPU0_SB_DQ<18>")
	)
	(gr_poly
		(pts
			(xy 337.206336 -230.290878) (xy 337.159346 -230.138478) (xy 336.897726 -230.138478) (xy 336.850736 -230.290878)
			(xy 336.850736 -230.335328) (xy 337.206336 -230.335328)
		)
		(stroke
			(width 0)
			(type solid)
		)
		(fill yes)
		(layer "In4.Cu")
		(net "M_C_CPU0_SB_DQS_DN<2>")
	)
	(gr_poly
		(pts
			(xy 337.206336 -229.882446) (xy 337.206336 -229.837996) (xy 336.850736 -229.837996) (xy 336.850736 -229.882446)
			(xy 336.897726 -230.034846) (xy 337.159346 -230.034846)
		)
		(stroke
			(width 0)
			(type solid)
		)
		(fill yes)
		(layer "In4.Cu")
		(net "M_C_CPU0_SB_DQS_DN<7>")
	)
	(gr_poly
		(pts
			(xy 337.206844 -285.220664) (xy 337.16849 -285.198566) (xy 337.013042 -285.163006) (xy 336.882232 -285.389574)
			(xy 336.99069 -285.506414) (xy 337.029044 -285.528512)
		)
		(stroke
			(width 0)
			(type solid)
		)
		(fill yes)
		(layer "In4.Cu")
		(net "M_C_CPU0_SA_DQ<2>")
	)
	(gr_poly
		(pts
			(xy 337.206844 -283.593032) (xy 337.16849 -283.570934) (xy 337.013042 -283.535374) (xy 336.882232 -283.761942)
			(xy 336.99069 -283.878782) (xy 337.029044 -283.90088)
		)
		(stroke
			(width 0)
			(type solid)
		)
		(fill yes)
		(layer "In4.Cu")
		(net "M_C_CPU0_SA_DQ<3>")
	)
	(gr_poly
		(pts
			(xy 337.206844 -278.709628) (xy 337.16849 -278.68753) (xy 337.013042 -278.65197) (xy 336.882232 -278.878538)
			(xy 336.99069 -278.995378) (xy 337.029044 -279.017476)
		)
		(stroke
			(width 0)
			(type solid)
		)
		(fill yes)
		(layer "In4.Cu")
		(net "M_C_CPU0_SA_DQS_DP<5>")
	)
	(gr_poly
		(pts
			(xy 337.206844 -277.081742) (xy 337.16849 -277.059644) (xy 337.013042 -277.024084) (xy 336.882232 -277.250652)
			(xy 336.99069 -277.367492) (xy 337.029044 -277.38959)
		)
		(stroke
			(width 0)
			(type solid)
		)
		(fill yes)
		(layer "In4.Cu")
		(net "M_C_CPU0_SA_DQ<6>")
	)
	(gr_poly
		(pts
			(xy 337.207098 -238.430054) (xy 337.160108 -238.277654) (xy 336.898488 -238.277654) (xy 336.851498 -238.430054)
			(xy 336.851498 -238.47425) (xy 337.207098 -238.47425)
		)
		(stroke
			(width 0)
			(type solid)
		)
		(fill yes)
		(layer "In4.Cu")
		(net "M_C_CPU0_SB_CB<2>")
	)
	(gr_poly
		(pts
			(xy 337.207098 -236.393482) (xy 337.207098 -236.349032) (xy 336.851498 -236.349032) (xy 336.851498 -236.393482)
			(xy 336.898488 -236.545882) (xy 337.160108 -236.545882)
		)
		(stroke
			(width 0)
			(type solid)
		)
		(fill yes)
		(layer "In4.Cu")
		(net "M_B_CPU0_SB_DQ<1>")
	)
	(gr_poly
		(pts
			(xy 337.207098 -233.54665) (xy 337.160108 -233.39425) (xy 336.898488 -233.39425) (xy 336.851498 -233.54665)
			(xy 336.851498 -233.5911) (xy 337.207098 -233.5911)
		)
		(stroke
			(width 0)
			(type solid)
		)
		(fill yes)
		(layer "In4.Cu")
		(net "M_B_CPU0_SB_DQ<6>")
	)
	(gr_poly
		(pts
			(xy 337.207098 -231.510078) (xy 337.207098 -231.465628) (xy 336.851498 -231.465628) (xy 336.851498 -231.510078)
			(xy 336.898488 -231.662478) (xy 337.160108 -231.662478)
		)
		(stroke
			(width 0)
			(type solid)
		)
		(fill yes)
		(layer "In4.Cu")
		(net "M_C_CPU0_SB_DQ<17>")
	)
	(gr_poly
		(pts
			(xy 337.207098 -228.663246) (xy 337.160108 -228.510846) (xy 336.898488 -228.510846) (xy 336.851498 -228.663246)
			(xy 336.851498 -228.707696) (xy 337.207098 -228.707696)
		)
		(stroke
			(width 0)
			(type solid)
		)
		(fill yes)
		(layer "In4.Cu")
		(net "M_C_CPU0_SB_DQ<22>")
	)
	(gr_poly
		(pts
			(xy 337.208876 -275.450046) (xy 337.170522 -275.427948) (xy 337.015074 -275.392388) (xy 336.884264 -275.618956)
			(xy 336.992722 -275.735796) (xy 337.031076 -275.757894)
		)
		(stroke
			(width 0)
			(type solid)
		)
		(fill yes)
		(layer "In4.Cu")
		(net "M_C_CPU0_SA_DQ<7>")
	)
	(gr_poly
		(pts
			(xy 337.277202 -280.6192) (xy 337.38566 -280.50236) (xy 337.25485 -280.275792) (xy 337.099402 -280.311352)
			(xy 337.061048 -280.33345) (xy 337.238848 -280.641298)
		)
		(stroke
			(width 0)
			(type solid)
		)
		(fill yes)
		(layer "In4.Cu")
		(net "M_C_CPU0_SA_DQS_DN<5>")
	)
	(gr_poly
		(pts
			(xy 337.30438 -261.040626) (xy 337.30438 -260.99643) (xy 336.94878 -260.99643) (xy 336.94878 -261.040626)
			(xy 336.99577 -261.193026) (xy 337.25739 -261.193026)
		)
		(stroke
			(width 0)
			(type solid)
		)
		(fill yes)
		(layer "In4.Cu")
		(net "M_B_CPU0_SA_DQ<29>")
	)
	(gr_poly
		(pts
			(xy 337.30438 -256.157222) (xy 337.30438 -256.113026) (xy 336.94878 -256.113026) (xy 336.94878 -256.157222)
			(xy 336.99577 -256.309622) (xy 337.25739 -256.309622)
		)
		(stroke
			(width 0)
			(type solid)
		)
		(fill yes)
		(layer "In4.Cu")
		(net "M_C_CPU0_SA_CA<2>")
	)
	(gr_poly
		(pts
			(xy 337.30438 -254.937514) (xy 337.25739 -254.785114) (xy 336.99577 -254.785114) (xy 336.94878 -254.937514)
			(xy 336.94878 -254.981964) (xy 337.30438 -254.981964)
		)
		(stroke
			(width 0)
			(type solid)
		)
		(fill yes)
		(layer "In4.Cu")
		(net "M_C_CPU0_SA_CA<5>")
	)
	(gr_poly
		(pts
			(xy 337.30692 -272.435066) (xy 337.30692 -272.390616) (xy 336.95132 -272.390616) (xy 336.95132 -272.435066)
			(xy 336.99831 -272.587466) (xy 337.25993 -272.587466)
		)
		(stroke
			(width 0)
			(type solid)
		)
		(fill yes)
		(layer "In4.Cu")
		(net "M_B_CPU0_SA_DQS_DN<6>")
	)
	(gr_poly
		(pts
			(xy 337.312762 -274.47113) (xy 337.265772 -274.31873) (xy 337.004152 -274.31873) (xy 336.957162 -274.47113)
			(xy 336.957162 -274.51558) (xy 337.312762 -274.51558)
		)
		(stroke
			(width 0)
			(type solid)
		)
		(fill yes)
		(layer "In4.Cu")
		(net "M_B_CPU0_SA_DQ<10>")
	)
	(gr_poly
		(pts
			(xy 337.312762 -274.062698) (xy 337.312762 -274.018248) (xy 336.957162 -274.018248) (xy 336.957162 -274.062698)
			(xy 337.004152 -274.215098) (xy 337.265772 -274.215098)
		)
		(stroke
			(width 0)
			(type solid)
		)
		(fill yes)
		(layer "In4.Cu")
		(net "M_B_CPU0_SA_DQ<9>")
	)
	(gr_poly
		(pts
			(xy 337.312762 -269.587726) (xy 337.265772 -269.435326) (xy 337.004152 -269.435326) (xy 336.957162 -269.587726)
			(xy 336.957162 -269.632176) (xy 337.312762 -269.632176)
		)
		(stroke
			(width 0)
			(type solid)
		)
		(fill yes)
		(layer "In4.Cu")
		(net "M_C_CPU0_SA_DQ<18>")
	)
	(gr_poly
		(pts
			(xy 337.312762 -264.70483) (xy 337.265772 -264.55243) (xy 337.004152 -264.55243) (xy 336.957162 -264.70483)
			(xy 336.957162 -264.749026) (xy 337.312762 -264.749026)
		)
		(stroke
			(width 0)
			(type solid)
		)
		(fill yes)
		(layer "In4.Cu")
		(net "M_B_CPU0_SA_DQ<24>")
	)
	(gr_poly
		(pts
			(xy 337.312762 -263.07669) (xy 337.265772 -262.92429) (xy 337.004152 -262.92429) (xy 336.957162 -263.07669)
			(xy 336.957162 -263.12114) (xy 337.312762 -263.12114)
		)
		(stroke
			(width 0)
			(type solid)
		)
		(fill yes)
		(layer "In4.Cu")
		(net "M_B_CPU0_SA_DQS_DN<3>")
	)
	(gr_poly
		(pts
			(xy 337.312762 -261.449058) (xy 337.265772 -261.296658) (xy 337.004152 -261.296658) (xy 336.957162 -261.449058)
			(xy 336.957162 -261.493508) (xy 337.312762 -261.493508)
		)
		(stroke
			(width 0)
			(type solid)
		)
		(fill yes)
		(layer "In4.Cu")
		(net "M_B_CPU0_SA_DQ<30>")
	)
	(gr_poly
		(pts
			(xy 337.312762 -258.193286) (xy 337.265772 -258.040886) (xy 337.004152 -258.040886) (xy 336.957162 -258.193286)
			(xy 336.957162 -258.237736) (xy 337.312762 -258.237736)
		)
		(stroke
			(width 0)
			(type solid)
		)
		(fill yes)
		(layer "In4.Cu")
		(net "M_C_CPU0_SA_CS_N<2>")
	)
	(gr_poly
		(pts
			(xy 337.312762 -257.784854) (xy 337.312762 -257.740404) (xy 336.957162 -257.740404) (xy 336.957162 -257.784854)
			(xy 337.004152 -257.937254) (xy 337.265772 -257.937254)
		)
		(stroke
			(width 0)
			(type solid)
		)
		(fill yes)
		(layer "In4.Cu")
		(net "M_C_CPU0_SA_CS_N<1>")
	)
	(gr_poly
		(pts
			(xy 337.312762 -256.565654) (xy 337.265772 -256.413254) (xy 337.004152 -256.413254) (xy 336.957162 -256.565654)
			(xy 336.957162 -256.610104) (xy 337.312762 -256.610104)
		)
		(stroke
			(width 0)
			(type solid)
		)
		(fill yes)
		(layer "In4.Cu")
		(net "M_C_CPU0_SA_CA<1>")
	)
	(gr_poly
		(pts
			(xy 337.312762 -254.529082) (xy 337.312762 -254.484886) (xy 336.957162 -254.484886) (xy 336.957162 -254.529082)
			(xy 337.004152 -254.681482) (xy 337.265772 -254.681482)
		)
		(stroke
			(width 0)
			(type solid)
		)
		(fill yes)
		(layer "In4.Cu")
		(net "M_C_CPU0_SA_CA<6>")
	)
	(gr_poly
		(pts
			(xy 337.315048 -266.332462) (xy 337.268058 -266.180062) (xy 337.006438 -266.180062) (xy 336.959448 -266.332462)
			(xy 336.959448 -266.376912) (xy 337.315048 -266.376912)
		)
		(stroke
			(width 0)
			(type solid)
		)
		(fill yes)
		(layer "In4.Cu")
		(net "M_C_CPU0_SA_DQ<22>")
	)
	(gr_poly
		(pts
			(xy 337.315556 -271.215866) (xy 337.268566 -271.063466) (xy 337.006946 -271.063466) (xy 336.959956 -271.215866)
			(xy 336.959956 -271.260062) (xy 337.315556 -271.260062)
		)
		(stroke
			(width 0)
			(type solid)
		)
		(fill yes)
		(layer "In4.Cu")
		(net "M_B_CPU0_SA_DQ<14>")
	)
	(gr_poly
		(pts
			(xy 337.315556 -270.806926) (xy 337.315556 -270.76273) (xy 336.959956 -270.76273) (xy 336.959956 -270.806926)
			(xy 337.006946 -270.959326) (xy 337.268566 -270.959326)
		)
		(stroke
			(width 0)
			(type solid)
		)
		(fill yes)
		(layer "In4.Cu")
		(net "M_B_CPU0_SA_DQ<13>")
	)
	(gr_poly
		(pts
			(xy 337.315556 -269.179294) (xy 337.315556 -269.134844) (xy 336.959956 -269.134844) (xy 336.959956 -269.179294)
			(xy 337.006946 -269.331694) (xy 337.268566 -269.331694)
		)
		(stroke
			(width 0)
			(type solid)
		)
		(fill yes)
		(layer "In4.Cu")
		(net "M_C_CPU0_SA_DQ<17>")
	)
	(gr_poly
		(pts
			(xy 337.315556 -267.960094) (xy 337.268566 -267.807694) (xy 337.006946 -267.807694) (xy 336.959956 -267.960094)
			(xy 336.959956 -268.004544) (xy 337.315556 -268.004544)
		)
		(stroke
			(width 0)
			(type solid)
		)
		(fill yes)
		(layer "In4.Cu")
		(net "M_C_CPU0_SA_DQS_DN<2>")
	)
	(gr_poly
		(pts
			(xy 337.315556 -267.551154) (xy 337.315556 -267.506958) (xy 336.959956 -267.506958) (xy 336.959956 -267.551154)
			(xy 337.006946 -267.703554) (xy 337.268566 -267.703554)
		)
		(stroke
			(width 0)
			(type solid)
		)
		(fill yes)
		(layer "In4.Cu")
		(net "M_C_CPU0_SA_DQS_DN<7>")
	)
	(gr_poly
		(pts
			(xy 337.315556 -265.923522) (xy 337.315556 -265.879326) (xy 336.959956 -265.879326) (xy 336.959956 -265.923522)
			(xy 337.006946 -266.075922) (xy 337.268566 -266.075922)
		)
		(stroke
			(width 0)
			(type solid)
		)
		(fill yes)
		(layer "In4.Cu")
		(net "M_C_CPU0_SA_DQ<21>")
	)
	(gr_poly
		(pts
			(xy 337.315556 -264.29589) (xy 337.315556 -264.25144) (xy 336.959956 -264.25144) (xy 336.959956 -264.29589)
			(xy 337.006946 -264.44829) (xy 337.268566 -264.44829)
		)
		(stroke
			(width 0)
			(type solid)
		)
		(fill yes)
		(layer "In4.Cu")
		(net "M_B_CPU0_SA_DQ<25>")
	)
	(gr_poly
		(pts
			(xy 337.315556 -262.668258) (xy 337.315556 -262.623808) (xy 336.959956 -262.623808) (xy 336.959956 -262.668258)
			(xy 337.006946 -262.820658) (xy 337.268566 -262.820658)
		)
		(stroke
			(width 0)
			(type solid)
		)
		(fill yes)
		(layer "In4.Cu")
		(net "M_B_CPU0_SA_DQS_DN<8>")
	)
	(gr_poly
		(pts
			(xy 337.318858 -272.843498) (xy 337.271868 -272.691098) (xy 337.010248 -272.691098) (xy 336.963258 -272.843498)
			(xy 336.963258 -272.887948) (xy 337.318858 -272.887948)
		)
		(stroke
			(width 0)
			(type solid)
		)
		(fill yes)
		(layer "In4.Cu")
		(net "M_B_CPU0_SA_DQS_DN<1>")
	)
	(gr_poly
		(pts
			(xy 337.321398 -282.610052) (xy 337.274408 -282.457652) (xy 337.012788 -282.457652) (xy 336.965798 -282.610052)
			(xy 336.965798 -282.654248) (xy 337.321398 -282.654248)
		)
		(stroke
			(width 0)
			(type solid)
		)
		(fill yes)
		(layer "In4.Cu")
		(net "M_C_CPU0_SA_DQS_DN<0>")
	)
	(gr_poly
		(pts
			(xy 337.384898 -285.937198) (xy 337.27644 -285.820358) (xy 337.238086 -285.79826) (xy 337.060286 -286.106108)
			(xy 337.09864 -286.128206) (xy 337.254088 -286.163766)
		)
		(stroke
			(width 0)
			(type solid)
		)
		(fill yes)
		(layer "In4.Cu")
		(net "M_C_CPU0_SA_DQ<0>")
	)
	(gr_poly
		(pts
			(xy 337.386676 -281.052524) (xy 337.278218 -280.935684) (xy 337.239864 -280.913586) (xy 337.062064 -281.221434)
			(xy 337.100418 -281.243532) (xy 337.255866 -281.279092)
		)
		(stroke
			(width 0)
			(type solid)
		)
		(fill yes)
		(layer "In4.Cu")
		(net "M_C_CPU0_SA_DQS_DN<5>")
	)
	(gr_poly
		(pts
			(xy 337.38693 -277.796244) (xy 337.278472 -277.679404) (xy 337.240118 -277.657306) (xy 337.062318 -277.965154)
			(xy 337.100672 -277.987252) (xy 337.25612 -278.022812)
		)
		(stroke
			(width 0)
			(type solid)
		)
		(fill yes)
		(layer "In4.Cu")
		(net "M_C_CPU0_SA_DQ<4>")
	)
	(gr_poly
		(pts
			(xy 337.387692 -279.422098) (xy 337.279234 -279.305258) (xy 337.24088 -279.28316) (xy 337.06308 -279.591008)
			(xy 337.101434 -279.613106) (xy 337.256882 -279.648666)
		)
		(stroke
			(width 0)
			(type solid)
		)
		(fill yes)
		(layer "In4.Cu")
		(net "M_C_CPU0_SA_DQS_DN<5>")
	)
	(gr_poly
		(pts
			(xy 337.387692 -276.16658) (xy 337.279234 -276.04974) (xy 337.24088 -276.027642) (xy 337.06308 -276.33549)
			(xy 337.101434 -276.357588) (xy 337.256882 -276.393148)
		)
		(stroke
			(width 0)
			(type solid)
		)
		(fill yes)
		(layer "In4.Cu")
		(net "M_C_CPU0_SA_DQ<5>")
	)
	(gr_poly
		(pts
			(xy 337.392264 -284.29839) (xy 337.283806 -284.18155) (xy 337.245452 -284.159452) (xy 337.067652 -284.4673)
			(xy 337.106006 -284.489398) (xy 337.261454 -284.524958)
		)
		(stroke
			(width 0)
			(type solid)
		)
		(fill yes)
		(layer "In4.Cu")
		(net "M_C_CPU0_SA_DQ<1>")
	)
	(gr_poly
		(pts
			(xy 337.634072 -282.047696) (xy 337.672426 -282.025598) (xy 337.494626 -281.71775) (xy 337.456272 -281.739848)
			(xy 337.347814 -281.856688) (xy 337.478624 -282.083256)
		)
		(stroke
			(width 0)
			(type solid)
		)
		(fill yes)
		(layer "In4.Cu")
		(net "M_C_CPU0_SA_DQS_DN<0>")
	)
	(gr_poly
		(pts
			(xy 337.668616 -238.83493) (xy 337.668616 -238.790734) (xy 337.313016 -238.790734) (xy 337.313016 -238.83493)
			(xy 337.360006 -238.98733) (xy 337.621626 -238.98733)
		)
		(stroke
			(width 0)
			(type solid)
		)
		(fill yes)
		(layer "In4.Cu")
		(net "M_C_CPU0_SB_CB<0>")
	)
	(gr_poly
		(pts
			(xy 337.668616 -235.988606) (xy 337.621626 -235.836206) (xy 337.360006 -235.836206) (xy 337.313016 -235.988606)
			(xy 337.313016 -236.032802) (xy 337.668616 -236.032802)
		)
		(stroke
			(width 0)
			(type solid)
		)
		(fill yes)
		(layer "In4.Cu")
		(net "M_B_CPU0_SB_DQ<3>")
	)
	(gr_poly
		(pts
			(xy 337.668616 -233.951526) (xy 337.668616 -233.90733) (xy 337.313016 -233.90733) (xy 337.313016 -233.951526)
			(xy 337.360006 -234.103926) (xy 337.621626 -234.103926)
		)
		(stroke
			(width 0)
			(type solid)
		)
		(fill yes)
		(layer "In4.Cu")
		(net "M_B_CPU0_SB_DQ<4>")
	)
	(gr_poly
		(pts
			(xy 337.668616 -231.105202) (xy 337.621626 -230.952802) (xy 337.360006 -230.952802) (xy 337.313016 -231.105202)
			(xy 337.313016 -231.149398) (xy 337.668616 -231.149398)
		)
		(stroke
			(width 0)
			(type solid)
		)
		(fill yes)
		(layer "In4.Cu")
		(net "M_C_CPU0_SB_DQ<19>")
	)
	(gr_poly
		(pts
			(xy 337.668616 -229.068122) (xy 337.668616 -229.023926) (xy 337.313016 -229.023926) (xy 337.313016 -229.068122)
			(xy 337.360006 -229.220522) (xy 337.621626 -229.220522)
		)
		(stroke
			(width 0)
			(type solid)
		)
		(fill yes)
		(layer "In4.Cu")
		(net "M_C_CPU0_SB_DQ<20>")
	)
	(gr_poly
		(pts
			(xy 337.669378 -240.871502) (xy 337.622388 -240.719102) (xy 337.360768 -240.719102) (xy 337.313778 -240.871502)
			(xy 337.313778 -240.915952) (xy 337.669378 -240.915952)
		)
		(stroke
			(width 0)
			(type solid)
		)
		(fill yes)
		(layer "In4.Cu")
		(net "M_C_CPU0_SB_CB<7>")
	)
	(gr_poly
		(pts
			(xy 337.669378 -237.616238) (xy 337.622388 -237.463838) (xy 337.360768 -237.463838) (xy 337.313778 -237.616238)
			(xy 337.313778 -237.660434) (xy 337.669378 -237.660434)
		)
		(stroke
			(width 0)
			(type solid)
		)
		(fill yes)
		(layer "In4.Cu")
		(net "M_C_CPU0_SB_CB<3>")
	)
	(gr_poly
		(pts
			(xy 337.669378 -232.732834) (xy 337.622388 -232.580434) (xy 337.360768 -232.580434) (xy 337.313778 -232.732834)
			(xy 337.313778 -232.77703) (xy 337.669378 -232.77703)
		)
		(stroke
			(width 0)
			(type solid)
		)
		(fill yes)
		(layer "In4.Cu")
		(net "M_B_CPU0_SB_DQ<7>")
	)
	(gr_poly
		(pts
			(xy 337.669378 -232.323894) (xy 337.669378 -232.279698) (xy 337.313778 -232.279698) (xy 337.313778 -232.323894)
			(xy 337.360768 -232.476294) (xy 337.622388 -232.476294)
		)
		(stroke
			(width 0)
			(type solid)
		)
		(fill yes)
		(layer "In4.Cu")
		(net "M_C_CPU0_SB_DQ<16>")
	)
	(gr_poly
		(pts
			(xy 337.669378 -229.477062) (xy 337.622388 -229.324662) (xy 337.360768 -229.324662) (xy 337.313778 -229.477062)
			(xy 337.313778 -229.521512) (xy 337.669378 -229.521512)
		)
		(stroke
			(width 0)
			(type solid)
		)
		(fill yes)
		(layer "In4.Cu")
		(net "M_C_CPU0_SB_DQS_DP<7>")
	)
	(gr_poly
		(pts
			(xy 337.673188 -243.718334) (xy 337.673188 -243.674138) (xy 337.317588 -243.674138) (xy 337.317588 -243.718334)
			(xy 337.364578 -243.870734) (xy 337.626198 -243.870734)
		)
		(stroke
			(width 0)
			(type solid)
		)
		(fill yes)
		(layer "In4.Cu")
		(net "M_C_CPU0_SB_CS_N<3>")
	)
	(gr_poly
		(pts
			(xy 337.674204 -281.155394) (xy 337.63585 -281.133296) (xy 337.480402 -281.097736) (xy 337.349592 -281.324304)
			(xy 337.45805 -281.441144) (xy 337.496404 -281.463242)
		)
		(stroke
			(width 0)
			(type solid)
		)
		(fill yes)
		(layer "In4.Cu")
		(net "M_C_CPU0_SA_DQS_DN<0>")
	)
	(gr_poly
		(pts
			(xy 337.676744 -284.406848) (xy 337.63839 -284.38475) (xy 337.482942 -284.34919) (xy 337.352132 -284.575758)
			(xy 337.46059 -284.692598) (xy 337.498944 -284.714696)
		)
		(stroke
			(width 0)
			(type solid)
		)
		(fill yes)
		(layer "In4.Cu")
		(net "M_C_CPU0_SA_DQ<2>")
	)
	(gr_poly
		(pts
			(xy 337.676744 -276.267926) (xy 337.63839 -276.245828) (xy 337.482942 -276.210268) (xy 337.352132 -276.436836)
			(xy 337.46059 -276.553676) (xy 337.498944 -276.575774)
		)
		(stroke
			(width 0)
			(type solid)
		)
		(fill yes)
		(layer "In4.Cu")
		(net "M_C_CPU0_SA_DQ<6>")
	)
	(gr_poly
		(pts
			(xy 337.678776 -277.891748) (xy 337.640422 -277.86965) (xy 337.484974 -277.83409) (xy 337.354164 -278.060658)
			(xy 337.462622 -278.177498) (xy 337.500976 -278.199596)
		)
		(stroke
			(width 0)
			(type solid)
		)
		(fill yes)
		(layer "In4.Cu")
		(net "M_C_CPU0_SA_DQS_DP<5>")
	)
	(gr_poly
		(pts
			(xy 337.678776 -246.974106) (xy 337.678776 -246.929656) (xy 337.323176 -246.929656) (xy 337.323176 -246.974106)
			(xy 337.370166 -247.126506) (xy 337.631786 -247.126506)
		)
		(stroke
			(width 0)
			(type solid)
		)
		(fill yes)
		(layer "In4.Cu")
		(net "M_C_CPU0_SB_CA<2>")
	)
	(gr_poly
		(pts
			(xy 337.681316 -245.754906) (xy 337.634326 -245.602506) (xy 337.372706 -245.602506) (xy 337.325716 -245.754906)
			(xy 337.325716 -245.799102) (xy 337.681316 -245.799102)
		)
		(stroke
			(width 0)
			(type solid)
		)
		(fill yes)
		(layer "In4.Cu")
		(net "M_C_CPU0_SB_CA<5>")
	)
	(gr_poly
		(pts
			(xy 337.681316 -245.346474) (xy 337.681316 -245.302278) (xy 337.325716 -245.302278) (xy 337.325716 -245.346474)
			(xy 337.372706 -245.498874) (xy 337.634326 -245.498874)
		)
		(stroke
			(width 0)
			(type solid)
		)
		(fill yes)
		(layer "In4.Cu")
		(net "M_C_CPU0_SB_CA<6>")
	)
	(gr_poly
		(pts
			(xy 337.681316 -244.126766) (xy 337.634326 -243.974366) (xy 337.372706 -243.974366) (xy 337.325716 -244.126766)
			(xy 337.325716 -244.171216) (xy 337.681316 -244.171216)
		)
		(stroke
			(width 0)
			(type solid)
		)
		(fill yes)
		(layer "In4.Cu")
		(net "M_C_CPU0_SB_CS_N<0>")
	)
	(gr_poly
		(pts
			(xy 337.681316 -242.090702) (xy 337.681316 -242.046506) (xy 337.325716 -242.046506) (xy 337.325716 -242.090702)
			(xy 337.372706 -242.243102) (xy 337.634326 -242.243102)
		)
		(stroke
			(width 0)
			(type solid)
		)
		(fill yes)
		(layer "In4.Cu")
		(net "M_C_CPU0_SB_CB<4>")
	)
	(gr_poly
		(pts
			(xy 337.681316 -240.46307) (xy 337.681316 -240.418874) (xy 337.325716 -240.418874) (xy 337.325716 -240.46307)
			(xy 337.372706 -240.61547) (xy 337.634326 -240.61547)
		)
		(stroke
			(width 0)
			(type solid)
		)
		(fill yes)
		(layer "In4.Cu")
		(net "M_C_CPU0_SB_DQS_DP<9>")
	)
	(gr_poly
		(pts
			(xy 337.681316 -239.243362) (xy 337.634326 -239.090962) (xy 337.372706 -239.090962) (xy 337.325716 -239.243362)
			(xy 337.325716 -239.287812) (xy 337.681316 -239.287812)
		)
		(stroke
			(width 0)
			(type solid)
		)
		(fill yes)
		(layer "In4.Cu")
		(net "M_C_CPU0_SB_DQS_DP<4>")
	)
	(gr_poly
		(pts
			(xy 337.681316 -237.207806) (xy 337.681316 -237.163356) (xy 337.325716 -237.163356) (xy 337.325716 -237.207806)
			(xy 337.372706 -237.360206) (xy 337.634326 -237.360206)
		)
		(stroke
			(width 0)
			(type solid)
		)
		(fill yes)
		(layer "In4.Cu")
		(net "M_B_CPU0_SB_DQ<2>")
	)
	(gr_poly
		(pts
			(xy 337.681316 -235.579666) (xy 337.681316 -235.53547) (xy 337.325716 -235.53547) (xy 337.325716 -235.579666)
			(xy 337.372706 -235.732066) (xy 337.634326 -235.732066)
		)
		(stroke
			(width 0)
			(type solid)
		)
		(fill yes)
		(layer "In4.Cu")
		(net "M_B_CPU0_SB_DQS_DP<0>")
	)
	(gr_poly
		(pts
			(xy 337.681316 -234.360466) (xy 337.634326 -234.208066) (xy 337.372706 -234.208066) (xy 337.325716 -234.360466)
			(xy 337.325716 -234.404662) (xy 337.681316 -234.404662)
		)
		(stroke
			(width 0)
			(type solid)
		)
		(fill yes)
		(layer "In4.Cu")
		(net "M_B_CPU0_SB_DQS_DP<5>")
	)
	(gr_poly
		(pts
			(xy 337.681316 -230.696262) (xy 337.681316 -230.652066) (xy 337.325716 -230.652066) (xy 337.325716 -230.696262)
			(xy 337.372706 -230.848662) (xy 337.634326 -230.848662)
		)
		(stroke
			(width 0)
			(type solid)
		)
		(fill yes)
		(layer "In4.Cu")
		(net "M_C_CPU0_SB_DQS_DP<2>")
	)
	(gr_poly
		(pts
			(xy 337.681316 -227.848922) (xy 337.634326 -227.696522) (xy 337.372706 -227.696522) (xy 337.325716 -227.848922)
			(xy 337.325716 -227.893372) (xy 337.681316 -227.893372)
		)
		(stroke
			(width 0)
			(type solid)
		)
		(fill yes)
		(layer "In4.Cu")
		(net "M_C_CPU0_SB_DQ<23>")
	)
	(gr_poly
		(pts
			(xy 337.77428 -283.01569) (xy 337.77428 -282.971494) (xy 337.41868 -282.971494) (xy 337.41868 -283.01569)
			(xy 337.46567 -283.16809) (xy 337.72729 -283.16809)
		)
		(stroke
			(width 0)
			(type solid)
		)
		(fill yes)
		(layer "In4.Cu")
		(net "M_C_CPU0_SA_DQS_DP<0>")
	)
	(gr_poly
		(pts
			(xy 337.782662 -283.424122) (xy 337.735672 -283.271722) (xy 337.474052 -283.271722) (xy 337.427062 -283.424122)
			(xy 337.427062 -283.468572) (xy 337.782662 -283.468572)
		)
		(stroke
			(width 0)
			(type solid)
		)
		(fill yes)
		(layer "In4.Cu")
		(net "M_C_CPU0_SA_DQ<3>")
	)
	(gr_poly
		(pts
			(xy 337.782662 -275.284946) (xy 337.735672 -275.132546) (xy 337.474052 -275.132546) (xy 337.427062 -275.284946)
			(xy 337.427062 -275.329396) (xy 337.782662 -275.329396)
		)
		(stroke
			(width 0)
			(type solid)
		)
		(fill yes)
		(layer "In4.Cu")
		(net "M_C_CPU0_SA_DQ<7>")
	)
	(gr_poly
		(pts
			(xy 337.782662 -274.876514) (xy 337.782662 -274.832064) (xy 337.427062 -274.832064) (xy 337.427062 -274.876514)
			(xy 337.474052 -275.028914) (xy 337.735672 -275.028914)
		)
		(stroke
			(width 0)
			(type solid)
		)
		(fill yes)
		(layer "In4.Cu")
		(net "M_B_CPU0_SA_DQ<8>")
	)
	(gr_poly
		(pts
			(xy 337.782662 -273.657314) (xy 337.735672 -273.504914) (xy 337.474052 -273.504914) (xy 337.427062 -273.657314)
			(xy 337.427062 -273.701764) (xy 337.782662 -273.701764)
		)
		(stroke
			(width 0)
			(type solid)
		)
		(fill yes)
		(layer "In4.Cu")
		(net "M_B_CPU0_SA_DQ<11>")
	)
	(gr_poly
		(pts
			(xy 337.782662 -273.248882) (xy 337.782662 -273.204432) (xy 337.427062 -273.204432) (xy 337.427062 -273.248882)
			(xy 337.474052 -273.401282) (xy 337.735672 -273.401282)
		)
		(stroke
			(width 0)
			(type solid)
		)
		(fill yes)
		(layer "In4.Cu")
		(net "M_B_CPU0_SA_DQS_DP<1>")
	)
	(gr_poly
		(pts
			(xy 337.782662 -269.99311) (xy 337.782662 -269.948914) (xy 337.427062 -269.948914) (xy 337.427062 -269.99311)
			(xy 337.474052 -270.14551) (xy 337.735672 -270.14551)
		)
		(stroke
			(width 0)
			(type solid)
		)
		(fill yes)
		(layer "In4.Cu")
		(net "M_C_CPU0_SA_DQ<16>")
	)
	(gr_poly
		(pts
			(xy 337.782662 -266.737846) (xy 337.782662 -266.693396) (xy 337.427062 -266.693396) (xy 337.427062 -266.737846)
			(xy 337.474052 -266.890246) (xy 337.735672 -266.890246)
		)
		(stroke
			(width 0)
			(type solid)
		)
		(fill yes)
		(layer "In4.Cu")
		(net "M_C_CPU0_SA_DQ<20>")
	)
	(gr_poly
		(pts
			(xy 337.782662 -265.109706) (xy 337.782662 -265.06551) (xy 337.427062 -265.06551) (xy 337.427062 -265.109706)
			(xy 337.474052 -265.262106) (xy 337.735672 -265.262106)
		)
		(stroke
			(width 0)
			(type solid)
		)
		(fill yes)
		(layer "In4.Cu")
		(net "M_B_CPU0_SA_DQ<26>")
	)
	(gr_poly
		(pts
			(xy 337.782662 -263.482074) (xy 337.782662 -263.437878) (xy 337.427062 -263.437878) (xy 337.427062 -263.482074)
			(xy 337.474052 -263.634474) (xy 337.735672 -263.634474)
		)
		(stroke
			(width 0)
			(type solid)
		)
		(fill yes)
		(layer "In4.Cu")
		(net "M_B_CPU0_SA_DQS_DP<3>")
	)
	(gr_poly
		(pts
			(xy 337.782662 -261.854442) (xy 337.782662 -261.809992) (xy 337.427062 -261.809992) (xy 337.427062 -261.854442)
			(xy 337.474052 -262.006842) (xy 337.735672 -262.006842)
		)
		(stroke
			(width 0)
			(type solid)
		)
		(fill yes)
		(layer "In4.Cu")
		(net "M_B_CPU0_SA_DQ<28>")
	)
	(gr_poly
		(pts
			(xy 337.782662 -258.59867) (xy 337.782662 -258.554474) (xy 337.427062 -258.554474) (xy 337.427062 -258.59867)
			(xy 337.474052 -258.75107) (xy 337.735672 -258.75107)
		)
		(stroke
			(width 0)
			(type solid)
		)
		(fill yes)
		(layer "In4.Cu")
		(net "M_C_CPU0_SA_CS_N<0>")
	)
	(gr_poly
		(pts
			(xy 337.782662 -257.37947) (xy 337.735672 -257.22707) (xy 337.474052 -257.22707) (xy 337.427062 -257.37947)
			(xy 337.427062 -257.42392) (xy 337.782662 -257.42392)
		)
		(stroke
			(width 0)
			(type solid)
		)
		(fill yes)
		(layer "In4.Cu")
		(net "M_C_CPU0_SA_CS_N<3>")
	)
	(gr_poly
		(pts
			(xy 337.782662 -256.971038) (xy 337.782662 -256.926588) (xy 337.427062 -256.926588) (xy 337.427062 -256.971038)
			(xy 337.474052 -257.123438) (xy 337.735672 -257.123438)
		)
		(stroke
			(width 0)
			(type solid)
		)
		(fill yes)
		(layer "In4.Cu")
		(net "M_C_CPU0_SA_CA<0>")
	)
	(gr_poly
		(pts
			(xy 337.782662 -254.124206) (xy 337.735672 -253.971806) (xy 337.474052 -253.971806) (xy 337.427062 -254.124206)
			(xy 337.427062 -254.168402) (xy 337.782662 -254.168402)
		)
		(stroke
			(width 0)
			(type solid)
		)
		(fill yes)
		(layer "In4.Cu")
		(net "M_C_CPU0_SA_PAR")
	)
	(gr_poly
		(pts
			(xy 337.782916 -271.620742) (xy 337.782916 -271.576546) (xy 337.427316 -271.576546) (xy 337.427316 -271.620742)
			(xy 337.474306 -271.773142) (xy 337.735926 -271.773142)
		)
		(stroke
			(width 0)
			(type solid)
		)
		(fill yes)
		(layer "In4.Cu")
		(net "M_B_CPU0_SA_DQ<12>")
	)
	(gr_poly
		(pts
			(xy 337.782916 -270.40205) (xy 337.735926 -270.24965) (xy 337.474306 -270.24965) (xy 337.427316 -270.40205)
			(xy 337.427316 -270.446246) (xy 337.782916 -270.446246)
		)
		(stroke
			(width 0)
			(type solid)
		)
		(fill yes)
		(layer "In4.Cu")
		(net "M_B_CPU0_SA_DQ<15>")
	)
	(gr_poly
		(pts
			(xy 337.782916 -268.77391) (xy 337.735926 -268.62151) (xy 337.474306 -268.62151) (xy 337.427316 -268.77391)
			(xy 337.427316 -268.81836) (xy 337.782916 -268.81836)
		)
		(stroke
			(width 0)
			(type solid)
		)
		(fill yes)
		(layer "In4.Cu")
		(net "M_C_CPU0_SA_DQ<19>")
	)
	(gr_poly
		(pts
			(xy 337.782916 -268.365478) (xy 337.782916 -268.321028) (xy 337.427316 -268.321028) (xy 337.427316 -268.365478)
			(xy 337.474306 -268.517878) (xy 337.735926 -268.517878)
		)
		(stroke
			(width 0)
			(type solid)
		)
		(fill yes)
		(layer "In4.Cu")
		(net "M_C_CPU0_SA_DQS_DP<2>")
	)
	(gr_poly
		(pts
			(xy 337.782916 -267.146278) (xy 337.735926 -266.993878) (xy 337.474306 -266.993878) (xy 337.427316 -267.146278)
			(xy 337.427316 -267.190728) (xy 337.782916 -267.190728)
		)
		(stroke
			(width 0)
			(type solid)
		)
		(fill yes)
		(layer "In4.Cu")
		(net "M_C_CPU0_SA_DQS_DP<7>")
	)
	(gr_poly
		(pts
			(xy 337.782916 -265.518646) (xy 337.735926 -265.366246) (xy 337.474306 -265.366246) (xy 337.427316 -265.518646)
			(xy 337.427316 -265.563096) (xy 337.782916 -265.563096)
		)
		(stroke
			(width 0)
			(type solid)
		)
		(fill yes)
		(layer "In4.Cu")
		(net "M_C_CPU0_SA_DQ<23>")
	)
	(gr_poly
		(pts
			(xy 337.782916 -263.891014) (xy 337.735926 -263.738614) (xy 337.474306 -263.738614) (xy 337.427316 -263.891014)
			(xy 337.427316 -263.93521) (xy 337.782916 -263.93521)
		)
		(stroke
			(width 0)
			(type solid)
		)
		(fill yes)
		(layer "In4.Cu")
		(net "M_B_CPU0_SA_DQ<27>")
	)
	(gr_poly
		(pts
			(xy 337.782916 -262.262874) (xy 337.735926 -262.110474) (xy 337.474306 -262.110474) (xy 337.427316 -262.262874)
			(xy 337.427316 -262.307324) (xy 337.782916 -262.307324)
		)
		(stroke
			(width 0)
			(type solid)
		)
		(fill yes)
		(layer "In4.Cu")
		(net "M_B_CPU0_SA_DQS_DP<8>")
	)
	(gr_poly
		(pts
			(xy 337.788758 -272.029682) (xy 337.741768 -271.877282) (xy 337.480148 -271.877282) (xy 337.433158 -272.029682)
			(xy 337.433158 -272.073878) (xy 337.788758 -272.073878)
		)
		(stroke
			(width 0)
			(type solid)
		)
		(fill yes)
		(layer "In4.Cu")
		(net "M_B_CPU0_SA_DQS_DP<6>")
	)
	(gr_poly
		(pts
			(xy 337.788758 -260.635242) (xy 337.741768 -260.482842) (xy 337.480148 -260.482842) (xy 337.433158 -260.635242)
			(xy 337.433158 -260.679438) (xy 337.788758 -260.679438)
		)
		(stroke
			(width 0)
			(type solid)
		)
		(fill yes)
		(layer "In4.Cu")
		(net "M_B_CPU0_SA_DQ<31>")
	)
	(gr_poly
		(pts
			(xy 337.788758 -255.751838) (xy 337.741768 -255.599438) (xy 337.480148 -255.599438) (xy 337.433158 -255.751838)
			(xy 337.433158 -255.796288) (xy 337.788758 -255.796288)
		)
		(stroke
			(width 0)
			(type solid)
		)
		(fill yes)
		(layer "In4.Cu")
		(net "M_C_CPU0_SA_CA<3>")
	)
	(gr_poly
		(pts
			(xy 337.788758 -255.343406) (xy 337.788758 -255.298956) (xy 337.433158 -255.298956) (xy 337.433158 -255.343406)
			(xy 337.480148 -255.495806) (xy 337.741768 -255.495806)
		)
		(stroke
			(width 0)
			(type solid)
		)
		(fill yes)
		(layer "In4.Cu")
		(net "M_C_CPU0_SA_CA<4>")
	)
	(gr_poly
		(pts
			(xy 337.857592 -285.119318) (xy 337.749134 -285.002478) (xy 337.71078 -284.98038) (xy 337.53298 -285.288228)
			(xy 337.571334 -285.310326) (xy 337.726782 -285.345886)
		)
		(stroke
			(width 0)
			(type solid)
		)
		(fill yes)
		(layer "In4.Cu")
		(net "M_C_CPU0_SA_DQ<0>")
	)
	(gr_poly
		(pts
			(xy 337.857592 -278.608282) (xy 337.749134 -278.491442) (xy 337.71078 -278.469344) (xy 337.53298 -278.777192)
			(xy 337.571334 -278.79929) (xy 337.726782 -278.83485)
		)
		(stroke
			(width 0)
			(type solid)
		)
		(fill yes)
		(layer "In4.Cu")
		(net "M_C_CPU0_SA_DQS_DN<5>")
	)
	(gr_poly
		(pts
			(xy 337.857592 -276.980396) (xy 337.749134 -276.863556) (xy 337.71078 -276.841458) (xy 337.53298 -277.149306)
			(xy 337.571334 -277.171404) (xy 337.726782 -277.206964)
		)
		(stroke
			(width 0)
			(type solid)
		)
		(fill yes)
		(layer "In4.Cu")
		(net "M_C_CPU0_SA_DQ<4>")
	)
	(gr_poly
		(pts
			(xy 338.10829 -279.613106) (xy 338.146644 -279.591008) (xy 337.968844 -279.28316) (xy 337.93049 -279.305258)
			(xy 337.822032 -279.422098) (xy 337.952842 -279.648666)
		)
		(stroke
			(width 0)
			(type solid)
		)
		(fill yes)
		(layer "In4.Cu")
		(net "M_C_CPU0_SA_DQS_DN<0>")
	)
	(gr_poly
		(pts
			(xy 338.134198 -246.16029) (xy 338.134198 -246.116094) (xy 337.778598 -246.116094) (xy 337.778598 -246.16029)
			(xy 337.825588 -246.31269) (xy 338.087208 -246.31269)
		)
		(stroke
			(width 0)
			(type solid)
		)
		(fill yes)
		(layer "In4.Cu")
		(net "M_C_CPU0_SB_CA<4>")
	)
	(gr_poly
		(pts
			(xy 338.134198 -241.685318) (xy 338.087208 -241.532918) (xy 337.825588 -241.532918) (xy 337.778598 -241.685318)
			(xy 337.778598 -241.729514) (xy 338.134198 -241.729514)
		)
		(stroke
			(width 0)
			(type solid)
		)
		(fill yes)
		(layer "In4.Cu")
		(net "M_C_CPU0_SB_CB<6>")
	)
	(gr_poly
		(pts
			(xy 338.134198 -236.801914) (xy 338.087208 -236.649514) (xy 337.825588 -236.649514) (xy 337.778598 -236.801914)
			(xy 337.778598 -236.84611) (xy 338.134198 -236.84611)
		)
		(stroke
			(width 0)
			(type solid)
		)
		(fill yes)
		(layer "In4.Cu")
		(net "M_B_CPU0_SB_DQ<0>")
	)
	(gr_poly
		(pts
			(xy 338.134198 -228.254814) (xy 338.134198 -228.210618) (xy 337.778598 -228.210618) (xy 337.778598 -228.254814)
			(xy 337.825588 -228.407214) (xy 338.087208 -228.407214)
		)
		(stroke
			(width 0)
			(type solid)
		)
		(fill yes)
		(layer "In4.Cu")
		(net "M_C_CPU0_SB_DQ<21>")
	)
	(gr_poly
		(pts
			(xy 338.136738 -244.940582) (xy 338.089748 -244.788182) (xy 337.828128 -244.788182) (xy 337.781138 -244.940582)
			(xy 337.781138 -244.985032) (xy 338.136738 -244.985032)
		)
		(stroke
			(width 0)
			(type solid)
		)
		(fill yes)
		(layer "In4.Cu")
		(net "M_C_CPU0_SB_PAR")
	)
	(gr_poly
		(pts
			(xy 338.136738 -240.057178) (xy 338.089748 -239.904778) (xy 337.828128 -239.904778) (xy 337.781138 -240.057178)
			(xy 337.781138 -240.101628) (xy 338.136738 -240.101628)
		)
		(stroke
			(width 0)
			(type solid)
		)
		(fill yes)
		(layer "In4.Cu")
		(net "M_C_CPU0_SB_DQS_DN<9>")
	)
	(gr_poly
		(pts
			(xy 338.136738 -239.649254) (xy 338.136738 -239.604804) (xy 337.781138 -239.604804) (xy 337.781138 -239.649254)
			(xy 337.828128 -239.801654) (xy 338.089748 -239.801654)
		)
		(stroke
			(width 0)
			(type solid)
		)
		(fill yes)
		(layer "In4.Cu")
		(net "M_C_CPU0_SB_DQS_DN<4>")
	)
	(gr_poly
		(pts
			(xy 338.136738 -235.174282) (xy 338.089748 -235.021882) (xy 337.828128 -235.021882) (xy 337.781138 -235.174282)
			(xy 337.781138 -235.218478) (xy 338.136738 -235.218478)
		)
		(stroke
			(width 0)
			(type solid)
		)
		(fill yes)
		(layer "In4.Cu")
		(net "M_B_CPU0_SB_DQS_DN<0>")
	)
	(gr_poly
		(pts
			(xy 338.136738 -234.76585) (xy 338.136738 -234.721654) (xy 337.781138 -234.721654) (xy 337.781138 -234.76585)
			(xy 337.828128 -234.91825) (xy 338.089748 -234.91825)
		)
		(stroke
			(width 0)
			(type solid)
		)
		(fill yes)
		(layer "In4.Cu")
		(net "M_B_CPU0_SB_DQS_DN<5>")
	)
	(gr_poly
		(pts
			(xy 338.136738 -230.290878) (xy 338.089748 -230.138478) (xy 337.828128 -230.138478) (xy 337.781138 -230.290878)
			(xy 337.781138 -230.335074) (xy 338.136738 -230.335074)
		)
		(stroke
			(width 0)
			(type solid)
		)
		(fill yes)
		(layer "In4.Cu")
		(net "M_C_CPU0_SB_DQS_DN<2>")
	)
	(gr_poly
		(pts
			(xy 338.142326 -277.089108) (xy 338.103972 -277.06701) (xy 337.948524 -277.03145) (xy 337.817714 -277.258018)
			(xy 337.926172 -277.374858) (xy 337.964526 -277.396956)
		)
		(stroke
			(width 0)
			(type solid)
		)
		(fill yes)
		(layer "In4.Cu")
		(net "M_C_CPU0_SA_DQS_DP<5>")
	)
	(gr_poly
		(pts
			(xy 338.14258 -246.568722) (xy 338.09559 -246.416322) (xy 337.83397 -246.416322) (xy 337.78698 -246.568722)
			(xy 337.78698 -246.613172) (xy 338.14258 -246.613172)
		)
		(stroke
			(width 0)
			(type solid)
		)
		(fill yes)
		(layer "In4.Cu")
		(net "M_C_CPU0_SB_CA<3>")
	)
	(gr_poly
		(pts
			(xy 338.14258 -244.53215) (xy 338.14258 -244.487954) (xy 337.78698 -244.487954) (xy 337.78698 -244.53215)
			(xy 337.83397 -244.68455) (xy 338.09559 -244.68455)
		)
		(stroke
			(width 0)
			(type solid)
		)
		(fill yes)
		(layer "In4.Cu")
		(net "M_C_CPU0_SB_CS_N<2>")
	)
	(gr_poly
		(pts
			(xy 338.146136 -241.276886) (xy 338.146136 -241.232436) (xy 337.790536 -241.232436) (xy 337.790536 -241.276886)
			(xy 337.837526 -241.429286) (xy 338.099146 -241.429286)
		)
		(stroke
			(width 0)
			(type solid)
		)
		(fill yes)
		(layer "In4.Cu")
		(net "M_C_CPU0_SB_CB<5>")
	)
	(gr_poly
		(pts
			(xy 338.146136 -238.021114) (xy 338.146136 -237.976664) (xy 337.790536 -237.976664) (xy 337.790536 -238.021114)
			(xy 337.837526 -238.173514) (xy 338.099146 -238.173514)
		)
		(stroke
			(width 0)
			(type solid)
		)
		(fill yes)
		(layer "In4.Cu")
		(net "M_C_CPU0_SB_CB<1>")
	)
	(gr_poly
		(pts
			(xy 338.146136 -233.13771) (xy 338.146136 -233.093514) (xy 337.790536 -233.093514) (xy 337.790536 -233.13771)
			(xy 337.837526 -233.29011) (xy 338.099146 -233.29011)
		)
		(stroke
			(width 0)
			(type solid)
		)
		(fill yes)
		(layer "In4.Cu")
		(net "M_B_CPU0_SB_DQ<5>")
	)
	(gr_poly
		(pts
			(xy 338.146136 -231.919018) (xy 338.099146 -231.766618) (xy 337.837526 -231.766618) (xy 337.790536 -231.919018)
			(xy 337.790536 -231.963214) (xy 338.146136 -231.963214)
		)
		(stroke
			(width 0)
			(type solid)
		)
		(fill yes)
		(layer "In4.Cu")
		(net "M_C_CPU0_SB_DQ<18>")
	)
	(gr_poly
		(pts
			(xy 338.146136 -229.882446) (xy 338.146136 -229.837996) (xy 337.790536 -229.837996) (xy 337.790536 -229.882446)
			(xy 337.837526 -230.034846) (xy 338.099146 -230.034846)
		)
		(stroke
			(width 0)
			(type solid)
		)
		(fill yes)
		(layer "In4.Cu")
		(net "M_C_CPU0_SB_DQS_DN<7>")
	)
	(gr_poly
		(pts
			(xy 338.146644 -278.709628) (xy 338.10829 -278.68753) (xy 337.952842 -278.65197) (xy 337.822032 -278.878538)
			(xy 337.93049 -278.995378) (xy 337.968844 -279.017476)
		)
		(stroke
			(width 0)
			(type solid)
		)
		(fill yes)
		(layer "In4.Cu")
		(net "M_C_CPU0_SA_DQS_DN<0>")
	)
	(gr_poly
		(pts
			(xy 338.146898 -238.430054) (xy 338.099908 -238.277654) (xy 337.838288 -238.277654) (xy 337.791298 -238.430054)
			(xy 337.791298 -238.47425) (xy 338.146898 -238.47425)
		)
		(stroke
			(width 0)
			(type solid)
		)
		(fill yes)
		(layer "In4.Cu")
		(net "M_C_CPU0_SB_CB<2>")
	)
	(gr_poly
		(pts
			(xy 338.146898 -236.393482) (xy 338.146898 -236.349032) (xy 337.791298 -236.349032) (xy 337.791298 -236.393482)
			(xy 337.838288 -236.545882) (xy 338.099908 -236.545882)
		)
		(stroke
			(width 0)
			(type solid)
		)
		(fill yes)
		(layer "In4.Cu")
		(net "M_B_CPU0_SB_DQ<1>")
	)
	(gr_poly
		(pts
			(xy 338.146898 -233.54665) (xy 338.099908 -233.39425) (xy 337.838288 -233.39425) (xy 337.791298 -233.54665)
			(xy 337.791298 -233.5911) (xy 338.146898 -233.5911)
		)
		(stroke
			(width 0)
			(type solid)
		)
		(fill yes)
		(layer "In4.Cu")
		(net "M_B_CPU0_SB_DQ<6>")
	)
	(gr_poly
		(pts
			(xy 338.146898 -231.510078) (xy 338.146898 -231.465628) (xy 337.791298 -231.465628) (xy 337.791298 -231.510078)
			(xy 337.838288 -231.662478) (xy 338.099908 -231.662478)
		)
		(stroke
			(width 0)
			(type solid)
		)
		(fill yes)
		(layer "In4.Cu")
		(net "M_C_CPU0_SB_DQ<17>")
	)
	(gr_poly
		(pts
			(xy 338.146898 -228.663246) (xy 338.099908 -228.510846) (xy 337.838288 -228.510846) (xy 337.791298 -228.663246)
			(xy 337.791298 -228.707696) (xy 338.146898 -228.707696)
		)
		(stroke
			(width 0)
			(type solid)
		)
		(fill yes)
		(layer "In4.Cu")
		(net "M_C_CPU0_SB_DQ<22>")
	)
	(gr_poly
		(pts
			(xy 338.148676 -280.33345) (xy 338.110322 -280.311352) (xy 337.954874 -280.275792) (xy 337.824064 -280.50236)
			(xy 337.932522 -280.6192) (xy 337.970876 -280.641298)
		)
		(stroke
			(width 0)
			(type solid)
		)
		(fill yes)
		(layer "In4.Cu")
		(net "M_C_CPU0_SA_DQS_DN<0>")
	)
	(gr_poly
		(pts
			(xy 338.223606 -282.258008) (xy 338.332064 -282.141168) (xy 338.201254 -281.9146) (xy 338.045806 -281.95016)
			(xy 338.007452 -281.972258) (xy 338.185252 -282.280106)
		)
		(stroke
			(width 0)
			(type solid)
		)
		(fill yes)
		(layer "In4.Cu")
		(net "M_C_CPU0_SA_DQS_DP<0>")
	)
	(gr_poly
		(pts
			(xy 338.252562 -284.237938) (xy 338.205572 -284.085538) (xy 337.943952 -284.085538) (xy 337.896962 -284.237938)
			(xy 337.896962 -284.282388) (xy 338.252562 -284.282388)
		)
		(stroke
			(width 0)
			(type solid)
		)
		(fill yes)
		(layer "In4.Cu")
		(net "M_C_CPU0_SA_DQ<2>")
	)
	(gr_poly
		(pts
			(xy 338.252562 -283.829506) (xy 338.252562 -283.785056) (xy 337.896962 -283.785056) (xy 337.896962 -283.829506)
			(xy 337.943952 -283.981906) (xy 338.205572 -283.981906)
		)
		(stroke
			(width 0)
			(type solid)
		)
		(fill yes)
		(layer "In4.Cu")
		(net "M_C_CPU0_SA_DQ<1>")
	)
	(gr_poly
		(pts
			(xy 338.252562 -276.09927) (xy 338.205572 -275.94687) (xy 337.943952 -275.94687) (xy 337.896962 -276.09927)
			(xy 337.896962 -276.143466) (xy 338.252562 -276.143466)
		)
		(stroke
			(width 0)
			(type solid)
		)
		(fill yes)
		(layer "In4.Cu")
		(net "M_C_CPU0_SA_DQ<6>")
	)
	(gr_poly
		(pts
			(xy 338.252562 -275.690584) (xy 338.252562 -275.646134) (xy 337.896962 -275.646134) (xy 337.896962 -275.690584)
			(xy 337.943952 -275.842984) (xy 338.205572 -275.842984)
		)
		(stroke
			(width 0)
			(type solid)
		)
		(fill yes)
		(layer "In4.Cu")
		(net "M_C_CPU0_SA_DQ<5>")
	)
	(gr_poly
		(pts
			(xy 338.252562 -274.47113) (xy 338.205572 -274.31873) (xy 337.943952 -274.31873) (xy 337.896962 -274.47113)
			(xy 337.896962 -274.51558) (xy 338.252562 -274.51558)
		)
		(stroke
			(width 0)
			(type solid)
		)
		(fill yes)
		(layer "In4.Cu")
		(net "M_B_CPU0_SA_DQ<10>")
	)
	(gr_poly
		(pts
			(xy 338.252562 -274.062698) (xy 338.252562 -274.018248) (xy 337.896962 -274.018248) (xy 337.896962 -274.062698)
			(xy 337.943952 -274.215098) (xy 338.205572 -274.215098)
		)
		(stroke
			(width 0)
			(type solid)
		)
		(fill yes)
		(layer "In4.Cu")
		(net "M_B_CPU0_SA_DQ<9>")
	)
	(gr_poly
		(pts
			(xy 338.252562 -269.587726) (xy 338.205572 -269.435326) (xy 337.943952 -269.435326) (xy 337.896962 -269.587726)
			(xy 337.896962 -269.632176) (xy 338.252562 -269.632176)
		)
		(stroke
			(width 0)
			(type solid)
		)
		(fill yes)
		(layer "In4.Cu")
		(net "M_C_CPU0_SA_DQ<18>")
	)
	(gr_poly
		(pts
			(xy 338.252562 -266.332462) (xy 338.205572 -266.180062) (xy 337.943952 -266.180062) (xy 337.896962 -266.332462)
			(xy 337.896962 -266.376658) (xy 338.252562 -266.376658)
		)
		(stroke
			(width 0)
			(type solid)
		)
		(fill yes)
		(layer "In4.Cu")
		(net "M_C_CPU0_SA_DQ<22>")
	)
	(gr_poly
		(pts
			(xy 338.252562 -264.70483) (xy 338.205572 -264.55243) (xy 337.943952 -264.55243) (xy 337.896962 -264.70483)
			(xy 337.896962 -264.749026) (xy 338.252562 -264.749026)
		)
		(stroke
			(width 0)
			(type solid)
		)
		(fill yes)
		(layer "In4.Cu")
		(net "M_B_CPU0_SA_DQ<24>")
	)
	(gr_poly
		(pts
			(xy 338.252562 -261.449058) (xy 338.205572 -261.296658) (xy 337.943952 -261.296658) (xy 337.896962 -261.449058)
			(xy 337.896962 -261.493508) (xy 338.252562 -261.493508)
		)
		(stroke
			(width 0)
			(type solid)
		)
		(fill yes)
		(layer "In4.Cu")
		(net "M_B_CPU0_SA_DQ<30>")
	)
	(gr_poly
		(pts
			(xy 338.252562 -261.040626) (xy 338.252562 -260.996176) (xy 337.896962 -260.996176) (xy 337.896962 -261.040626)
			(xy 337.943952 -261.193026) (xy 338.205572 -261.193026)
		)
		(stroke
			(width 0)
			(type solid)
		)
		(fill yes)
		(layer "In4.Cu")
		(net "M_B_CPU0_SA_DQ<29>")
	)
	(gr_poly
		(pts
			(xy 338.252562 -256.565654) (xy 338.205572 -256.413254) (xy 337.943952 -256.413254) (xy 337.896962 -256.565654)
			(xy 337.896962 -256.610104) (xy 338.252562 -256.610104)
		)
		(stroke
			(width 0)
			(type solid)
		)
		(fill yes)
		(layer "In4.Cu")
		(net "M_C_CPU0_SA_CA<1>")
	)
	(gr_poly
		(pts
			(xy 338.252562 -256.157222) (xy 338.252562 -256.112772) (xy 337.896962 -256.112772) (xy 337.896962 -256.157222)
			(xy 337.943952 -256.309622) (xy 338.205572 -256.309622)
		)
		(stroke
			(width 0)
			(type solid)
		)
		(fill yes)
		(layer "In4.Cu")
		(net "M_C_CPU0_SA_CA<2>")
	)
	(gr_poly
		(pts
			(xy 338.252562 -254.938022) (xy 338.205572 -254.785622) (xy 337.943952 -254.785622) (xy 337.896962 -254.938022)
			(xy 337.896962 -254.982218) (xy 338.252562 -254.982218)
		)
		(stroke
			(width 0)
			(type solid)
		)
		(fill yes)
		(layer "In4.Cu")
		(net "M_C_CPU0_SA_CA<5>")
	)
	(gr_poly
		(pts
			(xy 338.252562 -254.529082) (xy 338.252562 -254.484886) (xy 337.896962 -254.484886) (xy 337.896962 -254.529082)
			(xy 337.943952 -254.681482) (xy 338.205572 -254.681482)
		)
		(stroke
			(width 0)
			(type solid)
		)
		(fill yes)
		(layer "In4.Cu")
		(net "M_C_CPU0_SA_CA<6>")
	)
	(gr_poly
		(pts
			(xy 338.254848 -271.215866) (xy 338.207858 -271.063466) (xy 337.946238 -271.063466) (xy 337.899248 -271.215866)
			(xy 337.899248 -271.260062) (xy 338.254848 -271.260062)
		)
		(stroke
			(width 0)
			(type solid)
		)
		(fill yes)
		(layer "In4.Cu")
		(net "M_B_CPU0_SA_DQ<14>")
	)
	(gr_poly
		(pts
			(xy 338.254848 -270.806926) (xy 338.254848 -270.76273) (xy 337.899248 -270.76273) (xy 337.899248 -270.806926)
			(xy 337.946238 -270.959326) (xy 338.207858 -270.959326)
		)
		(stroke
			(width 0)
			(type solid)
		)
		(fill yes)
		(layer "In4.Cu")
		(net "M_B_CPU0_SA_DQ<13>")
	)
	(gr_poly
		(pts
			(xy 338.254848 -269.179294) (xy 338.254848 -269.134844) (xy 337.899248 -269.134844) (xy 337.899248 -269.179294)
			(xy 337.946238 -269.331694) (xy 338.207858 -269.331694)
		)
		(stroke
			(width 0)
			(type solid)
		)
		(fill yes)
		(layer "In4.Cu")
		(net "M_C_CPU0_SA_DQ<17>")
	)
	(gr_poly
		(pts
			(xy 338.254848 -267.960094) (xy 338.207858 -267.807694) (xy 337.946238 -267.807694) (xy 337.899248 -267.960094)
			(xy 337.899248 -268.004544) (xy 338.254848 -268.004544)
		)
		(stroke
			(width 0)
			(type solid)
		)
		(fill yes)
		(layer "In4.Cu")
		(net "M_C_CPU0_SA_DQS_DN<2>")
	)
	(gr_poly
		(pts
			(xy 338.254848 -265.92403) (xy 338.254848 -265.87958) (xy 337.899248 -265.87958) (xy 337.899248 -265.92403)
			(xy 337.946238 -266.07643) (xy 338.207858 -266.07643)
		)
		(stroke
			(width 0)
			(type solid)
		)
		(fill yes)
		(layer "In4.Cu")
		(net "M_C_CPU0_SA_DQ<21>")
	)
	(gr_poly
		(pts
			(xy 338.254848 -264.29589) (xy 338.254848 -264.251694) (xy 337.899248 -264.251694) (xy 337.899248 -264.29589)
			(xy 337.946238 -264.44829) (xy 338.207858 -264.44829)
		)
		(stroke
			(width 0)
			(type solid)
		)
		(fill yes)
		(layer "In4.Cu")
		(net "M_B_CPU0_SA_DQ<25>")
	)
	(gr_poly
		(pts
			(xy 338.254848 -262.668258) (xy 338.254848 -262.623808) (xy 337.899248 -262.623808) (xy 337.899248 -262.668258)
			(xy 337.946238 -262.820658) (xy 338.207858 -262.820658)
		)
		(stroke
			(width 0)
			(type solid)
		)
		(fill yes)
		(layer "In4.Cu")
		(net "M_B_CPU0_SA_DQS_DN<8>")
	)
	(gr_poly
		(pts
			(xy 338.255864 -267.551154) (xy 338.255864 -267.506958) (xy 337.900264 -267.506958) (xy 337.900264 -267.551154)
			(xy 337.947254 -267.703554) (xy 338.208874 -267.703554)
		)
		(stroke
			(width 0)
			(type solid)
		)
		(fill yes)
		(layer "In4.Cu")
		(net "M_C_CPU0_SA_DQS_DN<7>")
	)
	(gr_poly
		(pts
			(xy 338.258658 -272.843498) (xy 338.211668 -272.691098) (xy 337.950048 -272.691098) (xy 337.903058 -272.843498)
			(xy 337.903058 -272.887694) (xy 338.258658 -272.887694)
		)
		(stroke
			(width 0)
			(type solid)
		)
		(fill yes)
		(layer "In4.Cu")
		(net "M_B_CPU0_SA_DQS_DN<1>")
	)
	(gr_poly
		(pts
			(xy 338.258658 -272.435066) (xy 338.258658 -272.39087) (xy 337.903058 -272.39087) (xy 337.903058 -272.435066)
			(xy 337.950048 -272.587466) (xy 338.211668 -272.587466)
		)
		(stroke
			(width 0)
			(type solid)
		)
		(fill yes)
		(layer "In4.Cu")
		(net "M_B_CPU0_SA_DQS_DN<6>")
	)
	(gr_poly
		(pts
			(xy 338.258658 -263.07669) (xy 338.211668 -262.92429) (xy 337.950048 -262.92429) (xy 337.903058 -263.07669)
			(xy 337.903058 -263.120886) (xy 338.258658 -263.120886)
		)
		(stroke
			(width 0)
			(type solid)
		)
		(fill yes)
		(layer "In4.Cu")
		(net "M_B_CPU0_SA_DQS_DN<3>")
	)
	(gr_poly
		(pts
			(xy 338.258658 -258.193286) (xy 338.211668 -258.040886) (xy 337.950048 -258.040886) (xy 337.903058 -258.193286)
			(xy 337.903058 -258.237482) (xy 338.258658 -258.237482)
		)
		(stroke
			(width 0)
			(type solid)
		)
		(fill yes)
		(layer "In4.Cu")
		(net "M_C_CPU0_SA_CS_N<2>")
	)
	(gr_poly
		(pts
			(xy 338.258658 -257.784854) (xy 338.258658 -257.740658) (xy 337.903058 -257.740658) (xy 337.903058 -257.784854)
			(xy 337.950048 -257.937254) (xy 338.211668 -257.937254)
		)
		(stroke
			(width 0)
			(type solid)
		)
		(fill yes)
		(layer "In4.Cu")
		(net "M_C_CPU0_SA_CS_N<1>")
	)
	(gr_poly
		(pts
			(xy 338.32673 -282.679648) (xy 338.218272 -282.562808) (xy 338.179918 -282.54071) (xy 338.002118 -282.848558)
			(xy 338.040472 -282.870656) (xy 338.19592 -282.906216)
		)
		(stroke
			(width 0)
			(type solid)
		)
		(fill yes)
		(layer "In4.Cu")
		(net "M_C_CPU0_SA_DQS_DP<0>")
	)
	(gr_poly
		(pts
			(xy 338.327492 -281.049984) (xy 338.219034 -280.933144) (xy 338.18068 -280.911046) (xy 338.00288 -281.218894)
			(xy 338.041234 -281.240992) (xy 338.196682 -281.276552)
		)
		(stroke
			(width 0)
			(type solid)
		)
		(fill yes)
		(layer "In4.Cu")
		(net "M_C_CPU0_SA_DQS_DP<0>")
	)
	(gr_poly
		(pts
			(xy 338.328254 -277.79345) (xy 338.219796 -277.67661) (xy 338.181442 -277.654512) (xy 338.003642 -277.96236)
			(xy 338.041996 -277.984458) (xy 338.197444 -278.020018)
		)
		(stroke
			(width 0)
			(type solid)
		)
		(fill yes)
		(layer "In4.Cu")
		(net "M_C_CPU0_SA_DQS_DN<5>")
	)
	(gr_poly
		(pts
			(xy 338.573872 -282.047696) (xy 338.612226 -282.025598) (xy 338.434426 -281.71775) (xy 338.396072 -281.739848)
			(xy 338.287614 -281.856688) (xy 338.418424 -282.083256)
		)
		(stroke
			(width 0)
			(type solid)
		)
		(fill yes)
		(layer "In4.Cu")
		(net "M_C_CPU0_SA_DQ<3>")
	)
	(gr_poly
		(pts
			(xy 338.573872 -259.258562) (xy 338.612226 -259.236464) (xy 338.434426 -258.928616) (xy 338.396072 -258.950714)
			(xy 338.287614 -259.067554) (xy 338.418424 -259.294122)
		)
		(stroke
			(width 0)
			(type solid)
		)
		(fill yes)
		(layer "In4.Cu")
		(net "M_C_CPU0_SA_CS_N<0>")
	)
	(gr_poly
		(pts
			(xy 338.604352 -235.579666) (xy 338.604352 -235.53547) (xy 338.248752 -235.53547) (xy 338.248752 -235.579666)
			(xy 338.295742 -235.732066) (xy 338.557362 -235.732066)
		)
		(stroke
			(width 0)
			(type solid)
		)
		(fill yes)
		(layer "In4.Cu")
		(net "M_B_CPU0_SB_DQS_DP<0>")
	)
	(gr_poly
		(pts
			(xy 338.604352 -230.696262) (xy 338.604352 -230.652066) (xy 338.248752 -230.652066) (xy 338.248752 -230.696262)
			(xy 338.295742 -230.848662) (xy 338.557362 -230.848662)
		)
		(stroke
			(width 0)
			(type solid)
		)
		(fill yes)
		(layer "In4.Cu")
		(net "M_C_CPU0_SB_DQS_DP<2>")
	)
	(gr_poly
		(pts
			(xy 338.606638 -245.346474) (xy 338.606638 -245.302024) (xy 338.251038 -245.302024) (xy 338.251038 -245.346474)
			(xy 338.298028 -245.498874) (xy 338.559648 -245.498874)
		)
		(stroke
			(width 0)
			(type solid)
		)
		(fill yes)
		(layer "In4.Cu")
		(net "M_C_CPU0_SB_CA<6>")
	)
	(gr_poly
		(pts
			(xy 338.608416 -238.83493) (xy 338.608416 -238.790734) (xy 338.252816 -238.790734) (xy 338.252816 -238.83493)
			(xy 338.299806 -238.98733) (xy 338.561426 -238.98733)
		)
		(stroke
			(width 0)
			(type solid)
		)
		(fill yes)
		(layer "In4.Cu")
		(net "M_C_CPU0_SB_CB<0>")
	)
	(gr_poly
		(pts
			(xy 338.608416 -235.988606) (xy 338.561426 -235.836206) (xy 338.299806 -235.836206) (xy 338.252816 -235.988606)
			(xy 338.252816 -236.032802) (xy 338.608416 -236.032802)
		)
		(stroke
			(width 0)
			(type solid)
		)
		(fill yes)
		(layer "In4.Cu")
		(net "M_B_CPU0_SB_DQ<3>")
	)
	(gr_poly
		(pts
			(xy 338.608416 -233.951526) (xy 338.608416 -233.90733) (xy 338.252816 -233.90733) (xy 338.252816 -233.951526)
			(xy 338.299806 -234.103926) (xy 338.561426 -234.103926)
		)
		(stroke
			(width 0)
			(type solid)
		)
		(fill yes)
		(layer "In4.Cu")
		(net "M_B_CPU0_SB_DQ<4>")
	)
	(gr_poly
		(pts
			(xy 338.608416 -231.105202) (xy 338.561426 -230.952802) (xy 338.299806 -230.952802) (xy 338.252816 -231.105202)
			(xy 338.252816 -231.149398) (xy 338.608416 -231.149398)
		)
		(stroke
			(width 0)
			(type solid)
		)
		(fill yes)
		(layer "In4.Cu")
		(net "M_C_CPU0_SB_DQ<19>")
	)
	(gr_poly
		(pts
			(xy 338.608416 -229.068122) (xy 338.608416 -229.023926) (xy 338.252816 -229.023926) (xy 338.252816 -229.068122)
			(xy 338.299806 -229.220522) (xy 338.561426 -229.220522)
		)
		(stroke
			(width 0)
			(type solid)
		)
		(fill yes)
		(layer "In4.Cu")
		(net "M_C_CPU0_SB_DQ<20>")
	)
	(gr_poly
		(pts
			(xy 338.609178 -240.871502) (xy 338.562188 -240.719102) (xy 338.300568 -240.719102) (xy 338.253578 -240.871502)
			(xy 338.253578 -240.915952) (xy 338.609178 -240.915952)
		)
		(stroke
			(width 0)
			(type solid)
		)
		(fill yes)
		(layer "In4.Cu")
		(net "M_C_CPU0_SB_CB<7>")
	)
	(gr_poly
		(pts
			(xy 338.609178 -237.616238) (xy 338.562188 -237.463838) (xy 338.300568 -237.463838) (xy 338.253578 -237.616238)
			(xy 338.253578 -237.660434) (xy 338.609178 -237.660434)
		)
		(stroke
			(width 0)
			(type solid)
		)
		(fill yes)
		(layer "In4.Cu")
		(net "M_C_CPU0_SB_CB<3>")
	)
	(gr_poly
		(pts
			(xy 338.609178 -232.732834) (xy 338.562188 -232.580434) (xy 338.300568 -232.580434) (xy 338.253578 -232.732834)
			(xy 338.253578 -232.77703) (xy 338.609178 -232.77703)
		)
		(stroke
			(width 0)
			(type solid)
		)
		(fill yes)
		(layer "In4.Cu")
		(net "M_B_CPU0_SB_DQ<7>")
	)
	(gr_poly
		(pts
			(xy 338.609178 -232.323894) (xy 338.609178 -232.279698) (xy 338.253578 -232.279698) (xy 338.253578 -232.323894)
			(xy 338.300568 -232.476294) (xy 338.562188 -232.476294)
		)
		(stroke
			(width 0)
			(type solid)
		)
		(fill yes)
		(layer "In4.Cu")
		(net "M_C_CPU0_SB_DQ<16>")
	)
	(gr_poly
		(pts
			(xy 338.609178 -229.477062) (xy 338.562188 -229.324662) (xy 338.300568 -229.324662) (xy 338.253578 -229.477062)
			(xy 338.253578 -229.521512) (xy 338.609178 -229.521512)
		)
		(stroke
			(width 0)
			(type solid)
		)
		(fill yes)
		(layer "In4.Cu")
		(net "M_C_CPU0_SB_DQS_DP<7>")
	)
	(gr_poly
		(pts
			(xy 338.612734 -239.24387) (xy 338.565744 -239.09147) (xy 338.304124 -239.09147) (xy 338.257134 -239.24387)
			(xy 338.257134 -239.288066) (xy 338.612734 -239.288066)
		)
		(stroke
			(width 0)
			(type solid)
		)
		(fill yes)
		(layer "In4.Cu")
		(net "M_C_CPU0_SB_DQS_DP<4>")
	)
	(gr_poly
		(pts
			(xy 338.612734 -234.360466) (xy 338.565744 -234.208066) (xy 338.304124 -234.208066) (xy 338.257134 -234.360466)
			(xy 338.257134 -234.404916) (xy 338.612734 -234.404916)
		)
		(stroke
			(width 0)
			(type solid)
		)
		(fill yes)
		(layer "In4.Cu")
		(net "M_B_CPU0_SB_DQS_DP<5>")
	)
	(gr_poly
		(pts
			(xy 338.616544 -281.15133) (xy 338.57819 -281.129232) (xy 338.422742 -281.093672) (xy 338.291932 -281.32024)
			(xy 338.40039 -281.43708) (xy 338.438744 -281.459178)
		)
		(stroke
			(width 0)
			(type solid)
		)
		(fill yes)
		(layer "In4.Cu")
		(net "M_C_CPU0_SA_DQ<3>")
	)
	(gr_poly
		(pts
			(xy 338.61756 -282.777184) (xy 338.579206 -282.755086) (xy 338.423758 -282.719526) (xy 338.292948 -282.946094)
			(xy 338.401406 -283.062934) (xy 338.43976 -283.085032)
		)
		(stroke
			(width 0)
			(type solid)
		)
		(fill yes)
		(layer "In4.Cu")
		(net "M_C_CPU0_SA_DQ<3>")
	)
	(gr_poly
		(pts
			(xy 338.61756 -277.89378) (xy 338.579206 -277.871682) (xy 338.423758 -277.836122) (xy 338.292948 -278.06269)
			(xy 338.401406 -278.17953) (xy 338.43976 -278.201628)
		)
		(stroke
			(width 0)
			(type solid)
		)
		(fill yes)
		(layer "In4.Cu")
		(net "M_C_CPU0_SA_DQS_DN<0>")
	)
	(gr_poly
		(pts
			(xy 338.618576 -246.974106) (xy 338.618576 -246.92991) (xy 338.262976 -246.92991) (xy 338.262976 -246.974106)
			(xy 338.309966 -247.126506) (xy 338.571586 -247.126506)
		)
		(stroke
			(width 0)
			(type solid)
		)
		(fill yes)
		(layer "In4.Cu")
		(net "M_C_CPU0_SB_CA<2>")
	)
	(gr_poly
		(pts
			(xy 338.618576 -245.754906) (xy 338.571586 -245.602506) (xy 338.309966 -245.602506) (xy 338.262976 -245.754906)
			(xy 338.262976 -245.799356) (xy 338.618576 -245.799356)
		)
		(stroke
			(width 0)
			(type solid)
		)
		(fill yes)
		(layer "In4.Cu")
		(net "M_C_CPU0_SB_CA<5>")
	)
	(gr_poly
		(pts
			(xy 338.621116 -242.090702) (xy 338.621116 -242.046506) (xy 338.265516 -242.046506) (xy 338.265516 -242.090702)
			(xy 338.312506 -242.243102) (xy 338.574126 -242.243102)
		)
		(stroke
			(width 0)
			(type solid)
		)
		(fill yes)
		(layer "In4.Cu")
		(net "M_C_CPU0_SB_CB<4>")
	)
	(gr_poly
		(pts
			(xy 338.621116 -237.207806) (xy 338.621116 -237.163356) (xy 338.265516 -237.163356) (xy 338.265516 -237.207806)
			(xy 338.312506 -237.360206) (xy 338.574126 -237.360206)
		)
		(stroke
			(width 0)
			(type solid)
		)
		(fill yes)
		(layer "In4.Cu")
		(net "M_B_CPU0_SB_DQ<2>")
	)
	(gr_poly
		(pts
			(xy 338.621116 -227.848922) (xy 338.574126 -227.696522) (xy 338.312506 -227.696522) (xy 338.265516 -227.848922)
			(xy 338.265516 -227.893372) (xy 338.621116 -227.893372)
		)
		(stroke
			(width 0)
			(type solid)
		)
		(fill yes)
		(layer "In4.Cu")
		(net "M_C_CPU0_SB_DQ<23>")
	)
	(gr_poly
		(pts
			(xy 338.688172 -258.646168) (xy 338.79663 -258.529328) (xy 338.66582 -258.30276) (xy 338.510372 -258.33832)
			(xy 338.472018 -258.360418) (xy 338.649818 -258.668266)
		)
		(stroke
			(width 0)
			(type solid)
		)
		(fill yes)
		(layer "In4.Cu")
		(net "M_C_CPU0_SA_CS_N<2>")
	)
	(gr_poly
		(pts
			(xy 338.695284 -279.819354) (xy 338.803742 -279.702514) (xy 338.672932 -279.475946) (xy 338.517484 -279.511506)
			(xy 338.47913 -279.533604) (xy 338.65693 -279.841452)
		)
		(stroke
			(width 0)
			(type solid)
		)
		(fill yes)
		(layer "In4.Cu")
		(net "M_C_CPU0_SA_DQS_DP<0>")
	)
	(gr_poly
		(pts
			(xy 338.71408 -276.912578) (xy 338.66709 -276.760178) (xy 338.40547 -276.760178) (xy 338.35848 -276.912578)
			(xy 338.35848 -276.957028) (xy 338.71408 -276.957028)
		)
		(stroke
			(width 0)
			(type solid)
		)
		(fill yes)
		(layer "In4.Cu")
		(net "M_C_CPU0_SA_DQS_DP<5>")
	)
	(gr_poly
		(pts
			(xy 338.71408 -272.029174) (xy 338.66709 -271.876774) (xy 338.40547 -271.876774) (xy 338.35848 -272.029174)
			(xy 338.35848 -272.073624) (xy 338.71408 -272.073624)
		)
		(stroke
			(width 0)
			(type solid)
		)
		(fill yes)
		(layer "In4.Cu")
		(net "M_B_CPU0_SA_DQS_DP<6>")
	)
	(gr_poly
		(pts
			(xy 338.71408 -257.37947) (xy 338.66709 -257.22707) (xy 338.40547 -257.22707) (xy 338.35848 -257.37947)
			(xy 338.35848 -257.423666) (xy 338.71408 -257.423666)
		)
		(stroke
			(width 0)
			(type solid)
		)
		(fill yes)
		(layer "In4.Cu")
		(net "M_C_CPU0_SA_CS_N<3>")
	)
	(gr_poly
		(pts
			(xy 338.714334 -273.248882) (xy 338.714334 -273.204686) (xy 338.358734 -273.204686) (xy 338.358734 -273.248882)
			(xy 338.405724 -273.401282) (xy 338.667344 -273.401282)
		)
		(stroke
			(width 0)
			(type solid)
		)
		(fill yes)
		(layer "In4.Cu")
		(net "M_B_CPU0_SA_DQS_DP<1>")
	)
	(gr_poly
		(pts
			(xy 338.714334 -268.365478) (xy 338.714334 -268.321282) (xy 338.358734 -268.321282) (xy 338.358734 -268.365478)
			(xy 338.405724 -268.517878) (xy 338.667344 -268.517878)
		)
		(stroke
			(width 0)
			(type solid)
		)
		(fill yes)
		(layer "In4.Cu")
		(net "M_C_CPU0_SA_DQS_DP<2>")
	)
	(gr_poly
		(pts
			(xy 338.718398 -267.146278) (xy 338.671408 -266.993878) (xy 338.409788 -266.993878) (xy 338.362798 -267.146278)
			(xy 338.362798 -267.190728) (xy 338.718398 -267.190728)
		)
		(stroke
			(width 0)
			(type solid)
		)
		(fill yes)
		(layer "In4.Cu")
		(net "M_C_CPU0_SA_DQS_DP<7>")
	)
	(gr_poly
		(pts
			(xy 338.71916 -271.620742) (xy 338.71916 -271.576546) (xy 338.36356 -271.576546) (xy 338.36356 -271.620742)
			(xy 338.41055 -271.773142) (xy 338.67217 -271.773142)
		)
		(stroke
			(width 0)
			(type solid)
		)
		(fill yes)
		(layer "In4.Cu")
		(net "M_B_CPU0_SA_DQ<12>")
	)
	(gr_poly
		(pts
			(xy 338.71916 -270.40205) (xy 338.67217 -270.24965) (xy 338.41055 -270.24965) (xy 338.36356 -270.40205)
			(xy 338.36356 -270.446246) (xy 338.71916 -270.446246)
		)
		(stroke
			(width 0)
			(type solid)
		)
		(fill yes)
		(layer "In4.Cu")
		(net "M_B_CPU0_SA_DQ<15>")
	)
	(gr_poly
		(pts
			(xy 338.71916 -268.77391) (xy 338.67217 -268.62151) (xy 338.41055 -268.62151) (xy 338.36356 -268.77391)
			(xy 338.36356 -268.81836) (xy 338.71916 -268.81836)
		)
		(stroke
			(width 0)
			(type solid)
		)
		(fill yes)
		(layer "In4.Cu")
		(net "M_C_CPU0_SA_DQ<19>")
	)
	(gr_poly
		(pts
			(xy 338.71916 -265.518646) (xy 338.67217 -265.366246) (xy 338.41055 -265.366246) (xy 338.36356 -265.518646)
			(xy 338.36356 -265.563096) (xy 338.71916 -265.563096)
		)
		(stroke
			(width 0)
			(type solid)
		)
		(fill yes)
		(layer "In4.Cu")
		(net "M_C_CPU0_SA_DQ<23>")
	)
	(gr_poly
		(pts
			(xy 338.71916 -263.891014) (xy 338.67217 -263.738614) (xy 338.41055 -263.738614) (xy 338.36356 -263.891014)
			(xy 338.36356 -263.93521) (xy 338.71916 -263.93521)
		)
		(stroke
			(width 0)
			(type solid)
		)
		(fill yes)
		(layer "In4.Cu")
		(net "M_B_CPU0_SA_DQ<27>")
	)
	(gr_poly
		(pts
			(xy 338.71916 -262.262874) (xy 338.67217 -262.110474) (xy 338.41055 -262.110474) (xy 338.36356 -262.262874)
			(xy 338.36356 -262.307324) (xy 338.71916 -262.307324)
		)
		(stroke
			(width 0)
			(type solid)
		)
		(fill yes)
		(layer "In4.Cu")
		(net "M_B_CPU0_SA_DQS_DP<8>")
	)
	(gr_poly
		(pts
			(xy 338.722462 -284.643068) (xy 338.722462 -284.598872) (xy 338.366862 -284.598872) (xy 338.366862 -284.643068)
			(xy 338.413852 -284.795468) (xy 338.675472 -284.795468)
		)
		(stroke
			(width 0)
			(type solid)
		)
		(fill yes)
		(layer "In4.Cu")
		(net "M_C_CPU0_SA_DQ<0>")
	)
	(gr_poly
		(pts
			(xy 338.722462 -276.504146) (xy 338.722462 -276.45995) (xy 338.366862 -276.45995) (xy 338.366862 -276.504146)
			(xy 338.413852 -276.656546) (xy 338.675472 -276.656546)
		)
		(stroke
			(width 0)
			(type solid)
		)
		(fill yes)
		(layer "In4.Cu")
		(net "M_C_CPU0_SA_DQ<4>")
	)
	(gr_poly
		(pts
			(xy 338.722462 -266.737846) (xy 338.722462 -266.693396) (xy 338.366862 -266.693396) (xy 338.366862 -266.737846)
			(xy 338.413852 -266.890246) (xy 338.675472 -266.890246)
		)
		(stroke
			(width 0)
			(type solid)
		)
		(fill yes)
		(layer "In4.Cu")
		(net "M_C_CPU0_SA_DQ<20>")
	)
	(gr_poly
		(pts
			(xy 338.722462 -261.854442) (xy 338.722462 -261.809992) (xy 338.366862 -261.809992) (xy 338.366862 -261.854442)
			(xy 338.413852 -262.006842) (xy 338.675472 -262.006842)
		)
		(stroke
			(width 0)
			(type solid)
		)
		(fill yes)
		(layer "In4.Cu")
		(net "M_B_CPU0_SA_DQ<28>")
	)
	(gr_poly
		(pts
			(xy 338.722462 -256.971038) (xy 338.722462 -256.926588) (xy 338.366862 -256.926588) (xy 338.366862 -256.971038)
			(xy 338.413852 -257.123438) (xy 338.675472 -257.123438)
		)
		(stroke
			(width 0)
			(type solid)
		)
		(fill yes)
		(layer "In4.Cu")
		(net "M_C_CPU0_SA_CA<0>")
	)
	(gr_poly
		(pts
			(xy 338.728558 -275.284946) (xy 338.681568 -275.132546) (xy 338.419948 -275.132546) (xy 338.372958 -275.284946)
			(xy 338.372958 -275.329142) (xy 338.728558 -275.329142)
		)
		(stroke
			(width 0)
			(type solid)
		)
		(fill yes)
		(layer "In4.Cu")
		(net "M_C_CPU0_SA_DQ<7>")
	)
	(gr_poly
		(pts
			(xy 338.728558 -274.876514) (xy 338.728558 -274.832318) (xy 338.372958 -274.832318) (xy 338.372958 -274.876514)
			(xy 338.419948 -275.028914) (xy 338.681568 -275.028914)
		)
		(stroke
			(width 0)
			(type solid)
		)
		(fill yes)
		(layer "In4.Cu")
		(net "M_B_CPU0_SA_DQ<8>")
	)
	(gr_poly
		(pts
			(xy 338.728558 -273.657314) (xy 338.681568 -273.504914) (xy 338.419948 -273.504914) (xy 338.372958 -273.657314)
			(xy 338.372958 -273.70151) (xy 338.728558 -273.70151)
		)
		(stroke
			(width 0)
			(type solid)
		)
		(fill yes)
		(layer "In4.Cu")
		(net "M_B_CPU0_SA_DQ<11>")
	)
	(gr_poly
		(pts
			(xy 338.728558 -269.993618) (xy 338.728558 -269.949168) (xy 338.372958 -269.949168) (xy 338.372958 -269.993618)
			(xy 338.419948 -270.146018) (xy 338.681568 -270.146018)
		)
		(stroke
			(width 0)
			(type solid)
		)
		(fill yes)
		(layer "In4.Cu")
		(net "M_C_CPU0_SA_DQ<16>")
	)
	(gr_poly
		(pts
			(xy 338.728558 -265.110214) (xy 338.728558 -265.065764) (xy 338.372958 -265.065764) (xy 338.372958 -265.110214)
			(xy 338.419948 -265.262614) (xy 338.681568 -265.262614)
		)
		(stroke
			(width 0)
			(type solid)
		)
		(fill yes)
		(layer "In4.Cu")
		(net "M_B_CPU0_SA_DQ<26>")
	)
	(gr_poly
		(pts
			(xy 338.728558 -260.634734) (xy 338.681568 -260.482334) (xy 338.419948 -260.482334) (xy 338.372958 -260.634734)
			(xy 338.372958 -260.679184) (xy 338.728558 -260.679184)
		)
		(stroke
			(width 0)
			(type solid)
		)
		(fill yes)
		(layer "In4.Cu")
		(net "M_B_CPU0_SA_DQ<31>")
	)
	(gr_poly
		(pts
			(xy 338.728558 -255.751838) (xy 338.681568 -255.599438) (xy 338.419948 -255.599438) (xy 338.372958 -255.751838)
			(xy 338.372958 -255.796034) (xy 338.728558 -255.796034)
		)
		(stroke
			(width 0)
			(type solid)
		)
		(fill yes)
		(layer "In4.Cu")
		(net "M_C_CPU0_SA_CA<3>")
	)
	(gr_poly
		(pts
			(xy 338.728558 -255.343406) (xy 338.728558 -255.29921) (xy 338.372958 -255.29921) (xy 338.372958 -255.343406)
			(xy 338.419948 -255.495806) (xy 338.681568 -255.495806)
		)
		(stroke
			(width 0)
			(type solid)
		)
		(fill yes)
		(layer "In4.Cu")
		(net "M_C_CPU0_SA_CA<4>")
	)
	(gr_poly
		(pts
			(xy 338.728558 -254.123698) (xy 338.681568 -253.971298) (xy 338.419948 -253.971298) (xy 338.372958 -254.123698)
			(xy 338.372958 -254.168148) (xy 338.728558 -254.168148)
		)
		(stroke
			(width 0)
			(type solid)
		)
		(fill yes)
		(layer "In4.Cu")
		(net "M_C_CPU0_SA_PAR")
	)
	(gr_poly
		(pts
			(xy 338.797392 -278.608282) (xy 338.688934 -278.491442) (xy 338.65058 -278.469344) (xy 338.47278 -278.777192)
			(xy 338.511134 -278.79929) (xy 338.666582 -278.83485)
		)
		(stroke
			(width 0)
			(type solid)
		)
		(fill yes)
		(layer "In4.Cu")
		(net "M_C_CPU0_SA_DQS_DP<0>")
	)
	(gr_poly
		(pts
			(xy 338.798154 -280.235152) (xy 338.689696 -280.118312) (xy 338.651342 -280.096214) (xy 338.473542 -280.404062)
			(xy 338.511896 -280.42616) (xy 338.667344 -280.46172)
		)
		(stroke
			(width 0)
			(type solid)
		)
		(fill yes)
		(layer "In4.Cu")
		(net "M_C_CPU0_SA_DQS_DP<0>")
	)
	(gr_poly
		(pts
			(xy 338.803742 -283.481526) (xy 338.695284 -283.364686) (xy 338.65693 -283.342588) (xy 338.47913 -283.650436)
			(xy 338.517484 -283.672534) (xy 338.672932 -283.708094)
		)
		(stroke
			(width 0)
			(type solid)
		)
		(fill yes)
		(layer "In4.Cu")
		(net "M_C_CPU0_SA_DQ<1>")
	)
	(gr_poly
		(pts
			(xy 339.043772 -279.605994) (xy 339.082126 -279.583896) (xy 338.904326 -279.276048) (xy 338.865972 -279.298146)
			(xy 338.757514 -279.414986) (xy 338.888324 -279.641554)
		)
		(stroke
			(width 0)
			(type solid)
		)
		(fill yes)
		(layer "In4.Cu")
		(net "M_C_CPU0_SA_DQ<3>")
	)
	(gr_poly
		(pts
			(xy 339.073998 -246.568722) (xy 339.027008 -246.416322) (xy 338.765388 -246.416322) (xy 338.718398 -246.568722)
			(xy 338.718398 -246.612918) (xy 339.073998 -246.612918)
		)
		(stroke
			(width 0)
			(type solid)
		)
		(fill yes)
		(layer "In4.Cu")
		(net "M_C_CPU0_SB_CA<3>")
	)
	(gr_poly
		(pts
			(xy 339.073998 -241.685318) (xy 339.027008 -241.532918) (xy 338.765388 -241.532918) (xy 338.718398 -241.685318)
			(xy 338.718398 -241.729514) (xy 339.073998 -241.729514)
		)
		(stroke
			(width 0)
			(type solid)
		)
		(fill yes)
		(layer "In4.Cu")
		(net "M_C_CPU0_SB_CB<6>")
	)
	(gr_poly
		(pts
			(xy 339.073998 -236.801914) (xy 339.027008 -236.649514) (xy 338.765388 -236.649514) (xy 338.718398 -236.801914)
			(xy 338.718398 -236.84611) (xy 339.073998 -236.84611)
		)
		(stroke
			(width 0)
			(type solid)
		)
		(fill yes)
		(layer "In4.Cu")
		(net "M_B_CPU0_SB_DQ<0>")
	)
	(gr_poly
		(pts
			(xy 339.076538 -239.648746) (xy 339.076538 -239.60455) (xy 338.720938 -239.60455) (xy 338.720938 -239.648746)
			(xy 338.767928 -239.801146) (xy 339.029548 -239.801146)
		)
		(stroke
			(width 0)
			(type solid)
		)
		(fill yes)
		(layer "In4.Cu")
		(net "M_C_CPU0_SB_DQS_DN<4>")
	)
	(gr_poly
		(pts
			(xy 339.076538 -234.76585) (xy 339.076538 -234.7214) (xy 338.720938 -234.7214) (xy 338.720938 -234.76585)
			(xy 338.767928 -234.91825) (xy 339.029548 -234.91825)
		)
		(stroke
			(width 0)
			(type solid)
		)
		(fill yes)
		(layer "In4.Cu")
		(net "M_B_CPU0_SB_DQS_DN<5>")
	)
	(gr_poly
		(pts
			(xy 339.076538 -228.254814) (xy 339.076538 -228.210618) (xy 338.720938 -228.210618) (xy 338.720938 -228.254814)
			(xy 338.767928 -228.407214) (xy 339.029548 -228.407214)
		)
		(stroke
			(width 0)
			(type solid)
		)
		(fill yes)
		(layer "In4.Cu")
		(net "M_C_CPU0_SB_DQ<21>")
	)
	(gr_poly
		(pts
			(xy 339.08238 -246.16029) (xy 339.08238 -246.11584) (xy 338.72678 -246.11584) (xy 338.72678 -246.16029)
			(xy 338.77377 -246.31269) (xy 339.03539 -246.31269)
		)
		(stroke
			(width 0)
			(type solid)
		)
		(fill yes)
		(layer "In4.Cu")
		(net "M_C_CPU0_SB_CA<4>")
	)
	(gr_poly
		(pts
			(xy 339.085936 -238.021114) (xy 339.085936 -237.976664) (xy 338.730336 -237.976664) (xy 338.730336 -238.021114)
			(xy 338.777326 -238.173514) (xy 339.038946 -238.173514)
		)
		(stroke
			(width 0)
			(type solid)
		)
		(fill yes)
		(layer "In4.Cu")
		(net "M_C_CPU0_SB_CB<1>")
	)
	(gr_poly
		(pts
			(xy 339.085936 -233.13771) (xy 339.085936 -233.093514) (xy 338.730336 -233.093514) (xy 338.730336 -233.13771)
			(xy 338.777326 -233.29011) (xy 339.038946 -233.29011)
		)
		(stroke
			(width 0)
			(type solid)
		)
		(fill yes)
		(layer "In4.Cu")
		(net "M_B_CPU0_SB_DQ<5>")
	)
	(gr_poly
		(pts
			(xy 339.085936 -231.919018) (xy 339.038946 -231.766618) (xy 338.777326 -231.766618) (xy 338.730336 -231.919018)
			(xy 338.730336 -231.963214) (xy 339.085936 -231.963214)
		)
		(stroke
			(width 0)
			(type solid)
		)
		(fill yes)
		(layer "In4.Cu")
		(net "M_C_CPU0_SB_DQ<18>")
	)
	(gr_poly
		(pts
			(xy 339.085936 -229.882446) (xy 339.085936 -229.837996) (xy 338.730336 -229.837996) (xy 338.730336 -229.882446)
			(xy 338.777326 -230.034846) (xy 339.038946 -230.034846)
		)
		(stroke
			(width 0)
			(type solid)
		)
		(fill yes)
		(layer "In4.Cu")
		(net "M_C_CPU0_SB_DQS_DN<7>")
	)
	(gr_poly
		(pts
			(xy 339.086444 -283.593032) (xy 339.04809 -283.570934) (xy 338.892642 -283.535374) (xy 338.761832 -283.761942)
			(xy 338.87029 -283.878782) (xy 338.908644 -283.90088)
		)
		(stroke
			(width 0)
			(type solid)
		)
		(fill yes)
		(layer "In4.Cu")
		(net "M_C_CPU0_SA_DQ<2>")
	)
	(gr_poly
		(pts
			(xy 339.086444 -278.709628) (xy 339.04809 -278.68753) (xy 338.892642 -278.65197) (xy 338.761832 -278.878538)
			(xy 338.87029 -278.995378) (xy 338.908644 -279.017476)
		)
		(stroke
			(width 0)
			(type solid)
		)
		(fill yes)
		(layer "In4.Cu")
		(net "M_C_CPU0_SA_DQ<3>")
	)
	(gr_poly
		(pts
			(xy 339.086698 -238.430054) (xy 339.039708 -238.277654) (xy 338.778088 -238.277654) (xy 338.731098 -238.430054)
			(xy 338.731098 -238.47425) (xy 339.086698 -238.47425)
		)
		(stroke
			(width 0)
			(type solid)
		)
		(fill yes)
		(layer "In4.Cu")
		(net "M_C_CPU0_SB_CB<2>")
	)
	(gr_poly
		(pts
			(xy 339.086698 -236.393482) (xy 339.086698 -236.349032) (xy 338.731098 -236.349032) (xy 338.731098 -236.393482)
			(xy 338.778088 -236.545882) (xy 339.039708 -236.545882)
		)
		(stroke
			(width 0)
			(type solid)
		)
		(fill yes)
		(layer "In4.Cu")
		(net "M_B_CPU0_SB_DQ<1>")
	)
	(gr_poly
		(pts
			(xy 339.086698 -233.54665) (xy 339.039708 -233.39425) (xy 338.778088 -233.39425) (xy 338.731098 -233.54665)
			(xy 338.731098 -233.5911) (xy 339.086698 -233.5911)
		)
		(stroke
			(width 0)
			(type solid)
		)
		(fill yes)
		(layer "In4.Cu")
		(net "M_B_CPU0_SB_DQ<6>")
	)
	(gr_poly
		(pts
			(xy 339.086698 -231.510078) (xy 339.086698 -231.465628) (xy 338.731098 -231.465628) (xy 338.731098 -231.510078)
			(xy 338.778088 -231.662478) (xy 339.039708 -231.662478)
		)
		(stroke
			(width 0)
			(type solid)
		)
		(fill yes)
		(layer "In4.Cu")
		(net "M_C_CPU0_SB_DQ<17>")
	)
	(gr_poly
		(pts
			(xy 339.086698 -228.663246) (xy 339.039708 -228.510846) (xy 338.778088 -228.510846) (xy 338.731098 -228.663246)
			(xy 338.731098 -228.707696) (xy 339.086698 -228.707696)
		)
		(stroke
			(width 0)
			(type solid)
		)
		(fill yes)
		(layer "In4.Cu")
		(net "M_C_CPU0_SB_DQ<22>")
	)
	(gr_poly
		(pts
			(xy 339.08746 -280.335482) (xy 339.049106 -280.313384) (xy 338.893658 -280.277824) (xy 338.762848 -280.504392)
			(xy 338.871306 -280.621232) (xy 338.90966 -280.64333)
		)
		(stroke
			(width 0)
			(type solid)
		)
		(fill yes)
		(layer "In4.Cu")
		(net "M_C_CPU0_SA_DQ<3>")
	)
	(gr_poly
		(pts
			(xy 339.163406 -282.258008) (xy 339.271864 -282.141168) (xy 339.141054 -281.9146) (xy 338.985606 -281.95016)
			(xy 338.947252 -281.972258) (xy 339.125052 -282.280106)
		)
		(stroke
			(width 0)
			(type solid)
		)
		(fill yes)
		(layer "In4.Cu")
		(net "M_C_CPU0_SA_DQ<1>")
	)
	(gr_poly
		(pts
			(xy 339.163406 -257.841242) (xy 339.271864 -257.724402) (xy 339.141054 -257.497834) (xy 338.985606 -257.533394)
			(xy 338.947252 -257.555492) (xy 339.125052 -257.86334)
		)
		(stroke
			(width 0)
			(type solid)
		)
		(fill yes)
		(layer "In4.Cu")
		(net "M_C_CPU0_SA_CS_N<3>")
	)
	(gr_poly
		(pts
			(xy 339.18398 -275.690584) (xy 339.18398 -275.646388) (xy 338.82838 -275.646388) (xy 338.82838 -275.690584)
			(xy 338.87537 -275.842984) (xy 339.13699 -275.842984)
		)
		(stroke
			(width 0)
			(type solid)
		)
		(fill yes)
		(layer "In4.Cu")
		(net "M_C_CPU0_SA_DQ<5>")
	)
	(gr_poly
		(pts
			(xy 339.18398 -261.040626) (xy 339.18398 -260.99643) (xy 338.82838 -260.99643) (xy 338.82838 -261.040626)
			(xy 338.87537 -261.193026) (xy 339.13699 -261.193026)
		)
		(stroke
			(width 0)
			(type solid)
		)
		(fill yes)
		(layer "In4.Cu")
		(net "M_B_CPU0_SA_DQ<29>")
	)
	(gr_poly
		(pts
			(xy 339.18398 -256.157222) (xy 339.18398 -256.113026) (xy 338.82838 -256.113026) (xy 338.82838 -256.157222)
			(xy 338.87537 -256.309622) (xy 339.13699 -256.309622)
		)
		(stroke
			(width 0)
			(type solid)
		)
		(fill yes)
		(layer "In4.Cu")
		(net "M_C_CPU0_SA_CA<2>")
	)
	(gr_poly
		(pts
			(xy 339.18652 -274.47113) (xy 339.13953 -274.31873) (xy 338.87791 -274.31873) (xy 338.83092 -274.47113)
			(xy 338.83092 -274.515326) (xy 339.18652 -274.515326)
		)
		(stroke
			(width 0)
			(type solid)
		)
		(fill yes)
		(layer "In4.Cu")
		(net "M_B_CPU0_SA_DQ<10>")
	)
	(gr_poly
		(pts
			(xy 339.18652 -274.062698) (xy 339.18652 -274.018502) (xy 338.83092 -274.018502) (xy 338.83092 -274.062698)
			(xy 338.87791 -274.215098) (xy 339.13953 -274.215098)
		)
		(stroke
			(width 0)
			(type solid)
		)
		(fill yes)
		(layer "In4.Cu")
		(net "M_B_CPU0_SA_DQ<9>")
	)
	(gr_poly
		(pts
			(xy 339.18652 -269.587726) (xy 339.13953 -269.435326) (xy 338.87791 -269.435326) (xy 338.83092 -269.587726)
			(xy 338.83092 -269.631922) (xy 339.18652 -269.631922)
		)
		(stroke
			(width 0)
			(type solid)
		)
		(fill yes)
		(layer "In4.Cu")
		(net "M_C_CPU0_SA_DQ<18>")
	)
	(gr_poly
		(pts
			(xy 339.18652 -264.704322) (xy 339.13953 -264.551922) (xy 338.87791 -264.551922) (xy 338.83092 -264.704322)
			(xy 338.83092 -264.748772) (xy 339.18652 -264.748772)
		)
		(stroke
			(width 0)
			(type solid)
		)
		(fill yes)
		(layer "In4.Cu")
		(net "M_B_CPU0_SA_DQ<24>")
	)
	(gr_poly
		(pts
			(xy 339.18652 -259.412994) (xy 339.18652 -259.368544) (xy 338.83092 -259.368544) (xy 338.83092 -259.412994)
			(xy 338.87791 -259.565394) (xy 339.13953 -259.565394)
		)
		(stroke
			(width 0)
			(type solid)
		)
		(fill yes)
		(layer "In4.Cu")
		(net "M_C_CPU0_SA_CS_N<0>")
	)
	(gr_poly
		(pts
			(xy 339.18652 -254.937514) (xy 339.13953 -254.785114) (xy 338.87791 -254.785114) (xy 338.83092 -254.937514)
			(xy 338.83092 -254.981964) (xy 339.18652 -254.981964)
		)
		(stroke
			(width 0)
			(type solid)
		)
		(fill yes)
		(layer "In4.Cu")
		(net "M_C_CPU0_SA_CA<5>")
	)
	(gr_poly
		(pts
			(xy 339.192362 -276.09927) (xy 339.145372 -275.94687) (xy 338.883752 -275.94687) (xy 338.836762 -276.09927)
			(xy 338.836762 -276.143466) (xy 339.192362 -276.143466)
		)
		(stroke
			(width 0)
			(type solid)
		)
		(fill yes)
		(layer "In4.Cu")
		(net "M_C_CPU0_SA_DQ<6>")
	)
	(gr_poly
		(pts
			(xy 339.192362 -261.449058) (xy 339.145372 -261.296658) (xy 338.883752 -261.296658) (xy 338.836762 -261.449058)
			(xy 338.836762 -261.493508) (xy 339.192362 -261.493508)
		)
		(stroke
			(width 0)
			(type solid)
		)
		(fill yes)
		(layer "In4.Cu")
		(net "M_B_CPU0_SA_DQ<30>")
	)
	(gr_poly
		(pts
			(xy 339.192362 -256.565654) (xy 339.145372 -256.413254) (xy 338.883752 -256.413254) (xy 338.836762 -256.565654)
			(xy 338.836762 -256.610104) (xy 339.192362 -256.610104)
		)
		(stroke
			(width 0)
			(type solid)
		)
		(fill yes)
		(layer "In4.Cu")
		(net "M_C_CPU0_SA_CA<1>")
	)
	(gr_poly
		(pts
			(xy 339.195918 -270.806926) (xy 339.195918 -270.76273) (xy 338.840318 -270.76273) (xy 338.840318 -270.806926)
			(xy 338.887308 -270.959326) (xy 339.148928 -270.959326)
		)
		(stroke
			(width 0)
			(type solid)
		)
		(fill yes)
		(layer "In4.Cu")
		(net "M_B_CPU0_SA_DQ<13>")
	)
	(gr_poly
		(pts
			(xy 339.195918 -269.179294) (xy 339.195918 -269.134844) (xy 338.840318 -269.134844) (xy 338.840318 -269.179294)
			(xy 338.887308 -269.331694) (xy 339.148928 -269.331694)
		)
		(stroke
			(width 0)
			(type solid)
		)
		(fill yes)
		(layer "In4.Cu")
		(net "M_C_CPU0_SA_DQ<17>")
	)
	(gr_poly
		(pts
			(xy 339.195918 -266.332462) (xy 339.148928 -266.180062) (xy 338.887308 -266.180062) (xy 338.840318 -266.332462)
			(xy 338.840318 -266.376658) (xy 339.195918 -266.376658)
		)
		(stroke
			(width 0)
			(type solid)
		)
		(fill yes)
		(layer "In4.Cu")
		(net "M_C_CPU0_SA_DQ<22>")
	)
	(gr_poly
		(pts
			(xy 339.195918 -265.923522) (xy 339.195918 -265.879326) (xy 338.840318 -265.879326) (xy 338.840318 -265.923522)
			(xy 338.887308 -266.075922) (xy 339.148928 -266.075922)
		)
		(stroke
			(width 0)
			(type solid)
		)
		(fill yes)
		(layer "In4.Cu")
		(net "M_C_CPU0_SA_DQ<21>")
	)
	(gr_poly
		(pts
			(xy 339.195918 -264.29589) (xy 339.195918 -264.25144) (xy 338.840318 -264.25144) (xy 338.840318 -264.29589)
			(xy 338.887308 -264.44829) (xy 339.148928 -264.44829)
		)
		(stroke
			(width 0)
			(type solid)
		)
		(fill yes)
		(layer "In4.Cu")
		(net "M_B_CPU0_SA_DQ<25>")
	)
	(gr_poly
		(pts
			(xy 339.195918 -262.668258) (xy 339.195918 -262.623808) (xy 338.840318 -262.623808) (xy 338.840318 -262.668258)
			(xy 338.887308 -262.820658) (xy 339.148928 -262.820658)
		)
		(stroke
			(width 0)
			(type solid)
		)
		(fill yes)
		(layer "In4.Cu")
		(net "M_B_CPU0_SA_DQS_DN<8>")
	)
	(gr_poly
		(pts
			(xy 339.19668 -267.551154) (xy 339.19668 -267.506958) (xy 338.84108 -267.506958) (xy 338.84108 -267.551154)
			(xy 338.88807 -267.703554) (xy 339.14969 -267.703554)
		)
		(stroke
			(width 0)
			(type solid)
		)
		(fill yes)
		(layer "In4.Cu")
		(net "M_C_CPU0_SA_DQS_DN<7>")
	)
	(gr_poly
		(pts
			(xy 339.198458 -277.317962) (xy 339.198458 -277.273766) (xy 338.842858 -277.273766) (xy 338.842858 -277.317962)
			(xy 338.889848 -277.470362) (xy 339.151468 -277.470362)
		)
		(stroke
			(width 0)
			(type solid)
		)
		(fill yes)
		(layer "In4.Cu")
		(net "M_C_CPU0_SA_DQS_DN<5>")
	)
	(gr_poly
		(pts
			(xy 339.198458 -272.435066) (xy 339.198458 -272.390616) (xy 338.842858 -272.390616) (xy 338.842858 -272.435066)
			(xy 338.889848 -272.587466) (xy 339.151468 -272.587466)
		)
		(stroke
			(width 0)
			(type solid)
		)
		(fill yes)
		(layer "In4.Cu")
		(net "M_B_CPU0_SA_DQS_DN<6>")
	)
	(gr_poly
		(pts
			(xy 339.200998 -254.52959) (xy 339.200998 -254.48514) (xy 338.845398 -254.48514) (xy 338.845398 -254.52959)
			(xy 338.892388 -254.68199) (xy 339.154008 -254.68199)
		)
		(stroke
			(width 0)
			(type solid)
		)
		(fill yes)
		(layer "In4.Cu")
		(net "M_C_CPU0_SA_CA<6>")
	)
	(gr_poly
		(pts
			(xy 339.266276 -281.052524) (xy 339.157818 -280.935684) (xy 339.119464 -280.913586) (xy 338.941664 -281.221434)
			(xy 338.980018 -281.243532) (xy 339.135466 -281.279092)
		)
		(stroke
			(width 0)
			(type solid)
		)
		(fill yes)
		(layer "In4.Cu")
		(net "M_C_CPU0_SA_DQ<1>")
	)
	(gr_poly
		(pts
			(xy 339.26653 -282.679648) (xy 339.158072 -282.562808) (xy 339.119718 -282.54071) (xy 338.941918 -282.848558)
			(xy 338.980272 -282.870656) (xy 339.13572 -282.906216)
		)
		(stroke
			(width 0)
			(type solid)
		)
		(fill yes)
		(layer "In4.Cu")
		(net "M_C_CPU0_SA_DQ<1>")
	)
	(gr_poly
		(pts
			(xy 339.267292 -284.305502) (xy 339.158834 -284.188662) (xy 339.12048 -284.166564) (xy 338.94268 -284.474412)
			(xy 338.981034 -284.49651) (xy 339.136482 -284.53207)
		)
		(stroke
			(width 0)
			(type solid)
		)
		(fill yes)
		(layer "In4.Cu")
		(net "M_C_CPU0_SA_DQ<0>")
	)
	(gr_poly
		(pts
			(xy 339.546438 -227.84943) (xy 339.499448 -227.69703) (xy 339.237828 -227.69703) (xy 339.190838 -227.84943)
			(xy 339.190838 -227.893626) (xy 339.546438 -227.893626)
		)
		(stroke
			(width 0)
			(type solid)
		)
		(fill yes)
		(layer "In4.Cu")
		(net "M_C_CPU0_SB_DQ<23>")
	)
	(gr_poly
		(pts
			(xy 339.548978 -237.616238) (xy 339.501988 -237.463838) (xy 339.240368 -237.463838) (xy 339.193378 -237.616238)
			(xy 339.193378 -237.660434) (xy 339.548978 -237.660434)
		)
		(stroke
			(width 0)
			(type solid)
		)
		(fill yes)
		(layer "In4.Cu")
		(net "M_C_CPU0_SB_CB<3>")
	)
	(gr_poly
		(pts
			(xy 339.548978 -237.207298) (xy 339.548978 -237.163102) (xy 339.193378 -237.163102) (xy 339.193378 -237.207298)
			(xy 339.240368 -237.359698) (xy 339.501988 -237.359698)
		)
		(stroke
			(width 0)
			(type solid)
		)
		(fill yes)
		(layer "In4.Cu")
		(net "M_B_CPU0_SB_DQ<2>")
	)
	(gr_poly
		(pts
			(xy 339.548978 -232.732834) (xy 339.501988 -232.580434) (xy 339.240368 -232.580434) (xy 339.193378 -232.732834)
			(xy 339.193378 -232.77703) (xy 339.548978 -232.77703)
		)
		(stroke
			(width 0)
			(type solid)
		)
		(fill yes)
		(layer "In4.Cu")
		(net "M_B_CPU0_SB_DQ<7>")
	)
	(gr_poly
		(pts
			(xy 339.548978 -232.323894) (xy 339.548978 -232.279698) (xy 339.193378 -232.279698) (xy 339.193378 -232.323894)
			(xy 339.240368 -232.476294) (xy 339.501988 -232.476294)
		)
		(stroke
			(width 0)
			(type solid)
		)
		(fill yes)
		(layer "In4.Cu")
		(net "M_C_CPU0_SB_DQ<16>")
	)
	(gr_poly
		(pts
			(xy 339.552788 -244.127274) (xy 339.505798 -243.974874) (xy 339.244178 -243.974874) (xy 339.197188 -244.127274)
			(xy 339.197188 -244.17147) (xy 339.552788 -244.17147)
		)
		(stroke
			(width 0)
			(type solid)
		)
		(fill yes)
		(layer "In4.Cu")
		(net "M_C_CPU0_SB_CS_N<2>")
	)
	(gr_poly
		(pts
			(xy 339.55736 -282.777184) (xy 339.519006 -282.755086) (xy 339.363558 -282.719526) (xy 339.232748 -282.946094)
			(xy 339.341206 -283.062934) (xy 339.37956 -283.085032)
		)
		(stroke
			(width 0)
			(type solid)
		)
		(fill yes)
		(layer "In4.Cu")
		(net "M_C_CPU0_SA_DQ<2>")
	)
	(gr_poly
		(pts
			(xy 339.558376 -246.974106) (xy 339.558376 -246.929656) (xy 339.202776 -246.929656) (xy 339.202776 -246.974106)
			(xy 339.249766 -247.126506) (xy 339.511386 -247.126506)
		)
		(stroke
			(width 0)
			(type solid)
		)
		(fill yes)
		(layer "In4.Cu")
		(net "M_C_CPU0_SB_CA<2>")
	)
	(gr_poly
		(pts
			(xy 339.560916 -234.360466) (xy 339.513926 -234.208066) (xy 339.252306 -234.208066) (xy 339.205316 -234.360466)
			(xy 339.205316 -234.404662) (xy 339.560916 -234.404662)
		)
		(stroke
			(width 0)
			(type solid)
		)
		(fill yes)
		(layer "In4.Cu")
		(net "M_B_CPU0_SB_DQS_DP<5>")
	)
	(gr_poly
		(pts
			(xy 339.633306 -279.816306) (xy 339.741764 -279.699466) (xy 339.610954 -279.472898) (xy 339.455506 -279.508458)
			(xy 339.417152 -279.530556) (xy 339.594952 -279.838404)
		)
		(stroke
			(width 0)
			(type solid)
		)
		(fill yes)
		(layer "In4.Cu")
		(net "M_C_CPU0_SA_DQ<1>")
	)
	(gr_poly
		(pts
			(xy 339.65642 -274.876514) (xy 339.65642 -274.832064) (xy 339.30082 -274.832064) (xy 339.30082 -274.876514)
			(xy 339.34781 -275.028914) (xy 339.60943 -275.028914)
		)
		(stroke
			(width 0)
			(type solid)
		)
		(fill yes)
		(layer "In4.Cu")
		(net "M_B_CPU0_SA_DQ<8>")
	)
	(gr_poly
		(pts
			(xy 339.65642 -269.99311) (xy 339.65642 -269.948914) (xy 339.30082 -269.948914) (xy 339.30082 -269.99311)
			(xy 339.34781 -270.14551) (xy 339.60943 -270.14551)
		)
		(stroke
			(width 0)
			(type solid)
		)
		(fill yes)
		(layer "In4.Cu")
		(net "M_C_CPU0_SA_DQ<16>")
	)
	(gr_poly
		(pts
			(xy 339.65642 -265.109706) (xy 339.65642 -265.06551) (xy 339.30082 -265.06551) (xy 339.30082 -265.109706)
			(xy 339.34781 -265.262106) (xy 339.60943 -265.262106)
		)
		(stroke
			(width 0)
			(type solid)
		)
		(fill yes)
		(layer "In4.Cu")
		(net "M_B_CPU0_SA_DQ<26>")
	)
	(gr_poly
		(pts
			(xy 339.65642 -255.343406) (xy 339.65642 -255.298956) (xy 339.30082 -255.298956) (xy 339.30082 -255.343406)
			(xy 339.34781 -255.495806) (xy 339.60943 -255.495806)
		)
		(stroke
			(width 0)
			(type solid)
		)
		(fill yes)
		(layer "In4.Cu")
		(net "M_C_CPU0_SA_CA<4>")
	)
	(gr_poly
		(pts
			(xy 339.65896 -270.40205) (xy 339.61197 -270.24965) (xy 339.35035 -270.24965) (xy 339.30336 -270.40205)
			(xy 339.30336 -270.446246) (xy 339.65896 -270.446246)
		)
		(stroke
			(width 0)
			(type solid)
		)
		(fill yes)
		(layer "In4.Cu")
		(net "M_B_CPU0_SA_DQ<15>")
	)
	(gr_poly
		(pts
			(xy 339.65896 -265.518646) (xy 339.61197 -265.366246) (xy 339.35035 -265.366246) (xy 339.30336 -265.518646)
			(xy 339.30336 -265.563096) (xy 339.65896 -265.563096)
		)
		(stroke
			(width 0)
			(type solid)
		)
		(fill yes)
		(layer "In4.Cu")
		(net "M_C_CPU0_SA_DQ<23>")
	)
	(gr_poly
		(pts
			(xy 339.662516 -259.00761) (xy 339.615526 -258.85521) (xy 339.353906 -258.85521) (xy 339.306916 -259.00761)
			(xy 339.306916 -259.051806) (xy 339.662516 -259.051806)
		)
		(stroke
			(width 0)
			(type solid)
		)
		(fill yes)
		(layer "In4.Cu")
		(net "M_C_CPU0_SA_CS_N<2>")
	)
	(gr_poly
		(pts
			(xy 339.668358 -275.284946) (xy 339.621368 -275.132546) (xy 339.359748 -275.132546) (xy 339.312758 -275.284946)
			(xy 339.312758 -275.329396) (xy 339.668358 -275.329396)
		)
		(stroke
			(width 0)
			(type solid)
		)
		(fill yes)
		(layer "In4.Cu")
		(net "M_C_CPU0_SA_DQ<7>")
	)
	(gr_poly
		(pts
			(xy 339.668358 -260.635242) (xy 339.621368 -260.482842) (xy 339.359748 -260.482842) (xy 339.312758 -260.635242)
			(xy 339.312758 -260.679438) (xy 339.668358 -260.679438)
		)
		(stroke
			(width 0)
			(type solid)
		)
		(fill yes)
		(layer "In4.Cu")
		(net "M_B_CPU0_SA_DQ<31>")
	)
	(gr_poly
		(pts
			(xy 339.668358 -255.751838) (xy 339.621368 -255.599438) (xy 339.359748 -255.599438) (xy 339.312758 -255.751838)
			(xy 339.312758 -255.796288) (xy 339.668358 -255.796288)
		)
		(stroke
			(width 0)
			(type solid)
		)
		(fill yes)
		(layer "In4.Cu")
		(net "M_C_CPU0_SA_CA<3>")
	)
	(gr_poly
		(pts
			(xy 339.73643 -280.237946) (xy 339.627972 -280.121106) (xy 339.589618 -280.099008) (xy 339.411818 -280.406856)
			(xy 339.450172 -280.428954) (xy 339.60562 -280.464514)
		)
		(stroke
			(width 0)
			(type solid)
		)
		(fill yes)
		(layer "In4.Cu")
		(net "M_C_CPU0_SA_DQ<1>")
	)
	(gr_poly
		(pts
			(xy 339.737192 -283.491686) (xy 339.628734 -283.374846) (xy 339.59038 -283.352748) (xy 339.41258 -283.660596)
			(xy 339.450934 -283.682694) (xy 339.606382 -283.718254)
		)
		(stroke
			(width 0)
			(type solid)
		)
		(fill yes)
		(layer "In4.Cu")
		(net "M_C_CPU0_SA_DQ<0>")
	)
	(gr_poly
		(pts
			(xy 339.911944 -245.930928) (xy 339.87359 -245.90883) (xy 339.718142 -245.87327) (xy 339.587332 -246.099838)
			(xy 339.69579 -246.216678) (xy 339.734144 -246.238776)
		)
		(stroke
			(width 0)
			(type solid)
		)
		(fill yes)
		(layer "In4.Cu")
		(net "M_C_CPU0_SB_CA<3>")
	)
	(gr_poly
		(pts
			(xy 339.98916 -281.243532) (xy 340.027514 -281.221434) (xy 339.849714 -280.913586) (xy 339.81136 -280.935684)
			(xy 339.702902 -281.052524) (xy 339.833712 -281.279092)
		)
		(stroke
			(width 0)
			(type solid)
		)
		(fill yes)
		(layer "In4.Cu")
		(net "M_C_CPU0_SA_DQ<2>")
	)
	(gr_poly
		(pts
			(xy 340.016338 -244.532658) (xy 340.016338 -244.488208) (xy 339.660738 -244.488208) (xy 339.660738 -244.532658)
			(xy 339.707728 -244.685058) (xy 339.969348 -244.685058)
		)
		(stroke
			(width 0)
			(type solid)
		)
		(fill yes)
		(layer "In4.Cu")
		(net "M_C_CPU0_SB_PAR")
	)
	(gr_poly
		(pts
			(xy 340.016338 -243.313458) (xy 339.969348 -243.161058) (xy 339.707728 -243.161058) (xy 339.660738 -243.313458)
			(xy 339.660738 -243.357654) (xy 340.016338 -243.357654)
		)
		(stroke
			(width 0)
			(type solid)
		)
		(fill yes)
		(layer "In4.Cu")
		(net "M_C_CPU0_SB_CS_N<3>")
	)
	(gr_poly
		(pts
			(xy 340.021926 -268.949932) (xy 339.983572 -268.927834) (xy 339.828124 -268.892274) (xy 339.697314 -269.118842)
			(xy 339.805772 -269.235682) (xy 339.844126 -269.25778)
		)
		(stroke
			(width 0)
			(type solid)
		)
		(fill yes)
		(layer "In4.Cu")
		(net "M_C_CPU0_SA_DQ<18>")
	)
	(gr_poly
		(pts
			(xy 340.025736 -233.13771) (xy 340.025736 -233.093514) (xy 339.670136 -233.093514) (xy 339.670136 -233.13771)
			(xy 339.717126 -233.29011) (xy 339.978746 -233.29011)
		)
		(stroke
			(width 0)
			(type solid)
		)
		(fill yes)
		(layer "In4.Cu")
		(net "M_B_CPU0_SB_DQ<5>")
	)
	(gr_poly
		(pts
			(xy 340.026498 -233.54665) (xy 339.979508 -233.39425) (xy 339.717888 -233.39425) (xy 339.670898 -233.54665)
			(xy 339.670898 -233.5911) (xy 340.026498 -233.5911)
		)
		(stroke
			(width 0)
			(type solid)
		)
		(fill yes)
		(layer "In4.Cu")
		(net "M_B_CPU0_SB_DQ<6>")
	)
	(gr_poly
		(pts
			(xy 340.026498 -228.663246) (xy 339.979508 -228.510846) (xy 339.717888 -228.510846) (xy 339.670898 -228.663246)
			(xy 339.670898 -228.707696) (xy 340.026498 -228.707696)
		)
		(stroke
			(width 0)
			(type solid)
		)
		(fill yes)
		(layer "In4.Cu")
		(net "M_C_CPU0_SB_DQ<22>")
	)
	(gr_poly
		(pts
			(xy 340.027514 -281.962606) (xy 339.98916 -281.940508) (xy 339.833712 -281.904948) (xy 339.702902 -282.131516)
			(xy 339.81136 -282.248356) (xy 339.849714 -282.270454)
		)
		(stroke
			(width 0)
			(type solid)
		)
		(fill yes)
		(layer "In4.Cu")
		(net "M_C_CPU0_SA_DQ<2>")
	)
	(gr_poly
		(pts
			(xy 340.028276 -228.254814) (xy 340.028276 -228.210364) (xy 339.672676 -228.210364) (xy 339.672676 -228.254814)
			(xy 339.719666 -228.407214) (xy 339.981286 -228.407214)
		)
		(stroke
			(width 0)
			(type solid)
		)
		(fill yes)
		(layer "In4.Cu")
		(net "M_C_CPU0_SB_DQ<21>")
	)
	(gr_poly
		(pts
			(xy 340.02853 -280.33345) (xy 339.990176 -280.311352) (xy 339.834728 -280.275792) (xy 339.703918 -280.50236)
			(xy 339.812376 -280.6192) (xy 339.85073 -280.641298)
		)
		(stroke
			(width 0)
			(type solid)
		)
		(fill yes)
		(layer "In4.Cu")
		(net "M_C_CPU0_SA_DQ<2>")
	)
	(gr_poly
		(pts
			(xy 340.09711 -246.636286) (xy 339.988652 -246.519446) (xy 339.950298 -246.497348) (xy 339.772498 -246.805196)
			(xy 339.810852 -246.827294) (xy 339.9663 -246.862854)
		)
		(stroke
			(width 0)
			(type solid)
		)
		(fill yes)
		(layer "In4.Cu")
		(net "M_C_CPU0_SB_CA<2>")
	)
	(gr_poly
		(pts
			(xy 340.12378 -276.098762) (xy 340.07679 -275.946362) (xy 339.81517 -275.946362) (xy 339.76818 -276.098762)
			(xy 339.76818 -276.143212) (xy 340.12378 -276.143212)
		)
		(stroke
			(width 0)
			(type solid)
		)
		(fill yes)
		(layer "In4.Cu")
		(net "M_C_CPU0_SA_DQ<6>")
	)
	(gr_poly
		(pts
			(xy 340.12378 -261.449058) (xy 340.07679 -261.296658) (xy 339.81517 -261.296658) (xy 339.76818 -261.449058)
			(xy 339.76818 -261.493254) (xy 340.12378 -261.493254)
		)
		(stroke
			(width 0)
			(type solid)
		)
		(fill yes)
		(layer "In4.Cu")
		(net "M_B_CPU0_SA_DQ<30>")
	)
	(gr_poly
		(pts
			(xy 340.12632 -259.412486) (xy 340.12632 -259.36829) (xy 339.77072 -259.36829) (xy 339.77072 -259.412486)
			(xy 339.81771 -259.564886) (xy 340.07933 -259.564886)
		)
		(stroke
			(width 0)
			(type solid)
		)
		(fill yes)
		(layer "In4.Cu")
		(net "M_C_CPU0_SA_CS_N<0>")
	)
	(gr_poly
		(pts
			(xy 340.132162 -275.690584) (xy 340.132162 -275.646134) (xy 339.776562 -275.646134) (xy 339.776562 -275.690584)
			(xy 339.823552 -275.842984) (xy 340.085172 -275.842984)
		)
		(stroke
			(width 0)
			(type solid)
		)
		(fill yes)
		(layer "In4.Cu")
		(net "M_C_CPU0_SA_DQ<5>")
	)
	(gr_poly
		(pts
			(xy 340.132162 -261.040626) (xy 340.132162 -260.996176) (xy 339.776562 -260.996176) (xy 339.776562 -261.040626)
			(xy 339.823552 -261.193026) (xy 340.085172 -261.193026)
		)
		(stroke
			(width 0)
			(type solid)
		)
		(fill yes)
		(layer "In4.Cu")
		(net "M_B_CPU0_SA_DQ<29>")
	)
	(gr_poly
		(pts
			(xy 340.135718 -270.806926) (xy 340.135718 -270.76273) (xy 339.780118 -270.76273) (xy 339.780118 -270.806926)
			(xy 339.827108 -270.959326) (xy 340.088728 -270.959326)
		)
		(stroke
			(width 0)
			(type solid)
		)
		(fill yes)
		(layer "In4.Cu")
		(net "M_B_CPU0_SA_DQ<13>")
	)
	(gr_poly
		(pts
			(xy 340.20633 -282.679648) (xy 340.097872 -282.562808) (xy 340.059518 -282.54071) (xy 339.881718 -282.848558)
			(xy 339.920072 -282.870656) (xy 340.07552 -282.906216)
		)
		(stroke
			(width 0)
			(type solid)
		)
		(fill yes)
		(layer "In4.Cu")
		(net "M_C_CPU0_SA_DQ<0>")
	)
	(gr_poly
		(pts
			(xy 340.20633 -269.657322) (xy 340.097872 -269.540482) (xy 340.059518 -269.518384) (xy 339.881718 -269.826232)
			(xy 339.920072 -269.84833) (xy 340.07552 -269.88389)
		)
		(stroke
			(width 0)
			(type solid)
		)
		(fill yes)
		(layer "In4.Cu")
		(net "M_C_CPU0_SA_DQ<16>")
	)
	(gr_poly
		(pts
			(xy 340.453472 -256.003044) (xy 340.491826 -255.980946) (xy 340.314026 -255.673098) (xy 340.275672 -255.695196)
			(xy 340.167214 -255.812036) (xy 340.298024 -256.038604)
		)
		(stroke
			(width 0)
			(type solid)
		)
		(fill yes)
		(layer "In4.Cu")
		(net "M_C_CPU0_SA_CA<4>")
	)
	(gr_poly
		(pts
			(xy 340.45906 -254.385064) (xy 340.497414 -254.362966) (xy 340.319614 -254.055118) (xy 340.28126 -254.077216)
			(xy 340.172802 -254.194056) (xy 340.303612 -254.420624)
		)
		(stroke
			(width 0)
			(type solid)
		)
		(fill yes)
		(layer "In4.Cu")
		(net "M_C_CPU0_CLK_DP<1>")
	)
	(gr_poly
		(pts
			(xy 340.492334 -244.127274) (xy 340.445344 -243.974874) (xy 340.183724 -243.974874) (xy 340.136734 -244.127274)
			(xy 340.136734 -244.17147) (xy 340.492334 -244.17147)
		)
		(stroke
			(width 0)
			(type solid)
		)
		(fill yes)
		(layer "In4.Cu")
		(net "M_C_CPU0_SB_CS_N<2>")
	)
	(gr_poly
		(pts
			(xy 340.498176 -245.754906) (xy 340.451186 -245.602506) (xy 340.189566 -245.602506) (xy 340.142576 -245.754906)
			(xy 340.142576 -245.799356) (xy 340.498176 -245.799356)
		)
		(stroke
			(width 0)
			(type solid)
		)
		(fill yes)
		(layer "In4.Cu")
		(net "M_C_CPU0_SB_CA<3>")
	)
	(gr_poly
		(pts
			(xy 340.498176 -227.848922) (xy 340.451186 -227.696522) (xy 340.189566 -227.696522) (xy 340.142576 -227.848922)
			(xy 340.142576 -227.893372) (xy 340.498176 -227.893372)
		)
		(stroke
			(width 0)
			(type solid)
		)
		(fill yes)
		(layer "In4.Cu")
		(net "M_C_CPU0_SB_DQ<23>")
	)
	(gr_poly
		(pts
			(xy 340.567518 -281.43454) (xy 340.675976 -281.3177) (xy 340.545166 -281.091132) (xy 340.389718 -281.126692)
			(xy 340.351364 -281.14879) (xy 340.529164 -281.456638)
		)
		(stroke
			(width 0)
			(type solid)
		)
		(fill yes)
		(layer "In4.Cu")
		(net "M_C_CPU0_SA_DQ<0>")
	)
	(gr_poly
		(pts
			(xy 340.569296 -255.393444) (xy 340.677754 -255.276604) (xy 340.546944 -255.050036) (xy 340.391496 -255.085596)
			(xy 340.353142 -255.107694) (xy 340.530942 -255.415542)
		)
		(stroke
			(width 0)
			(type solid)
		)
		(fill yes)
		(layer "In4.Cu")
		(net "M_C_CPU0_SA_CA<5>")
	)
	(gr_poly
		(pts
			(xy 340.59876 -270.40205) (xy 340.55177 -270.24965) (xy 340.29015 -270.24965) (xy 340.24316 -270.40205)
			(xy 340.24316 -270.446246) (xy 340.59876 -270.446246)
		)
		(stroke
			(width 0)
			(type solid)
		)
		(fill yes)
		(layer "In4.Cu")
		(net "M_B_CPU0_SA_DQ<15>")
	)
	(gr_poly
		(pts
			(xy 340.608158 -275.284946) (xy 340.561168 -275.132546) (xy 340.299548 -275.132546) (xy 340.252558 -275.284946)
			(xy 340.252558 -275.329142) (xy 340.608158 -275.329142)
		)
		(stroke
			(width 0)
			(type solid)
		)
		(fill yes)
		(layer "In4.Cu")
		(net "M_C_CPU0_SA_DQ<7>")
	)
	(gr_poly
		(pts
			(xy 340.608158 -260.634734) (xy 340.561168 -260.482334) (xy 340.299548 -260.482334) (xy 340.252558 -260.634734)
			(xy 340.252558 -260.679184) (xy 340.608158 -260.679184)
		)
		(stroke
			(width 0)
			(type solid)
		)
		(fill yes)
		(layer "In4.Cu")
		(net "M_B_CPU0_SA_DQ<31>")
	)
	(gr_poly
		(pts
			(xy 340.610698 -268.77391) (xy 340.563708 -268.62151) (xy 340.302088 -268.62151) (xy 340.255098 -268.77391)
			(xy 340.255098 -268.818106) (xy 340.610698 -268.818106)
		)
		(stroke
			(width 0)
			(type solid)
		)
		(fill yes)
		(layer "In4.Cu")
		(net "M_C_CPU0_SA_DQ<18>")
	)
	(gr_poly
		(pts
			(xy 340.610698 -259.007102) (xy 340.563708 -258.854702) (xy 340.302088 -258.854702) (xy 340.255098 -259.007102)
			(xy 340.255098 -259.051552) (xy 340.610698 -259.051552)
		)
		(stroke
			(width 0)
			(type solid)
		)
		(fill yes)
		(layer "In4.Cu")
		(net "M_C_CPU0_SA_CS_N<2>")
	)
	(gr_poly
		(pts
			(xy 340.675214 -280.239978) (xy 340.566756 -280.123138) (xy 340.528402 -280.10104) (xy 340.350602 -280.408888)
			(xy 340.388956 -280.430986) (xy 340.544404 -280.466546)
		)
		(stroke
			(width 0)
			(type solid)
		)
		(fill yes)
		(layer "In4.Cu")
		(net "M_C_CPU0_SA_DQ<0>")
	)
	(gr_poly
		(pts
			(xy 340.675976 -281.86634) (xy 340.567518 -281.7495) (xy 340.529164 -281.727402) (xy 340.351364 -282.03525)
			(xy 340.389718 -282.057348) (xy 340.545166 -282.092908)
		)
		(stroke
			(width 0)
			(type solid)
		)
		(fill yes)
		(layer "In4.Cu")
		(net "M_C_CPU0_SA_DQ<0>")
	)
	(gr_poly
		(pts
			(xy 340.928706 -255.198372) (xy 340.96706 -255.176274) (xy 340.78926 -254.868426) (xy 340.750906 -254.890524)
			(xy 340.642448 -255.007364) (xy 340.773258 -255.233932)
		)
		(stroke
			(width 0)
			(type solid)
		)
		(fill yes)
		(layer "In4.Cu")
		(net "M_C_CPU0_CLK_DP<1>")
	)
	(gr_poly
		(pts
			(xy 340.96198 -244.53215) (xy 340.96198 -244.487954) (xy 340.60638 -244.487954) (xy 340.60638 -244.53215)
			(xy 340.65337 -244.68455) (xy 340.91499 -244.68455)
		)
		(stroke
			(width 0)
			(type solid)
		)
		(fill yes)
		(layer "In4.Cu")
		(net "M_C_CPU0_SB_PAR")
	)
	(gr_poly
		(pts
			(xy 341.037418 -254.576072) (xy 341.145876 -254.459232) (xy 341.015066 -254.232664) (xy 340.859618 -254.268224)
			(xy 340.821264 -254.290322) (xy 340.999064 -254.59817)
		)
		(stroke
			(width 0)
			(type solid)
		)
		(fill yes)
		(layer "In4.Cu")
		(net "M_C_CPU0_CLK_DN<1>")
	)
	(gr_poly
		(pts
			(xy 341.39886 -256.01295) (xy 341.437214 -255.990852) (xy 341.259414 -255.683004) (xy 341.22106 -255.705102)
			(xy 341.112602 -255.821942) (xy 341.243412 -256.04851)
		)
		(stroke
			(width 0)
			(type solid)
		)
		(fill yes)
		(layer "In4.Cu")
		(net "M_C_CPU0_CLK_DP<1>")
	)
	(gr_poly
		(pts
			(xy 341.39886 -254.385064) (xy 341.437214 -254.362966) (xy 341.259414 -254.055118) (xy 341.22106 -254.077216)
			(xy 341.112602 -254.194056) (xy 341.243412 -254.420624)
		)
		(stroke
			(width 0)
			(type solid)
		)
		(fill yes)
		(layer "In4.Cu")
		(net "M_C_CPU0_CLK_DP<0>")
	)
	(gr_poly
		(pts
			(xy 341.507572 -255.39065) (xy 341.61603 -255.27381) (xy 341.48522 -255.047242) (xy 341.329772 -255.082802)
			(xy 341.291418 -255.1049) (xy 341.469218 -255.412748)
		)
		(stroke
			(width 0)
			(type solid)
		)
		(fill yes)
		(layer "In4.Cu")
		(net "M_C_CPU0_CLK_DN<1>")
	)
	(gr_poly
		(pts
			(xy 341.861394 -256.814066) (xy 341.899748 -256.791968) (xy 341.721948 -256.48412) (xy 341.683594 -256.506218)
			(xy 341.575136 -256.623058) (xy 341.705946 -256.849626)
		)
		(stroke
			(width 0)
			(type solid)
		)
		(fill yes)
		(layer "In4.Cu")
		(net "M_C_CPU0_CLK_DP<1>")
	)
	(gr_poly
		(pts
			(xy 341.868506 -255.198372) (xy 341.90686 -255.176274) (xy 341.72906 -254.868426) (xy 341.690706 -254.890524)
			(xy 341.582248 -255.007364) (xy 341.713058 -255.233932)
		)
		(stroke
			(width 0)
			(type solid)
		)
		(fill yes)
		(layer "In4.Cu")
		(net "M_C_CPU0_CLK_DP<0>")
	)
	(gr_poly
		(pts
			(xy 341.982806 -256.213864) (xy 342.091264 -256.097024) (xy 341.960454 -255.870456) (xy 341.805006 -255.906016)
			(xy 341.766652 -255.928114) (xy 341.944452 -256.235962)
		)
		(stroke
			(width 0)
			(type solid)
		)
		(fill yes)
		(layer "In4.Cu")
		(net "M_C_CPU0_CLK_DN<1>")
	)
	(gr_poly
		(pts
			(xy 342.337644 -256.01041) (xy 342.375998 -255.988312) (xy 342.198198 -255.680464) (xy 342.159844 -255.702562)
			(xy 342.051386 -255.819402) (xy 342.182196 -256.04597)
		)
		(stroke
			(width 0)
			(type solid)
		)
		(fill yes)
		(layer "In4.Cu")
		(net "M_C_CPU0_CLK_DP<0>")
	)
	(gr_poly
		(pts
			(xy 342.447372 -255.39065) (xy 342.55583 -255.27381) (xy 342.42502 -255.047242) (xy 342.269572 -255.082802)
			(xy 342.231218 -255.1049) (xy 342.409018 -255.412748)
		)
		(stroke
			(width 0)
			(type solid)
		)
		(fill yes)
		(layer "In4.Cu")
		(net "M_C_CPU0_CLK_DN<0>")
	)
	(gr_poly
		(pts
			(xy 342.481916 -256.971038) (xy 342.481916 -256.926588) (xy 342.126316 -256.926588) (xy 342.126316 -256.971038)
			(xy 342.173306 -257.123438) (xy 342.434926 -257.123438)
		)
		(stroke
			(width 0)
			(type solid)
		)
		(fill yes)
		(layer "In4.Cu")
		(net "M_C_CPU0_CLK_DP<1>")
	)
	(gr_poly
		(pts
			(xy 342.94572 -256.565654) (xy 342.89873 -256.413254) (xy 342.63711 -256.413254) (xy 342.59012 -256.565654)
			(xy 342.59012 -256.610104) (xy 342.94572 -256.610104)
		)
		(stroke
			(width 0)
			(type solid)
		)
		(fill yes)
		(layer "In4.Cu")
		(net "M_C_CPU0_CLK_DN<1>")
	)
	(gr_poly
		(pts
			(xy 342.94572 -256.157222) (xy 342.94572 -256.112772) (xy 342.59012 -256.112772) (xy 342.59012 -256.157222)
			(xy 342.63711 -256.309622) (xy 342.89873 -256.309622)
		)
		(stroke
			(width 0)
			(type solid)
		)
		(fill yes)
		(layer "In4.Cu")
		(net "M_C_CPU0_CLK_DP<0>")
	)
	(gr_poly
		(pts
			(xy 343.430098 -256.971038) (xy 343.430098 -256.926842) (xy 343.074498 -256.926842) (xy 343.074498 -256.971038)
			(xy 343.121488 -257.123438) (xy 343.383108 -257.123438)
		)
		(stroke
			(width 0)
			(type solid)
		)
		(fill yes)
		(layer "In4.Cu")
		(net "M_C_CPU0_CLK_DP<1>")
	)
	(gr_poly
		(pts
			(xy 343.88298 -256.565654) (xy 343.83599 -256.413254) (xy 343.57437 -256.413254) (xy 343.52738 -256.565654)
			(xy 343.52738 -256.60985) (xy 343.88298 -256.60985)
		)
		(stroke
			(width 0)
			(type solid)
		)
		(fill yes)
		(layer "In4.Cu")
		(net "M_C_CPU0_CLK_DN<1>")
	)
	(gr_poly
		(pts
			(xy 344.369898 -256.971038) (xy 344.369898 -256.926842) (xy 344.014298 -256.926842) (xy 344.014298 -256.971038)
			(xy 344.061288 -257.123438) (xy 344.322908 -257.123438)
		)
		(stroke
			(width 0)
			(type solid)
		)
		(fill yes)
		(layer "In4.Cu")
		(net "M_C_CPU0_CLK_DP<1>")
	)
	(gr_poly
		(pts
			(xy 344.720926 -255.92786) (xy 344.682572 -255.905762) (xy 344.527124 -255.870202) (xy 344.396314 -256.09677)
			(xy 344.504772 -256.21361) (xy 344.543126 -256.235708)
		)
		(stroke
			(width 0)
			(type solid)
		)
		(fill yes)
		(layer "In4.Cu")
		(net "M_C_CPU0_CLK_DN<1>")
	)
	(gr_poly
		(pts
			(xy 344.905076 -256.635758) (xy 344.796618 -256.518918) (xy 344.758264 -256.49682) (xy 344.580464 -256.804668)
			(xy 344.618818 -256.826766) (xy 344.774266 -256.862326)
		)
		(stroke
			(width 0)
			(type solid)
		)
		(fill yes)
		(layer "In4.Cu")
		(net "M_C_CPU0_CLK_DP<1>")
	)
	(gr_poly
		(pts
			(xy 378.548138 -247.787922) (xy 378.548138 -247.743726) (xy 378.192538 -247.743726) (xy 378.192538 -247.787922)
			(xy 378.239528 -247.940322) (xy 378.501148 -247.940322)
		)
		(stroke
			(width 0)
			(type solid)
		)
		(fill yes)
		(layer "In4.Cu")
		(net "M_G_CPU0_SB_CA<6>")
	)
	(gr_poly
		(pts
			(xy 379.02388 -246.974106) (xy 379.02388 -246.929656) (xy 378.66828 -246.929656) (xy 378.66828 -246.974106)
			(xy 378.71527 -247.126506) (xy 378.97689 -247.126506)
		)
		(stroke
			(width 0)
			(type solid)
		)
		(fill yes)
		(layer "In4.Cu")
		(net "M_G_CPU0_SB_CS_N<2>")
	)
	(gr_poly
		(pts
			(xy 379.024134 -248.506742) (xy 379.024134 -248.462292) (xy 378.668534 -248.462292) (xy 378.668534 -248.506742)
			(xy 378.715524 -248.659142) (xy 378.977144 -248.659142)
		)
		(stroke
			(width 0)
			(type solid)
		)
		(fill yes)
		(layer "In4.Cu")
		(net "M_G_CPU0_SB_CA<4>")
	)
	(gr_poly
		(pts
			(xy 379.142498 -255.751838) (xy 379.095508 -255.599438) (xy 378.833888 -255.599438) (xy 378.786898 -255.751838)
			(xy 378.786898 -255.796034) (xy 379.142498 -255.796034)
		)
		(stroke
			(width 0)
			(type solid)
		)
		(fill yes)
		(layer "In4.Cu")
		(net "M_G_CPU0_SA_CA<0>")
	)
	(gr_poly
		(pts
			(xy 379.142498 -255.343406) (xy 379.142498 -255.29921) (xy 378.786898 -255.29921) (xy 378.786898 -255.343406)
			(xy 378.833888 -255.495806) (xy 379.095508 -255.495806)
		)
		(stroke
			(width 0)
			(type solid)
		)
		(fill yes)
		(layer "In4.Cu")
		(net "M_G_CPU0_SA_CA<3>")
	)
	(gr_poly
		(pts
			(xy 379.487938 -249.416062) (xy 379.487938 -249.371612) (xy 379.132338 -249.371612) (xy 379.132338 -249.416062)
			(xy 379.179328 -249.568462) (xy 379.440948 -249.568462)
		)
		(stroke
			(width 0)
			(type solid)
		)
		(fill yes)
		(layer "In4.Cu")
		(net "M_G_CPU0_SB_CA<2>")
	)
	(gr_poly
		(pts
			(xy 379.499876 -247.787922) (xy 379.499876 -247.743472) (xy 379.144276 -247.743472) (xy 379.144276 -247.787922)
			(xy 379.191266 -247.940322) (xy 379.452886 -247.940322)
		)
		(stroke
			(width 0)
			(type solid)
		)
		(fill yes)
		(layer "In4.Cu")
		(net "M_G_CPU0_SB_CA<6>")
	)
	(gr_poly
		(pts
			(xy 379.59538 -274.062698) (xy 379.59538 -274.018502) (xy 379.23978 -274.018502) (xy 379.23978 -274.062698)
			(xy 379.28677 -274.215098) (xy 379.54839 -274.215098)
		)
		(stroke
			(width 0)
			(type solid)
		)
		(fill yes)
		(layer "In4.Cu")
		(net "M_G_CPU0_SA_DQ<5>")
	)
	(gr_poly
		(pts
			(xy 379.59538 -256.565654) (xy 379.54839 -256.413254) (xy 379.28677 -256.413254) (xy 379.23978 -256.565654)
			(xy 379.23978 -256.60985) (xy 379.59538 -256.60985)
		)
		(stroke
			(width 0)
			(type solid)
		)
		(fill yes)
		(layer "In4.Cu")
		(net "M_G_CPU0_SA_CS_N<3>")
	)
	(gr_poly
		(pts
			(xy 379.59538 -256.157222) (xy 379.59538 -256.113026) (xy 379.23978 -256.113026) (xy 379.23978 -256.157222)
			(xy 379.28677 -256.309622) (xy 379.54839 -256.309622)
		)
		(stroke
			(width 0)
			(type solid)
		)
		(fill yes)
		(layer "In4.Cu")
		(net "M_G_CPU0_SA_CA<1>")
	)
	(gr_poly
		(pts
			(xy 379.59538 -254.937514) (xy 379.54839 -254.785114) (xy 379.28677 -254.785114) (xy 379.23978 -254.937514)
			(xy 379.23978 -254.981964) (xy 379.59538 -254.981964)
		)
		(stroke
			(width 0)
			(type solid)
		)
		(fill yes)
		(layer "In4.Cu")
		(net "M_G_CPU0_SA_CA<2>")
	)
	(gr_poly
		(pts
			(xy 379.59792 -277.317962) (xy 379.59792 -277.273766) (xy 379.24232 -277.273766) (xy 379.24232 -277.317962)
			(xy 379.28931 -277.470362) (xy 379.55093 -277.470362)
		)
		(stroke
			(width 0)
			(type solid)
		)
		(fill yes)
		(layer "In4.Cu")
		(net "M_G_CPU0_SA_DQ<0>")
	)
	(gr_poly
		(pts
			(xy 379.59792 -257.784854) (xy 379.59792 -257.740658) (xy 379.24232 -257.740658) (xy 379.24232 -257.784854)
			(xy 379.28931 -257.937254) (xy 379.55093 -257.937254)
		)
		(stroke
			(width 0)
			(type solid)
		)
		(fill yes)
		(layer "In4.Cu")
		(net "M_G_CPU0_SA_CS_N<0>")
	)
	(gr_poly
		(pts
			(xy 379.859032 -223.946212) (xy 379.820678 -223.924114) (xy 379.66523 -223.888554) (xy 379.53442 -224.115122)
			(xy 379.642878 -224.231962) (xy 379.681232 -224.25406)
		)
		(stroke
			(width 0)
			(type solid)
		)
		(fill yes)
		(layer "In4.Cu")
		(net "M_F_CPU0_SB_DQ<28>")
	)
	(gr_poly
		(pts
			(xy 379.955298 -246.974106) (xy 379.955298 -246.92991) (xy 379.599698 -246.92991) (xy 379.599698 -246.974106)
			(xy 379.646688 -247.126506) (xy 379.908308 -247.126506)
		)
		(stroke
			(width 0)
			(type solid)
		)
		(fill yes)
		(layer "In4.Cu")
		(net "M_G_CPU0_SB_CS_N<2>")
	)
	(gr_poly
		(pts
			(xy 379.959616 -244.127274) (xy 379.912626 -243.974874) (xy 379.651006 -243.974874) (xy 379.604016 -244.127274)
			(xy 379.604016 -244.171724) (xy 379.959616 -244.171724)
		)
		(stroke
			(width 0)
			(type solid)
		)
		(fill yes)
		(layer "In4.Cu")
		(net "M_G_CPU0_SB_CB<6>")
	)
	(gr_poly
		(pts
			(xy 379.959616 -238.83493) (xy 379.959616 -238.790734) (xy 379.604016 -238.790734) (xy 379.604016 -238.83493)
			(xy 379.651006 -238.98733) (xy 379.912626 -238.98733)
		)
		(stroke
			(width 0)
			(type solid)
		)
		(fill yes)
		(layer "In4.Cu")
		(net "M_F_CPU0_SB_DQ<1>")
	)
	(gr_poly
		(pts
			(xy 379.960378 -243.718334) (xy 379.960378 -243.674138) (xy 379.604778 -243.674138) (xy 379.604778 -243.718334)
			(xy 379.651768 -243.870734) (xy 379.913388 -243.870734)
		)
		(stroke
			(width 0)
			(type solid)
		)
		(fill yes)
		(layer "In4.Cu")
		(net "M_G_CPU0_SB_CB<5>")
	)
	(gr_poly
		(pts
			(xy 379.960378 -239.24387) (xy 379.913388 -239.09147) (xy 379.651768 -239.09147) (xy 379.604778 -239.24387)
			(xy 379.604778 -239.28832) (xy 379.960378 -239.28832)
		)
		(stroke
			(width 0)
			(type solid)
		)
		(fill yes)
		(layer "In4.Cu")
		(net "M_F_CPU0_SB_DQ<2>")
	)
	(gr_poly
		(pts
			(xy 379.963934 -249.010678) (xy 379.916944 -248.858278) (xy 379.655324 -248.858278) (xy 379.608334 -249.010678)
			(xy 379.608334 -249.054874) (xy 379.963934 -249.054874)
		)
		(stroke
			(width 0)
			(type solid)
		)
		(fill yes)
		(layer "In4.Cu")
		(net "M_G_CPU0_SB_CA<3>")
	)
	(gr_poly
		(pts
			(xy 379.963934 -234.360466) (xy 379.916944 -234.208066) (xy 379.655324 -234.208066) (xy 379.608334 -234.360466)
			(xy 379.608334 -234.404916) (xy 379.963934 -234.404916)
		)
		(stroke
			(width 0)
			(type solid)
		)
		(fill yes)
		(layer "In4.Cu")
		(net "M_G_CPU0_SB_DQ<18>")
	)
	(gr_poly
		(pts
			(xy 379.971808 -248.506742) (xy 379.971808 -248.462292) (xy 379.616208 -248.462292) (xy 379.616208 -248.506742)
			(xy 379.663198 -248.659142) (xy 379.924818 -248.659142)
		)
		(stroke
			(width 0)
			(type solid)
		)
		(fill yes)
		(layer "In4.Cu")
		(net "M_G_CPU0_SB_CA<4>")
	)
	(gr_poly
		(pts
			(xy 379.972316 -222.557594) (xy 379.972316 -222.513144) (xy 379.616716 -222.513144) (xy 379.616716 -222.557594)
			(xy 379.663706 -222.709994) (xy 379.925326 -222.709994)
		)
		(stroke
			(width 0)
			(type solid)
		)
		(fill yes)
		(layer "In4.Cu")
		(net "M_F_CPU0_SB_DQ<29>")
	)
	(gr_poly
		(pts
			(xy 380.06782 -257.37947) (xy 380.02083 -257.22707) (xy 379.75921 -257.22707) (xy 379.71222 -257.37947)
			(xy 379.71222 -257.42392) (xy 380.06782 -257.42392)
		)
		(stroke
			(width 0)
			(type solid)
		)
		(fill yes)
		(layer "In4.Cu")
		(net "M_G_CPU0_SA_CS_N<1>")
	)
	(gr_poly
		(pts
			(xy 380.069598 -267.146278) (xy 380.022608 -266.993878) (xy 379.760988 -266.993878) (xy 379.713998 -267.146278)
			(xy 379.713998 -267.190728) (xy 380.069598 -267.190728)
		)
		(stroke
			(width 0)
			(type solid)
		)
		(fill yes)
		(layer "In4.Cu")
		(net "M_G_CPU0_SA_DQ<18>")
	)
	(gr_poly
		(pts
			(xy 380.069598 -261.854442) (xy 380.069598 -261.809992) (xy 379.713998 -261.809992) (xy 379.713998 -261.854442)
			(xy 379.760988 -262.006842) (xy 380.022608 -262.006842)
		)
		(stroke
			(width 0)
			(type solid)
		)
		(fill yes)
		(layer "In4.Cu")
		(net "M_F_CPU0_SA_DQ<25>")
	)
	(gr_poly
		(pts
			(xy 380.07036 -276.504146) (xy 380.07036 -276.45995) (xy 379.71476 -276.45995) (xy 379.71476 -276.504146)
			(xy 379.76175 -276.656546) (xy 380.02337 -276.656546)
		)
		(stroke
			(width 0)
			(type solid)
		)
		(fill yes)
		(layer "In4.Cu")
		(net "M_G_CPU0_SA_DQ<1>")
	)
	(gr_poly
		(pts
			(xy 380.07036 -271.620742) (xy 380.07036 -271.576546) (xy 379.71476 -271.576546) (xy 379.71476 -271.620742)
			(xy 379.76175 -271.773142) (xy 380.02337 -271.773142)
		)
		(stroke
			(width 0)
			(type solid)
		)
		(fill yes)
		(layer "In4.Cu")
		(net "M_F_CPU0_SA_DQ<9>")
	)
	(gr_poly
		(pts
			(xy 380.07036 -266.737338) (xy 380.07036 -266.693142) (xy 379.71476 -266.693142) (xy 379.71476 -266.737338)
			(xy 379.76175 -266.889738) (xy 380.02337 -266.889738)
		)
		(stroke
			(width 0)
			(type solid)
		)
		(fill yes)
		(layer "In4.Cu")
		(net "M_G_CPU0_SA_DQ<17>")
	)
	(gr_poly
		(pts
			(xy 380.079758 -276.913086) (xy 380.032768 -276.760686) (xy 379.771148 -276.760686) (xy 379.724158 -276.913086)
			(xy 379.724158 -276.957282) (xy 380.079758 -276.957282)
		)
		(stroke
			(width 0)
			(type solid)
		)
		(fill yes)
		(layer "In4.Cu")
		(net "M_G_CPU0_SA_DQ<2>")
	)
	(gr_poly
		(pts
			(xy 380.079758 -256.971038) (xy 380.079758 -256.926588) (xy 379.724158 -256.926588) (xy 379.724158 -256.971038)
			(xy 379.771148 -257.123438) (xy 380.032768 -257.123438)
		)
		(stroke
			(width 0)
			(type solid)
		)
		(fill yes)
		(layer "In4.Cu")
		(net "M_G_CPU0_SA_CS_N<2>")
	)
	(gr_poly
		(pts
			(xy 380.079758 -255.751838) (xy 380.032768 -255.599438) (xy 379.771148 -255.599438) (xy 379.724158 -255.751838)
			(xy 379.724158 -255.796288) (xy 380.079758 -255.796288)
		)
		(stroke
			(width 0)
			(type solid)
		)
		(fill yes)
		(layer "In4.Cu")
		(net "M_G_CPU0_SA_CA<0>")
	)
	(gr_poly
		(pts
			(xy 380.082298 -255.343406) (xy 380.082298 -255.29921) (xy 379.726698 -255.29921) (xy 379.726698 -255.343406)
			(xy 379.773688 -255.495806) (xy 380.035308 -255.495806)
		)
		(stroke
			(width 0)
			(type solid)
		)
		(fill yes)
		(layer "In4.Cu")
		(net "M_G_CPU0_SA_CA<3>")
	)
	(gr_poly
		(pts
			(xy 380.153164 -273.717766) (xy 380.044706 -273.600926) (xy 380.006352 -273.578828) (xy 379.828552 -273.886676)
			(xy 379.866906 -273.908774) (xy 380.022354 -273.944334)
		)
		(stroke
			(width 0)
			(type solid)
		)
		(fill yes)
		(layer "In4.Cu")
		(net "M_G_CPU0_SA_DQ<5>")
	)
	(gr_poly
		(pts
			(xy 380.323344 -221.514162) (xy 380.28499 -221.492064) (xy 380.129542 -221.456504) (xy 379.998732 -221.683072)
			(xy 380.10719 -221.799912) (xy 380.145544 -221.82201)
		)
		(stroke
			(width 0)
			(type solid)
		)
		(fill yes)
		(layer "In4.Cu")
		(net "M_F_CPU0_SB_DQ<31>")
	)
	(gr_poly
		(pts
			(xy 380.327154 -223.135698) (xy 380.2888 -223.1136) (xy 380.133352 -223.07804) (xy 380.002542 -223.304608)
			(xy 380.111 -223.421448) (xy 380.149354 -223.443546)
		)
		(stroke
			(width 0)
			(type solid)
		)
		(fill yes)
		(layer "In4.Cu")
		(net "M_F_CPU0_SB_DQ<28>")
	)
	(gr_poly
		(pts
			(xy 380.427738 -234.76585) (xy 380.427738 -234.7214) (xy 380.072138 -234.7214) (xy 380.072138 -234.76585)
			(xy 380.119128 -234.91825) (xy 380.380748 -234.91825)
		)
		(stroke
			(width 0)
			(type solid)
		)
		(fill yes)
		(layer "In4.Cu")
		(net "M_G_CPU0_SB_DQ<16>")
	)
	(gr_poly
		(pts
			(xy 380.431548 -246.160798) (xy 380.431548 -246.116348) (xy 380.075948 -246.116348) (xy 380.075948 -246.160798)
			(xy 380.122938 -246.313198) (xy 380.384558 -246.313198)
		)
		(stroke
			(width 0)
			(type solid)
		)
		(fill yes)
		(layer "In4.Cu")
		(net "M_G_CPU0_SB_CS_N<3>")
	)
	(gr_poly
		(pts
			(xy 380.433834 -249.415554) (xy 380.433834 -249.371358) (xy 380.078234 -249.371358) (xy 380.078234 -249.415554)
			(xy 380.125224 -249.567954) (xy 380.386844 -249.567954)
		)
		(stroke
			(width 0)
			(type solid)
		)
		(fill yes)
		(layer "In4.Cu")
		(net "M_G_CPU0_SB_CA<2>")
	)
	(gr_poly
		(pts
			(xy 380.437136 -240.057686) (xy 380.390146 -239.905286) (xy 380.128526 -239.905286) (xy 380.081536 -240.057686)
			(xy 380.081536 -240.102136) (xy 380.437136 -240.102136)
		)
		(stroke
			(width 0)
			(type solid)
		)
		(fill yes)
		(layer "In4.Cu")
		(net "M_G_CPU0_SB_CB<3>")
	)
	(gr_poly
		(pts
			(xy 380.437136 -239.648746) (xy 380.437136 -239.60455) (xy 380.081536 -239.60455) (xy 380.081536 -239.648746)
			(xy 380.128526 -239.801146) (xy 380.390146 -239.801146)
		)
		(stroke
			(width 0)
			(type solid)
		)
		(fill yes)
		(layer "In4.Cu")
		(net "M_F_CPU0_SB_DQ<0>")
	)
	(gr_poly
		(pts
			(xy 380.437136 -235.174282) (xy 380.390146 -235.021882) (xy 380.128526 -235.021882) (xy 380.081536 -235.174282)
			(xy 380.081536 -235.218732) (xy 380.437136 -235.218732)
		)
		(stroke
			(width 0)
			(type solid)
		)
		(fill yes)
		(layer "In4.Cu")
		(net "M_F_CPU0_SB_DQ<7>")
	)
	(gr_poly
		(pts
			(xy 380.437898 -244.53215) (xy 380.437898 -244.487954) (xy 380.082298 -244.487954) (xy 380.082298 -244.53215)
			(xy 380.129288 -244.68455) (xy 380.390908 -244.68455)
		)
		(stroke
			(width 0)
			(type solid)
		)
		(fill yes)
		(layer "In4.Cu")
		(net "M_G_CPU0_SB_CB<4>")
	)
	(gr_poly
		(pts
			(xy 380.507494 -222.22206) (xy 380.399036 -222.10522) (xy 380.360682 -222.083122) (xy 380.182882 -222.39097)
			(xy 380.221236 -222.413068) (xy 380.376684 -222.448628)
		)
		(stroke
			(width 0)
			(type solid)
		)
		(fill yes)
		(layer "In4.Cu")
		(net "M_F_CPU0_SB_DQ<29>")
	)
	(gr_poly
		(pts
			(xy 380.513082 -223.84004) (xy 380.404624 -223.7232) (xy 380.36627 -223.701102) (xy 380.18847 -224.00895)
			(xy 380.226824 -224.031048) (xy 380.382272 -224.066608)
		)
		(stroke
			(width 0)
			(type solid)
		)
		(fill yes)
		(layer "In4.Cu")
		(net "M_F_CPU0_SB_DQ<30>")
	)
	(gr_poly
		(pts
			(xy 380.53518 -265.92403) (xy 380.53518 -265.87958) (xy 380.17958 -265.87958) (xy 380.17958 -265.92403)
			(xy 380.22657 -266.07643) (xy 380.48819 -266.07643)
		)
		(stroke
			(width 0)
			(type solid)
		)
		(fill yes)
		(layer "In4.Cu")
		(net "M_G_CPU0_SA_DQS_DP<2>")
	)
	(gr_poly
		(pts
			(xy 380.535434 -254.937514) (xy 380.488444 -254.785114) (xy 380.226824 -254.785114) (xy 380.179834 -254.937514)
			(xy 380.179834 -254.981964) (xy 380.535434 -254.981964)
		)
		(stroke
			(width 0)
			(type solid)
		)
		(fill yes)
		(layer "In4.Cu")
		(net "M_G_CPU0_SA_CA<2>")
	)
	(gr_poly
		(pts
			(xy 380.53772 -272.843498) (xy 380.49073 -272.691098) (xy 380.22911 -272.691098) (xy 380.18212 -272.843498)
			(xy 380.18212 -272.887948) (xy 380.53772 -272.887948)
		)
		(stroke
			(width 0)
			(type solid)
		)
		(fill yes)
		(layer "In4.Cu")
		(net "M_G_CPU0_SA_DQ<7>")
	)
	(gr_poly
		(pts
			(xy 380.53772 -267.960094) (xy 380.49073 -267.807694) (xy 380.22911 -267.807694) (xy 380.18212 -267.960094)
			(xy 380.18212 -268.004544) (xy 380.53772 -268.004544)
		)
		(stroke
			(width 0)
			(type solid)
		)
		(fill yes)
		(layer "In4.Cu")
		(net "M_F_CPU0_SA_DQ<13>")
	)
	(gr_poly
		(pts
			(xy 380.53772 -258.193286) (xy 380.49073 -258.040886) (xy 380.22911 -258.040886) (xy 380.18212 -258.193286)
			(xy 380.18212 -258.237736) (xy 380.53772 -258.237736)
		)
		(stroke
			(width 0)
			(type solid)
		)
		(fill yes)
		(layer "In4.Cu")
		(net "M_F_CPU0_SA_DQ<31>")
	)
	(gr_poly
		(pts
			(xy 380.543562 -277.317962) (xy 380.543562 -277.273766) (xy 380.187962 -277.273766) (xy 380.187962 -277.317962)
			(xy 380.234952 -277.470362) (xy 380.496572 -277.470362)
		)
		(stroke
			(width 0)
			(type solid)
		)
		(fill yes)
		(layer "In4.Cu")
		(net "M_G_CPU0_SA_DQ<0>")
	)
	(gr_poly
		(pts
			(xy 380.543562 -256.565654) (xy 380.496572 -256.413254) (xy 380.234952 -256.413254) (xy 380.187962 -256.565654)
			(xy 380.187962 -256.610104) (xy 380.543562 -256.610104)
		)
		(stroke
			(width 0)
			(type solid)
		)
		(fill yes)
		(layer "In4.Cu")
		(net "M_G_CPU0_SA_CS_N<3>")
	)
	(gr_poly
		(pts
			(xy 380.543562 -256.157222) (xy 380.543562 -256.112772) (xy 380.187962 -256.112772) (xy 380.187962 -256.157222)
			(xy 380.234952 -256.309622) (xy 380.496572 -256.309622)
		)
		(stroke
			(width 0)
			(type solid)
		)
		(fill yes)
		(layer "In4.Cu")
		(net "M_G_CPU0_SA_CA<1>")
	)
	(gr_poly
		(pts
			(xy 380.547118 -263.077198) (xy 380.500128 -262.924798) (xy 380.238508 -262.924798) (xy 380.191518 -263.077198)
			(xy 380.191518 -263.121394) (xy 380.547118 -263.121394)
		)
		(stroke
			(width 0)
			(type solid)
		)
		(fill yes)
		(layer "In4.Cu")
		(net "M_G_CPU0_SA_DQ<23>")
	)
	(gr_poly
		(pts
			(xy 380.54788 -272.434558) (xy 380.54788 -272.390362) (xy 380.19228 -272.390362) (xy 380.19228 -272.434558)
			(xy 380.23927 -272.586958) (xy 380.50089 -272.586958)
		)
		(stroke
			(width 0)
			(type solid)
		)
		(fill yes)
		(layer "In4.Cu")
		(net "M_F_CPU0_SA_DQ<8>")
	)
	(gr_poly
		(pts
			(xy 380.54788 -267.551154) (xy 380.54788 -267.506958) (xy 380.19228 -267.506958) (xy 380.19228 -267.551154)
			(xy 380.23927 -267.703554) (xy 380.50089 -267.703554)
		)
		(stroke
			(width 0)
			(type solid)
		)
		(fill yes)
		(layer "In4.Cu")
		(net "M_G_CPU0_SA_DQ<16>")
	)
	(gr_poly
		(pts
			(xy 380.549658 -257.784854) (xy 380.549658 -257.740404) (xy 380.194058 -257.740404) (xy 380.194058 -257.784854)
			(xy 380.241048 -257.937254) (xy 380.502668 -257.937254)
		)
		(stroke
			(width 0)
			(type solid)
		)
		(fill yes)
		(layer "In4.Cu")
		(net "M_G_CPU0_SA_CS_N<0>")
	)
	(gr_poly
		(pts
			(xy 380.550928 -270.806926) (xy 380.550928 -270.76273) (xy 380.195328 -270.76273) (xy 380.195328 -270.806926)
			(xy 380.242318 -270.959326) (xy 380.503938 -270.959326)
		)
		(stroke
			(width 0)
			(type solid)
		)
		(fill yes)
		(layer "In4.Cu")
		(net "M_F_CPU0_SA_DQS_DP<1>")
	)
	(gr_poly
		(pts
			(xy 380.798832 -222.318326) (xy 380.760478 -222.296228) (xy 380.60503 -222.260668) (xy 380.47422 -222.487236)
			(xy 380.582678 -222.604076) (xy 380.621032 -222.626174)
		)
		(stroke
			(width 0)
			(type solid)
		)
		(fill yes)
		(layer "In4.Cu")
		(net "M_F_CPU0_SB_DQ<28>")
	)
	(gr_poly
		(pts
			(xy 380.799848 -220.68917) (xy 380.761494 -220.667072) (xy 380.606046 -220.631512) (xy 380.475236 -220.85808)
			(xy 380.583694 -220.97492) (xy 380.622048 -220.997018)
		)
		(stroke
			(width 0)
			(type solid)
		)
		(fill yes)
		(layer "In4.Cu")
		(net "M_F_CPU0_SB_DQ<31>")
	)
	(gr_poly
		(pts
			(xy 380.895098 -245.754906) (xy 380.848108 -245.602506) (xy 380.586488 -245.602506) (xy 380.539498 -245.754906)
			(xy 380.539498 -245.799102) (xy 380.895098 -245.799102)
		)
		(stroke
			(width 0)
			(type solid)
		)
		(fill yes)
		(layer "In4.Cu")
		(net "M_G_CPU0_SB_CS_N<1>")
	)
	(gr_poly
		(pts
			(xy 380.897638 -237.616238) (xy 380.850648 -237.463838) (xy 380.589028 -237.463838) (xy 380.542038 -237.616238)
			(xy 380.542038 -237.660434) (xy 380.897638 -237.660434)
		)
		(stroke
			(width 0)
			(type solid)
		)
		(fill yes)
		(layer "In4.Cu")
		(net "M_F_CPU0_SB_DQS_DN<0>")
	)
	(gr_poly
		(pts
			(xy 380.897638 -232.732834) (xy 380.850648 -232.580434) (xy 380.589028 -232.580434) (xy 380.542038 -232.732834)
			(xy 380.542038 -232.77703) (xy 380.897638 -232.77703)
		)
		(stroke
			(width 0)
			(type solid)
		)
		(fill yes)
		(layer "In4.Cu")
		(net "M_G_CPU0_SB_DQS_DN<2>")
	)
	(gr_poly
		(pts
			(xy 380.899416 -244.127274) (xy 380.852426 -243.974874) (xy 380.590806 -243.974874) (xy 380.543816 -244.127274)
			(xy 380.543816 -244.171724) (xy 380.899416 -244.171724)
		)
		(stroke
			(width 0)
			(type solid)
		)
		(fill yes)
		(layer "In4.Cu")
		(net "M_G_CPU0_SB_CB<6>")
	)
	(gr_poly
		(pts
			(xy 380.899416 -238.83493) (xy 380.899416 -238.790734) (xy 380.543816 -238.790734) (xy 380.543816 -238.83493)
			(xy 380.590806 -238.98733) (xy 380.852426 -238.98733)
		)
		(stroke
			(width 0)
			(type solid)
		)
		(fill yes)
		(layer "In4.Cu")
		(net "M_F_CPU0_SB_DQ<1>")
	)
	(gr_poly
		(pts
			(xy 380.899416 -235.988606) (xy 380.852426 -235.836206) (xy 380.590806 -235.836206) (xy 380.543816 -235.988606)
			(xy 380.543816 -236.032802) (xy 380.899416 -236.032802)
		)
		(stroke
			(width 0)
			(type solid)
		)
		(fill yes)
		(layer "In4.Cu")
		(net "M_F_CPU0_SB_DQ<6>")
	)
	(gr_poly
		(pts
			(xy 380.899416 -233.951526) (xy 380.899416 -233.90733) (xy 380.543816 -233.90733) (xy 380.543816 -233.951526)
			(xy 380.590806 -234.103926) (xy 380.852426 -234.103926)
		)
		(stroke
			(width 0)
			(type solid)
		)
		(fill yes)
		(layer "In4.Cu")
		(net "M_G_CPU0_SB_DQ<17>")
	)
	(gr_poly
		(pts
			(xy 380.899416 -231.105202) (xy 380.852426 -230.952802) (xy 380.590806 -230.952802) (xy 380.543816 -231.105202)
			(xy 380.543816 -231.149398) (xy 380.899416 -231.149398)
		)
		(stroke
			(width 0)
			(type solid)
		)
		(fill yes)
		(layer "In4.Cu")
		(net "M_G_CPU0_SB_DQ<22>")
	)
	(gr_poly
		(pts
			(xy 380.900178 -243.718334) (xy 380.900178 -243.674138) (xy 380.544578 -243.674138) (xy 380.544578 -243.718334)
			(xy 380.591568 -243.870734) (xy 380.853188 -243.870734)
		)
		(stroke
			(width 0)
			(type solid)
		)
		(fill yes)
		(layer "In4.Cu")
		(net "M_G_CPU0_SB_CB<5>")
	)
	(gr_poly
		(pts
			(xy 380.900178 -240.871502) (xy 380.853188 -240.719102) (xy 380.591568 -240.719102) (xy 380.544578 -240.871502)
			(xy 380.544578 -240.915952) (xy 380.900178 -240.915952)
		)
		(stroke
			(width 0)
			(type solid)
		)
		(fill yes)
		(layer "In4.Cu")
		(net "M_G_CPU0_SB_CB<2>")
	)
	(gr_poly
		(pts
			(xy 380.900178 -240.462562) (xy 380.900178 -240.418366) (xy 380.544578 -240.418366) (xy 380.544578 -240.462562)
			(xy 380.591568 -240.614962) (xy 380.853188 -240.614962)
		)
		(stroke
			(width 0)
			(type solid)
		)
		(fill yes)
		(layer "In4.Cu")
		(net "M_G_CPU0_SB_CB<1>")
	)
	(gr_poly
		(pts
			(xy 380.900178 -239.24387) (xy 380.853188 -239.09147) (xy 380.591568 -239.09147) (xy 380.544578 -239.24387)
			(xy 380.544578 -239.28832) (xy 380.900178 -239.28832)
		)
		(stroke
			(width 0)
			(type solid)
		)
		(fill yes)
		(layer "In4.Cu")
		(net "M_F_CPU0_SB_DQ<2>")
	)
	(gr_poly
		(pts
			(xy 380.900178 -235.579666) (xy 380.900178 -235.535216) (xy 380.544578 -235.535216) (xy 380.544578 -235.579666)
			(xy 380.591568 -235.732066) (xy 380.853188 -235.732066)
		)
		(stroke
			(width 0)
			(type solid)
		)
		(fill yes)
		(layer "In4.Cu")
		(net "M_F_CPU0_SB_DQ<5>")
	)
	(gr_poly
		(pts
			(xy 380.900178 -230.696262) (xy 380.900178 -230.651812) (xy 380.544578 -230.651812) (xy 380.544578 -230.696262)
			(xy 380.591568 -230.848662) (xy 380.853188 -230.848662)
		)
		(stroke
			(width 0)
			(type solid)
		)
		(fill yes)
		(layer "In4.Cu")
		(net "M_G_CPU0_SB_DQ<21>")
	)
	(gr_poly
		(pts
			(xy 380.903734 -249.010678) (xy 380.856744 -248.858278) (xy 380.595124 -248.858278) (xy 380.548134 -249.010678)
			(xy 380.548134 -249.054874) (xy 380.903734 -249.054874)
		)
		(stroke
			(width 0)
			(type solid)
		)
		(fill yes)
		(layer "In4.Cu")
		(net "M_G_CPU0_SB_CA<3>")
	)
	(gr_poly
		(pts
			(xy 380.903734 -248.601738) (xy 380.903734 -248.557542) (xy 380.548134 -248.557542) (xy 380.548134 -248.601738)
			(xy 380.595124 -248.754138) (xy 380.856744 -248.754138)
		)
		(stroke
			(width 0)
			(type solid)
		)
		(fill yes)
		(layer "In4.Cu")
		(net "M_G_CPU0_SB_CA<4>")
	)
	(gr_poly
		(pts
			(xy 380.903734 -242.499642) (xy 380.856744 -242.347242) (xy 380.595124 -242.347242) (xy 380.548134 -242.499642)
			(xy 380.548134 -242.544092) (xy 380.903734 -242.544092)
		)
		(stroke
			(width 0)
			(type solid)
		)
		(fill yes)
		(layer "In4.Cu")
		(net "M_G_CPU0_SB_DQS_DN<9>")
	)
	(gr_poly
		(pts
			(xy 380.912116 -234.360466) (xy 380.865126 -234.208066) (xy 380.603506 -234.208066) (xy 380.556516 -234.360466)
			(xy 380.556516 -234.404662) (xy 380.912116 -234.404662)
		)
		(stroke
			(width 0)
			(type solid)
		)
		(fill yes)
		(layer "In4.Cu")
		(net "M_G_CPU0_SB_DQ<18>")
	)
	(gr_poly
		(pts
			(xy 380.976632 -223.0374) (xy 380.868174 -222.92056) (xy 380.82982 -222.898462) (xy 380.65202 -223.20631)
			(xy 380.690374 -223.228408) (xy 380.845822 -223.263968)
		)
		(stroke
			(width 0)
			(type solid)
		)
		(fill yes)
		(layer "In4.Cu")
		(net "M_F_CPU0_SB_DQ<30>")
	)
	(gr_poly
		(pts
			(xy 380.982982 -221.398592) (xy 380.874524 -221.281752) (xy 380.83617 -221.259654) (xy 380.65837 -221.567502)
			(xy 380.696724 -221.5896) (xy 380.852172 -221.62516)
		)
		(stroke
			(width 0)
			(type solid)
		)
		(fill yes)
		(layer "In4.Cu")
		(net "M_F_CPU0_SB_DQ<29>")
	)
	(gr_poly
		(pts
			(xy 381.009144 -270.40205) (xy 380.962154 -270.24965) (xy 380.700534 -270.24965) (xy 380.653544 -270.40205)
			(xy 380.653544 -270.446246) (xy 381.009144 -270.446246)
		)
		(stroke
			(width 0)
			(type solid)
		)
		(fill yes)
		(layer "In4.Cu")
		(net "M_F_CPU0_SA_DQS_DN<1>")
	)
	(gr_poly
		(pts
			(xy 381.009398 -272.029682) (xy 380.962408 -271.877282) (xy 380.700788 -271.877282) (xy 380.653798 -272.029682)
			(xy 380.653798 -272.074132) (xy 381.009398 -272.074132)
		)
		(stroke
			(width 0)
			(type solid)
		)
		(fill yes)
		(layer "In4.Cu")
		(net "M_F_CPU0_SA_DQ<10>")
	)
	(gr_poly
		(pts
			(xy 381.009398 -267.146278) (xy 380.962408 -266.993878) (xy 380.700788 -266.993878) (xy 380.653798 -267.146278)
			(xy 380.653798 -267.190728) (xy 381.009398 -267.190728)
		)
		(stroke
			(width 0)
			(type solid)
		)
		(fill yes)
		(layer "In4.Cu")
		(net "M_G_CPU0_SA_DQ<18>")
	)
	(gr_poly
		(pts
			(xy 381.009398 -261.854442) (xy 381.009398 -261.809992) (xy 380.653798 -261.809992) (xy 380.653798 -261.854442)
			(xy 380.700788 -262.006842) (xy 380.962408 -262.006842)
		)
		(stroke
			(width 0)
			(type solid)
		)
		(fill yes)
		(layer "In4.Cu")
		(net "M_F_CPU0_SA_DQ<25>")
	)
	(gr_poly
		(pts
			(xy 381.01016 -273.657314) (xy 380.96317 -273.504914) (xy 380.70155 -273.504914) (xy 380.65456 -273.657314)
			(xy 380.65456 -273.701764) (xy 381.01016 -273.701764)
		)
		(stroke
			(width 0)
			(type solid)
		)
		(fill yes)
		(layer "In4.Cu")
		(net "M_G_CPU0_SA_DQ<6>")
	)
	(gr_poly
		(pts
			(xy 381.01016 -271.620742) (xy 381.01016 -271.576546) (xy 380.65456 -271.576546) (xy 380.65456 -271.620742)
			(xy 380.70155 -271.773142) (xy 380.96317 -271.773142)
		)
		(stroke
			(width 0)
			(type solid)
		)
		(fill yes)
		(layer "In4.Cu")
		(net "M_F_CPU0_SA_DQ<9>")
	)
	(gr_poly
		(pts
			(xy 381.01016 -268.77391) (xy 380.96317 -268.62151) (xy 380.70155 -268.62151) (xy 380.65456 -268.77391)
			(xy 380.65456 -268.81836) (xy 381.01016 -268.81836)
		)
		(stroke
			(width 0)
			(type solid)
		)
		(fill yes)
		(layer "In4.Cu")
		(net "M_F_CPU0_SA_DQ<14>")
	)
	(gr_poly
		(pts
			(xy 381.01016 -266.737338) (xy 381.01016 -266.693142) (xy 380.65456 -266.693142) (xy 380.65456 -266.737338)
			(xy 380.70155 -266.889738) (xy 380.96317 -266.889738)
		)
		(stroke
			(width 0)
			(type solid)
		)
		(fill yes)
		(layer "In4.Cu")
		(net "M_G_CPU0_SA_DQ<17>")
	)
	(gr_poly
		(pts
			(xy 381.01016 -263.891014) (xy 380.96317 -263.738614) (xy 380.70155 -263.738614) (xy 380.65456 -263.891014)
			(xy 380.65456 -263.93521) (xy 381.01016 -263.93521)
		)
		(stroke
			(width 0)
			(type solid)
		)
		(fill yes)
		(layer "In4.Cu")
		(net "M_G_CPU0_SA_DQ<22>")
	)
	(gr_poly
		(pts
			(xy 381.01016 -263.482074) (xy 381.01016 -263.437624) (xy 380.65456 -263.437624) (xy 380.65456 -263.482074)
			(xy 380.70155 -263.634474) (xy 380.96317 -263.634474)
		)
		(stroke
			(width 0)
			(type solid)
		)
		(fill yes)
		(layer "In4.Cu")
		(net "M_G_CPU0_SA_DQ<21>")
	)
	(gr_poly
		(pts
			(xy 381.013462 -255.751838) (xy 380.966472 -255.599438) (xy 380.704852 -255.599438) (xy 380.657862 -255.751838)
			(xy 380.657862 -255.796288) (xy 381.013462 -255.796288)
		)
		(stroke
			(width 0)
			(type solid)
		)
		(fill yes)
		(layer "In4.Cu")
		(net "M_G_CPU0_SA_CA<0>")
	)
	(gr_poly
		(pts
			(xy 381.013716 -255.343406) (xy 381.013716 -255.298956) (xy 380.658116 -255.298956) (xy 380.658116 -255.343406)
			(xy 380.705106 -255.495806) (xy 380.966726 -255.495806)
		)
		(stroke
			(width 0)
			(type solid)
		)
		(fill yes)
		(layer "In4.Cu")
		(net "M_G_CPU0_SA_CA<3>")
	)
	(gr_poly
		(pts
			(xy 381.019558 -276.912578) (xy 380.972568 -276.760178) (xy 380.710948 -276.760178) (xy 380.663958 -276.912578)
			(xy 380.663958 -276.957028) (xy 381.019558 -276.957028)
		)
		(stroke
			(width 0)
			(type solid)
		)
		(fill yes)
		(layer "In4.Cu")
		(net "M_G_CPU0_SA_DQ<2>")
	)
	(gr_poly
		(pts
			(xy 381.019558 -276.5044) (xy 381.019558 -276.460204) (xy 380.663958 -276.460204) (xy 380.663958 -276.5044)
			(xy 380.710948 -276.6568) (xy 380.972568 -276.6568)
		)
		(stroke
			(width 0)
			(type solid)
		)
		(fill yes)
		(layer "In4.Cu")
		(net "M_G_CPU0_SA_DQ<1>")
	)
	(gr_poly
		(pts
			(xy 381.019558 -275.284946) (xy 380.972568 -275.132546) (xy 380.710948 -275.132546) (xy 380.663958 -275.284946)
			(xy 380.663958 -275.329396) (xy 381.019558 -275.329396)
		)
		(stroke
			(width 0)
			(type solid)
		)
		(fill yes)
		(layer "In4.Cu")
		(net "M_G_CPU0_SA_DQS_DN<0>")
	)
	(gr_poly
		(pts
			(xy 381.019558 -265.518646) (xy 380.972568 -265.366246) (xy 380.710948 -265.366246) (xy 380.663958 -265.518646)
			(xy 380.663958 -265.562842) (xy 381.019558 -265.562842)
		)
		(stroke
			(width 0)
			(type solid)
		)
		(fill yes)
		(layer "In4.Cu")
		(net "M_G_CPU0_SA_DQS_DN<2>")
	)
	(gr_poly
		(pts
			(xy 381.019558 -260.635242) (xy 380.972568 -260.482842) (xy 380.710948 -260.482842) (xy 380.663958 -260.635242)
			(xy 380.663958 -260.679438) (xy 381.019558 -260.679438)
		)
		(stroke
			(width 0)
			(type solid)
		)
		(fill yes)
		(layer "In4.Cu")
		(net "M_F_CPU0_SA_DQS_DN<3>")
	)
	(gr_poly
		(pts
			(xy 381.019558 -257.37947) (xy 380.972568 -257.22707) (xy 380.710948 -257.22707) (xy 380.663958 -257.37947)
			(xy 380.663958 -257.423666) (xy 381.019558 -257.423666)
		)
		(stroke
			(width 0)
			(type solid)
		)
		(fill yes)
		(layer "In4.Cu")
		(net "M_G_CPU0_SA_CS_N<1>")
	)
	(gr_poly
		(pts
			(xy 381.019558 -256.971038) (xy 381.019558 -256.926842) (xy 380.663958 -256.926842) (xy 380.663958 -256.971038)
			(xy 380.710948 -257.123438) (xy 380.972568 -257.123438)
		)
		(stroke
			(width 0)
			(type solid)
		)
		(fill yes)
		(layer "In4.Cu")
		(net "M_G_CPU0_SA_CS_N<2>")
	)
	(gr_poly
		(pts
			(xy 381.022098 -273.248882) (xy 381.022098 -273.204686) (xy 380.666498 -273.204686) (xy 380.666498 -273.248882)
			(xy 380.713488 -273.401282) (xy 380.975108 -273.401282)
		)
		(stroke
			(width 0)
			(type solid)
		)
		(fill yes)
		(layer "In4.Cu")
		(net "M_G_CPU0_SA_DQ<5>")
	)
	(gr_poly
		(pts
			(xy 381.022098 -268.365478) (xy 381.022098 -268.321282) (xy 380.666498 -268.321282) (xy 380.666498 -268.365478)
			(xy 380.713488 -268.517878) (xy 380.975108 -268.517878)
		)
		(stroke
			(width 0)
			(type solid)
		)
		(fill yes)
		(layer "In4.Cu")
		(net "M_F_CPU0_SA_DQ<15>")
	)
	(gr_poly
		(pts
			(xy 381.022098 -258.599178) (xy 381.022098 -258.554728) (xy 380.666498 -258.554728) (xy 380.666498 -258.599178)
			(xy 380.713488 -258.751578) (xy 380.975108 -258.751578)
		)
		(stroke
			(width 0)
			(type solid)
		)
		(fill yes)
		(layer "In4.Cu")
		(net "M_F_CPU0_SA_DQ<29>")
	)
	(gr_poly
		(pts
			(xy 381.261366 -226.400614) (xy 381.223012 -226.378516) (xy 381.067564 -226.342956) (xy 380.936754 -226.569524)
			(xy 381.045212 -226.686364) (xy 381.083566 -226.708462)
		)
		(stroke
			(width 0)
			(type solid)
		)
		(fill yes)
		(layer "In4.Cu")
		(net "M_F_CPU0_SB_DQS_DN<3>")
	)
	(gr_poly
		(pts
			(xy 381.267716 -219.879164) (xy 381.229362 -219.857066) (xy 381.073914 -219.821506) (xy 380.943104 -220.048074)
			(xy 381.051562 -220.164914) (xy 381.089916 -220.187012)
		)
		(stroke
			(width 0)
			(type solid)
		)
		(fill yes)
		(layer "In4.Cu")
		(net "M_F_CPU0_SB_DQ<31>")
	)
	(gr_poly
		(pts
			(xy 381.367538 -241.685318) (xy 381.320548 -241.532918) (xy 381.058928 -241.532918) (xy 381.011938 -241.685318)
			(xy 381.011938 -241.729514) (xy 381.367538 -241.729514)
		)
		(stroke
			(width 0)
			(type solid)
		)
		(fill yes)
		(layer "In4.Cu")
		(net "M_G_CPU0_SB_DQS_DP<4>")
	)
	(gr_poly
		(pts
			(xy 381.367538 -234.76585) (xy 381.367538 -234.721654) (xy 381.011938 -234.721654) (xy 381.011938 -234.76585)
			(xy 381.058928 -234.91825) (xy 381.320548 -234.91825)
		)
		(stroke
			(width 0)
			(type solid)
		)
		(fill yes)
		(layer "In4.Cu")
		(net "M_G_CPU0_SB_DQ<16>")
	)
	(gr_poly
		(pts
			(xy 381.367538 -222.151702) (xy 381.320548 -221.999302) (xy 381.058928 -221.999302) (xy 381.011938 -222.151702)
			(xy 381.011938 -222.196152) (xy 381.367538 -222.196152)
		)
		(stroke
			(width 0)
			(type solid)
		)
		(fill yes)
		(layer "In4.Cu")
		(net "M_F_CPU0_SB_DQ<28>")
	)
	(gr_poly
		(pts
			(xy 381.373634 -249.415554) (xy 381.373634 -249.371358) (xy 381.018034 -249.371358) (xy 381.018034 -249.415554)
			(xy 381.065024 -249.567954) (xy 381.326644 -249.567954)
		)
		(stroke
			(width 0)
			(type solid)
		)
		(fill yes)
		(layer "In4.Cu")
		(net "M_G_CPU0_SB_CA<2>")
	)
	(gr_poly
		(pts
			(xy 381.373634 -248.196354) (xy 381.326644 -248.043954) (xy 381.065024 -248.043954) (xy 381.018034 -248.196354)
			(xy 381.018034 -248.240804) (xy 381.373634 -248.240804)
		)
		(stroke
			(width 0)
			(type solid)
		)
		(fill yes)
		(layer "In4.Cu")
		(net "M_G_CPU0_SB_CA<5>")
	)
	(gr_poly
		(pts
			(xy 381.373634 -228.254814) (xy 381.373634 -228.210364) (xy 381.018034 -228.210364) (xy 381.018034 -228.254814)
			(xy 381.065024 -228.407214) (xy 381.326644 -228.407214)
		)
		(stroke
			(width 0)
			(type solid)
		)
		(fill yes)
		(layer "In4.Cu")
		(net "M_F_CPU0_SB_DQS_DN<8>")
	)
	(gr_poly
		(pts
			(xy 381.376936 -243.313458) (xy 381.329946 -243.161058) (xy 381.068326 -243.161058) (xy 381.021336 -243.313458)
			(xy 381.021336 -243.357654) (xy 381.376936 -243.357654)
		)
		(stroke
			(width 0)
			(type solid)
		)
		(fill yes)
		(layer "In4.Cu")
		(net "M_G_CPU0_SB_CB<7>")
	)
	(gr_poly
		(pts
			(xy 381.376936 -241.276886) (xy 381.376936 -241.232436) (xy 381.021336 -241.232436) (xy 381.021336 -241.276886)
			(xy 381.068326 -241.429286) (xy 381.329946 -241.429286)
		)
		(stroke
			(width 0)
			(type solid)
		)
		(fill yes)
		(layer "In4.Cu")
		(net "M_G_CPU0_SB_CB<0>")
	)
	(gr_poly
		(pts
			(xy 381.376936 -240.057686) (xy 381.329946 -239.905286) (xy 381.068326 -239.905286) (xy 381.021336 -240.057686)
			(xy 381.021336 -240.102136) (xy 381.376936 -240.102136)
		)
		(stroke
			(width 0)
			(type solid)
		)
		(fill yes)
		(layer "In4.Cu")
		(net "M_G_CPU0_SB_CB<3>")
	)
	(gr_poly
		(pts
			(xy 381.376936 -239.648746) (xy 381.376936 -239.60455) (xy 381.021336 -239.60455) (xy 381.021336 -239.648746)
			(xy 381.068326 -239.801146) (xy 381.329946 -239.801146)
		)
		(stroke
			(width 0)
			(type solid)
		)
		(fill yes)
		(layer "In4.Cu")
		(net "M_F_CPU0_SB_DQ<0>")
	)
	(gr_poly
		(pts
			(xy 381.376936 -235.174282) (xy 381.329946 -235.021882) (xy 381.068326 -235.021882) (xy 381.021336 -235.174282)
			(xy 381.021336 -235.218732) (xy 381.376936 -235.218732)
		)
		(stroke
			(width 0)
			(type solid)
		)
		(fill yes)
		(layer "In4.Cu")
		(net "M_F_CPU0_SB_DQ<7>")
	)
	(gr_poly
		(pts
			(xy 381.376936 -230.290878) (xy 381.329946 -230.138478) (xy 381.068326 -230.138478) (xy 381.021336 -230.290878)
			(xy 381.021336 -230.335328) (xy 381.376936 -230.335328)
		)
		(stroke
			(width 0)
			(type solid)
		)
		(fill yes)
		(layer "In4.Cu")
		(net "M_G_CPU0_SB_DQ<23>")
	)
	(gr_poly
		(pts
			(xy 381.376936 -229.882446) (xy 381.376936 -229.837996) (xy 381.021336 -229.837996) (xy 381.021336 -229.882446)
			(xy 381.068326 -230.034846) (xy 381.329946 -230.034846)
		)
		(stroke
			(width 0)
			(type solid)
		)
		(fill yes)
		(layer "In4.Cu")
		(net "M_F_CPU0_SB_DQ<26>")
	)
	(gr_poly
		(pts
			(xy 381.377698 -244.53215) (xy 381.377698 -244.487954) (xy 381.022098 -244.487954) (xy 381.022098 -244.53215)
			(xy 381.069088 -244.68455) (xy 381.330708 -244.68455)
		)
		(stroke
			(width 0)
			(type solid)
		)
		(fill yes)
		(layer "In4.Cu")
		(net "M_G_CPU0_SB_CB<4>")
	)
	(gr_poly
		(pts
			(xy 381.377698 -238.430054) (xy 381.330708 -238.277654) (xy 381.069088 -238.277654) (xy 381.022098 -238.430054)
			(xy 381.022098 -238.47425) (xy 381.377698 -238.47425)
		)
		(stroke
			(width 0)
			(type solid)
		)
		(fill yes)
		(layer "In4.Cu")
		(net "M_F_CPU0_SB_DQ<3>")
	)
	(gr_poly
		(pts
			(xy 381.377698 -236.393482) (xy 381.377698 -236.349032) (xy 381.022098 -236.349032) (xy 381.022098 -236.393482)
			(xy 381.069088 -236.545882) (xy 381.330708 -236.545882)
		)
		(stroke
			(width 0)
			(type solid)
		)
		(fill yes)
		(layer "In4.Cu")
		(net "M_F_CPU0_SB_DQ<4>")
	)
	(gr_poly
		(pts
			(xy 381.377698 -233.54665) (xy 381.330708 -233.39425) (xy 381.069088 -233.39425) (xy 381.022098 -233.54665)
			(xy 381.022098 -233.5911) (xy 381.377698 -233.5911)
		)
		(stroke
			(width 0)
			(type solid)
		)
		(fill yes)
		(layer "In4.Cu")
		(net "M_G_CPU0_SB_DQ<19>")
	)
	(gr_poly
		(pts
			(xy 381.377698 -231.510078) (xy 381.377698 -231.465628) (xy 381.022098 -231.465628) (xy 381.022098 -231.510078)
			(xy 381.069088 -231.662478) (xy 381.330708 -231.662478)
		)
		(stroke
			(width 0)
			(type solid)
		)
		(fill yes)
		(layer "In4.Cu")
		(net "M_G_CPU0_SB_DQ<20>")
	)
	(gr_poly
		(pts
			(xy 381.379476 -236.801914) (xy 381.332486 -236.649514) (xy 381.070866 -236.649514) (xy 381.023876 -236.801914)
			(xy 381.023876 -236.84611) (xy 381.379476 -236.84611)
		)
		(stroke
			(width 0)
			(type solid)
		)
		(fill yes)
		(layer "In4.Cu")
		(net "M_F_CPU0_SB_DQS_DP<5>")
	)
	(gr_poly
		(pts
			(xy 381.379476 -231.91851) (xy 381.332486 -231.76611) (xy 381.070866 -231.76611) (xy 381.023876 -231.91851)
			(xy 381.023876 -231.96296) (xy 381.379476 -231.96296)
		)
		(stroke
			(width 0)
			(type solid)
		)
		(fill yes)
		(layer "In4.Cu")
		(net "M_G_CPU0_SB_DQS_DP<7>")
	)
	(gr_poly
		(pts
			(xy 381.382016 -247.787922) (xy 381.382016 -247.743726) (xy 381.026416 -247.743726) (xy 381.026416 -247.787922)
			(xy 381.073406 -247.940322) (xy 381.335026 -247.940322)
		)
		(stroke
			(width 0)
			(type solid)
		)
		(fill yes)
		(layer "In4.Cu")
		(net "M_G_CPU0_SB_CA<6>")
	)
	(gr_poly
		(pts
			(xy 381.382016 -246.568722) (xy 381.335026 -246.416322) (xy 381.073406 -246.416322) (xy 381.026416 -246.568722)
			(xy 381.026416 -246.612918) (xy 381.382016 -246.612918)
		)
		(stroke
			(width 0)
			(type solid)
		)
		(fill yes)
		(layer "In4.Cu")
		(net "M_G_CPU0_SB_CS_N<0>")
	)
	(gr_poly
		(pts
			(xy 381.382016 -246.16029) (xy 381.382016 -246.116094) (xy 381.026416 -246.116094) (xy 381.026416 -246.16029)
			(xy 381.073406 -246.31269) (xy 381.335026 -246.31269)
		)
		(stroke
			(width 0)
			(type solid)
		)
		(fill yes)
		(layer "In4.Cu")
		(net "M_G_CPU0_SB_CS_N<3>")
	)
	(gr_poly
		(pts
			(xy 381.382016 -242.905026) (xy 381.382016 -242.860576) (xy 381.026416 -242.860576) (xy 381.026416 -242.905026)
			(xy 381.073406 -243.057426) (xy 381.335026 -243.057426)
		)
		(stroke
			(width 0)
			(type solid)
		)
		(fill yes)
		(layer "In4.Cu")
		(net "M_G_CPU0_SB_DQS_DP<9>")
	)
	(gr_poly
		(pts
			(xy 381.382016 -238.021622) (xy 381.382016 -237.977172) (xy 381.026416 -237.977172) (xy 381.026416 -238.021622)
			(xy 381.073406 -238.174022) (xy 381.335026 -238.174022)
		)
		(stroke
			(width 0)
			(type solid)
		)
		(fill yes)
		(layer "In4.Cu")
		(net "M_F_CPU0_SB_DQS_DP<0>")
	)
	(gr_poly
		(pts
			(xy 381.382016 -233.138218) (xy 381.382016 -233.093768) (xy 381.026416 -233.093768) (xy 381.026416 -233.138218)
			(xy 381.073406 -233.290618) (xy 381.335026 -233.290618)
		)
		(stroke
			(width 0)
			(type solid)
		)
		(fill yes)
		(layer "In4.Cu")
		(net "M_G_CPU0_SB_DQS_DP<2>")
	)
	(gr_poly
		(pts
			(xy 381.446532 -220.595698) (xy 381.338074 -220.478858) (xy 381.29972 -220.45676) (xy 381.12192 -220.764608)
			(xy 381.160274 -220.786706) (xy 381.315722 -220.822266)
		)
		(stroke
			(width 0)
			(type solid)
		)
		(fill yes)
		(layer "In4.Cu")
		(net "M_F_CPU0_SB_DQ<29>")
	)
	(gr_poly
		(pts
			(xy 381.452882 -227.095558) (xy 381.344424 -226.978718) (xy 381.30607 -226.95662) (xy 381.12827 -227.264468)
			(xy 381.166624 -227.286566) (xy 381.322072 -227.322126)
		)
		(stroke
			(width 0)
			(type solid)
		)
		(fill yes)
		(layer "In4.Cu")
		(net "M_F_CPU0_SB_DQS_DP<3>")
	)
	(gr_poly
		(pts
			(xy 381.47498 -277.318216) (xy 381.47498 -277.27402) (xy 381.11938 -277.27402) (xy 381.11938 -277.318216)
			(xy 381.16637 -277.470616) (xy 381.42799 -277.470616)
		)
		(stroke
			(width 0)
			(type solid)
		)
		(fill yes)
		(layer "In4.Cu")
		(net "M_G_CPU0_SA_DQ<0>")
	)
	(gr_poly
		(pts
			(xy 381.47498 -276.098762) (xy 381.42799 -275.946362) (xy 381.16637 -275.946362) (xy 381.11938 -276.098762)
			(xy 381.11938 -276.143212) (xy 381.47498 -276.143212)
		)
		(stroke
			(width 0)
			(type solid)
		)
		(fill yes)
		(layer "In4.Cu")
		(net "M_G_CPU0_SA_DQ<3>")
	)
	(gr_poly
		(pts
			(xy 381.47498 -272.843498) (xy 381.42799 -272.691098) (xy 381.16637 -272.691098) (xy 381.11938 -272.843498)
			(xy 381.11938 -272.887694) (xy 381.47498 -272.887694)
		)
		(stroke
			(width 0)
			(type solid)
		)
		(fill yes)
		(layer "In4.Cu")
		(net "M_G_CPU0_SA_DQ<7>")
	)
	(gr_poly
		(pts
			(xy 381.47498 -256.565654) (xy 381.42799 -256.413254) (xy 381.16637 -256.413254) (xy 381.11938 -256.565654)
			(xy 381.11938 -256.60985) (xy 381.47498 -256.60985)
		)
		(stroke
			(width 0)
			(type solid)
		)
		(fill yes)
		(layer "In4.Cu")
		(net "M_G_CPU0_SA_CS_N<3>")
	)
	(gr_poly
		(pts
			(xy 381.47752 -258.193286) (xy 381.43053 -258.040886) (xy 381.16891 -258.040886) (xy 381.12192 -258.193286)
			(xy 381.12192 -258.237482) (xy 381.47752 -258.237482)
		)
		(stroke
			(width 0)
			(type solid)
		)
		(fill yes)
		(layer "In4.Cu")
		(net "M_F_CPU0_SA_DQ<31>")
	)
	(gr_poly
		(pts
			(xy 381.47752 -257.784854) (xy 381.47752 -257.740658) (xy 381.12192 -257.740658) (xy 381.12192 -257.784854)
			(xy 381.16891 -257.937254) (xy 381.43053 -257.937254)
		)
		(stroke
			(width 0)
			(type solid)
		)
		(fill yes)
		(layer "In4.Cu")
		(net "M_G_CPU0_SA_CS_N<0>")
	)
	(gr_poly
		(pts
			(xy 381.483362 -275.690584) (xy 381.483362 -275.646134) (xy 381.127762 -275.646134) (xy 381.127762 -275.690584)
			(xy 381.174752 -275.842984) (xy 381.436372 -275.842984)
		)
		(stroke
			(width 0)
			(type solid)
		)
		(fill yes)
		(layer "In4.Cu")
		(net "M_G_CPU0_SA_DQS_DP<0>")
	)
	(gr_poly
		(pts
			(xy 381.483362 -269.588234) (xy 381.436372 -269.435834) (xy 381.174752 -269.435834) (xy 381.127762 -269.588234)
			(xy 381.127762 -269.632684) (xy 381.483362 -269.632684)
		)
		(stroke
			(width 0)
			(type solid)
		)
		(fill yes)
		(layer "In4.Cu")
		(net "M_F_CPU0_SA_DQS_DP<6>")
	)
	(gr_poly
		(pts
			(xy 381.483362 -265.923522) (xy 381.483362 -265.879326) (xy 381.127762 -265.879326) (xy 381.127762 -265.923522)
			(xy 381.174752 -266.075922) (xy 381.436372 -266.075922)
		)
		(stroke
			(width 0)
			(type solid)
		)
		(fill yes)
		(layer "In4.Cu")
		(net "M_G_CPU0_SA_DQS_DP<2>")
	)
	(gr_poly
		(pts
			(xy 381.483362 -261.040626) (xy 381.483362 -260.996176) (xy 381.127762 -260.996176) (xy 381.127762 -261.040626)
			(xy 381.174752 -261.193026) (xy 381.436372 -261.193026)
		)
		(stroke
			(width 0)
			(type solid)
		)
		(fill yes)
		(layer "In4.Cu")
		(net "M_F_CPU0_SA_DQS_DP<3>")
	)
	(gr_poly
		(pts
			(xy 381.483362 -256.157222) (xy 381.483362 -256.112772) (xy 381.127762 -256.112772) (xy 381.127762 -256.157222)
			(xy 381.174752 -256.309622) (xy 381.436372 -256.309622)
		)
		(stroke
			(width 0)
			(type solid)
		)
		(fill yes)
		(layer "In4.Cu")
		(net "M_G_CPU0_SA_CA<1>")
	)
	(gr_poly
		(pts
			(xy 381.483616 -264.70483) (xy 381.436626 -264.55243) (xy 381.175006 -264.55243) (xy 381.128016 -264.70483)
			(xy 381.128016 -264.74928) (xy 381.483616 -264.74928)
		)
		(stroke
			(width 0)
			(type solid)
		)
		(fill yes)
		(layer "In4.Cu")
		(net "M_G_CPU0_SA_DQS_DP<7>")
	)
	(gr_poly
		(pts
			(xy 381.483616 -259.821426) (xy 381.436626 -259.669026) (xy 381.175006 -259.669026) (xy 381.128016 -259.821426)
			(xy 381.128016 -259.865876) (xy 381.483616 -259.865876)
		)
		(stroke
			(width 0)
			(type solid)
		)
		(fill yes)
		(layer "In4.Cu")
		(net "M_F_CPU0_SA_DQS_DP<8>")
	)
	(gr_poly
		(pts
			(xy 381.48387 -274.471638) (xy 381.43688 -274.319238) (xy 381.17526 -274.319238) (xy 381.12827 -274.471638)
			(xy 381.12827 -274.515834) (xy 381.48387 -274.515834)
		)
		(stroke
			(width 0)
			(type solid)
		)
		(fill yes)
		(layer "In4.Cu")
		(net "M_G_CPU0_SA_DQS_DP<5>")
	)
	(gr_poly
		(pts
			(xy 381.486918 -274.062698) (xy 381.486918 -274.018248) (xy 381.131318 -274.018248) (xy 381.131318 -274.062698)
			(xy 381.178308 -274.215098) (xy 381.439928 -274.215098)
		)
		(stroke
			(width 0)
			(type solid)
		)
		(fill yes)
		(layer "In4.Cu")
		(net "M_G_CPU0_SA_DQ<4>")
	)
	(gr_poly
		(pts
			(xy 381.486918 -271.215866) (xy 381.439928 -271.063466) (xy 381.178308 -271.063466) (xy 381.131318 -271.215866)
			(xy 381.131318 -271.260062) (xy 381.486918 -271.260062)
		)
		(stroke
			(width 0)
			(type solid)
		)
		(fill yes)
		(layer "In4.Cu")
		(net "M_F_CPU0_SA_DQ<11>")
	)
	(gr_poly
		(pts
			(xy 381.486918 -270.806926) (xy 381.486918 -270.76273) (xy 381.131318 -270.76273) (xy 381.131318 -270.806926)
			(xy 381.178308 -270.959326) (xy 381.439928 -270.959326)
		)
		(stroke
			(width 0)
			(type solid)
		)
		(fill yes)
		(layer "In4.Cu")
		(net "M_F_CPU0_SA_DQS_DP<1>")
	)
	(gr_poly
		(pts
			(xy 381.486918 -269.179294) (xy 381.486918 -269.134844) (xy 381.131318 -269.134844) (xy 381.131318 -269.179294)
			(xy 381.178308 -269.331694) (xy 381.439928 -269.331694)
		)
		(stroke
			(width 0)
			(type solid)
		)
		(fill yes)
		(layer "In4.Cu")
		(net "M_F_CPU0_SA_DQ<12>")
	)
	(gr_poly
		(pts
			(xy 381.486918 -267.960094) (xy 381.439928 -267.807694) (xy 381.178308 -267.807694) (xy 381.131318 -267.960094)
			(xy 381.131318 -268.004544) (xy 381.486918 -268.004544)
		)
		(stroke
			(width 0)
			(type solid)
		)
		(fill yes)
		(layer "In4.Cu")
		(net "M_F_CPU0_SA_DQ<13>")
	)
	(gr_poly
		(pts
			(xy 381.486918 -266.332462) (xy 381.439928 -266.180062) (xy 381.178308 -266.180062) (xy 381.131318 -266.332462)
			(xy 381.131318 -266.376658) (xy 381.486918 -266.376658)
		)
		(stroke
			(width 0)
			(type solid)
		)
		(fill yes)
		(layer "In4.Cu")
		(net "M_G_CPU0_SA_DQ<19>")
	)
	(gr_poly
		(pts
			(xy 381.486918 -264.29589) (xy 381.486918 -264.25144) (xy 381.131318 -264.25144) (xy 381.131318 -264.29589)
			(xy 381.178308 -264.44829) (xy 381.439928 -264.44829)
		)
		(stroke
			(width 0)
			(type solid)
		)
		(fill yes)
		(layer "In4.Cu")
		(net "M_G_CPU0_SA_DQ<20>")
	)
	(gr_poly
		(pts
			(xy 381.486918 -263.077198) (xy 381.439928 -262.924798) (xy 381.178308 -262.924798) (xy 381.131318 -263.077198)
			(xy 381.131318 -263.121394) (xy 381.486918 -263.121394)
		)
		(stroke
			(width 0)
			(type solid)
		)
		(fill yes)
		(layer "In4.Cu")
		(net "M_G_CPU0_SA_DQ<23>")
	)
	(gr_poly
		(pts
			(xy 381.486918 -262.668258) (xy 381.486918 -262.623808) (xy 381.131318 -262.623808) (xy 381.131318 -262.668258)
			(xy 381.178308 -262.820658) (xy 381.439928 -262.820658)
		)
		(stroke
			(width 0)
			(type solid)
		)
		(fill yes)
		(layer "In4.Cu")
		(net "M_F_CPU0_SA_DQ<24>")
	)
	(gr_poly
		(pts
			(xy 381.48768 -272.434558) (xy 381.48768 -272.390362) (xy 381.13208 -272.390362) (xy 381.13208 -272.434558)
			(xy 381.17907 -272.586958) (xy 381.44069 -272.586958)
		)
		(stroke
			(width 0)
			(type solid)
		)
		(fill yes)
		(layer "In4.Cu")
		(net "M_F_CPU0_SA_DQ<8>")
	)
	(gr_poly
		(pts
			(xy 381.48768 -267.551154) (xy 381.48768 -267.506958) (xy 381.13208 -267.506958) (xy 381.13208 -267.551154)
			(xy 381.17907 -267.703554) (xy 381.44069 -267.703554)
		)
		(stroke
			(width 0)
			(type solid)
		)
		(fill yes)
		(layer "In4.Cu")
		(net "M_G_CPU0_SA_DQ<16>")
	)
	(gr_poly
		(pts
			(xy 381.48768 -261.449058) (xy 381.44069 -261.296658) (xy 381.17907 -261.296658) (xy 381.13208 -261.449058)
			(xy 381.13208 -261.493508) (xy 381.48768 -261.493508)
		)
		(stroke
			(width 0)
			(type solid)
		)
		(fill yes)
		(layer "In4.Cu")
		(net "M_F_CPU0_SA_DQ<27>")
	)
	(gr_poly
		(pts
			(xy 381.48768 -259.412486) (xy 381.48768 -259.368036) (xy 381.13208 -259.368036) (xy 381.13208 -259.412486)
			(xy 381.17907 -259.564886) (xy 381.44069 -259.564886)
		)
		(stroke
			(width 0)
			(type solid)
		)
		(fill yes)
		(layer "In4.Cu")
		(net "M_F_CPU0_SA_DQ<28>")
	)
	(gr_poly
		(pts
			(xy 381.489458 -254.938022) (xy 381.442468 -254.785622) (xy 381.180848 -254.785622) (xy 381.133858 -254.938022)
			(xy 381.133858 -254.982218) (xy 381.489458 -254.982218)
		)
		(stroke
			(width 0)
			(type solid)
		)
		(fill yes)
		(layer "In4.Cu")
		(net "M_G_CPU0_SA_CA<2>")
	)
	(gr_poly
		(pts
			(xy 381.699262 -224.85223) (xy 381.737616 -224.830132) (xy 381.559816 -224.522284) (xy 381.521462 -224.544382)
			(xy 381.413004 -224.661222) (xy 381.543814 -224.88779)
		)
		(stroke
			(width 0)
			(type solid)
		)
		(fill yes)
		(layer "In4.Cu")
		(net "M_F_CPU0_SB_DQS_DN<3>")
	)
	(gr_poly
		(pts
			(xy 381.737616 -227.20427) (xy 381.699262 -227.182172) (xy 381.543814 -227.146612) (xy 381.413004 -227.37318)
			(xy 381.521462 -227.49002) (xy 381.559816 -227.512118)
		)
		(stroke
			(width 0)
			(type solid)
		)
		(fill yes)
		(layer "In4.Cu")
		(net "M_F_CPU0_SB_DQS_DP<8>")
	)
	(gr_poly
		(pts
			(xy 381.737616 -223.948752) (xy 381.699262 -223.926654) (xy 381.543814 -223.891094) (xy 381.413004 -224.117662)
			(xy 381.521462 -224.234502) (xy 381.559816 -224.2566)
		)
		(stroke
			(width 0)
			(type solid)
		)
		(fill yes)
		(layer "In4.Cu")
		(net "M_F_CPU0_SB_DQS_DN<3>")
	)
	(gr_poly
		(pts
			(xy 381.739648 -225.572574) (xy 381.701294 -225.550476) (xy 381.545846 -225.514916) (xy 381.415036 -225.741484)
			(xy 381.523494 -225.858324) (xy 381.561848 -225.880422)
		)
		(stroke
			(width 0)
			(type solid)
		)
		(fill yes)
		(layer "In4.Cu")
		(net "M_F_CPU0_SB_DQS_DN<3>")
	)
	(gr_poly
		(pts
			(xy 381.835152 -247.382538) (xy 381.788162 -247.230138) (xy 381.526542 -247.230138) (xy 381.479552 -247.382538)
			(xy 381.479552 -247.426734) (xy 381.835152 -247.426734)
		)
		(stroke
			(width 0)
			(type solid)
		)
		(fill yes)
		(layer "In4.Cu")
		(net "M_G_CPU0_SB_PAR")
	)
	(gr_poly
		(pts
			(xy 381.837438 -246.974106) (xy 381.837438 -246.92991) (xy 381.481838 -246.92991) (xy 381.481838 -246.974106)
			(xy 381.528828 -247.126506) (xy 381.790448 -247.126506)
		)
		(stroke
			(width 0)
			(type solid)
		)
		(fill yes)
		(layer "In4.Cu")
		(net "M_G_CPU0_SB_CS_N<2>")
	)
	(gr_poly
		(pts
			(xy 381.837438 -237.61573) (xy 381.790448 -237.46333) (xy 381.528828 -237.46333) (xy 381.481838 -237.61573)
			(xy 381.481838 -237.66018) (xy 381.837438 -237.66018)
		)
		(stroke
			(width 0)
			(type solid)
		)
		(fill yes)
		(layer "In4.Cu")
		(net "M_F_CPU0_SB_DQS_DN<0>")
	)
	(gr_poly
		(pts
			(xy 381.837438 -237.207806) (xy 381.837438 -237.163356) (xy 381.481838 -237.163356) (xy 381.481838 -237.207806)
			(xy 381.528828 -237.360206) (xy 381.790448 -237.360206)
		)
		(stroke
			(width 0)
			(type solid)
		)
		(fill yes)
		(layer "In4.Cu")
		(net "M_F_CPU0_SB_DQS_DN<5>")
	)
	(gr_poly
		(pts
			(xy 381.837438 -232.732326) (xy 381.790448 -232.579926) (xy 381.528828 -232.579926) (xy 381.481838 -232.732326)
			(xy 381.481838 -232.776776) (xy 381.837438 -232.776776)
		)
		(stroke
			(width 0)
			(type solid)
		)
		(fill yes)
		(layer "In4.Cu")
		(net "M_G_CPU0_SB_DQS_DN<2>")
	)
	(gr_poly
		(pts
			(xy 381.837438 -232.324402) (xy 381.837438 -232.279952) (xy 381.481838 -232.279952) (xy 381.481838 -232.324402)
			(xy 381.528828 -232.476802) (xy 381.790448 -232.476802)
		)
		(stroke
			(width 0)
			(type solid)
		)
		(fill yes)
		(layer "In4.Cu")
		(net "M_G_CPU0_SB_DQS_DN<7>")
	)
	(gr_poly
		(pts
			(xy 381.840232 -244.127274) (xy 381.793242 -243.974874) (xy 381.531622 -243.974874) (xy 381.484632 -244.127274)
			(xy 381.484632 -244.17147) (xy 381.840232 -244.17147)
		)
		(stroke
			(width 0)
			(type solid)
		)
		(fill yes)
		(layer "In4.Cu")
		(net "M_G_CPU0_SB_CB<6>")
	)
	(gr_poly
		(pts
			(xy 381.840232 -238.83493) (xy 381.840232 -238.790734) (xy 381.484632 -238.790734) (xy 381.484632 -238.83493)
			(xy 381.531622 -238.98733) (xy 381.793242 -238.98733)
		)
		(stroke
			(width 0)
			(type solid)
		)
		(fill yes)
		(layer "In4.Cu")
		(net "M_F_CPU0_SB_DQ<1>")
	)
	(gr_poly
		(pts
			(xy 381.840232 -235.988606) (xy 381.793242 -235.836206) (xy 381.531622 -235.836206) (xy 381.484632 -235.988606)
			(xy 381.484632 -236.032802) (xy 381.840232 -236.032802)
		)
		(stroke
			(width 0)
			(type solid)
		)
		(fill yes)
		(layer "In4.Cu")
		(net "M_F_CPU0_SB_DQ<6>")
	)
	(gr_poly
		(pts
			(xy 381.840232 -233.951526) (xy 381.840232 -233.90733) (xy 381.484632 -233.90733) (xy 381.484632 -233.951526)
			(xy 381.531622 -234.103926) (xy 381.793242 -234.103926)
		)
		(stroke
			(width 0)
			(type solid)
		)
		(fill yes)
		(layer "In4.Cu")
		(net "M_G_CPU0_SB_DQ<17>")
	)
	(gr_poly
		(pts
			(xy 381.840232 -231.105202) (xy 381.793242 -230.952802) (xy 381.531622 -230.952802) (xy 381.484632 -231.105202)
			(xy 381.484632 -231.149398) (xy 381.840232 -231.149398)
		)
		(stroke
			(width 0)
			(type solid)
		)
		(fill yes)
		(layer "In4.Cu")
		(net "M_G_CPU0_SB_DQ<22>")
	)
	(gr_poly
		(pts
			(xy 381.841248 -243.718334) (xy 381.841248 -243.674138) (xy 381.485648 -243.674138) (xy 381.485648 -243.718334)
			(xy 381.532638 -243.870734) (xy 381.794258 -243.870734)
		)
		(stroke
			(width 0)
			(type solid)
		)
		(fill yes)
		(layer "In4.Cu")
		(net "M_G_CPU0_SB_CB<5>")
	)
	(gr_poly
		(pts
			(xy 381.841248 -240.871502) (xy 381.794258 -240.719102) (xy 381.532638 -240.719102) (xy 381.485648 -240.871502)
			(xy 381.485648 -240.915952) (xy 381.841248 -240.915952)
		)
		(stroke
			(width 0)
			(type solid)
		)
		(fill yes)
		(layer "In4.Cu")
		(net "M_G_CPU0_SB_CB<2>")
	)
	(gr_poly
		(pts
			(xy 381.841248 -240.46307) (xy 381.841248 -240.41862) (xy 381.485648 -240.41862) (xy 381.485648 -240.46307)
			(xy 381.532638 -240.61547) (xy 381.794258 -240.61547)
		)
		(stroke
			(width 0)
			(type solid)
		)
		(fill yes)
		(layer "In4.Cu")
		(net "M_G_CPU0_SB_CB<1>")
	)
	(gr_poly
		(pts
			(xy 381.841248 -239.24387) (xy 381.794258 -239.09147) (xy 381.532638 -239.09147) (xy 381.485648 -239.24387)
			(xy 381.485648 -239.288066) (xy 381.841248 -239.288066)
		)
		(stroke
			(width 0)
			(type solid)
		)
		(fill yes)
		(layer "In4.Cu")
		(net "M_F_CPU0_SB_DQ<2>")
	)
	(gr_poly
		(pts
			(xy 381.841248 -235.579666) (xy 381.841248 -235.535216) (xy 381.485648 -235.535216) (xy 381.485648 -235.579666)
			(xy 381.532638 -235.732066) (xy 381.794258 -235.732066)
		)
		(stroke
			(width 0)
			(type solid)
		)
		(fill yes)
		(layer "In4.Cu")
		(net "M_F_CPU0_SB_DQ<5>")
	)
	(gr_poly
		(pts
			(xy 381.841248 -230.696262) (xy 381.841248 -230.651812) (xy 381.485648 -230.651812) (xy 381.485648 -230.696262)
			(xy 381.532638 -230.848662) (xy 381.794258 -230.848662)
		)
		(stroke
			(width 0)
			(type solid)
		)
		(fill yes)
		(layer "In4.Cu")
		(net "M_G_CPU0_SB_DQ<21>")
	)
	(gr_poly
		(pts
			(xy 381.843534 -249.010678) (xy 381.796544 -248.858278) (xy 381.534924 -248.858278) (xy 381.487934 -249.010678)
			(xy 381.487934 -249.054874) (xy 381.843534 -249.054874)
		)
		(stroke
			(width 0)
			(type solid)
		)
		(fill yes)
		(layer "In4.Cu")
		(net "M_G_CPU0_SB_CA<3>")
	)
	(gr_poly
		(pts
			(xy 381.843534 -248.601738) (xy 381.843534 -248.557542) (xy 381.487934 -248.557542) (xy 381.487934 -248.601738)
			(xy 381.534924 -248.754138) (xy 381.796544 -248.754138)
		)
		(stroke
			(width 0)
			(type solid)
		)
		(fill yes)
		(layer "In4.Cu")
		(net "M_G_CPU0_SB_CA<4>")
	)
	(gr_poly
		(pts
			(xy 381.843534 -245.754906) (xy 381.796544 -245.602506) (xy 381.534924 -245.602506) (xy 381.487934 -245.754906)
			(xy 381.487934 -245.799356) (xy 381.843534 -245.799356)
		)
		(stroke
			(width 0)
			(type solid)
		)
		(fill yes)
		(layer "In4.Cu")
		(net "M_G_CPU0_SB_CS_N<1>")
	)
	(gr_poly
		(pts
			(xy 381.843534 -242.499642) (xy 381.796544 -242.347242) (xy 381.534924 -242.347242) (xy 381.487934 -242.499642)
			(xy 381.487934 -242.544092) (xy 381.843534 -242.544092)
		)
		(stroke
			(width 0)
			(type solid)
		)
		(fill yes)
		(layer "In4.Cu")
		(net "M_G_CPU0_SB_DQS_DN<9>")
	)
	(gr_poly
		(pts
			(xy 381.843534 -242.090702) (xy 381.843534 -242.046252) (xy 381.487934 -242.046252) (xy 381.487934 -242.090702)
			(xy 381.534924 -242.243102) (xy 381.796544 -242.243102)
		)
		(stroke
			(width 0)
			(type solid)
		)
		(fill yes)
		(layer "In4.Cu")
		(net "M_G_CPU0_SB_DQS_DN<4>")
	)
	(gr_poly
		(pts
			(xy 381.843534 -234.360466) (xy 381.796544 -234.208066) (xy 381.534924 -234.208066) (xy 381.487934 -234.360466)
			(xy 381.487934 -234.404916) (xy 381.843534 -234.404916)
		)
		(stroke
			(width 0)
			(type solid)
		)
		(fill yes)
		(layer "In4.Cu")
		(net "M_G_CPU0_SB_DQ<18>")
	)
	(gr_poly
		(pts
			(xy 381.843534 -229.06863) (xy 381.843534 -229.02418) (xy 381.487934 -229.02418) (xy 381.487934 -229.06863)
			(xy 381.534924 -229.22103) (xy 381.796544 -229.22103)
		)
		(stroke
			(width 0)
			(type solid)
		)
		(fill yes)
		(layer "In4.Cu")
		(net "M_F_CPU0_SB_DQ<27>")
	)
	(gr_poly
		(pts
			(xy 381.843534 -222.557086) (xy 381.843534 -222.51289) (xy 381.487934 -222.51289) (xy 381.487934 -222.557086)
			(xy 381.534924 -222.709486) (xy 381.796544 -222.709486)
		)
		(stroke
			(width 0)
			(type solid)
		)
		(fill yes)
		(layer "In4.Cu")
		(net "M_F_CPU0_SB_DQ<30>")
	)
	(gr_poly
		(pts
			(xy 381.843534 -219.710254) (xy 381.796544 -219.557854) (xy 381.534924 -219.557854) (xy 381.487934 -219.710254)
			(xy 381.487934 -219.754704) (xy 381.843534 -219.754704)
		)
		(stroke
			(width 0)
			(type solid)
		)
		(fill yes)
		(layer "In4.Cu")
		(net "M_F_CPU0_SB_DQ<31>")
	)
	(gr_poly
		(pts
			(xy 381.916432 -227.920804) (xy 381.807974 -227.803964) (xy 381.76962 -227.781866) (xy 381.59182 -228.089714)
			(xy 381.630174 -228.111812) (xy 381.785622 -228.147372)
		)
		(stroke
			(width 0)
			(type solid)
		)
		(fill yes)
		(layer "In4.Cu")
		(net "M_F_CPU0_SB_DQS_DN<8>")
	)
	(gr_poly
		(pts
			(xy 381.918464 -226.289108) (xy 381.810006 -226.172268) (xy 381.771652 -226.15017) (xy 381.593852 -226.458018)
			(xy 381.632206 -226.480116) (xy 381.787654 -226.515676)
		)
		(stroke
			(width 0)
			(type solid)
		)
		(fill yes)
		(layer "In4.Cu")
		(net "M_F_CPU0_SB_DQS_DP<3>")
	)
	(gr_poly
		(pts
			(xy 381.94742 -257.37947) (xy 381.90043 -257.22707) (xy 381.63881 -257.22707) (xy 381.59182 -257.37947)
			(xy 381.59182 -257.42392) (xy 381.94742 -257.42392)
		)
		(stroke
			(width 0)
			(type solid)
		)
		(fill yes)
		(layer "In4.Cu")
		(net "M_G_CPU0_SA_CS_N<1>")
	)
	(gr_poly
		(pts
			(xy 381.949198 -272.029682) (xy 381.902208 -271.877282) (xy 381.640588 -271.877282) (xy 381.593598 -272.029682)
			(xy 381.593598 -272.074132) (xy 381.949198 -272.074132)
		)
		(stroke
			(width 0)
			(type solid)
		)
		(fill yes)
		(layer "In4.Cu")
		(net "M_F_CPU0_SA_DQ<10>")
	)
	(gr_poly
		(pts
			(xy 381.949198 -267.146278) (xy 381.902208 -266.993878) (xy 381.640588 -266.993878) (xy 381.593598 -267.146278)
			(xy 381.593598 -267.190728) (xy 381.949198 -267.190728)
		)
		(stroke
			(width 0)
			(type solid)
		)
		(fill yes)
		(layer "In4.Cu")
		(net "M_G_CPU0_SA_DQ<18>")
	)
	(gr_poly
		(pts
			(xy 381.949198 -261.854442) (xy 381.949198 -261.809992) (xy 381.593598 -261.809992) (xy 381.593598 -261.854442)
			(xy 381.640588 -262.006842) (xy 381.902208 -262.006842)
		)
		(stroke
			(width 0)
			(type solid)
		)
		(fill yes)
		(layer "In4.Cu")
		(net "M_F_CPU0_SA_DQ<25>")
	)
	(gr_poly
		(pts
			(xy 381.949198 -259.00761) (xy 381.902208 -258.85521) (xy 381.640588 -258.85521) (xy 381.593598 -259.00761)
			(xy 381.593598 -259.051806) (xy 381.949198 -259.051806)
		)
		(stroke
			(width 0)
			(type solid)
		)
		(fill yes)
		(layer "In4.Cu")
		(net "M_F_CPU0_SA_DQ<30>")
	)
	(gr_poly
		(pts
			(xy 381.94996 -273.657314) (xy 381.90297 -273.504914) (xy 381.64135 -273.504914) (xy 381.59436 -273.657314)
			(xy 381.59436 -273.701764) (xy 381.94996 -273.701764)
		)
		(stroke
			(width 0)
			(type solid)
		)
		(fill yes)
		(layer "In4.Cu")
		(net "M_G_CPU0_SA_DQ<6>")
	)
	(gr_poly
		(pts
			(xy 381.94996 -271.620742) (xy 381.94996 -271.576546) (xy 381.59436 -271.576546) (xy 381.59436 -271.620742)
			(xy 381.64135 -271.773142) (xy 381.90297 -271.773142)
		)
		(stroke
			(width 0)
			(type solid)
		)
		(fill yes)
		(layer "In4.Cu")
		(net "M_F_CPU0_SA_DQ<9>")
	)
	(gr_poly
		(pts
			(xy 381.94996 -268.77391) (xy 381.90297 -268.62151) (xy 381.64135 -268.62151) (xy 381.59436 -268.77391)
			(xy 381.59436 -268.81836) (xy 381.94996 -268.81836)
		)
		(stroke
			(width 0)
			(type solid)
		)
		(fill yes)
		(layer "In4.Cu")
		(net "M_F_CPU0_SA_DQ<14>")
	)
	(gr_poly
		(pts
			(xy 381.94996 -268.365478) (xy 381.94996 -268.321028) (xy 381.59436 -268.321028) (xy 381.59436 -268.365478)
			(xy 381.64135 -268.517878) (xy 381.90297 -268.517878)
		)
		(stroke
			(width 0)
			(type solid)
		)
		(fill yes)
		(layer "In4.Cu")
		(net "M_F_CPU0_SA_DQ<15>")
	)
	(gr_poly
		(pts
			(xy 381.94996 -266.737338) (xy 381.94996 -266.693142) (xy 381.59436 -266.693142) (xy 381.59436 -266.737338)
			(xy 381.64135 -266.889738) (xy 381.90297 -266.889738)
		)
		(stroke
			(width 0)
			(type solid)
		)
		(fill yes)
		(layer "In4.Cu")
		(net "M_G_CPU0_SA_DQ<17>")
	)
	(gr_poly
		(pts
			(xy 381.94996 -263.891014) (xy 381.90297 -263.738614) (xy 381.64135 -263.738614) (xy 381.59436 -263.891014)
			(xy 381.59436 -263.93521) (xy 381.94996 -263.93521)
		)
		(stroke
			(width 0)
			(type solid)
		)
		(fill yes)
		(layer "In4.Cu")
		(net "M_G_CPU0_SA_DQ<22>")
	)
	(gr_poly
		(pts
			(xy 381.94996 -263.482074) (xy 381.94996 -263.437624) (xy 381.59436 -263.437624) (xy 381.59436 -263.482074)
			(xy 381.64135 -263.634474) (xy 381.90297 -263.634474)
		)
		(stroke
			(width 0)
			(type solid)
		)
		(fill yes)
		(layer "In4.Cu")
		(net "M_G_CPU0_SA_DQ<21>")
	)
	(gr_poly
		(pts
			(xy 381.94996 -262.262874) (xy 381.90297 -262.110474) (xy 381.64135 -262.110474) (xy 381.59436 -262.262874)
			(xy 381.59436 -262.307324) (xy 381.94996 -262.307324)
		)
		(stroke
			(width 0)
			(type solid)
		)
		(fill yes)
		(layer "In4.Cu")
		(net "M_F_CPU0_SA_DQ<26>")
	)
	(gr_poly
		(pts
			(xy 381.953516 -270.40205) (xy 381.906526 -270.24965) (xy 381.644906 -270.24965) (xy 381.597916 -270.40205)
			(xy 381.597916 -270.446246) (xy 381.953516 -270.446246)
		)
		(stroke
			(width 0)
			(type solid)
		)
		(fill yes)
		(layer "In4.Cu")
		(net "M_F_CPU0_SA_DQS_DN<1>")
	)
	(gr_poly
		(pts
			(xy 381.953516 -258.59867) (xy 381.953516 -258.554474) (xy 381.597916 -258.554474) (xy 381.597916 -258.59867)
			(xy 381.644906 -258.75107) (xy 381.906526 -258.75107)
		)
		(stroke
			(width 0)
			(type solid)
		)
		(fill yes)
		(layer "In4.Cu")
		(net "M_F_CPU0_SA_DQ<29>")
	)
	(gr_poly
		(pts
			(xy 381.959358 -275.284946) (xy 381.912368 -275.132546) (xy 381.650748 -275.132546) (xy 381.603758 -275.284946)
			(xy 381.603758 -275.329142) (xy 381.959358 -275.329142)
		)
		(stroke
			(width 0)
			(type solid)
		)
		(fill yes)
		(layer "In4.Cu")
		(net "M_G_CPU0_SA_DQS_DN<0>")
	)
	(gr_poly
		(pts
			(xy 381.959358 -274.876514) (xy 381.959358 -274.832318) (xy 381.603758 -274.832318) (xy 381.603758 -274.876514)
			(xy 381.650748 -275.028914) (xy 381.912368 -275.028914)
		)
		(stroke
			(width 0)
			(type solid)
		)
		(fill yes)
		(layer "In4.Cu")
		(net "M_G_CPU0_SA_DQS_DN<5>")
	)
	(gr_poly
		(pts
			(xy 381.959358 -269.993618) (xy 381.959358 -269.949168) (xy 381.603758 -269.949168) (xy 381.603758 -269.993618)
			(xy 381.650748 -270.146018) (xy 381.912368 -270.146018)
		)
		(stroke
			(width 0)
			(type solid)
		)
		(fill yes)
		(layer "In4.Cu")
		(net "M_F_CPU0_SA_DQS_DN<6>")
	)
	(gr_poly
		(pts
			(xy 381.959358 -265.518138) (xy 381.912368 -265.365738) (xy 381.650748 -265.365738) (xy 381.603758 -265.518138)
			(xy 381.603758 -265.562588) (xy 381.959358 -265.562588)
		)
		(stroke
			(width 0)
			(type solid)
		)
		(fill yes)
		(layer "In4.Cu")
		(net "M_G_CPU0_SA_DQS_DN<2>")
	)
	(gr_poly
		(pts
			(xy 381.959358 -265.110214) (xy 381.959358 -265.065764) (xy 381.603758 -265.065764) (xy 381.603758 -265.110214)
			(xy 381.650748 -265.262614) (xy 381.912368 -265.262614)
		)
		(stroke
			(width 0)
			(type solid)
		)
		(fill yes)
		(layer "In4.Cu")
		(net "M_G_CPU0_SA_DQS_DN<7>")
	)
	(gr_poly
		(pts
			(xy 381.959358 -260.634734) (xy 381.912368 -260.482334) (xy 381.650748 -260.482334) (xy 381.603758 -260.634734)
			(xy 381.603758 -260.679184) (xy 381.959358 -260.679184)
		)
		(stroke
			(width 0)
			(type solid)
		)
		(fill yes)
		(layer "In4.Cu")
		(net "M_F_CPU0_SA_DQS_DN<3>")
	)
	(gr_poly
		(pts
			(xy 381.959358 -260.22681) (xy 381.959358 -260.18236) (xy 381.603758 -260.18236) (xy 381.603758 -260.22681)
			(xy 381.650748 -260.37921) (xy 381.912368 -260.37921)
		)
		(stroke
			(width 0)
			(type solid)
		)
		(fill yes)
		(layer "In4.Cu")
		(net "M_F_CPU0_SA_DQS_DN<8>")
	)
	(gr_poly
		(pts
			(xy 381.959358 -256.971038) (xy 381.959358 -256.926588) (xy 381.603758 -256.926588) (xy 381.603758 -256.971038)
			(xy 381.650748 -257.123438) (xy 381.912368 -257.123438)
		)
		(stroke
			(width 0)
			(type solid)
		)
		(fill yes)
		(layer "In4.Cu")
		(net "M_G_CPU0_SA_CS_N<2>")
	)
	(gr_poly
		(pts
			(xy 381.959358 -255.751838) (xy 381.912368 -255.599438) (xy 381.650748 -255.599438) (xy 381.603758 -255.751838)
			(xy 381.603758 -255.796034) (xy 381.959358 -255.796034)
		)
		(stroke
			(width 0)
			(type solid)
		)
		(fill yes)
		(layer "In4.Cu")
		(net "M_G_CPU0_SA_CA<0>")
	)
	(gr_poly
		(pts
			(xy 381.959358 -255.343406) (xy 381.959358 -255.29921) (xy 381.603758 -255.29921) (xy 381.603758 -255.343406)
			(xy 381.650748 -255.495806) (xy 381.912368 -255.495806)
		)
		(stroke
			(width 0)
			(type solid)
		)
		(fill yes)
		(layer "In4.Cu")
		(net "M_G_CPU0_SA_CA<3>")
	)
	(gr_poly
		(pts
			(xy 381.961898 -276.912578) (xy 381.914908 -276.760178) (xy 381.653288 -276.760178) (xy 381.606298 -276.912578)
			(xy 381.606298 -276.957028) (xy 381.961898 -276.957028)
		)
		(stroke
			(width 0)
			(type solid)
		)
		(fill yes)
		(layer "In4.Cu")
		(net "M_G_CPU0_SA_DQ<2>")
	)
	(gr_poly
		(pts
			(xy 381.961898 -276.5044) (xy 381.961898 -276.460204) (xy 381.606298 -276.460204) (xy 381.606298 -276.5044)
			(xy 381.653288 -276.6568) (xy 381.914908 -276.6568)
		)
		(stroke
			(width 0)
			(type solid)
		)
		(fill yes)
		(layer "In4.Cu")
		(net "M_G_CPU0_SA_DQ<1>")
	)
	(gr_poly
		(pts
			(xy 381.961898 -273.248882) (xy 381.961898 -273.204686) (xy 381.606298 -273.204686) (xy 381.606298 -273.248882)
			(xy 381.653288 -273.401282) (xy 381.914908 -273.401282)
		)
		(stroke
			(width 0)
			(type solid)
		)
		(fill yes)
		(layer "In4.Cu")
		(net "M_G_CPU0_SA_DQ<5>")
	)
	(gr_poly
		(pts
			(xy 382.202944 -226.397566) (xy 382.16459 -226.375468) (xy 382.009142 -226.339908) (xy 381.878332 -226.566476)
			(xy 381.98679 -226.683316) (xy 382.025144 -226.705414)
		)
		(stroke
			(width 0)
			(type solid)
		)
		(fill yes)
		(layer "In4.Cu")
		(net "M_F_CPU0_SB_DQS_DP<8>")
	)
	(gr_poly
		(pts
			(xy 382.202944 -221.514162) (xy 382.16459 -221.492064) (xy 382.009142 -221.456504) (xy 381.878332 -221.683072)
			(xy 381.98679 -221.799912) (xy 382.025144 -221.82201)
		)
		(stroke
			(width 0)
			(type solid)
		)
		(fill yes)
		(layer "In4.Cu")
		(net "M_F_CPU0_SB_DQ<28>")
	)
	(gr_poly
		(pts
			(xy 382.208278 -228.016308) (xy 382.169924 -227.99421) (xy 382.014476 -227.95865) (xy 381.883666 -228.185218)
			(xy 381.992124 -228.302058) (xy 382.030478 -228.324156)
		)
		(stroke
			(width 0)
			(type solid)
		)
		(fill yes)
		(layer "In4.Cu")
		(net "M_F_CPU0_SB_DQ<25>")
	)
	(gr_poly
		(pts
			(xy 382.209548 -223.130872) (xy 382.171194 -223.108774) (xy 382.015746 -223.073214) (xy 381.884936 -223.299782)
			(xy 381.993394 -223.416622) (xy 382.031748 -223.43872)
		)
		(stroke
			(width 0)
			(type solid)
		)
		(fill yes)
		(layer "In4.Cu")
		(net "M_F_CPU0_SB_DQS_DN<3>")
	)
	(gr_poly
		(pts
			(xy 382.279906 -225.048318) (xy 382.388364 -224.931478) (xy 382.257554 -224.70491) (xy 382.102106 -224.74047)
			(xy 382.063752 -224.762568) (xy 382.241552 -225.070416)
		)
		(stroke
			(width 0)
			(type solid)
		)
		(fill yes)
		(layer "In4.Cu")
		(net "M_F_CPU0_SB_DQS_DP<3>")
	)
	(gr_poly
		(pts
			(xy 382.280922 -277.989284) (xy 382.319276 -277.967186) (xy 382.141476 -277.659338) (xy 382.103122 -277.681436)
			(xy 381.994664 -277.798276) (xy 382.125474 -278.024844)
		)
		(stroke
			(width 0)
			(type solid)
		)
		(fill yes)
		(layer "In4.Cu")
		(net "M_G_CPU0_SA_DQ<0>")
	)
	(gr_poly
		(pts
			(xy 382.307338 -242.904518) (xy 382.307338 -242.860322) (xy 381.951738 -242.860322) (xy 381.951738 -242.904518)
			(xy 381.998728 -243.056918) (xy 382.260348 -243.056918)
		)
		(stroke
			(width 0)
			(type solid)
		)
		(fill yes)
		(layer "In4.Cu")
		(net "M_G_CPU0_SB_DQS_DP<9>")
	)
	(gr_poly
		(pts
			(xy 382.307338 -220.115638) (xy 382.307338 -220.071188) (xy 381.951738 -220.071188) (xy 381.951738 -220.115638)
			(xy 381.998728 -220.268038) (xy 382.260348 -220.268038)
		)
		(stroke
			(width 0)
			(type solid)
		)
		(fill yes)
		(layer "In4.Cu")
		(net "M_F_CPU0_SB_DQ<29>")
	)
	(gr_poly
		(pts
			(xy 382.31318 -244.53215) (xy 382.31318 -244.487954) (xy 381.95758 -244.487954) (xy 381.95758 -244.53215)
			(xy 382.00457 -244.68455) (xy 382.26619 -244.68455)
		)
		(stroke
			(width 0)
			(type solid)
		)
		(fill yes)
		(layer "In4.Cu")
		(net "M_G_CPU0_SB_CB<4>")
	)
	(gr_poly
		(pts
			(xy 382.31318 -243.313458) (xy 382.26619 -243.161058) (xy 382.00457 -243.161058) (xy 381.95758 -243.313458)
			(xy 381.95758 -243.357654) (xy 382.31318 -243.357654)
		)
		(stroke
			(width 0)
			(type solid)
		)
		(fill yes)
		(layer "In4.Cu")
		(net "M_G_CPU0_SB_CB<7>")
	)
	(gr_poly
		(pts
			(xy 382.31318 -241.276886) (xy 382.31318 -241.232436) (xy 381.95758 -241.232436) (xy 381.95758 -241.276886)
			(xy 382.00457 -241.429286) (xy 382.26619 -241.429286)
		)
		(stroke
			(width 0)
			(type solid)
		)
		(fill yes)
		(layer "In4.Cu")
		(net "M_G_CPU0_SB_CB<0>")
	)
	(gr_poly
		(pts
			(xy 382.31318 -240.057686) (xy 382.26619 -239.905286) (xy 382.00457 -239.905286) (xy 381.95758 -240.057686)
			(xy 381.95758 -240.102136) (xy 382.31318 -240.102136)
		)
		(stroke
			(width 0)
			(type solid)
		)
		(fill yes)
		(layer "In4.Cu")
		(net "M_G_CPU0_SB_CB<3>")
	)
	(gr_poly
		(pts
			(xy 382.31318 -239.648746) (xy 382.31318 -239.60455) (xy 381.95758 -239.60455) (xy 381.95758 -239.648746)
			(xy 382.00457 -239.801146) (xy 382.26619 -239.801146)
		)
		(stroke
			(width 0)
			(type solid)
		)
		(fill yes)
		(layer "In4.Cu")
		(net "M_F_CPU0_SB_DQ<0>")
	)
	(gr_poly
		(pts
			(xy 382.31318 -238.430054) (xy 382.26619 -238.277654) (xy 382.00457 -238.277654) (xy 381.95758 -238.430054)
			(xy 381.95758 -238.47425) (xy 382.31318 -238.47425)
		)
		(stroke
			(width 0)
			(type solid)
		)
		(fill yes)
		(layer "In4.Cu")
		(net "M_F_CPU0_SB_DQ<3>")
	)
	(gr_poly
		(pts
			(xy 382.31318 -236.393482) (xy 382.31318 -236.349032) (xy 381.95758 -236.349032) (xy 381.95758 -236.393482)
			(xy 382.00457 -236.545882) (xy 382.26619 -236.545882)
		)
		(stroke
			(width 0)
			(type solid)
		)
		(fill yes)
		(layer "In4.Cu")
		(net "M_F_CPU0_SB_DQ<4>")
	)
	(gr_poly
		(pts
			(xy 382.31318 -235.174282) (xy 382.26619 -235.021882) (xy 382.00457 -235.021882) (xy 381.95758 -235.174282)
			(xy 381.95758 -235.218732) (xy 382.31318 -235.218732)
		)
		(stroke
			(width 0)
			(type solid)
		)
		(fill yes)
		(layer "In4.Cu")
		(net "M_F_CPU0_SB_DQ<7>")
	)
	(gr_poly
		(pts
			(xy 382.31318 -233.54665) (xy 382.26619 -233.39425) (xy 382.00457 -233.39425) (xy 381.95758 -233.54665)
			(xy 381.95758 -233.5911) (xy 382.31318 -233.5911)
		)
		(stroke
			(width 0)
			(type solid)
		)
		(fill yes)
		(layer "In4.Cu")
		(net "M_G_CPU0_SB_DQ<19>")
	)
	(gr_poly
		(pts
			(xy 382.31318 -231.510078) (xy 382.31318 -231.465628) (xy 381.95758 -231.465628) (xy 381.95758 -231.510078)
			(xy 382.00457 -231.662478) (xy 382.26619 -231.662478)
		)
		(stroke
			(width 0)
			(type solid)
		)
		(fill yes)
		(layer "In4.Cu")
		(net "M_G_CPU0_SB_DQ<20>")
	)
	(gr_poly
		(pts
			(xy 382.31318 -230.290878) (xy 382.26619 -230.138478) (xy 382.00457 -230.138478) (xy 381.95758 -230.290878)
			(xy 381.95758 -230.335328) (xy 382.31318 -230.335328)
		)
		(stroke
			(width 0)
			(type solid)
		)
		(fill yes)
		(layer "In4.Cu")
		(net "M_G_CPU0_SB_DQ<23>")
	)
	(gr_poly
		(pts
			(xy 382.31318 -229.882446) (xy 382.31318 -229.837996) (xy 381.95758 -229.837996) (xy 381.95758 -229.882446)
			(xy 382.00457 -230.034846) (xy 382.26619 -230.034846)
		)
		(stroke
			(width 0)
			(type solid)
		)
		(fill yes)
		(layer "In4.Cu")
		(net "M_F_CPU0_SB_DQ<26>")
	)
	(gr_poly
		(pts
			(xy 382.313434 -249.415554) (xy 382.313434 -249.371358) (xy 381.957834 -249.371358) (xy 381.957834 -249.415554)
			(xy 382.004824 -249.567954) (xy 382.266444 -249.567954)
		)
		(stroke
			(width 0)
			(type solid)
		)
		(fill yes)
		(layer "In4.Cu")
		(net "M_G_CPU0_SB_CA<2>")
	)
	(gr_poly
		(pts
			(xy 382.313434 -248.196354) (xy 382.266444 -248.043954) (xy 382.004824 -248.043954) (xy 381.957834 -248.196354)
			(xy 381.957834 -248.240804) (xy 382.313434 -248.240804)
		)
		(stroke
			(width 0)
			(type solid)
		)
		(fill yes)
		(layer "In4.Cu")
		(net "M_G_CPU0_SB_CA<5>")
	)
	(gr_poly
		(pts
			(xy 382.313434 -246.568722) (xy 382.266444 -246.416322) (xy 382.004824 -246.416322) (xy 381.957834 -246.568722)
			(xy 381.957834 -246.613172) (xy 382.313434 -246.613172)
		)
		(stroke
			(width 0)
			(type solid)
		)
		(fill yes)
		(layer "In4.Cu")
		(net "M_G_CPU0_SB_CS_N<0>")
	)
	(gr_poly
		(pts
			(xy 382.313434 -246.16029) (xy 382.313434 -246.11584) (xy 381.957834 -246.11584) (xy 381.957834 -246.16029)
			(xy 382.004824 -246.31269) (xy 382.266444 -246.31269)
		)
		(stroke
			(width 0)
			(type solid)
		)
		(fill yes)
		(layer "In4.Cu")
		(net "M_G_CPU0_SB_CS_N<3>")
	)
	(gr_poly
		(pts
			(xy 382.313434 -238.021114) (xy 382.313434 -237.976918) (xy 381.957834 -237.976918) (xy 381.957834 -238.021114)
			(xy 382.004824 -238.173514) (xy 382.266444 -238.173514)
		)
		(stroke
			(width 0)
			(type solid)
		)
		(fill yes)
		(layer "In4.Cu")
		(net "M_F_CPU0_SB_DQS_DP<0>")
	)
	(gr_poly
		(pts
			(xy 382.313434 -236.801914) (xy 382.266444 -236.649514) (xy 382.004824 -236.649514) (xy 381.957834 -236.801914)
			(xy 381.957834 -236.846364) (xy 382.313434 -236.846364)
		)
		(stroke
			(width 0)
			(type solid)
		)
		(fill yes)
		(layer "In4.Cu")
		(net "M_F_CPU0_SB_DQS_DP<5>")
	)
	(gr_poly
		(pts
			(xy 382.313434 -234.76585) (xy 382.313434 -234.7214) (xy 381.957834 -234.7214) (xy 381.957834 -234.76585)
			(xy 382.004824 -234.91825) (xy 382.266444 -234.91825)
		)
		(stroke
			(width 0)
			(type solid)
		)
		(fill yes)
		(layer "In4.Cu")
		(net "M_G_CPU0_SB_DQ<16>")
	)
	(gr_poly
		(pts
			(xy 382.313434 -233.13771) (xy 382.313434 -233.093514) (xy 381.957834 -233.093514) (xy 381.957834 -233.13771)
			(xy 382.004824 -233.29011) (xy 382.266444 -233.29011)
		)
		(stroke
			(width 0)
			(type solid)
		)
		(fill yes)
		(layer "In4.Cu")
		(net "M_G_CPU0_SB_DQS_DP<2>")
	)
	(gr_poly
		(pts
			(xy 382.313434 -231.919018) (xy 382.266444 -231.766618) (xy 382.004824 -231.766618) (xy 381.957834 -231.919018)
			(xy 381.957834 -231.963214) (xy 382.313434 -231.963214)
		)
		(stroke
			(width 0)
			(type solid)
		)
		(fill yes)
		(layer "In4.Cu")
		(net "M_G_CPU0_SB_DQS_DP<7>")
	)
	(gr_poly
		(pts
			(xy 382.313942 -241.685826) (xy 382.266952 -241.533426) (xy 382.005332 -241.533426) (xy 381.958342 -241.685826)
			(xy 381.958342 -241.730022) (xy 382.313942 -241.730022)
		)
		(stroke
			(width 0)
			(type solid)
		)
		(fill yes)
		(layer "In4.Cu")
		(net "M_G_CPU0_SB_DQS_DP<4>")
	)
	(gr_poly
		(pts
			(xy 382.32207 -247.787922) (xy 382.32207 -247.743726) (xy 381.96647 -247.743726) (xy 381.96647 -247.787922)
			(xy 382.01346 -247.940322) (xy 382.27508 -247.940322)
		)
		(stroke
			(width 0)
			(type solid)
		)
		(fill yes)
		(layer "In4.Cu")
		(net "M_G_CPU0_SB_CA<6>")
	)
	(gr_poly
		(pts
			(xy 382.386332 -225.479102) (xy 382.277874 -225.362262) (xy 382.23952 -225.340164) (xy 382.06172 -225.648012)
			(xy 382.100074 -225.67011) (xy 382.255522 -225.70567)
		)
		(stroke
			(width 0)
			(type solid)
		)
		(fill yes)
		(layer "In4.Cu")
		(net "M_F_CPU0_SB_DQS_DP<3>")
	)
	(gr_poly
		(pts
			(xy 382.388364 -228.73081) (xy 382.279906 -228.61397) (xy 382.241552 -228.591872) (xy 382.063752 -228.89972)
			(xy 382.102106 -228.921818) (xy 382.257554 -228.957378)
		)
		(stroke
			(width 0)
			(type solid)
		)
		(fill yes)
		(layer "In4.Cu")
		(net "M_F_CPU0_SB_DQ<27>")
	)
	(gr_poly
		(pts
			(xy 382.388364 -227.102924) (xy 382.279906 -226.986084) (xy 382.241552 -226.963986) (xy 382.063752 -227.271834)
			(xy 382.102106 -227.293932) (xy 382.257554 -227.329492)
		)
		(stroke
			(width 0)
			(type solid)
		)
		(fill yes)
		(layer "In4.Cu")
		(net "M_F_CPU0_SB_DQS_DN<8>")
	)
	(gr_poly
		(pts
			(xy 382.388364 -223.847406) (xy 382.279906 -223.730566) (xy 382.241552 -223.708468) (xy 382.063752 -224.016316)
			(xy 382.102106 -224.038414) (xy 382.257554 -224.073974)
		)
		(stroke
			(width 0)
			(type solid)
		)
		(fill yes)
		(layer "In4.Cu")
		(net "M_F_CPU0_SB_DQS_DP<3>")
	)
	(gr_poly
		(pts
			(xy 382.388364 -222.21952) (xy 382.279906 -222.10268) (xy 382.241552 -222.080582) (xy 382.063752 -222.38843)
			(xy 382.102106 -222.410528) (xy 382.257554 -222.446088)
		)
		(stroke
			(width 0)
			(type solid)
		)
		(fill yes)
		(layer "In4.Cu")
		(net "M_F_CPU0_SB_DQ<30>")
	)
	(gr_poly
		(pts
			(xy 382.388618 -277.364952) (xy 382.497076 -277.248112) (xy 382.366266 -277.021544) (xy 382.210818 -277.057104)
			(xy 382.172464 -277.079202) (xy 382.350264 -277.38705)
		)
		(stroke
			(width 0)
			(type solid)
		)
		(fill yes)
		(layer "In4.Cu")
		(net "M_G_CPU0_SA_DQ<2>")
	)
	(gr_poly
		(pts
			(xy 382.41478 -276.098762) (xy 382.36779 -275.946362) (xy 382.10617 -275.946362) (xy 382.05918 -276.098762)
			(xy 382.05918 -276.143212) (xy 382.41478 -276.143212)
		)
		(stroke
			(width 0)
			(type solid)
		)
		(fill yes)
		(layer "In4.Cu")
		(net "M_G_CPU0_SA_DQ<3>")
	)
	(gr_poly
		(pts
			(xy 382.41478 -275.690584) (xy 382.41478 -275.646388) (xy 382.05918 -275.646388) (xy 382.05918 -275.690584)
			(xy 382.10617 -275.842984) (xy 382.36779 -275.842984)
		)
		(stroke
			(width 0)
			(type solid)
		)
		(fill yes)
		(layer "In4.Cu")
		(net "M_G_CPU0_SA_DQS_DP<0>")
	)
	(gr_poly
		(pts
			(xy 382.41478 -274.47113) (xy 382.36779 -274.31873) (xy 382.10617 -274.31873) (xy 382.05918 -274.47113)
			(xy 382.05918 -274.515326) (xy 382.41478 -274.515326)
		)
		(stroke
			(width 0)
			(type solid)
		)
		(fill yes)
		(layer "In4.Cu")
		(net "M_G_CPU0_SA_DQS_DP<5>")
	)
	(gr_poly
		(pts
			(xy 382.41478 -272.843498) (xy 382.36779 -272.691098) (xy 382.10617 -272.691098) (xy 382.05918 -272.843498)
			(xy 382.05918 -272.887694) (xy 382.41478 -272.887694)
		)
		(stroke
			(width 0)
			(type solid)
		)
		(fill yes)
		(layer "In4.Cu")
		(net "M_G_CPU0_SA_DQ<7>")
	)
	(gr_poly
		(pts
			(xy 382.41478 -270.807434) (xy 382.41478 -270.762984) (xy 382.05918 -270.762984) (xy 382.05918 -270.807434)
			(xy 382.10617 -270.959834) (xy 382.36779 -270.959834)
		)
		(stroke
			(width 0)
			(type solid)
		)
		(fill yes)
		(layer "In4.Cu")
		(net "M_F_CPU0_SA_DQS_DP<1>")
	)
	(gr_poly
		(pts
			(xy 382.41478 -265.92403) (xy 382.41478 -265.87958) (xy 382.05918 -265.87958) (xy 382.05918 -265.92403)
			(xy 382.10617 -266.07643) (xy 382.36779 -266.07643)
		)
		(stroke
			(width 0)
			(type solid)
		)
		(fill yes)
		(layer "In4.Cu")
		(net "M_G_CPU0_SA_DQS_DP<2>")
	)
	(gr_poly
		(pts
			(xy 382.41478 -261.040626) (xy 382.41478 -260.99643) (xy 382.05918 -260.99643) (xy 382.05918 -261.040626)
			(xy 382.10617 -261.193026) (xy 382.36779 -261.193026)
		)
		(stroke
			(width 0)
			(type solid)
		)
		(fill yes)
		(layer "In4.Cu")
		(net "M_F_CPU0_SA_DQS_DP<3>")
	)
	(gr_poly
		(pts
			(xy 382.41478 -259.820918) (xy 382.36779 -259.668518) (xy 382.10617 -259.668518) (xy 382.05918 -259.820918)
			(xy 382.05918 -259.865368) (xy 382.41478 -259.865368)
		)
		(stroke
			(width 0)
			(type solid)
		)
		(fill yes)
		(layer "In4.Cu")
		(net "M_F_CPU0_SA_DQS_DP<8>")
	)
	(gr_poly
		(pts
			(xy 382.41478 -256.157222) (xy 382.41478 -256.113026) (xy 382.05918 -256.113026) (xy 382.05918 -256.157222)
			(xy 382.10617 -256.309622) (xy 382.36779 -256.309622)
		)
		(stroke
			(width 0)
			(type solid)
		)
		(fill yes)
		(layer "In4.Cu")
		(net "M_G_CPU0_SA_CA<1>")
	)
	(gr_poly
		(pts
			(xy 382.41478 -254.937514) (xy 382.36779 -254.785114) (xy 382.10617 -254.785114) (xy 382.05918 -254.937514)
			(xy 382.05918 -254.981964) (xy 382.41478 -254.981964)
		)
		(stroke
			(width 0)
			(type solid)
		)
		(fill yes)
		(layer "In4.Cu")
		(net "M_G_CPU0_SA_CA<2>")
	)
	(gr_poly
		(pts
			(xy 382.41732 -258.193286) (xy 382.37033 -258.040886) (xy 382.10871 -258.040886) (xy 382.06172 -258.193286)
			(xy 382.06172 -258.237736) (xy 382.41732 -258.237736)
		)
		(stroke
			(width 0)
			(type solid)
		)
		(fill yes)
		(layer "In4.Cu")
		(net "M_F_CPU0_SA_DQ<31>")
	)
	(gr_poly
		(pts
			(xy 382.423162 -256.565654) (xy 382.376172 -256.413254) (xy 382.114552 -256.413254) (xy 382.067562 -256.565654)
			(xy 382.067562 -256.610104) (xy 382.423162 -256.610104)
		)
		(stroke
			(width 0)
			(type solid)
		)
		(fill yes)
		(layer "In4.Cu")
		(net "M_G_CPU0_SA_CS_N<3>")
	)
	(gr_poly
		(pts
			(xy 382.426718 -274.062698) (xy 382.426718 -274.018248) (xy 382.071118 -274.018248) (xy 382.071118 -274.062698)
			(xy 382.118108 -274.215098) (xy 382.379728 -274.215098)
		)
		(stroke
			(width 0)
			(type solid)
		)
		(fill yes)
		(layer "In4.Cu")
		(net "M_G_CPU0_SA_DQ<4>")
	)
	(gr_poly
		(pts
			(xy 382.426718 -271.215866) (xy 382.379728 -271.063466) (xy 382.118108 -271.063466) (xy 382.071118 -271.215866)
			(xy 382.071118 -271.260062) (xy 382.426718 -271.260062)
		)
		(stroke
			(width 0)
			(type solid)
		)
		(fill yes)
		(layer "In4.Cu")
		(net "M_F_CPU0_SA_DQ<11>")
	)
	(gr_poly
		(pts
			(xy 382.426718 -269.179294) (xy 382.426718 -269.134844) (xy 382.071118 -269.134844) (xy 382.071118 -269.179294)
			(xy 382.118108 -269.331694) (xy 382.379728 -269.331694)
		)
		(stroke
			(width 0)
			(type solid)
		)
		(fill yes)
		(layer "In4.Cu")
		(net "M_F_CPU0_SA_DQ<12>")
	)
	(gr_poly
		(pts
			(xy 382.426718 -267.960094) (xy 382.379728 -267.807694) (xy 382.118108 -267.807694) (xy 382.071118 -267.960094)
			(xy 382.071118 -268.004544) (xy 382.426718 -268.004544)
		)
		(stroke
			(width 0)
			(type solid)
		)
		(fill yes)
		(layer "In4.Cu")
		(net "M_F_CPU0_SA_DQ<13>")
	)
	(gr_poly
		(pts
			(xy 382.426718 -266.332462) (xy 382.379728 -266.180062) (xy 382.118108 -266.180062) (xy 382.071118 -266.332462)
			(xy 382.071118 -266.376658) (xy 382.426718 -266.376658)
		)
		(stroke
			(width 0)
			(type solid)
		)
		(fill yes)
		(layer "In4.Cu")
		(net "M_G_CPU0_SA_DQ<19>")
	)
	(gr_poly
		(pts
			(xy 382.426718 -264.29589) (xy 382.426718 -264.25144) (xy 382.071118 -264.25144) (xy 382.071118 -264.29589)
			(xy 382.118108 -264.44829) (xy 382.379728 -264.44829)
		)
		(stroke
			(width 0)
			(type solid)
		)
		(fill yes)
		(layer "In4.Cu")
		(net "M_G_CPU0_SA_DQ<20>")
	)
	(gr_poly
		(pts
			(xy 382.426718 -263.077198) (xy 382.379728 -262.924798) (xy 382.118108 -262.924798) (xy 382.071118 -263.077198)
			(xy 382.071118 -263.121394) (xy 382.426718 -263.121394)
		)
		(stroke
			(width 0)
			(type solid)
		)
		(fill yes)
		(layer "In4.Cu")
		(net "M_G_CPU0_SA_DQ<23>")
	)
	(gr_poly
		(pts
			(xy 382.426718 -262.668258) (xy 382.426718 -262.623808) (xy 382.071118 -262.623808) (xy 382.071118 -262.668258)
			(xy 382.118108 -262.820658) (xy 382.379728 -262.820658)
		)
		(stroke
			(width 0)
			(type solid)
		)
		(fill yes)
		(layer "In4.Cu")
		(net "M_F_CPU0_SA_DQ<24>")
	)
	(gr_poly
		(pts
			(xy 382.42748 -272.434558) (xy 382.42748 -272.390362) (xy 382.07188 -272.390362) (xy 382.07188 -272.434558)
			(xy 382.11887 -272.586958) (xy 382.38049 -272.586958)
		)
		(stroke
			(width 0)
			(type solid)
		)
		(fill yes)
		(layer "In4.Cu")
		(net "M_F_CPU0_SA_DQ<8>")
	)
	(gr_poly
		(pts
			(xy 382.42748 -269.588234) (xy 382.38049 -269.435834) (xy 382.11887 -269.435834) (xy 382.07188 -269.588234)
			(xy 382.07188 -269.63243) (xy 382.42748 -269.63243)
		)
		(stroke
			(width 0)
			(type solid)
		)
		(fill yes)
		(layer "In4.Cu")
		(net "M_F_CPU0_SA_DQS_DP<6>")
	)
	(gr_poly
		(pts
			(xy 382.42748 -267.551154) (xy 382.42748 -267.506958) (xy 382.07188 -267.506958) (xy 382.07188 -267.551154)
			(xy 382.11887 -267.703554) (xy 382.38049 -267.703554)
		)
		(stroke
			(width 0)
			(type solid)
		)
		(fill yes)
		(layer "In4.Cu")
		(net "M_G_CPU0_SA_DQ<16>")
	)
	(gr_poly
		(pts
			(xy 382.42748 -264.70483) (xy 382.38049 -264.55243) (xy 382.11887 -264.55243) (xy 382.07188 -264.70483)
			(xy 382.07188 -264.749026) (xy 382.42748 -264.749026)
		)
		(stroke
			(width 0)
			(type solid)
		)
		(fill yes)
		(layer "In4.Cu")
		(net "M_G_CPU0_SA_DQS_DP<7>")
	)
	(gr_poly
		(pts
			(xy 382.42748 -261.449058) (xy 382.38049 -261.296658) (xy 382.11887 -261.296658) (xy 382.07188 -261.449058)
			(xy 382.07188 -261.493508) (xy 382.42748 -261.493508)
		)
		(stroke
			(width 0)
			(type solid)
		)
		(fill yes)
		(layer "In4.Cu")
		(net "M_F_CPU0_SA_DQ<27>")
	)
	(gr_poly
		(pts
			(xy 382.42748 -259.412486) (xy 382.42748 -259.368036) (xy 382.07188 -259.368036) (xy 382.07188 -259.412486)
			(xy 382.11887 -259.564886) (xy 382.38049 -259.564886)
		)
		(stroke
			(width 0)
			(type solid)
		)
		(fill yes)
		(layer "In4.Cu")
		(net "M_F_CPU0_SA_DQ<28>")
	)
	(gr_poly
		(pts
			(xy 382.429258 -257.784854) (xy 382.429258 -257.740404) (xy 382.073658 -257.740404) (xy 382.073658 -257.784854)
			(xy 382.120648 -257.937254) (xy 382.382268 -257.937254)
		)
		(stroke
			(width 0)
			(type solid)
		)
		(fill yes)
		(layer "In4.Cu")
		(net "M_G_CPU0_SA_CS_N<0>")
	)
	(gr_poly
		(pts
			(xy 382.677416 -219.065348) (xy 382.639062 -219.04325) (xy 382.483614 -219.00769) (xy 382.352804 -219.234258)
			(xy 382.461262 -219.351098) (xy 382.499616 -219.373196)
		)
		(stroke
			(width 0)
			(type solid)
		)
		(fill yes)
		(layer "In4.Cu")
		(net "M_F_CPU0_SB_DQ<31>")
	)
	(gr_poly
		(pts
			(xy 382.678432 -228.829616) (xy 382.640078 -228.807518) (xy 382.48463 -228.771958) (xy 382.35382 -228.998526)
			(xy 382.462278 -229.115366) (xy 382.500632 -229.137464)
		)
		(stroke
			(width 0)
			(type solid)
		)
		(fill yes)
		(layer "In4.Cu")
		(net "M_F_CPU0_SB_DQ<24>")
	)
	(gr_poly
		(pts
			(xy 382.678432 -227.20173) (xy 382.640078 -227.179632) (xy 382.48463 -227.144072) (xy 382.35382 -227.37064)
			(xy 382.462278 -227.48748) (xy 382.500632 -227.509578)
		)
		(stroke
			(width 0)
			(type solid)
		)
		(fill yes)
		(layer "In4.Cu")
		(net "M_F_CPU0_SB_DQ<25>")
	)
	(gr_poly
		(pts
			(xy 382.678432 -222.318326) (xy 382.640078 -222.296228) (xy 382.48463 -222.260668) (xy 382.35382 -222.487236)
			(xy 382.462278 -222.604076) (xy 382.500632 -222.626174)
		)
		(stroke
			(width 0)
			(type solid)
		)
		(fill yes)
		(layer "In4.Cu")
		(net "M_F_CPU0_SB_DQS_DN<3>")
	)
	(gr_poly
		(pts
			(xy 382.679448 -225.572574) (xy 382.641094 -225.550476) (xy 382.485646 -225.514916) (xy 382.354836 -225.741484)
			(xy 382.463294 -225.858324) (xy 382.501648 -225.880422)
		)
		(stroke
			(width 0)
			(type solid)
		)
		(fill yes)
		(layer "In4.Cu")
		(net "M_F_CPU0_SB_DQS_DP<8>")
	)
	(gr_poly
		(pts
			(xy 382.68021 -220.68917) (xy 382.641856 -220.667072) (xy 382.486408 -220.631512) (xy 382.355598 -220.85808)
			(xy 382.464056 -220.97492) (xy 382.50241 -220.997018)
		)
		(stroke
			(width 0)
			(type solid)
		)
		(fill yes)
		(layer "In4.Cu")
		(net "M_F_CPU0_SB_DQ<28>")
	)
	(gr_poly
		(pts
			(xy 382.74879 -278.79929) (xy 382.787144 -278.777192) (xy 382.609344 -278.469344) (xy 382.57099 -278.491442)
			(xy 382.462532 -278.608282) (xy 382.593342 -278.83485)
		)
		(stroke
			(width 0)
			(type solid)
		)
		(fill yes)
		(layer "In4.Cu")
		(net "M_G_CPU0_SA_DQ<0>")
	)
	(gr_poly
		(pts
			(xy 382.75006 -277.173944) (xy 382.788414 -277.151846) (xy 382.610614 -276.843998) (xy 382.57226 -276.866096)
			(xy 382.463802 -276.982936) (xy 382.594612 -277.209504)
		)
		(stroke
			(width 0)
			(type solid)
		)
		(fill yes)
		(layer "In4.Cu")
		(net "M_G_CPU0_SA_DQ<1>")
	)
	(gr_poly
		(pts
			(xy 382.774952 -247.382538) (xy 382.727962 -247.230138) (xy 382.466342 -247.230138) (xy 382.419352 -247.382538)
			(xy 382.419352 -247.426734) (xy 382.774952 -247.426734)
		)
		(stroke
			(width 0)
			(type solid)
		)
		(fill yes)
		(layer "In4.Cu")
		(net "M_G_CPU0_SB_PAR")
	)
	(gr_poly
		(pts
			(xy 382.777238 -246.974106) (xy 382.777238 -246.929656) (xy 382.421638 -246.929656) (xy 382.421638 -246.974106)
			(xy 382.468628 -247.126506) (xy 382.730248 -247.126506)
		)
		(stroke
			(width 0)
			(type solid)
		)
		(fill yes)
		(layer "In4.Cu")
		(net "M_G_CPU0_SB_CS_N<2>")
	)
	(gr_poly
		(pts
			(xy 382.777238 -245.754906) (xy 382.730248 -245.602506) (xy 382.468628 -245.602506) (xy 382.421638 -245.754906)
			(xy 382.421638 -245.799356) (xy 382.777238 -245.799356)
		)
		(stroke
			(width 0)
			(type solid)
		)
		(fill yes)
		(layer "In4.Cu")
		(net "M_G_CPU0_SB_CS_N<1>")
	)
	(gr_poly
		(pts
			(xy 382.777492 -248.602246) (xy 382.777492 -248.557796) (xy 382.421892 -248.557796) (xy 382.421892 -248.602246)
			(xy 382.468882 -248.754646) (xy 382.730502 -248.754646)
		)
		(stroke
			(width 0)
			(type solid)
		)
		(fill yes)
		(layer "In4.Cu")
		(net "M_G_CPU0_SB_CA<4>")
	)
	(gr_poly
		(pts
			(xy 382.78054 -244.127274) (xy 382.73355 -243.974874) (xy 382.47193 -243.974874) (xy 382.42494 -244.127274)
			(xy 382.42494 -244.171724) (xy 382.78054 -244.171724)
		)
		(stroke
			(width 0)
			(type solid)
		)
		(fill yes)
		(layer "In4.Cu")
		(net "M_G_CPU0_SB_CB<6>")
	)
	(gr_poly
		(pts
			(xy 382.78054 -243.718334) (xy 382.78054 -243.674138) (xy 382.42494 -243.674138) (xy 382.42494 -243.718334)
			(xy 382.47193 -243.870734) (xy 382.73355 -243.870734)
		)
		(stroke
			(width 0)
			(type solid)
		)
		(fill yes)
		(layer "In4.Cu")
		(net "M_G_CPU0_SB_CB<5>")
	)
	(gr_poly
		(pts
			(xy 382.78054 -240.871502) (xy 382.73355 -240.719102) (xy 382.47193 -240.719102) (xy 382.42494 -240.871502)
			(xy 382.42494 -240.915952) (xy 382.78054 -240.915952)
		)
		(stroke
			(width 0)
			(type solid)
		)
		(fill yes)
		(layer "In4.Cu")
		(net "M_G_CPU0_SB_CB<2>")
	)
	(gr_poly
		(pts
			(xy 382.78054 -240.46307) (xy 382.78054 -240.41862) (xy 382.42494 -240.41862) (xy 382.42494 -240.46307)
			(xy 382.47193 -240.61547) (xy 382.73355 -240.61547)
		)
		(stroke
			(width 0)
			(type solid)
		)
		(fill yes)
		(layer "In4.Cu")
		(net "M_G_CPU0_SB_CB<1>")
	)
	(gr_poly
		(pts
			(xy 382.78054 -239.24387) (xy 382.73355 -239.09147) (xy 382.47193 -239.09147) (xy 382.42494 -239.24387)
			(xy 382.42494 -239.28832) (xy 382.78054 -239.28832)
		)
		(stroke
			(width 0)
			(type solid)
		)
		(fill yes)
		(layer "In4.Cu")
		(net "M_F_CPU0_SB_DQ<2>")
	)
	(gr_poly
		(pts
			(xy 382.78054 -238.83493) (xy 382.78054 -238.790734) (xy 382.42494 -238.790734) (xy 382.42494 -238.83493)
			(xy 382.47193 -238.98733) (xy 382.73355 -238.98733)
		)
		(stroke
			(width 0)
			(type solid)
		)
		(fill yes)
		(layer "In4.Cu")
		(net "M_F_CPU0_SB_DQ<1>")
	)
	(gr_poly
		(pts
			(xy 382.78054 -235.988606) (xy 382.73355 -235.836206) (xy 382.47193 -235.836206) (xy 382.42494 -235.988606)
			(xy 382.42494 -236.032802) (xy 382.78054 -236.032802)
		)
		(stroke
			(width 0)
			(type solid)
		)
		(fill yes)
		(layer "In4.Cu")
		(net "M_F_CPU0_SB_DQ<6>")
	)
	(gr_poly
		(pts
			(xy 382.78054 -235.579666) (xy 382.78054 -235.535216) (xy 382.42494 -235.535216) (xy 382.42494 -235.579666)
			(xy 382.47193 -235.732066) (xy 382.73355 -235.732066)
		)
		(stroke
			(width 0)
			(type solid)
		)
		(fill yes)
		(layer "In4.Cu")
		(net "M_F_CPU0_SB_DQ<5>")
	)
	(gr_poly
		(pts
			(xy 382.78054 -233.951526) (xy 382.78054 -233.90733) (xy 382.42494 -233.90733) (xy 382.42494 -233.951526)
			(xy 382.47193 -234.103926) (xy 382.73355 -234.103926)
		)
		(stroke
			(width 0)
			(type solid)
		)
		(fill yes)
		(layer "In4.Cu")
		(net "M_G_CPU0_SB_DQ<17>")
	)
	(gr_poly
		(pts
			(xy 382.78054 -231.105202) (xy 382.73355 -230.952802) (xy 382.47193 -230.952802) (xy 382.42494 -231.105202)
			(xy 382.42494 -231.149398) (xy 382.78054 -231.149398)
		)
		(stroke
			(width 0)
			(type solid)
		)
		(fill yes)
		(layer "In4.Cu")
		(net "M_G_CPU0_SB_DQ<22>")
	)
	(gr_poly
		(pts
			(xy 382.78054 -230.696262) (xy 382.78054 -230.651812) (xy 382.42494 -230.651812) (xy 382.42494 -230.696262)
			(xy 382.47193 -230.848662) (xy 382.73355 -230.848662)
		)
		(stroke
			(width 0)
			(type solid)
		)
		(fill yes)
		(layer "In4.Cu")
		(net "M_G_CPU0_SB_DQ<21>")
	)
	(gr_poly
		(pts
			(xy 382.782826 -242.499642) (xy 382.735836 -242.347242) (xy 382.474216 -242.347242) (xy 382.427226 -242.499642)
			(xy 382.427226 -242.544092) (xy 382.782826 -242.544092)
		)
		(stroke
			(width 0)
			(type solid)
		)
		(fill yes)
		(layer "In4.Cu")
		(net "M_G_CPU0_SB_DQS_DN<9>")
	)
	(gr_poly
		(pts
			(xy 382.783334 -249.010678) (xy 382.736344 -248.858278) (xy 382.474724 -248.858278) (xy 382.427734 -249.010678)
			(xy 382.427734 -249.054874) (xy 382.783334 -249.054874)
		)
		(stroke
			(width 0)
			(type solid)
		)
		(fill yes)
		(layer "In4.Cu")
		(net "M_G_CPU0_SB_CA<3>")
	)
	(gr_poly
		(pts
			(xy 382.783334 -237.616238) (xy 382.736344 -237.463838) (xy 382.474724 -237.463838) (xy 382.427734 -237.616238)
			(xy 382.427734 -237.660434) (xy 382.783334 -237.660434)
		)
		(stroke
			(width 0)
			(type solid)
		)
		(fill yes)
		(layer "In4.Cu")
		(net "M_F_CPU0_SB_DQS_DN<0>")
	)
	(gr_poly
		(pts
			(xy 382.783334 -237.207298) (xy 382.783334 -237.163102) (xy 382.427734 -237.163102) (xy 382.427734 -237.207298)
			(xy 382.474724 -237.359698) (xy 382.736344 -237.359698)
		)
		(stroke
			(width 0)
			(type solid)
		)
		(fill yes)
		(layer "In4.Cu")
		(net "M_F_CPU0_SB_DQS_DN<5>")
	)
	(gr_poly
		(pts
			(xy 382.783334 -234.360466) (xy 382.736344 -234.208066) (xy 382.474724 -234.208066) (xy 382.427734 -234.360466)
			(xy 382.427734 -234.404916) (xy 382.783334 -234.404916)
		)
		(stroke
			(width 0)
			(type solid)
		)
		(fill yes)
		(layer "In4.Cu")
		(net "M_G_CPU0_SB_DQ<18>")
	)
	(gr_poly
		(pts
			(xy 382.783334 -232.732834) (xy 382.736344 -232.580434) (xy 382.474724 -232.580434) (xy 382.427734 -232.732834)
			(xy 382.427734 -232.77703) (xy 382.783334 -232.77703)
		)
		(stroke
			(width 0)
			(type solid)
		)
		(fill yes)
		(layer "In4.Cu")
		(net "M_G_CPU0_SB_DQS_DN<2>")
	)
	(gr_poly
		(pts
			(xy 382.783334 -232.323894) (xy 382.783334 -232.279698) (xy 382.427734 -232.279698) (xy 382.427734 -232.323894)
			(xy 382.474724 -232.476294) (xy 382.736344 -232.476294)
		)
		(stroke
			(width 0)
			(type solid)
		)
		(fill yes)
		(layer "In4.Cu")
		(net "M_G_CPU0_SB_DQS_DN<7>")
	)
	(gr_poly
		(pts
			(xy 382.791716 -242.090702) (xy 382.791716 -242.046506) (xy 382.436116 -242.046506) (xy 382.436116 -242.090702)
			(xy 382.483106 -242.243102) (xy 382.744726 -242.243102)
		)
		(stroke
			(width 0)
			(type solid)
		)
		(fill yes)
		(layer "In4.Cu")
		(net "M_G_CPU0_SB_DQS_DN<4>")
	)
	(gr_poly
		(pts
			(xy 382.856232 -223.0374) (xy 382.747774 -222.92056) (xy 382.70942 -222.898462) (xy 382.53162 -223.20631)
			(xy 382.569974 -223.228408) (xy 382.725422 -223.263968)
		)
		(stroke
			(width 0)
			(type solid)
		)
		(fill yes)
		(layer "In4.Cu")
		(net "M_F_CPU0_SB_DQS_DP<3>")
	)
	(gr_poly
		(pts
			(xy 382.857248 -227.918772) (xy 382.74879 -227.801932) (xy 382.710436 -227.779834) (xy 382.532636 -228.087682)
			(xy 382.57099 -228.10978) (xy 382.726438 -228.14534)
		)
		(stroke
			(width 0)
			(type solid)
		)
		(fill yes)
		(layer "In4.Cu")
		(net "M_F_CPU0_SB_DQ<27>")
	)
	(gr_poly
		(pts
			(xy 382.857502 -278.177498) (xy 382.96596 -278.060658) (xy 382.83515 -277.83409) (xy 382.679702 -277.86965)
			(xy 382.641348 -277.891748) (xy 382.819148 -278.199596)
		)
		(stroke
			(width 0)
			(type solid)
		)
		(fill yes)
		(layer "In4.Cu")
		(net "M_G_CPU0_SA_DQ<2>")
	)
	(gr_poly
		(pts
			(xy 382.858264 -229.544626) (xy 382.749806 -229.427786) (xy 382.711452 -229.405688) (xy 382.533652 -229.713536)
			(xy 382.572006 -229.735634) (xy 382.727454 -229.771194)
		)
		(stroke
			(width 0)
			(type solid)
		)
		(fill yes)
		(layer "In4.Cu")
		(net "M_F_CPU0_SB_DQ<26>")
	)
	(gr_poly
		(pts
			(xy 382.862582 -226.281996) (xy 382.754124 -226.165156) (xy 382.71577 -226.143058) (xy 382.53797 -226.450906)
			(xy 382.576324 -226.473004) (xy 382.731772 -226.508564)
		)
		(stroke
			(width 0)
			(type solid)
		)
		(fill yes)
		(layer "In4.Cu")
		(net "M_F_CPU0_SB_DQS_DN<8>")
	)
	(gr_poly
		(pts
			(xy 382.862582 -221.398592) (xy 382.754124 -221.281752) (xy 382.71577 -221.259654) (xy 382.53797 -221.567502)
			(xy 382.576324 -221.5896) (xy 382.731772 -221.62516)
		)
		(stroke
			(width 0)
			(type solid)
		)
		(fill yes)
		(layer "In4.Cu")
		(net "M_F_CPU0_SB_DQ<30>")
	)
	(gr_poly
		(pts
			(xy 382.862582 -219.770706) (xy 382.754124 -219.653866) (xy 382.71577 -219.631768) (xy 382.53797 -219.939616)
			(xy 382.576324 -219.961714) (xy 382.731772 -219.997274)
		)
		(stroke
			(width 0)
			(type solid)
		)
		(fill yes)
		(layer "In4.Cu")
		(net "M_F_CPU0_SB_DQ<29>")
	)
	(gr_poly
		(pts
			(xy 382.864106 -276.560788) (xy 382.972564 -276.443948) (xy 382.841754 -276.21738) (xy 382.686306 -276.25294)
			(xy 382.647952 -276.275038) (xy 382.825752 -276.582886)
		)
		(stroke
			(width 0)
			(type solid)
		)
		(fill yes)
		(layer "In4.Cu")
		(net "M_G_CPU0_SA_DQ<3>")
	)
	(gr_poly
		(pts
			(xy 382.888998 -272.029682) (xy 382.842008 -271.877282) (xy 382.580388 -271.877282) (xy 382.533398 -272.029682)
			(xy 382.533398 -272.074132) (xy 382.888998 -272.074132)
		)
		(stroke
			(width 0)
			(type solid)
		)
		(fill yes)
		(layer "In4.Cu")
		(net "M_F_CPU0_SA_DQ<10>")
	)
	(gr_poly
		(pts
			(xy 382.888998 -269.99311) (xy 382.888998 -269.94866) (xy 382.533398 -269.94866) (xy 382.533398 -269.99311)
			(xy 382.580388 -270.14551) (xy 382.842008 -270.14551)
		)
		(stroke
			(width 0)
			(type solid)
		)
		(fill yes)
		(layer "In4.Cu")
		(net "M_F_CPU0_SA_DQS_DN<6>")
	)
	(gr_poly
		(pts
			(xy 382.888998 -267.146278) (xy 382.842008 -266.993878) (xy 382.580388 -266.993878) (xy 382.533398 -267.146278)
			(xy 382.533398 -267.190728) (xy 382.888998 -267.190728)
		)
		(stroke
			(width 0)
			(type solid)
		)
		(fill yes)
		(layer "In4.Cu")
		(net "M_G_CPU0_SA_DQ<18>")
	)
	(gr_poly
		(pts
			(xy 382.888998 -261.854442) (xy 382.888998 -261.809992) (xy 382.533398 -261.809992) (xy 382.533398 -261.854442)
			(xy 382.580388 -262.006842) (xy 382.842008 -262.006842)
		)
		(stroke
			(width 0)
			(type solid)
		)
		(fill yes)
		(layer "In4.Cu")
		(net "M_F_CPU0_SA_DQ<25>")
	)
	(gr_poly
		(pts
			(xy 382.888998 -259.00761) (xy 382.842008 -258.85521) (xy 382.580388 -258.85521) (xy 382.533398 -259.00761)
			(xy 382.533398 -259.051806) (xy 382.888998 -259.051806)
		)
		(stroke
			(width 0)
			(type solid)
		)
		(fill yes)
		(layer "In4.Cu")
		(net "M_F_CPU0_SA_DQ<30>")
	)
	(gr_poly
		(pts
			(xy 382.88976 -273.657314) (xy 382.84277 -273.504914) (xy 382.58115 -273.504914) (xy 382.53416 -273.657314)
			(xy 382.53416 -273.701764) (xy 382.88976 -273.701764)
		)
		(stroke
			(width 0)
			(type solid)
		)
		(fill yes)
		(layer "In4.Cu")
		(net "M_G_CPU0_SA_DQ<6>")
	)
	(gr_poly
		(pts
			(xy 382.88976 -271.620742) (xy 382.88976 -271.576546) (xy 382.53416 -271.576546) (xy 382.53416 -271.620742)
			(xy 382.58115 -271.773142) (xy 382.84277 -271.773142)
		)
		(stroke
			(width 0)
			(type solid)
		)
		(fill yes)
		(layer "In4.Cu")
		(net "M_F_CPU0_SA_DQ<9>")
	)
	(gr_poly
		(pts
			(xy 382.88976 -268.77391) (xy 382.84277 -268.62151) (xy 382.58115 -268.62151) (xy 382.53416 -268.77391)
			(xy 382.53416 -268.81836) (xy 382.88976 -268.81836)
		)
		(stroke
			(width 0)
			(type solid)
		)
		(fill yes)
		(layer "In4.Cu")
		(net "M_F_CPU0_SA_DQ<14>")
	)
	(gr_poly
		(pts
			(xy 382.88976 -268.365478) (xy 382.88976 -268.321028) (xy 382.53416 -268.321028) (xy 382.53416 -268.365478)
			(xy 382.58115 -268.517878) (xy 382.84277 -268.517878)
		)
		(stroke
			(width 0)
			(type solid)
		)
		(fill yes)
		(layer "In4.Cu")
		(net "M_F_CPU0_SA_DQ<15>")
	)
	(gr_poly
		(pts
			(xy 382.88976 -266.737338) (xy 382.88976 -266.693142) (xy 382.53416 -266.693142) (xy 382.53416 -266.737338)
			(xy 382.58115 -266.889738) (xy 382.84277 -266.889738)
		)
		(stroke
			(width 0)
			(type solid)
		)
		(fill yes)
		(layer "In4.Cu")
		(net "M_G_CPU0_SA_DQ<17>")
	)
	(gr_poly
		(pts
			(xy 382.88976 -263.482074) (xy 382.88976 -263.437624) (xy 382.53416 -263.437624) (xy 382.53416 -263.482074)
			(xy 382.58115 -263.634474) (xy 382.84277 -263.634474)
		)
		(stroke
			(width 0)
			(type solid)
		)
		(fill yes)
		(layer "In4.Cu")
		(net "M_G_CPU0_SA_DQ<21>")
	)
	(gr_poly
		(pts
			(xy 382.88976 -262.262874) (xy 382.84277 -262.110474) (xy 382.58115 -262.110474) (xy 382.53416 -262.262874)
			(xy 382.53416 -262.307324) (xy 382.88976 -262.307324)
		)
		(stroke
			(width 0)
			(type solid)
		)
		(fill yes)
		(layer "In4.Cu")
		(net "M_F_CPU0_SA_DQ<26>")
	)
	(gr_poly
		(pts
			(xy 382.892808 -270.40205) (xy 382.845818 -270.24965) (xy 382.584198 -270.24965) (xy 382.537208 -270.40205)
			(xy 382.537208 -270.446246) (xy 382.892808 -270.446246)
		)
		(stroke
			(width 0)
			(type solid)
		)
		(fill yes)
		(layer "In4.Cu")
		(net "M_F_CPU0_SA_DQS_DN<1>")
	)
	(gr_poly
		(pts
			(xy 382.893062 -257.37947) (xy 382.846072 -257.22707) (xy 382.584452 -257.22707) (xy 382.537462 -257.37947)
			(xy 382.537462 -257.42392) (xy 382.893062 -257.42392)
		)
		(stroke
			(width 0)
			(type solid)
		)
		(fill yes)
		(layer "In4.Cu")
		(net "M_G_CPU0_SA_CS_N<1>")
	)
	(gr_poly
		(pts
			(xy 382.893062 -256.971038) (xy 382.893062 -256.926588) (xy 382.537462 -256.926588) (xy 382.537462 -256.971038)
			(xy 382.584452 -257.123438) (xy 382.846072 -257.123438)
		)
		(stroke
			(width 0)
			(type solid)
		)
		(fill yes)
		(layer "In4.Cu")
		(net "M_G_CPU0_SA_CS_N<2>")
	)
	(gr_poly
		(pts
			(xy 382.896618 -275.284946) (xy 382.849628 -275.132546) (xy 382.588008 -275.132546) (xy 382.541018 -275.284946)
			(xy 382.541018 -275.329396) (xy 382.896618 -275.329396)
		)
		(stroke
			(width 0)
			(type solid)
		)
		(fill yes)
		(layer "In4.Cu")
		(net "M_G_CPU0_SA_DQS_DN<0>")
	)
	(gr_poly
		(pts
			(xy 382.899158 -263.891014) (xy 382.852168 -263.738614) (xy 382.590548 -263.738614) (xy 382.543558 -263.891014)
			(xy 382.543558 -263.93521) (xy 382.899158 -263.93521)
		)
		(stroke
			(width 0)
			(type solid)
		)
		(fill yes)
		(layer "In4.Cu")
		(net "M_G_CPU0_SA_DQ<22>")
	)
	(gr_poly
		(pts
			(xy 382.899158 -260.635242) (xy 382.852168 -260.482842) (xy 382.590548 -260.482842) (xy 382.543558 -260.635242)
			(xy 382.543558 -260.679438) (xy 382.899158 -260.679438)
		)
		(stroke
			(width 0)
			(type solid)
		)
		(fill yes)
		(layer "In4.Cu")
		(net "M_F_CPU0_SA_DQS_DN<3>")
	)
	(gr_poly
		(pts
			(xy 382.899158 -260.226302) (xy 382.899158 -260.182106) (xy 382.543558 -260.182106) (xy 382.543558 -260.226302)
			(xy 382.590548 -260.378702) (xy 382.852168 -260.378702)
		)
		(stroke
			(width 0)
			(type solid)
		)
		(fill yes)
		(layer "In4.Cu")
		(net "M_F_CPU0_SA_DQS_DN<8>")
	)
	(gr_poly
		(pts
			(xy 382.899158 -258.59867) (xy 382.899158 -258.554474) (xy 382.543558 -258.554474) (xy 382.543558 -258.59867)
			(xy 382.590548 -258.75107) (xy 382.852168 -258.75107)
		)
		(stroke
			(width 0)
			(type solid)
		)
		(fill yes)
		(layer "In4.Cu")
		(net "M_F_CPU0_SA_DQ<29>")
	)
	(gr_poly
		(pts
			(xy 382.899158 -255.751838) (xy 382.852168 -255.599438) (xy 382.590548 -255.599438) (xy 382.543558 -255.751838)
			(xy 382.543558 -255.796288) (xy 382.899158 -255.796288)
		)
		(stroke
			(width 0)
			(type solid)
		)
		(fill yes)
		(layer "In4.Cu")
		(net "M_G_CPU0_SA_CA<0>")
	)
	(gr_poly
		(pts
			(xy 382.899158 -255.343406) (xy 382.899158 -255.298956) (xy 382.543558 -255.298956) (xy 382.543558 -255.343406)
			(xy 382.590548 -255.495806) (xy 382.852168 -255.495806)
		)
		(stroke
			(width 0)
			(type solid)
		)
		(fill yes)
		(layer "In4.Cu")
		(net "M_G_CPU0_SA_CA<3>")
	)
	(gr_poly
		(pts
			(xy 382.901698 -273.248882) (xy 382.901698 -273.204686) (xy 382.546098 -273.204686) (xy 382.546098 -273.248882)
			(xy 382.593088 -273.401282) (xy 382.854708 -273.401282)
		)
		(stroke
			(width 0)
			(type solid)
		)
		(fill yes)
		(layer "In4.Cu")
		(net "M_G_CPU0_SA_DQ<5>")
	)
	(gr_poly
		(pts
			(xy 382.901698 -265.518138) (xy 382.854708 -265.365738) (xy 382.593088 -265.365738) (xy 382.546098 -265.518138)
			(xy 382.546098 -265.562588) (xy 382.901698 -265.562588)
		)
		(stroke
			(width 0)
			(type solid)
		)
		(fill yes)
		(layer "In4.Cu")
		(net "M_G_CPU0_SA_DQS_DN<2>")
	)
	(gr_poly
		(pts
			(xy 382.901698 -265.110214) (xy 382.901698 -265.065764) (xy 382.546098 -265.065764) (xy 382.546098 -265.110214)
			(xy 382.593088 -265.262614) (xy 382.854708 -265.262614)
		)
		(stroke
			(width 0)
			(type solid)
		)
		(fill yes)
		(layer "In4.Cu")
		(net "M_G_CPU0_SA_DQS_DN<7>")
	)
	(gr_poly
		(pts
			(xy 382.902714 -274.876514) (xy 382.902714 -274.832318) (xy 382.547114 -274.832318) (xy 382.547114 -274.876514)
			(xy 382.594104 -275.028914) (xy 382.855724 -275.028914)
		)
		(stroke
			(width 0)
			(type solid)
		)
		(fill yes)
		(layer "In4.Cu")
		(net "M_G_CPU0_SA_DQS_DN<5>")
	)
	(gr_poly
		(pts
			(xy 383.140966 -226.400614) (xy 383.102612 -226.378516) (xy 382.947164 -226.342956) (xy 382.816354 -226.569524)
			(xy 382.924812 -226.686364) (xy 382.963166 -226.708462)
		)
		(stroke
			(width 0)
			(type solid)
		)
		(fill yes)
		(layer "In4.Cu")
		(net "M_F_CPU0_SB_DQ<25>")
	)
	(gr_poly
		(pts
			(xy 383.140966 -221.51721) (xy 383.102612 -221.495112) (xy 382.947164 -221.459552) (xy 382.816354 -221.68612)
			(xy 382.924812 -221.80296) (xy 382.963166 -221.825058)
		)
		(stroke
			(width 0)
			(type solid)
		)
		(fill yes)
		(layer "In4.Cu")
		(net "M_F_CPU0_SB_DQS_DN<3>")
	)
	(gr_poly
		(pts
			(xy 383.140966 -219.889324) (xy 383.102612 -219.867226) (xy 382.947164 -219.831666) (xy 382.816354 -220.058234)
			(xy 382.924812 -220.175074) (xy 382.963166 -220.197172)
		)
		(stroke
			(width 0)
			(type solid)
		)
		(fill yes)
		(layer "In4.Cu")
		(net "M_F_CPU0_SB_DQ<28>")
	)
	(gr_poly
		(pts
			(xy 383.146554 -228.019102) (xy 383.1082 -227.997004) (xy 382.952752 -227.961444) (xy 382.821942 -228.188012)
			(xy 382.9304 -228.304852) (xy 382.968754 -228.32695)
		)
		(stroke
			(width 0)
			(type solid)
		)
		(fill yes)
		(layer "In4.Cu")
		(net "M_F_CPU0_SB_DQ<24>")
	)
	(gr_poly
		(pts
			(xy 383.148332 -224.760028) (xy 383.109978 -224.73793) (xy 382.95453 -224.70237) (xy 382.82372 -224.928938)
			(xy 382.932178 -225.045778) (xy 382.970532 -225.067876)
		)
		(stroke
			(width 0)
			(type solid)
		)
		(fill yes)
		(layer "In4.Cu")
		(net "M_F_CPU0_SB_DQS_DP<8>")
	)
	(gr_poly
		(pts
			(xy 383.214372 -276.350476) (xy 383.252726 -276.328378) (xy 383.074926 -276.02053) (xy 383.036572 -276.042628)
			(xy 382.928114 -276.159468) (xy 383.058924 -276.386036)
		)
		(stroke
			(width 0)
			(type solid)
		)
		(fill yes)
		(layer "In4.Cu")
		(net "M_G_CPU0_SA_DQS_DP<0>")
	)
	(gr_poly
		(pts
			(xy 383.219706 -279.615646) (xy 383.25806 -279.593548) (xy 383.08026 -279.2857) (xy 383.041906 -279.307798)
			(xy 382.933448 -279.424638) (xy 383.064258 -279.651206)
		)
		(stroke
			(width 0)
			(type solid)
		)
		(fill yes)
		(layer "In4.Cu")
		(net "M_G_CPU0_SA_DQ<0>")
	)
	(gr_poly
		(pts
			(xy 383.247138 -242.905026) (xy 383.247138 -242.860576) (xy 382.891538 -242.860576) (xy 382.891538 -242.905026)
			(xy 382.938528 -243.057426) (xy 383.200148 -243.057426)
		)
		(stroke
			(width 0)
			(type solid)
		)
		(fill yes)
		(layer "In4.Cu")
		(net "M_G_CPU0_SB_DQS_DP<9>")
	)
	(gr_poly
		(pts
			(xy 383.247138 -236.801914) (xy 383.200148 -236.649514) (xy 382.938528 -236.649514) (xy 382.891538 -236.801914)
			(xy 382.891538 -236.846364) (xy 383.247138 -236.846364)
		)
		(stroke
			(width 0)
			(type solid)
		)
		(fill yes)
		(layer "In4.Cu")
		(net "M_F_CPU0_SB_DQS_DP<5>")
	)
	(gr_poly
		(pts
			(xy 383.247392 -248.196354) (xy 383.200402 -248.043954) (xy 382.938782 -248.043954) (xy 382.891792 -248.196354)
			(xy 382.891792 -248.240804) (xy 383.247392 -248.240804)
		)
		(stroke
			(width 0)
			(type solid)
		)
		(fill yes)
		(layer "In4.Cu")
		(net "M_G_CPU0_SB_CA<5>")
	)
	(gr_poly
		(pts
			(xy 383.253234 -246.568722) (xy 383.206244 -246.416322) (xy 382.944624 -246.416322) (xy 382.897634 -246.568722)
			(xy 382.897634 -246.613172) (xy 383.253234 -246.613172)
		)
		(stroke
			(width 0)
			(type solid)
		)
		(fill yes)
		(layer "In4.Cu")
		(net "M_G_CPU0_SB_CS_N<0>")
	)
	(gr_poly
		(pts
			(xy 383.253234 -246.16029) (xy 383.253234 -246.11584) (xy 382.897634 -246.11584) (xy 382.897634 -246.16029)
			(xy 382.944624 -246.31269) (xy 383.206244 -246.31269)
		)
		(stroke
			(width 0)
			(type solid)
		)
		(fill yes)
		(layer "In4.Cu")
		(net "M_G_CPU0_SB_CS_N<3>")
	)
	(gr_poly
		(pts
			(xy 383.253234 -238.021114) (xy 383.253234 -237.976918) (xy 382.897634 -237.976918) (xy 382.897634 -238.021114)
			(xy 382.944624 -238.173514) (xy 383.206244 -238.173514)
		)
		(stroke
			(width 0)
			(type solid)
		)
		(fill yes)
		(layer "In4.Cu")
		(net "M_F_CPU0_SB_DQS_DP<0>")
	)
	(gr_poly
		(pts
			(xy 383.253234 -234.76585) (xy 383.253234 -234.7214) (xy 382.897634 -234.7214) (xy 382.897634 -234.76585)
			(xy 382.944624 -234.91825) (xy 383.206244 -234.91825)
		)
		(stroke
			(width 0)
			(type solid)
		)
		(fill yes)
		(layer "In4.Cu")
		(net "M_G_CPU0_SB_DQ<16>")
	)
	(gr_poly
		(pts
			(xy 383.253234 -233.13771) (xy 383.253234 -233.093514) (xy 382.897634 -233.093514) (xy 382.897634 -233.13771)
			(xy 382.944624 -233.29011) (xy 383.206244 -233.29011)
		)
		(stroke
			(width 0)
			(type solid)
		)
		(fill yes)
		(layer "In4.Cu")
		(net "M_G_CPU0_SB_DQS_DP<2>")
	)
	(gr_poly
		(pts
			(xy 383.253234 -231.919018) (xy 383.206244 -231.766618) (xy 382.944624 -231.766618) (xy 382.897634 -231.919018)
			(xy 382.897634 -231.963214) (xy 383.253234 -231.963214)
		)
		(stroke
			(width 0)
			(type solid)
		)
		(fill yes)
		(layer "In4.Cu")
		(net "M_G_CPU0_SB_DQS_DP<7>")
	)
	(gr_poly
		(pts
			(xy 383.253234 -218.896438) (xy 383.206244 -218.744038) (xy 382.944624 -218.744038) (xy 382.897634 -218.896438)
			(xy 382.897634 -218.940888) (xy 383.253234 -218.940888)
		)
		(stroke
			(width 0)
			(type solid)
		)
		(fill yes)
		(layer "In4.Cu")
		(net "M_F_CPU0_SB_DQ<31>")
	)
	(gr_poly
		(pts
			(xy 383.255774 -241.685826) (xy 383.208784 -241.533426) (xy 382.947164 -241.533426) (xy 382.900174 -241.685826)
			(xy 382.900174 -241.730022) (xy 383.255774 -241.730022)
		)
		(stroke
			(width 0)
			(type solid)
		)
		(fill yes)
		(layer "In4.Cu")
		(net "M_G_CPU0_SB_DQS_DP<4>")
	)
	(gr_poly
		(pts
			(xy 383.256536 -243.313458) (xy 383.209546 -243.161058) (xy 382.947926 -243.161058) (xy 382.900936 -243.313458)
			(xy 382.900936 -243.357654) (xy 383.256536 -243.357654)
		)
		(stroke
			(width 0)
			(type solid)
		)
		(fill yes)
		(layer "In4.Cu")
		(net "M_G_CPU0_SB_CB<7>")
	)
	(gr_poly
		(pts
			(xy 383.256536 -241.276886) (xy 383.256536 -241.232436) (xy 382.900936 -241.232436) (xy 382.900936 -241.276886)
			(xy 382.947926 -241.429286) (xy 383.209546 -241.429286)
		)
		(stroke
			(width 0)
			(type solid)
		)
		(fill yes)
		(layer "In4.Cu")
		(net "M_G_CPU0_SB_CB<0>")
	)
	(gr_poly
		(pts
			(xy 383.256536 -240.057686) (xy 383.209546 -239.905286) (xy 382.947926 -239.905286) (xy 382.900936 -240.057686)
			(xy 382.900936 -240.102136) (xy 383.256536 -240.102136)
		)
		(stroke
			(width 0)
			(type solid)
		)
		(fill yes)
		(layer "In4.Cu")
		(net "M_G_CPU0_SB_CB<3>")
	)
	(gr_poly
		(pts
			(xy 383.256536 -239.648746) (xy 383.256536 -239.60455) (xy 382.900936 -239.60455) (xy 382.900936 -239.648746)
			(xy 382.947926 -239.801146) (xy 383.209546 -239.801146)
		)
		(stroke
			(width 0)
			(type solid)
		)
		(fill yes)
		(layer "In4.Cu")
		(net "M_F_CPU0_SB_DQ<0>")
	)
	(gr_poly
		(pts
			(xy 383.256536 -235.174282) (xy 383.209546 -235.021882) (xy 382.947926 -235.021882) (xy 382.900936 -235.174282)
			(xy 382.900936 -235.218732) (xy 383.256536 -235.218732)
		)
		(stroke
			(width 0)
			(type solid)
		)
		(fill yes)
		(layer "In4.Cu")
		(net "M_F_CPU0_SB_DQ<7>")
	)
	(gr_poly
		(pts
			(xy 383.256536 -230.290878) (xy 383.209546 -230.138478) (xy 382.947926 -230.138478) (xy 382.900936 -230.290878)
			(xy 382.900936 -230.335328) (xy 383.256536 -230.335328)
		)
		(stroke
			(width 0)
			(type solid)
		)
		(fill yes)
		(layer "In4.Cu")
		(net "M_G_CPU0_SB_DQ<23>")
	)
	(gr_poly
		(pts
			(xy 383.257298 -244.53215) (xy 383.257298 -244.487954) (xy 382.901698 -244.487954) (xy 382.901698 -244.53215)
			(xy 382.948688 -244.68455) (xy 383.210308 -244.68455)
		)
		(stroke
			(width 0)
			(type solid)
		)
		(fill yes)
		(layer "In4.Cu")
		(net "M_G_CPU0_SB_CB<4>")
	)
	(gr_poly
		(pts
			(xy 383.257298 -238.430054) (xy 383.210308 -238.277654) (xy 382.948688 -238.277654) (xy 382.901698 -238.430054)
			(xy 382.901698 -238.47425) (xy 383.257298 -238.47425)
		)
		(stroke
			(width 0)
			(type solid)
		)
		(fill yes)
		(layer "In4.Cu")
		(net "M_F_CPU0_SB_DQ<3>")
	)
	(gr_poly
		(pts
			(xy 383.257298 -236.393482) (xy 383.257298 -236.349032) (xy 382.901698 -236.349032) (xy 382.901698 -236.393482)
			(xy 382.948688 -236.545882) (xy 383.210308 -236.545882)
		)
		(stroke
			(width 0)
			(type solid)
		)
		(fill yes)
		(layer "In4.Cu")
		(net "M_F_CPU0_SB_DQ<4>")
	)
	(gr_poly
		(pts
			(xy 383.257298 -233.54665) (xy 383.210308 -233.39425) (xy 382.948688 -233.39425) (xy 382.901698 -233.54665)
			(xy 382.901698 -233.5911) (xy 383.257298 -233.5911)
		)
		(stroke
			(width 0)
			(type solid)
		)
		(fill yes)
		(layer "In4.Cu")
		(net "M_G_CPU0_SB_DQ<19>")
	)
	(gr_poly
		(pts
			(xy 383.257298 -231.510078) (xy 383.257298 -231.465628) (xy 382.901698 -231.465628) (xy 382.901698 -231.510078)
			(xy 382.948688 -231.662478) (xy 383.210308 -231.662478)
		)
		(stroke
			(width 0)
			(type solid)
		)
		(fill yes)
		(layer "In4.Cu")
		(net "M_G_CPU0_SB_DQ<20>")
	)
	(gr_poly
		(pts
			(xy 383.25933 -247.787922) (xy 383.25933 -247.743472) (xy 382.90373 -247.743472) (xy 382.90373 -247.787922)
			(xy 382.95072 -247.940322) (xy 383.21234 -247.940322)
		)
		(stroke
			(width 0)
			(type solid)
		)
		(fill yes)
		(layer "In4.Cu")
		(net "M_G_CPU0_SB_CA<6>")
	)
	(gr_poly
		(pts
			(xy 383.326132 -225.479102) (xy 383.217674 -225.362262) (xy 383.17932 -225.340164) (xy 383.00152 -225.648012)
			(xy 383.039874 -225.67011) (xy 383.195322 -225.70567)
		)
		(stroke
			(width 0)
			(type solid)
		)
		(fill yes)
		(layer "In4.Cu")
		(net "M_F_CPU0_SB_DQS_DN<8>")
	)
	(gr_poly
		(pts
			(xy 383.327148 -220.593666) (xy 383.21869 -220.476826) (xy 383.180336 -220.454728) (xy 383.002536 -220.762576)
			(xy 383.04089 -220.784674) (xy 383.196338 -220.820234)
		)
		(stroke
			(width 0)
			(type solid)
		)
		(fill yes)
		(layer "In4.Cu")
		(net "M_F_CPU0_SB_DQ<30>")
	)
	(gr_poly
		(pts
			(xy 383.328418 -275.73732) (xy 383.436876 -275.62048) (xy 383.306066 -275.393912) (xy 383.150618 -275.429472)
			(xy 383.112264 -275.45157) (xy 383.290064 -275.759418)
		)
		(stroke
			(width 0)
			(type solid)
		)
		(fill yes)
		(layer "In4.Cu")
		(net "M_G_CPU0_SA_DQS_DN<0>")
	)
	(gr_poly
		(pts
			(xy 383.329434 -278.995378) (xy 383.437892 -278.878538) (xy 383.307082 -278.65197) (xy 383.151634 -278.68753)
			(xy 383.11328 -278.709628) (xy 383.29108 -279.017476)
		)
		(stroke
			(width 0)
			(type solid)
		)
		(fill yes)
		(layer "In4.Cu")
		(net "M_G_CPU0_SA_DQ<2>")
	)
	(gr_poly
		(pts
			(xy 383.332482 -228.723444) (xy 383.224024 -228.606604) (xy 383.18567 -228.584506) (xy 383.00787 -228.892354)
			(xy 383.046224 -228.914452) (xy 383.201672 -228.950012)
		)
		(stroke
			(width 0)
			(type solid)
		)
		(fill yes)
		(layer "In4.Cu")
		(net "M_F_CPU0_SB_DQ<26>")
	)
	(gr_poly
		(pts
			(xy 383.332482 -227.095558) (xy 383.224024 -226.978718) (xy 383.18567 -226.95662) (xy 383.00787 -227.264468)
			(xy 383.046224 -227.286566) (xy 383.201672 -227.322126)
		)
		(stroke
			(width 0)
			(type solid)
		)
		(fill yes)
		(layer "In4.Cu")
		(net "M_F_CPU0_SB_DQ<27>")
	)
	(gr_poly
		(pts
			(xy 383.332482 -222.212154) (xy 383.224024 -222.095314) (xy 383.18567 -222.073216) (xy 383.00787 -222.381064)
			(xy 383.046224 -222.403162) (xy 383.201672 -222.438722)
		)
		(stroke
			(width 0)
			(type solid)
		)
		(fill yes)
		(layer "In4.Cu")
		(net "M_F_CPU0_SB_DQS_DP<3>")
	)
	(gr_poly
		(pts
			(xy 383.35458 -277.318216) (xy 383.35458 -277.27402) (xy 382.99898 -277.27402) (xy 382.99898 -277.318216)
			(xy 383.04597 -277.470616) (xy 383.30759 -277.470616)
		)
		(stroke
			(width 0)
			(type solid)
		)
		(fill yes)
		(layer "In4.Cu")
		(net "M_G_CPU0_SA_DQ<1>")
	)
	(gr_poly
		(pts
			(xy 383.35458 -272.843498) (xy 383.30759 -272.691098) (xy 383.04597 -272.691098) (xy 382.99898 -272.843498)
			(xy 382.99898 -272.887694) (xy 383.35458 -272.887694)
		)
		(stroke
			(width 0)
			(type solid)
		)
		(fill yes)
		(layer "In4.Cu")
		(net "M_G_CPU0_SA_DQ<7>")
	)
	(gr_poly
		(pts
			(xy 383.35458 -270.807434) (xy 383.35458 -270.762984) (xy 382.99898 -270.762984) (xy 382.99898 -270.807434)
			(xy 383.04597 -270.959834) (xy 383.30759 -270.959834)
		)
		(stroke
			(width 0)
			(type solid)
		)
		(fill yes)
		(layer "In4.Cu")
		(net "M_F_CPU0_SA_DQS_DP<1>")
	)
	(gr_poly
		(pts
			(xy 383.35458 -265.92403) (xy 383.35458 -265.87958) (xy 382.99898 -265.87958) (xy 382.99898 -265.92403)
			(xy 383.04597 -266.07643) (xy 383.30759 -266.07643)
		)
		(stroke
			(width 0)
			(type solid)
		)
		(fill yes)
		(layer "In4.Cu")
		(net "M_G_CPU0_SA_DQS_DP<2>")
	)
	(gr_poly
		(pts
			(xy 383.35458 -264.704322) (xy 383.30759 -264.551922) (xy 383.04597 -264.551922) (xy 382.99898 -264.704322)
			(xy 382.99898 -264.748772) (xy 383.35458 -264.748772)
		)
		(stroke
			(width 0)
			(type solid)
		)
		(fill yes)
		(layer "In4.Cu")
		(net "M_G_CPU0_SA_DQS_DP<7>")
	)
	(gr_poly
		(pts
			(xy 383.354834 -261.449058) (xy 383.307844 -261.296658) (xy 383.046224 -261.296658) (xy 382.999234 -261.449058)
			(xy 382.999234 -261.493508) (xy 383.354834 -261.493508)
		)
		(stroke
			(width 0)
			(type solid)
		)
		(fill yes)
		(layer "In4.Cu")
		(net "M_F_CPU0_SA_DQ<27>")
	)
	(gr_poly
		(pts
			(xy 383.356866 -259.821426) (xy 383.309876 -259.669026) (xy 383.048256 -259.669026) (xy 383.001266 -259.821426)
			(xy 383.001266 -259.865622) (xy 383.356866 -259.865622)
		)
		(stroke
			(width 0)
			(type solid)
		)
		(fill yes)
		(layer "In4.Cu")
		(net "M_F_CPU0_SA_DQS_DP<8>")
	)
	(gr_poly
		(pts
			(xy 383.359406 -259.412486) (xy 383.359406 -259.368036) (xy 383.003806 -259.368036) (xy 383.003806 -259.412486)
			(xy 383.050796 -259.564886) (xy 383.312416 -259.564886)
		)
		(stroke
			(width 0)
			(type solid)
		)
		(fill yes)
		(layer "In4.Cu")
		(net "M_F_CPU0_SA_DQ<28>")
	)
	(gr_poly
		(pts
			(xy 383.362962 -274.471638) (xy 383.315972 -274.319238) (xy 383.054352 -274.319238) (xy 383.007362 -274.471638)
			(xy 383.007362 -274.516088) (xy 383.362962 -274.516088)
		)
		(stroke
			(width 0)
			(type solid)
		)
		(fill yes)
		(layer "In4.Cu")
		(net "M_G_CPU0_SA_DQS_DP<5>")
	)
	(gr_poly
		(pts
			(xy 383.362962 -264.29589) (xy 383.362962 -264.251694) (xy 383.007362 -264.251694) (xy 383.007362 -264.29589)
			(xy 383.054352 -264.44829) (xy 383.315972 -264.44829)
		)
		(stroke
			(width 0)
			(type solid)
		)
		(fill yes)
		(layer "In4.Cu")
		(net "M_G_CPU0_SA_DQ<20>")
	)
	(gr_poly
		(pts
			(xy 383.362962 -261.040626) (xy 383.362962 -260.996176) (xy 383.007362 -260.996176) (xy 383.007362 -261.040626)
			(xy 383.054352 -261.193026) (xy 383.315972 -261.193026)
		)
		(stroke
			(width 0)
			(type solid)
		)
		(fill yes)
		(layer "In4.Cu")
		(net "M_F_CPU0_SA_DQS_DP<3>")
	)
	(gr_poly
		(pts
			(xy 383.362962 -258.193286) (xy 383.315972 -258.040886) (xy 383.054352 -258.040886) (xy 383.007362 -258.193286)
			(xy 383.007362 -258.237736) (xy 383.362962 -258.237736)
		)
		(stroke
			(width 0)
			(type solid)
		)
		(fill yes)
		(layer "In4.Cu")
		(net "M_F_CPU0_SA_DQ<31>")
	)
	(gr_poly
		(pts
			(xy 383.362962 -257.784854) (xy 383.362962 -257.740404) (xy 383.007362 -257.740404) (xy 383.007362 -257.784854)
			(xy 383.054352 -257.937254) (xy 383.315972 -257.937254)
		)
		(stroke
			(width 0)
			(type solid)
		)
		(fill yes)
		(layer "In4.Cu")
		(net "M_G_CPU0_SA_CS_N<0>")
	)
	(gr_poly
		(pts
			(xy 383.362962 -256.565654) (xy 383.315972 -256.413254) (xy 383.054352 -256.413254) (xy 383.007362 -256.565654)
			(xy 383.007362 -256.610104) (xy 383.362962 -256.610104)
		)
		(stroke
			(width 0)
			(type solid)
		)
		(fill yes)
		(layer "In4.Cu")
		(net "M_G_CPU0_SA_CS_N<3>")
	)
	(gr_poly
		(pts
			(xy 383.362962 -256.157222) (xy 383.362962 -256.112772) (xy 383.007362 -256.112772) (xy 383.007362 -256.157222)
			(xy 383.054352 -256.309622) (xy 383.315972 -256.309622)
		)
		(stroke
			(width 0)
			(type solid)
		)
		(fill yes)
		(layer "In4.Cu")
		(net "M_G_CPU0_SA_CA<1>")
	)
	(gr_poly
		(pts
			(xy 383.362962 -254.938022) (xy 383.315972 -254.785622) (xy 383.054352 -254.785622) (xy 383.007362 -254.938022)
			(xy 383.007362 -254.982218) (xy 383.362962 -254.982218)
		)
		(stroke
			(width 0)
			(type solid)
		)
		(fill yes)
		(layer "In4.Cu")
		(net "M_G_CPU0_SA_CA<2>")
	)
	(gr_poly
		(pts
			(xy 383.365248 -266.332462) (xy 383.318258 -266.180062) (xy 383.056638 -266.180062) (xy 383.009648 -266.332462)
			(xy 383.009648 -266.376912) (xy 383.365248 -266.376912)
		)
		(stroke
			(width 0)
			(type solid)
		)
		(fill yes)
		(layer "In4.Cu")
		(net "M_G_CPU0_SA_DQ<19>")
	)
	(gr_poly
		(pts
			(xy 383.365756 -274.062698) (xy 383.365756 -274.018248) (xy 383.010156 -274.018248) (xy 383.010156 -274.062698)
			(xy 383.057146 -274.215098) (xy 383.318766 -274.215098)
		)
		(stroke
			(width 0)
			(type solid)
		)
		(fill yes)
		(layer "In4.Cu")
		(net "M_G_CPU0_SA_DQ<4>")
	)
	(gr_poly
		(pts
			(xy 383.365756 -272.434558) (xy 383.365756 -272.390362) (xy 383.010156 -272.390362) (xy 383.010156 -272.434558)
			(xy 383.057146 -272.586958) (xy 383.318766 -272.586958)
		)
		(stroke
			(width 0)
			(type solid)
		)
		(fill yes)
		(layer "In4.Cu")
		(net "M_F_CPU0_SA_DQ<8>")
	)
	(gr_poly
		(pts
			(xy 383.365756 -271.215866) (xy 383.318766 -271.063466) (xy 383.057146 -271.063466) (xy 383.010156 -271.215866)
			(xy 383.010156 -271.260062) (xy 383.365756 -271.260062)
		)
		(stroke
			(width 0)
			(type solid)
		)
		(fill yes)
		(layer "In4.Cu")
		(net "M_F_CPU0_SA_DQ<11>")
	)
	(gr_poly
		(pts
			(xy 383.365756 -269.588234) (xy 383.318766 -269.435834) (xy 383.057146 -269.435834) (xy 383.010156 -269.588234)
			(xy 383.010156 -269.63243) (xy 383.365756 -269.63243)
		)
		(stroke
			(width 0)
			(type solid)
		)
		(fill yes)
		(layer "In4.Cu")
		(net "M_F_CPU0_SA_DQS_DP<6>")
	)
	(gr_poly
		(pts
			(xy 383.365756 -269.179294) (xy 383.365756 -269.134844) (xy 383.010156 -269.134844) (xy 383.010156 -269.179294)
			(xy 383.057146 -269.331694) (xy 383.318766 -269.331694)
		)
		(stroke
			(width 0)
			(type solid)
		)
		(fill yes)
		(layer "In4.Cu")
		(net "M_F_CPU0_SA_DQ<12>")
	)
	(gr_poly
		(pts
			(xy 383.365756 -267.960094) (xy 383.318766 -267.807694) (xy 383.057146 -267.807694) (xy 383.010156 -267.960094)
			(xy 383.010156 -268.004544) (xy 383.365756 -268.004544)
		)
		(stroke
			(width 0)
			(type solid)
		)
		(fill yes)
		(layer "In4.Cu")
		(net "M_F_CPU0_SA_DQ<13>")
	)
	(gr_poly
		(pts
			(xy 383.365756 -267.551154) (xy 383.365756 -267.506958) (xy 383.010156 -267.506958) (xy 383.010156 -267.551154)
			(xy 383.057146 -267.703554) (xy 383.318766 -267.703554)
		)
		(stroke
			(width 0)
			(type solid)
		)
		(fill yes)
		(layer "In4.Cu")
		(net "M_G_CPU0_SA_DQ<16>")
	)
	(gr_poly
		(pts
			(xy 383.365756 -263.07669) (xy 383.318766 -262.92429) (xy 383.057146 -262.92429) (xy 383.010156 -263.07669)
			(xy 383.010156 -263.12114) (xy 383.365756 -263.12114)
		)
		(stroke
			(width 0)
			(type solid)
		)
		(fill yes)
		(layer "In4.Cu")
		(net "M_G_CPU0_SA_DQ<23>")
	)
	(gr_poly
		(pts
			(xy 383.365756 -262.668258) (xy 383.365756 -262.623808) (xy 383.010156 -262.623808) (xy 383.010156 -262.668258)
			(xy 383.057146 -262.820658) (xy 383.318766 -262.820658)
		)
		(stroke
			(width 0)
			(type solid)
		)
		(fill yes)
		(layer "In4.Cu")
		(net "M_F_CPU0_SA_DQ<24>")
	)
	(gr_poly
		(pts
			(xy 383.580894 -223.228408) (xy 383.619248 -223.20631) (xy 383.441448 -222.898462) (xy 383.403094 -222.92056)
			(xy 383.294636 -223.0374) (xy 383.425446 -223.263968)
		)
		(stroke
			(width 0)
			(type solid)
		)
		(fill yes)
		(layer "In4.Cu")
		(net "M_F_CPU0_SB_DQS_DP<8>")
	)
	(gr_poly
		(pts
			(xy 383.610866 -223.958912) (xy 383.572512 -223.936814) (xy 383.417064 -223.901254) (xy 383.286254 -224.127822)
			(xy 383.394712 -224.244662) (xy 383.433066 -224.26676)
		)
		(stroke
			(width 0)
			(type solid)
		)
		(fill yes)
		(layer "In4.Cu")
		(net "M_F_CPU0_SB_DQS_DP<8>")
	)
	(gr_poly
		(pts
			(xy 383.617216 -227.20427) (xy 383.578862 -227.182172) (xy 383.423414 -227.146612) (xy 383.292604 -227.37318)
			(xy 383.401062 -227.49002) (xy 383.439416 -227.512118)
		)
		(stroke
			(width 0)
			(type solid)
		)
		(fill yes)
		(layer "In4.Cu")
		(net "M_F_CPU0_SB_DQ<24>")
	)
	(gr_poly
		(pts
			(xy 383.617216 -222.320866) (xy 383.578862 -222.298768) (xy 383.423414 -222.263208) (xy 383.292604 -222.489776)
			(xy 383.401062 -222.606616) (xy 383.439416 -222.628714)
		)
		(stroke
			(width 0)
			(type solid)
		)
		(fill yes)
		(layer "In4.Cu")
		(net "M_F_CPU0_SB_DQS_DP<8>")
	)
	(gr_poly
		(pts
			(xy 383.619248 -225.572574) (xy 383.580894 -225.550476) (xy 383.425446 -225.514916) (xy 383.294636 -225.741484)
			(xy 383.403094 -225.858324) (xy 383.441448 -225.880422)
		)
		(stroke
			(width 0)
			(type solid)
		)
		(fill yes)
		(layer "In4.Cu")
		(net "M_F_CPU0_SB_DQ<25>")
	)
	(gr_poly
		(pts
			(xy 383.68986 -275.546312) (xy 383.728214 -275.524214) (xy 383.550414 -275.216366) (xy 383.51206 -275.238464)
			(xy 383.403602 -275.355304) (xy 383.534412 -275.581872)
		)
		(stroke
			(width 0)
			(type solid)
		)
		(fill yes)
		(layer "In4.Cu")
		(net "M_G_CPU0_SA_DQS_DN<5>")
	)
	(gr_poly
		(pts
			(xy 383.719832 -244.127274) (xy 383.672842 -243.974874) (xy 383.411222 -243.974874) (xy 383.364232 -244.127274)
			(xy 383.364232 -244.17147) (xy 383.719832 -244.17147)
		)
		(stroke
			(width 0)
			(type solid)
		)
		(fill yes)
		(layer "In4.Cu")
		(net "M_G_CPU0_SB_CB<6>")
	)
	(gr_poly
		(pts
			(xy 383.719832 -238.83493) (xy 383.719832 -238.790734) (xy 383.364232 -238.790734) (xy 383.364232 -238.83493)
			(xy 383.411222 -238.98733) (xy 383.672842 -238.98733)
		)
		(stroke
			(width 0)
			(type solid)
		)
		(fill yes)
		(layer "In4.Cu")
		(net "M_F_CPU0_SB_DQ<1>")
	)
	(gr_poly
		(pts
			(xy 383.719832 -235.988606) (xy 383.672842 -235.836206) (xy 383.411222 -235.836206) (xy 383.364232 -235.988606)
			(xy 383.364232 -236.032802) (xy 383.719832 -236.032802)
		)
		(stroke
			(width 0)
			(type solid)
		)
		(fill yes)
		(layer "In4.Cu")
		(net "M_F_CPU0_SB_DQ<6>")
	)
	(gr_poly
		(pts
			(xy 383.719832 -233.951526) (xy 383.719832 -233.90733) (xy 383.364232 -233.90733) (xy 383.364232 -233.951526)
			(xy 383.411222 -234.103926) (xy 383.672842 -234.103926)
		)
		(stroke
			(width 0)
			(type solid)
		)
		(fill yes)
		(layer "In4.Cu")
		(net "M_G_CPU0_SB_DQ<17>")
	)
	(gr_poly
		(pts
			(xy 383.719832 -231.105202) (xy 383.672842 -230.952802) (xy 383.411222 -230.952802) (xy 383.364232 -231.105202)
			(xy 383.364232 -231.149398) (xy 383.719832 -231.149398)
		)
		(stroke
			(width 0)
			(type solid)
		)
		(fill yes)
		(layer "In4.Cu")
		(net "M_G_CPU0_SB_DQ<22>")
	)
	(gr_poly
		(pts
			(xy 383.720848 -243.718334) (xy 383.720848 -243.674138) (xy 383.365248 -243.674138) (xy 383.365248 -243.718334)
			(xy 383.412238 -243.870734) (xy 383.673858 -243.870734)
		)
		(stroke
			(width 0)
			(type solid)
		)
		(fill yes)
		(layer "In4.Cu")
		(net "M_G_CPU0_SB_CB<5>")
	)
	(gr_poly
		(pts
			(xy 383.720848 -240.871502) (xy 383.673858 -240.719102) (xy 383.412238 -240.719102) (xy 383.365248 -240.871502)
			(xy 383.365248 -240.915952) (xy 383.720848 -240.915952)
		)
		(stroke
			(width 0)
			(type solid)
		)
		(fill yes)
		(layer "In4.Cu")
		(net "M_G_CPU0_SB_CB<2>")
	)
	(gr_poly
		(pts
			(xy 383.720848 -240.46307) (xy 383.720848 -240.41862) (xy 383.365248 -240.41862) (xy 383.365248 -240.46307)
			(xy 383.412238 -240.61547) (xy 383.673858 -240.61547)
		)
		(stroke
			(width 0)
			(type solid)
		)
		(fill yes)
		(layer "In4.Cu")
		(net "M_G_CPU0_SB_CB<1>")
	)
	(gr_poly
		(pts
			(xy 383.720848 -239.24387) (xy 383.673858 -239.09147) (xy 383.412238 -239.09147) (xy 383.365248 -239.24387)
			(xy 383.365248 -239.288066) (xy 383.720848 -239.288066)
		)
		(stroke
			(width 0)
			(type solid)
		)
		(fill yes)
		(layer "In4.Cu")
		(net "M_F_CPU0_SB_DQ<2>")
	)
	(gr_poly
		(pts
			(xy 383.720848 -235.579666) (xy 383.720848 -235.535216) (xy 383.365248 -235.535216) (xy 383.365248 -235.579666)
			(xy 383.412238 -235.732066) (xy 383.673858 -235.732066)
		)
		(stroke
			(width 0)
			(type solid)
		)
		(fill yes)
		(layer "In4.Cu")
		(net "M_F_CPU0_SB_DQ<5>")
	)
	(gr_poly
		(pts
			(xy 383.720848 -230.696262) (xy 383.720848 -230.651812) (xy 383.365248 -230.651812) (xy 383.365248 -230.696262)
			(xy 383.412238 -230.848662) (xy 383.673858 -230.848662)
		)
		(stroke
			(width 0)
			(type solid)
		)
		(fill yes)
		(layer "In4.Cu")
		(net "M_G_CPU0_SB_DQ<21>")
	)
	(gr_poly
		(pts
			(xy 383.723134 -247.382538) (xy 383.676144 -247.230138) (xy 383.414524 -247.230138) (xy 383.367534 -247.382538)
			(xy 383.367534 -247.426988) (xy 383.723134 -247.426988)
		)
		(stroke
			(width 0)
			(type solid)
		)
		(fill yes)
		(layer "In4.Cu")
		(net "M_G_CPU0_SB_PAR")
	)
	(gr_poly
		(pts
			(xy 383.723134 -246.974106) (xy 383.723134 -246.929656) (xy 383.367534 -246.929656) (xy 383.367534 -246.974106)
			(xy 383.414524 -247.126506) (xy 383.676144 -247.126506)
		)
		(stroke
			(width 0)
			(type solid)
		)
		(fill yes)
		(layer "In4.Cu")
		(net "M_G_CPU0_SB_CS_N<2>")
	)
	(gr_poly
		(pts
			(xy 383.723134 -245.754906) (xy 383.676144 -245.602506) (xy 383.414524 -245.602506) (xy 383.367534 -245.754906)
			(xy 383.367534 -245.799356) (xy 383.723134 -245.799356)
		)
		(stroke
			(width 0)
			(type solid)
		)
		(fill yes)
		(layer "In4.Cu")
		(net "M_G_CPU0_SB_CS_N<1>")
	)
	(gr_poly
		(pts
			(xy 383.723134 -242.499134) (xy 383.676144 -242.346734) (xy 383.414524 -242.346734) (xy 383.367534 -242.499134)
			(xy 383.367534 -242.543584) (xy 383.723134 -242.543584)
		)
		(stroke
			(width 0)
			(type solid)
		)
		(fill yes)
		(layer "In4.Cu")
		(net "M_G_CPU0_SB_DQS_DN<9>")
	)
	(gr_poly
		(pts
			(xy 383.723134 -242.090702) (xy 383.723134 -242.046252) (xy 383.367534 -242.046252) (xy 383.367534 -242.090702)
			(xy 383.414524 -242.243102) (xy 383.676144 -242.243102)
		)
		(stroke
			(width 0)
			(type solid)
		)
		(fill yes)
		(layer "In4.Cu")
		(net "M_G_CPU0_SB_DQS_DN<4>")
	)
	(gr_poly
		(pts
			(xy 383.723134 -237.61573) (xy 383.676144 -237.46333) (xy 383.414524 -237.46333) (xy 383.367534 -237.61573)
			(xy 383.367534 -237.66018) (xy 383.723134 -237.66018)
		)
		(stroke
			(width 0)
			(type solid)
		)
		(fill yes)
		(layer "In4.Cu")
		(net "M_F_CPU0_SB_DQS_DN<0>")
	)
	(gr_poly
		(pts
			(xy 383.723134 -234.360466) (xy 383.676144 -234.208066) (xy 383.414524 -234.208066) (xy 383.367534 -234.360466)
			(xy 383.367534 -234.404916) (xy 383.723134 -234.404916)
		)
		(stroke
			(width 0)
			(type solid)
		)
		(fill yes)
		(layer "In4.Cu")
		(net "M_G_CPU0_SB_DQ<18>")
	)
	(gr_poly
		(pts
			(xy 383.723134 -232.732834) (xy 383.676144 -232.580434) (xy 383.414524 -232.580434) (xy 383.367534 -232.732834)
			(xy 383.367534 -232.77703) (xy 383.723134 -232.77703)
		)
		(stroke
			(width 0)
			(type solid)
		)
		(fill yes)
		(layer "In4.Cu")
		(net "M_G_CPU0_SB_DQS_DN<2>")
	)
	(gr_poly
		(pts
			(xy 383.723134 -232.323894) (xy 383.723134 -232.279698) (xy 383.367534 -232.279698) (xy 383.367534 -232.323894)
			(xy 383.414524 -232.476294) (xy 383.676144 -232.476294)
		)
		(stroke
			(width 0)
			(type solid)
		)
		(fill yes)
		(layer "In4.Cu")
		(net "M_G_CPU0_SB_DQS_DN<7>")
	)
	(gr_poly
		(pts
			(xy 383.723134 -221.338394) (xy 383.676144 -221.185994) (xy 383.414524 -221.185994) (xy 383.367534 -221.338394)
			(xy 383.367534 -221.38259) (xy 383.723134 -221.38259)
		)
		(stroke
			(width 0)
			(type solid)
		)
		(fill yes)
		(layer "In4.Cu")
		(net "M_F_CPU0_SB_DQS_DN<3>")
	)
	(gr_poly
		(pts
			(xy 383.723134 -219.710254) (xy 383.676144 -219.557854) (xy 383.414524 -219.557854) (xy 383.367534 -219.710254)
			(xy 383.367534 -219.754704) (xy 383.723134 -219.754704)
		)
		(stroke
			(width 0)
			(type solid)
		)
		(fill yes)
		(layer "In4.Cu")
		(net "M_F_CPU0_SB_DQ<28>")
	)
	(gr_poly
		(pts
			(xy 383.723134 -219.301822) (xy 383.723134 -219.257372) (xy 383.367534 -219.257372) (xy 383.367534 -219.301822)
			(xy 383.414524 -219.454222) (xy 383.676144 -219.454222)
		)
		(stroke
			(width 0)
			(type solid)
		)
		(fill yes)
		(layer "In4.Cu")
		(net "M_F_CPU0_SB_DQ<29>")
	)
	(gr_poly
		(pts
			(xy 383.731516 -237.207806) (xy 383.731516 -237.163356) (xy 383.375916 -237.163356) (xy 383.375916 -237.207806)
			(xy 383.422906 -237.360206) (xy 383.684526 -237.360206)
		)
		(stroke
			(width 0)
			(type solid)
		)
		(fill yes)
		(layer "In4.Cu")
		(net "M_F_CPU0_SB_DQS_DN<5>")
	)
	(gr_poly
		(pts
			(xy 383.796032 -227.920804) (xy 383.687574 -227.803964) (xy 383.64922 -227.781866) (xy 383.47142 -228.089714)
			(xy 383.509774 -228.111812) (xy 383.665222 -228.147372)
		)
		(stroke
			(width 0)
			(type solid)
		)
		(fill yes)
		(layer "In4.Cu")
		(net "M_F_CPU0_SB_DQ<26>")
	)
	(gr_poly
		(pts
			(xy 383.798064 -226.289108) (xy 383.689606 -226.172268) (xy 383.651252 -226.15017) (xy 383.473452 -226.458018)
			(xy 383.511806 -226.480116) (xy 383.667254 -226.515676)
		)
		(stroke
			(width 0)
			(type solid)
		)
		(fill yes)
		(layer "In4.Cu")
		(net "M_F_CPU0_SB_DQ<27>")
	)
	(gr_poly
		(pts
			(xy 383.798572 -274.924012) (xy 383.90703 -274.807172) (xy 383.77622 -274.580604) (xy 383.620772 -274.616164)
			(xy 383.582418 -274.638262) (xy 383.760218 -274.94611)
		)
		(stroke
			(width 0)
			(type solid)
		)
		(fill yes)
		(layer "In4.Cu")
		(net "M_G_CPU0_SA_DQS_DP<5>")
	)
	(gr_poly
		(pts
			(xy 383.802382 -224.653856) (xy 383.693924 -224.537016) (xy 383.65557 -224.514918) (xy 383.47777 -224.822766)
			(xy 383.516124 -224.844864) (xy 383.671572 -224.880424)
		)
		(stroke
			(width 0)
			(type solid)
		)
		(fill yes)
		(layer "In4.Cu")
		(net "M_F_CPU0_SB_DQS_DN<8>")
	)
	(gr_poly
		(pts
			(xy 383.826766 -279.759918) (xy 383.826766 -279.715722) (xy 383.471166 -279.715722) (xy 383.471166 -279.759918)
			(xy 383.518156 -279.912318) (xy 383.779776 -279.912318)
		)
		(stroke
			(width 0)
			(type solid)
		)
		(fill yes)
		(layer "In4.Cu")
		(net "M_G_CPU0_SA_DQ<0>")
	)
	(gr_poly
		(pts
			(xy 383.832862 -263.891014) (xy 383.785872 -263.738614) (xy 383.524252 -263.738614) (xy 383.477262 -263.891014)
			(xy 383.477262 -263.93521) (xy 383.832862 -263.93521)
		)
		(stroke
			(width 0)
			(type solid)
		)
		(fill yes)
		(layer "In4.Cu")
		(net "M_G_CPU0_SA_DQ<22>")
	)
	(gr_poly
		(pts
			(xy 383.832862 -260.635242) (xy 383.785872 -260.482842) (xy 383.524252 -260.482842) (xy 383.477262 -260.635242)
			(xy 383.477262 -260.679438) (xy 383.832862 -260.679438)
		)
		(stroke
			(width 0)
			(type solid)
		)
		(fill yes)
		(layer "In4.Cu")
		(net "M_F_CPU0_SA_DQS_DN<3>")
	)
	(gr_poly
		(pts
			(xy 383.832862 -258.59867) (xy 383.832862 -258.554474) (xy 383.477262 -258.554474) (xy 383.477262 -258.59867)
			(xy 383.524252 -258.75107) (xy 383.785872 -258.75107)
		)
		(stroke
			(width 0)
			(type solid)
		)
		(fill yes)
		(layer "In4.Cu")
		(net "M_F_CPU0_SA_DQ<29>")
	)
	(gr_poly
		(pts
			(xy 383.832862 -257.37947) (xy 383.785872 -257.22707) (xy 383.524252 -257.22707) (xy 383.477262 -257.37947)
			(xy 383.477262 -257.42392) (xy 383.832862 -257.42392)
		)
		(stroke
			(width 0)
			(type solid)
		)
		(fill yes)
		(layer "In4.Cu")
		(net "M_G_CPU0_SA_CS_N<1>")
	)
	(gr_poly
		(pts
			(xy 383.832862 -256.971038) (xy 383.832862 -256.926588) (xy 383.477262 -256.926588) (xy 383.477262 -256.971038)
			(xy 383.524252 -257.123438) (xy 383.785872 -257.123438)
		)
		(stroke
			(width 0)
			(type solid)
		)
		(fill yes)
		(layer "In4.Cu")
		(net "M_G_CPU0_SA_CS_N<2>")
	)
	(gr_poly
		(pts
			(xy 383.832862 -255.751838) (xy 383.785872 -255.599438) (xy 383.524252 -255.599438) (xy 383.477262 -255.751838)
			(xy 383.477262 -255.796288) (xy 383.832862 -255.796288)
		)
		(stroke
			(width 0)
			(type solid)
		)
		(fill yes)
		(layer "In4.Cu")
		(net "M_G_CPU0_SA_CA<0>")
	)
	(gr_poly
		(pts
			(xy 383.832862 -255.343406) (xy 383.832862 -255.298956) (xy 383.477262 -255.298956) (xy 383.477262 -255.343406)
			(xy 383.524252 -255.495806) (xy 383.785872 -255.495806)
		)
		(stroke
			(width 0)
			(type solid)
		)
		(fill yes)
		(layer "In4.Cu")
		(net "M_G_CPU0_SA_CA<3>")
	)
	(gr_poly
		(pts
			(xy 383.833116 -273.657314) (xy 383.786126 -273.504914) (xy 383.524506 -273.504914) (xy 383.477516 -273.657314)
			(xy 383.477516 -273.701764) (xy 383.833116 -273.701764)
		)
		(stroke
			(width 0)
			(type solid)
		)
		(fill yes)
		(layer "In4.Cu")
		(net "M_G_CPU0_SA_DQ<6>")
	)
	(gr_poly
		(pts
			(xy 383.833116 -272.029682) (xy 383.786126 -271.877282) (xy 383.524506 -271.877282) (xy 383.477516 -272.029682)
			(xy 383.477516 -272.074132) (xy 383.833116 -272.074132)
		)
		(stroke
			(width 0)
			(type solid)
		)
		(fill yes)
		(layer "In4.Cu")
		(net "M_F_CPU0_SA_DQ<10>")
	)
	(gr_poly
		(pts
			(xy 383.833116 -268.77391) (xy 383.786126 -268.62151) (xy 383.524506 -268.62151) (xy 383.477516 -268.77391)
			(xy 383.477516 -268.81836) (xy 383.833116 -268.81836)
		)
		(stroke
			(width 0)
			(type solid)
		)
		(fill yes)
		(layer "In4.Cu")
		(net "M_F_CPU0_SA_DQ<14>")
	)
	(gr_poly
		(pts
			(xy 383.833116 -267.146278) (xy 383.786126 -266.993878) (xy 383.524506 -266.993878) (xy 383.477516 -267.146278)
			(xy 383.477516 -267.190728) (xy 383.833116 -267.190728)
		)
		(stroke
			(width 0)
			(type solid)
		)
		(fill yes)
		(layer "In4.Cu")
		(net "M_G_CPU0_SA_DQ<18>")
	)
	(gr_poly
		(pts
			(xy 383.833116 -266.737338) (xy 383.833116 -266.693142) (xy 383.477516 -266.693142) (xy 383.477516 -266.737338)
			(xy 383.524506 -266.889738) (xy 383.786126 -266.889738)
		)
		(stroke
			(width 0)
			(type solid)
		)
		(fill yes)
		(layer "In4.Cu")
		(net "M_G_CPU0_SA_DQ<17>")
	)
	(gr_poly
		(pts
			(xy 383.833116 -263.482074) (xy 383.833116 -263.437624) (xy 383.477516 -263.437624) (xy 383.477516 -263.482074)
			(xy 383.524506 -263.634474) (xy 383.786126 -263.634474)
		)
		(stroke
			(width 0)
			(type solid)
		)
		(fill yes)
		(layer "In4.Cu")
		(net "M_G_CPU0_SA_DQ<21>")
	)
	(gr_poly
		(pts
			(xy 383.833116 -262.262874) (xy 383.786126 -262.110474) (xy 383.524506 -262.110474) (xy 383.477516 -262.262874)
			(xy 383.477516 -262.307324) (xy 383.833116 -262.307324)
		)
		(stroke
			(width 0)
			(type solid)
		)
		(fill yes)
		(layer "In4.Cu")
		(net "M_F_CPU0_SA_DQ<26>")
	)
	(gr_poly
		(pts
			(xy 383.838958 -276.913086) (xy 383.791968 -276.760686) (xy 383.530348 -276.760686) (xy 383.483358 -276.913086)
			(xy 383.483358 -276.957282) (xy 383.838958 -276.957282)
		)
		(stroke
			(width 0)
			(type solid)
		)
		(fill yes)
		(layer "In4.Cu")
		(net "M_G_CPU0_SA_DQ<3>")
	)
	(gr_poly
		(pts
			(xy 383.838958 -276.504146) (xy 383.838958 -276.45995) (xy 383.483358 -276.45995) (xy 383.483358 -276.504146)
			(xy 383.530348 -276.656546) (xy 383.791968 -276.656546)
		)
		(stroke
			(width 0)
			(type solid)
		)
		(fill yes)
		(layer "In4.Cu")
		(net "M_G_CPU0_SA_DQS_DP<0>")
	)
	(gr_poly
		(pts
			(xy 383.838958 -273.248882) (xy 383.838958 -273.204432) (xy 383.483358 -273.204432) (xy 383.483358 -273.248882)
			(xy 383.530348 -273.401282) (xy 383.791968 -273.401282)
		)
		(stroke
			(width 0)
			(type solid)
		)
		(fill yes)
		(layer "In4.Cu")
		(net "M_G_CPU0_SA_DQ<5>")
	)
	(gr_poly
		(pts
			(xy 383.838958 -268.365478) (xy 383.838958 -268.321028) (xy 383.483358 -268.321028) (xy 383.483358 -268.365478)
			(xy 383.530348 -268.517878) (xy 383.791968 -268.517878)
		)
		(stroke
			(width 0)
			(type solid)
		)
		(fill yes)
		(layer "In4.Cu")
		(net "M_F_CPU0_SA_DQ<15>")
	)
	(gr_poly
		(pts
			(xy 383.84099 -261.854442) (xy 383.84099 -261.809992) (xy 383.48539 -261.809992) (xy 383.48539 -261.854442)
			(xy 383.53238 -262.006842) (xy 383.794 -262.006842)
		)
		(stroke
			(width 0)
			(type solid)
		)
		(fill yes)
		(layer "In4.Cu")
		(net "M_F_CPU0_SA_DQ<25>")
	)
	(gr_poly
		(pts
			(xy 383.841244 -260.22681) (xy 383.841244 -260.18236) (xy 383.485644 -260.18236) (xy 383.485644 -260.22681)
			(xy 383.532634 -260.37921) (xy 383.794254 -260.37921)
		)
		(stroke
			(width 0)
			(type solid)
		)
		(fill yes)
		(layer "In4.Cu")
		(net "M_F_CPU0_SA_DQS_DN<8>")
	)
	(gr_poly
		(pts
			(xy 383.841244 -259.007102) (xy 383.794254 -258.854702) (xy 383.532634 -258.854702) (xy 383.485644 -259.007102)
			(xy 383.485644 -259.051552) (xy 383.841244 -259.051552)
		)
		(stroke
			(width 0)
			(type solid)
		)
		(fill yes)
		(layer "In4.Cu")
		(net "M_F_CPU0_SA_DQ<30>")
	)
	(gr_poly
		(pts
			(xy 383.841498 -271.62125) (xy 383.841498 -271.5768) (xy 383.485898 -271.5768) (xy 383.485898 -271.62125)
			(xy 383.532888 -271.77365) (xy 383.794508 -271.77365)
		)
		(stroke
			(width 0)
			(type solid)
		)
		(fill yes)
		(layer "In4.Cu")
		(net "M_F_CPU0_SA_DQ<9>")
	)
	(gr_poly
		(pts
			(xy 383.841498 -270.401542) (xy 383.794508 -270.249142) (xy 383.532888 -270.249142) (xy 383.485898 -270.401542)
			(xy 383.485898 -270.445992) (xy 383.841498 -270.445992)
		)
		(stroke
			(width 0)
			(type solid)
		)
		(fill yes)
		(layer "In4.Cu")
		(net "M_F_CPU0_SA_DQS_DN<1>")
	)
	(gr_poly
		(pts
			(xy 383.841498 -269.993618) (xy 383.841498 -269.949168) (xy 383.485898 -269.949168) (xy 383.485898 -269.993618)
			(xy 383.532888 -270.146018) (xy 383.794508 -270.146018)
		)
		(stroke
			(width 0)
			(type solid)
		)
		(fill yes)
		(layer "In4.Cu")
		(net "M_F_CPU0_SA_DQS_DN<6>")
	)
	(gr_poly
		(pts
			(xy 383.841498 -265.518138) (xy 383.794508 -265.365738) (xy 383.532888 -265.365738) (xy 383.485898 -265.518138)
			(xy 383.485898 -265.562588) (xy 383.841498 -265.562588)
		)
		(stroke
			(width 0)
			(type solid)
		)
		(fill yes)
		(layer "In4.Cu")
		(net "M_G_CPU0_SA_DQS_DN<2>")
	)
	(gr_poly
		(pts
			(xy 383.841498 -265.110214) (xy 383.841498 -265.065764) (xy 383.485898 -265.065764) (xy 383.485898 -265.110214)
			(xy 383.532888 -265.262614) (xy 383.794508 -265.262614)
		)
		(stroke
			(width 0)
			(type solid)
		)
		(fill yes)
		(layer "In4.Cu")
		(net "M_G_CPU0_SA_DQS_DN<7>")
	)
	(gr_poly
		(pts
			(xy 384.087116 -229.645972) (xy 384.048762 -229.623874) (xy 383.893314 -229.588314) (xy 383.762504 -229.814882)
			(xy 383.870962 -229.931722) (xy 383.909316 -229.95382)
		)
		(stroke
			(width 0)
			(type solid)
		)
		(fill yes)
		(layer "In4.Cu")
		(net "M_G_CPU0_SB_DQ<23>")
	)
	(gr_poly
		(pts
			(xy 384.087116 -226.390454) (xy 384.048762 -226.368356) (xy 383.893314 -226.332796) (xy 383.762504 -226.559364)
			(xy 383.870962 -226.676204) (xy 383.909316 -226.698302)
		)
		(stroke
			(width 0)
			(type solid)
		)
		(fill yes)
		(layer "In4.Cu")
		(net "M_F_CPU0_SB_DQ<24>")
	)
	(gr_poly
		(pts
			(xy 384.087116 -224.762568) (xy 384.048762 -224.74047) (xy 383.893314 -224.70491) (xy 383.762504 -224.931478)
			(xy 383.870962 -225.048318) (xy 383.909316 -225.070416)
		)
		(stroke
			(width 0)
			(type solid)
		)
		(fill yes)
		(layer "In4.Cu")
		(net "M_F_CPU0_SB_DQ<25>")
	)
	(gr_poly
		(pts
			(xy 384.157474 -223.416622) (xy 384.265932 -223.299782) (xy 384.135122 -223.073214) (xy 383.979674 -223.108774)
			(xy 383.94132 -223.130872) (xy 384.11912 -223.43872)
		)
		(stroke
			(width 0)
			(type solid)
		)
		(fill yes)
		(layer "In4.Cu")
		(net "M_F_CPU0_SB_DQS_DN<8>")
	)
	(gr_poly
		(pts
			(xy 384.157728 -277.984458) (xy 384.196082 -277.96236) (xy 384.018282 -277.654512) (xy 383.979928 -277.67661)
			(xy 383.87147 -277.79345) (xy 384.00228 -278.020018)
		)
		(stroke
			(width 0)
			(type solid)
		)
		(fill yes)
		(layer "In4.Cu")
		(net "M_G_CPU0_SA_DQ<1>")
	)
	(gr_poly
		(pts
			(xy 384.159506 -274.731734) (xy 384.19786 -274.709636) (xy 384.02006 -274.401788) (xy 383.981706 -274.423886)
			(xy 383.873248 -274.540726) (xy 384.004058 -274.767294)
		)
		(stroke
			(width 0)
			(type solid)
		)
		(fill yes)
		(layer "In4.Cu")
		(net "M_G_CPU0_SA_DQ<4>")
	)
	(gr_poly
		(pts
			(xy 384.184398 -236.801914) (xy 384.137408 -236.649514) (xy 383.875788 -236.649514) (xy 383.828798 -236.801914)
			(xy 383.828798 -236.84611) (xy 384.184398 -236.84611)
		)
		(stroke
			(width 0)
			(type solid)
		)
		(fill yes)
		(layer "In4.Cu")
		(net "M_F_CPU0_SB_DQS_DP<5>")
	)
	(gr_poly
		(pts
			(xy 384.184398 -236.39399) (xy 384.184398 -236.34954) (xy 383.828798 -236.34954) (xy 383.828798 -236.39399)
			(xy 383.875788 -236.54639) (xy 384.137408 -236.54639)
		)
		(stroke
			(width 0)
			(type solid)
		)
		(fill yes)
		(layer "In4.Cu")
		(net "M_F_CPU0_SB_DQ<4>")
	)
	(gr_poly
		(pts
			(xy 384.186938 -239.648746) (xy 384.186938 -239.60455) (xy 383.831338 -239.60455) (xy 383.831338 -239.648746)
			(xy 383.878328 -239.801146) (xy 384.139948 -239.801146)
		)
		(stroke
			(width 0)
			(type solid)
		)
		(fill yes)
		(layer "In4.Cu")
		(net "M_F_CPU0_SB_DQ<0>")
	)
	(gr_poly
		(pts
			(xy 384.186938 -234.76585) (xy 384.186938 -234.7214) (xy 383.831338 -234.7214) (xy 383.831338 -234.76585)
			(xy 383.878328 -234.91825) (xy 384.139948 -234.91825)
		)
		(stroke
			(width 0)
			(type solid)
		)
		(fill yes)
		(layer "In4.Cu")
		(net "M_G_CPU0_SB_DQ<16>")
	)
	(gr_poly
		(pts
			(xy 384.186938 -222.15221) (xy 384.139948 -221.99981) (xy 383.878328 -221.99981) (xy 383.831338 -222.15221)
			(xy 383.831338 -222.196406) (xy 384.186938 -222.196406)
		)
		(stroke
			(width 0)
			(type solid)
		)
		(fill yes)
		(layer "In4.Cu")
		(net "M_F_CPU0_SB_DQS_DP<8>")
	)
	(gr_poly
		(pts
			(xy 384.186938 -221.74327) (xy 384.186938 -221.699074) (xy 383.831338 -221.699074) (xy 383.831338 -221.74327)
			(xy 383.878328 -221.89567) (xy 384.139948 -221.89567)
		)
		(stroke
			(width 0)
			(type solid)
		)
		(fill yes)
		(layer "In4.Cu")
		(net "M_F_CPU0_SB_DQS_DP<3>")
	)
	(gr_poly
		(pts
			(xy 384.19278 -240.057686) (xy 384.14579 -239.905286) (xy 383.88417 -239.905286) (xy 383.83718 -240.057686)
			(xy 383.83718 -240.102136) (xy 384.19278 -240.102136)
		)
		(stroke
			(width 0)
			(type solid)
		)
		(fill yes)
		(layer "In4.Cu")
		(net "M_G_CPU0_SB_CB<3>")
	)
	(gr_poly
		(pts
			(xy 384.19278 -235.174282) (xy 384.14579 -235.021882) (xy 383.88417 -235.021882) (xy 383.83718 -235.174282)
			(xy 383.83718 -235.218732) (xy 384.19278 -235.218732)
		)
		(stroke
			(width 0)
			(type solid)
		)
		(fill yes)
		(layer "In4.Cu")
		(net "M_F_CPU0_SB_DQ<7>")
	)
	(gr_poly
		(pts
			(xy 384.19278 -233.138218) (xy 384.19278 -233.093768) (xy 383.83718 -233.093768) (xy 383.83718 -233.138218)
			(xy 383.88417 -233.290618) (xy 384.14579 -233.290618)
		)
		(stroke
			(width 0)
			(type solid)
		)
		(fill yes)
		(layer "In4.Cu")
		(net "M_G_CPU0_SB_DQS_DP<2>")
	)
	(gr_poly
		(pts
			(xy 384.193034 -246.568722) (xy 384.146044 -246.416322) (xy 383.884424 -246.416322) (xy 383.837434 -246.568722)
			(xy 383.837434 -246.613172) (xy 384.193034 -246.613172)
		)
		(stroke
			(width 0)
			(type solid)
		)
		(fill yes)
		(layer "In4.Cu")
		(net "M_G_CPU0_SB_CS_N<0>")
	)
	(gr_poly
		(pts
			(xy 384.193034 -246.16029) (xy 384.193034 -246.11584) (xy 383.837434 -246.11584) (xy 383.837434 -246.16029)
			(xy 383.884424 -246.31269) (xy 384.146044 -246.31269)
		)
		(stroke
			(width 0)
			(type solid)
		)
		(fill yes)
		(layer "In4.Cu")
		(net "M_G_CPU0_SB_CS_N<3>")
	)
	(gr_poly
		(pts
			(xy 384.193034 -244.53215) (xy 384.193034 -244.487954) (xy 383.837434 -244.487954) (xy 383.837434 -244.53215)
			(xy 383.884424 -244.68455) (xy 384.146044 -244.68455)
		)
		(stroke
			(width 0)
			(type solid)
		)
		(fill yes)
		(layer "In4.Cu")
		(net "M_G_CPU0_SB_CB<4>")
	)
	(gr_poly
		(pts
			(xy 384.193034 -243.313458) (xy 384.146044 -243.161058) (xy 383.884424 -243.161058) (xy 383.837434 -243.313458)
			(xy 383.837434 -243.357654) (xy 384.193034 -243.357654)
		)
		(stroke
			(width 0)
			(type solid)
		)
		(fill yes)
		(layer "In4.Cu")
		(net "M_G_CPU0_SB_CB<7>")
	)
	(gr_poly
		(pts
			(xy 384.193034 -242.904518) (xy 384.193034 -242.860322) (xy 383.837434 -242.860322) (xy 383.837434 -242.904518)
			(xy 383.884424 -243.056918) (xy 384.146044 -243.056918)
		)
		(stroke
			(width 0)
			(type solid)
		)
		(fill yes)
		(layer "In4.Cu")
		(net "M_G_CPU0_SB_DQS_DP<9>")
	)
	(gr_poly
		(pts
			(xy 384.193034 -241.685318) (xy 384.146044 -241.532918) (xy 383.884424 -241.532918) (xy 383.837434 -241.685318)
			(xy 383.837434 -241.729768) (xy 384.193034 -241.729768)
		)
		(stroke
			(width 0)
			(type solid)
		)
		(fill yes)
		(layer "In4.Cu")
		(net "M_G_CPU0_SB_DQS_DP<4>")
	)
	(gr_poly
		(pts
			(xy 384.193034 -241.276886) (xy 384.193034 -241.232436) (xy 383.837434 -241.232436) (xy 383.837434 -241.276886)
			(xy 383.884424 -241.429286) (xy 384.146044 -241.429286)
		)
		(stroke
			(width 0)
			(type solid)
		)
		(fill yes)
		(layer "In4.Cu")
		(net "M_G_CPU0_SB_CB<0>")
	)
	(gr_poly
		(pts
			(xy 384.193034 -238.430054) (xy 384.146044 -238.277654) (xy 383.884424 -238.277654) (xy 383.837434 -238.430054)
			(xy 383.837434 -238.47425) (xy 384.193034 -238.47425)
		)
		(stroke
			(width 0)
			(type solid)
		)
		(fill yes)
		(layer "In4.Cu")
		(net "M_F_CPU0_SB_DQ<3>")
	)
	(gr_poly
		(pts
			(xy 384.193034 -238.021114) (xy 384.193034 -237.976918) (xy 383.837434 -237.976918) (xy 383.837434 -238.021114)
			(xy 383.884424 -238.173514) (xy 384.146044 -238.173514)
		)
		(stroke
			(width 0)
			(type solid)
		)
		(fill yes)
		(layer "In4.Cu")
		(net "M_F_CPU0_SB_DQS_DP<0>")
	)
	(gr_poly
		(pts
			(xy 384.193034 -233.54665) (xy 384.146044 -233.39425) (xy 383.884424 -233.39425) (xy 383.837434 -233.54665)
			(xy 383.837434 -233.590846) (xy 384.193034 -233.590846)
		)
		(stroke
			(width 0)
			(type solid)
		)
		(fill yes)
		(layer "In4.Cu")
		(net "M_G_CPU0_SB_DQ<19>")
	)
	(gr_poly
		(pts
			(xy 384.193034 -231.919018) (xy 384.146044 -231.766618) (xy 383.884424 -231.766618) (xy 383.837434 -231.919018)
			(xy 383.837434 -231.963214) (xy 384.193034 -231.963214)
		)
		(stroke
			(width 0)
			(type solid)
		)
		(fill yes)
		(layer "In4.Cu")
		(net "M_G_CPU0_SB_DQS_DP<7>")
	)
	(gr_poly
		(pts
			(xy 384.193034 -231.510078) (xy 384.193034 -231.465882) (xy 383.837434 -231.465882) (xy 383.837434 -231.510078)
			(xy 383.884424 -231.662478) (xy 384.146044 -231.662478)
		)
		(stroke
			(width 0)
			(type solid)
		)
		(fill yes)
		(layer "In4.Cu")
		(net "M_G_CPU0_SB_DQ<20>")
	)
	(gr_poly
		(pts
			(xy 384.193034 -220.115638) (xy 384.193034 -220.071188) (xy 383.837434 -220.071188) (xy 383.837434 -220.115638)
			(xy 383.884424 -220.268038) (xy 384.146044 -220.268038)
		)
		(stroke
			(width 0)
			(type solid)
		)
		(fill yes)
		(layer "In4.Cu")
		(net "M_F_CPU0_SB_DQ<30>")
	)
	(gr_poly
		(pts
			(xy 384.193034 -218.896438) (xy 384.146044 -218.744038) (xy 383.884424 -218.744038) (xy 383.837434 -218.896438)
			(xy 383.837434 -218.940888) (xy 384.193034 -218.940888)
		)
		(stroke
			(width 0)
			(type solid)
		)
		(fill yes)
		(layer "In4.Cu")
		(net "M_F_CPU0_SB_DQ<31>")
	)
	(gr_poly
		(pts
			(xy 384.265932 -225.479102) (xy 384.157474 -225.362262) (xy 384.11912 -225.340164) (xy 383.94132 -225.648012)
			(xy 383.979674 -225.67011) (xy 384.135122 -225.70567)
		)
		(stroke
			(width 0)
			(type solid)
		)
		(fill yes)
		(layer "In4.Cu")
		(net "M_F_CPU0_SB_DQ<27>")
	)
	(gr_poly
		(pts
			(xy 384.267964 -230.358442) (xy 384.159506 -230.241602) (xy 384.121152 -230.219504) (xy 383.943352 -230.527352)
			(xy 383.981706 -230.54945) (xy 384.137154 -230.58501)
		)
		(stroke
			(width 0)
			(type solid)
		)
		(fill yes)
		(layer "In4.Cu")
		(net "M_G_CPU0_SB_DQ<21>")
	)
	(gr_poly
		(pts
			(xy 384.267964 -227.102924) (xy 384.159506 -226.986084) (xy 384.121152 -226.963986) (xy 383.943352 -227.271834)
			(xy 383.981706 -227.293932) (xy 384.137154 -227.329492)
		)
		(stroke
			(width 0)
			(type solid)
		)
		(fill yes)
		(layer "In4.Cu")
		(net "M_F_CPU0_SB_DQ<26>")
	)
	(gr_poly
		(pts
			(xy 384.267964 -223.847406) (xy 384.159506 -223.730566) (xy 384.121152 -223.708468) (xy 383.943352 -224.016316)
			(xy 383.981706 -224.038414) (xy 384.137154 -224.073974)
		)
		(stroke
			(width 0)
			(type solid)
		)
		(fill yes)
		(layer "In4.Cu")
		(net "M_F_CPU0_SB_DQS_DN<8>")
	)
	(gr_poly
		(pts
			(xy 384.269234 -277.367492) (xy 384.377692 -277.250652) (xy 384.246882 -277.024084) (xy 384.091434 -277.059644)
			(xy 384.05308 -277.081742) (xy 384.23088 -277.38959)
		)
		(stroke
			(width 0)
			(type solid)
		)
		(fill yes)
		(layer "In4.Cu")
		(net "M_G_CPU0_SA_DQ<3>")
	)
	(gr_poly
		(pts
			(xy 384.269234 -274.111974) (xy 384.377692 -273.995134) (xy 384.246882 -273.768566) (xy 384.091434 -273.804126)
			(xy 384.05308 -273.826224) (xy 384.23088 -274.134072)
		)
		(stroke
			(width 0)
			(type solid)
		)
		(fill yes)
		(layer "In4.Cu")
		(net "M_G_CPU0_SA_DQ<6>")
	)
	(gr_poly
		(pts
			(xy 384.294126 -259.820918) (xy 384.247136 -259.668518) (xy 383.985516 -259.668518) (xy 383.938526 -259.820918)
			(xy 383.938526 -259.865368) (xy 384.294126 -259.865368)
		)
		(stroke
			(width 0)
			(type solid)
		)
		(fill yes)
		(layer "In4.Cu")
		(net "M_F_CPU0_SA_DQS_DP<8>")
	)
	(gr_poly
		(pts
			(xy 384.294126 -259.412994) (xy 384.294126 -259.368544) (xy 383.938526 -259.368544) (xy 383.938526 -259.412994)
			(xy 383.985516 -259.565394) (xy 384.247136 -259.565394)
		)
		(stroke
			(width 0)
			(type solid)
		)
		(fill yes)
		(layer "In4.Cu")
		(net "M_F_CPU0_SA_DQ<28>")
	)
	(gr_poly
		(pts
			(xy 384.29438 -275.690584) (xy 384.29438 -275.646388) (xy 383.93878 -275.646388) (xy 383.93878 -275.690584)
			(xy 383.98577 -275.842984) (xy 384.24739 -275.842984)
		)
		(stroke
			(width 0)
			(type solid)
		)
		(fill yes)
		(layer "In4.Cu")
		(net "M_G_CPU0_SA_DQS_DN<5>")
	)
	(gr_poly
		(pts
			(xy 384.29438 -272.435066) (xy 384.29438 -272.39087) (xy 383.93878 -272.39087) (xy 383.93878 -272.435066)
			(xy 383.98577 -272.587466) (xy 384.24739 -272.587466)
		)
		(stroke
			(width 0)
			(type solid)
		)
		(fill yes)
		(layer "In4.Cu")
		(net "M_F_CPU0_SA_DQ<8>")
	)
	(gr_poly
		(pts
			(xy 384.29438 -271.215358) (xy 384.24739 -271.062958) (xy 383.98577 -271.062958) (xy 383.93878 -271.215358)
			(xy 383.93878 -271.259808) (xy 384.29438 -271.259808)
		)
		(stroke
			(width 0)
			(type solid)
		)
		(fill yes)
		(layer "In4.Cu")
		(net "M_F_CPU0_SA_DQ<11>")
	)
	(gr_poly
		(pts
			(xy 384.29438 -270.807434) (xy 384.29438 -270.762984) (xy 383.93878 -270.762984) (xy 383.93878 -270.807434)
			(xy 383.98577 -270.959834) (xy 384.24739 -270.959834)
		)
		(stroke
			(width 0)
			(type solid)
		)
		(fill yes)
		(layer "In4.Cu")
		(net "M_F_CPU0_SA_DQS_DP<1>")
	)
	(gr_poly
		(pts
			(xy 384.29438 -269.587726) (xy 384.24739 -269.435326) (xy 383.98577 -269.435326) (xy 383.93878 -269.587726)
			(xy 383.93878 -269.631922) (xy 384.29438 -269.631922)
		)
		(stroke
			(width 0)
			(type solid)
		)
		(fill yes)
		(layer "In4.Cu")
		(net "M_F_CPU0_SA_DQS_DP<6>")
	)
	(gr_poly
		(pts
			(xy 384.29438 -265.92403) (xy 384.29438 -265.879834) (xy 383.93878 -265.879834) (xy 383.93878 -265.92403)
			(xy 383.98577 -266.07643) (xy 384.24739 -266.07643)
		)
		(stroke
			(width 0)
			(type solid)
		)
		(fill yes)
		(layer "In4.Cu")
		(net "M_G_CPU0_SA_DQS_DP<2>")
	)
	(gr_poly
		(pts
			(xy 384.29438 -264.704322) (xy 384.24739 -264.551922) (xy 383.98577 -264.551922) (xy 383.93878 -264.704322)
			(xy 383.93878 -264.748772) (xy 384.29438 -264.748772)
		)
		(stroke
			(width 0)
			(type solid)
		)
		(fill yes)
		(layer "In4.Cu")
		(net "M_G_CPU0_SA_DQS_DP<7>")
	)
	(gr_poly
		(pts
			(xy 384.296666 -261.449058) (xy 384.249676 -261.296658) (xy 383.988056 -261.296658) (xy 383.941066 -261.449058)
			(xy 383.941066 -261.493508) (xy 384.296666 -261.493508)
		)
		(stroke
			(width 0)
			(type solid)
		)
		(fill yes)
		(layer "In4.Cu")
		(net "M_F_CPU0_SA_DQ<27>")
	)
	(gr_poly
		(pts
			(xy 384.296666 -261.040626) (xy 384.296666 -260.996176) (xy 383.941066 -260.996176) (xy 383.941066 -261.040626)
			(xy 383.988056 -261.193026) (xy 384.249676 -261.193026)
		)
		(stroke
			(width 0)
			(type solid)
		)
		(fill yes)
		(layer "In4.Cu")
		(net "M_F_CPU0_SA_DQS_DP<3>")
	)
	(gr_poly
		(pts
			(xy 384.302762 -279.354788) (xy 384.255772 -279.202388) (xy 383.994152 -279.202388) (xy 383.947162 -279.354788)
			(xy 383.947162 -279.398984) (xy 384.302762 -279.398984)
		)
		(stroke
			(width 0)
			(type solid)
		)
		(fill yes)
		(layer "In4.Cu")
		(net "M_G_CPU0_SA_DQ<2>")
	)
	(gr_poly
		(pts
			(xy 384.302762 -276.09927) (xy 384.255772 -275.94687) (xy 383.994152 -275.94687) (xy 383.947162 -276.09927)
			(xy 383.947162 -276.143466) (xy 384.302762 -276.143466)
		)
		(stroke
			(width 0)
			(type solid)
		)
		(fill yes)
		(layer "In4.Cu")
		(net "M_G_CPU0_SA_DQS_DN<0>")
	)
	(gr_poly
		(pts
			(xy 384.302762 -272.843498) (xy 384.255772 -272.691098) (xy 383.994152 -272.691098) (xy 383.947162 -272.843498)
			(xy 383.947162 -272.887948) (xy 384.302762 -272.887948)
		)
		(stroke
			(width 0)
			(type solid)
		)
		(fill yes)
		(layer "In4.Cu")
		(net "M_G_CPU0_SA_DQ<7>")
	)
	(gr_poly
		(pts
			(xy 384.302762 -269.179294) (xy 384.302762 -269.134844) (xy 383.947162 -269.134844) (xy 383.947162 -269.179294)
			(xy 383.994152 -269.331694) (xy 384.255772 -269.331694)
		)
		(stroke
			(width 0)
			(type solid)
		)
		(fill yes)
		(layer "In4.Cu")
		(net "M_F_CPU0_SA_DQ<12>")
	)
	(gr_poly
		(pts
			(xy 384.302762 -267.960094) (xy 384.255772 -267.807694) (xy 383.994152 -267.807694) (xy 383.947162 -267.960094)
			(xy 383.947162 -268.004544) (xy 384.302762 -268.004544)
		)
		(stroke
			(width 0)
			(type solid)
		)
		(fill yes)
		(layer "In4.Cu")
		(net "M_F_CPU0_SA_DQ<13>")
	)
	(gr_poly
		(pts
			(xy 384.302762 -266.332462) (xy 384.255772 -266.180062) (xy 383.994152 -266.180062) (xy 383.947162 -266.332462)
			(xy 383.947162 -266.376658) (xy 384.302762 -266.376658)
		)
		(stroke
			(width 0)
			(type solid)
		)
		(fill yes)
		(layer "In4.Cu")
		(net "M_G_CPU0_SA_DQ<19>")
	)
	(gr_poly
		(pts
			(xy 384.302762 -264.29589) (xy 384.302762 -264.251694) (xy 383.947162 -264.251694) (xy 383.947162 -264.29589)
			(xy 383.994152 -264.44829) (xy 384.255772 -264.44829)
		)
		(stroke
			(width 0)
			(type solid)
		)
		(fill yes)
		(layer "In4.Cu")
		(net "M_G_CPU0_SA_DQ<20>")
	)
	(gr_poly
		(pts
			(xy 384.302762 -262.668258) (xy 384.302762 -262.623808) (xy 383.947162 -262.623808) (xy 383.947162 -262.668258)
			(xy 383.994152 -262.820658) (xy 384.255772 -262.820658)
		)
		(stroke
			(width 0)
			(type solid)
		)
		(fill yes)
		(layer "In4.Cu")
		(net "M_F_CPU0_SA_DQ<24>")
	)
	(gr_poly
		(pts
			(xy 384.305048 -263.07669) (xy 384.258058 -262.92429) (xy 383.996438 -262.92429) (xy 383.949448 -263.07669)
			(xy 383.949448 -263.12114) (xy 384.305048 -263.12114)
		)
		(stroke
			(width 0)
			(type solid)
		)
		(fill yes)
		(layer "In4.Cu")
		(net "M_G_CPU0_SA_DQ<23>")
	)
	(gr_poly
		(pts
			(xy 384.306064 -267.551154) (xy 384.306064 -267.506958) (xy 383.950464 -267.506958) (xy 383.950464 -267.551154)
			(xy 383.997454 -267.703554) (xy 384.259074 -267.703554)
		)
		(stroke
			(width 0)
			(type solid)
		)
		(fill yes)
		(layer "In4.Cu")
		(net "M_G_CPU0_SA_DQ<16>")
	)
	(gr_poly
		(pts
			(xy 384.308858 -258.193286) (xy 384.261868 -258.040886) (xy 384.000248 -258.040886) (xy 383.953258 -258.193286)
			(xy 383.953258 -258.237482) (xy 384.308858 -258.237482)
		)
		(stroke
			(width 0)
			(type solid)
		)
		(fill yes)
		(layer "In4.Cu")
		(net "M_F_CPU0_SA_DQ<31>")
	)
	(gr_poly
		(pts
			(xy 384.308858 -257.784854) (xy 384.308858 -257.740658) (xy 383.953258 -257.740658) (xy 383.953258 -257.784854)
			(xy 384.000248 -257.937254) (xy 384.261868 -257.937254)
		)
		(stroke
			(width 0)
			(type solid)
		)
		(fill yes)
		(layer "In4.Cu")
		(net "M_G_CPU0_SA_CS_N<0>")
	)
	(gr_poly
		(pts
			(xy 384.552444 -228.839268) (xy 384.51409 -228.81717) (xy 384.358642 -228.78161) (xy 384.227832 -229.008178)
			(xy 384.33629 -229.125018) (xy 384.374644 -229.147116)
		)
		(stroke
			(width 0)
			(type solid)
		)
		(fill yes)
		(layer "In4.Cu")
		(net "M_G_CPU0_SB_DQ<23>")
	)
	(gr_poly
		(pts
			(xy 384.557016 -230.459788) (xy 384.518662 -230.43769) (xy 384.363214 -230.40213) (xy 384.232404 -230.628698)
			(xy 384.340862 -230.745538) (xy 384.379216 -230.767636)
		)
		(stroke
			(width 0)
			(type solid)
		)
		(fill yes)
		(layer "In4.Cu")
		(net "M_G_CPU0_SB_DQ<22>")
	)
	(gr_poly
		(pts
			(xy 384.557778 -225.574606) (xy 384.519424 -225.552508) (xy 384.363976 -225.516948) (xy 384.233166 -225.743516)
			(xy 384.341624 -225.860356) (xy 384.379978 -225.882454)
		)
		(stroke
			(width 0)
			(type solid)
		)
		(fill yes)
		(layer "In4.Cu")
		(net "M_F_CPU0_SB_DQ<24>")
	)
	(gr_poly
		(pts
			(xy 384.558032 -223.946212) (xy 384.519678 -223.924114) (xy 384.36423 -223.888554) (xy 384.23342 -224.115122)
			(xy 384.341878 -224.231962) (xy 384.380232 -224.25406)
		)
		(stroke
			(width 0)
			(type solid)
		)
		(fill yes)
		(layer "In4.Cu")
		(net "M_F_CPU0_SB_DQ<25>")
	)
	(gr_poly
		(pts
			(xy 384.559048 -220.68917) (xy 384.520694 -220.667072) (xy 384.365246 -220.631512) (xy 384.234436 -220.85808)
			(xy 384.342894 -220.97492) (xy 384.381248 -220.997018)
		)
		(stroke
			(width 0)
			(type solid)
		)
		(fill yes)
		(layer "In4.Cu")
		(net "M_F_CPU0_SB_DQS_DN<3>")
	)
	(gr_poly
		(pts
			(xy 384.62585 -278.795226) (xy 384.664204 -278.773128) (xy 384.486404 -278.46528) (xy 384.44805 -278.487378)
			(xy 384.339592 -278.604218) (xy 384.470402 -278.830786)
		)
		(stroke
			(width 0)
			(type solid)
		)
		(fill yes)
		(layer "In4.Cu")
		(net "M_G_CPU0_SA_DQ<1>")
	)
	(gr_poly
		(pts
			(xy 384.62839 -277.171404) (xy 384.666744 -277.149306) (xy 384.488944 -276.841458) (xy 384.45059 -276.863556)
			(xy 384.342132 -276.980396) (xy 384.472942 -277.206964)
		)
		(stroke
			(width 0)
			(type solid)
		)
		(fill yes)
		(layer "In4.Cu")
		(net "M_G_CPU0_SA_DQS_DP<0>")
	)
	(gr_poly
		(pts
			(xy 384.62839 -273.915886) (xy 384.666744 -273.893788) (xy 384.488944 -273.58594) (xy 384.45059 -273.608038)
			(xy 384.342132 -273.724878) (xy 384.472942 -273.951446)
		)
		(stroke
			(width 0)
			(type solid)
		)
		(fill yes)
		(layer "In4.Cu")
		(net "M_G_CPU0_SA_DQ<5>")
	)
	(gr_poly
		(pts
			(xy 384.656838 -219.710254) (xy 384.609848 -219.557854) (xy 384.348228 -219.557854) (xy 384.301238 -219.710254)
			(xy 384.301238 -219.754704) (xy 384.656838 -219.754704)
		)
		(stroke
			(width 0)
			(type solid)
		)
		(fill yes)
		(layer "In4.Cu")
		(net "M_F_CPU0_SB_DQ<28>")
	)
	(gr_poly
		(pts
			(xy 384.656838 -219.301822) (xy 384.656838 -219.257372) (xy 384.301238 -219.257372) (xy 384.301238 -219.301822)
			(xy 384.348228 -219.454222) (xy 384.609848 -219.454222)
		)
		(stroke
			(width 0)
			(type solid)
		)
		(fill yes)
		(layer "In4.Cu")
		(net "M_F_CPU0_SB_DQ<29>")
	)
	(gr_poly
		(pts
			(xy 384.662934 -246.974106) (xy 384.662934 -246.929656) (xy 384.307334 -246.929656) (xy 384.307334 -246.974106)
			(xy 384.354324 -247.126506) (xy 384.615944 -247.126506)
		)
		(stroke
			(width 0)
			(type solid)
		)
		(fill yes)
		(layer "In4.Cu")
		(net "M_G_CPU0_SB_CS_N<2>")
	)
	(gr_poly
		(pts
			(xy 384.662934 -244.127274) (xy 384.615944 -243.974874) (xy 384.354324 -243.974874) (xy 384.307334 -244.127274)
			(xy 384.307334 -244.17147) (xy 384.662934 -244.17147)
		)
		(stroke
			(width 0)
			(type solid)
		)
		(fill yes)
		(layer "In4.Cu")
		(net "M_G_CPU0_SB_CB<6>")
	)
	(gr_poly
		(pts
			(xy 384.662934 -243.718334) (xy 384.662934 -243.674138) (xy 384.307334 -243.674138) (xy 384.307334 -243.718334)
			(xy 384.354324 -243.870734) (xy 384.615944 -243.870734)
		)
		(stroke
			(width 0)
			(type solid)
		)
		(fill yes)
		(layer "In4.Cu")
		(net "M_G_CPU0_SB_CB<5>")
	)
	(gr_poly
		(pts
			(xy 384.662934 -242.499134) (xy 384.615944 -242.346734) (xy 384.354324 -242.346734) (xy 384.307334 -242.499134)
			(xy 384.307334 -242.543584) (xy 384.662934 -242.543584)
		)
		(stroke
			(width 0)
			(type solid)
		)
		(fill yes)
		(layer "In4.Cu")
		(net "M_G_CPU0_SB_DQS_DN<9>")
	)
	(gr_poly
		(pts
			(xy 384.662934 -242.090702) (xy 384.662934 -242.046252) (xy 384.307334 -242.046252) (xy 384.307334 -242.090702)
			(xy 384.354324 -242.243102) (xy 384.615944 -242.243102)
		)
		(stroke
			(width 0)
			(type solid)
		)
		(fill yes)
		(layer "In4.Cu")
		(net "M_G_CPU0_SB_DQS_DN<4>")
	)
	(gr_poly
		(pts
			(xy 384.662934 -240.871502) (xy 384.615944 -240.719102) (xy 384.354324 -240.719102) (xy 384.307334 -240.871502)
			(xy 384.307334 -240.915952) (xy 384.662934 -240.915952)
		)
		(stroke
			(width 0)
			(type solid)
		)
		(fill yes)
		(layer "In4.Cu")
		(net "M_G_CPU0_SB_CB<2>")
	)
	(gr_poly
		(pts
			(xy 384.662934 -238.83493) (xy 384.662934 -238.790734) (xy 384.307334 -238.790734) (xy 384.307334 -238.83493)
			(xy 384.354324 -238.98733) (xy 384.615944 -238.98733)
		)
		(stroke
			(width 0)
			(type solid)
		)
		(fill yes)
		(layer "In4.Cu")
		(net "M_F_CPU0_SB_DQ<1>")
	)
	(gr_poly
		(pts
			(xy 384.662934 -237.61573) (xy 384.615944 -237.46333) (xy 384.354324 -237.46333) (xy 384.307334 -237.61573)
			(xy 384.307334 -237.66018) (xy 384.662934 -237.66018)
		)
		(stroke
			(width 0)
			(type solid)
		)
		(fill yes)
		(layer "In4.Cu")
		(net "M_F_CPU0_SB_DQS_DN<0>")
	)
	(gr_poly
		(pts
			(xy 384.662934 -233.952034) (xy 384.662934 -233.907584) (xy 384.307334 -233.907584) (xy 384.307334 -233.952034)
			(xy 384.354324 -234.104434) (xy 384.615944 -234.104434)
		)
		(stroke
			(width 0)
			(type solid)
		)
		(fill yes)
		(layer "In4.Cu")
		(net "M_G_CPU0_SB_DQ<17>")
	)
	(gr_poly
		(pts
			(xy 384.662934 -232.732834) (xy 384.615944 -232.580434) (xy 384.354324 -232.580434) (xy 384.307334 -232.732834)
			(xy 384.307334 -232.77703) (xy 384.662934 -232.77703)
		)
		(stroke
			(width 0)
			(type solid)
		)
		(fill yes)
		(layer "In4.Cu")
		(net "M_G_CPU0_SB_DQS_DN<2>")
	)
	(gr_poly
		(pts
			(xy 384.662934 -232.323894) (xy 384.662934 -232.279698) (xy 384.307334 -232.279698) (xy 384.307334 -232.323894)
			(xy 384.354324 -232.476294) (xy 384.615944 -232.476294)
		)
		(stroke
			(width 0)
			(type solid)
		)
		(fill yes)
		(layer "In4.Cu")
		(net "M_G_CPU0_SB_DQS_DN<7>")
	)
	(gr_poly
		(pts
			(xy 384.668776 -222.557086) (xy 384.668776 -222.51289) (xy 384.313176 -222.51289) (xy 384.313176 -222.557086)
			(xy 384.360166 -222.709486) (xy 384.621786 -222.709486)
		)
		(stroke
			(width 0)
			(type solid)
		)
		(fill yes)
		(layer "In4.Cu")
		(net "M_F_CPU0_SB_DQS_DN<8>")
	)
	(gr_poly
		(pts
			(xy 384.671316 -240.46307) (xy 384.671316 -240.418874) (xy 384.315716 -240.418874) (xy 384.315716 -240.46307)
			(xy 384.362706 -240.61547) (xy 384.624326 -240.61547)
		)
		(stroke
			(width 0)
			(type solid)
		)
		(fill yes)
		(layer "In4.Cu")
		(net "M_G_CPU0_SB_CB<1>")
	)
	(gr_poly
		(pts
			(xy 384.671316 -239.243362) (xy 384.624326 -239.090962) (xy 384.362706 -239.090962) (xy 384.315716 -239.243362)
			(xy 384.315716 -239.287812) (xy 384.671316 -239.287812)
		)
		(stroke
			(width 0)
			(type solid)
		)
		(fill yes)
		(layer "In4.Cu")
		(net "M_F_CPU0_SB_DQ<2>")
	)
	(gr_poly
		(pts
			(xy 384.671316 -237.207806) (xy 384.671316 -237.163356) (xy 384.315716 -237.163356) (xy 384.315716 -237.207806)
			(xy 384.362706 -237.360206) (xy 384.624326 -237.360206)
		)
		(stroke
			(width 0)
			(type solid)
		)
		(fill yes)
		(layer "In4.Cu")
		(net "M_F_CPU0_SB_DQS_DN<5>")
	)
	(gr_poly
		(pts
			(xy 384.671316 -235.988098) (xy 384.624326 -235.835698) (xy 384.362706 -235.835698) (xy 384.315716 -235.988098)
			(xy 384.315716 -236.032294) (xy 384.671316 -236.032294)
		)
		(stroke
			(width 0)
			(type solid)
		)
		(fill yes)
		(layer "In4.Cu")
		(net "M_F_CPU0_SB_DQ<6>")
	)
	(gr_poly
		(pts
			(xy 384.671316 -235.579666) (xy 384.671316 -235.53547) (xy 384.315716 -235.53547) (xy 384.315716 -235.579666)
			(xy 384.362706 -235.732066) (xy 384.624326 -235.732066)
		)
		(stroke
			(width 0)
			(type solid)
		)
		(fill yes)
		(layer "In4.Cu")
		(net "M_F_CPU0_SB_DQ<5>")
	)
	(gr_poly
		(pts
			(xy 384.671316 -234.360466) (xy 384.624326 -234.208066) (xy 384.362706 -234.208066) (xy 384.315716 -234.360466)
			(xy 384.315716 -234.404662) (xy 384.671316 -234.404662)
		)
		(stroke
			(width 0)
			(type solid)
		)
		(fill yes)
		(layer "In4.Cu")
		(net "M_G_CPU0_SB_DQ<18>")
	)
	(gr_poly
		(pts
			(xy 384.735832 -231.176322) (xy 384.627374 -231.059482) (xy 384.58902 -231.037384) (xy 384.41122 -231.345232)
			(xy 384.449574 -231.36733) (xy 384.605022 -231.40289)
		)
		(stroke
			(width 0)
			(type solid)
		)
		(fill yes)
		(layer "In4.Cu")
		(net "M_G_CPU0_SB_DQ<20>")
	)
	(gr_poly
		(pts
			(xy 384.737102 -278.177498) (xy 384.84556 -278.060658) (xy 384.71475 -277.83409) (xy 384.559302 -277.86965)
			(xy 384.520948 -277.891748) (xy 384.698748 -278.199596)
		)
		(stroke
			(width 0)
			(type solid)
		)
		(fill yes)
		(layer "In4.Cu")
		(net "M_G_CPU0_SA_DQ<3>")
	)
	(gr_poly
		(pts
			(xy 384.737864 -229.544626) (xy 384.629406 -229.427786) (xy 384.591052 -229.405688) (xy 384.413252 -229.713536)
			(xy 384.451606 -229.735634) (xy 384.607054 -229.771194)
		)
		(stroke
			(width 0)
			(type solid)
		)
		(fill yes)
		(layer "In4.Cu")
		(net "M_G_CPU0_SB_DQ<21>")
	)
	(gr_poly
		(pts
			(xy 384.737864 -226.289108) (xy 384.629406 -226.172268) (xy 384.591052 -226.15017) (xy 384.413252 -226.458018)
			(xy 384.451606 -226.480116) (xy 384.607054 -226.515676)
		)
		(stroke
			(width 0)
			(type solid)
		)
		(fill yes)
		(layer "In4.Cu")
		(net "M_F_CPU0_SB_DQ<26>")
	)
	(gr_poly
		(pts
			(xy 384.737864 -224.661222) (xy 384.629406 -224.544382) (xy 384.591052 -224.522284) (xy 384.413252 -224.830132)
			(xy 384.451606 -224.85223) (xy 384.607054 -224.88779)
		)
		(stroke
			(width 0)
			(type solid)
		)
		(fill yes)
		(layer "In4.Cu")
		(net "M_F_CPU0_SB_DQ<27>")
	)
	(gr_poly
		(pts
			(xy 384.739134 -276.553676) (xy 384.847592 -276.436836) (xy 384.716782 -276.210268) (xy 384.561334 -276.245828)
			(xy 384.52298 -276.267926) (xy 384.70078 -276.575774)
		)
		(stroke
			(width 0)
			(type solid)
		)
		(fill yes)
		(layer "In4.Cu")
		(net "M_G_CPU0_SA_DQS_DN<0>")
	)
	(gr_poly
		(pts
			(xy 384.739134 -273.298158) (xy 384.847592 -273.181318) (xy 384.716782 -272.95475) (xy 384.561334 -272.99031)
			(xy 384.52298 -273.012408) (xy 384.70078 -273.320256)
		)
		(stroke
			(width 0)
			(type solid)
		)
		(fill yes)
		(layer "In4.Cu")
		(net "M_G_CPU0_SA_DQ<7>")
	)
	(gr_poly
		(pts
			(xy 384.742182 -221.398592) (xy 384.633724 -221.281752) (xy 384.59537 -221.259654) (xy 384.41757 -221.567502)
			(xy 384.455924 -221.5896) (xy 384.611372 -221.62516)
		)
		(stroke
			(width 0)
			(type solid)
		)
		(fill yes)
		(layer "In4.Cu")
		(net "M_F_CPU0_SB_DQS_DP<3>")
	)
	(gr_poly
		(pts
			(xy 384.76428 -258.599178) (xy 384.76428 -258.554728) (xy 384.40868 -258.554728) (xy 384.40868 -258.599178)
			(xy 384.45567 -258.751578) (xy 384.71729 -258.751578)
		)
		(stroke
			(width 0)
			(type solid)
		)
		(fill yes)
		(layer "In4.Cu")
		(net "M_F_CPU0_SA_DQ<29>")
	)
	(gr_poly
		(pts
			(xy 384.772662 -279.759664) (xy 384.772662 -279.715468) (xy 384.417062 -279.715468) (xy 384.417062 -279.759664)
			(xy 384.464052 -279.912064) (xy 384.725672 -279.912064)
		)
		(stroke
			(width 0)
			(type solid)
		)
		(fill yes)
		(layer "In4.Cu")
		(net "M_G_CPU0_SA_DQ<0>")
	)
	(gr_poly
		(pts
			(xy 384.772662 -268.77391) (xy 384.725672 -268.62151) (xy 384.464052 -268.62151) (xy 384.417062 -268.77391)
			(xy 384.417062 -268.81836) (xy 384.772662 -268.81836)
		)
		(stroke
			(width 0)
			(type solid)
		)
		(fill yes)
		(layer "In4.Cu")
		(net "M_F_CPU0_SA_DQ<14>")
	)
	(gr_poly
		(pts
			(xy 384.772662 -268.365478) (xy 384.772662 -268.321028) (xy 384.417062 -268.321028) (xy 384.417062 -268.365478)
			(xy 384.464052 -268.517878) (xy 384.725672 -268.517878)
		)
		(stroke
			(width 0)
			(type solid)
		)
		(fill yes)
		(layer "In4.Cu")
		(net "M_F_CPU0_SA_DQ<15>")
	)
	(gr_poly
		(pts
			(xy 384.772662 -267.146278) (xy 384.725672 -266.993878) (xy 384.464052 -266.993878) (xy 384.417062 -267.146278)
			(xy 384.417062 -267.190474) (xy 384.772662 -267.190474)
		)
		(stroke
			(width 0)
			(type solid)
		)
		(fill yes)
		(layer "In4.Cu")
		(net "M_G_CPU0_SA_DQ<18>")
	)
	(gr_poly
		(pts
			(xy 384.772662 -266.737846) (xy 384.772662 -266.693396) (xy 384.417062 -266.693396) (xy 384.417062 -266.737846)
			(xy 384.464052 -266.890246) (xy 384.725672 -266.890246)
		)
		(stroke
			(width 0)
			(type solid)
		)
		(fill yes)
		(layer "In4.Cu")
		(net "M_G_CPU0_SA_DQ<17>")
	)
	(gr_poly
		(pts
			(xy 384.772662 -263.891014) (xy 384.725672 -263.738614) (xy 384.464052 -263.738614) (xy 384.417062 -263.891014)
			(xy 384.417062 -263.93521) (xy 384.772662 -263.93521)
		)
		(stroke
			(width 0)
			(type solid)
		)
		(fill yes)
		(layer "In4.Cu")
		(net "M_G_CPU0_SA_DQ<22>")
	)
	(gr_poly
		(pts
			(xy 384.772662 -263.482074) (xy 384.772662 -263.437878) (xy 384.417062 -263.437878) (xy 384.417062 -263.482074)
			(xy 384.464052 -263.634474) (xy 384.725672 -263.634474)
		)
		(stroke
			(width 0)
			(type solid)
		)
		(fill yes)
		(layer "In4.Cu")
		(net "M_G_CPU0_SA_DQ<21>")
	)
	(gr_poly
		(pts
			(xy 384.772662 -262.262874) (xy 384.725672 -262.110474) (xy 384.464052 -262.110474) (xy 384.417062 -262.262874)
			(xy 384.417062 -262.307324) (xy 384.772662 -262.307324)
		)
		(stroke
			(width 0)
			(type solid)
		)
		(fill yes)
		(layer "In4.Cu")
		(net "M_F_CPU0_SA_DQ<26>")
	)
	(gr_poly
		(pts
			(xy 384.778504 -261.854442) (xy 384.778504 -261.809992) (xy 384.422904 -261.809992) (xy 384.422904 -261.854442)
			(xy 384.469894 -262.006842) (xy 384.731514 -262.006842)
		)
		(stroke
			(width 0)
			(type solid)
		)
		(fill yes)
		(layer "In4.Cu")
		(net "M_F_CPU0_SA_DQ<25>")
	)
	(gr_poly
		(pts
			(xy 384.778504 -260.635242) (xy 384.731514 -260.482842) (xy 384.469894 -260.482842) (xy 384.422904 -260.635242)
			(xy 384.422904 -260.679438) (xy 384.778504 -260.679438)
		)
		(stroke
			(width 0)
			(type solid)
		)
		(fill yes)
		(layer "In4.Cu")
		(net "M_F_CPU0_SA_DQS_DN<3>")
	)
	(gr_poly
		(pts
			(xy 384.78079 -260.22681) (xy 384.78079 -260.18236) (xy 384.42519 -260.18236) (xy 384.42519 -260.22681)
			(xy 384.47218 -260.37921) (xy 384.7338 -260.37921)
		)
		(stroke
			(width 0)
			(type solid)
		)
		(fill yes)
		(layer "In4.Cu")
		(net "M_F_CPU0_SA_DQS_DN<8>")
	)
	(gr_poly
		(pts
			(xy 384.78079 -259.007102) (xy 384.7338 -258.854702) (xy 384.47218 -258.854702) (xy 384.42519 -259.007102)
			(xy 384.42519 -259.051552) (xy 384.78079 -259.051552)
		)
		(stroke
			(width 0)
			(type solid)
		)
		(fill yes)
		(layer "In4.Cu")
		(net "M_F_CPU0_SA_DQ<30>")
	)
	(gr_poly
		(pts
			(xy 384.781298 -275.284946) (xy 384.734308 -275.132546) (xy 384.472688 -275.132546) (xy 384.425698 -275.284946)
			(xy 384.425698 -275.329396) (xy 384.781298 -275.329396)
		)
		(stroke
			(width 0)
			(type solid)
		)
		(fill yes)
		(layer "In4.Cu")
		(net "M_G_CPU0_SA_DQS_DP<5>")
	)
	(gr_poly
		(pts
			(xy 384.781298 -274.876768) (xy 384.781298 -274.832572) (xy 384.425698 -274.832572) (xy 384.425698 -274.876768)
			(xy 384.472688 -275.029168) (xy 384.734308 -275.029168)
		)
		(stroke
			(width 0)
			(type solid)
		)
		(fill yes)
		(layer "In4.Cu")
		(net "M_G_CPU0_SA_DQ<4>")
	)
	(gr_poly
		(pts
			(xy 384.781298 -272.029174) (xy 384.734308 -271.876774) (xy 384.472688 -271.876774) (xy 384.425698 -272.029174)
			(xy 384.425698 -272.073624) (xy 384.781298 -272.073624)
		)
		(stroke
			(width 0)
			(type solid)
		)
		(fill yes)
		(layer "In4.Cu")
		(net "M_F_CPU0_SA_DQ<10>")
	)
	(gr_poly
		(pts
			(xy 384.781298 -271.62125) (xy 384.781298 -271.5768) (xy 384.425698 -271.5768) (xy 384.425698 -271.62125)
			(xy 384.472688 -271.77365) (xy 384.734308 -271.77365)
		)
		(stroke
			(width 0)
			(type solid)
		)
		(fill yes)
		(layer "In4.Cu")
		(net "M_F_CPU0_SA_DQ<9>")
	)
	(gr_poly
		(pts
			(xy 384.781298 -270.401542) (xy 384.734308 -270.249142) (xy 384.472688 -270.249142) (xy 384.425698 -270.401542)
			(xy 384.425698 -270.445992) (xy 384.781298 -270.445992)
		)
		(stroke
			(width 0)
			(type solid)
		)
		(fill yes)
		(layer "In4.Cu")
		(net "M_F_CPU0_SA_DQS_DN<1>")
	)
	(gr_poly
		(pts
			(xy 384.781298 -269.993618) (xy 384.781298 -269.949168) (xy 384.425698 -269.949168) (xy 384.425698 -269.993618)
			(xy 384.472688 -270.146018) (xy 384.734308 -270.146018)
		)
		(stroke
			(width 0)
			(type solid)
		)
		(fill yes)
		(layer "In4.Cu")
		(net "M_F_CPU0_SA_DQS_DN<6>")
	)
	(gr_poly
		(pts
			(xy 384.781298 -265.518138) (xy 384.734308 -265.365738) (xy 384.472688 -265.365738) (xy 384.425698 -265.518138)
			(xy 384.425698 -265.562588) (xy 384.781298 -265.562588)
		)
		(stroke
			(width 0)
			(type solid)
		)
		(fill yes)
		(layer "In4.Cu")
		(net "M_G_CPU0_SA_DQS_DN<2>")
	)
	(gr_poly
		(pts
			(xy 384.781298 -265.110214) (xy 384.781298 -265.065764) (xy 384.425698 -265.065764) (xy 384.425698 -265.110214)
			(xy 384.472688 -265.262614) (xy 384.734308 -265.262614)
		)
		(stroke
			(width 0)
			(type solid)
		)
		(fill yes)
		(layer "In4.Cu")
		(net "M_G_CPU0_SA_DQS_DN<7>")
	)
	(gr_poly
		(pts
			(xy 385.020566 -221.51721) (xy 384.982212 -221.495112) (xy 384.826764 -221.459552) (xy 384.695954 -221.68612)
			(xy 384.804412 -221.80296) (xy 384.842766 -221.825058)
		)
		(stroke
			(width 0)
			(type solid)
		)
		(fill yes)
		(layer "In4.Cu")
		(net "M_F_CPU0_SB_DQS_DP<8>")
	)
	(gr_poly
		(pts
			(xy 385.026916 -224.762568) (xy 384.988562 -224.74047) (xy 384.833114 -224.70491) (xy 384.702304 -224.931478)
			(xy 384.810762 -225.048318) (xy 384.849116 -225.070416)
		)
		(stroke
			(width 0)
			(type solid)
		)
		(fill yes)
		(layer "In4.Cu")
		(net "M_F_CPU0_SB_DQ<24>")
	)
	(gr_poly
		(pts
			(xy 385.027678 -228.015546) (xy 384.989324 -227.993448) (xy 384.833876 -227.957888) (xy 384.703066 -228.184456)
			(xy 384.811524 -228.301296) (xy 384.849878 -228.323394)
		)
		(stroke
			(width 0)
			(type solid)
		)
		(fill yes)
		(layer "In4.Cu")
		(net "M_G_CPU0_SB_DQ<23>")
	)
	(gr_poly
		(pts
			(xy 385.027678 -223.132904) (xy 384.989324 -223.110806) (xy 384.833876 -223.075246) (xy 384.703066 -223.301814)
			(xy 384.811524 -223.418654) (xy 384.849878 -223.440752)
		)
		(stroke
			(width 0)
			(type solid)
		)
		(fill yes)
		(layer "In4.Cu")
		(net "M_F_CPU0_SB_DQ<25>")
	)
	(gr_poly
		(pts
			(xy 385.027932 -229.643432) (xy 384.989578 -229.621334) (xy 384.83413 -229.585774) (xy 384.70332 -229.812342)
			(xy 384.811778 -229.929182) (xy 384.850132 -229.95128)
		)
		(stroke
			(width 0)
			(type solid)
		)
		(fill yes)
		(layer "In4.Cu")
		(net "M_G_CPU0_SB_DQ<22>")
	)
	(gr_poly
		(pts
			(xy 385.028948 -231.269794) (xy 384.990594 -231.247696) (xy 384.835146 -231.212136) (xy 384.704336 -231.438704)
			(xy 384.812794 -231.555544) (xy 384.851148 -231.577642)
		)
		(stroke
			(width 0)
			(type solid)
		)
		(fill yes)
		(layer "In4.Cu")
		(net "M_G_CPU0_SB_DQS_DP<7>")
	)
	(gr_poly
		(pts
			(xy 385.09829 -276.357588) (xy 385.136644 -276.33549) (xy 384.958844 -276.027642) (xy 384.92049 -276.04974)
			(xy 384.812032 -276.16658) (xy 384.942842 -276.393148)
		)
		(stroke
			(width 0)
			(type solid)
		)
		(fill yes)
		(layer "In4.Cu")
		(net "M_G_CPU0_SA_DQS_DN<5>")
	)
	(gr_poly
		(pts
			(xy 385.09829 -273.10207) (xy 385.136644 -273.079972) (xy 384.958844 -272.772124) (xy 384.92049 -272.794222)
			(xy 384.812032 -272.911062) (xy 384.942842 -273.13763)
		)
		(stroke
			(width 0)
			(type solid)
		)
		(fill yes)
		(layer "In4.Cu")
		(net "M_F_CPU0_SA_DQ<8>")
	)
	(gr_poly
		(pts
			(xy 385.100322 -277.989284) (xy 385.138676 -277.967186) (xy 384.960876 -277.659338) (xy 384.922522 -277.681436)
			(xy 384.814064 -277.798276) (xy 384.944874 -278.024844)
		)
		(stroke
			(width 0)
			(type solid)
		)
		(fill yes)
		(layer "In4.Cu")
		(net "M_G_CPU0_SA_DQS_DP<0>")
	)
	(gr_poly
		(pts
			(xy 385.124198 -240.057178) (xy 385.077208 -239.904778) (xy 384.815588 -239.904778) (xy 384.768598 -240.057178)
			(xy 384.768598 -240.101628) (xy 385.124198 -240.101628)
		)
		(stroke
			(width 0)
			(type solid)
		)
		(fill yes)
		(layer "In4.Cu")
		(net "M_G_CPU0_SB_CB<3>")
	)
	(gr_poly
		(pts
			(xy 385.124198 -239.649254) (xy 385.124198 -239.604804) (xy 384.768598 -239.604804) (xy 384.768598 -239.649254)
			(xy 384.815588 -239.801654) (xy 385.077208 -239.801654)
		)
		(stroke
			(width 0)
			(type solid)
		)
		(fill yes)
		(layer "In4.Cu")
		(net "M_F_CPU0_SB_DQ<0>")
	)
	(gr_poly
		(pts
			(xy 385.124198 -236.39399) (xy 385.124198 -236.34954) (xy 384.768598 -236.34954) (xy 384.768598 -236.39399)
			(xy 384.815588 -236.54639) (xy 385.077208 -236.54639)
		)
		(stroke
			(width 0)
			(type solid)
		)
		(fill yes)
		(layer "In4.Cu")
		(net "M_F_CPU0_SB_DQ<4>")
	)
	(gr_poly
		(pts
			(xy 385.124198 -235.174282) (xy 385.077208 -235.021882) (xy 384.815588 -235.021882) (xy 384.768598 -235.174282)
			(xy 384.768598 -235.218478) (xy 385.124198 -235.218478)
		)
		(stroke
			(width 0)
			(type solid)
		)
		(fill yes)
		(layer "In4.Cu")
		(net "M_F_CPU0_SB_DQ<7>")
	)
	(gr_poly
		(pts
			(xy 385.124198 -234.76585) (xy 385.124198 -234.721654) (xy 384.768598 -234.721654) (xy 384.768598 -234.76585)
			(xy 384.815588 -234.91825) (xy 385.077208 -234.91825)
		)
		(stroke
			(width 0)
			(type solid)
		)
		(fill yes)
		(layer "In4.Cu")
		(net "M_G_CPU0_SB_DQ<16>")
	)
	(gr_poly
		(pts
			(xy 385.126738 -236.801914) (xy 385.079748 -236.649514) (xy 384.818128 -236.649514) (xy 384.771138 -236.801914)
			(xy 384.771138 -236.84611) (xy 385.126738 -236.84611)
		)
		(stroke
			(width 0)
			(type solid)
		)
		(fill yes)
		(layer "In4.Cu")
		(net "M_F_CPU0_SB_DQS_DP<5>")
	)
	(gr_poly
		(pts
			(xy 385.132834 -246.568722) (xy 385.085844 -246.416322) (xy 384.824224 -246.416322) (xy 384.777234 -246.568722)
			(xy 384.777234 -246.613172) (xy 385.132834 -246.613172)
		)
		(stroke
			(width 0)
			(type solid)
		)
		(fill yes)
		(layer "In4.Cu")
		(net "M_G_CPU0_SB_CS_N<0>")
	)
	(gr_poly
		(pts
			(xy 385.132834 -244.53215) (xy 385.132834 -244.487954) (xy 384.777234 -244.487954) (xy 384.777234 -244.53215)
			(xy 384.824224 -244.68455) (xy 385.085844 -244.68455)
		)
		(stroke
			(width 0)
			(type solid)
		)
		(fill yes)
		(layer "In4.Cu")
		(net "M_G_CPU0_SB_CB<4>")
	)
	(gr_poly
		(pts
			(xy 385.132834 -243.313458) (xy 385.085844 -243.161058) (xy 384.824224 -243.161058) (xy 384.777234 -243.313458)
			(xy 384.777234 -243.357654) (xy 385.132834 -243.357654)
		)
		(stroke
			(width 0)
			(type solid)
		)
		(fill yes)
		(layer "In4.Cu")
		(net "M_G_CPU0_SB_CB<7>")
	)
	(gr_poly
		(pts
			(xy 385.132834 -242.904518) (xy 385.132834 -242.860322) (xy 384.777234 -242.860322) (xy 384.777234 -242.904518)
			(xy 384.824224 -243.056918) (xy 385.085844 -243.056918)
		)
		(stroke
			(width 0)
			(type solid)
		)
		(fill yes)
		(layer "In4.Cu")
		(net "M_G_CPU0_SB_DQS_DP<9>")
	)
	(gr_poly
		(pts
			(xy 385.132834 -241.685318) (xy 385.085844 -241.532918) (xy 384.824224 -241.532918) (xy 384.777234 -241.685318)
			(xy 384.777234 -241.729768) (xy 385.132834 -241.729768)
		)
		(stroke
			(width 0)
			(type solid)
		)
		(fill yes)
		(layer "In4.Cu")
		(net "M_G_CPU0_SB_DQS_DP<4>")
	)
	(gr_poly
		(pts
			(xy 385.132834 -241.276886) (xy 385.132834 -241.232436) (xy 384.777234 -241.232436) (xy 384.777234 -241.276886)
			(xy 384.824224 -241.429286) (xy 385.085844 -241.429286)
		)
		(stroke
			(width 0)
			(type solid)
		)
		(fill yes)
		(layer "In4.Cu")
		(net "M_G_CPU0_SB_CB<0>")
	)
	(gr_poly
		(pts
			(xy 385.132834 -238.430054) (xy 385.085844 -238.277654) (xy 384.824224 -238.277654) (xy 384.777234 -238.430054)
			(xy 384.777234 -238.47425) (xy 385.132834 -238.47425)
		)
		(stroke
			(width 0)
			(type solid)
		)
		(fill yes)
		(layer "In4.Cu")
		(net "M_F_CPU0_SB_DQ<3>")
	)
	(gr_poly
		(pts
			(xy 385.132834 -238.021114) (xy 385.132834 -237.976918) (xy 384.777234 -237.976918) (xy 384.777234 -238.021114)
			(xy 384.824224 -238.173514) (xy 385.085844 -238.173514)
		)
		(stroke
			(width 0)
			(type solid)
		)
		(fill yes)
		(layer "In4.Cu")
		(net "M_F_CPU0_SB_DQS_DP<0>")
	)
	(gr_poly
		(pts
			(xy 385.132834 -233.54665) (xy 385.085844 -233.39425) (xy 384.824224 -233.39425) (xy 384.777234 -233.54665)
			(xy 384.777234 -233.590846) (xy 385.132834 -233.590846)
		)
		(stroke
			(width 0)
			(type solid)
		)
		(fill yes)
		(layer "In4.Cu")
		(net "M_G_CPU0_SB_DQ<19>")
	)
	(gr_poly
		(pts
			(xy 385.132834 -233.13771) (xy 385.132834 -233.093514) (xy 384.777234 -233.093514) (xy 384.777234 -233.13771)
			(xy 384.824224 -233.29011) (xy 385.085844 -233.29011)
		)
		(stroke
			(width 0)
			(type solid)
		)
		(fill yes)
		(layer "In4.Cu")
		(net "M_G_CPU0_SB_DQS_DP<2>")
	)
	(gr_poly
		(pts
			(xy 385.132834 -220.52407) (xy 385.085844 -220.37167) (xy 384.824224 -220.37167) (xy 384.777234 -220.52407)
			(xy 384.777234 -220.56852) (xy 385.132834 -220.56852)
		)
		(stroke
			(width 0)
			(type solid)
		)
		(fill yes)
		(layer "In4.Cu")
		(net "M_F_CPU0_SB_DQS_DN<3>")
	)
	(gr_poly
		(pts
			(xy 385.141216 -220.115638) (xy 385.141216 -220.071442) (xy 384.785616 -220.071442) (xy 384.785616 -220.115638)
			(xy 384.832606 -220.268038) (xy 385.094226 -220.268038)
		)
		(stroke
			(width 0)
			(type solid)
		)
		(fill yes)
		(layer "In4.Cu")
		(net "M_F_CPU0_SB_DQ<30>")
	)
	(gr_poly
		(pts
			(xy 385.141216 -218.896438) (xy 385.094226 -218.744038) (xy 384.832606 -218.744038) (xy 384.785616 -218.896438)
			(xy 384.785616 -218.940634) (xy 385.141216 -218.940634)
		)
		(stroke
			(width 0)
			(type solid)
		)
		(fill yes)
		(layer "In4.Cu")
		(net "M_F_CPU0_SB_DQ<31>")
	)
	(gr_poly
		(pts
			(xy 385.205732 -231.990392) (xy 385.097274 -231.873552) (xy 385.05892 -231.851454) (xy 384.88112 -232.159302)
			(xy 384.919474 -232.1814) (xy 385.074922 -232.21696)
		)
		(stroke
			(width 0)
			(type solid)
		)
		(fill yes)
		(layer "In4.Cu")
		(net "M_G_CPU0_SB_DQS_DN<7>")
	)
	(gr_poly
		(pts
			(xy 385.20624 -272.479008) (xy 385.314698 -272.362168) (xy 385.183888 -272.1356) (xy 385.02844 -272.17116)
			(xy 384.990086 -272.193258) (xy 385.167886 -272.501106)
		)
		(stroke
			(width 0)
			(type solid)
		)
		(fill yes)
		(layer "In4.Cu")
		(net "M_F_CPU0_SA_DQ<10>")
	)
	(gr_poly
		(pts
			(xy 385.206748 -225.47707) (xy 385.09829 -225.36023) (xy 385.059936 -225.338132) (xy 384.882136 -225.64598)
			(xy 384.92049 -225.668078) (xy 385.075938 -225.703638)
		)
		(stroke
			(width 0)
			(type solid)
		)
		(fill yes)
		(layer "In4.Cu")
		(net "M_F_CPU0_SB_DQ<26>")
	)
	(gr_poly
		(pts
			(xy 385.207764 -230.358442) (xy 385.099306 -230.241602) (xy 385.060952 -230.219504) (xy 384.883152 -230.527352)
			(xy 384.921506 -230.54945) (xy 385.076954 -230.58501)
		)
		(stroke
			(width 0)
			(type solid)
		)
		(fill yes)
		(layer "In4.Cu")
		(net "M_G_CPU0_SB_DQ<20>")
	)
	(gr_poly
		(pts
			(xy 385.208018 -275.73732) (xy 385.316476 -275.62048) (xy 385.185666 -275.393912) (xy 385.030218 -275.429472)
			(xy 384.991864 -275.45157) (xy 385.169664 -275.759418)
		)
		(stroke
			(width 0)
			(type solid)
		)
		(fill yes)
		(layer "In4.Cu")
		(net "M_G_CPU0_SA_DQS_DP<5>")
	)
	(gr_poly
		(pts
			(xy 385.209034 -277.367492) (xy 385.317492 -277.250652) (xy 385.186682 -277.024084) (xy 385.031234 -277.059644)
			(xy 384.99288 -277.081742) (xy 385.17068 -277.38959)
		)
		(stroke
			(width 0)
			(type solid)
		)
		(fill yes)
		(layer "In4.Cu")
		(net "M_G_CPU0_SA_DQS_DN<0>")
	)
	(gr_poly
		(pts
			(xy 385.212082 -228.723698) (xy 385.103624 -228.606858) (xy 385.06527 -228.58476) (xy 384.88747 -228.892608)
			(xy 384.925824 -228.914706) (xy 385.081272 -228.950266)
		)
		(stroke
			(width 0)
			(type solid)
		)
		(fill yes)
		(layer "In4.Cu")
		(net "M_G_CPU0_SB_DQ<21>")
	)
	(gr_poly
		(pts
			(xy 385.212082 -223.84004) (xy 385.103624 -223.7232) (xy 385.06527 -223.701102) (xy 384.88747 -224.00895)
			(xy 384.925824 -224.031048) (xy 385.081272 -224.066608)
		)
		(stroke
			(width 0)
			(type solid)
		)
		(fill yes)
		(layer "In4.Cu")
		(net "M_F_CPU0_SB_DQ<27>")
	)
	(gr_poly
		(pts
			(xy 385.21386 -222.20936) (xy 385.105402 -222.09252) (xy 385.067048 -222.070422) (xy 384.889248 -222.37827)
			(xy 384.927602 -222.400368) (xy 385.08305 -222.435928)
		)
		(stroke
			(width 0)
			(type solid)
		)
		(fill yes)
		(layer "In4.Cu")
		(net "M_F_CPU0_SB_DQS_DN<8>")
	)
	(gr_poly
		(pts
			(xy 385.233672 -259.820918) (xy 385.186682 -259.668518) (xy 384.925062 -259.668518) (xy 384.878072 -259.820918)
			(xy 384.878072 -259.865368) (xy 385.233672 -259.865368)
		)
		(stroke
			(width 0)
			(type solid)
		)
		(fill yes)
		(layer "In4.Cu")
		(net "M_F_CPU0_SA_DQS_DP<8>")
	)
	(gr_poly
		(pts
			(xy 385.233926 -259.412994) (xy 385.233926 -259.368544) (xy 384.878326 -259.368544) (xy 384.878326 -259.412994)
			(xy 384.925316 -259.565394) (xy 385.186936 -259.565394)
		)
		(stroke
			(width 0)
			(type solid)
		)
		(fill yes)
		(layer "In4.Cu")
		(net "M_F_CPU0_SA_DQ<28>")
	)
	(gr_poly
		(pts
			(xy 385.23418 -274.47113) (xy 385.18719 -274.31873) (xy 384.92557 -274.31873) (xy 384.87858 -274.47113)
			(xy 384.87858 -274.515326) (xy 385.23418 -274.515326)
		)
		(stroke
			(width 0)
			(type solid)
		)
		(fill yes)
		(layer "In4.Cu")
		(net "M_G_CPU0_SA_DQ<6>")
	)
	(gr_poly
		(pts
			(xy 385.23418 -271.215358) (xy 385.18719 -271.062958) (xy 384.92557 -271.062958) (xy 384.87858 -271.215358)
			(xy 384.87858 -271.259808) (xy 385.23418 -271.259808)
		)
		(stroke
			(width 0)
			(type solid)
		)
		(fill yes)
		(layer "In4.Cu")
		(net "M_F_CPU0_SA_DQ<11>")
	)
	(gr_poly
		(pts
			(xy 385.23418 -270.807434) (xy 385.23418 -270.762984) (xy 384.87858 -270.762984) (xy 384.87858 -270.807434)
			(xy 384.92557 -270.959834) (xy 385.18719 -270.959834)
		)
		(stroke
			(width 0)
			(type solid)
		)
		(fill yes)
		(layer "In4.Cu")
		(net "M_F_CPU0_SA_DQS_DP<1>")
	)
	(gr_poly
		(pts
			(xy 385.23418 -269.587726) (xy 385.18719 -269.435326) (xy 384.92557 -269.435326) (xy 384.87858 -269.587726)
			(xy 384.87858 -269.631922) (xy 385.23418 -269.631922)
		)
		(stroke
			(width 0)
			(type solid)
		)
		(fill yes)
		(layer "In4.Cu")
		(net "M_F_CPU0_SA_DQS_DP<6>")
	)
	(gr_poly
		(pts
			(xy 385.23418 -264.704322) (xy 385.18719 -264.551922) (xy 384.92557 -264.551922) (xy 384.87858 -264.704322)
			(xy 384.87858 -264.748772) (xy 385.23418 -264.748772)
		)
		(stroke
			(width 0)
			(type solid)
		)
		(fill yes)
		(layer "In4.Cu")
		(net "M_G_CPU0_SA_DQS_DP<7>")
	)
	(gr_poly
		(pts
			(xy 385.242308 -261.449058) (xy 385.195318 -261.296658) (xy 384.933698 -261.296658) (xy 384.886708 -261.449058)
			(xy 384.886708 -261.493508) (xy 385.242308 -261.493508)
		)
		(stroke
			(width 0)
			(type solid)
		)
		(fill yes)
		(layer "In4.Cu")
		(net "M_F_CPU0_SA_DQ<27>")
	)
	(gr_poly
		(pts
			(xy 385.242308 -261.040626) (xy 385.242308 -260.996176) (xy 384.886708 -260.996176) (xy 384.886708 -261.040626)
			(xy 384.933698 -261.193026) (xy 385.195318 -261.193026)
		)
		(stroke
			(width 0)
			(type solid)
		)
		(fill yes)
		(layer "In4.Cu")
		(net "M_F_CPU0_SA_DQS_DP<3>")
	)
	(gr_poly
		(pts
			(xy 385.242562 -279.354788) (xy 385.195572 -279.202388) (xy 384.933952 -279.202388) (xy 384.886962 -279.354788)
			(xy 384.886962 -279.398984) (xy 385.242562 -279.398984)
		)
		(stroke
			(width 0)
			(type solid)
		)
		(fill yes)
		(layer "In4.Cu")
		(net "M_G_CPU0_SA_DQ<2>")
	)
	(gr_poly
		(pts
			(xy 385.242562 -278.945848) (xy 385.242562 -278.901652) (xy 384.886962 -278.901652) (xy 384.886962 -278.945848)
			(xy 384.933952 -279.098248) (xy 385.195572 -279.098248)
		)
		(stroke
			(width 0)
			(type solid)
		)
		(fill yes)
		(layer "In4.Cu")
		(net "M_G_CPU0_SA_DQ<1>")
	)
	(gr_poly
		(pts
			(xy 385.242562 -274.062698) (xy 385.242562 -274.018248) (xy 384.886962 -274.018248) (xy 384.886962 -274.062698)
			(xy 384.933952 -274.215098) (xy 385.195572 -274.215098)
		)
		(stroke
			(width 0)
			(type solid)
		)
		(fill yes)
		(layer "In4.Cu")
		(net "M_G_CPU0_SA_DQ<5>")
	)
	(gr_poly
		(pts
			(xy 385.242562 -269.179294) (xy 385.242562 -269.134844) (xy 384.886962 -269.134844) (xy 384.886962 -269.179294)
			(xy 384.933952 -269.331694) (xy 385.195572 -269.331694)
		)
		(stroke
			(width 0)
			(type solid)
		)
		(fill yes)
		(layer "In4.Cu")
		(net "M_F_CPU0_SA_DQ<12>")
	)
	(gr_poly
		(pts
			(xy 385.242562 -267.960094) (xy 385.195572 -267.807694) (xy 384.933952 -267.807694) (xy 384.886962 -267.960094)
			(xy 384.886962 -268.004544) (xy 385.242562 -268.004544)
		)
		(stroke
			(width 0)
			(type solid)
		)
		(fill yes)
		(layer "In4.Cu")
		(net "M_F_CPU0_SA_DQ<13>")
	)
	(gr_poly
		(pts
			(xy 385.242562 -267.551662) (xy 385.242562 -267.507212) (xy 384.886962 -267.507212) (xy 384.886962 -267.551662)
			(xy 384.933952 -267.704062) (xy 385.195572 -267.704062)
		)
		(stroke
			(width 0)
			(type solid)
		)
		(fill yes)
		(layer "In4.Cu")
		(net "M_G_CPU0_SA_DQ<16>")
	)
	(gr_poly
		(pts
			(xy 385.242562 -266.332462) (xy 385.195572 -266.180062) (xy 384.933952 -266.180062) (xy 384.886962 -266.332462)
			(xy 384.886962 -266.376658) (xy 385.242562 -266.376658)
		)
		(stroke
			(width 0)
			(type solid)
		)
		(fill yes)
		(layer "In4.Cu")
		(net "M_G_CPU0_SA_DQ<19>")
	)
	(gr_poly
		(pts
			(xy 385.242562 -264.29589) (xy 385.242562 -264.251694) (xy 384.886962 -264.251694) (xy 384.886962 -264.29589)
			(xy 384.933952 -264.44829) (xy 385.195572 -264.44829)
		)
		(stroke
			(width 0)
			(type solid)
		)
		(fill yes)
		(layer "In4.Cu")
		(net "M_G_CPU0_SA_DQ<20>")
	)
	(gr_poly
		(pts
			(xy 385.242562 -263.07669) (xy 385.195572 -262.92429) (xy 384.933952 -262.92429) (xy 384.886962 -263.07669)
			(xy 384.886962 -263.12114) (xy 385.242562 -263.12114)
		)
		(stroke
			(width 0)
			(type solid)
		)
		(fill yes)
		(layer "In4.Cu")
		(net "M_G_CPU0_SA_DQ<23>")
	)
	(gr_poly
		(pts
			(xy 385.242562 -262.668258) (xy 385.242562 -262.623808) (xy 384.886962 -262.623808) (xy 384.886962 -262.668258)
			(xy 384.933952 -262.820658) (xy 385.195572 -262.820658)
		)
		(stroke
			(width 0)
			(type solid)
		)
		(fill yes)
		(layer "In4.Cu")
		(net "M_F_CPU0_SA_DQ<24>")
	)
	(gr_poly
		(pts
			(xy 385.243324 -265.923522) (xy 385.243324 -265.879072) (xy 384.887724 -265.879072) (xy 384.887724 -265.923522)
			(xy 384.934714 -266.075922) (xy 385.196334 -266.075922)
		)
		(stroke
			(width 0)
			(type solid)
		)
		(fill yes)
		(layer "In4.Cu")
		(net "M_G_CPU0_SA_DQS_DP<2>")
	)
	(gr_poly
		(pts
			(xy 385.251198 -258.193286) (xy 385.204208 -258.040886) (xy 384.942588 -258.040886) (xy 384.895598 -258.193286)
			(xy 384.895598 -258.237482) (xy 385.251198 -258.237482)
		)
		(stroke
			(width 0)
			(type solid)
		)
		(fill yes)
		(layer "In4.Cu")
		(net "M_F_CPU0_SA_DQ<31>")
	)
	(gr_poly
		(pts
			(xy 385.490466 -228.842316) (xy 385.452112 -228.820218) (xy 385.296664 -228.784658) (xy 385.165854 -229.011226)
			(xy 385.274312 -229.128066) (xy 385.312666 -229.150164)
		)
		(stroke
			(width 0)
			(type solid)
		)
		(fill yes)
		(layer "In4.Cu")
		(net "M_G_CPU0_SB_DQ<22>")
	)
	(gr_poly
		(pts
			(xy 385.490466 -222.331026) (xy 385.452112 -222.308928) (xy 385.296664 -222.273368) (xy 385.165854 -222.499936)
			(xy 385.274312 -222.616776) (xy 385.312666 -222.638874)
		)
		(stroke
			(width 0)
			(type solid)
		)
		(fill yes)
		(layer "In4.Cu")
		(net "M_F_CPU0_SB_DQ<25>")
	)
	(gr_poly
		(pts
			(xy 385.496816 -230.459788) (xy 385.458462 -230.43769) (xy 385.303014 -230.40213) (xy 385.172204 -230.628698)
			(xy 385.280662 -230.745538) (xy 385.319016 -230.767636)
		)
		(stroke
			(width 0)
			(type solid)
		)
		(fill yes)
		(layer "In4.Cu")
		(net "M_G_CPU0_SB_DQS_DP<7>")
	)
	(gr_poly
		(pts
			(xy 385.496816 -227.20427) (xy 385.458462 -227.182172) (xy 385.303014 -227.146612) (xy 385.172204 -227.37318)
			(xy 385.280662 -227.49002) (xy 385.319016 -227.512118)
		)
		(stroke
			(width 0)
			(type solid)
		)
		(fill yes)
		(layer "In4.Cu")
		(net "M_G_CPU0_SB_DQ<23>")
	)
	(gr_poly
		(pts
			(xy 385.496816 -223.948752) (xy 385.458462 -223.926654) (xy 385.303014 -223.891094) (xy 385.172204 -224.117662)
			(xy 385.280662 -224.234502) (xy 385.319016 -224.2566)
		)
		(stroke
			(width 0)
			(type solid)
		)
		(fill yes)
		(layer "In4.Cu")
		(net "M_F_CPU0_SB_DQ<24>")
	)
	(gr_poly
		(pts
			(xy 385.497832 -232.085134) (xy 385.459478 -232.063036) (xy 385.30403 -232.027476) (xy 385.17322 -232.254044)
			(xy 385.281678 -232.370884) (xy 385.320032 -232.392982)
		)
		(stroke
			(width 0)
			(type solid)
		)
		(fill yes)
		(layer "In4.Cu")
		(net "M_G_CPU0_SB_DQS_DN<2>")
	)
	(gr_poly
		(pts
			(xy 385.56819 -277.171404) (xy 385.606544 -277.149306) (xy 385.428744 -276.841458) (xy 385.39039 -276.863556)
			(xy 385.281932 -276.980396) (xy 385.412742 -277.206964)
		)
		(stroke
			(width 0)
			(type solid)
		)
		(fill yes)
		(layer "In4.Cu")
		(net "M_G_CPU0_SA_DQS_DN<5>")
	)
	(gr_poly
		(pts
			(xy 385.56946 -275.546312) (xy 385.607814 -275.524214) (xy 385.430014 -275.216366) (xy 385.39166 -275.238464)
			(xy 385.283202 -275.355304) (xy 385.414012 -275.581872)
		)
		(stroke
			(width 0)
			(type solid)
		)
		(fill yes)
		(layer "In4.Cu")
		(net "M_G_CPU0_SA_DQ<4>")
	)
	(gr_poly
		(pts
			(xy 385.571238 -272.293334) (xy 385.609592 -272.271236) (xy 385.431792 -271.963388) (xy 385.393438 -271.985486)
			(xy 385.28498 -272.102326) (xy 385.41579 -272.328894)
		)
		(stroke
			(width 0)
			(type solid)
		)
		(fill yes)
		(layer "In4.Cu")
		(net "M_F_CPU0_SA_DQ<9>")
	)
	(gr_poly
		(pts
			(xy 385.594098 -219.710254) (xy 385.547108 -219.557854) (xy 385.285488 -219.557854) (xy 385.238498 -219.710254)
			(xy 385.238498 -219.75445) (xy 385.594098 -219.75445)
		)
		(stroke
			(width 0)
			(type solid)
		)
		(fill yes)
		(layer "In4.Cu")
		(net "M_F_CPU0_SB_DQ<28>")
	)
	(gr_poly
		(pts
			(xy 385.594098 -219.301822) (xy 385.594098 -219.257626) (xy 385.238498 -219.257626) (xy 385.238498 -219.301822)
			(xy 385.285488 -219.454222) (xy 385.547108 -219.454222)
		)
		(stroke
			(width 0)
			(type solid)
		)
		(fill yes)
		(layer "In4.Cu")
		(net "M_F_CPU0_SB_DQ<29>")
	)
	(gr_poly
		(pts
			(xy 385.60248 -237.207806) (xy 385.60248 -237.163356) (xy 385.24688 -237.163356) (xy 385.24688 -237.207806)
			(xy 385.29387 -237.360206) (xy 385.55549 -237.360206)
		)
		(stroke
			(width 0)
			(type solid)
		)
		(fill yes)
		(layer "In4.Cu")
		(net "M_F_CPU0_SB_DQS_DN<5>")
	)
	(gr_poly
		(pts
			(xy 385.602734 -244.127274) (xy 385.555744 -243.974874) (xy 385.294124 -243.974874) (xy 385.247134 -244.127274)
			(xy 385.247134 -244.17147) (xy 385.602734 -244.17147)
		)
		(stroke
			(width 0)
			(type solid)
		)
		(fill yes)
		(layer "In4.Cu")
		(net "M_G_CPU0_SB_CB<6>")
	)
	(gr_poly
		(pts
			(xy 385.602734 -242.499134) (xy 385.555744 -242.346734) (xy 385.294124 -242.346734) (xy 385.247134 -242.499134)
			(xy 385.247134 -242.543584) (xy 385.602734 -242.543584)
		)
		(stroke
			(width 0)
			(type solid)
		)
		(fill yes)
		(layer "In4.Cu")
		(net "M_G_CPU0_SB_DQS_DN<9>")
	)
	(gr_poly
		(pts
			(xy 385.602734 -242.090702) (xy 385.602734 -242.046252) (xy 385.247134 -242.046252) (xy 385.247134 -242.090702)
			(xy 385.294124 -242.243102) (xy 385.555744 -242.243102)
		)
		(stroke
			(width 0)
			(type solid)
		)
		(fill yes)
		(layer "In4.Cu")
		(net "M_G_CPU0_SB_DQS_DN<4>")
	)
	(gr_poly
		(pts
			(xy 385.602734 -240.871502) (xy 385.555744 -240.719102) (xy 385.294124 -240.719102) (xy 385.247134 -240.871502)
			(xy 385.247134 -240.915952) (xy 385.602734 -240.915952)
		)
		(stroke
			(width 0)
			(type solid)
		)
		(fill yes)
		(layer "In4.Cu")
		(net "M_G_CPU0_SB_CB<2>")
	)
	(gr_poly
		(pts
			(xy 385.602734 -238.83493) (xy 385.602734 -238.790734) (xy 385.247134 -238.790734) (xy 385.247134 -238.83493)
			(xy 385.294124 -238.98733) (xy 385.555744 -238.98733)
		)
		(stroke
			(width 0)
			(type solid)
		)
		(fill yes)
		(layer "In4.Cu")
		(net "M_F_CPU0_SB_DQ<1>")
	)
	(gr_poly
		(pts
			(xy 385.602734 -237.61573) (xy 385.555744 -237.46333) (xy 385.294124 -237.46333) (xy 385.247134 -237.61573)
			(xy 385.247134 -237.66018) (xy 385.602734 -237.66018)
		)
		(stroke
			(width 0)
			(type solid)
		)
		(fill yes)
		(layer "In4.Cu")
		(net "M_F_CPU0_SB_DQS_DN<0>")
	)
	(gr_poly
		(pts
			(xy 385.602734 -233.952034) (xy 385.602734 -233.907584) (xy 385.247134 -233.907584) (xy 385.247134 -233.952034)
			(xy 385.294124 -234.104434) (xy 385.555744 -234.104434)
		)
		(stroke
			(width 0)
			(type solid)
		)
		(fill yes)
		(layer "In4.Cu")
		(net "M_G_CPU0_SB_DQ<17>")
	)
	(gr_poly
		(pts
			(xy 385.602734 -221.338394) (xy 385.555744 -221.185994) (xy 385.294124 -221.185994) (xy 385.247134 -221.338394)
			(xy 385.247134 -221.38259) (xy 385.602734 -221.38259)
		)
		(stroke
			(width 0)
			(type solid)
		)
		(fill yes)
		(layer "In4.Cu")
		(net "M_F_CPU0_SB_DQS_DP<8>")
	)
	(gr_poly
		(pts
			(xy 385.602734 -220.929454) (xy 385.602734 -220.885258) (xy 385.247134 -220.885258) (xy 385.247134 -220.929454)
			(xy 385.294124 -221.081854) (xy 385.555744 -221.081854)
		)
		(stroke
			(width 0)
			(type solid)
		)
		(fill yes)
		(layer "In4.Cu")
		(net "M_F_CPU0_SB_DQS_DP<3>")
	)
	(gr_poly
		(pts
			(xy 385.611116 -240.46307) (xy 385.611116 -240.418874) (xy 385.255516 -240.418874) (xy 385.255516 -240.46307)
			(xy 385.302506 -240.61547) (xy 385.564126 -240.61547)
		)
		(stroke
			(width 0)
			(type solid)
		)
		(fill yes)
		(layer "In4.Cu")
		(net "M_G_CPU0_SB_CB<1>")
	)
	(gr_poly
		(pts
			(xy 385.611116 -239.243362) (xy 385.564126 -239.090962) (xy 385.302506 -239.090962) (xy 385.255516 -239.243362)
			(xy 385.255516 -239.287812) (xy 385.611116 -239.287812)
		)
		(stroke
			(width 0)
			(type solid)
		)
		(fill yes)
		(layer "In4.Cu")
		(net "M_F_CPU0_SB_DQ<2>")
	)
	(gr_poly
		(pts
			(xy 385.611116 -235.988098) (xy 385.564126 -235.835698) (xy 385.302506 -235.835698) (xy 385.255516 -235.988098)
			(xy 385.255516 -236.032294) (xy 385.611116 -236.032294)
		)
		(stroke
			(width 0)
			(type solid)
		)
		(fill yes)
		(layer "In4.Cu")
		(net "M_F_CPU0_SB_DQ<6>")
	)
	(gr_poly
		(pts
			(xy 385.611116 -235.579666) (xy 385.611116 -235.53547) (xy 385.255516 -235.53547) (xy 385.255516 -235.579666)
			(xy 385.302506 -235.732066) (xy 385.564126 -235.732066)
		)
		(stroke
			(width 0)
			(type solid)
		)
		(fill yes)
		(layer "In4.Cu")
		(net "M_F_CPU0_SB_DQ<5>")
	)
	(gr_poly
		(pts
			(xy 385.611116 -234.360466) (xy 385.564126 -234.208066) (xy 385.302506 -234.208066) (xy 385.255516 -234.360466)
			(xy 385.255516 -234.404662) (xy 385.611116 -234.404662)
		)
		(stroke
			(width 0)
			(type solid)
		)
		(fill yes)
		(layer "In4.Cu")
		(net "M_G_CPU0_SB_DQ<18>")
	)
	(gr_poly
		(pts
			(xy 385.675632 -231.176322) (xy 385.567174 -231.059482) (xy 385.52882 -231.037384) (xy 385.35102 -231.345232)
			(xy 385.389374 -231.36733) (xy 385.544822 -231.40289)
		)
		(stroke
			(width 0)
			(type solid)
		)
		(fill yes)
		(layer "In4.Cu")
		(net "M_G_CPU0_SB_DQS_DN<7>")
	)
	(gr_poly
		(pts
			(xy 385.676648 -223.035368) (xy 385.56819 -222.918528) (xy 385.529836 -222.89643) (xy 385.352036 -223.204278)
			(xy 385.39039 -223.226376) (xy 385.545838 -223.261936)
		)
		(stroke
			(width 0)
			(type solid)
		)
		(fill yes)
		(layer "In4.Cu")
		(net "M_F_CPU0_SB_DQ<27>")
	)
	(gr_poly
		(pts
			(xy 385.677664 -232.800144) (xy 385.569206 -232.683304) (xy 385.530852 -232.661206) (xy 385.353052 -232.969054)
			(xy 385.391406 -232.991152) (xy 385.546854 -233.026712)
		)
		(stroke
			(width 0)
			(type solid)
		)
		(fill yes)
		(layer "In4.Cu")
		(net "M_G_CPU0_SB_DQS_DP<2>")
	)
	(gr_poly
		(pts
			(xy 385.677664 -224.661222) (xy 385.569206 -224.544382) (xy 385.530852 -224.522284) (xy 385.353052 -224.830132)
			(xy 385.391406 -224.85223) (xy 385.546854 -224.88779)
		)
		(stroke
			(width 0)
			(type solid)
		)
		(fill yes)
		(layer "In4.Cu")
		(net "M_F_CPU0_SB_DQ<26>")
	)
	(gr_poly
		(pts
			(xy 385.678934 -276.553676) (xy 385.787392 -276.436836) (xy 385.656582 -276.210268) (xy 385.501134 -276.245828)
			(xy 385.46278 -276.267926) (xy 385.64058 -276.575774)
		)
		(stroke
			(width 0)
			(type solid)
		)
		(fill yes)
		(layer "In4.Cu")
		(net "M_G_CPU0_SA_DQS_DP<5>")
	)
	(gr_poly
		(pts
			(xy 385.681982 -229.53726) (xy 385.573524 -229.42042) (xy 385.53517 -229.398322) (xy 385.35737 -229.70617)
			(xy 385.395724 -229.728268) (xy 385.551172 -229.763828)
		)
		(stroke
			(width 0)
			(type solid)
		)
		(fill yes)
		(layer "In4.Cu")
		(net "M_G_CPU0_SB_DQ<20>")
	)
	(gr_poly
		(pts
			(xy 385.683506 -271.677384) (xy 385.791964 -271.560544) (xy 385.661154 -271.333976) (xy 385.505706 -271.369536)
			(xy 385.467352 -271.391634) (xy 385.645152 -271.699482)
		)
		(stroke
			(width 0)
			(type solid)
		)
		(fill yes)
		(layer "In4.Cu")
		(net "M_F_CPU0_SA_DQ<11>")
	)
	(gr_poly
		(pts
			(xy 385.684776 -227.904548) (xy 385.576318 -227.787708) (xy 385.537964 -227.76561) (xy 385.360164 -228.073458)
			(xy 385.398518 -228.095556) (xy 385.553966 -228.131116)
		)
		(stroke
			(width 0)
			(type solid)
		)
		(fill yes)
		(layer "In4.Cu")
		(net "M_G_CPU0_SB_DQ<21>")
	)
	(gr_poly
		(pts
			(xy 385.70408 -258.599178) (xy 385.70408 -258.554728) (xy 385.34848 -258.554728) (xy 385.34848 -258.599178)
			(xy 385.39547 -258.751578) (xy 385.65709 -258.751578)
		)
		(stroke
			(width 0)
			(type solid)
		)
		(fill yes)
		(layer "In4.Cu")
		(net "M_F_CPU0_SA_DQ<29>")
	)
	(gr_poly
		(pts
			(xy 385.712208 -261.854442) (xy 385.712208 -261.809992) (xy 385.356608 -261.809992) (xy 385.356608 -261.854442)
			(xy 385.403598 -262.006842) (xy 385.665218 -262.006842)
		)
		(stroke
			(width 0)
			(type solid)
		)
		(fill yes)
		(layer "In4.Cu")
		(net "M_F_CPU0_SA_DQ<25>")
	)
	(gr_poly
		(pts
			(xy 385.712208 -260.635242) (xy 385.665218 -260.482842) (xy 385.403598 -260.482842) (xy 385.356608 -260.635242)
			(xy 385.356608 -260.679438) (xy 385.712208 -260.679438)
		)
		(stroke
			(width 0)
			(type solid)
		)
		(fill yes)
		(layer "In4.Cu")
		(net "M_F_CPU0_SA_DQS_DN<3>")
	)
	(gr_poly
		(pts
			(xy 385.712462 -278.540718) (xy 385.665472 -278.388318) (xy 385.403852 -278.388318) (xy 385.356862 -278.540718)
			(xy 385.356862 -278.585168) (xy 385.712462 -278.585168)
		)
		(stroke
			(width 0)
			(type solid)
		)
		(fill yes)
		(layer "In4.Cu")
		(net "M_G_CPU0_SA_DQ<3>")
	)
	(gr_poly
		(pts
			(xy 385.712462 -278.132032) (xy 385.712462 -278.087836) (xy 385.356862 -278.087836) (xy 385.356862 -278.132032)
			(xy 385.403852 -278.284432) (xy 385.665472 -278.284432)
		)
		(stroke
			(width 0)
			(type solid)
		)
		(fill yes)
		(layer "In4.Cu")
		(net "M_G_CPU0_SA_DQS_DP<0>")
	)
	(gr_poly
		(pts
			(xy 385.712462 -273.657314) (xy 385.665472 -273.504914) (xy 385.403852 -273.504914) (xy 385.356862 -273.657314)
			(xy 385.356862 -273.701764) (xy 385.712462 -273.701764)
		)
		(stroke
			(width 0)
			(type solid)
		)
		(fill yes)
		(layer "In4.Cu")
		(net "M_G_CPU0_SA_DQ<7>")
	)
	(gr_poly
		(pts
			(xy 385.712462 -273.248882) (xy 385.712462 -273.204432) (xy 385.356862 -273.204432) (xy 385.356862 -273.248882)
			(xy 385.403852 -273.401282) (xy 385.665472 -273.401282)
		)
		(stroke
			(width 0)
			(type solid)
		)
		(fill yes)
		(layer "In4.Cu")
		(net "M_F_CPU0_SA_DQ<8>")
	)
	(gr_poly
		(pts
			(xy 385.712462 -268.77391) (xy 385.665472 -268.62151) (xy 385.403852 -268.62151) (xy 385.356862 -268.77391)
			(xy 385.356862 -268.81836) (xy 385.712462 -268.81836)
		)
		(stroke
			(width 0)
			(type solid)
		)
		(fill yes)
		(layer "In4.Cu")
		(net "M_F_CPU0_SA_DQ<14>")
	)
	(gr_poly
		(pts
			(xy 385.712462 -268.365478) (xy 385.712462 -268.321028) (xy 385.356862 -268.321028) (xy 385.356862 -268.365478)
			(xy 385.403852 -268.517878) (xy 385.665472 -268.517878)
		)
		(stroke
			(width 0)
			(type solid)
		)
		(fill yes)
		(layer "In4.Cu")
		(net "M_F_CPU0_SA_DQ<15>")
	)
	(gr_poly
		(pts
			(xy 385.712462 -262.262874) (xy 385.665472 -262.110474) (xy 385.403852 -262.110474) (xy 385.356862 -262.262874)
			(xy 385.356862 -262.307324) (xy 385.712462 -262.307324)
		)
		(stroke
			(width 0)
			(type solid)
		)
		(fill yes)
		(layer "In4.Cu")
		(net "M_F_CPU0_SA_DQ<26>")
	)
	(gr_poly
		(pts
			(xy 385.72059 -260.22681) (xy 385.72059 -260.18236) (xy 385.36499 -260.18236) (xy 385.36499 -260.22681)
			(xy 385.41198 -260.37921) (xy 385.6736 -260.37921)
		)
		(stroke
			(width 0)
			(type solid)
		)
		(fill yes)
		(layer "In4.Cu")
		(net "M_F_CPU0_SA_DQS_DN<8>")
	)
	(gr_poly
		(pts
			(xy 385.72059 -259.007102) (xy 385.6736 -258.854702) (xy 385.41198 -258.854702) (xy 385.36499 -259.007102)
			(xy 385.36499 -259.051552) (xy 385.72059 -259.051552)
		)
		(stroke
			(width 0)
			(type solid)
		)
		(fill yes)
		(layer "In4.Cu")
		(net "M_F_CPU0_SA_DQ<30>")
	)
	(gr_poly
		(pts
			(xy 385.721098 -270.401542) (xy 385.674108 -270.249142) (xy 385.412488 -270.249142) (xy 385.365498 -270.401542)
			(xy 385.365498 -270.445992) (xy 385.721098 -270.445992)
		)
		(stroke
			(width 0)
			(type solid)
		)
		(fill yes)
		(layer "In4.Cu")
		(net "M_F_CPU0_SA_DQS_DN<1>")
	)
	(gr_poly
		(pts
			(xy 385.721098 -269.993618) (xy 385.721098 -269.949168) (xy 385.365498 -269.949168) (xy 385.365498 -269.993618)
			(xy 385.412488 -270.146018) (xy 385.674108 -270.146018)
		)
		(stroke
			(width 0)
			(type solid)
		)
		(fill yes)
		(layer "In4.Cu")
		(net "M_F_CPU0_SA_DQS_DN<6>")
	)
	(gr_poly
		(pts
			(xy 385.966716 -232.90149) (xy 385.928362 -232.879392) (xy 385.772914 -232.843832) (xy 385.642104 -233.0704)
			(xy 385.750562 -233.18724) (xy 385.788916 -233.209338)
		)
		(stroke
			(width 0)
			(type solid)
		)
		(fill yes)
		(layer "In4.Cu")
		(net "M_G_CPU0_SB_DQ<19>")
	)
	(gr_poly
		(pts
			(xy 385.966716 -229.645972) (xy 385.928362 -229.623874) (xy 385.772914 -229.588314) (xy 385.642104 -229.814882)
			(xy 385.750562 -229.931722) (xy 385.788916 -229.95382)
		)
		(stroke
			(width 0)
			(type solid)
		)
		(fill yes)
		(layer "In4.Cu")
		(net "M_G_CPU0_SB_DQS_DP<7>")
	)
	(gr_poly
		(pts
			(xy 385.966716 -226.390454) (xy 385.928362 -226.368356) (xy 385.772914 -226.332796) (xy 385.642104 -226.559364)
			(xy 385.750562 -226.676204) (xy 385.788916 -226.698302)
		)
		(stroke
			(width 0)
			(type solid)
		)
		(fill yes)
		(layer "In4.Cu")
		(net "M_G_CPU0_SB_DQ<23>")
	)
	(gr_poly
		(pts
			(xy 385.967478 -231.271826) (xy 385.929124 -231.249728) (xy 385.773676 -231.214168) (xy 385.642866 -231.440736)
			(xy 385.751324 -231.557576) (xy 385.789678 -231.579674)
		)
		(stroke
			(width 0)
			(type solid)
		)
		(fill yes)
		(layer "In4.Cu")
		(net "M_G_CPU0_SB_DQS_DN<2>")
	)
	(gr_poly
		(pts
			(xy 385.968748 -228.014276) (xy 385.930394 -227.992178) (xy 385.774946 -227.956618) (xy 385.644136 -228.183186)
			(xy 385.752594 -228.300026) (xy 385.790948 -228.322124)
		)
		(stroke
			(width 0)
			(type solid)
		)
		(fill yes)
		(layer "In4.Cu")
		(net "M_G_CPU0_SB_DQ<22>")
	)
	(gr_poly
		(pts
			(xy 385.968748 -223.130872) (xy 385.930394 -223.108774) (xy 385.774946 -223.073214) (xy 385.644136 -223.299782)
			(xy 385.752594 -223.416622) (xy 385.790948 -223.43872)
		)
		(stroke
			(width 0)
			(type solid)
		)
		(fill yes)
		(layer "In4.Cu")
		(net "M_F_CPU0_SB_DQ<24>")
	)
	(gr_poly
		(pts
			(xy 386.033772 -271.467072) (xy 386.072126 -271.444974) (xy 385.894326 -271.137126) (xy 385.855972 -271.159224)
			(xy 385.747514 -271.276064) (xy 385.878324 -271.502632)
		)
		(stroke
			(width 0)
			(type solid)
		)
		(fill yes)
		(layer "In4.Cu")
		(net "M_F_CPU0_SA_DQS_DP<1>")
	)
	(gr_poly
		(pts
			(xy 386.03809 -276.357588) (xy 386.076444 -276.33549) (xy 385.898644 -276.027642) (xy 385.86029 -276.04974)
			(xy 385.751832 -276.16658) (xy 385.882642 -276.393148)
		)
		(stroke
			(width 0)
			(type solid)
		)
		(fill yes)
		(layer "In4.Cu")
		(net "M_G_CPU0_SA_DQ<4>")
	)
	(gr_poly
		(pts
			(xy 386.039106 -274.731734) (xy 386.07746 -274.709636) (xy 385.89966 -274.401788) (xy 385.861306 -274.423886)
			(xy 385.752848 -274.540726) (xy 385.883658 -274.767294)
		)
		(stroke
			(width 0)
			(type solid)
		)
		(fill yes)
		(layer "In4.Cu")
		(net "M_G_CPU0_SA_DQ<5>")
	)
	(gr_poly
		(pts
			(xy 386.063998 -240.057178) (xy 386.017008 -239.904778) (xy 385.755388 -239.904778) (xy 385.708398 -240.057178)
			(xy 385.708398 -240.101628) (xy 386.063998 -240.101628)
		)
		(stroke
			(width 0)
			(type solid)
		)
		(fill yes)
		(layer "In4.Cu")
		(net "M_G_CPU0_SB_CB<3>")
	)
	(gr_poly
		(pts
			(xy 386.063998 -239.649254) (xy 386.063998 -239.604804) (xy 385.708398 -239.604804) (xy 385.708398 -239.649254)
			(xy 385.755388 -239.801654) (xy 386.017008 -239.801654)
		)
		(stroke
			(width 0)
			(type solid)
		)
		(fill yes)
		(layer "In4.Cu")
		(net "M_F_CPU0_SB_DQ<0>")
	)
	(gr_poly
		(pts
			(xy 386.063998 -236.801914) (xy 386.017008 -236.649514) (xy 385.755388 -236.649514) (xy 385.708398 -236.801914)
			(xy 385.708398 -236.84611) (xy 386.063998 -236.84611)
		)
		(stroke
			(width 0)
			(type solid)
		)
		(fill yes)
		(layer "In4.Cu")
		(net "M_F_CPU0_SB_DQS_DP<5>")
	)
	(gr_poly
		(pts
			(xy 386.063998 -236.39399) (xy 386.063998 -236.34954) (xy 385.708398 -236.34954) (xy 385.708398 -236.39399)
			(xy 385.755388 -236.54639) (xy 386.017008 -236.54639)
		)
		(stroke
			(width 0)
			(type solid)
		)
		(fill yes)
		(layer "In4.Cu")
		(net "M_F_CPU0_SB_DQ<4>")
	)
	(gr_poly
		(pts
			(xy 386.063998 -235.174282) (xy 386.017008 -235.021882) (xy 385.755388 -235.021882) (xy 385.708398 -235.174282)
			(xy 385.708398 -235.218478) (xy 386.063998 -235.218478)
		)
		(stroke
			(width 0)
			(type solid)
		)
		(fill yes)
		(layer "In4.Cu")
		(net "M_F_CPU0_SB_DQ<7>")
	)
	(gr_poly
		(pts
			(xy 386.063998 -234.76585) (xy 386.063998 -234.721654) (xy 385.708398 -234.721654) (xy 385.708398 -234.76585)
			(xy 385.755388 -234.91825) (xy 386.017008 -234.91825)
		)
		(stroke
			(width 0)
			(type solid)
		)
		(fill yes)
		(layer "In4.Cu")
		(net "M_G_CPU0_SB_DQ<16>")
	)
	(gr_poly
		(pts
			(xy 386.072634 -244.53215) (xy 386.072634 -244.487954) (xy 385.717034 -244.487954) (xy 385.717034 -244.53215)
			(xy 385.764024 -244.68455) (xy 386.025644 -244.68455)
		)
		(stroke
			(width 0)
			(type solid)
		)
		(fill yes)
		(layer "In4.Cu")
		(net "M_G_CPU0_SB_CB<4>")
	)
	(gr_poly
		(pts
			(xy 386.072634 -242.904518) (xy 386.072634 -242.860322) (xy 385.717034 -242.860322) (xy 385.717034 -242.904518)
			(xy 385.764024 -243.056918) (xy 386.025644 -243.056918)
		)
		(stroke
			(width 0)
			(type solid)
		)
		(fill yes)
		(layer "In4.Cu")
		(net "M_G_CPU0_SB_DQS_DP<9>")
	)
	(gr_poly
		(pts
			(xy 386.072634 -241.685318) (xy 386.025644 -241.532918) (xy 385.764024 -241.532918) (xy 385.717034 -241.685318)
			(xy 385.717034 -241.729768) (xy 386.072634 -241.729768)
		)
		(stroke
			(width 0)
			(type solid)
		)
		(fill yes)
		(layer "In4.Cu")
		(net "M_G_CPU0_SB_DQS_DP<4>")
	)
	(gr_poly
		(pts
			(xy 386.072634 -241.276886) (xy 386.072634 -241.232436) (xy 385.717034 -241.232436) (xy 385.717034 -241.276886)
			(xy 385.764024 -241.429286) (xy 386.025644 -241.429286)
		)
		(stroke
			(width 0)
			(type solid)
		)
		(fill yes)
		(layer "In4.Cu")
		(net "M_G_CPU0_SB_CB<0>")
	)
	(gr_poly
		(pts
			(xy 386.072634 -238.430054) (xy 386.025644 -238.277654) (xy 385.764024 -238.277654) (xy 385.717034 -238.430054)
			(xy 385.717034 -238.47425) (xy 386.072634 -238.47425)
		)
		(stroke
			(width 0)
			(type solid)
		)
		(fill yes)
		(layer "In4.Cu")
		(net "M_F_CPU0_SB_DQ<3>")
	)
	(gr_poly
		(pts
			(xy 386.072634 -238.021114) (xy 386.072634 -237.976918) (xy 385.717034 -237.976918) (xy 385.717034 -238.021114)
			(xy 385.764024 -238.173514) (xy 386.025644 -238.173514)
		)
		(stroke
			(width 0)
			(type solid)
		)
		(fill yes)
		(layer "In4.Cu")
		(net "M_F_CPU0_SB_DQS_DP<0>")
	)
	(gr_poly
		(pts
			(xy 386.072634 -222.15221) (xy 386.025644 -221.99981) (xy 385.764024 -221.99981) (xy 385.717034 -222.15221)
			(xy 385.717034 -222.196406) (xy 386.072634 -222.196406)
		)
		(stroke
			(width 0)
			(type solid)
		)
		(fill yes)
		(layer "In4.Cu")
		(net "M_F_CPU0_SB_DQ<25>")
	)
	(gr_poly
		(pts
			(xy 386.072634 -221.74327) (xy 386.072634 -221.699074) (xy 385.717034 -221.699074) (xy 385.717034 -221.74327)
			(xy 385.764024 -221.89567) (xy 386.025644 -221.89567)
		)
		(stroke
			(width 0)
			(type solid)
		)
		(fill yes)
		(layer "In4.Cu")
		(net "M_F_CPU0_SB_DQS_DN<8>")
	)
	(gr_poly
		(pts
			(xy 386.072634 -220.52407) (xy 386.025644 -220.37167) (xy 385.764024 -220.37167) (xy 385.717034 -220.52407)
			(xy 385.717034 -220.56852) (xy 386.072634 -220.56852)
		)
		(stroke
			(width 0)
			(type solid)
		)
		(fill yes)
		(layer "In4.Cu")
		(net "M_F_CPU0_SB_DQS_DN<3>")
	)
	(gr_poly
		(pts
			(xy 386.081016 -220.115638) (xy 386.081016 -220.071442) (xy 385.725416 -220.071442) (xy 385.725416 -220.115638)
			(xy 385.772406 -220.268038) (xy 386.034026 -220.268038)
		)
		(stroke
			(width 0)
			(type solid)
		)
		(fill yes)
		(layer "In4.Cu")
		(net "M_F_CPU0_SB_DQ<30>")
	)
	(gr_poly
		(pts
			(xy 386.081016 -218.896438) (xy 386.034026 -218.744038) (xy 385.772406 -218.744038) (xy 385.725416 -218.896438)
			(xy 385.725416 -218.940634) (xy 386.081016 -218.940634)
		)
		(stroke
			(width 0)
			(type solid)
		)
		(fill yes)
		(layer "In4.Cu")
		(net "M_F_CPU0_SB_DQ<31>")
	)
	(gr_poly
		(pts
			(xy 386.147564 -233.61396) (xy 386.039106 -233.49712) (xy 386.000752 -233.475022) (xy 385.822952 -233.78287)
			(xy 385.861306 -233.804968) (xy 386.016754 -233.840528)
		)
		(stroke
			(width 0)
			(type solid)
		)
		(fill yes)
		(layer "In4.Cu")
		(net "M_G_CPU0_SB_DQ<17>")
	)
	(gr_poly
		(pts
			(xy 386.147564 -230.358442) (xy 386.039106 -230.241602) (xy 386.000752 -230.219504) (xy 385.822952 -230.527352)
			(xy 385.861306 -230.54945) (xy 386.016754 -230.58501)
		)
		(stroke
			(width 0)
			(type solid)
		)
		(fill yes)
		(layer "In4.Cu")
		(net "M_G_CPU0_SB_DQS_DN<7>")
	)
	(gr_poly
		(pts
			(xy 386.147564 -228.73081) (xy 386.039106 -228.61397) (xy 386.000752 -228.591872) (xy 385.822952 -228.89972)
			(xy 385.861306 -228.921818) (xy 386.016754 -228.957378)
		)
		(stroke
			(width 0)
			(type solid)
		)
		(fill yes)
		(layer "In4.Cu")
		(net "M_G_CPU0_SB_DQ<20>")
	)
	(gr_poly
		(pts
			(xy 386.147564 -227.102924) (xy 386.039106 -226.986084) (xy 386.000752 -226.963986) (xy 385.822952 -227.271834)
			(xy 385.861306 -227.293932) (xy 386.016754 -227.329492)
		)
		(stroke
			(width 0)
			(type solid)
		)
		(fill yes)
		(layer "In4.Cu")
		(net "M_G_CPU0_SB_DQ<21>")
	)
	(gr_poly
		(pts
			(xy 386.147564 -223.847406) (xy 386.039106 -223.730566) (xy 386.000752 -223.708468) (xy 385.822952 -224.016316)
			(xy 385.861306 -224.038414) (xy 386.016754 -224.073974)
		)
		(stroke
			(width 0)
			(type solid)
		)
		(fill yes)
		(layer "In4.Cu")
		(net "M_F_CPU0_SB_DQ<26>")
	)
	(gr_poly
		(pts
			(xy 386.147818 -275.73732) (xy 386.256276 -275.62048) (xy 386.125466 -275.393912) (xy 385.970018 -275.429472)
			(xy 385.931664 -275.45157) (xy 386.109464 -275.759418)
		)
		(stroke
			(width 0)
			(type solid)
		)
		(fill yes)
		(layer "In4.Cu")
		(net "M_G_CPU0_SA_DQ<6>")
	)
	(gr_poly
		(pts
			(xy 386.147818 -270.853916) (xy 386.256276 -270.737076) (xy 386.125466 -270.510508) (xy 385.970018 -270.546068)
			(xy 385.931664 -270.568166) (xy 386.109464 -270.876014)
		)
		(stroke
			(width 0)
			(type solid)
		)
		(fill yes)
		(layer "In4.Cu")
		(net "M_F_CPU0_SA_DQS_DN<1>")
	)
	(gr_poly
		(pts
			(xy 386.148834 -274.111974) (xy 386.257292 -273.995134) (xy 386.126482 -273.768566) (xy 385.971034 -273.804126)
			(xy 385.93268 -273.826224) (xy 386.11048 -274.134072)
		)
		(stroke
			(width 0)
			(type solid)
		)
		(fill yes)
		(layer "In4.Cu")
		(net "M_G_CPU0_SA_DQ<7>")
	)
	(gr_poly
		(pts
			(xy 386.151882 -231.978962) (xy 386.043424 -231.862122) (xy 386.00507 -231.840024) (xy 385.82727 -232.147872)
			(xy 385.865624 -232.16997) (xy 386.021072 -232.20553)
		)
		(stroke
			(width 0)
			(type solid)
		)
		(fill yes)
		(layer "In4.Cu")
		(net "M_G_CPU0_SB_DQS_DP<2>")
	)
	(gr_poly
		(pts
			(xy 386.173726 -259.412994) (xy 386.173726 -259.368544) (xy 385.818126 -259.368544) (xy 385.818126 -259.412994)
			(xy 385.865116 -259.565394) (xy 386.126736 -259.565394)
		)
		(stroke
			(width 0)
			(type solid)
		)
		(fill yes)
		(layer "In4.Cu")
		(net "M_F_CPU0_SA_DQ<28>")
	)
	(gr_poly
		(pts
			(xy 386.17398 -272.435066) (xy 386.17398 -272.39087) (xy 385.81838 -272.39087) (xy 385.81838 -272.435066)
			(xy 385.86537 -272.587466) (xy 386.12699 -272.587466)
		)
		(stroke
			(width 0)
			(type solid)
		)
		(fill yes)
		(layer "In4.Cu")
		(net "M_F_CPU0_SA_DQ<9>")
	)
	(gr_poly
		(pts
			(xy 386.17398 -269.587726) (xy 386.12699 -269.435326) (xy 385.86537 -269.435326) (xy 385.81838 -269.587726)
			(xy 385.81838 -269.631922) (xy 386.17398 -269.631922)
		)
		(stroke
			(width 0)
			(type solid)
		)
		(fill yes)
		(layer "In4.Cu")
		(net "M_F_CPU0_SA_DQS_DP<6>")
	)
	(gr_poly
		(pts
			(xy 386.182108 -261.040118) (xy 386.182108 -260.995668) (xy 385.826508 -260.995668) (xy 385.826508 -261.040118)
			(xy 385.873498 -261.192518) (xy 386.135118 -261.192518)
		)
		(stroke
			(width 0)
			(type solid)
		)
		(fill yes)
		(layer "In4.Cu")
		(net "M_F_CPU0_SA_DQS_DP<3>")
	)
	(gr_poly
		(pts
			(xy 386.182108 -259.821934) (xy 386.135118 -259.669534) (xy 385.873498 -259.669534) (xy 385.826508 -259.821934)
			(xy 385.826508 -259.86613) (xy 386.182108 -259.86613)
		)
		(stroke
			(width 0)
			(type solid)
		)
		(fill yes)
		(layer "In4.Cu")
		(net "M_F_CPU0_SA_DQS_DP<8>")
	)
	(gr_poly
		(pts
			(xy 386.182362 -277.726902) (xy 386.135372 -277.574502) (xy 385.873752 -277.574502) (xy 385.826762 -277.726902)
			(xy 385.826762 -277.771098) (xy 386.182362 -277.771098)
		)
		(stroke
			(width 0)
			(type solid)
		)
		(fill yes)
		(layer "In4.Cu")
		(net "M_G_CPU0_SA_DQS_DN<0>")
	)
	(gr_poly
		(pts
			(xy 386.182362 -277.317962) (xy 386.182362 -277.273766) (xy 385.826762 -277.273766) (xy 385.826762 -277.317962)
			(xy 385.873752 -277.470362) (xy 386.135372 -277.470362)
		)
		(stroke
			(width 0)
			(type solid)
		)
		(fill yes)
		(layer "In4.Cu")
		(net "M_G_CPU0_SA_DQS_DN<5>")
	)
	(gr_poly
		(pts
			(xy 386.182362 -272.843498) (xy 386.135372 -272.691098) (xy 385.873752 -272.691098) (xy 385.826762 -272.843498)
			(xy 385.826762 -272.887948) (xy 386.182362 -272.887948)
		)
		(stroke
			(width 0)
			(type solid)
		)
		(fill yes)
		(layer "In4.Cu")
		(net "M_F_CPU0_SA_DQ<10>")
	)
	(gr_poly
		(pts
			(xy 386.182362 -269.179294) (xy 386.182362 -269.134844) (xy 385.826762 -269.134844) (xy 385.826762 -269.179294)
			(xy 385.873752 -269.331694) (xy 386.135372 -269.331694)
		)
		(stroke
			(width 0)
			(type solid)
		)
		(fill yes)
		(layer "In4.Cu")
		(net "M_F_CPU0_SA_DQ<12>")
	)
	(gr_poly
		(pts
			(xy 386.182362 -267.960094) (xy 386.135372 -267.807694) (xy 385.873752 -267.807694) (xy 385.826762 -267.960094)
			(xy 385.826762 -268.004544) (xy 386.182362 -268.004544)
		)
		(stroke
			(width 0)
			(type solid)
		)
		(fill yes)
		(layer "In4.Cu")
		(net "M_F_CPU0_SA_DQ<13>")
	)
	(gr_poly
		(pts
			(xy 386.182362 -261.449058) (xy 386.135372 -261.296658) (xy 385.873752 -261.296658) (xy 385.826762 -261.449058)
			(xy 385.826762 -261.493508) (xy 386.182362 -261.493508)
		)
		(stroke
			(width 0)
			(type solid)
		)
		(fill yes)
		(layer "In4.Cu")
		(net "M_F_CPU0_SA_DQ<27>")
	)
	(gr_poly
		(pts
			(xy 386.188458 -262.668258) (xy 386.188458 -262.624062) (xy 385.832858 -262.624062) (xy 385.832858 -262.668258)
			(xy 385.879848 -262.820658) (xy 386.141468 -262.820658)
		)
		(stroke
			(width 0)
			(type solid)
		)
		(fill yes)
		(layer "In4.Cu")
		(net "M_F_CPU0_SA_DQ<24>")
	)
	(gr_poly
		(pts
			(xy 386.190998 -258.193286) (xy 386.144008 -258.040886) (xy 385.882388 -258.040886) (xy 385.835398 -258.193286)
			(xy 385.835398 -258.237482) (xy 386.190998 -258.237482)
		)
		(stroke
			(width 0)
			(type solid)
		)
		(fill yes)
		(layer "In4.Cu")
		(net "M_F_CPU0_SA_DQ<31>")
	)
	(gr_poly
		(pts
			(xy 386.430266 -230.469948) (xy 386.391912 -230.44785) (xy 386.236464 -230.41229) (xy 386.105654 -230.638858)
			(xy 386.214112 -230.755698) (xy 386.252466 -230.777796)
		)
		(stroke
			(width 0)
			(type solid)
		)
		(fill yes)
		(layer "In4.Cu")
		(net "M_G_CPU0_SB_DQS_DN<2>")
	)
	(gr_poly
		(pts
			(xy 386.432044 -227.211382) (xy 386.39369 -227.189284) (xy 386.238242 -227.153724) (xy 386.107432 -227.380292)
			(xy 386.21589 -227.497132) (xy 386.254244 -227.51923)
		)
		(stroke
			(width 0)
			(type solid)
		)
		(fill yes)
		(layer "In4.Cu")
		(net "M_G_CPU0_SB_DQ<22>")
	)
	(gr_poly
		(pts
			(xy 386.436362 -228.831902) (xy 386.398008 -228.809804) (xy 386.24256 -228.774244) (xy 386.11175 -229.000812)
			(xy 386.220208 -229.117652) (xy 386.258562 -229.13975)
		)
		(stroke
			(width 0)
			(type solid)
		)
		(fill yes)
		(layer "In4.Cu")
		(net "M_G_CPU0_SB_DQS_DP<7>")
	)
	(gr_poly
		(pts
			(xy 386.436616 -232.087674) (xy 386.398262 -232.065576) (xy 386.242814 -232.030016) (xy 386.112004 -232.256584)
			(xy 386.220462 -232.373424) (xy 386.258816 -232.395522)
		)
		(stroke
			(width 0)
			(type solid)
		)
		(fill yes)
		(layer "In4.Cu")
		(net "M_G_CPU0_SB_DQ<19>")
	)
	(gr_poly
		(pts
			(xy 386.438648 -233.711496) (xy 386.400294 -233.689398) (xy 386.244846 -233.653838) (xy 386.114036 -233.880406)
			(xy 386.222494 -233.997246) (xy 386.260848 -234.019344)
		)
		(stroke
			(width 0)
			(type solid)
		)
		(fill yes)
		(layer "In4.Cu")
		(net "M_G_CPU0_SB_DQ<18>")
	)
	(gr_poly
		(pts
			(xy 386.50926 -270.662908) (xy 386.547614 -270.64081) (xy 386.369814 -270.332962) (xy 386.33146 -270.35506)
			(xy 386.223002 -270.4719) (xy 386.353812 -270.698468)
		)
		(stroke
			(width 0)
			(type solid)
		)
		(fill yes)
		(layer "In4.Cu")
		(net "M_F_CPU0_SA_DQS_DN<6>")
	)
	(gr_poly
		(pts
			(xy 386.533898 -219.710254) (xy 386.486908 -219.557854) (xy 386.225288 -219.557854) (xy 386.178298 -219.710254)
			(xy 386.178298 -219.75445) (xy 386.533898 -219.75445)
		)
		(stroke
			(width 0)
			(type solid)
		)
		(fill yes)
		(layer "In4.Cu")
		(net "M_F_CPU0_SB_DQ<28>")
	)
	(gr_poly
		(pts
			(xy 386.533898 -219.301822) (xy 386.533898 -219.257626) (xy 386.178298 -219.257626) (xy 386.178298 -219.301822)
			(xy 386.225288 -219.454222) (xy 386.486908 -219.454222)
		)
		(stroke
			(width 0)
			(type solid)
		)
		(fill yes)
		(layer "In4.Cu")
		(net "M_F_CPU0_SB_DQ<29>")
	)
	(gr_poly
		(pts
			(xy 386.536438 -222.966026) (xy 386.489448 -222.813626) (xy 386.227828 -222.813626) (xy 386.180838 -222.966026)
			(xy 386.180838 -223.010222) (xy 386.536438 -223.010222)
		)
		(stroke
			(width 0)
			(type solid)
		)
		(fill yes)
		(layer "In4.Cu")
		(net "M_F_CPU0_SB_DQ<24>")
	)
	(gr_poly
		(pts
			(xy 386.536438 -222.557086) (xy 386.536438 -222.51289) (xy 386.180838 -222.51289) (xy 386.180838 -222.557086)
			(xy 386.227828 -222.709486) (xy 386.489448 -222.709486)
		)
		(stroke
			(width 0)
			(type solid)
		)
		(fill yes)
		(layer "In4.Cu")
		(net "M_F_CPU0_SB_DQ<27>")
	)
	(gr_poly
		(pts
			(xy 386.54228 -221.338394) (xy 386.49529 -221.185994) (xy 386.23367 -221.185994) (xy 386.18668 -221.338394)
			(xy 386.18668 -221.382844) (xy 386.54228 -221.382844)
		)
		(stroke
			(width 0)
			(type solid)
		)
		(fill yes)
		(layer "In4.Cu")
		(net "M_F_CPU0_SB_DQS_DP<8>")
	)
	(gr_poly
		(pts
			(xy 386.542534 -242.090702) (xy 386.542534 -242.046252) (xy 386.186934 -242.046252) (xy 386.186934 -242.090702)
			(xy 386.233924 -242.243102) (xy 386.495544 -242.243102)
		)
		(stroke
			(width 0)
			(type solid)
		)
		(fill yes)
		(layer "In4.Cu")
		(net "M_G_CPU0_SB_DQS_DN<4>")
	)
	(gr_poly
		(pts
			(xy 386.542534 -238.83493) (xy 386.542534 -238.790734) (xy 386.186934 -238.790734) (xy 386.186934 -238.83493)
			(xy 386.233924 -238.98733) (xy 386.495544 -238.98733)
		)
		(stroke
			(width 0)
			(type solid)
		)
		(fill yes)
		(layer "In4.Cu")
		(net "M_F_CPU0_SB_DQ<1>")
	)
	(gr_poly
		(pts
			(xy 386.542534 -237.61573) (xy 386.495544 -237.46333) (xy 386.233924 -237.46333) (xy 386.186934 -237.61573)
			(xy 386.186934 -237.66018) (xy 386.542534 -237.66018)
		)
		(stroke
			(width 0)
			(type solid)
		)
		(fill yes)
		(layer "In4.Cu")
		(net "M_F_CPU0_SB_DQS_DN<0>")
	)
	(gr_poly
		(pts
			(xy 386.542534 -220.929454) (xy 386.542534 -220.885258) (xy 386.186934 -220.885258) (xy 386.186934 -220.929454)
			(xy 386.233924 -221.081854) (xy 386.495544 -221.081854)
		)
		(stroke
			(width 0)
			(type solid)
		)
		(fill yes)
		(layer "In4.Cu")
		(net "M_F_CPU0_SB_DQS_DP<3>")
	)
	(gr_poly
		(pts
			(xy 386.550916 -240.46307) (xy 386.550916 -240.418874) (xy 386.195316 -240.418874) (xy 386.195316 -240.46307)
			(xy 386.242306 -240.61547) (xy 386.503926 -240.61547)
		)
		(stroke
			(width 0)
			(type solid)
		)
		(fill yes)
		(layer "In4.Cu")
		(net "M_G_CPU0_SB_CB<1>")
	)
	(gr_poly
		(pts
			(xy 386.550916 -239.243362) (xy 386.503926 -239.090962) (xy 386.242306 -239.090962) (xy 386.195316 -239.243362)
			(xy 386.195316 -239.287812) (xy 386.550916 -239.287812)
		)
		(stroke
			(width 0)
			(type solid)
		)
		(fill yes)
		(layer "In4.Cu")
		(net "M_F_CPU0_SB_DQ<2>")
	)
	(gr_poly
		(pts
			(xy 386.550916 -237.207806) (xy 386.550916 -237.163356) (xy 386.195316 -237.163356) (xy 386.195316 -237.207806)
			(xy 386.242306 -237.360206) (xy 386.503926 -237.360206)
		)
		(stroke
			(width 0)
			(type solid)
		)
		(fill yes)
		(layer "In4.Cu")
		(net "M_F_CPU0_SB_DQS_DN<5>")
	)
	(gr_poly
		(pts
			(xy 386.550916 -235.988098) (xy 386.503926 -235.835698) (xy 386.242306 -235.835698) (xy 386.195316 -235.988098)
			(xy 386.195316 -236.032294) (xy 386.550916 -236.032294)
		)
		(stroke
			(width 0)
			(type solid)
		)
		(fill yes)
		(layer "In4.Cu")
		(net "M_F_CPU0_SB_DQ<6>")
	)
	(gr_poly
		(pts
			(xy 386.550916 -235.579666) (xy 386.550916 -235.53547) (xy 386.195316 -235.53547) (xy 386.195316 -235.579666)
			(xy 386.242306 -235.732066) (xy 386.503926 -235.732066)
		)
		(stroke
			(width 0)
			(type solid)
		)
		(fill yes)
		(layer "In4.Cu")
		(net "M_F_CPU0_SB_DQ<5>")
	)
	(gr_poly
		(pts
			(xy 386.615432 -227.920804) (xy 386.506974 -227.803964) (xy 386.46862 -227.781866) (xy 386.29082 -228.089714)
			(xy 386.329174 -228.111812) (xy 386.484622 -228.147372)
		)
		(stroke
			(width 0)
			(type solid)
		)
		(fill yes)
		(layer "In4.Cu")
		(net "M_G_CPU0_SB_DQ<20>")
	)
	(gr_poly
		(pts
			(xy 386.616448 -231.17429) (xy 386.50799 -231.05745) (xy 386.469636 -231.035352) (xy 386.291836 -231.3432)
			(xy 386.33019 -231.365298) (xy 386.485638 -231.400858)
		)
		(stroke
			(width 0)
			(type solid)
		)
		(fill yes)
		(layer "In4.Cu")
		(net "M_G_CPU0_SB_DQS_DP<2>")
	)
	(gr_poly
		(pts
			(xy 386.616702 -278.177498) (xy 386.72516 -278.060658) (xy 386.59435 -277.83409) (xy 386.438902 -277.86965)
			(xy 386.400548 -277.891748) (xy 386.578348 -278.199596)
		)
		(stroke
			(width 0)
			(type solid)
		)
		(fill yes)
		(layer "In4.Cu")
		(net "M_G_CPU0_SA_DQS_DN<0>")
	)
	(gr_poly
		(pts
			(xy 386.617464 -232.800144) (xy 386.509006 -232.683304) (xy 386.470652 -232.661206) (xy 386.292852 -232.969054)
			(xy 386.331206 -232.991152) (xy 386.486654 -233.026712)
		)
		(stroke
			(width 0)
			(type solid)
		)
		(fill yes)
		(layer "In4.Cu")
		(net "M_G_CPU0_SB_DQ<17>")
	)
	(gr_poly
		(pts
			(xy 386.617464 -229.544626) (xy 386.509006 -229.427786) (xy 386.470652 -229.405688) (xy 386.292852 -229.713536)
			(xy 386.331206 -229.735634) (xy 386.486654 -229.771194)
		)
		(stroke
			(width 0)
			(type solid)
		)
		(fill yes)
		(layer "In4.Cu")
		(net "M_G_CPU0_SB_DQS_DN<7>")
	)
	(gr_poly
		(pts
			(xy 386.617464 -226.289108) (xy 386.509006 -226.172268) (xy 386.470652 -226.15017) (xy 386.292852 -226.458018)
			(xy 386.331206 -226.480116) (xy 386.486654 -226.515676)
		)
		(stroke
			(width 0)
			(type solid)
		)
		(fill yes)
		(layer "In4.Cu")
		(net "M_G_CPU0_SB_DQ<21>")
	)
	(gr_poly
		(pts
			(xy 386.617972 -274.924012) (xy 386.72643 -274.807172) (xy 386.59562 -274.580604) (xy 386.440172 -274.616164)
			(xy 386.401818 -274.638262) (xy 386.579618 -274.94611)
		)
		(stroke
			(width 0)
			(type solid)
		)
		(fill yes)
		(layer "In4.Cu")
		(net "M_G_CPU0_SA_DQ<7>")
	)
	(gr_poly
		(pts
			(xy 386.617972 -270.040608) (xy 386.72643 -269.923768) (xy 386.59562 -269.6972) (xy 386.440172 -269.73276)
			(xy 386.401818 -269.754858) (xy 386.579618 -270.062706)
		)
		(stroke
			(width 0)
			(type solid)
		)
		(fill yes)
		(layer "In4.Cu")
		(net "M_F_CPU0_SA_DQS_DP<6>")
	)
	(gr_poly
		(pts
			(xy 386.621782 -234.420918) (xy 386.513324 -234.304078) (xy 386.47497 -234.28198) (xy 386.29717 -234.589828)
			(xy 386.335524 -234.611926) (xy 386.490972 -234.647486)
		)
		(stroke
			(width 0)
			(type solid)
		)
		(fill yes)
		(layer "In4.Cu")
		(net "M_G_CPU0_SB_DQ<16>")
	)
	(gr_poly
		(pts
			(xy 386.64388 -262.262874) (xy 386.59689 -262.110474) (xy 386.33527 -262.110474) (xy 386.28828 -262.262874)
			(xy 386.28828 -262.30707) (xy 386.64388 -262.30707)
		)
		(stroke
			(width 0)
			(type solid)
		)
		(fill yes)
		(layer "In4.Cu")
		(net "M_F_CPU0_SA_DQ<26>")
	)
	(gr_poly
		(pts
			(xy 386.652262 -268.77391) (xy 386.605272 -268.62151) (xy 386.343652 -268.62151) (xy 386.296662 -268.77391)
			(xy 386.296662 -268.81836) (xy 386.652262 -268.81836)
		)
		(stroke
			(width 0)
			(type solid)
		)
		(fill yes)
		(layer "In4.Cu")
		(net "M_F_CPU0_SA_DQ<14>")
	)
	(gr_poly
		(pts
			(xy 386.660898 -272.029174) (xy 386.613908 -271.876774) (xy 386.352288 -271.876774) (xy 386.305298 -272.029174)
			(xy 386.305298 -272.073624) (xy 386.660898 -272.073624)
		)
		(stroke
			(width 0)
			(type solid)
		)
		(fill yes)
		(layer "In4.Cu")
		(net "M_F_CPU0_SA_DQ<11>")
	)
	(gr_poly
		(pts
			(xy 386.660898 -271.62125) (xy 386.660898 -271.5768) (xy 386.305298 -271.5768) (xy 386.305298 -271.62125)
			(xy 386.352288 -271.77365) (xy 386.613908 -271.77365)
		)
		(stroke
			(width 0)
			(type solid)
		)
		(fill yes)
		(layer "In4.Cu")
		(net "M_F_CPU0_SA_DQS_DP<1>")
	)
	(gr_poly
		(pts
			(xy 386.901944 -234.536488) (xy 386.86359 -234.51439) (xy 386.708142 -234.47883) (xy 386.577332 -234.705398)
			(xy 386.68579 -234.822238) (xy 386.724144 -234.844336)
		)
		(stroke
			(width 0)
			(type solid)
		)
		(fill yes)
		(layer "In4.Cu")
		(net "M_F_CPU0_SB_DQ<7>")
	)
	(gr_poly
		(pts
			(xy 386.902706 -229.652576) (xy 386.864352 -229.630478) (xy 386.708904 -229.594918) (xy 386.578094 -229.821486)
			(xy 386.686552 -229.938326) (xy 386.724906 -229.960424)
		)
		(stroke
			(width 0)
			(type solid)
		)
		(fill yes)
		(layer "In4.Cu")
		(net "M_G_CPU0_SB_DQS_DN<2>")
	)
	(gr_poly
		(pts
			(xy 386.906516 -232.90149) (xy 386.868162 -232.879392) (xy 386.712714 -232.843832) (xy 386.581904 -233.0704)
			(xy 386.690362 -233.18724) (xy 386.728716 -233.209338)
		)
		(stroke
			(width 0)
			(type solid)
		)
		(fill yes)
		(layer "In4.Cu")
		(net "M_G_CPU0_SB_DQ<18>")
	)
	(gr_poly
		(pts
			(xy 386.908548 -231.269794) (xy 386.870194 -231.247696) (xy 386.714746 -231.212136) (xy 386.583936 -231.438704)
			(xy 386.692394 -231.555544) (xy 386.730748 -231.577642)
		)
		(stroke
			(width 0)
			(type solid)
		)
		(fill yes)
		(layer "In4.Cu")
		(net "M_G_CPU0_SB_DQ<19>")
	)
	(gr_poly
		(pts
			(xy 387.003798 -239.649254) (xy 387.003798 -239.604804) (xy 386.648198 -239.604804) (xy 386.648198 -239.649254)
			(xy 386.695188 -239.801654) (xy 386.956808 -239.801654)
		)
		(stroke
			(width 0)
			(type solid)
		)
		(fill yes)
		(layer "In4.Cu")
		(net "M_F_CPU0_SB_DQ<0>")
	)
	(gr_poly
		(pts
			(xy 387.003798 -236.801914) (xy 386.956808 -236.649514) (xy 386.695188 -236.649514) (xy 386.648198 -236.801914)
			(xy 386.648198 -236.84611) (xy 387.003798 -236.84611)
		)
		(stroke
			(width 0)
			(type solid)
		)
		(fill yes)
		(layer "In4.Cu")
		(net "M_F_CPU0_SB_DQS_DP<5>")
	)
	(gr_poly
		(pts
			(xy 387.003798 -236.39399) (xy 387.003798 -236.34954) (xy 386.648198 -236.34954) (xy 386.648198 -236.39399)
			(xy 386.695188 -236.54639) (xy 386.956808 -236.54639)
		)
		(stroke
			(width 0)
			(type solid)
		)
		(fill yes)
		(layer "In4.Cu")
		(net "M_F_CPU0_SB_DQ<4>")
	)
	(gr_poly
		(pts
			(xy 387.012434 -238.021114) (xy 387.012434 -237.976918) (xy 386.656834 -237.976918) (xy 386.656834 -238.021114)
			(xy 386.703824 -238.173514) (xy 386.965444 -238.173514)
		)
		(stroke
			(width 0)
			(type solid)
		)
		(fill yes)
		(layer "In4.Cu")
		(net "M_F_CPU0_SB_DQS_DP<0>")
	)
	(gr_poly
		(pts
			(xy 387.020816 -220.115638) (xy 387.020816 -220.071442) (xy 386.665216 -220.071442) (xy 386.665216 -220.115638)
			(xy 386.712206 -220.268038) (xy 386.973826 -220.268038)
		)
		(stroke
			(width 0)
			(type solid)
		)
		(fill yes)
		(layer "In4.Cu")
		(net "M_F_CPU0_SB_DQ<30>")
	)
	(gr_poly
		(pts
			(xy 387.085332 -233.618024) (xy 386.976874 -233.501184) (xy 386.93852 -233.479086) (xy 386.76072 -233.786934)
			(xy 386.799074 -233.809032) (xy 386.954522 -233.844592)
		)
		(stroke
			(width 0)
			(type solid)
		)
		(fill yes)
		(layer "In4.Cu")
		(net "M_G_CPU0_SB_DQ<16>")
	)
	(gr_poly
		(pts
			(xy 387.086094 -235.244386) (xy 386.977636 -235.127546) (xy 386.939282 -235.105448) (xy 386.761482 -235.413296)
			(xy 386.799836 -235.435394) (xy 386.955284 -235.470954)
		)
		(stroke
			(width 0)
			(type solid)
		)
		(fill yes)
		(layer "In4.Cu")
		(net "M_F_CPU0_SB_DQ<5>")
	)
	(gr_poly
		(pts
			(xy 387.086094 -227.105464) (xy 386.977636 -226.988624) (xy 386.939282 -226.966526) (xy 386.761482 -227.274374)
			(xy 386.799836 -227.296472) (xy 386.955284 -227.332032)
		)
		(stroke
			(width 0)
			(type solid)
		)
		(fill yes)
		(layer "In4.Cu")
		(net "M_G_CPU0_SB_DQ<20>")
	)
	(gr_poly
		(pts
			(xy 387.087364 -231.986328) (xy 386.978906 -231.869488) (xy 386.940552 -231.84739) (xy 386.762752 -232.155238)
			(xy 386.801106 -232.177336) (xy 386.956554 -232.212896)
		)
		(stroke
			(width 0)
			(type solid)
		)
		(fill yes)
		(layer "In4.Cu")
		(net "M_G_CPU0_SB_DQ<17>")
	)
	(gr_poly
		(pts
			(xy 387.087364 -230.358442) (xy 386.978906 -230.241602) (xy 386.940552 -230.219504) (xy 386.762752 -230.527352)
			(xy 386.801106 -230.54945) (xy 386.956554 -230.58501)
		)
		(stroke
			(width 0)
			(type solid)
		)
		(fill yes)
		(layer "In4.Cu")
		(net "M_G_CPU0_SB_DQS_DP<2>")
	)
	(gr_poly
		(pts
			(xy 387.087618 -228.73081) (xy 386.97916 -228.61397) (xy 386.940806 -228.591872) (xy 386.763006 -228.89972)
			(xy 386.80136 -228.921818) (xy 386.956808 -228.957378)
		)
		(stroke
			(width 0)
			(type solid)
		)
		(fill yes)
		(layer "In4.Cu")
		(net "M_G_CPU0_SB_DQS_DN<7>")
	)
	(gr_poly
		(pts
			(xy 387.130798 -262.668258) (xy 387.130798 -262.624062) (xy 386.775198 -262.624062) (xy 386.775198 -262.668258)
			(xy 386.822188 -262.820658) (xy 387.083808 -262.820658)
		)
		(stroke
			(width 0)
			(type solid)
		)
		(fill yes)
		(layer "In4.Cu")
		(net "M_F_CPU0_SA_DQ<24>")
	)
	(gr_poly
		(pts
			(xy 387.376416 -232.087674) (xy 387.338062 -232.065576) (xy 387.182614 -232.030016) (xy 387.051804 -232.256584)
			(xy 387.160262 -232.373424) (xy 387.198616 -232.395522)
		)
		(stroke
			(width 0)
			(type solid)
		)
		(fill yes)
		(layer "In4.Cu")
		(net "M_G_CPU0_SB_DQ<18>")
	)
	(gr_poly
		(pts
			(xy 387.376416 -230.459788) (xy 387.338062 -230.43769) (xy 387.182614 -230.40213) (xy 387.051804 -230.628698)
			(xy 387.160262 -230.745538) (xy 387.198616 -230.767636)
		)
		(stroke
			(width 0)
			(type solid)
		)
		(fill yes)
		(layer "In4.Cu")
		(net "M_G_CPU0_SB_DQ<19>")
	)
	(gr_poly
		(pts
			(xy 387.377432 -235.340652) (xy 387.339078 -235.318554) (xy 387.18363 -235.282994) (xy 387.05282 -235.509562)
			(xy 387.161278 -235.626402) (xy 387.199632 -235.6485)
		)
		(stroke
			(width 0)
			(type solid)
		)
		(fill yes)
		(layer "In4.Cu")
		(net "M_F_CPU0_SB_DQ<6>")
	)
	(gr_poly
		(pts
			(xy 387.555232 -231.176322) (xy 387.446774 -231.059482) (xy 387.40842 -231.037384) (xy 387.23062 -231.345232)
			(xy 387.268974 -231.36733) (xy 387.424422 -231.40289)
		)
		(stroke
			(width 0)
			(type solid)
		)
		(fill yes)
		(layer "In4.Cu")
		(net "M_G_CPU0_SB_DQ<17>")
	)
	(gr_poly
		(pts
			(xy 387.556248 -236.057694) (xy 387.44779 -235.940854) (xy 387.409436 -235.918756) (xy 387.231636 -236.226604)
			(xy 387.26999 -236.248702) (xy 387.425438 -236.284262)
		)
		(stroke
			(width 0)
			(type solid)
		)
		(fill yes)
		(layer "In4.Cu")
		(net "M_F_CPU0_SB_DQ<4>")
	)
	(gr_poly
		(pts
			(xy 387.557264 -232.800144) (xy 387.448806 -232.683304) (xy 387.410452 -232.661206) (xy 387.232652 -232.969054)
			(xy 387.271006 -232.991152) (xy 387.426454 -233.026712)
		)
		(stroke
			(width 0)
			(type solid)
		)
		(fill yes)
		(layer "In4.Cu")
		(net "M_G_CPU0_SB_DQ<16>")
	)
	(gr_poly
		(pts
			(xy 387.58368 -262.262874) (xy 387.53669 -262.110474) (xy 387.27507 -262.110474) (xy 387.22808 -262.262874)
			(xy 387.22808 -262.30707) (xy 387.58368 -262.30707)
		)
		(stroke
			(width 0)
			(type solid)
		)
		(fill yes)
		(layer "In4.Cu")
		(net "M_F_CPU0_SA_DQ<26>")
	)
	(gr_poly
		(pts
			(xy 249.511312 -89.374472) (xy 249.511312 -86.478872) (xy 249.333512 -86.301072) (xy 245.904512 -86.301072)
			(xy 245.752112 -86.453472) (xy 245.752112 -89.653872) (xy 245.929912 -89.831672) (xy 249.054112 -89.831672)
		)
		(stroke
			(width 0)
			(type solid)
		)
		(fill yes)
		(layer "In4.Cu")
		(net "GND")
	)
	(gr_poly
		(pts
			(xy 326.70242 -32.253428) (xy 326.70242 -31.360872) (xy 323.875908 -28.53436) (xy 323.57822 -28.53436)
			(xy 321.00901 -31.10357) (xy 321.00901 -31.812484) (xy 323.807074 -34.610548) (xy 324.3453 -34.610548)
		)
		(stroke
			(width 0)
			(type solid)
		)
		(fill yes)
		(layer "In4.Cu")
		(net "GND")
	)
	(gr_poly
		(pts
			(xy 337.936586 -70.187058) (xy 337.936586 -67.25412) (xy 337.568032 -66.885566) (xy 333.806038 -66.885566)
			(xy 333.422244 -67.26936) (xy 333.422244 -70.586092) (xy 333.54518 -70.709028) (xy 337.414616 -70.709028)
		)
		(stroke
			(width 0)
			(type solid)
		)
		(fill yes)
		(layer "In4.Cu")
		(net "GND")
	)
	(gr_poly
		(pts
			(xy 427.559216 -138.21791) (xy 427.559216 -134.61111) (xy 427.508416 -134.56031) (xy 423.901616 -134.56031)
			(xy 423.850816 -134.61111) (xy 423.850816 -138.21791) (xy 423.901616 -138.26871) (xy 427.508416 -138.26871)
		)
		(stroke
			(width 0)
			(type solid)
		)
		(fill yes)
		(layer "In4.Cu")
		(net "GND")
	)
	(gr_poly
		(pts
			(xy 217.33256 -26.947368) (xy 217.33256 -25.212548) (xy 216.7382 -24.618188) (xy 213.22538 -24.618188)
			(xy 213.03488 -24.808688) (xy 213.03488 -25.91054)
			(arc
				(start 213.040976 -25.92197)
				(mid 213.073902 -26.006606)
				(end 213.085172 -26.096722)
			)
			(xy 213.085172 -27.44724) (xy 213.26856 -27.630628) (xy 216.6493 -27.630628)
		)
		(stroke
			(width 0)
			(type solid)
		)
		(fill yes)
		(layer "In4.Cu")
		(net "GND")
	)
	(gr_poly
		(pts
			(xy 230.38054 -434.93182) (xy 230.38054 -427.00194) (xy 230.38689 -426.99559) (xy 230.38689 -423.32275)
			(xy 233.07548 -420.63416) (xy 270.3576 -420.63416) (xy 275.73224 -415.25952) (xy 279.97912 -415.25952)
			(xy 280.19756 -415.04108) (xy 280.19756 -408.29992) (xy 279.96896 -408.07132) (xy 239.84458 -408.07132)
			(xy 233.0704 -414.8455) (xy 207.34528 -414.8455) (xy 206.49184 -415.69894) (xy 206.49184 -435.39156)
			(xy 207.63484 -436.53456) (xy 228.7778 -436.53456)
		)
		(stroke
			(width 0)
			(type solid)
		)
		(fill yes)
		(layer "In4.Cu")
		(net "P12V_PSU")
	)
	(gr_poly
		(pts
			(arc
				(start 150.250652 -39.515288)
				(mid 150.54834 -39.354795)
				(end 150.846028 -39.515288)
			)
			(xy 151.5364 -39.515288) (xy 151.70658 -39.345108) (xy 151.70658 -35.753548) (xy 151.4348 -35.481768)
			(xy 148.99386 -35.481768) (xy 148.73224 -35.743388) (xy 148.73224 -39.238428) (xy 149.0091 -39.515288)
		)
		(stroke
			(width 0)
			(type solid)
		)
		(fill yes)
		(layer "In4.Cu")
		(net "GND")
	)
	(gr_poly
		(pts
			(arc
				(start 65.20561 -177.844958)
				(mid 65.308729 -177.775963)
				(end 65.4304 -177.75174)
			)
			(xy 65.893188 -177.75174) (xy 66.222372 -177.422556)
			(arc
				(start 66.222372 -176.781968)
				(mid 66.246662 -176.660325)
				(end 66.31559 -176.557178)
			)
			(xy 66.90614 -175.966628) (xy 66.90614 -172.09897) (xy 65.90284 -171.09567) (xy 61.061854 -171.09567)
			(xy 60.661804 -171.49572) (xy 60.661804 -178.238912) (xy 61.47562 -179.052728) (xy 63.99784 -179.052728)
		)
		(stroke
			(width 0)
			(type solid)
		)
		(fill yes)
		(layer "In4.Cu")
		(net "PVCCFA_EHV_CPU1")
	)
	(gr_poly
		(pts
			(arc
				(start 309.437786 -63.464948)
				(mid 309.163974 -63.464948)
				(end 309.437786 -63.464948)
			)
		)
		(stroke
			(width 0)
			(type solid)
		)
		(fill yes)
		(layer "In4.Cu")
		(net "GND")
	)
	(gr_poly
		(pts
			(arc
				(start 19.360134 -383.527808)
				(mid 19.040094 -383.527808)
				(end 19.360134 -383.527808)
			)
		)
		(stroke
			(width 0)
			(type solid)
		)
		(fill yes)
		(layer "In4.Cu")
		(net "GND")
	)
	(gr_poly
		(pts
			(arc
				(start 20.618958 -383.527808)
				(mid 20.298918 -383.527808)
				(end 20.618958 -383.527808)
			)
		)
		(stroke
			(width 0)
			(type solid)
		)
		(fill yes)
		(layer "In4.Cu")
		(net "GND")
	)
	(gr_poly
		(pts
			(arc
				(start 22.635464 -383.567178)
				(mid 22.315424 -383.567178)
				(end 22.635464 -383.567178)
			)
		)
		(stroke
			(width 0)
			(type solid)
		)
		(fill yes)
		(layer "In4.Cu")
		(net "GND")
	)
	(gr_poly
		(pts
			(arc
				(start 23.894288 -383.567178)
				(mid 23.574248 -383.567178)
				(end 23.894288 -383.567178)
			)
		)
		(stroke
			(width 0)
			(type solid)
		)
		(fill yes)
		(layer "In4.Cu")
		(net "GND")
	)
	(gr_poly
		(pts
			(arc
				(start 36.92906 -384.779012)
				(mid 36.60902 -384.779012)
				(end 36.92906 -384.779012)
			)
		)
		(stroke
			(width 0)
			(type solid)
		)
		(fill yes)
		(layer "In4.Cu")
		(net "GND")
	)
	(gr_poly
		(pts
			(arc
				(start 37.125656 -399.293334)
				(mid 36.805616 -399.293334)
				(end 37.125656 -399.293334)
			)
		)
		(stroke
			(width 0)
			(type solid)
		)
		(fill yes)
		(layer "In4.Cu")
		(net "GND")
	)
	(gr_poly
		(pts
			(arc
				(start 38.187884 -384.779012)
				(mid 37.867844 -384.779012)
				(end 38.187884 -384.779012)
			)
		)
		(stroke
			(width 0)
			(type solid)
		)
		(fill yes)
		(layer "In4.Cu")
		(net "GND")
	)
	(gr_poly
		(pts
			(arc
				(start 38.38448 -399.293334)
				(mid 38.06444 -399.293334)
				(end 38.38448 -399.293334)
			)
		)
		(stroke
			(width 0)
			(type solid)
		)
		(fill yes)
		(layer "In4.Cu")
		(net "GND")
	)
	(gr_poly
		(pts
			(arc
				(start 41.798748 -386.20954)
				(mid 41.478708 -386.20954)
				(end 41.798748 -386.20954)
			)
		)
		(stroke
			(width 0)
			(type solid)
		)
		(fill yes)
		(layer "In4.Cu")
		(net "GND")
	)
	(gr_poly
		(pts
			(arc
				(start 42.447972 -399.405856)
				(mid 42.127932 -399.405856)
				(end 42.447972 -399.405856)
			)
		)
		(stroke
			(width 0)
			(type solid)
		)
		(fill yes)
		(layer "In4.Cu")
		(net "GND")
	)
	(gr_poly
		(pts
			(arc
				(start 43.057572 -386.20954)
				(mid 42.737532 -386.20954)
				(end 43.057572 -386.20954)
			)
		)
		(stroke
			(width 0)
			(type solid)
		)
		(fill yes)
		(layer "In4.Cu")
		(net "GND")
	)
	(gr_poly
		(pts
			(arc
				(start 43.706796 -399.405856)
				(mid 43.386756 -399.405856)
				(end 43.706796 -399.405856)
			)
		)
		(stroke
			(width 0)
			(type solid)
		)
		(fill yes)
		(layer "In4.Cu")
		(net "GND")
	)
	(gr_poly
		(pts
			(arc
				(start 98.496628 -401.995386)
				(mid 98.176588 -401.995386)
				(end 98.496628 -401.995386)
			)
		)
		(stroke
			(width 0)
			(type solid)
		)
		(fill yes)
		(layer "In4.Cu")
		(net "GND")
	)
	(gr_poly
		(pts
			(arc
				(start 99.755452 -401.995386)
				(mid 99.435412 -401.995386)
				(end 99.755452 -401.995386)
			)
		)
		(stroke
			(width 0)
			(type solid)
		)
		(fill yes)
		(layer "In4.Cu")
		(net "GND")
	)
	(gr_poly
		(pts
			(arc
				(start 102.220268 -410.579824)
				(mid 101.900228 -410.579824)
				(end 102.220268 -410.579824)
			)
		)
		(stroke
			(width 0)
			(type solid)
		)
		(fill yes)
		(layer "In4.Cu")
		(net "GND")
	)
	(gr_poly
		(pts
			(arc
				(start 103.479092 -410.579824)
				(mid 103.159052 -410.579824)
				(end 103.479092 -410.579824)
			)
		)
		(stroke
			(width 0)
			(type solid)
		)
		(fill yes)
		(layer "In4.Cu")
		(net "GND")
	)
	(gr_poly
		(pts
			(arc
				(start 104.78516 -413.80918)
				(mid 104.46512 -413.80918)
				(end 104.78516 -413.80918)
			)
		)
		(stroke
			(width 0)
			(type solid)
		)
		(fill yes)
		(layer "In4.Cu")
		(net "GND")
	)
	(gr_poly
		(pts
			(arc
				(start 104.78516 -412.550356)
				(mid 104.46512 -412.550356)
				(end 104.78516 -412.550356)
			)
		)
		(stroke
			(width 0)
			(type solid)
		)
		(fill yes)
		(layer "In4.Cu")
		(net "GND")
	)
	(gr_poly
		(pts
			(arc
				(start 106.586528 -406.477724)
				(mid 106.266488 -406.477724)
				(end 106.586528 -406.477724)
			)
		)
		(stroke
			(width 0)
			(type solid)
		)
		(fill yes)
		(layer "In4.Cu")
		(net "GND")
	)
	(gr_poly
		(pts
			(arc
				(start 107.845352 -406.477724)
				(mid 107.525312 -406.477724)
				(end 107.845352 -406.477724)
			)
		)
		(stroke
			(width 0)
			(type solid)
		)
		(fill yes)
		(layer "In4.Cu")
		(net "GND")
	)
	(gr_poly
		(pts
			(arc
				(start 111.300768 -419.04158)
				(mid 110.980728 -419.04158)
				(end 111.300768 -419.04158)
			)
		)
		(stroke
			(width 0)
			(type solid)
		)
		(fill yes)
		(layer "In4.Cu")
		(net "GND")
	)
	(gr_poly
		(pts
			(arc
				(start 112.559592 -419.04158)
				(mid 112.239552 -419.04158)
				(end 112.559592 -419.04158)
			)
		)
		(stroke
			(width 0)
			(type solid)
		)
		(fill yes)
		(layer "In4.Cu")
		(net "GND")
	)
	(gr_poly
		(pts
			(arc
				(start 116.597176 -414.0073)
				(mid 116.277136 -414.0073)
				(end 116.597176 -414.0073)
			)
		)
		(stroke
			(width 0)
			(type solid)
		)
		(fill yes)
		(layer "In4.Cu")
		(net "GND")
	)
	(gr_poly
		(pts
			(arc
				(start 116.597176 -412.748476)
				(mid 116.277136 -412.748476)
				(end 116.597176 -412.748476)
			)
		)
		(stroke
			(width 0)
			(type solid)
		)
		(fill yes)
		(layer "In4.Cu")
		(net "GND")
	)
	(gr_poly
		(pts
			(arc
				(start 355.44379 -44.998386)
				(mid 355.13137 -44.998386)
				(end 355.44379 -44.998386)
			)
		)
		(stroke
			(width 0)
			(type solid)
		)
		(fill yes)
		(layer "In4.Cu")
		(net "GND")
	)
	(gr_poly
		(pts
			(arc
				(start 356.329742 -46.802802)
				(mid 356.017322 -46.802802)
				(end 356.329742 -46.802802)
			)
		)
		(stroke
			(width 0)
			(type solid)
		)
		(fill yes)
		(layer "In4.Cu")
		(net "GND")
	)
	(gr_poly
		(pts
			(arc
				(start 357.689912 -44.998386)
				(mid 357.377492 -44.998386)
				(end 357.689912 -44.998386)
			)
		)
		(stroke
			(width 0)
			(type solid)
		)
		(fill yes)
		(layer "In4.Cu")
		(net "GND")
	)
	(gr_poly
		(pts
			(arc
				(start 358.575864 -46.802802)
				(mid 358.263444 -46.802802)
				(end 358.575864 -46.802802)
			)
		)
		(stroke
			(width 0)
			(type solid)
		)
		(fill yes)
		(layer "In4.Cu")
		(net "GND")
	)
	(gr_poly
		(pts
			(arc
				(start 360.892598 -46.802802)
				(mid 360.580178 -46.802802)
				(end 360.892598 -46.802802)
			)
		)
		(stroke
			(width 0)
			(type solid)
		)
		(fill yes)
		(layer "In4.Cu")
		(net "GND")
	)
	(gr_poly
		(pts
			(arc
				(start 363.219238 -46.802802)
				(mid 362.906818 -46.802802)
				(end 363.219238 -46.802802)
			)
		)
		(stroke
			(width 0)
			(type solid)
		)
		(fill yes)
		(layer "In4.Cu")
		(net "GND")
	)
	(gr_poly
		(pts
			(xy 41.025318 -366.59693)
			(arc
				(start 41.025318 -360.969052)
				(mid 41.021417 -360.949529)
				(end 41.010332 -360.932984)
			)
			(arc
				(start 40.877744 -360.800396)
				(mid 40.86121 -360.789285)
				(end 40.841676 -360.78541)
			)
			(arc
				(start 36.86048 -360.78541)
				(mid 36.840957 -360.781509)
				(end 36.824412 -360.770424)
			)
			(arc
				(start 33.882584 -357.828596)
				(mid 33.871473 -357.812062)
				(end 33.867598 -357.792528)
			)
			(arc
				(start 33.867598 -338.998052)
				(mid 33.863697 -338.978529)
				(end 33.852612 -338.961984)
			)
			(arc
				(start 32.726884 -337.836256)
				(mid 32.71035 -337.825145)
				(end 32.690816 -337.82127)
			)
			(xy 16.09852 -337.82127) (xy 16.09852 -351.757488) (xy 20.03044 -355.689408) (xy 20.03044 -366.095788)
			(xy 20.9423 -367.007648) (xy 40.6146 -367.007648)
		)
		(stroke
			(width 0)
			(type solid)
		)
		(fill yes)
		(layer "In4.Cu")
		(net "P12V_AUX")
	)
	(gr_poly
		(pts
			(arc
				(start 327.924668 -75.452224)
				(mid 327.558908 -75.452224)
				(end 327.924668 -75.452224)
			)
		)
		(stroke
			(width 0)
			(type solid)
		)
		(fill yes)
		(layer "In4.Cu")
		(net "GND")
	)
	(gr_poly
		(pts
			(arc
				(start 329.183492 -75.452224)
				(mid 328.817732 -75.452224)
				(end 329.183492 -75.452224)
			)
		)
		(stroke
			(width 0)
			(type solid)
		)
		(fill yes)
		(layer "In4.Cu")
		(net "GND")
	)
	(gr_poly
		(pts
			(arc
				(start 331.17536 -77.257148)
				(mid 330.8096 -77.257148)
				(end 331.17536 -77.257148)
			)
		)
		(stroke
			(width 0)
			(type solid)
		)
		(fill yes)
		(layer "In4.Cu")
		(net "GND")
	)
	(gr_poly
		(pts
			(arc
				(start 332.47076 -77.282548)
				(mid 332.105 -77.282548)
				(end 332.47076 -77.282548)
			)
		)
		(stroke
			(width 0)
			(type solid)
		)
		(fill yes)
		(layer "In4.Cu")
		(net "GND")
	)
	(gr_poly
		(pts
			(arc
				(start 335.24063 -75.32116)
				(mid 334.87487 -75.32116)
				(end 335.24063 -75.32116)
			)
		)
		(stroke
			(width 0)
			(type solid)
		)
		(fill yes)
		(layer "In4.Cu")
		(net "GND")
	)
	(gr_poly
		(pts
			(arc
				(start 336.499454 -75.32116)
				(mid 336.133694 -75.32116)
				(end 336.499454 -75.32116)
			)
		)
		(stroke
			(width 0)
			(type solid)
		)
		(fill yes)
		(layer "In4.Cu")
		(net "GND")
	)
	(gr_poly
		(pts
			(arc
				(start 336.640424 -73.89368)
				(mid 336.274664 -73.89368)
				(end 336.640424 -73.89368)
			)
		)
		(stroke
			(width 0)
			(type solid)
		)
		(fill yes)
		(layer "In4.Cu")
		(net "GND")
	)
	(gr_poly
		(pts
			(arc
				(start 337.899248 -73.89368)
				(mid 337.533488 -73.89368)
				(end 337.899248 -73.89368)
			)
		)
		(stroke
			(width 0)
			(type solid)
		)
		(fill yes)
		(layer "In4.Cu")
		(net "GND")
	)
	(gr_poly
		(pts
			(arc
				(start 341.396828 -71.92137)
				(mid 341.031068 -71.92137)
				(end 341.396828 -71.92137)
			)
		)
		(stroke
			(width 0)
			(type solid)
		)
		(fill yes)
		(layer "In4.Cu")
		(net "GND")
	)
	(gr_poly
		(pts
			(arc
				(start 342.920828 -71.92137)
				(mid 342.555068 -71.92137)
				(end 342.920828 -71.92137)
			)
		)
		(stroke
			(width 0)
			(type solid)
		)
		(fill yes)
		(layer "In4.Cu")
		(net "GND")
	)
	(gr_poly
		(pts
			(arc
				(start 344.073988 -73.03516)
				(mid 343.708228 -73.03516)
				(end 344.073988 -73.03516)
			)
		)
		(stroke
			(width 0)
			(type solid)
		)
		(fill yes)
		(layer "In4.Cu")
		(net "GND")
	)
	(gr_poly
		(pts
			(arc
				(start 345.597988 -73.03516)
				(mid 345.232228 -73.03516)
				(end 345.597988 -73.03516)
			)
		)
		(stroke
			(width 0)
			(type solid)
		)
		(fill yes)
		(layer "In4.Cu")
		(net "GND")
	)
	(gr_poly
		(pts
			(arc
				(start 346.599764 -71.081392)
				(mid 346.234004 -71.081392)
				(end 346.599764 -71.081392)
			)
		)
		(stroke
			(width 0)
			(type solid)
		)
		(fill yes)
		(layer "In4.Cu")
		(net "GND")
	)
	(gr_poly
		(pts
			(arc
				(start 348.123764 -71.081392)
				(mid 347.758004 -71.081392)
				(end 348.123764 -71.081392)
			)
		)
		(stroke
			(width 0)
			(type solid)
		)
		(fill yes)
		(layer "In4.Cu")
		(net "GND")
	)
	(gr_poly
		(pts
			(arc
				(start 351.5868 -22.588728)
				(mid 351.22104 -22.588728)
				(end 351.5868 -22.588728)
			)
		)
		(stroke
			(width 0)
			(type solid)
		)
		(fill yes)
		(layer "In4.Cu")
		(net "GND")
	)
	(gr_poly
		(pts
			(arc
				(start 355.82987 -60.517278)
				(mid 355.475286 -60.517278)
				(end 355.82987 -60.517278)
			)
		)
		(stroke
			(width 0)
			(type solid)
		)
		(fill yes)
		(layer "In4.Cu")
		(net "GND")
	)
	(gr_poly
		(pts
			(arc
				(start 356.953312 -55.884572)
				(mid 356.598728 -55.884572)
				(end 356.953312 -55.884572)
			)
		)
		(stroke
			(width 0)
			(type solid)
		)
		(fill yes)
		(layer "In4.Cu")
		(net "GND")
	)
	(gr_poly
		(pts
			(arc
				(start 357.158036 -60.548012)
				(mid 356.803452 -60.548012)
				(end 357.158036 -60.548012)
			)
		)
		(stroke
			(width 0)
			(type solid)
		)
		(fill yes)
		(layer "In4.Cu")
		(net "GND")
	)
	(gr_poly
		(pts
			(arc
				(start 358.893872 -58.661808)
				(mid 358.539288 -58.661808)
				(end 358.893872 -58.661808)
			)
		)
		(stroke
			(width 0)
			(type solid)
		)
		(fill yes)
		(layer "In4.Cu")
		(net "GND")
	)
	(gr_poly
		(pts
			(arc
				(start 359.168192 -55.884572)
				(mid 358.813608 -55.884572)
				(end 359.168192 -55.884572)
			)
		)
		(stroke
			(width 0)
			(type solid)
		)
		(fill yes)
		(layer "In4.Cu")
		(net "GND")
	)
	(gr_poly
		(pts
			(arc
				(start 359.846372 -55.884572)
				(mid 359.491788 -55.884572)
				(end 359.846372 -55.884572)
			)
		)
		(stroke
			(width 0)
			(type solid)
		)
		(fill yes)
		(layer "In4.Cu")
		(net "GND")
	)
	(gr_poly
		(pts
			(arc
				(start 360.047032 -57.257188)
				(mid 359.692448 -57.257188)
				(end 360.047032 -57.257188)
			)
		)
		(stroke
			(width 0)
			(type solid)
		)
		(fill yes)
		(layer "In4.Cu")
		(net "GND")
	)
	(gr_poly
		(pts
			(arc
				(start 362.005372 -57.150508)
				(mid 361.650788 -57.150508)
				(end 362.005372 -57.150508)
			)
		)
		(stroke
			(width 0)
			(type solid)
		)
		(fill yes)
		(layer "In4.Cu")
		(net "GND")
	)
	(gr_poly
		(pts
			(arc
				(start 362.048552 -55.884572)
				(mid 361.693968 -55.884572)
				(end 362.048552 -55.884572)
			)
		)
		(stroke
			(width 0)
			(type solid)
		)
		(fill yes)
		(layer "In4.Cu")
		(net "GND")
	)
	(gr_poly
		(pts
			(arc
				(start 363.051852 -58.425588)
				(mid 362.697268 -58.425588)
				(end 363.051852 -58.425588)
			)
		)
		(stroke
			(width 0)
			(type solid)
		)
		(fill yes)
		(layer "In4.Cu")
		(net "GND")
	)
	(gr_poly
		(pts
			(arc
				(start 363.128052 -68.400168)
				(mid 362.773468 -68.400168)
				(end 363.128052 -68.400168)
			)
		)
		(stroke
			(width 0)
			(type solid)
		)
		(fill yes)
		(layer "In4.Cu")
		(net "GND")
	)
	(gr_poly
		(pts
			(arc
				(start 363.397292 -55.884572)
				(mid 363.042708 -55.884572)
				(end 363.397292 -55.884572)
			)
		)
		(stroke
			(width 0)
			(type solid)
		)
		(fill yes)
		(layer "In4.Cu")
		(net "GND")
	)
	(gr_poly
		(pts
			(arc
				(start 363.430312 -65.872868)
				(mid 363.075728 -65.872868)
				(end 363.430312 -65.872868)
			)
		)
		(stroke
			(width 0)
			(type solid)
		)
		(fill yes)
		(layer "In4.Cu")
		(net "GND")
	)
	(gr_poly
		(pts
			(arc
				(start 365.612172 -55.884572)
				(mid 365.257588 -55.884572)
				(end 365.612172 -55.884572)
			)
		)
		(stroke
			(width 0)
			(type solid)
		)
		(fill yes)
		(layer "In4.Cu")
		(net "GND")
	)
	(gr_poly
		(pts
			(arc
				(start 367.672112 -60.002928)
				(mid 367.317528 -60.002928)
				(end 367.672112 -60.002928)
			)
		)
		(stroke
			(width 0)
			(type solid)
		)
		(fill yes)
		(layer "In4.Cu")
		(net "GND")
	)
	(gr_poly
		(pts
			(arc
				(start 370.18468 -93.889068)
				(mid 369.81892 -93.889068)
				(end 370.18468 -93.889068)
			)
		)
		(stroke
			(width 0)
			(type solid)
		)
		(fill yes)
		(layer "In4.Cu")
		(net "GND")
	)
	(gr_poly
		(pts
			(arc
				(start 370.848128 -86.64702)
				(mid 370.482368 -86.64702)
				(end 370.848128 -86.64702)
			)
		)
		(stroke
			(width 0)
			(type solid)
		)
		(fill yes)
		(layer "In4.Cu")
		(net "GND")
	)
	(gr_poly
		(pts
			(arc
				(start 371.17528 -89.596468)
				(mid 370.80952 -89.596468)
				(end 371.17528 -89.596468)
			)
		)
		(stroke
			(width 0)
			(type solid)
		)
		(fill yes)
		(layer "In4.Cu")
		(net "GND")
	)
	(gr_poly
		(pts
			(arc
				(start 372.780052 -58.489088)
				(mid 372.425468 -58.489088)
				(end 372.780052 -58.489088)
			)
		)
		(stroke
			(width 0)
			(type solid)
		)
		(fill yes)
		(layer "In4.Cu")
		(net "GND")
	)
	(gr_poly
		(pts
			(arc
				(start 372.853712 -64.127888)
				(mid 372.499128 -64.127888)
				(end 372.853712 -64.127888)
			)
		)
		(stroke
			(width 0)
			(type solid)
		)
		(fill yes)
		(layer "In4.Cu")
		(net "GND")
	)
	(gr_poly
		(pts
			(arc
				(start 373.206772 -65.749678)
				(mid 372.852188 -65.749678)
				(end 373.206772 -65.749678)
			)
		)
		(stroke
			(width 0)
			(type solid)
		)
		(fill yes)
		(layer "In4.Cu")
		(net "GND")
	)
	(gr_poly
		(pts
			(arc
				(start 373.582946 -52.768754)
				(mid 373.228362 -52.768754)
				(end 373.582946 -52.768754)
			)
		)
		(stroke
			(width 0)
			(type solid)
		)
		(fill yes)
		(layer "In4.Cu")
		(net "GND")
	)
	(gr_poly
		(pts
			(arc
				(start 374.40362 -106.299508)
				(mid 374.03786 -106.299508)
				(end 374.40362 -106.299508)
			)
		)
		(stroke
			(width 0)
			(type solid)
		)
		(fill yes)
		(layer "In4.Cu")
		(net "GND")
	)
	(gr_poly
		(pts
			(arc
				(start 375.03354 -102.829868)
				(mid 374.66778 -102.829868)
				(end 375.03354 -102.829868)
			)
		)
		(stroke
			(width 0)
			(type solid)
		)
		(fill yes)
		(layer "In4.Cu")
		(net "GND")
	)
	(gr_poly
		(pts
			(arc
				(start 376.44832 -91.133168)
				(mid 376.08256 -91.133168)
				(end 376.44832 -91.133168)
			)
		)
		(stroke
			(width 0)
			(type solid)
		)
		(fill yes)
		(layer "In4.Cu")
		(net "GND")
	)
	(gr_poly
		(pts
			(arc
				(start 378.26188 -104.178608)
				(mid 377.89612 -104.178608)
				(end 378.26188 -104.178608)
			)
		)
		(stroke
			(width 0)
			(type solid)
		)
		(fill yes)
		(layer "In4.Cu")
		(net "GND")
	)
	(gr_poly
		(pts
			(arc
				(start 380.21768 -91.318588)
				(mid 379.85192 -91.318588)
				(end 380.21768 -91.318588)
			)
		)
		(stroke
			(width 0)
			(type solid)
		)
		(fill yes)
		(layer "In4.Cu")
		(net "GND")
	)
	(gr_poly
		(pts
			(arc
				(start 380.6444 -94.757748)
				(mid 380.27864 -94.757748)
				(end 380.6444 -94.757748)
			)
		)
		(stroke
			(width 0)
			(type solid)
		)
		(fill yes)
		(layer "In4.Cu")
		(net "GND")
	)
	(gr_poly
		(pts
			(arc
				(start 350.146874 -67.288156)
				(mid 349.687134 -67.288156)
				(end 350.146874 -67.288156)
			)
		)
		(stroke
			(width 0)
			(type solid)
		)
		(fill yes)
		(layer "In4.Cu")
		(net "GND")
	)
	(gr_poly
		(pts
			(arc
				(start 350.146874 -65.764156)
				(mid 349.687134 -65.764156)
				(end 350.146874 -65.764156)
			)
		)
		(stroke
			(width 0)
			(type solid)
		)
		(fill yes)
		(layer "In4.Cu")
		(net "GND")
	)
	(gr_poly
		(pts
			(arc
				(start 350.176338 -63.594488)
				(mid 349.716598 -63.594488)
				(end 350.176338 -63.594488)
			)
		)
		(stroke
			(width 0)
			(type solid)
		)
		(fill yes)
		(layer "In4.Cu")
		(net "GND")
	)
	(gr_poly
		(pts
			(arc
				(start 350.176338 -62.070488)
				(mid 349.716598 -62.070488)
				(end 350.176338 -62.070488)
			)
		)
		(stroke
			(width 0)
			(type solid)
		)
		(fill yes)
		(layer "In4.Cu")
		(net "GND")
	)
	(gr_poly
		(pts
			(arc
				(start 351.698306 -61.805566)
				(mid 351.238566 -61.805566)
				(end 351.698306 -61.805566)
			)
		)
		(stroke
			(width 0)
			(type solid)
		)
		(fill yes)
		(layer "In4.Cu")
		(net "GND")
	)
	(gr_poly
		(pts
			(arc
				(start 351.698306 -60.281566)
				(mid 351.238566 -60.281566)
				(end 351.698306 -60.281566)
			)
		)
		(stroke
			(width 0)
			(type solid)
		)
		(fill yes)
		(layer "In4.Cu")
		(net "GND")
	)
	(gr_poly
		(pts
			(arc
				(start 352.334068 -69.9008)
				(mid 351.874328 -69.9008)
				(end 352.334068 -69.9008)
			)
		)
		(stroke
			(width 0)
			(type solid)
		)
		(fill yes)
		(layer "In4.Cu")
		(net "GND")
	)
	(gr_poly
		(pts
			(arc
				(start 352.334068 -67.46748)
				(mid 351.874328 -67.46748)
				(end 352.334068 -67.46748)
			)
		)
		(stroke
			(width 0)
			(type solid)
		)
		(fill yes)
		(layer "In4.Cu")
		(net "GND")
	)
	(gr_poly
		(pts
			(arc
				(start 352.979482 -63.667894)
				(mid 352.519742 -63.667894)
				(end 352.979482 -63.667894)
			)
		)
		(stroke
			(width 0)
			(type solid)
		)
		(fill yes)
		(layer "In4.Cu")
		(net "GND")
	)
	(gr_poly
		(pts
			(arc
				(start 353.012502 -66.116454)
				(mid 352.552762 -66.116454)
				(end 353.012502 -66.116454)
			)
		)
		(stroke
			(width 0)
			(type solid)
		)
		(fill yes)
		(layer "In4.Cu")
		(net "GND")
	)
	(gr_poly
		(pts
			(xy 120.836944 -337.294474) (xy 120.852946 -337.27898)
			(arc
				(start 120.85701 -337.268566)
				(mid 120.947084 -337.130736)
				(end 121.08688 -337.043776)
			)
			(xy 121.101866 -337.038442) (xy 121.120408 -337.013296)
			(arc
				(start 121.123456 -336.902552)
				(mid 121.115292 -336.873367)
				(end 121.09196 -336.854038)
			)
			(arc
				(start 120.954292 -336.797142)
				(mid 120.944702 -336.794269)
				(end 120.934734 -336.793332)
			)
			(arc
				(start 120.153938 -336.793332)
				(mid 120.126462 -336.801404)
				(end 120.10771 -336.82305)
			)
			(xy 120.063006 -336.92084) (xy 120.067324 -336.95005)
			(arc
				(start 120.07723 -336.96148)
				(mid 120.168101 -337.090662)
				(end 120.230392 -337.2358)
			)
			(xy 120.233694 -337.246214) (xy 120.247664 -337.26247) (xy 120.336056 -337.30311) (xy 120.357392 -337.303364)
			(arc
				(start 120.367552 -337.299046)
				(mid 120.441285 -337.275882)
				(end 120.518174 -337.268058)
			)
			(arc
				(start 120.518174 -337.268058)
				(mid 120.61789 -337.28132)
				(end 120.710706 -337.320128)
			)
			(xy 120.720358 -337.32597) (xy 120.742456 -337.328002)
		)
		(stroke
			(width 0)
			(type solid)
		)
		(fill yes)
		(layer "In4.Cu")
		(net "GND")
	)
	(gr_poly
		(pts
			(arc
				(start 217.717116 -412.201868)
				(mid 217.810982 -412.139149)
				(end 217.788998 -412.028386)
			)
			(arc
				(start 217.330528 -411.569662)
				(mid 217.258807 -411.462464)
				(end 217.2335 -411.335982)
			)
			(xy 217.2335 -407.474928) (xy 216.982802 -407.22423)
			(arc
				(start 216.97061 -407.22042)
				(mid 216.929871 -407.205421)
				(end 216.891108 -407.185876)
			)
			(xy 216.146634 -407.185876)
			(arc
				(start 214.99957 -408.33294)
				(mid 214.976683 -408.441603)
				(end 215.06688 -408.506422)
			)
			(arc
				(start 215.06688 -408.506422)
				(mid 215.325331 -408.623915)
				(end 215.431116 -408.887422)
			)
			(arc
				(start 215.431116 -408.887422)
				(mid 215.418226 -408.986007)
				(end 215.380316 -409.077922)
			)
			(xy 215.380316 -411.618176) (xy 215.963754 -412.201868)
		)
		(stroke
			(width 0)
			(type solid)
		)
		(fill yes)
		(layer "In4.Cu")
		(net "AGND_HSC")
	)
	(gr_poly
		(pts
			(arc
				(start 207.054196 -412.179008)
				(mid 207.148062 -412.116289)
				(end 207.126078 -412.005526)
			)
			(arc
				(start 206.662528 -411.541722)
				(mid 206.590807 -411.434524)
				(end 206.5655 -411.308042)
			)
			(xy 206.5655 -407.474928) (xy 206.314802 -407.22423)
			(arc
				(start 206.30261 -407.22042)
				(mid 206.261871 -407.205421)
				(end 206.223108 -407.185876)
			)
			(xy 205.338934 -407.185876) (xy 203.980796 -408.544268) (xy 203.980796 -408.68473) (xy 204.057504 -408.68473)
			(arc
				(start 204.07249 -408.663648)
				(mid 204.20809 -408.547626)
				(end 204.381608 -408.505914)
			)
			(arc
				(start 204.381608 -408.505914)
				(mid 204.651375 -408.617655)
				(end 204.763116 -408.887422)
			)
			(arc
				(start 204.763116 -408.887422)
				(mid 204.750226 -408.986007)
				(end 204.712316 -409.077922)
			)
			(xy 204.712316 -411.392116) (xy 205.498954 -412.179008)
		)
		(stroke
			(width 0)
			(type solid)
		)
		(fill yes)
		(layer "In4.Cu")
		(net "AGND_HSC")
	)
	(gr_poly
		(pts
			(xy 245.05412 -251.739908) (xy 245.05412 -247.254268) (xy 244.60962 -246.809768) (xy 240.52276 -246.809768)
			(xy 240.18748 -247.145048) (xy 240.18748 -249.273568) (xy 240.806222 -249.273568) (xy 240.810293 -249.217946)
			(xy 240.822419 -249.163509) (xy 240.842342 -249.111418) (xy 240.869638 -249.062783) (xy 240.903724 -249.01864)
			(xy 240.943873 -248.979931) (xy 240.989231 -248.94748) (xy 241.038831 -248.921979) (xy 241.091615 -248.903972)
			(xy 241.146458 -248.893842) (xy 241.202192 -248.891805) (xy 241.257629 -248.897905) (xy 241.311586 -248.912011)
			(xy 241.362915 -248.933823) (xy 241.410521 -248.962877) (xy 241.453389 -248.998552) (xy 241.490606 -249.040089)
			(xy 241.521379 -249.086602) (xy 241.545051 -249.137099) (xy 241.561119 -249.190506) (xy 241.569239 -249.245682)
			(xy 241.569748 -249.273568) (xy 241.569239 -249.301454) (xy 241.561119 -249.35663) (xy 241.545051 -249.410037)
			(xy 241.521379 -249.460534) (xy 241.490606 -249.507047) (xy 241.453389 -249.548584) (xy 241.410521 -249.584259)
			(xy 241.362915 -249.613313) (xy 241.311586 -249.635125) (xy 241.257629 -249.649231) (xy 241.202192 -249.655331)
			(xy 241.146458 -249.653294) (xy 241.091615 -249.643164) (xy 241.038831 -249.625157) (xy 240.989231 -249.599656)
			(xy 240.943873 -249.567205) (xy 240.903724 -249.528496) (xy 240.869638 -249.484353) (xy 240.842342 -249.435718)
			(xy 240.822419 -249.383627) (xy 240.810293 -249.32919) (xy 240.806222 -249.273568) (xy 240.18748 -249.273568)
			(xy 240.18748 -251.889768) (xy 240.49228 -252.194568) (xy 244.59946 -252.194568)
		)
		(stroke
			(width 0)
			(type solid)
		)
		(fill yes)
		(layer "In4.Cu")
		(net "GND")
	)
	(gr_poly
		(pts
			(xy 411.86608 -192.166748) (xy 411.86608 -187.239148) (xy 410.62148 -185.994548) (xy 402.84908 -185.994548)
			(xy 402.67128 -186.172348) (xy 402.67128 -189.158978) (xy 407.266581 -189.158978) (xy 407.266581 -189.074422)
			(xy 407.274383 -188.990228) (xy 407.289921 -188.907113) (xy 407.313061 -188.825786) (xy 407.343607 -188.746941)
			(xy 407.381298 -188.671251) (xy 407.425811 -188.599362) (xy 407.476769 -188.531886) (xy 407.533735 -188.469401)
			(xy 407.596223 -188.412438) (xy 407.663701 -188.361484) (xy 407.735593 -188.316974) (xy 407.811285 -188.279288)
			(xy 407.890131 -188.248746) (xy 407.97146 -188.22561) (xy 408.054576 -188.210077) (xy 408.13877 -188.202279)
			(xy 408.181048 -188.201808) (xy 409.425648 -188.201808) (xy 409.467923 -188.202266) (xy 409.552113 -188.210072)
			(xy 409.635224 -188.225612) (xy 409.716546 -188.248754) (xy 409.795387 -188.279301) (xy 409.871072 -188.316991)
			(xy 409.942957 -188.361504) (xy 410.010429 -188.412459) (xy 410.072911 -188.469423) (xy 410.129871 -188.531908)
			(xy 410.180823 -188.599382) (xy 410.225332 -188.67127) (xy 410.263019 -188.746957) (xy 410.293561 -188.825799)
			(xy 410.316699 -188.907123) (xy 410.332235 -188.990234) (xy 410.340036 -189.074424) (xy 410.340036 -189.158976)
			(xy 410.332235 -189.243166) (xy 410.316699 -189.326277) (xy 410.293561 -189.407601) (xy 410.263019 -189.486443)
			(xy 410.225332 -189.56213) (xy 410.180823 -189.634018) (xy 410.129871 -189.701492) (xy 410.072911 -189.763977)
			(xy 410.010429 -189.820941) (xy 409.942957 -189.871896) (xy 409.871072 -189.916409) (xy 409.795387 -189.954099)
			(xy 409.716546 -189.984646) (xy 409.635224 -190.007788) (xy 409.552113 -190.023328) (xy 409.467923 -190.031134)
			(xy 409.425648 -190.031624) (xy 408.181048 -190.031624) (xy 408.13877 -190.031121) (xy 408.054576 -190.023323)
			(xy 407.97146 -190.00779) (xy 407.890131 -189.984654) (xy 407.811285 -189.954112) (xy 407.735593 -189.916426)
			(xy 407.663701 -189.871916) (xy 407.596223 -189.820962) (xy 407.533735 -189.763999) (xy 407.476769 -189.701514)
			(xy 407.425811 -189.634038) (xy 407.381298 -189.562149) (xy 407.343607 -189.486459) (xy 407.313061 -189.407614)
			(xy 407.289921 -189.326287) (xy 407.274383 -189.243172) (xy 407.266581 -189.158978) (xy 402.67128 -189.158978)
			(xy 402.67128 -192.471548) (xy 403.05228 -192.852548) (xy 411.18028 -192.852548)
		)
		(stroke
			(width 0)
			(type solid)
		)
		(fill yes)
		(layer "In4.Cu")
		(net "PVNN_TERM_CPU0")
	)
	(gr_poly
		(pts
			(xy 10.35558 -100.975668)
			(arc
				(start 10.35558 -100.736908)
				(mid 10.269496 -100.495608)
				(end 10.35558 -100.254308)
			)
			(arc
				(start 10.35558 -100.03917)
				(mid 10.302076 -99.949675)
				(end 10.197846 -99.954334)
			)
			(arc
				(start 10.197846 -99.954334)
				(mid 10.09724 -100.001603)
				(end 9.98728 -100.017834)
			)
			(arc
				(start 9.98728 -100.017834)
				(mid 9.605772 -99.636326)
				(end 9.98728 -99.254818)
			)
			(arc
				(start 9.98728 -99.254818)
				(mid 10.097231 -99.271082)
				(end 10.197846 -99.318318)
			)
			(arc
				(start 10.197846 -99.318318)
				(mid 10.302135 -99.323088)
				(end 10.35558 -99.233482)
			)
			(xy 10.35558 -98.755962)
			(arc
				(start 10.315702 -98.747072)
				(mid 10.017245 -98.374708)
				(end 10.315702 -98.002344)
			)
			(xy 10.35558 -97.993454) (xy 10.35558 -97.711768) (xy 9.72566 -97.081848) (xy 6.02742 -97.081848)
			(xy 5.44576 -97.663508) (xy 5.44576 -100.912168) (xy 5.91312 -101.379528) (xy 9.95172 -101.379528)
		)
		(stroke
			(width 0)
			(type solid)
		)
		(fill yes)
		(layer "In4.Cu")
		(net "GND")
	)
	(gr_poly
		(pts
			(arc
				(start 133.858254 -344.792808)
				(mid 133.950536 -344.733712)
				(end 133.93547 -344.625168)
			)
			(arc
				(start 133.93547 -344.625168)
				(mid 133.867618 -344.509379)
				(end 133.84403 -344.377264)
			)
			(arc
				(start 133.84403 -344.377264)
				(mid 133.85296 -344.295205)
				(end 133.879336 -344.21699)
			)
			(arc
				(start 133.879336 -344.21699)
				(mid 133.87259 -344.119821)
				(end 133.787134 -344.072972)
			)
			(arc
				(start 133.478524 -344.072972)
				(mid 133.352021 -344.047715)
				(end 133.244844 -343.975944)
			)
			(xy 129.811526 -340.54288)
			(arc
				(start 129.745994 -340.54288)
				(mid 129.701907 -340.568442)
				(end 129.702306 -340.619334)
			)
			(arc
				(start 129.702306 -340.619334)
				(mid 129.74207 -340.713026)
				(end 129.755646 -340.813898)
			)
			(arc
				(start 129.755646 -340.813898)
				(mid 129.750974 -340.873423)
				(end 129.737104 -340.9315)
			)
			(arc
				(start 129.737104 -340.9315)
				(mid 129.746595 -341.014878)
				(end 129.81559 -341.062818)
			)
			(arc
				(start 129.81559 -341.062818)
				(mid 130.040661 -341.19356)
				(end 130.129534 -341.43823)
			)
			(arc
				(start 130.129534 -341.43823)
				(mid 129.748026 -341.819738)
				(end 129.366518 -341.43823)
			)
			(arc
				(start 129.366518 -341.43823)
				(mid 129.37119 -341.378705)
				(end 129.38506 -341.320628)
			)
			(arc
				(start 129.38506 -341.320628)
				(mid 129.375569 -341.23725)
				(end 129.306574 -341.18931)
			)
			(arc
				(start 129.306574 -341.18931)
				(mid 129.242073 -341.171808)
				(end 129.181606 -341.143336)
			)
			(arc
				(start 129.181606 -341.143336)
				(mid 129.096518 -341.135203)
				(end 129.035302 -341.194898)
			)
			(arc
				(start 129.035302 -341.194898)
				(mid 128.99309 -341.275605)
				(end 128.93294 -341.343996)
			)
			(xy 128.93294 -343.350088) (xy 130.37566 -344.792808)
		)
		(stroke
			(width 0)
			(type solid)
		)
		(fill yes)
		(layer "In4.Cu")
		(net "GND")
	)
	(gr_poly
		(pts
			(arc
				(start 381.798068 -344.792808)
				(mid 381.89035 -344.733712)
				(end 381.875284 -344.625168)
			)
			(arc
				(start 381.875284 -344.625168)
				(mid 381.807432 -344.509379)
				(end 381.783844 -344.377264)
			)
			(arc
				(start 381.783844 -344.377264)
				(mid 381.792774 -344.295205)
				(end 381.81915 -344.21699)
			)
			(arc
				(start 381.81915 -344.21699)
				(mid 381.812404 -344.119821)
				(end 381.726948 -344.072972)
			)
			(arc
				(start 381.418338 -344.072972)
				(mid 381.291835 -344.047715)
				(end 381.184658 -343.975944)
			)
			(xy 377.729496 -340.521036)
			(arc
				(start 377.672092 -340.521036)
				(mid 377.627237 -340.54799)
				(end 377.629928 -340.600284)
			)
			(arc
				(start 377.629928 -340.600284)
				(mid 377.678703 -340.702183)
				(end 377.69546 -340.813898)
			)
			(arc
				(start 377.69546 -340.813898)
				(mid 377.690788 -340.873423)
				(end 377.676918 -340.9315)
			)
			(arc
				(start 377.676918 -340.9315)
				(mid 377.686409 -341.014878)
				(end 377.755404 -341.062818)
			)
			(arc
				(start 377.755404 -341.062818)
				(mid 377.980475 -341.19356)
				(end 378.069348 -341.43823)
			)
			(arc
				(start 378.069348 -341.43823)
				(mid 377.68784 -341.819738)
				(end 377.306332 -341.43823)
			)
			(arc
				(start 377.306332 -341.43823)
				(mid 377.311004 -341.378705)
				(end 377.324874 -341.320628)
			)
			(arc
				(start 377.324874 -341.320628)
				(mid 377.315383 -341.23725)
				(end 377.246388 -341.18931)
			)
			(arc
				(start 377.246388 -341.18931)
				(mid 377.181887 -341.171808)
				(end 377.12142 -341.143336)
			)
			(arc
				(start 377.12142 -341.143336)
				(mid 377.036332 -341.135203)
				(end 376.975116 -341.194898)
			)
			(arc
				(start 376.975116 -341.194898)
				(mid 376.933019 -341.275582)
				(end 376.873008 -341.343996)
			)
			(xy 376.873008 -343.350088) (xy 378.315474 -344.792808)
		)
		(stroke
			(width 0)
			(type solid)
		)
		(fill yes)
		(layer "In4.Cu")
		(net "GND")
	)
	(gr_poly
		(pts
			(xy 182.767732 -399.974054)
			(arc
				(start 182.767732 -399.01622)
				(mid 182.792989 -398.889717)
				(end 182.86476 -398.78254)
			)
			(xy 183.237632 -398.409414) (xy 183.237632 -397.799306)
			(arc
				(start 182.86476 -397.42618)
				(mid 182.793039 -397.318982)
				(end 182.767732 -397.1925)
			)
			(arc
				(start 182.767732 -392.263122)
				(mid 182.705096 -392.16929)
				(end 182.594504 -392.19124)
			)
			(arc
				(start 182.281576 -392.504168)
				(mid 182.254348 -392.598661)
				(end 182.31993 -392.671808)
			)
			(arc
				(start 182.31993 -392.671808)
				(mid 182.505244 -392.811109)
				(end 182.575708 -393.03198)
			)
			(arc
				(start 182.575708 -393.03198)
				(mid 182.463967 -393.301747)
				(end 182.1942 -393.413488)
			)
			(arc
				(start 182.1942 -393.413488)
				(mid 181.973317 -393.343041)
				(end 181.834028 -393.15771)
			)
			(arc
				(start 181.834028 -393.15771)
				(mid 181.760837 -393.092322)
				(end 181.666388 -393.119356)
			)
			(xy 181.377336 -393.408408)
			(arc
				(start 181.377336 -397.784574)
				(mid 181.438813 -397.877916)
				(end 181.548786 -397.858234)
			)
			(arc
				(start 181.548786 -397.858234)
				(mid 181.669927 -397.780713)
				(end 181.811168 -397.753586)
			)
			(arc
				(start 181.811168 -397.753586)
				(mid 182.080935 -397.865327)
				(end 182.192676 -398.135094)
			)
			(arc
				(start 182.192676 -398.135094)
				(mid 182.125794 -398.350869)
				(end 181.948582 -398.490948)
			)
			(arc
				(start 181.948582 -398.490948)
				(mid 181.892254 -398.544669)
				(end 181.890416 -398.62252)
			)
			(arc
				(start 181.890416 -398.62252)
				(mid 181.90714 -398.681173)
				(end 181.912768 -398.7419)
			)
			(xy 181.912768 -399.131028) (xy 182.318914 -399.537174)
			(arc
				(start 182.331106 -399.540984)
				(mid 182.526613 -399.678828)
				(end 182.601616 -399.905982)
			)
			(arc
				(start 182.601616 -399.905982)
				(mid 182.597045 -399.965119)
				(end 182.583328 -400.022822)
			)
			(xy 182.573676 -400.052286) (xy 182.631588 -400.110198)
		)
		(stroke
			(width 0)
			(type solid)
		)
		(fill yes)
		(layer "In4.Cu")
		(net "AGND_HSC")
	)
	(gr_poly
		(pts
			(xy 409.22956 -156.088588) (xy 409.22956 -148.760688) (xy 408.62758 -148.158708) (xy 400.4818 -148.158708)
			(xy 399.31594 -149.324568) (xy 399.31594 -150.339552) (xy 399.642589 -150.339552) (xy 399.646611 -150.253832)
			(xy 399.658642 -150.168864) (xy 399.678578 -150.085397) (xy 399.706241 -150.004163) (xy 399.74139 -149.925877)
			(xy 399.783716 -149.851226) (xy 399.832845 -149.780867) (xy 399.888348 -149.715417) (xy 399.949735 -149.655453)
			(xy 400.016468 -149.6015) (xy 400.08796 -149.554033) (xy 400.163582 -149.513469) (xy 400.242671 -149.480165)
			(xy 400.324531 -149.454413) (xy 400.408442 -149.43644) (xy 400.493668 -149.426404) (xy 400.57946 -149.424392)
			(xy 400.665062 -149.430423) (xy 400.749724 -149.444443) (xy 400.832701 -149.466329) (xy 400.913264 -149.49589)
			(xy 400.990704 -149.532864) (xy 401.064343 -149.576928) (xy 401.133531 -149.627694) (xy 401.197662 -149.684715)
			(xy 401.256171 -149.747491) (xy 401.308544 -149.815471) (xy 401.354322 -149.888056) (xy 401.393102 -149.964608)
			(xy 401.424543 -150.044456) (xy 401.448369 -150.126897) (xy 401.46437 -150.211207) (xy 401.472405 -150.296645)
			(xy 401.472908 -150.339552) (xy 401.472405 -150.382459) (xy 401.46437 -150.467897) (xy 401.448369 -150.552207)
			(xy 401.424543 -150.634648) (xy 401.393102 -150.714496) (xy 401.354322 -150.791048) (xy 401.308544 -150.863633)
			(xy 401.256171 -150.931613) (xy 401.197662 -150.994389) (xy 401.133531 -151.05141) (xy 401.064343 -151.102176)
			(xy 400.990704 -151.14624) (xy 400.913264 -151.183214) (xy 400.832701 -151.212775) (xy 400.749724 -151.234661)
			(xy 400.665062 -151.248681) (xy 400.57946 -151.254712) (xy 400.493668 -151.2527) (xy 400.408442 -151.242664)
			(xy 400.324531 -151.224691) (xy 400.242671 -151.198939) (xy 400.163582 -151.165635) (xy 400.08796 -151.125071)
			(xy 400.016468 -151.077604) (xy 399.949735 -151.023651) (xy 399.888348 -150.963687) (xy 399.832845 -150.898237)
			(xy 399.783716 -150.827878) (xy 399.74139 -150.753227) (xy 399.706241 -150.674941) (xy 399.678578 -150.593707)
			(xy 399.658642 -150.51024) (xy 399.646611 -150.425272) (xy 399.642589 -150.339552) (xy 399.31594 -150.339552)
			(xy 399.31594 -152.381896) (xy 399.668996 -152.381896) (xy 399.668996 -152.2972) (xy 399.677047 -152.212886)
			(xy 399.693076 -152.12972) (xy 399.716937 -152.048453) (xy 399.748416 -151.969823) (xy 399.787227 -151.894542)
			(xy 399.833017 -151.82329) (xy 399.885373 -151.756714) (xy 399.943821 -151.695416) (xy 400.007831 -151.639951)
			(xy 400.076823 -151.590822) (xy 400.150173 -151.548473) (xy 400.227216 -151.513289) (xy 400.307255 -151.485587)
			(xy 400.389564 -151.465619) (xy 400.473399 -151.453566) (xy 400.558 -151.449536) (xy 400.642601 -151.453566)
			(xy 400.726436 -151.465619) (xy 400.808745 -151.485587) (xy 400.888784 -151.513289) (xy 400.965827 -151.548473)
			(xy 401.039177 -151.590822) (xy 401.108169 -151.639951) (xy 401.172179 -151.695416) (xy 401.230627 -151.756714)
			(xy 401.282983 -151.82329) (xy 401.328773 -151.894542) (xy 401.367584 -151.969823) (xy 401.399063 -152.048453)
			(xy 401.422924 -152.12972) (xy 401.438953 -152.212886) (xy 401.447004 -152.2972) (xy 401.447508 -152.339548)
			(xy 401.447004 -152.381896) (xy 401.438953 -152.46621) (xy 401.422924 -152.549376) (xy 401.399063 -152.630643)
			(xy 401.367584 -152.709273) (xy 401.328773 -152.784554) (xy 401.282983 -152.855806) (xy 401.230627 -152.922382)
			(xy 401.172179 -152.98368) (xy 401.108169 -153.039145) (xy 401.039177 -153.088274) (xy 400.965827 -153.130623)
			(xy 400.888784 -153.165807) (xy 400.808745 -153.193509) (xy 400.726436 -153.213477) (xy 400.642601 -153.22553)
			(xy 400.558 -153.229561) (xy 400.473399 -153.22553) (xy 400.389564 -153.213477) (xy 400.307255 -153.193509)
			(xy 400.227216 -153.165807) (xy 400.150173 -153.130623) (xy 400.076823 -153.088274) (xy 400.007831 -153.039145)
			(xy 399.943821 -152.98368) (xy 399.885373 -152.922382) (xy 399.833017 -152.855806) (xy 399.787227 -152.784554)
			(xy 399.748416 -152.709273) (xy 399.716937 -152.630643) (xy 399.693076 -152.549376) (xy 399.677047 -152.46621)
			(xy 399.668996 -152.381896) (xy 399.31594 -152.381896) (xy 399.31594 -156.131768) (xy 399.515838 -156.331666)
			(xy 399.526776 -156.341811) (xy 399.553089 -156.355838) (xy 399.582331 -156.361675) (xy 399.612012 -156.358822)
			(xy 399.639608 -156.347525) (xy 399.662768 -156.328743) (xy 399.679521 -156.304076) (xy 399.684494 -156.29001)
			(xy 399.697296 -156.250582) (xy 399.729071 -156.174009) (xy 399.76764 -156.100624) (xy 399.812689 -156.031028)
			(xy 399.863847 -155.965791) (xy 399.920696 -155.905449) (xy 399.98277 -155.850495) (xy 400.049559 -155.801381)
			(xy 400.120516 -155.758509) (xy 400.19506 -155.722229) (xy 400.27258 -155.692841) (xy 400.35244 -155.670583)
			(xy 400.433985 -155.65564) (xy 400.516548 -155.648133) (xy 400.558 -155.647644) (xy 400.601441 -155.648157)
			(xy 400.687931 -155.656394) (xy 400.773251 -155.672794) (xy 400.856631 -155.697208) (xy 400.937322 -155.729418)
			(xy 401.014595 -155.769133) (xy 401.087755 -155.815995) (xy 401.156142 -155.869581) (xy 401.219141 -155.92941)
			(xy 401.276185 -155.994943) (xy 401.326758 -156.065588) (xy 401.370406 -156.14071) (xy 401.406735 -156.219631)
			(xy 401.435418 -156.301641) (xy 401.456197 -156.386001) (xy 401.468885 -156.471952) (xy 401.471638 -156.515308)
			(xy 401.474178 -156.563568) (xy 408.75458 -156.563568)
		)
		(stroke
			(width 0)
			(type solid)
		)
		(fill yes)
		(layer "In4.Cu")
		(net "PVCCFA_EHV_CPU0")
	)
	(gr_poly
		(pts
			(xy 198.43496 -113.538762) (xy 198.434485 -113.5241) (xy 198.426171 -113.495981) (xy 198.41021 -113.471384)
			(xy 198.387918 -113.452334) (xy 198.361132 -113.440404) (xy 198.332061 -113.436575) (xy 198.3031 -113.441165)
			(xy 198.289672 -113.447068) (xy 198.263848 -113.458844) (xy 198.209585 -113.475481) (xy 198.153458 -113.483899)
			(xy 198.12508 -113.484406) (xy 198.09783 -113.483919) (xy 198.043885 -113.47616) (xy 197.991592 -113.460803)
			(xy 197.942018 -113.438161) (xy 197.89617 -113.408694) (xy 197.854983 -113.373003) (xy 197.819294 -113.331814)
			(xy 197.789829 -113.285964) (xy 197.76719 -113.236389) (xy 197.751836 -113.184096) (xy 197.74408 -113.13015)
			(xy 197.74408 -113.07565) (xy 197.751836 -113.021704) (xy 197.76719 -112.969411) (xy 197.789829 -112.919836)
			(xy 197.819294 -112.873986) (xy 197.854983 -112.832797) (xy 197.89617 -112.797106) (xy 197.942018 -112.767639)
			(xy 197.991592 -112.744997) (xy 198.043885 -112.72964) (xy 198.09783 -112.721881) (xy 198.12508 -112.72139)
			(xy 198.153458 -112.72191) (xy 198.209586 -112.730317) (xy 198.26385 -112.746949) (xy 198.289672 -112.758728)
			(xy 198.303113 -112.7646) (xy 198.332072 -112.769183) (xy 198.361141 -112.765354) (xy 198.387926 -112.75343)
			(xy 198.410222 -112.73439) (xy 198.426195 -112.709804) (xy 198.43453 -112.681694) (xy 198.43496 -112.667034)
			(xy 198.43496 -112.560862) (xy 198.434485 -112.5462) (xy 198.426171 -112.518081) (xy 198.41021 -112.493484)
			(xy 198.387918 -112.474434) (xy 198.361132 -112.462504) (xy 198.332061 -112.458675) (xy 198.3031 -112.463265)
			(xy 198.289672 -112.469168) (xy 198.263848 -112.480944) (xy 198.209585 -112.497581) (xy 198.153458 -112.505999)
			(xy 198.12508 -112.506506) (xy 198.09783 -112.506019) (xy 198.043885 -112.49826) (xy 197.991592 -112.482903)
			(xy 197.942018 -112.460261) (xy 197.89617 -112.430794) (xy 197.854983 -112.395103) (xy 197.819294 -112.353914)
			(xy 197.789829 -112.308064) (xy 197.76719 -112.258489) (xy 197.751836 -112.206196) (xy 197.74408 -112.15225)
			(xy 197.74408 -112.09775) (xy 197.751836 -112.043804) (xy 197.76719 -111.991511) (xy 197.789829 -111.941936)
			(xy 197.819294 -111.896086) (xy 197.854983 -111.854897) (xy 197.89617 -111.819206) (xy 197.942018 -111.789739)
			(xy 197.991592 -111.767097) (xy 198.043885 -111.75174) (xy 198.09783 -111.743981) (xy 198.12508 -111.74349)
			(xy 198.153458 -111.74401) (xy 198.209586 -111.752417) (xy 198.26385 -111.769049) (xy 198.289672 -111.780828)
			(xy 198.303113 -111.7867) (xy 198.332072 -111.791283) (xy 198.361141 -111.787454) (xy 198.387926 -111.77553)
			(xy 198.410222 -111.75649) (xy 198.426195 -111.731904) (xy 198.43453 -111.703794) (xy 198.43496 -111.689134)
			(xy 198.43496 -110.922308) (xy 193.381376 -110.922308) (xy 193.367067 -110.922795) (xy 193.339573 -110.930735)
			(xy 193.315358 -110.945985) (xy 193.296319 -110.967351) (xy 193.283949 -110.993157) (xy 193.279219 -111.021381)
			(xy 193.282497 -111.04981) (xy 193.293529 -111.076216) (xy 193.302128 -111.087662) (xy 193.316963 -111.106715)
			(xy 193.341899 -111.148068) (xy 193.361012 -111.192414) (xy 193.373951 -111.238937) (xy 193.380479 -111.286783)
			(xy 193.380868 -111.310928) (xy 193.38035 -111.338136) (xy 193.372067 -111.391917) (xy 193.355696 -111.443812)
			(xy 193.331621 -111.492611) (xy 193.3004 -111.537179) (xy 193.262762 -111.576478) (xy 193.219583 -111.609593)
			(xy 193.195956 -111.623094) (xy 193.16954 -111.637572) (xy 193.16954 -112.048544) (xy 193.213228 -112.05464)
			(xy 193.240149 -112.058967) (xy 193.292471 -112.074307) (xy 193.342077 -112.09694) (xy 193.387955 -112.126404)
			(xy 193.429171 -112.1621) (xy 193.464887 -112.203299) (xy 193.494373 -112.249164) (xy 193.517029 -112.298758)
			(xy 193.532395 -112.351073) (xy 193.540156 -112.405043) (xy 193.540155 -112.459568) (xy 193.532392 -112.513537)
			(xy 193.517025 -112.565852) (xy 193.494367 -112.615446) (xy 193.46488 -112.661309) (xy 193.429164 -112.702508)
			(xy 193.387946 -112.738202) (xy 193.342067 -112.767665) (xy 193.292461 -112.790297) (xy 193.240138 -112.805636)
			(xy 193.213228 -112.810036) (xy 193.16954 -112.816132) (xy 193.16954 -113.514632) (xy 196.46341 -113.514632)
			(xy 196.467481 -113.45901) (xy 196.479607 -113.404573) (xy 196.49953 -113.352482) (xy 196.526826 -113.303847)
			(xy 196.560912 -113.259704) (xy 196.601061 -113.220995) (xy 196.646419 -113.188544) (xy 196.696019 -113.163043)
			(xy 196.748803 -113.145036) (xy 196.803646 -113.134906) (xy 196.85938 -113.132869) (xy 196.914817 -113.138969)
			(xy 196.968774 -113.153075) (xy 197.020103 -113.174887) (xy 197.067709 -113.203941) (xy 197.110577 -113.239616)
			(xy 197.147794 -113.281153) (xy 197.178567 -113.327666) (xy 197.202239 -113.378163) (xy 197.218307 -113.43157)
			(xy 197.226427 -113.486746) (xy 197.226936 -113.514632) (xy 197.226427 -113.542518) (xy 197.218307 -113.597694)
			(xy 197.202239 -113.651101) (xy 197.178567 -113.701598) (xy 197.147794 -113.748111) (xy 197.110577 -113.789648)
			(xy 197.067709 -113.825323) (xy 197.020103 -113.854377) (xy 196.968774 -113.876189) (xy 196.914817 -113.890295)
			(xy 196.85938 -113.896395) (xy 196.803646 -113.894358) (xy 196.748803 -113.884228) (xy 196.696019 -113.866221)
			(xy 196.646419 -113.84072) (xy 196.601061 -113.808269) (xy 196.560912 -113.76956) (xy 196.526826 -113.725417)
			(xy 196.49953 -113.676782) (xy 196.479607 -113.624691) (xy 196.467481 -113.570254) (xy 196.46341 -113.514632)
			(xy 193.16954 -113.514632) (xy 193.16954 -114.303048) (xy 198.43496 -114.303048)
		)
		(stroke
			(width 0)
			(type solid)
		)
		(fill yes)
		(layer "In4.Cu")
		(net "GND")
	)
	(gr_poly
		(pts
			(xy 251.9807 -51.444906) (xy 251.9807 -47.167546) (xy 250.98248 -46.169326) (xy 250.98248 -44.721526)
			(xy 249.73026 -43.469306) (xy 236.96168 -43.469306) (xy 236.47908 -43.951906) (xy 236.47908 -45.988732)
			(xy 248.905012 -45.988732) (xy 248.909083 -45.93311) (xy 248.921209 -45.878673) (xy 248.941132 -45.826582)
			(xy 248.968428 -45.777947) (xy 249.002514 -45.733804) (xy 249.042663 -45.695095) (xy 249.088021 -45.662644)
			(xy 249.137621 -45.637143) (xy 249.190405 -45.619136) (xy 249.245248 -45.609006) (xy 249.300982 -45.606969)
			(xy 249.356419 -45.613069) (xy 249.410376 -45.627175) (xy 249.461705 -45.648987) (xy 249.509311 -45.678041)
			(xy 249.552179 -45.713716) (xy 249.589396 -45.755253) (xy 249.620169 -45.801766) (xy 249.643841 -45.852263)
			(xy 249.659909 -45.90567) (xy 249.668029 -45.960846) (xy 249.668538 -45.988732) (xy 249.917456 -45.988732)
			(xy 249.921527 -45.93311) (xy 249.933653 -45.878673) (xy 249.953576 -45.826582) (xy 249.980872 -45.777947)
			(xy 250.014958 -45.733804) (xy 250.055107 -45.695095) (xy 250.100465 -45.662644) (xy 250.150065 -45.637143)
			(xy 250.202849 -45.619136) (xy 250.257692 -45.609006) (xy 250.313426 -45.606969) (xy 250.368863 -45.613069)
			(xy 250.42282 -45.627175) (xy 250.474149 -45.648987) (xy 250.521755 -45.678041) (xy 250.564623 -45.713716)
			(xy 250.60184 -45.755253) (xy 250.632613 -45.801766) (xy 250.656285 -45.852263) (xy 250.672353 -45.90567)
			(xy 250.680473 -45.960846) (xy 250.680982 -45.988732) (xy 250.680473 -46.016618) (xy 250.672353 -46.071794)
			(xy 250.656285 -46.125201) (xy 250.632613 -46.175698) (xy 250.60184 -46.222211) (xy 250.564623 -46.263748)
			(xy 250.521755 -46.299423) (xy 250.474149 -46.328477) (xy 250.42282 -46.350289) (xy 250.368863 -46.364395)
			(xy 250.313426 -46.370495) (xy 250.257692 -46.368458) (xy 250.202849 -46.358328) (xy 250.150065 -46.340321)
			(xy 250.100465 -46.31482) (xy 250.055107 -46.282369) (xy 250.014958 -46.24366) (xy 249.980872 -46.199517)
			(xy 249.953576 -46.150882) (xy 249.933653 -46.098791) (xy 249.921527 -46.044354) (xy 249.917456 -45.988732)
			(xy 249.668538 -45.988732) (xy 249.668029 -46.016618) (xy 249.659909 -46.071794) (xy 249.643841 -46.125201)
			(xy 249.620169 -46.175698) (xy 249.589396 -46.222211) (xy 249.552179 -46.263748) (xy 249.509311 -46.299423)
			(xy 249.461705 -46.328477) (xy 249.410376 -46.350289) (xy 249.356419 -46.364395) (xy 249.300982 -46.370495)
			(xy 249.245248 -46.368458) (xy 249.190405 -46.358328) (xy 249.137621 -46.340321) (xy 249.088021 -46.31482)
			(xy 249.042663 -46.282369) (xy 249.002514 -46.24366) (xy 248.968428 -46.199517) (xy 248.941132 -46.150882)
			(xy 248.921209 -46.098791) (xy 248.909083 -46.044354) (xy 248.905012 -45.988732) (xy 236.47908 -45.988732)
			(xy 236.47908 -46.248828) (xy 237.001558 -46.771306) (xy 237.467902 -46.771306) (xy 237.474252 -46.728126)
			(xy 237.478722 -46.701327) (xy 237.494256 -46.649264) (xy 237.517017 -46.599931) (xy 237.546545 -46.554325)
			(xy 237.582243 -46.513368) (xy 237.623389 -46.477889) (xy 237.669151 -46.448604) (xy 237.718605 -46.426106)
			(xy 237.77075 -46.41085) (xy 237.824531 -46.403144) (xy 237.878861 -46.403144) (xy 237.932642 -46.41085)
			(xy 237.984787 -46.426106) (xy 238.034241 -46.448604) (xy 238.080003 -46.477889) (xy 238.121149 -46.513368)
			(xy 238.156847 -46.554325) (xy 238.186375 -46.599931) (xy 238.209136 -46.649264) (xy 238.22467 -46.701327)
			(xy 238.22914 -46.728126) (xy 238.23549 -46.771306) (xy 238.483902 -46.771306) (xy 238.490252 -46.728126)
			(xy 238.494722 -46.701327) (xy 238.510256 -46.649264) (xy 238.533017 -46.599931) (xy 238.562545 -46.554325)
			(xy 238.598243 -46.513368) (xy 238.639389 -46.477889) (xy 238.685151 -46.448604) (xy 238.734605 -46.426106)
			(xy 238.78675 -46.41085) (xy 238.840531 -46.403144) (xy 238.894861 -46.403144) (xy 238.948642 -46.41085)
			(xy 239.000787 -46.426106) (xy 239.050241 -46.448604) (xy 239.096003 -46.477889) (xy 239.137149 -46.513368)
			(xy 239.172847 -46.554325) (xy 239.202375 -46.599931) (xy 239.225136 -46.649264) (xy 239.24067 -46.701327)
			(xy 239.24514 -46.728126) (xy 239.25149 -46.771306) (xy 240.749328 -46.771306) (xy 240.764208 -46.747472)
			(xy 240.799867 -46.704051) (xy 240.84151 -46.666331) (xy 240.888236 -46.635129) (xy 240.939035 -46.61112)
			(xy 240.992806 -46.594823) (xy 241.048387 -46.586591) (xy 241.07648 -46.58614) (xy 241.103733 -46.586602)
			(xy 241.157683 -46.594357) (xy 241.209981 -46.609712) (xy 241.25956 -46.632354) (xy 241.305412 -46.661822)
			(xy 241.346603 -46.697516) (xy 241.382295 -46.73871) (xy 241.41176 -46.784564) (xy 241.434398 -46.834146)
			(xy 241.449749 -46.886444) (xy 241.4575 -46.940395) (xy 241.457988 -46.967648) (xy 241.45621 -47.00397)
			(xy 241.453924 -47.027592) (xy 241.528854 -47.102522) (xy 250.782072 -47.102522) (xy 250.786143 -47.0469)
			(xy 250.798269 -46.992463) (xy 250.818192 -46.940372) (xy 250.845488 -46.891737) (xy 250.879574 -46.847594)
			(xy 250.919723 -46.808885) (xy 250.965081 -46.776434) (xy 251.014681 -46.750933) (xy 251.067465 -46.732926)
			(xy 251.122308 -46.722796) (xy 251.178042 -46.720759) (xy 251.233479 -46.726859) (xy 251.287436 -46.740965)
			(xy 251.338765 -46.762777) (xy 251.386371 -46.791831) (xy 251.429239 -46.827506) (xy 251.466456 -46.869043)
			(xy 251.497229 -46.915556) (xy 251.520901 -46.966053) (xy 251.536969 -47.01946) (xy 251.545089 -47.074636)
			(xy 251.545598 -47.102522) (xy 251.545089 -47.130408) (xy 251.536969 -47.185584) (xy 251.520901 -47.238991)
			(xy 251.497229 -47.289488) (xy 251.466456 -47.336001) (xy 251.429239 -47.377538) (xy 251.386371 -47.413213)
			(xy 251.338765 -47.442267) (xy 251.287436 -47.464079) (xy 251.233479 -47.478185) (xy 251.178042 -47.484285)
			(xy 251.122308 -47.482248) (xy 251.067465 -47.472118) (xy 251.014681 -47.454111) (xy 250.965081 -47.42861)
			(xy 250.919723 -47.396159) (xy 250.879574 -47.35745) (xy 250.845488 -47.313307) (xy 250.818192 -47.264672)
			(xy 250.798269 -47.212581) (xy 250.786143 -47.158144) (xy 250.782072 -47.102522) (xy 241.528854 -47.102522)
			(xy 242.48745 -48.061118) (xy 242.48745 -48.962818) (xy 243.45646 -49.931828) (xy 243.45646 -51.861466)
			(xy 243.68252 -52.087526) (xy 243.68252 -52.247546) (xy 251.17806 -52.247546)
		)
		(stroke
			(width 0)
			(type solid)
		)
		(fill yes)
		(layer "In4.Cu")
		(net "P12V_E1S_0")
	)
	(gr_poly
		(pts
			(xy 109.812074 -416.275774) (xy 109.81563 -416.26917) (xy 109.829339 -416.244556) (xy 109.862887 -416.199295)
			(xy 109.902727 -416.159459) (xy 109.947993 -416.125916) (xy 109.972602 -416.112198) (xy 109.979206 -416.108642)
			(xy 110.55858 -415.529268) (xy 110.55858 -411.772608) (xy 111.10214 -411.229048) (xy 113.82502 -411.229048)
			(xy 114.1349 -410.919168) (xy 114.1349 -409.364688) (xy 113.95202 -409.181808) (xy 113.103914 -409.181808)
			(xy 113.093754 -409.2194) (xy 113.086098 -409.246095) (xy 113.064125 -409.297098) (xy 113.034989 -409.344375)
			(xy 112.999307 -409.386929) (xy 112.957832 -409.42386) (xy 112.911441 -409.454387) (xy 112.861114 -409.477865)
			(xy 112.807914 -409.493799) (xy 112.752967 -409.501851) (xy 112.697433 -409.501851) (xy 112.642486 -409.493799)
			(xy 112.589286 -409.477865) (xy 112.538959 -409.454387) (xy 112.492568 -409.42386) (xy 112.451093 -409.386929)
			(xy 112.415411 -409.344375) (xy 112.386275 -409.297098) (xy 112.364302 -409.246095) (xy 112.356646 -409.2194)
			(xy 112.346486 -409.181808) (xy 107.99572 -409.181808) (xy 107.26674 -409.910788) (xy 109.472982 -409.910788)
			(xy 109.477053 -409.855166) (xy 109.489179 -409.800729) (xy 109.509102 -409.748638) (xy 109.536398 -409.700003)
			(xy 109.570484 -409.65586) (xy 109.610633 -409.617151) (xy 109.655991 -409.5847) (xy 109.705591 -409.559199)
			(xy 109.758375 -409.541192) (xy 109.813218 -409.531062) (xy 109.868952 -409.529025) (xy 109.924389 -409.535125)
			(xy 109.978346 -409.549231) (xy 110.029675 -409.571043) (xy 110.077281 -409.600097) (xy 110.120149 -409.635772)
			(xy 110.157366 -409.677309) (xy 110.188139 -409.723822) (xy 110.211811 -409.774319) (xy 110.227879 -409.827726)
			(xy 110.235999 -409.882902) (xy 110.236508 -409.910788) (xy 110.235999 -409.938674) (xy 110.227879 -409.99385)
			(xy 110.211811 -410.047257) (xy 110.188139 -410.097754) (xy 110.157366 -410.144267) (xy 110.120149 -410.185804)
			(xy 110.077281 -410.221479) (xy 110.029675 -410.250533) (xy 109.978346 -410.272345) (xy 109.924389 -410.286451)
			(xy 109.868952 -410.292551) (xy 109.813218 -410.290514) (xy 109.758375 -410.280384) (xy 109.705591 -410.262377)
			(xy 109.655991 -410.236876) (xy 109.610633 -410.204425) (xy 109.570484 -410.165716) (xy 109.536398 -410.121573)
			(xy 109.509102 -410.072938) (xy 109.489179 -410.020847) (xy 109.477053 -409.96641) (xy 109.472982 -409.910788)
			(xy 107.26674 -409.910788) (xy 106.90606 -410.271468) (xy 106.90606 -410.6164) (xy 107.517182 -410.6164)
			(xy 107.521253 -410.560778) (xy 107.533379 -410.506341) (xy 107.553302 -410.45425) (xy 107.580598 -410.405615)
			(xy 107.614684 -410.361472) (xy 107.654833 -410.322763) (xy 107.700191 -410.290312) (xy 107.749791 -410.264811)
			(xy 107.802575 -410.246804) (xy 107.857418 -410.236674) (xy 107.913152 -410.234637) (xy 107.968589 -410.240737)
			(xy 108.022546 -410.254843) (xy 108.073875 -410.276655) (xy 108.121481 -410.305709) (xy 108.164349 -410.341384)
			(xy 108.186593 -410.36621) (xy 112.133378 -410.36621) (xy 112.137449 -410.310588) (xy 112.149575 -410.256151)
			(xy 112.169498 -410.20406) (xy 112.196794 -410.155425) (xy 112.23088 -410.111282) (xy 112.271029 -410.072573)
			(xy 112.316387 -410.040122) (xy 112.365987 -410.014621) (xy 112.418771 -409.996614) (xy 112.473614 -409.986484)
			(xy 112.529348 -409.984447) (xy 112.584785 -409.990547) (xy 112.638742 -410.004653) (xy 112.690071 -410.026465)
			(xy 112.737677 -410.055519) (xy 112.780545 -410.091194) (xy 112.817762 -410.132731) (xy 112.848535 -410.179244)
			(xy 112.872207 -410.229741) (xy 112.888275 -410.283148) (xy 112.896395 -410.338324) (xy 112.896904 -410.36621)
			(xy 112.896395 -410.394096) (xy 112.888275 -410.449272) (xy 112.872207 -410.502679) (xy 112.848535 -410.553176)
			(xy 112.817762 -410.599689) (xy 112.780545 -410.641226) (xy 112.737677 -410.676901) (xy 112.690071 -410.705955)
			(xy 112.638742 -410.727767) (xy 112.584785 -410.741873) (xy 112.529348 -410.747973) (xy 112.473614 -410.745936)
			(xy 112.418771 -410.735806) (xy 112.365987 -410.717799) (xy 112.316387 -410.692298) (xy 112.271029 -410.659847)
			(xy 112.23088 -410.621138) (xy 112.196794 -410.576995) (xy 112.169498 -410.52836) (xy 112.149575 -410.476269)
			(xy 112.137449 -410.421832) (xy 112.133378 -410.36621) (xy 108.186593 -410.36621) (xy 108.201566 -410.382921)
			(xy 108.232339 -410.429434) (xy 108.256011 -410.479931) (xy 108.272079 -410.533338) (xy 108.280199 -410.588514)
			(xy 108.280708 -410.6164) (xy 108.280199 -410.644286) (xy 108.272079 -410.699462) (xy 108.256011 -410.752869)
			(xy 108.232339 -410.803366) (xy 108.201566 -410.849879) (xy 108.164349 -410.891416) (xy 108.121481 -410.927091)
			(xy 108.073875 -410.956145) (xy 108.022546 -410.977957) (xy 107.968589 -410.992063) (xy 107.913152 -410.998163)
			(xy 107.857418 -410.996126) (xy 107.802575 -410.985996) (xy 107.749791 -410.967989) (xy 107.700191 -410.942488)
			(xy 107.654833 -410.910037) (xy 107.614684 -410.871328) (xy 107.580598 -410.827185) (xy 107.553302 -410.77855)
			(xy 107.533379 -410.726459) (xy 107.521253 -410.672022) (xy 107.517182 -410.6164) (xy 106.90606 -410.6164)
			(xy 106.90606 -413.158432) (xy 108.841792 -413.158432) (xy 108.845863 -413.10281) (xy 108.857989 -413.048373)
			(xy 108.877912 -412.996282) (xy 108.905208 -412.947647) (xy 108.939294 -412.903504) (xy 108.979443 -412.864795)
			(xy 109.024801 -412.832344) (xy 109.074401 -412.806843) (xy 109.127185 -412.788836) (xy 109.182028 -412.778706)
			(xy 109.237762 -412.776669) (xy 109.293199 -412.782769) (xy 109.347156 -412.796875) (xy 109.398485 -412.818687)
			(xy 109.446091 -412.847741) (xy 109.488959 -412.883416) (xy 109.526176 -412.924953) (xy 109.556949 -412.971466)
			(xy 109.580621 -413.021963) (xy 109.596689 -413.07537) (xy 109.604809 -413.130546) (xy 109.605318 -413.158432)
			(xy 109.604809 -413.186318) (xy 109.596689 -413.241494) (xy 109.580621 -413.294901) (xy 109.556949 -413.345398)
			(xy 109.526176 -413.391911) (xy 109.488959 -413.433448) (xy 109.446091 -413.469123) (xy 109.398485 -413.498177)
			(xy 109.347156 -413.519989) (xy 109.293199 -413.534095) (xy 109.237762 -413.540195) (xy 109.182028 -413.538158)
			(xy 109.127185 -413.528028) (xy 109.074401 -413.510021) (xy 109.024801 -413.48452) (xy 108.979443 -413.452069)
			(xy 108.939294 -413.41336) (xy 108.905208 -413.369217) (xy 108.877912 -413.320582) (xy 108.857989 -413.268491)
			(xy 108.845863 -413.214054) (xy 108.841792 -413.158432) (xy 106.90606 -413.158432) (xy 106.90606 -416.616388)
			(xy 107.13974 -416.850068) (xy 109.23778 -416.850068)
		)
		(stroke
			(width 0)
			(type solid)
		)
		(fill yes)
		(layer "In4.Cu")
		(net "P3V3_9ZXL045_VDDA")
	)
	(gr_poly
		(pts
			(arc
				(start 2.510536 -315.03747)
				(mid 2.535947 -315.081471)
				(end 2.586736 -315.081412)
			)
			(arc
				(start 2.586736 -315.081412)
				(mid 2.67252 -315.046002)
				(end 2.764536 -315.033914)
			)
			(xy 2.79527 -315.035184) (xy 3.017266 -313.665108) (xy 3.018028 -313.65698)
			(arc
				(start 3.018028 -81.32826)
				(mid 2.788133 -80.17353)
				(end 2.133854 -79.19466)
			)
			(arc
				(start 1.305306 -78.366112)
				(mid 1.092705 -78.047693)
				(end 1.018032 -77.672184)
			)
			(arc
				(start 1.018032 -42.244772)
				(mid 1.013298 -42.223357)
				(end 0.999998 -42.20591)
			)
			(arc
				(start 0.999998 -42.20591)
				(mid 0.873253 -41.933622)
				(end 0.999998 -41.661334)
			)
			(arc
				(start 0.999998 -41.661334)
				(mid 1.013327 -41.6439)
				(end 1.018032 -41.622472)
			)
			(arc
				(start 1.018032 -41.222422)
				(mid 1.013298 -41.201007)
				(end 0.999998 -41.18356)
			)
			(arc
				(start 0.999998 -41.18356)
				(mid 0.873253 -40.911272)
				(end 0.999998 -40.638984)
			)
			(arc
				(start 0.999998 -40.638984)
				(mid 1.013327 -40.62155)
				(end 1.018032 -40.600122)
			)
			(arc
				(start 1.018032 -40.167814)
				(mid 1.012748 -40.145255)
				(end 0.997966 -40.127428)
			)
			(arc
				(start 0.997966 -40.127428)
				(mid 0.84779 -39.824152)
				(end 0.997966 -39.520876)
			)
			(arc
				(start 0.997966 -39.520876)
				(mid 1.012704 -39.503027)
				(end 1.018032 -39.48049)
			)
			(arc
				(start 1.018032 -39.099998)
				(mid 1.013298 -39.078583)
				(end 0.999998 -39.061136)
			)
			(arc
				(start 0.999998 -39.061136)
				(mid 0.873253 -38.788848)
				(end 0.999998 -38.51656)
			)
			(arc
				(start 0.999998 -38.51656)
				(mid 1.013327 -38.499126)
				(end 1.018032 -38.477698)
			)
			(arc
				(start 1.018032 -38.110414)
				(mid 1.011311 -38.085415)
				(end 0.99314 -38.06698)
			)
			(arc
				(start 0.99314 -38.06698)
				(mid 0.807128 -37.73932)
				(end 0.99314 -37.41166)
			)
			(arc
				(start 0.99314 -37.41166)
				(mid 1.011304 -37.393221)
				(end 1.018032 -37.368226)
			)
			(arc
				(start 1.018032 -37.067236)
				(mid 1.011311 -37.042237)
				(end 0.99314 -37.023802)
			)
			(arc
				(start 0.99314 -37.023802)
				(mid 0.807128 -36.696142)
				(end 0.99314 -36.368482)
			)
			(arc
				(start 0.99314 -36.368482)
				(mid 1.011304 -36.350043)
				(end 1.018032 -36.325048)
			)
			(arc
				(start 1.018032 -35.987228)
				(mid 1.011311 -35.962229)
				(end 0.99314 -35.943794)
			)
			(arc
				(start 0.99314 -35.943794)
				(mid 0.807128 -35.616134)
				(end 0.99314 -35.288474)
			)
			(arc
				(start 0.99314 -35.288474)
				(mid 1.011304 -35.270035)
				(end 1.018032 -35.24504)
			)
			(arc
				(start 1.018032 -26.980642)
				(mid 1.010858 -26.954615)
				(end 0.991362 -26.935938)
			)
			(arc
				(start 0.991362 -26.935938)
				(mid 0.827352 -26.84333)
				(end 0.66675 -26.74493)
			)
			(xy 0.654812 -26.73731) (xy 0.62738 -26.736294)
			(arc
				(start 0.536956 -26.786078)
				(mid 0.517713 -26.8047)
				(end 0.51054 -26.830528)
			)
			(arc
				(start 0.51054 -77.671676)
				(mid 0.623884 -78.241583)
				(end 0.946658 -78.72476)
			)
			(arc
				(start 1.775206 -79.553308)
				(mid 2.319424 -80.367648)
				(end 2.510536 -81.32826)
			)
		)
		(stroke
			(width 0)
			(type solid)
		)
		(fill yes)
		(layer "In4.Cu")
		(net "GND")
	)
	(gr_poly
		(pts
			(xy 29.749242 -135.177022) (xy 29.749242 -134.83463) (xy 29.70022 -134.785608) (xy 28.13812 -134.785608)
			(xy 27.88666 -134.534148) (xy 27.88666 -133.650228) (xy 28.10002 -133.436868) (xy 28.45562 -133.436868)
			(xy 28.47594 -133.457188) (xy 29.57576 -133.457188) (xy 30.53334 -132.499608) (xy 31.467806 -132.499608)
			(xy 32.884872 -132.499608) (xy 33.007808 -132.376672) (xy 33.007808 -128.01346) (xy 31.794196 -126.799848)
			(xy 31.2293 -126.799848) (xy 30.309312 -125.87986) (xy 29.324808 -125.87986) (xy 29.070808 -126.13386)
			(xy 29.070808 -128.109472) (xy 30.155132 -128.109472) (xy 30.159203 -128.05385) (xy 30.171329 -127.999413)
			(xy 30.191252 -127.947322) (xy 30.218548 -127.898687) (xy 30.252634 -127.854544) (xy 30.292783 -127.815835)
			(xy 30.338141 -127.783384) (xy 30.387741 -127.757883) (xy 30.440525 -127.739876) (xy 30.495368 -127.729746)
			(xy 30.551102 -127.727709) (xy 30.606539 -127.733809) (xy 30.660496 -127.747915) (xy 30.711825 -127.769727)
			(xy 30.759431 -127.798781) (xy 30.802299 -127.834456) (xy 30.839516 -127.875993) (xy 30.870289 -127.922506)
			(xy 30.893961 -127.973003) (xy 30.910029 -128.02641) (xy 30.918149 -128.081586) (xy 30.918658 -128.109472)
			(xy 31.679132 -128.109472) (xy 31.683203 -128.05385) (xy 31.695329 -127.999413) (xy 31.715252 -127.947322)
			(xy 31.742548 -127.898687) (xy 31.776634 -127.854544) (xy 31.816783 -127.815835) (xy 31.862141 -127.783384)
			(xy 31.911741 -127.757883) (xy 31.964525 -127.739876) (xy 32.019368 -127.729746) (xy 32.075102 -127.727709)
			(xy 32.130539 -127.733809) (xy 32.184496 -127.747915) (xy 32.235825 -127.769727) (xy 32.283431 -127.798781)
			(xy 32.326299 -127.834456) (xy 32.363516 -127.875993) (xy 32.394289 -127.922506) (xy 32.417961 -127.973003)
			(xy 32.434029 -128.02641) (xy 32.442149 -128.081586) (xy 32.442658 -128.109472) (xy 32.442149 -128.137358)
			(xy 32.434029 -128.192534) (xy 32.417961 -128.245941) (xy 32.394289 -128.296438) (xy 32.363516 -128.342951)
			(xy 32.326299 -128.384488) (xy 32.283431 -128.420163) (xy 32.235825 -128.449217) (xy 32.184496 -128.471029)
			(xy 32.130539 -128.485135) (xy 32.075102 -128.491235) (xy 32.019368 -128.489198) (xy 31.964525 -128.479068)
			(xy 31.911741 -128.461061) (xy 31.862141 -128.43556) (xy 31.816783 -128.403109) (xy 31.776634 -128.3644)
			(xy 31.742548 -128.320257) (xy 31.715252 -128.271622) (xy 31.695329 -128.219531) (xy 31.683203 -128.165094)
			(xy 31.679132 -128.109472) (xy 30.918658 -128.109472) (xy 30.918149 -128.137358) (xy 30.910029 -128.192534)
			(xy 30.893961 -128.245941) (xy 30.870289 -128.296438) (xy 30.839516 -128.342951) (xy 30.802299 -128.384488)
			(xy 30.759431 -128.420163) (xy 30.711825 -128.449217) (xy 30.660496 -128.471029) (xy 30.606539 -128.485135)
			(xy 30.551102 -128.491235) (xy 30.495368 -128.489198) (xy 30.440525 -128.479068) (xy 30.387741 -128.461061)
			(xy 30.338141 -128.43556) (xy 30.292783 -128.403109) (xy 30.252634 -128.3644) (xy 30.218548 -128.320257)
			(xy 30.191252 -128.271622) (xy 30.171329 -128.219531) (xy 30.159203 -128.165094) (xy 30.155132 -128.109472)
			(xy 29.070808 -128.109472) (xy 29.070808 -129.633472) (xy 30.155132 -129.633472) (xy 30.159203 -129.57785)
			(xy 30.171329 -129.523413) (xy 30.191252 -129.471322) (xy 30.218548 -129.422687) (xy 30.252634 -129.378544)
			(xy 30.292783 -129.339835) (xy 30.338141 -129.307384) (xy 30.387741 -129.281883) (xy 30.440525 -129.263876)
			(xy 30.495368 -129.253746) (xy 30.551102 -129.251709) (xy 30.606539 -129.257809) (xy 30.660496 -129.271915)
			(xy 30.711825 -129.293727) (xy 30.759431 -129.322781) (xy 30.802299 -129.358456) (xy 30.839516 -129.399993)
			(xy 30.870289 -129.446506) (xy 30.893961 -129.497003) (xy 30.910029 -129.55041) (xy 30.918149 -129.605586)
			(xy 30.918658 -129.633472) (xy 30.918149 -129.661358) (xy 30.910029 -129.716534) (xy 30.893961 -129.769941)
			(xy 30.870289 -129.820438) (xy 30.839516 -129.866951) (xy 30.802299 -129.908488) (xy 30.759431 -129.944163)
			(xy 30.711825 -129.973217) (xy 30.660496 -129.995029) (xy 30.606539 -130.009135) (xy 30.551102 -130.015235)
			(xy 30.495368 -130.013198) (xy 30.440525 -130.003068) (xy 30.387741 -129.985061) (xy 30.338141 -129.95956)
			(xy 30.292783 -129.927109) (xy 30.252634 -129.8884) (xy 30.218548 -129.844257) (xy 30.191252 -129.795622)
			(xy 30.171329 -129.743531) (xy 30.159203 -129.689094) (xy 30.155132 -129.633472) (xy 29.070808 -129.633472)
			(xy 29.070808 -130.718052) (xy 28.631388 -131.157472) (xy 30.155132 -131.157472) (xy 30.159203 -131.10185)
			(xy 30.171329 -131.047413) (xy 30.191252 -130.995322) (xy 30.218548 -130.946687) (xy 30.252634 -130.902544)
			(xy 30.292783 -130.863835) (xy 30.338141 -130.831384) (xy 30.387741 -130.805883) (xy 30.440525 -130.787876)
			(xy 30.495368 -130.777746) (xy 30.551102 -130.775709) (xy 30.606539 -130.781809) (xy 30.660496 -130.795915)
			(xy 30.711825 -130.817727) (xy 30.759431 -130.846781) (xy 30.802299 -130.882456) (xy 30.839516 -130.923993)
			(xy 30.870289 -130.970506) (xy 30.893961 -131.021003) (xy 30.910029 -131.07441) (xy 30.918149 -131.129586)
			(xy 30.918658 -131.157472) (xy 31.679132 -131.157472) (xy 31.683203 -131.10185) (xy 31.695329 -131.047413)
			(xy 31.715252 -130.995322) (xy 31.742548 -130.946687) (xy 31.776634 -130.902544) (xy 31.816783 -130.863835)
			(xy 31.862141 -130.831384) (xy 31.911741 -130.805883) (xy 31.964525 -130.787876) (xy 32.019368 -130.777746)
			(xy 32.075102 -130.775709) (xy 32.130539 -130.781809) (xy 32.184496 -130.795915) (xy 32.235825 -130.817727)
			(xy 32.283431 -130.846781) (xy 32.326299 -130.882456) (xy 32.363516 -130.923993) (xy 32.394289 -130.970506)
			(xy 32.417961 -131.021003) (xy 32.434029 -131.07441) (xy 32.442149 -131.129586) (xy 32.442658 -131.157472)
			(xy 32.442149 -131.185358) (xy 32.434029 -131.240534) (xy 32.417961 -131.293941) (xy 32.394289 -131.344438)
			(xy 32.363516 -131.390951) (xy 32.326299 -131.432488) (xy 32.283431 -131.468163) (xy 32.235825 -131.497217)
			(xy 32.184496 -131.519029) (xy 32.130539 -131.533135) (xy 32.075102 -131.539235) (xy 32.019368 -131.537198)
			(xy 31.964525 -131.527068) (xy 31.911741 -131.509061) (xy 31.862141 -131.48356) (xy 31.816783 -131.451109)
			(xy 31.776634 -131.4124) (xy 31.742548 -131.368257) (xy 31.715252 -131.319622) (xy 31.695329 -131.267531)
			(xy 31.683203 -131.213094) (xy 31.679132 -131.157472) (xy 30.918658 -131.157472) (xy 30.918149 -131.185358)
			(xy 30.910029 -131.240534) (xy 30.893961 -131.293941) (xy 30.870289 -131.344438) (xy 30.839516 -131.390951)
			(xy 30.802299 -131.432488) (xy 30.759431 -131.468163) (xy 30.711825 -131.497217) (xy 30.660496 -131.519029)
			(xy 30.606539 -131.533135) (xy 30.551102 -131.539235) (xy 30.495368 -131.537198) (xy 30.440525 -131.527068)
			(xy 30.387741 -131.509061) (xy 30.338141 -131.48356) (xy 30.292783 -131.451109) (xy 30.252634 -131.4124)
			(xy 30.218548 -131.368257) (xy 30.191252 -131.319622) (xy 30.171329 -131.267531) (xy 30.159203 -131.213094)
			(xy 30.155132 -131.157472) (xy 28.631388 -131.157472) (xy 28.3845 -131.40436) (xy 27.005788 -131.40436)
			(xy 26.353008 -132.05714) (xy 26.353008 -132.093208) (xy 27.83408 -132.093208) (xy 27.838151 -132.037586)
			(xy 27.850277 -131.983149) (xy 27.8702 -131.931058) (xy 27.897496 -131.882423) (xy 27.931582 -131.83828)
			(xy 27.971731 -131.799571) (xy 28.017089 -131.76712) (xy 28.066689 -131.741619) (xy 28.119473 -131.723612)
			(xy 28.174316 -131.713482) (xy 28.23005 -131.711445) (xy 28.285487 -131.717545) (xy 28.339444 -131.731651)
			(xy 28.390773 -131.753463) (xy 28.438379 -131.782517) (xy 28.481247 -131.818192) (xy 28.518464 -131.859729)
			(xy 28.549237 -131.906242) (xy 28.572909 -131.956739) (xy 28.588977 -132.010146) (xy 28.597097 -132.065322)
			(xy 28.597606 -132.093208) (xy 28.597097 -132.121094) (xy 28.588977 -132.17627) (xy 28.572909 -132.229677)
			(xy 28.549237 -132.280174) (xy 28.518464 -132.326687) (xy 28.481247 -132.368224) (xy 28.438379 -132.403899)
			(xy 28.390773 -132.432953) (xy 28.339444 -132.454765) (xy 28.285487 -132.468871) (xy 28.23005 -132.474971)
			(xy 28.174316 -132.472934) (xy 28.119473 -132.462804) (xy 28.066689 -132.444797) (xy 28.017089 -132.419296)
			(xy 27.971731 -132.386845) (xy 27.931582 -132.348136) (xy 27.897496 -132.303993) (xy 27.8702 -132.255358)
			(xy 27.850277 -132.203267) (xy 27.838151 -132.14883) (xy 27.83408 -132.093208) (xy 26.353008 -132.093208)
			(xy 26.353008 -134.771384) (xy 26.930096 -135.348472) (xy 29.577792 -135.348472)
		)
		(stroke
			(width 0)
			(type solid)
		)
		(fill yes)
		(layer "In4.Cu")
		(net "PVCCINFAON_CPU1_VREF")
	)
	(gr_poly
		(pts
			(xy 409.455366 -165.563042) (xy 409.464968 -165.552825) (xy 409.478672 -165.528374) (xy 409.485218 -165.501121)
			(xy 409.484116 -165.473114) (xy 409.475447 -165.44646) (xy 409.459864 -165.423162) (xy 409.449524 -165.41369)
			(xy 409.428885 -165.395489) (xy 409.392543 -165.354167) (xy 409.362521 -165.30805) (xy 409.339443 -165.258094)
			(xy 409.323787 -165.20534) (xy 409.315879 -165.150882) (xy 409.315412 -165.123368) (xy 409.315907 -165.095699)
			(xy 409.323905 -165.040942) (xy 409.339729 -164.987914) (xy 409.363046 -164.937729) (xy 409.393368 -164.891437)
			(xy 409.430058 -164.850011) (xy 409.472348 -164.81432) (xy 409.51935 -164.785111) (xy 409.54452 -164.77361)
			(xy 409.575 -164.760402) (xy 409.575 -159.458914) (xy 409.54452 -159.445706) (xy 409.519352 -159.434201)
			(xy 409.472347 -159.404997) (xy 409.430056 -159.369309) (xy 409.393365 -159.327883) (xy 409.363045 -159.281591)
			(xy 409.339732 -159.231404) (xy 409.323915 -159.178375) (xy 409.315927 -159.123617) (xy 409.315412 -159.095948)
			(xy 409.315929 -159.067208) (xy 409.324546 -159.010376) (xy 409.341591 -158.955481) (xy 409.366679 -158.903765)
			(xy 409.399242 -158.856397) (xy 409.418536 -158.83509) (xy 409.428618 -158.823557) (xy 409.441978 -158.796007)
			(xy 409.446577 -158.765735) (xy 409.441999 -158.73546) (xy 409.428658 -158.707901) (xy 409.418536 -158.696406)
			(xy 409.399262 -158.67508) (xy 409.36669 -158.62772) (xy 409.341591 -158.576008) (xy 409.324533 -158.521117)
			(xy 409.315903 -158.464288) (xy 409.315412 -158.435548) (xy 409.315908 -158.40788) (xy 409.323909 -158.353125)
			(xy 409.339734 -158.300099) (xy 409.363053 -158.249916) (xy 409.393376 -158.203627) (xy 409.430067 -158.162203)
			(xy 409.472356 -158.126513) (xy 409.519357 -158.097307) (xy 409.54452 -158.08579) (xy 409.575 -158.072582)
			(xy 409.575 -157.599888) (xy 408.97048 -156.995368) (xy 401.363942 -156.995368) (xy 401.343218 -157.032919)
			(xy 401.295757 -157.104366) (xy 401.241816 -157.171056) (xy 401.181868 -157.232404) (xy 401.11644 -157.28787)
			(xy 401.046107 -157.336966) (xy 400.971487 -157.379263) (xy 400.893234 -157.414388) (xy 400.812036 -157.442032)
			(xy 400.728608 -157.461953) (xy 400.64368 -157.473977) (xy 400.558 -157.477996) (xy 400.47232 -157.473977)
			(xy 400.387392 -157.461953) (xy 400.303964 -157.442032) (xy 400.222766 -157.414388) (xy 400.144513 -157.379263)
			(xy 400.069893 -157.336966) (xy 399.99956 -157.28787) (xy 399.934132 -157.232404) (xy 399.874184 -157.171056)
			(xy 399.820243 -157.104366) (xy 399.772782 -157.032919) (xy 399.752058 -156.995368) (xy 398.7292 -156.995368)
			(xy 397.80718 -157.917388) (xy 397.80718 -158.604896) (xy 399.668996 -158.604896) (xy 399.668996 -158.5202)
			(xy 399.677047 -158.435886) (xy 399.693076 -158.35272) (xy 399.716937 -158.271453) (xy 399.748416 -158.192823)
			(xy 399.787227 -158.117542) (xy 399.833017 -158.04629) (xy 399.885373 -157.979714) (xy 399.943821 -157.918416)
			(xy 400.007831 -157.862951) (xy 400.076823 -157.813822) (xy 400.150173 -157.771473) (xy 400.227216 -157.736289)
			(xy 400.307255 -157.708587) (xy 400.389564 -157.688619) (xy 400.473399 -157.676566) (xy 400.558 -157.672536)
			(xy 400.642601 -157.676566) (xy 400.726436 -157.688619) (xy 400.808745 -157.708587) (xy 400.888784 -157.736289)
			(xy 400.965827 -157.771473) (xy 401.039177 -157.813822) (xy 401.108169 -157.862951) (xy 401.172179 -157.918416)
			(xy 401.230627 -157.979714) (xy 401.282983 -158.04629) (xy 401.328773 -158.117542) (xy 401.367584 -158.192823)
			(xy 401.399063 -158.271453) (xy 401.422924 -158.35272) (xy 401.438953 -158.435886) (xy 401.447004 -158.5202)
			(xy 401.447508 -158.562548) (xy 401.447004 -158.604896) (xy 401.438953 -158.68921) (xy 401.422924 -158.772376)
			(xy 401.399063 -158.853643) (xy 401.367584 -158.932273) (xy 401.328773 -159.007554) (xy 401.282983 -159.078806)
			(xy 401.230627 -159.145382) (xy 401.172179 -159.20668) (xy 401.108169 -159.262145) (xy 401.039177 -159.311274)
			(xy 400.965827 -159.353623) (xy 400.888784 -159.388807) (xy 400.808745 -159.416509) (xy 400.726436 -159.436477)
			(xy 400.642601 -159.44853) (xy 400.558 -159.452561) (xy 400.473399 -159.44853) (xy 400.389564 -159.436477)
			(xy 400.307255 -159.416509) (xy 400.227216 -159.388807) (xy 400.150173 -159.353623) (xy 400.076823 -159.311274)
			(xy 400.007831 -159.262145) (xy 399.943821 -159.20668) (xy 399.885373 -159.145382) (xy 399.833017 -159.078806)
			(xy 399.787227 -159.007554) (xy 399.748416 -158.932273) (xy 399.716937 -158.853643) (xy 399.693076 -158.772376)
			(xy 399.677047 -158.68921) (xy 399.668996 -158.604896) (xy 397.80718 -158.604896) (xy 397.80718 -162.785552)
			(xy 399.642589 -162.785552) (xy 399.646611 -162.699832) (xy 399.658642 -162.614864) (xy 399.678578 -162.531397)
			(xy 399.706241 -162.450163) (xy 399.74139 -162.371877) (xy 399.783716 -162.297226) (xy 399.832845 -162.226867)
			(xy 399.888348 -162.161417) (xy 399.949735 -162.101453) (xy 400.016468 -162.0475) (xy 400.08796 -162.000033)
			(xy 400.163582 -161.959469) (xy 400.242671 -161.926165) (xy 400.324531 -161.900413) (xy 400.408442 -161.88244)
			(xy 400.493668 -161.872404) (xy 400.57946 -161.870392) (xy 400.665062 -161.876423) (xy 400.749724 -161.890443)
			(xy 400.832701 -161.912329) (xy 400.913264 -161.94189) (xy 400.990704 -161.978864) (xy 401.064343 -162.022928)
			(xy 401.133531 -162.073694) (xy 401.197662 -162.130715) (xy 401.256171 -162.193491) (xy 401.308544 -162.261471)
			(xy 401.354322 -162.334056) (xy 401.393102 -162.410608) (xy 401.424543 -162.490456) (xy 401.448369 -162.572897)
			(xy 401.46437 -162.657207) (xy 401.472405 -162.742645) (xy 401.472908 -162.785552) (xy 401.472405 -162.828459)
			(xy 401.46437 -162.913897) (xy 401.448369 -162.998207) (xy 401.424543 -163.080648) (xy 401.393102 -163.160496)
			(xy 401.354322 -163.237048) (xy 401.308544 -163.309633) (xy 401.256171 -163.377613) (xy 401.197662 -163.440389)
			(xy 401.133531 -163.49741) (xy 401.064343 -163.548176) (xy 400.990704 -163.59224) (xy 400.913264 -163.629214)
			(xy 400.832701 -163.658775) (xy 400.749724 -163.680661) (xy 400.665062 -163.694681) (xy 400.57946 -163.700712)
			(xy 400.493668 -163.6987) (xy 400.408442 -163.688664) (xy 400.324531 -163.670691) (xy 400.242671 -163.644939)
			(xy 400.163582 -163.611635) (xy 400.08796 -163.571071) (xy 400.016468 -163.523604) (xy 399.949735 -163.469651)
			(xy 399.888348 -163.409687) (xy 399.832845 -163.344237) (xy 399.783716 -163.273878) (xy 399.74139 -163.199227)
			(xy 399.706241 -163.120941) (xy 399.678578 -163.039707) (xy 399.658642 -162.95624) (xy 399.646611 -162.871272)
			(xy 399.642589 -162.785552) (xy 397.80718 -162.785552) (xy 397.80718 -164.827896) (xy 399.668996 -164.827896)
			(xy 399.668996 -164.7432) (xy 399.677047 -164.658886) (xy 399.693076 -164.57572) (xy 399.716937 -164.494453)
			(xy 399.748416 -164.415823) (xy 399.787227 -164.340542) (xy 399.833017 -164.26929) (xy 399.885373 -164.202714)
			(xy 399.943821 -164.141416) (xy 400.007831 -164.085951) (xy 400.076823 -164.036822) (xy 400.150173 -163.994473)
			(xy 400.227216 -163.959289) (xy 400.307255 -163.931587) (xy 400.389564 -163.911619) (xy 400.473399 -163.899566)
			(xy 400.558 -163.895536) (xy 400.642601 -163.899566) (xy 400.726436 -163.911619) (xy 400.808745 -163.931587)
			(xy 400.888784 -163.959289) (xy 400.965827 -163.994473) (xy 401.039177 -164.036822) (xy 401.108169 -164.085951)
			(xy 401.172179 -164.141416) (xy 401.230627 -164.202714) (xy 401.282983 -164.26929) (xy 401.328773 -164.340542)
			(xy 401.367584 -164.415823) (xy 401.399063 -164.494453) (xy 401.422924 -164.57572) (xy 401.438953 -164.658886)
			(xy 401.447004 -164.7432) (xy 401.447508 -164.785548) (xy 401.447004 -164.827896) (xy 401.438953 -164.91221)
			(xy 401.422924 -164.995376) (xy 401.399063 -165.076643) (xy 401.367584 -165.155273) (xy 401.328773 -165.230554)
			(xy 401.282983 -165.301806) (xy 401.230627 -165.368382) (xy 401.172179 -165.42968) (xy 401.108169 -165.485145)
			(xy 401.039177 -165.534274) (xy 400.965827 -165.576623) (xy 400.888784 -165.611807) (xy 400.808745 -165.639509)
			(xy 400.726436 -165.659477) (xy 400.642601 -165.67153) (xy 400.558 -165.675561) (xy 400.473399 -165.67153)
			(xy 400.389564 -165.659477) (xy 400.307255 -165.639509) (xy 400.227216 -165.611807) (xy 400.150173 -165.576623)
			(xy 400.076823 -165.534274) (xy 400.007831 -165.485145) (xy 399.943821 -165.42968) (xy 399.885373 -165.368382)
			(xy 399.833017 -165.301806) (xy 399.787227 -165.230554) (xy 399.748416 -165.155273) (xy 399.716937 -165.076643)
			(xy 399.693076 -164.995376) (xy 399.677047 -164.91221) (xy 399.668996 -164.827896) (xy 397.80718 -164.827896)
			(xy 397.80718 -164.965888) (xy 399.01622 -166.174928) (xy 408.84348 -166.174928)
		)
		(stroke
			(width 0)
			(type solid)
		)
		(fill yes)
		(layer "In4.Cu")
		(net "PVCCD_HV_CPU0")
	)
	(gr_poly
		(pts
			(xy 70.037706 -172.687488) (xy 70.051862 -172.687036) (xy 70.079091 -172.67928) (xy 70.103139 -172.664338)
			(xy 70.122154 -172.643363) (xy 70.134671 -172.617969) (xy 70.139727 -172.590112) (xy 70.136932 -172.561939)
			(xy 70.126501 -172.535619) (xy 70.109237 -172.51318) (xy 70.098158 -172.504354) (xy 70.064249 -172.478525)
			(xy 70.000873 -172.421512) (xy 69.943073 -172.358852) (xy 69.891349 -172.29109) (xy 69.84615 -172.218813)
			(xy 69.807868 -172.142645) (xy 69.776833 -172.063248) (xy 69.753316 -171.98131) (xy 69.737519 -171.89754)
			(xy 69.72958 -171.812663) (xy 69.729096 -171.77004) (xy 69.729584 -171.727764) (xy 69.737386 -171.643572)
			(xy 69.752922 -171.560459) (xy 69.776061 -171.479135) (xy 69.806605 -171.400292) (xy 69.844293 -171.324604)
			(xy 69.888804 -171.252716) (xy 69.939758 -171.185242) (xy 69.996721 -171.122757) (xy 70.059206 -171.065794)
			(xy 70.12668 -171.01484) (xy 70.198568 -170.970329) (xy 70.274256 -170.932641) (xy 70.353099 -170.902097)
			(xy 70.434423 -170.878958) (xy 70.517536 -170.863422) (xy 70.601728 -170.85562) (xy 70.68628 -170.85562)
			(xy 70.770472 -170.863422) (xy 70.853585 -170.878958) (xy 70.934909 -170.902097) (xy 71.013752 -170.932641)
			(xy 71.08944 -170.970329) (xy 71.161328 -171.01484) (xy 71.228802 -171.065794) (xy 71.291287 -171.122757)
			(xy 71.34825 -171.185242) (xy 71.399204 -171.252716) (xy 71.443715 -171.324604) (xy 71.481403 -171.400292)
			(xy 71.511947 -171.479135) (xy 71.535086 -171.560459) (xy 71.550622 -171.643572) (xy 71.558424 -171.727764)
			(xy 71.558912 -171.77004) (xy 71.558425 -171.812664) (xy 71.550501 -171.897544) (xy 71.534715 -171.981318)
			(xy 71.511204 -172.063261) (xy 71.480172 -172.142661) (xy 71.441889 -172.21883) (xy 71.396686 -172.291107)
			(xy 71.344956 -172.358867) (xy 71.287147 -172.42152) (xy 71.22376 -172.478524) (xy 71.18985 -172.504354)
			(xy 71.17877 -172.513158) (xy 71.161557 -172.535608) (xy 71.151167 -172.561919) (xy 71.148395 -172.590072)
			(xy 71.153456 -172.617904) (xy 71.165961 -172.643279) (xy 71.184949 -172.664249) (xy 71.208963 -172.679202)
			(xy 71.236158 -172.686992) (xy 71.250302 -172.687488) (xy 73.30186 -172.687488) (xy 75.946 -170.043348)
			(xy 75.946 -168.906444) (xy 75.95108 -168.884346) (xy 75.95108 -163.167568) (xy 75.08494 -162.301428)
			(xy 75.050396 -162.32378) (xy 75.027134 -162.338272) (xy 74.977336 -162.36116) (xy 74.924776 -162.376688)
			(xy 74.870535 -162.384535) (xy 74.843132 -162.384994) (xy 74.815878 -162.384533) (xy 74.761924 -162.376779)
			(xy 74.709623 -162.361426) (xy 74.66004 -162.338785) (xy 74.614184 -162.309318) (xy 74.572989 -162.273624)
			(xy 74.537293 -162.23243) (xy 74.507823 -162.186576) (xy 74.48518 -162.136993) (xy 74.469824 -162.084693)
			(xy 74.462068 -162.03074) (xy 74.461624 -162.003486) (xy 74.462064 -161.977486) (xy 74.469122 -161.925968)
			(xy 74.483105 -161.875884) (xy 74.503755 -161.828161) (xy 74.53069 -161.783681) (xy 74.546714 -161.763202)
			(xy 73.61936 -160.835848) (xy 72.17918 -160.835848) (xy 70.910704 -162.104324) (xy 69.068696 -162.104324)
			(xy 67.997832 -161.03346) (xy 63.270638 -161.03346) (xy 63.123572 -161.180526) (xy 63.123572 -164.634926)
			(xy 69.007995 -164.634926) (xy 69.012017 -164.549206) (xy 69.024048 -164.464238) (xy 69.043984 -164.380771)
			(xy 69.071647 -164.299537) (xy 69.106796 -164.221251) (xy 69.149122 -164.1466) (xy 69.198251 -164.076241)
			(xy 69.253754 -164.010791) (xy 69.315141 -163.950827) (xy 69.381874 -163.896874) (xy 69.453366 -163.849407)
			(xy 69.528988 -163.808843) (xy 69.608077 -163.775539) (xy 69.689937 -163.749787) (xy 69.773848 -163.731814)
			(xy 69.859074 -163.721778) (xy 69.944866 -163.719766) (xy 70.030468 -163.725797) (xy 70.11513 -163.739817)
			(xy 70.198107 -163.761703) (xy 70.27867 -163.791264) (xy 70.35611 -163.828238) (xy 70.429749 -163.872302)
			(xy 70.498937 -163.923068) (xy 70.563068 -163.980089) (xy 70.621577 -164.042865) (xy 70.67395 -164.110845)
			(xy 70.719728 -164.18343) (xy 70.758508 -164.259982) (xy 70.789949 -164.33983) (xy 70.813775 -164.422271)
			(xy 70.829776 -164.506581) (xy 70.837811 -164.592019) (xy 70.838314 -164.634926) (xy 70.837811 -164.677833)
			(xy 70.829776 -164.763271) (xy 70.813775 -164.847581) (xy 70.789949 -164.930022) (xy 70.758508 -165.00987)
			(xy 70.719728 -165.086422) (xy 70.67395 -165.159007) (xy 70.621577 -165.226987) (xy 70.563068 -165.289763)
			(xy 70.498937 -165.346784) (xy 70.429749 -165.39755) (xy 70.35611 -165.441614) (xy 70.27867 -165.478588)
			(xy 70.198107 -165.508149) (xy 70.11513 -165.530035) (xy 70.030468 -165.544055) (xy 69.944866 -165.550086)
			(xy 69.859074 -165.548074) (xy 69.773848 -165.538038) (xy 69.689937 -165.520065) (xy 69.608077 -165.494313)
			(xy 69.528988 -165.461009) (xy 69.453366 -165.420445) (xy 69.381874 -165.372978) (xy 69.315141 -165.319025)
			(xy 69.253754 -165.259061) (xy 69.198251 -165.193611) (xy 69.149122 -165.123252) (xy 69.106796 -165.048601)
			(xy 69.071647 -164.970315) (xy 69.043984 -164.889081) (xy 69.024048 -164.805614) (xy 69.012017 -164.720646)
			(xy 69.007995 -164.634926) (xy 63.123572 -164.634926) (xy 63.123572 -166.67727) (xy 69.034402 -166.67727)
			(xy 69.034402 -166.592574) (xy 69.042453 -166.50826) (xy 69.058482 -166.425094) (xy 69.082343 -166.343827)
			(xy 69.113822 -166.265197) (xy 69.152633 -166.189916) (xy 69.198423 -166.118664) (xy 69.250779 -166.052088)
			(xy 69.309227 -165.99079) (xy 69.373237 -165.935325) (xy 69.442229 -165.886196) (xy 69.515579 -165.843847)
			(xy 69.592622 -165.808663) (xy 69.672661 -165.780961) (xy 69.75497 -165.760993) (xy 69.838805 -165.74894)
			(xy 69.923406 -165.74491) (xy 70.008007 -165.74894) (xy 70.091842 -165.760993) (xy 70.174151 -165.780961)
			(xy 70.25419 -165.808663) (xy 70.331233 -165.843847) (xy 70.404583 -165.886196) (xy 70.473575 -165.935325)
			(xy 70.537585 -165.99079) (xy 70.596033 -166.052088) (xy 70.648389 -166.118664) (xy 70.694179 -166.189916)
			(xy 70.73299 -166.265197) (xy 70.764469 -166.343827) (xy 70.78833 -166.425094) (xy 70.804359 -166.50826)
			(xy 70.81241 -166.592574) (xy 70.812914 -166.634922) (xy 70.81241 -166.67727) (xy 70.804359 -166.761584)
			(xy 70.78833 -166.84475) (xy 70.764469 -166.926017) (xy 70.73299 -167.004647) (xy 70.694179 -167.079928)
			(xy 70.648389 -167.15118) (xy 70.596033 -167.217756) (xy 70.537585 -167.279054) (xy 70.473575 -167.334519)
			(xy 70.404583 -167.383648) (xy 70.331233 -167.425997) (xy 70.25419 -167.461181) (xy 70.174151 -167.488883)
			(xy 70.091842 -167.508851) (xy 70.008007 -167.520904) (xy 69.923406 -167.524935) (xy 69.838805 -167.520904)
			(xy 69.75497 -167.508851) (xy 69.672661 -167.488883) (xy 69.592622 -167.461181) (xy 69.515579 -167.425997)
			(xy 69.442229 -167.383648) (xy 69.373237 -167.334519) (xy 69.309227 -167.279054) (xy 69.250779 -167.217756)
			(xy 69.198423 -167.15118) (xy 69.152633 -167.079928) (xy 69.113822 -167.004647) (xy 69.082343 -166.926017)
			(xy 69.058482 -166.84475) (xy 69.042453 -166.761584) (xy 69.034402 -166.67727) (xy 63.123572 -166.67727)
			(xy 63.123572 -169.185844) (xy 63.284608 -169.34688) (xy 64.9986 -169.34688) (xy 67.585336 -171.933616)
			(xy 67.59545 -171.943089) (xy 67.619569 -171.956709) (xy 67.646464 -171.963337) (xy 67.67415 -171.962486)
			(xy 67.700586 -171.954217) (xy 67.723823 -171.939141) (xy 67.742148 -171.918369) (xy 67.754208 -171.893433)
			(xy 67.759114 -171.866171) (xy 67.75831 -171.852336) (xy 67.756521 -171.831809) (xy 67.754615 -171.790644)
			(xy 67.7545 -171.77004) (xy 67.755004 -171.727692) (xy 67.763055 -171.643378) (xy 67.779084 -171.560212)
			(xy 67.802945 -171.478945) (xy 67.834424 -171.400315) (xy 67.873235 -171.325034) (xy 67.919025 -171.253782)
			(xy 67.971381 -171.187206) (xy 68.029829 -171.125908) (xy 68.093839 -171.070443) (xy 68.162831 -171.021314)
			(xy 68.236181 -170.978965) (xy 68.313224 -170.943781) (xy 68.393263 -170.916079) (xy 68.475572 -170.896111)
			(xy 68.559407 -170.884058) (xy 68.644008 -170.880028) (xy 68.728609 -170.884058) (xy 68.812444 -170.896111)
			(xy 68.894753 -170.916079) (xy 68.974792 -170.943781) (xy 69.051835 -170.978965) (xy 69.125185 -171.021314)
			(xy 69.194177 -171.070443) (xy 69.258187 -171.125908) (xy 69.316635 -171.187206) (xy 69.368991 -171.253782)
			(xy 69.414781 -171.325034) (xy 69.453592 -171.400315) (xy 69.485071 -171.478945) (xy 69.508932 -171.560212)
			(xy 69.524961 -171.643378) (xy 69.533012 -171.727692) (xy 69.533516 -171.77004) (xy 69.53301 -171.813061)
			(xy 69.524698 -171.898701) (xy 69.508156 -171.983138) (xy 69.483538 -172.065583) (xy 69.451074 -172.145266)
			(xy 69.411068 -172.221441) (xy 69.363894 -172.293399) (xy 69.309992 -172.360464) (xy 69.249866 -172.422012)
			(xy 69.184078 -172.477467) (xy 69.14896 -172.502322) (xy 69.13744 -172.510875) (xy 69.119309 -172.533095)
			(xy 69.108071 -172.55948) (xy 69.104615 -172.587949) (xy 69.109211 -172.616257) (xy 69.121499 -172.64217)
			(xy 69.140507 -172.663644) (xy 69.164738 -172.678985) (xy 69.192279 -172.686982) (xy 69.206618 -172.687488)
		)
		(stroke
			(width 0)
			(type solid)
		)
		(fill yes)
		(layer "In4.Cu")
		(net "PVCCD_HV_CPU1")
	)
	(gr_poly
		(pts
			(xy 127.926084 -342.801956) (xy 127.926084 -342.10371) (xy 127.925657 -342.089804) (xy 127.918155 -342.063024)
			(xy 127.903704 -342.039261) (xy 127.883378 -342.020279) (xy 127.858683 -342.007486) (xy 127.831453 -342.001831)
			(xy 127.803707 -342.003733) (xy 127.790448 -342.007952) (xy 127.75952 -342.018266) (xy 127.695282 -342.029377)
			(xy 127.662686 -342.03005) (xy 127.635434 -342.029563) (xy 127.581486 -342.021805) (xy 127.52919 -342.006449)
			(xy 127.479612 -341.983808) (xy 127.433761 -341.954342) (xy 127.392569 -341.918651) (xy 127.356875 -341.877462)
			(xy 127.327405 -341.831612) (xy 127.30476 -341.782036) (xy 127.289401 -341.729742) (xy 127.281639 -341.675794)
			(xy 127.281178 -341.648542) (xy 127.281747 -341.618857) (xy 127.290953 -341.560204) (xy 127.309134 -341.503685)
			(xy 127.33585 -341.450664) (xy 127.370457 -341.402422) (xy 127.412119 -341.360124) (xy 127.43561 -341.341964)
			(xy 127.446221 -341.333538) (xy 127.462935 -341.312223) (xy 127.47346 -341.287265) (xy 127.477056 -341.260418)
			(xy 127.47347 -341.23357) (xy 127.462954 -341.208608) (xy 127.446247 -341.187287) (xy 127.43561 -341.178896)
			(xy 127.41209 -341.160772) (xy 127.370427 -341.118466) (xy 127.335821 -341.070218) (xy 127.309107 -341.01719)
			(xy 127.29093 -340.960665) (xy 127.281729 -340.902006) (xy 127.281178 -340.872318) (xy 127.281664 -340.845067)
			(xy 127.28942 -340.791119) (xy 127.304775 -340.738824) (xy 127.327417 -340.689247) (xy 127.356883 -340.643397)
			(xy 127.392574 -340.602206) (xy 127.433765 -340.566515) (xy 127.479615 -340.537049) (xy 127.529192 -340.514407)
			(xy 127.581487 -340.499052) (xy 127.635435 -340.491296) (xy 127.689937 -340.491296) (xy 127.743885 -340.499052)
			(xy 127.79618 -340.514407) (xy 127.845757 -340.537049) (xy 127.891607 -340.566515) (xy 127.932798 -340.602206)
			(xy 127.968489 -340.643397) (xy 127.997955 -340.689247) (xy 128.020597 -340.738824) (xy 128.035952 -340.791119)
			(xy 128.043708 -340.845067) (xy 128.044194 -340.872318) (xy 128.043739 -340.898899) (xy 128.036365 -340.951546)
			(xy 128.02175 -341.002658) (xy 128.000176 -341.051244) (xy 127.972062 -341.096363) (xy 127.937953 -341.137138)
			(xy 127.89851 -341.17278) (xy 127.854498 -341.202597) (xy 127.830834 -341.21471) (xy 127.822473 -341.219234)
			(xy 127.809613 -341.233216) (xy 127.802714 -341.250915) (xy 127.802719 -341.269911) (xy 127.809628 -341.287607)
			(xy 127.822495 -341.301582) (xy 127.830834 -341.30615) (xy 127.834644 -341.307928) (xy 127.848241 -341.314224)
			(xy 127.877731 -341.319437) (xy 127.907468 -341.315885) (xy 127.934901 -341.303872) (xy 127.957679 -341.284428)
			(xy 127.966216 -341.272114) (xy 127.973772 -341.260667) (xy 127.990957 -341.239288) (xy 128.000506 -341.229442)
			(xy 128.244854 -340.985094) (xy 128.261164 -340.969478) (xy 128.298212 -340.943671) (xy 128.318514 -340.933786)
			(xy 128.327564 -340.909223) (xy 128.351443 -340.862639) (xy 128.381468 -340.819759) (xy 128.417077 -340.781388)
			(xy 128.457598 -340.748249) (xy 128.502272 -340.720962) (xy 128.550257 -340.700043) (xy 128.600653 -340.685883)
			(xy 128.652512 -340.678748) (xy 128.678686 -340.678262) (xy 128.70472 -340.678703) (xy 128.756305 -340.685782)
			(xy 128.806448 -340.699811) (xy 128.854218 -340.720528) (xy 128.898726 -340.747549) (xy 128.919224 -340.763606)
			(xy 128.927648 -340.769798) (xy 128.947759 -340.775435) (xy 128.968453 -340.772613) (xy 128.986321 -340.7618)
			(xy 128.99842 -340.744775) (xy 129.001012 -340.73465) (xy 129.004118 -340.720751) (xy 129.012126 -340.693417)
			(xy 129.017014 -340.68004) (xy 129.021505 -340.666748) (xy 129.023799 -340.638796) (xy 129.018399 -340.611274)
			(xy 129.005712 -340.586262) (xy 128.986695 -340.565648) (xy 128.962785 -340.550988) (xy 128.935788 -340.54339)
			(xy 128.921764 -340.54288) (xy 128.652524 -340.54288) (xy 128.630873 -340.542513) (xy 128.587949 -340.536795)
			(xy 128.546143 -340.525507) (xy 128.526032 -340.51748) (xy 128.067816 -340.327742) (xy 128.047967 -340.319134)
			(xy 128.010501 -340.297497) (xy 127.97618 -340.271155) (xy 127.960628 -340.256114) (xy 126.994666 -339.290406)
			(xy 126.982728 -339.286596) (xy 126.965073 -339.281025) (xy 126.930847 -339.266905) (xy 126.914402 -339.258402)
			(xy 126.903226 -339.25256) (xy 126.737872 -339.25256) (xy 126.372366 -339.617812) (xy 126.353645 -339.635828)
			(xy 126.311631 -339.666388) (xy 126.265359 -339.690011) (xy 126.215965 -339.706115) (xy 126.164662 -339.714306)
			(xy 126.138686 -339.71484) (xy 124.378212 -339.71484) (xy 124.352231 -339.714341) (xy 124.300915 -339.706177)
			(xy 124.25151 -339.69008) (xy 124.205234 -339.666446) (xy 124.163229 -339.635859) (xy 124.144532 -339.617812)
			(xy 121.584974 -337.058254) (xy 121.468896 -337.010248) (xy 121.435368 -337.09102) (xy 121.463054 -337.11515)
			(xy 121.483398 -337.13334) (xy 121.519189 -337.174537) (xy 121.54874 -337.220416) (xy 121.571449 -337.270039)
			(xy 121.586851 -337.322393) (xy 121.594632 -337.376408) (xy 121.595134 -337.403694) (xy 121.594551 -337.433595)
			(xy 121.58524 -337.492667) (xy 121.576592 -337.521296) (xy 121.572641 -337.535206) (xy 121.571828 -337.564097)
			(xy 121.579126 -337.592063) (xy 121.593952 -337.616873) (xy 121.615125 -337.636548) (xy 121.640954 -337.649518)
			(xy 121.655078 -337.652614) (xy 121.681149 -337.657778) (xy 121.731641 -337.67437) (xy 121.779342 -337.697807)
			(xy 121.823329 -337.727637) (xy 121.862752 -337.763281) (xy 121.896848 -337.804051) (xy 121.924957 -337.849157)
			(xy 121.946535 -337.897727) (xy 121.961165 -337.948822) (xy 121.968564 -338.001452) (xy 121.969022 -338.028026)
			(xy 121.968536 -338.055277) (xy 121.96078 -338.109225) (xy 121.945425 -338.16152) (xy 121.922783 -338.211097)
			(xy 121.893317 -338.256947) (xy 121.857626 -338.298138) (xy 121.816435 -338.333829) (xy 121.770585 -338.363295)
			(xy 121.721008 -338.385937) (xy 121.668713 -338.401292) (xy 121.614765 -338.409048) (xy 121.560263 -338.409048)
			(xy 121.506315 -338.401292) (xy 121.45402 -338.385937) (xy 121.404443 -338.363295) (xy 121.358593 -338.333829)
			(xy 121.317402 -338.298138) (xy 121.281711 -338.256947) (xy 121.252245 -338.211097) (xy 121.229603 -338.16152)
			(xy 121.214248 -338.109225) (xy 121.206492 -338.055277) (xy 121.206006 -338.028026) (xy 121.206587 -337.998125)
			(xy 121.215896 -337.939052) (xy 121.224548 -337.910424) (xy 121.228501 -337.896511) (xy 121.229318 -337.867614)
			(xy 121.222023 -337.83964) (xy 121.2072 -337.814821) (xy 121.186029 -337.795135) (xy 121.160198 -337.782153)
			(xy 121.146062 -337.779106) (xy 121.113225 -337.772514) (xy 121.050372 -337.749396) (xy 121.021094 -337.733132)
			(xy 121.008124 -337.726123) (xy 120.979496 -337.719129) (xy 120.950063 -337.720591) (xy 120.922271 -337.730389)
			(xy 120.898427 -337.747707) (xy 120.880514 -337.771107) (xy 120.87479 -337.784694) (xy 120.863443 -337.812956)
			(xy 120.833084 -337.865747) (xy 120.794719 -337.913041) (xy 120.772428 -337.933792) (xy 120.772428 -339.082634)
			(xy 121.7449 -340.054946) (xy 126.474472 -340.054946) (xy 126.478543 -339.999324) (xy 126.490669 -339.944887)
			(xy 126.510592 -339.892796) (xy 126.537888 -339.844161) (xy 126.571974 -339.800018) (xy 126.612123 -339.761309)
			(xy 126.657481 -339.728858) (xy 126.707081 -339.703357) (xy 126.759865 -339.68535) (xy 126.814708 -339.67522)
			(xy 126.870442 -339.673183) (xy 126.925879 -339.679283) (xy 126.979836 -339.693389) (xy 127.031165 -339.715201)
			(xy 127.078771 -339.744255) (xy 127.121639 -339.77993) (xy 127.158856 -339.821467) (xy 127.189629 -339.86798)
			(xy 127.213301 -339.918477) (xy 127.229369 -339.971884) (xy 127.237489 -340.02706) (xy 127.237998 -340.054946)
			(xy 127.237489 -340.082832) (xy 127.229369 -340.138008) (xy 127.213301 -340.191415) (xy 127.189629 -340.241912)
			(xy 127.158856 -340.288425) (xy 127.121639 -340.329962) (xy 127.078771 -340.365637) (xy 127.031165 -340.394691)
			(xy 126.979836 -340.416503) (xy 126.925879 -340.430609) (xy 126.870442 -340.436709) (xy 126.814708 -340.434672)
			(xy 126.759865 -340.424542) (xy 126.707081 -340.406535) (xy 126.657481 -340.381034) (xy 126.612123 -340.348583)
			(xy 126.571974 -340.309874) (xy 126.537888 -340.265731) (xy 126.510592 -340.217096) (xy 126.490669 -340.165005)
			(xy 126.478543 -340.110568) (xy 126.474472 -340.054946) (xy 121.7449 -340.054946) (xy 122.316748 -340.6267)
			(xy 123.139454 -340.6267) (xy 123.164451 -340.627337) (xy 123.213475 -340.637136) (xy 123.259647 -340.656308)
			(xy 123.296622 -340.681056) (xy 125.683008 -340.681056) (xy 125.687079 -340.625434) (xy 125.699205 -340.570997)
			(xy 125.719128 -340.518906) (xy 125.746424 -340.470271) (xy 125.78051 -340.426128) (xy 125.820659 -340.387419)
			(xy 125.866017 -340.354968) (xy 125.915617 -340.329467) (xy 125.968401 -340.31146) (xy 126.023244 -340.30133)
			(xy 126.078978 -340.299293) (xy 126.134415 -340.305393) (xy 126.188372 -340.319499) (xy 126.239701 -340.341311)
			(xy 126.287307 -340.370365) (xy 126.330175 -340.40604) (xy 126.367392 -340.447577) (xy 126.398165 -340.49409)
			(xy 126.421837 -340.544587) (xy 126.437905 -340.597994) (xy 126.446025 -340.65317) (xy 126.446534 -340.681056)
			(xy 126.446025 -340.708942) (xy 126.437905 -340.764118) (xy 126.421837 -340.817525) (xy 126.398165 -340.868022)
			(xy 126.367392 -340.914535) (xy 126.330175 -340.956072) (xy 126.287307 -340.991747) (xy 126.239701 -341.020801)
			(xy 126.188372 -341.042613) (xy 126.134415 -341.056719) (xy 126.078978 -341.062819) (xy 126.023244 -341.060782)
			(xy 125.968401 -341.050652) (xy 125.915617 -341.032645) (xy 125.866017 -341.007144) (xy 125.820659 -340.974693)
			(xy 125.78051 -340.935984) (xy 125.746424 -340.891841) (xy 125.719128 -340.843206) (xy 125.699205 -340.791115)
			(xy 125.687079 -340.736678) (xy 125.683008 -340.681056) (xy 123.296622 -340.681056) (xy 123.301194 -340.684116)
			(xy 123.319286 -340.701376) (xy 125.89383 -343.27592) (xy 127.45212 -343.27592)
		)
		(stroke
			(width 0)
			(type solid)
		)
		(fill yes)
		(layer "In4.Cu")
		(net "GND")
	)
	(gr_poly
		(pts
			(xy 0.654812 -17.86255)
			(arc
				(start 0.66675 -17.85493)
				(mid 0.827347 -17.756522)
				(end 0.991362 -17.663922)
			)
			(xy 1.017524 -17.61998)
			(arc
				(start 1.017524 -13.780008)
				(mid 1.305283 -13.085295)
				(end 1.999996 -12.797536)
			)
			(arc
				(start 11.102594 -12.797536)
				(mid 13.236139 -11.913635)
				(end 14.11986 -9.780016)
			)
			(xy 14.11986 -3.945382)
			(arc
				(start 14.10081 -3.90779)
				(mid 13.825764 -3.583504)
				(end 13.726922 -3.16992)
			)
			(arc
				(start 13.726922 -3.16992)
				(mid 13.825371 -2.757062)
				(end 14.09954 -2.433066)
			)
			(xy 14.11986 -2.392934) (xy 14.11986 -1.016) (xy 80.684116 -1.016) (xy 80.684116 -2.39141)
			(arc
				(start 80.704944 -2.43205)
				(mid 81.07796 -3.169158)
				(end 80.704944 -3.906266)
			)
			(xy 80.684116 -3.946906)
			(arc
				(start 80.684116 -9.780016)
				(mid 81.568091 -11.91374)
				(end 83.70189 -12.797536)
			)
			(arc
				(start 124.102622 -12.797536)
				(mid 126.236167 -11.913635)
				(end 127.119888 -9.780016)
			)
			(arc
				(start 127.119888 -9.223756)
				(mid 127.113727 -9.202804)
				(end 127.099314 -9.186418)
			)
			(arc
				(start 127.099314 -9.186418)
				(mid 126.839825 -8.890054)
				(end 126.728982 -8.512048)
			)
			(xy 126.700534 -8.46963) (xy 126.687326 -8.463026)
			(arc
				(start 126.66345 -8.457184)
				(mid 126.627619 -8.471973)
				(end 126.61265 -8.50773)
			)
			(arc
				(start 126.61265 -9.780016)
				(mid 125.877331 -11.555233)
				(end 124.102114 -12.290552)
			)
			(arc
				(start 83.70189 -12.290552)
				(mid 81.926673 -11.555233)
				(end 81.191354 -9.780016)
			)
			(xy 81.191354 -1.28524) (xy 81.19364 -1.28524)
			(arc
				(start 81.19364 -0.999998)
				(mid 81.049612 -0.652282)
				(end 80.701896 -0.508254)
			)
			(arc
				(start 14.10208 -0.508254)
				(mid 13.754364 -0.652282)
				(end 13.610336 -0.999998)
			)
			(xy 13.610336 -1.28524) (xy 13.612622 -1.28524)
			(arc
				(start 13.612622 -9.780016)
				(mid 12.877303 -11.555233)
				(end 11.102086 -12.290552)
			)
			(arc
				(start 1.999996 -12.290552)
				(mid 0.946792 -12.726804)
				(end 0.51054 -13.780008)
			)
			(arc
				(start 0.51054 -17.769332)
				(mid 0.517626 -17.795211)
				(end 0.536956 -17.813782)
			)
			(xy 0.62738 -17.863566)
		)
		(stroke
			(width 0)
			(type solid)
		)
		(fill yes)
		(layer "In4.Cu")
		(net "GND")
	)
	(gr_poly
		(pts
			(xy 62.50432 -25.782524) (xy 62.517934 -25.782087) (xy 62.544192 -25.774886) (xy 62.567614 -25.761)
			(xy 62.586533 -25.741419) (xy 62.599603 -25.717533) (xy 62.605896 -25.691043) (xy 62.604965 -25.663831)
			(xy 62.601348 -25.650698) (xy 62.59337 -25.62319) (xy 62.58482 -25.566559) (xy 62.58433 -25.537922)
			(xy 62.584816 -25.510671) (xy 62.592572 -25.456723) (xy 62.607927 -25.404428) (xy 62.630569 -25.354851)
			(xy 62.660035 -25.309001) (xy 62.695726 -25.26781) (xy 62.736917 -25.232119) (xy 62.782767 -25.202653)
			(xy 62.832344 -25.180011) (xy 62.884639 -25.164656) (xy 62.938587 -25.1569) (xy 62.993089 -25.1569)
			(xy 63.047037 -25.164656) (xy 63.099332 -25.180011) (xy 63.148909 -25.202653) (xy 63.194759 -25.232119)
			(xy 63.23595 -25.26781) (xy 63.271641 -25.309001) (xy 63.301107 -25.354851) (xy 63.323749 -25.404428)
			(xy 63.339104 -25.456723) (xy 63.34686 -25.510671) (xy 63.347346 -25.537922) (xy 63.346803 -25.566555)
			(xy 63.338255 -25.623179) (xy 63.330328 -25.650698) (xy 63.326695 -25.663825) (xy 63.325761 -25.691035)
			(xy 63.332055 -25.717524) (xy 63.34513 -25.741406) (xy 63.364054 -25.760981) (xy 63.387481 -25.774854)
			(xy 63.413742 -25.782039) (xy 63.427356 -25.782524) (xy 63.477902 -25.782524) (xy 63.492417 -25.78201)
			(xy 63.520275 -25.773842) (xy 63.54471 -25.758168) (xy 63.563749 -25.736252) (xy 63.575854 -25.709865)
			(xy 63.580046 -25.681139) (xy 63.578486 -25.6667) (xy 63.576795 -25.653622) (xy 63.575013 -25.627309)
			(xy 63.57493 -25.614122) (xy 63.575416 -25.586871) (xy 63.583172 -25.532923) (xy 63.598527 -25.480628)
			(xy 63.621169 -25.431051) (xy 63.650635 -25.385201) (xy 63.686326 -25.34401) (xy 63.727517 -25.308319)
			(xy 63.773367 -25.278853) (xy 63.822944 -25.256211) (xy 63.875239 -25.240856) (xy 63.929187 -25.2331)
			(xy 63.983689 -25.2331) (xy 64.037637 -25.240856) (xy 64.089932 -25.256211) (xy 64.139509 -25.278853)
			(xy 64.185359 -25.308319) (xy 64.22655 -25.34401) (xy 64.262241 -25.385201) (xy 64.291707 -25.431051)
			(xy 64.314349 -25.480628) (xy 64.329704 -25.532923) (xy 64.33746 -25.586871) (xy 64.337946 -25.614122)
			(xy 64.337847 -25.627308) (xy 64.336066 -25.65362) (xy 64.33439 -25.6667) (xy 64.332871 -25.68114)
			(xy 64.337061 -25.709857) (xy 64.349161 -25.736236) (xy 64.368191 -25.758147) (xy 64.392616 -25.77382)
			(xy 64.420464 -25.78199) (xy 64.434974 -25.782524) (xy 69.158104 -25.782524) (xy 70.26656 -24.674068)
			(xy 70.26656 -14.272768) (xy 68.16852 -12.174728) (xy 62.86754 -12.174728) (xy 62.13602 -12.906248)
			(xy 62.13602 -14.80566) (xy 62.171072 -14.81709) (xy 62.197659 -14.826341) (xy 62.247987 -14.851556)
			(xy 62.294062 -14.883895) (xy 62.334884 -14.922655) (xy 62.369565 -14.966994) (xy 62.397353 -15.015949)
			(xy 62.417643 -15.068457) (xy 62.429996 -15.123376) (xy 62.434142 -15.179515) (xy 62.429991 -15.235653)
			(xy 62.417635 -15.290572) (xy 62.39734 -15.343078) (xy 62.369549 -15.392031) (xy 62.334864 -15.436367)
			(xy 62.294039 -15.475124) (xy 62.247961 -15.507459) (xy 62.197631 -15.53267) (xy 62.171072 -15.542006)
			(xy 62.13602 -15.553436) (xy 62.13602 -16.75638) (xy 62.136483 -16.770555) (xy 62.144274 -16.797814)
			(xy 62.159259 -16.82188) (xy 62.180284 -16.840897) (xy 62.205728 -16.853401) (xy 62.233629 -16.858425)
			(xy 62.24778 -16.857472) (xy 62.28588 -16.85544) (xy 62.31313 -16.855902) (xy 62.367077 -16.863656)
			(xy 62.41937 -16.879008) (xy 62.468947 -16.901646) (xy 62.514797 -16.93111) (xy 62.555986 -16.966799)
			(xy 62.591678 -17.007987) (xy 62.621144 -17.053836) (xy 62.643785 -17.103411) (xy 62.65914 -17.155704)
			(xy 62.666897 -17.20965) (xy 62.666897 -17.26415) (xy 62.65914 -17.318096) (xy 62.643785 -17.370389)
			(xy 62.621144 -17.419964) (xy 62.591678 -17.465813) (xy 62.555986 -17.507001) (xy 62.514797 -17.54269)
			(xy 62.468947 -17.572154) (xy 62.41937 -17.594792) (xy 62.367077 -17.610144) (xy 62.31313 -17.617898)
			(xy 62.28588 -17.618456) (xy 62.24778 -17.616424) (xy 62.233629 -17.615467) (xy 62.205726 -17.620492)
			(xy 62.180281 -17.632996) (xy 62.159255 -17.652014) (xy 62.144268 -17.67608) (xy 62.136477 -17.70334)
			(xy 62.13602 -17.717516) (xy 62.13602 -18.280144) (xy 62.539926 -18.280144) (xy 62.539926 -18.225651)
			(xy 62.547682 -18.171712) (xy 62.563034 -18.119426) (xy 62.585671 -18.069856) (xy 62.615132 -18.024013)
			(xy 62.650817 -17.982829) (xy 62.691999 -17.947142) (xy 62.737841 -17.917679) (xy 62.787409 -17.89504)
			(xy 62.839695 -17.879685) (xy 62.893633 -17.871928) (xy 62.92088 -17.87144) (xy 62.935864 -17.871546)
			(xy 62.965744 -17.873838) (xy 62.98057 -17.876012) (xy 62.994395 -17.877749) (xy 63.022057 -17.874491)
			(xy 63.047809 -17.863876) (xy 63.069732 -17.846695) (xy 63.086194 -17.824227) (xy 63.09597 -17.798146)
			(xy 63.09833 -17.770392) (xy 63.09614 -17.756632) (xy 63.09292 -17.738708) (xy 63.089488 -17.702452)
			(xy 63.089282 -17.684242) (xy 63.08971 -17.656985) (xy 63.097462 -17.603026) (xy 63.112815 -17.550719)
			(xy 63.135456 -17.50113) (xy 63.164924 -17.455268) (xy 63.200619 -17.414066) (xy 63.241814 -17.378364)
			(xy 63.287671 -17.348888) (xy 63.337257 -17.326239) (xy 63.389561 -17.310877) (xy 63.443519 -17.303115)
			(xy 63.498032 -17.303111) (xy 63.551991 -17.310866) (xy 63.604297 -17.326221) (xy 63.653885 -17.348864)
			(xy 63.699746 -17.378334) (xy 63.740946 -17.414031) (xy 63.776647 -17.455228) (xy 63.80612 -17.501087)
			(xy 63.828768 -17.550673) (xy 63.844127 -17.602978) (xy 63.851886 -17.656936) (xy 63.851888 -17.711449)
			(xy 63.84413 -17.765408) (xy 63.828773 -17.817713) (xy 63.806127 -17.867301) (xy 63.776655 -17.91316)
			(xy 63.740957 -17.954359) (xy 63.699758 -17.990057) (xy 63.653898 -18.019529) (xy 63.604311 -18.042174)
			(xy 63.552005 -18.057531) (xy 63.498047 -18.065288) (xy 63.47079 -18.06575) (xy 63.455806 -18.065635)
			(xy 63.425926 -18.063349) (xy 63.4111 -18.061178) (xy 63.397278 -18.059423) (xy 63.369615 -18.062688)
			(xy 63.343865 -18.073307) (xy 63.321942 -18.090491) (xy 63.305481 -18.112961) (xy 63.295705 -18.139043)
			(xy 63.293342 -18.166797) (xy 63.29553 -18.180558) (xy 63.298748 -18.198482) (xy 63.302181 -18.234739)
			(xy 63.302388 -18.252948) (xy 63.30187 -18.280195) (xy 63.294109 -18.334133) (xy 63.27875 -18.386417)
			(xy 63.256107 -18.435984) (xy 63.226641 -18.481823) (xy 63.190951 -18.523003) (xy 63.149765 -18.558685)
			(xy 63.103919 -18.588142) (xy 63.054348 -18.610776) (xy 63.002061 -18.626124) (xy 62.948121 -18.633876)
			(xy 62.893628 -18.633872) (xy 62.83969 -18.626114) (xy 62.787404 -18.610758) (xy 62.737836 -18.588118)
			(xy 62.691995 -18.558655) (xy 62.650813 -18.522967) (xy 62.615129 -18.481783) (xy 62.585668 -18.435939)
			(xy 62.563032 -18.386369) (xy 62.54768 -18.334083) (xy 62.539926 -18.280144) (xy 62.13602 -18.280144)
			(xy 62.13602 -19.268948) (xy 62.538862 -19.268948) (xy 62.542933 -19.213326) (xy 62.555059 -19.158889)
			(xy 62.574982 -19.106798) (xy 62.602278 -19.058163) (xy 62.636364 -19.01402) (xy 62.676513 -18.975311)
			(xy 62.721871 -18.94286) (xy 62.771471 -18.917359) (xy 62.824255 -18.899352) (xy 62.879098 -18.889222)
			(xy 62.934832 -18.887185) (xy 62.990269 -18.893285) (xy 63.044226 -18.907391) (xy 63.095555 -18.929203)
			(xy 63.143161 -18.958257) (xy 63.186029 -18.993932) (xy 63.223246 -19.035469) (xy 63.254019 -19.081982)
			(xy 63.277691 -19.132479) (xy 63.293759 -19.185886) (xy 63.301879 -19.241062) (xy 63.302388 -19.268948)
			(xy 63.301879 -19.296834) (xy 63.293759 -19.35201) (xy 63.277691 -19.405417) (xy 63.254019 -19.455914)
			(xy 63.223246 -19.502427) (xy 63.186029 -19.543964) (xy 63.143161 -19.579639) (xy 63.095555 -19.608693)
			(xy 63.044226 -19.630505) (xy 62.990269 -19.644611) (xy 62.934832 -19.650711) (xy 62.879098 -19.648674)
			(xy 62.824255 -19.638544) (xy 62.771471 -19.620537) (xy 62.721871 -19.595036) (xy 62.676513 -19.562585)
			(xy 62.636364 -19.523876) (xy 62.602278 -19.479733) (xy 62.574982 -19.431098) (xy 62.555059 -19.379007)
			(xy 62.542933 -19.32457) (xy 62.538862 -19.268948) (xy 62.13602 -19.268948) (xy 62.13602 -23.404322)
			(xy 62.63462 -23.404322) (xy 62.638691 -23.3487) (xy 62.650817 -23.294263) (xy 62.67074 -23.242172)
			(xy 62.698036 -23.193537) (xy 62.732122 -23.149394) (xy 62.772271 -23.110685) (xy 62.817629 -23.078234)
			(xy 62.867229 -23.052733) (xy 62.920013 -23.034726) (xy 62.974856 -23.024596) (xy 63.03059 -23.022559)
			(xy 63.086027 -23.028659) (xy 63.139984 -23.042765) (xy 63.191313 -23.064577) (xy 63.238919 -23.093631)
			(xy 63.281787 -23.129306) (xy 63.319004 -23.170843) (xy 63.349777 -23.217356) (xy 63.373449 -23.267853)
			(xy 63.389517 -23.32126) (xy 63.397637 -23.376436) (xy 63.398146 -23.404322) (xy 63.397637 -23.432208)
			(xy 63.389517 -23.487384) (xy 63.373449 -23.540791) (xy 63.349777 -23.591288) (xy 63.319004 -23.637801)
			(xy 63.281787 -23.679338) (xy 63.238919 -23.715013) (xy 63.191313 -23.744067) (xy 63.139984 -23.765879)
			(xy 63.086027 -23.779985) (xy 63.03059 -23.786085) (xy 62.974856 -23.784048) (xy 62.920013 -23.773918)
			(xy 62.867229 -23.755911) (xy 62.817629 -23.73041) (xy 62.772271 -23.697959) (xy 62.732122 -23.65925)
			(xy 62.698036 -23.615107) (xy 62.67074 -23.566472) (xy 62.650817 -23.514381) (xy 62.638691 -23.459944)
			(xy 62.63462 -23.404322) (xy 62.13602 -23.404322) (xy 62.13602 -25.657048) (xy 62.261496 -25.782524)
		)
		(stroke
			(width 0)
			(type solid)
		)
		(fill yes)
		(layer "In4.Cu")
		(net "P12V_OCP_V3_2")
	)
	(gr_poly
		(pts
			(xy 179.63388 -110.378748) (xy 179.63388 -107.370118) (xy 179.633413 -107.355628) (xy 179.625352 -107.327796)
			(xy 179.609791 -107.303353) (xy 179.587983 -107.284272) (xy 179.561691 -107.272093) (xy 179.533034 -107.267799)
			(xy 179.504327 -107.271737) (xy 179.490878 -107.277154) (xy 179.469537 -107.286298) (xy 179.424933 -107.299184)
			(xy 179.378964 -107.305694) (xy 179.35575 -107.30611) (xy 179.329765 -107.305597) (xy 179.278436 -107.29746)
			(xy 179.229012 -107.281394) (xy 179.182709 -107.257796) (xy 179.140668 -107.227245) (xy 179.103923 -107.190494)
			(xy 179.073378 -107.148448) (xy 179.049786 -107.102141) (xy 179.033728 -107.052715) (xy 179.025599 -107.001385)
			(xy 179.025599 -106.949415) (xy 179.033728 -106.898085) (xy 179.049786 -106.848659) (xy 179.073378 -106.802352)
			(xy 179.103923 -106.760306) (xy 179.140668 -106.723555) (xy 179.182709 -106.693004) (xy 179.229012 -106.669406)
			(xy 179.278436 -106.65334) (xy 179.329765 -106.645203) (xy 179.35575 -106.644694) (xy 179.382611 -106.645214)
			(xy 179.435629 -106.65389) (xy 179.486547 -106.671021) (xy 179.534027 -106.696157) (xy 179.576819 -106.728637)
			(xy 179.613799 -106.767607) (xy 179.643993 -106.812041) (xy 179.655724 -106.83621) (xy 179.661997 -106.848719)
			(xy 179.680189 -106.869968) (xy 179.703462 -106.885489) (xy 179.73007 -106.894119) (xy 179.758022 -106.895211)
			(xy 179.785223 -106.888684) (xy 179.809636 -106.875027) (xy 179.819808 -106.86542) (xy 179.96408 -106.721148)
			(xy 179.96408 -101.133148) (xy 179.83708 -101.006148) (xy 179.76723 -101.006148) (xy 179.761896 -101.007418)
			(xy 179.741578 -101.011589) (xy 179.70034 -101.016048) (xy 179.6796 -101.016308) (xy 179.658859 -101.016064)
			(xy 179.617618 -101.01161) (xy 179.597304 -101.007418) (xy 179.59197 -101.006148) (xy 178.628548 -101.006148)
			(xy 178.607946 -101.024758) (xy 178.562196 -101.056206) (xy 178.512246 -101.080436) (xy 178.459227 -101.0969)
			(xy 178.404338 -101.105224) (xy 178.37658 -101.105716) (xy 177.476912 -101.105716) (xy 177.449988 -101.13264)
			(xy 177.449988 -102.570534) (xy 177.452782 -102.578916) (xy 177.463293 -102.610136) (xy 177.474666 -102.675015)
			(xy 177.475388 -102.707948) (xy 177.474676 -102.740883) (xy 177.463312 -102.805766) (xy 177.452782 -102.83698)
			(xy 177.449988 -102.845362) (xy 177.449988 -103.689404) (xy 177.449988 -103.698548) (xy 177.449988 -104.426237)
			(xy 178.91251 -104.426237) (xy 178.91251 -104.372939) (xy 178.920453 -104.320235) (xy 178.936163 -104.269305)
			(xy 178.959289 -104.221284) (xy 178.989313 -104.177247) (xy 179.025565 -104.138176) (xy 179.067236 -104.104945)
			(xy 179.113394 -104.078296) (xy 179.163008 -104.058824) (xy 179.21497 -104.046964) (xy 179.26812 -104.042981)
			(xy 179.32127 -104.046964) (xy 179.373232 -104.058824) (xy 179.422846 -104.078296) (xy 179.469004 -104.104945)
			(xy 179.510675 -104.138176) (xy 179.546927 -104.177247) (xy 179.576951 -104.221284) (xy 179.600077 -104.269305)
			(xy 179.615787 -104.320235) (xy 179.62373 -104.372939) (xy 179.624228 -104.399588) (xy 179.62373 -104.426237)
			(xy 179.615787 -104.478941) (xy 179.600077 -104.529871) (xy 179.576951 -104.577892) (xy 179.546927 -104.621929)
			(xy 179.510675 -104.661) (xy 179.469004 -104.694231) (xy 179.422846 -104.72088) (xy 179.373232 -104.740352)
			(xy 179.32127 -104.752212) (xy 179.26812 -104.756196) (xy 179.21497 -104.752212) (xy 179.163008 -104.740352)
			(xy 179.113394 -104.72088) (xy 179.067236 -104.694231) (xy 179.025565 -104.661) (xy 178.989313 -104.621929)
			(xy 178.959289 -104.577892) (xy 178.936163 -104.529871) (xy 178.920453 -104.478941) (xy 178.91251 -104.426237)
			(xy 177.449988 -104.426237) (xy 177.449988 -104.994456) (xy 177.450475 -105.009483) (xy 177.459128 -105.038262)
			(xy 177.475785 -105.063275) (xy 177.499003 -105.082354) (xy 177.52677 -105.093846) (xy 177.556681 -105.096755)
			(xy 177.586142 -105.090829) (xy 177.599594 -105.084118) (xy 177.623762 -105.071765) (xy 177.67513 -105.054245)
			(xy 177.728668 -105.045341) (xy 177.755804 -105.044748) (xy 177.781794 -105.045258) (xy 177.833135 -105.05339)
			(xy 177.882572 -105.069454) (xy 177.928887 -105.093053) (xy 177.97094 -105.123607) (xy 178.007696 -105.160363)
			(xy 178.038249 -105.202416) (xy 178.061848 -105.248732) (xy 178.077911 -105.298169) (xy 178.086042 -105.34951)
			(xy 178.086042 -105.401443) (xy 178.225452 -105.401443) (xy 178.225452 -105.349469) (xy 178.233582 -105.298134)
			(xy 178.249643 -105.248704) (xy 178.273239 -105.202394) (xy 178.303789 -105.160346) (xy 178.34054 -105.123595)
			(xy 178.382588 -105.093045) (xy 178.428898 -105.069449) (xy 178.478328 -105.053388) (xy 178.529663 -105.045258)
			(xy 178.581637 -105.045258) (xy 178.632972 -105.053388) (xy 178.682402 -105.069449) (xy 178.728712 -105.093045)
			(xy 178.77076 -105.123595) (xy 178.807511 -105.160346) (xy 178.838061 -105.202394) (xy 178.861657 -105.248704)
			(xy 178.877718 -105.298134) (xy 178.885848 -105.349469) (xy 178.886358 -105.375456) (xy 178.885848 -105.401443)
			(xy 178.877718 -105.452778) (xy 178.861657 -105.502208) (xy 178.838061 -105.548518) (xy 178.807511 -105.590566)
			(xy 178.77076 -105.627317) (xy 178.728712 -105.657867) (xy 178.682402 -105.681463) (xy 178.632972 -105.697524)
			(xy 178.581637 -105.705654) (xy 178.529663 -105.705654) (xy 178.478328 -105.697524) (xy 178.428898 -105.681463)
			(xy 178.382588 -105.657867) (xy 178.34054 -105.627317) (xy 178.303789 -105.590566) (xy 178.273239 -105.548518)
			(xy 178.249643 -105.502208) (xy 178.233582 -105.452778) (xy 178.225452 -105.401443) (xy 178.086042 -105.401443)
			(xy 178.086042 -105.40149) (xy 178.077911 -105.452831) (xy 178.061848 -105.502268) (xy 178.038249 -105.548584)
			(xy 178.007696 -105.590637) (xy 177.97094 -105.627393) (xy 177.928887 -105.657947) (xy 177.882572 -105.681546)
			(xy 177.833135 -105.69761) (xy 177.781794 -105.705742) (xy 177.755804 -105.706164) (xy 177.728665 -105.7056)
			(xy 177.675123 -105.696699) (xy 177.623754 -105.679167) (xy 177.599594 -105.666794) (xy 177.586116 -105.660174)
			(xy 177.556684 -105.654292) (xy 177.526813 -105.657218) (xy 177.499083 -105.668701) (xy 177.475888 -105.687749)
			(xy 177.459231 -105.712717) (xy 177.450551 -105.741448) (xy 177.449988 -105.756456) (xy 177.449988 -107.394502)
			(xy 177.450546 -107.409471) (xy 177.45928 -107.438107) (xy 177.475939 -107.462984) (xy 177.499093 -107.481964)
			(xy 177.526754 -107.49342) (xy 177.556548 -107.496366) (xy 177.585917 -107.490552) (xy 177.59934 -107.48391)
			(xy 177.623519 -107.471599) (xy 177.674893 -107.45416) (xy 177.728423 -107.445326) (xy 177.75555 -107.444794)
			(xy 177.781542 -107.445273) (xy 177.832886 -107.453398) (xy 177.882327 -107.469456) (xy 177.928647 -107.493051)
			(xy 177.970705 -107.523602) (xy 178.007465 -107.560357) (xy 178.038023 -107.602411) (xy 178.061625 -107.648727)
			(xy 178.07769 -107.698165) (xy 178.085823 -107.749508) (xy 178.085823 -107.801492) (xy 178.07769 -107.852835)
			(xy 178.061625 -107.902273) (xy 178.038023 -107.948589) (xy 178.007465 -107.990643) (xy 177.970705 -108.027398)
			(xy 177.928647 -108.057949) (xy 177.882327 -108.081544) (xy 177.832886 -108.097602) (xy 177.781542 -108.105727)
			(xy 177.75555 -108.10621) (xy 177.728421 -108.10569) (xy 177.674884 -108.096877) (xy 177.623508 -108.07943)
			(xy 177.59934 -108.067094) (xy 177.585886 -108.060531) (xy 177.556533 -108.054727) (xy 177.526758 -108.057673)
			(xy 177.499112 -108.069117) (xy 177.475966 -108.088078) (xy 177.459303 -108.11293) (xy 177.450553 -108.141543)
			(xy 177.449988 -108.156502) (xy 177.449988 -108.194348) (xy 177.450552 -108.209311) (xy 177.459294 -108.237936)
			(xy 177.475954 -108.2628) (xy 177.499103 -108.281771) (xy 177.526756 -108.29322) (xy 177.556541 -108.296167)
			(xy 177.585901 -108.290357) (xy 177.59934 -108.283756) (xy 177.623518 -108.271444) (xy 177.674893 -108.254001)
			(xy 177.728423 -108.245166) (xy 177.75555 -108.24464) (xy 177.781538 -108.245119) (xy 177.832875 -108.253243)
			(xy 177.882309 -108.269299) (xy 177.928623 -108.29289) (xy 177.970675 -108.323437) (xy 178.00743 -108.360187)
			(xy 178.037984 -108.402235) (xy 178.061582 -108.448544) (xy 178.077645 -108.497976) (xy 178.085777 -108.549312)
			(xy 178.085777 -108.601288) (xy 178.077645 -108.652624) (xy 178.061582 -108.702056) (xy 178.037984 -108.748365)
			(xy 178.00743 -108.790413) (xy 177.970675 -108.827163) (xy 177.928623 -108.85771) (xy 177.882309 -108.881301)
			(xy 177.832875 -108.897357) (xy 177.781538 -108.905481) (xy 177.75555 -108.906056) (xy 177.728421 -108.905536)
			(xy 177.674884 -108.896722) (xy 177.62351 -108.879272) (xy 177.59934 -108.86694) (xy 177.585888 -108.860375)
			(xy 177.556538 -108.854568) (xy 177.526765 -108.857514) (xy 177.499122 -108.868959) (xy 177.475981 -108.887922)
			(xy 177.459327 -108.912777) (xy 177.450588 -108.94139) (xy 177.449988 -108.956348) (xy 177.449988 -108.994448)
			(xy 177.450552 -109.009411) (xy 177.459294 -109.038036) (xy 177.475954 -109.0629) (xy 177.499103 -109.081871)
			(xy 177.526756 -109.09332) (xy 177.556541 -109.096267) (xy 177.585901 -109.090457) (xy 177.59934 -109.083856)
			(xy 177.623518 -109.071544) (xy 177.674893 -109.054101) (xy 177.728423 -109.045266) (xy 177.75555 -109.04474)
			(xy 177.781538 -109.045219) (xy 177.832875 -109.053343) (xy 177.882309 -109.069399) (xy 177.928623 -109.09299)
			(xy 177.970675 -109.123537) (xy 178.00743 -109.160287) (xy 178.037984 -109.202335) (xy 178.061582 -109.248644)
			(xy 178.077645 -109.298076) (xy 178.085777 -109.349412) (xy 178.085777 -109.401388) (xy 178.077645 -109.452724)
			(xy 178.061582 -109.502156) (xy 178.037984 -109.548465) (xy 178.00743 -109.590513) (xy 177.970675 -109.627263)
			(xy 177.928623 -109.65781) (xy 177.882309 -109.681401) (xy 177.832875 -109.697457) (xy 177.781538 -109.705581)
			(xy 177.75555 -109.706156) (xy 177.728421 -109.705636) (xy 177.674884 -109.696822) (xy 177.62351 -109.679372)
			(xy 177.59934 -109.66704) (xy 177.585888 -109.660475) (xy 177.556538 -109.654668) (xy 177.526765 -109.657614)
			(xy 177.499122 -109.669059) (xy 177.475981 -109.688022) (xy 177.459327 -109.712877) (xy 177.450588 -109.74149)
			(xy 177.449988 -109.756448) (xy 177.449988 -110.328456) (xy 177.57648 -110.454948) (xy 179.55768 -110.454948)
		)
		(stroke
			(width 0)
			(type solid)
		)
		(fill yes)
		(layer "In4.Cu")
		(net "P3V3_AUX_FPGA_VCCIO4")
	)
	(gr_poly
		(pts
			(arc
				(start 208.044796 -400.004534)
				(mid 208.093127 -400.09105)
				(end 208.192116 -400.095212)
			)
			(arc
				(start 208.192116 -400.095212)
				(mid 208.264455 -400.068723)
				(end 208.34096 -400.059652)
			)
			(arc
				(start 208.656428 -400.059652)
				(mid 208.734475 -400.0231)
				(end 208.75625 -399.939764)
			)
			(arc
				(start 208.75625 -399.939764)
				(mid 208.751491 -399.905238)
				(end 208.7499 -399.870422)
			)
			(arc
				(start 208.7499 -399.870422)
				(mid 208.788635 -399.702926)
				(end 208.896966 -399.569432)
			)
			(arc
				(start 208.896966 -399.569432)
				(mid 208.936 -399.489422)
				(end 208.896966 -399.409412)
			)
			(arc
				(start 208.896966 -399.409412)
				(mid 208.749887 -399.108422)
				(end 208.896966 -398.807432)
			)
			(arc
				(start 208.896966 -398.807432)
				(mid 208.936 -398.727422)
				(end 208.896966 -398.647412)
			)
			(arc
				(start 208.896966 -398.647412)
				(mid 208.749887 -398.346422)
				(end 208.896966 -398.045432)
			)
			(arc
				(start 208.896966 -398.045432)
				(mid 208.936 -397.965422)
				(end 208.896966 -397.885412)
			)
			(arc
				(start 208.896966 -397.885412)
				(mid 208.749887 -397.584422)
				(end 208.896966 -397.283432)
			)
			(arc
				(start 208.896966 -397.283432)
				(mid 208.936 -397.203422)
				(end 208.896966 -397.123412)
			)
			(arc
				(start 208.896966 -397.123412)
				(mid 208.749887 -396.822422)
				(end 208.896966 -396.521432)
			)
			(arc
				(start 208.896966 -396.521432)
				(mid 208.936 -396.441422)
				(end 208.896966 -396.361412)
			)
			(arc
				(start 208.896966 -396.361412)
				(mid 208.788623 -396.227924)
				(end 208.7499 -396.060422)
			)
			(arc
				(start 208.7499 -396.060422)
				(mid 208.861641 -395.790655)
				(end 209.131408 -395.678914)
			)
			(arc
				(start 209.131408 -395.678914)
				(mid 209.298904 -395.717649)
				(end 209.432398 -395.82598)
			)
			(arc
				(start 209.432398 -395.82598)
				(mid 209.512408 -395.865014)
				(end 209.592418 -395.82598)
			)
			(arc
				(start 209.592418 -395.82598)
				(mid 209.893408 -395.678901)
				(end 210.194398 -395.82598)
			)
			(arc
				(start 210.194398 -395.82598)
				(mid 210.274408 -395.865014)
				(end 210.354418 -395.82598)
			)
			(arc
				(start 210.354418 -395.82598)
				(mid 210.655408 -395.678901)
				(end 210.956398 -395.82598)
			)
			(arc
				(start 210.956398 -395.82598)
				(mid 211.036408 -395.865014)
				(end 211.116418 -395.82598)
			)
			(arc
				(start 211.116418 -395.82598)
				(mid 211.417408 -395.678901)
				(end 211.718398 -395.82598)
			)
			(arc
				(start 211.718398 -395.82598)
				(mid 211.798408 -395.865014)
				(end 211.878418 -395.82598)
			)
			(arc
				(start 211.878418 -395.82598)
				(mid 212.179408 -395.678901)
				(end 212.480398 -395.82598)
			)
			(arc
				(start 212.480398 -395.82598)
				(mid 212.560408 -395.865014)
				(end 212.640418 -395.82598)
			)
			(arc
				(start 212.640418 -395.82598)
				(mid 212.941408 -395.678901)
				(end 213.242398 -395.82598)
			)
			(arc
				(start 213.242398 -395.82598)
				(mid 213.322408 -395.865014)
				(end 213.402418 -395.82598)
			)
			(arc
				(start 213.402418 -395.82598)
				(mid 213.535906 -395.717637)
				(end 213.703408 -395.678914)
			)
			(arc
				(start 213.703408 -395.678914)
				(mid 213.973175 -395.790655)
				(end 214.084916 -396.060422)
			)
			(arc
				(start 214.084916 -396.060422)
				(mid 214.046181 -396.227918)
				(end 213.93785 -396.361412)
			)
			(arc
				(start 213.93785 -396.361412)
				(mid 213.898816 -396.441422)
				(end 213.93785 -396.521432)
			)
			(arc
				(start 213.93785 -396.521432)
				(mid 214.084929 -396.822422)
				(end 213.93785 -397.123412)
			)
			(arc
				(start 213.93785 -397.123412)
				(mid 213.898816 -397.203422)
				(end 213.93785 -397.283432)
			)
			(arc
				(start 213.93785 -397.283432)
				(mid 214.084929 -397.584422)
				(end 213.93785 -397.885412)
			)
			(arc
				(start 213.93785 -397.885412)
				(mid 213.898816 -397.965422)
				(end 213.93785 -398.045432)
			)
			(arc
				(start 213.93785 -398.045432)
				(mid 214.084929 -398.346422)
				(end 213.93785 -398.647412)
			)
			(arc
				(start 213.93785 -398.647412)
				(mid 213.898816 -398.727422)
				(end 213.93785 -398.807432)
			)
			(arc
				(start 213.93785 -398.807432)
				(mid 214.084929 -399.108422)
				(end 213.93785 -399.409412)
			)
			(arc
				(start 213.93785 -399.409412)
				(mid 213.898816 -399.489422)
				(end 213.93785 -399.569432)
			)
			(arc
				(start 213.93785 -399.569432)
				(mid 214.046193 -399.70292)
				(end 214.084916 -399.870422)
			)
			(arc
				(start 214.084916 -399.870422)
				(mid 214.083325 -399.905238)
				(end 214.078566 -399.939764)
			)
			(arc
				(start 214.078566 -399.939764)
				(mid 214.10043 -400.023025)
				(end 214.178388 -400.059652)
			)
			(arc
				(start 216.712546 -400.059652)
				(mid 216.749873 -400.061881)
				(end 216.786714 -400.068288)
			)
			(arc
				(start 216.786714 -400.068288)
				(mid 216.872672 -400.048666)
				(end 216.91092 -399.969228)
			)
			(xy 216.91092 -392.158728) (xy 216.416382 -391.663936) (xy 209.001614 -391.663936) (xy 208.044796 -392.621008)
		)
		(stroke
			(width 0)
			(type solid)
		)
		(fill yes)
		(layer "In4.Cu")
		(net "AGND_HSC")
	)
	(gr_poly
		(pts
			(arc
				(start 196.914516 -400.813778)
				(mid 196.980701 -400.908752)
				(end 197.092824 -400.880072)
			)
			(xy 197.10908 -400.8628)
			(arc
				(start 197.82028 -400.1516)
				(mid 197.904564 -400.090503)
				(end 198.003668 -400.058636)
			)
			(arc
				(start 198.003668 -400.058636)
				(mid 198.071127 -400.017121)
				(end 198.08825 -399.939764)
			)
			(arc
				(start 198.08825 -399.939764)
				(mid 198.083491 -399.905238)
				(end 198.0819 -399.870422)
			)
			(arc
				(start 198.0819 -399.870422)
				(mid 198.120635 -399.702926)
				(end 198.228966 -399.569432)
			)
			(arc
				(start 198.228966 -399.569432)
				(mid 198.268 -399.489422)
				(end 198.228966 -399.409412)
			)
			(arc
				(start 198.228966 -399.409412)
				(mid 198.081887 -399.108422)
				(end 198.228966 -398.807432)
			)
			(arc
				(start 198.228966 -398.807432)
				(mid 198.268 -398.727422)
				(end 198.228966 -398.647412)
			)
			(arc
				(start 198.228966 -398.647412)
				(mid 198.081887 -398.346422)
				(end 198.228966 -398.045432)
			)
			(arc
				(start 198.228966 -398.045432)
				(mid 198.268 -397.965422)
				(end 198.228966 -397.885412)
			)
			(arc
				(start 198.228966 -397.885412)
				(mid 198.081887 -397.584422)
				(end 198.228966 -397.283432)
			)
			(arc
				(start 198.228966 -397.283432)
				(mid 198.268 -397.203422)
				(end 198.228966 -397.123412)
			)
			(arc
				(start 198.228966 -397.123412)
				(mid 198.081887 -396.822422)
				(end 198.228966 -396.521432)
			)
			(arc
				(start 198.228966 -396.521432)
				(mid 198.268 -396.441422)
				(end 198.228966 -396.361412)
			)
			(arc
				(start 198.228966 -396.361412)
				(mid 198.120623 -396.227924)
				(end 198.0819 -396.060422)
			)
			(arc
				(start 198.0819 -396.060422)
				(mid 198.193641 -395.790655)
				(end 198.463408 -395.678914)
			)
			(arc
				(start 198.463408 -395.678914)
				(mid 198.630904 -395.717649)
				(end 198.764398 -395.82598)
			)
			(arc
				(start 198.764398 -395.82598)
				(mid 198.844408 -395.865014)
				(end 198.924418 -395.82598)
			)
			(arc
				(start 198.924418 -395.82598)
				(mid 199.225408 -395.678901)
				(end 199.526398 -395.82598)
			)
			(arc
				(start 199.526398 -395.82598)
				(mid 199.606408 -395.865014)
				(end 199.686418 -395.82598)
			)
			(arc
				(start 199.686418 -395.82598)
				(mid 199.987408 -395.678901)
				(end 200.288398 -395.82598)
			)
			(arc
				(start 200.288398 -395.82598)
				(mid 200.368408 -395.865014)
				(end 200.448418 -395.82598)
			)
			(arc
				(start 200.448418 -395.82598)
				(mid 200.749408 -395.678901)
				(end 201.050398 -395.82598)
			)
			(arc
				(start 201.050398 -395.82598)
				(mid 201.130408 -395.865014)
				(end 201.210418 -395.82598)
			)
			(arc
				(start 201.210418 -395.82598)
				(mid 201.511408 -395.678901)
				(end 201.812398 -395.82598)
			)
			(arc
				(start 201.812398 -395.82598)
				(mid 201.892408 -395.865014)
				(end 201.972418 -395.82598)
			)
			(arc
				(start 201.972418 -395.82598)
				(mid 202.273408 -395.678901)
				(end 202.574398 -395.82598)
			)
			(arc
				(start 202.574398 -395.82598)
				(mid 202.654408 -395.865014)
				(end 202.734418 -395.82598)
			)
			(arc
				(start 202.734418 -395.82598)
				(mid 202.867906 -395.717637)
				(end 203.035408 -395.678914)
			)
			(arc
				(start 203.035408 -395.678914)
				(mid 203.305175 -395.790655)
				(end 203.416916 -396.060422)
			)
			(arc
				(start 203.416916 -396.060422)
				(mid 203.378181 -396.227918)
				(end 203.26985 -396.361412)
			)
			(arc
				(start 203.26985 -396.361412)
				(mid 203.230816 -396.441422)
				(end 203.26985 -396.521432)
			)
			(arc
				(start 203.26985 -396.521432)
				(mid 203.416929 -396.822422)
				(end 203.26985 -397.123412)
			)
			(arc
				(start 203.26985 -397.123412)
				(mid 203.230816 -397.203422)
				(end 203.26985 -397.283432)
			)
			(arc
				(start 203.26985 -397.283432)
				(mid 203.416929 -397.584422)
				(end 203.26985 -397.885412)
			)
			(arc
				(start 203.26985 -397.885412)
				(mid 203.230816 -397.965422)
				(end 203.26985 -398.045432)
			)
			(arc
				(start 203.26985 -398.045432)
				(mid 203.416929 -398.346422)
				(end 203.26985 -398.647412)
			)
			(arc
				(start 203.26985 -398.647412)
				(mid 203.230816 -398.727422)
				(end 203.26985 -398.807432)
			)
			(arc
				(start 203.26985 -398.807432)
				(mid 203.416929 -399.108422)
				(end 203.26985 -399.409412)
			)
			(arc
				(start 203.26985 -399.409412)
				(mid 203.230816 -399.489422)
				(end 203.26985 -399.569432)
			)
			(arc
				(start 203.26985 -399.569432)
				(mid 203.378193 -399.70292)
				(end 203.416916 -399.870422)
			)
			(arc
				(start 203.416916 -399.870422)
				(mid 203.415529 -399.903182)
				(end 203.411328 -399.9357)
			)
			(arc
				(start 203.411328 -399.9357)
				(mid 203.433726 -400.018392)
				(end 203.511404 -400.054572)
			)
			(arc
				(start 206.039466 -400.054572)
				(mid 206.089714 -400.058529)
				(end 206.13878 -400.070066)
			)
			(arc
				(start 206.13878 -400.070066)
				(mid 206.229369 -400.05503)
				(end 206.27086 -399.973038)
			)
			(xy 206.27086 -392.415268) (xy 205.545182 -391.689336) (xy 197.198234 -391.689336) (xy 196.914516 -391.973308)
		)
		(stroke
			(width 0)
			(type solid)
		)
		(fill yes)
		(layer "In4.Cu")
		(net "AGND_HSC")
	)
	(gr_poly
		(pts
			(arc
				(start 227.597716 -400.392138)
				(mid 227.633136 -400.379395)
				(end 227.669598 -400.37004)
			)
			(xy 227.68052 -400.359118)
			(arc
				(start 227.671122 -400.329654)
				(mid 227.659191 -400.27973)
				(end 227.65512 -400.228562)
			)
			(xy 227.65512 -392.044428) (xy 227.079302 -391.468356) (xy 219.456254 -391.468356) (xy 218.834716 -392.090148)
			(arc
				(start 218.834716 -400.129502)
				(mid 218.897352 -400.223334)
				(end 219.007944 -400.201384)
			)
			(arc
				(start 219.068142 -400.14144)
				(mid 219.17534 -400.069719)
				(end 219.301822 -400.044412)
			)
			(arc
				(start 219.321888 -400.044412)
				(mid 219.398936 -400.00904)
				(end 219.422218 -399.927572)
			)
			(arc
				(start 219.422218 -399.927572)
				(mid 219.418991 -399.899078)
				(end 219.4179 -399.870422)
			)
			(arc
				(start 219.4179 -399.870422)
				(mid 219.456635 -399.702926)
				(end 219.564966 -399.569432)
			)
			(arc
				(start 219.564966 -399.569432)
				(mid 219.604 -399.489422)
				(end 219.564966 -399.409412)
			)
			(arc
				(start 219.564966 -399.409412)
				(mid 219.417887 -399.108422)
				(end 219.564966 -398.807432)
			)
			(arc
				(start 219.564966 -398.807432)
				(mid 219.604 -398.727422)
				(end 219.564966 -398.647412)
			)
			(arc
				(start 219.564966 -398.647412)
				(mid 219.417887 -398.346422)
				(end 219.564966 -398.045432)
			)
			(arc
				(start 219.564966 -398.045432)
				(mid 219.604 -397.965422)
				(end 219.564966 -397.885412)
			)
			(arc
				(start 219.564966 -397.885412)
				(mid 219.417887 -397.584422)
				(end 219.564966 -397.283432)
			)
			(arc
				(start 219.564966 -397.283432)
				(mid 219.604 -397.203422)
				(end 219.564966 -397.123412)
			)
			(arc
				(start 219.564966 -397.123412)
				(mid 219.417887 -396.822422)
				(end 219.564966 -396.521432)
			)
			(arc
				(start 219.564966 -396.521432)
				(mid 219.604 -396.441422)
				(end 219.564966 -396.361412)
			)
			(arc
				(start 219.564966 -396.361412)
				(mid 219.456623 -396.227924)
				(end 219.4179 -396.060422)
			)
			(arc
				(start 219.4179 -396.060422)
				(mid 219.529641 -395.790655)
				(end 219.799408 -395.678914)
			)
			(arc
				(start 219.799408 -395.678914)
				(mid 219.966904 -395.717649)
				(end 220.100398 -395.82598)
			)
			(arc
				(start 220.100398 -395.82598)
				(mid 220.180408 -395.865014)
				(end 220.260418 -395.82598)
			)
			(arc
				(start 220.260418 -395.82598)
				(mid 220.561408 -395.678901)
				(end 220.862398 -395.82598)
			)
			(arc
				(start 220.862398 -395.82598)
				(mid 220.942408 -395.865014)
				(end 221.022418 -395.82598)
			)
			(arc
				(start 221.022418 -395.82598)
				(mid 221.323408 -395.678901)
				(end 221.624398 -395.82598)
			)
			(arc
				(start 221.624398 -395.82598)
				(mid 221.704408 -395.865014)
				(end 221.784418 -395.82598)
			)
			(arc
				(start 221.784418 -395.82598)
				(mid 222.085408 -395.678901)
				(end 222.386398 -395.82598)
			)
			(arc
				(start 222.386398 -395.82598)
				(mid 222.466408 -395.865014)
				(end 222.546418 -395.82598)
			)
			(arc
				(start 222.546418 -395.82598)
				(mid 222.847408 -395.678901)
				(end 223.148398 -395.82598)
			)
			(arc
				(start 223.148398 -395.82598)
				(mid 223.228408 -395.865014)
				(end 223.308418 -395.82598)
			)
			(arc
				(start 223.308418 -395.82598)
				(mid 223.609408 -395.678901)
				(end 223.910398 -395.82598)
			)
			(arc
				(start 223.910398 -395.82598)
				(mid 223.990408 -395.865014)
				(end 224.070418 -395.82598)
			)
			(arc
				(start 224.070418 -395.82598)
				(mid 224.203906 -395.717637)
				(end 224.371408 -395.678914)
			)
			(arc
				(start 224.371408 -395.678914)
				(mid 224.641175 -395.790655)
				(end 224.752916 -396.060422)
			)
			(arc
				(start 224.752916 -396.060422)
				(mid 224.714181 -396.227918)
				(end 224.60585 -396.361412)
			)
			(arc
				(start 224.60585 -396.361412)
				(mid 224.566816 -396.441422)
				(end 224.60585 -396.521432)
			)
			(arc
				(start 224.60585 -396.521432)
				(mid 224.752929 -396.822422)
				(end 224.60585 -397.123412)
			)
			(arc
				(start 224.60585 -397.123412)
				(mid 224.566816 -397.203422)
				(end 224.60585 -397.283432)
			)
			(arc
				(start 224.60585 -397.283432)
				(mid 224.752929 -397.584422)
				(end 224.60585 -397.885412)
			)
			(arc
				(start 224.60585 -397.885412)
				(mid 224.566816 -397.965422)
				(end 224.60585 -398.045432)
			)
			(arc
				(start 224.60585 -398.045432)
				(mid 224.752929 -398.346422)
				(end 224.60585 -398.647412)
			)
			(arc
				(start 224.60585 -398.647412)
				(mid 224.566816 -398.727422)
				(end 224.60585 -398.807432)
			)
			(arc
				(start 224.60585 -398.807432)
				(mid 224.752929 -399.108422)
				(end 224.60585 -399.409412)
			)
			(arc
				(start 224.60585 -399.409412)
				(mid 224.566816 -399.489422)
				(end 224.60585 -399.569432)
			)
			(arc
				(start 224.60585 -399.569432)
				(mid 224.714193 -399.70292)
				(end 224.752916 -399.870422)
			)
			(arc
				(start 224.752916 -399.870422)
				(mid 224.751838 -399.899079)
				(end 224.748598 -399.927572)
			)
			(arc
				(start 224.748598 -399.927572)
				(mid 224.77197 -400.008963)
				(end 224.848928 -400.044412)
			)
			(arc
				(start 227.113338 -400.044412)
				(mid 227.239841 -400.069669)
				(end 227.347018 -400.14144)
			)
		)
		(stroke
			(width 0)
			(type solid)
		)
		(fill yes)
		(layer "In4.Cu")
		(net "AGND_HSC")
	)
	(gr_poly
		(pts
			(xy 360.544618 -357.987092) (xy 360.578696 -357.959911) (xy 360.651958 -357.912672) (xy 360.730132 -357.874101)
			(xy 360.812196 -357.844701) (xy 360.854498 -357.834184) (xy 360.868552 -357.830465) (xy 360.893882 -357.816218)
			(xy 360.91417 -357.79541) (xy 360.927769 -357.769726) (xy 360.933577 -357.741251) (xy 360.931124 -357.712294)
			(xy 360.92638 -357.698548) (xy 360.918289 -357.676594) (xy 360.906897 -357.631213) (xy 360.901123 -357.584782)
			(xy 360.900726 -357.561388) (xy 360.901212 -357.534137) (xy 360.908968 -357.480189) (xy 360.924323 -357.427894)
			(xy 360.946965 -357.378317) (xy 360.976431 -357.332467) (xy 361.012122 -357.291276) (xy 361.053313 -357.255585)
			(xy 361.099163 -357.226119) (xy 361.14874 -357.203477) (xy 361.201035 -357.188122) (xy 361.254983 -357.180366)
			(xy 361.309485 -357.180366) (xy 361.363433 -357.188122) (xy 361.415728 -357.203477) (xy 361.465305 -357.226119)
			(xy 361.511155 -357.255585) (xy 361.552346 -357.291276) (xy 361.588037 -357.332467) (xy 361.617503 -357.378317)
			(xy 361.640145 -357.427894) (xy 361.6555 -357.480189) (xy 361.663256 -357.534137) (xy 361.663742 -357.561388)
			(xy 361.66321 -357.590671) (xy 361.654267 -357.64855) (xy 361.636589 -357.704384) (xy 361.610591 -357.756863)
			(xy 361.594146 -357.781098) (xy 361.586455 -357.792712) (xy 361.577107 -357.818941) (xy 361.575189 -357.846721)
			(xy 361.580845 -357.873986) (xy 361.593654 -357.89871) (xy 361.612664 -357.919057) (xy 361.636462 -357.933514)
			(xy 361.663281 -357.941007) (xy 361.677204 -357.941372) (xy 361.921552 -357.941372) (xy 363.47908 -356.38359)
			(xy 363.47908 -352.898456) (xy 363.316012 -352.898456) (xy 363.28035 -352.897975) (xy 363.209475 -352.889989)
			(xy 363.139941 -352.874116) (xy 363.072621 -352.850555) (xy 363.008363 -352.819604) (xy 362.947976 -352.781651)
			(xy 362.892219 -352.737174) (xy 362.866686 -352.712274) (xy 362.733844 -352.579432) (xy 360.766614 -352.579432)
			(xy 360.753707 -352.604808) (xy 360.721505 -352.651756) (xy 360.682684 -352.693396) (xy 360.638105 -352.728805)
			(xy 360.58876 -352.757196) (xy 360.535743 -352.777938) (xy 360.480232 -352.79057) (xy 360.42346 -352.794812)
			(xy 360.366688 -352.79057) (xy 360.311177 -352.777938) (xy 360.25816 -352.757196) (xy 360.208815 -352.728805)
			(xy 360.164236 -352.693396) (xy 360.125415 -352.651756) (xy 360.093213 -352.604808) (xy 360.080306 -352.579432)
			(xy 359.226866 -352.579432) (xy 359.212358 -352.604753) (xy 359.176852 -352.651063) (xy 359.134713 -352.691432)
			(xy 359.086923 -352.72492) (xy 359.034594 -352.750746) (xy 358.978945 -352.76831) (xy 358.921271 -352.777203)
			(xy 358.892094 -352.777806) (xy 358.864136 -352.777297) (xy 358.808823 -352.769108) (xy 358.755292 -352.752949)
			(xy 358.729788 -352.741484) (xy 358.717051 -352.73602) (xy 358.689732 -352.731423) (xy 358.662182 -352.734337)
			(xy 358.636429 -352.744548) (xy 358.614368 -352.761305) (xy 358.597622 -352.783375) (xy 358.59212 -352.796094)
			(xy 358.58113 -352.822348) (xy 358.552504 -352.871539) (xy 358.516888 -352.915932) (xy 358.475074 -352.954542)
			(xy 358.427988 -352.986512) (xy 358.376675 -353.011133) (xy 358.322274 -353.027859) (xy 358.265993 -353.036318)
			(xy 358.237536 -353.036886) (xy 358.209344 -353.036382) (xy 358.153574 -353.028091) (xy 358.09963 -353.011682)
			(xy 358.048689 -352.987515) (xy 358.001858 -352.956115) (xy 357.960158 -352.918165) (xy 357.924496 -352.874492)
			(xy 357.895649 -352.826046) (xy 357.884476 -352.800158) (xy 357.878615 -352.787123) (xy 357.860881 -352.764728)
			(xy 357.83763 -352.748131) (xy 357.810688 -352.738635) (xy 357.782169 -352.736986) (xy 357.754312 -352.743312)
			(xy 357.729303 -352.757119) (xy 357.718868 -352.766884) (xy 357.61168 -352.874072) (xy 357.61168 -353.887532)
			(xy 358.42194 -353.887532) (xy 358.436152 -353.887068) (xy 358.463476 -353.879246) (xy 358.487584 -353.864191)
			(xy 358.506605 -353.843071) (xy 358.519063 -353.817524) (xy 358.523993 -353.789532) (xy 358.521012 -353.761267)
			(xy 358.51035 -353.73492) (xy 358.50195 -353.723448) (xy 358.486672 -353.703247) (xy 358.461017 -353.659577)
			(xy 358.441367 -353.612895) (xy 358.428068 -353.564024) (xy 358.421352 -353.513822) (xy 358.420924 -353.488498)
			(xy 358.42141 -353.461247) (xy 358.429166 -353.407299) (xy 358.444521 -353.355004) (xy 358.467163 -353.305427)
			(xy 358.496629 -353.259577) (xy 358.53232 -353.218386) (xy 358.573511 -353.182695) (xy 358.619361 -353.153229)
			(xy 358.668938 -353.130587) (xy 358.721233 -353.115232) (xy 358.775181 -353.107476) (xy 358.829683 -353.107476)
			(xy 358.883631 -353.115232) (xy 358.935926 -353.130587) (xy 358.985503 -353.153229) (xy 359.031353 -353.182695)
			(xy 359.072544 -353.218386) (xy 359.108235 -353.259577) (xy 359.137701 -353.305427) (xy 359.160343 -353.355004)
			(xy 359.175698 -353.407299) (xy 359.183454 -353.461247) (xy 359.18394 -353.488498) (xy 359.183525 -353.513823)
			(xy 359.176815 -353.564026) (xy 359.163513 -353.612898) (xy 359.143854 -353.659577) (xy 359.118183 -353.703239)
			(xy 359.102914 -353.723448) (xy 359.094555 -353.734932) (xy 359.083937 -353.761264) (xy 359.080984 -353.789503)
			(xy 359.085922 -353.817463) (xy 359.098371 -353.842981) (xy 359.117366 -353.864083) (xy 359.14144 -353.879137)
			(xy 359.168728 -353.886977) (xy 359.182924 -353.887532) (xy 359.886758 -353.887532) (xy 360.058462 -353.716082)
			(xy 360.058462 -353.694746) (xy 360.058888 -353.667467) (xy 360.066581 -353.613455) (xy 360.08189 -353.56109)
			(xy 360.104501 -353.511439) (xy 360.133953 -353.465515) (xy 360.169647 -353.424255) (xy 360.210853 -353.388499)
			(xy 360.256733 -353.358977) (xy 360.306349 -353.336291) (xy 360.358691 -353.320904) (xy 360.412692 -353.313128)
			(xy 360.43997 -353.31273) (xy 360.467223 -353.313191) (xy 360.521175 -353.320945) (xy 360.573475 -353.336299)
			(xy 360.623056 -353.35894) (xy 360.66891 -353.388408) (xy 360.710103 -353.424102) (xy 360.745797 -353.465296)
			(xy 360.775264 -353.511151) (xy 360.797904 -353.560733) (xy 360.813257 -353.613032) (xy 360.821009 -353.666985)
			(xy 360.821478 -353.694238) (xy 360.821043 -353.720498) (xy 360.813843 -353.772523) (xy 360.79957 -353.823068)
			(xy 360.778495 -353.871175) (xy 360.751016 -353.915933) (xy 360.717654 -353.956497) (xy 360.67904 -353.992098)
			(xy 360.635905 -354.022061) (xy 360.61269 -354.034344) (xy 360.604101 -354.039275) (xy 360.591212 -354.054288)
			(xy 360.584936 -354.073052) (xy 360.586199 -354.092798) (xy 360.590084 -354.101908) (xy 360.60224 -354.128075)
			(xy 360.619418 -354.183156) (xy 360.628126 -354.240192) (xy 360.628692 -354.26904) (xy 360.62817 -354.297796)
			(xy 360.619528 -354.354656) (xy 360.602431 -354.409569) (xy 360.590338 -354.435664) (xy 360.584389 -354.449074)
			(xy 360.579646 -354.478013) (xy 360.583317 -354.507107) (xy 360.595101 -354.53396) (xy 360.614028 -354.556359)
			(xy 360.638537 -354.57246) (xy 360.66661 -354.580936) (xy 360.68127 -354.58146) (xy 360.708402 -354.58212)
			(xy 360.762074 -354.590172) (xy 360.814062 -354.605748) (xy 360.863319 -354.628534) (xy 360.908851 -354.65807)
			(xy 360.949737 -354.69376) (xy 360.985154 -354.734883) (xy 360.988072 -354.739448) (xy 361.378752 -354.739448)
			(xy 361.382823 -354.683826) (xy 361.394949 -354.629389) (xy 361.414872 -354.577298) (xy 361.442168 -354.528663)
			(xy 361.476254 -354.48452) (xy 361.516403 -354.445811) (xy 361.561761 -354.41336) (xy 361.611361 -354.387859)
			(xy 361.664145 -354.369852) (xy 361.718988 -354.359722) (xy 361.774722 -354.357685) (xy 361.830159 -354.363785)
			(xy 361.884116 -354.377891) (xy 361.935445 -354.399703) (xy 361.983051 -354.428757) (xy 362.025919 -354.464432)
			(xy 362.063136 -354.505969) (xy 362.093909 -354.552482) (xy 362.117581 -354.602979) (xy 362.133649 -354.656386)
			(xy 362.141769 -354.711562) (xy 362.142278 -354.739448) (xy 362.141769 -354.767334) (xy 362.133649 -354.82251)
			(xy 362.117581 -354.875917) (xy 362.093909 -354.926414) (xy 362.063136 -354.972927) (xy 362.025919 -355.014464)
			(xy 361.983051 -355.050139) (xy 361.935445 -355.079193) (xy 361.884116 -355.101005) (xy 361.830159 -355.115111)
			(xy 361.774722 -355.121211) (xy 361.718988 -355.119174) (xy 361.664145 -355.109044) (xy 361.611361 -355.091037)
			(xy 361.561761 -355.065536) (xy 361.516403 -355.033085) (xy 361.476254 -354.994376) (xy 361.442168 -354.950233)
			(xy 361.414872 -354.901598) (xy 361.394949 -354.849507) (xy 361.382823 -354.79507) (xy 361.378752 -354.739448)
			(xy 360.988072 -354.739448) (xy 361.014386 -354.780609) (xy 361.036844 -354.830017) (xy 361.052074 -354.882108)
			(xy 361.059769 -354.935832) (xy 361.060238 -354.962968) (xy 361.059752 -354.990219) (xy 361.051996 -355.044167)
			(xy 361.036641 -355.096462) (xy 361.013999 -355.146039) (xy 360.984533 -355.191889) (xy 360.948842 -355.23308)
			(xy 360.907651 -355.268771) (xy 360.861801 -355.298237) (xy 360.812224 -355.320879) (xy 360.759929 -355.336234)
			(xy 360.705981 -355.34399) (xy 360.651479 -355.34399) (xy 360.597531 -355.336234) (xy 360.545236 -355.320879)
			(xy 360.495659 -355.298237) (xy 360.449809 -355.268771) (xy 360.408618 -355.23308) (xy 360.372927 -355.191889)
			(xy 360.343461 -355.146039) (xy 360.320819 -355.096462) (xy 360.305464 -355.044167) (xy 360.297708 -354.990219)
			(xy 360.297222 -354.962968) (xy 360.297684 -354.93696) (xy 360.304792 -354.885432) (xy 360.318829 -354.835346)
			(xy 360.339537 -354.787629) (xy 360.366532 -354.743166) (xy 360.382566 -354.722684) (xy 360.388788 -354.714177)
			(xy 360.394368 -354.693877) (xy 360.391336 -354.673043) (xy 360.380201 -354.655175) (xy 360.362834 -354.643275)
			(xy 360.342151 -354.639342) (xy 360.331766 -354.64115) (xy 360.3109 -354.645563) (xy 360.26851 -354.650278)
			(xy 360.247184 -354.650548) (xy 360.220303 -354.650089) (xy 360.167074 -354.642548) (xy 360.115428 -354.627617)
			(xy 360.09072 -354.61702) (xy 360.076721 -354.611276) (xy 360.046728 -354.607402) (xy 360.016916 -354.612491)
			(xy 359.989907 -354.626096) (xy 359.968072 -354.647022) (xy 359.953332 -354.67343) (xy 359.946982 -354.702998)
			(xy 359.947718 -354.718112) (xy 359.948988 -354.749608) (xy 359.948502 -354.776859) (xy 359.940746 -354.830807)
			(xy 359.925391 -354.883102) (xy 359.902749 -354.932679) (xy 359.873283 -354.978529) (xy 359.837592 -355.01972)
			(xy 359.796401 -355.055411) (xy 359.750551 -355.084877) (xy 359.700974 -355.107519) (xy 359.648679 -355.122874)
			(xy 359.594731 -355.13063) (xy 359.540229 -355.13063) (xy 359.486281 -355.122874) (xy 359.433986 -355.107519)
			(xy 359.384409 -355.084877) (xy 359.338559 -355.055411) (xy 359.297368 -355.01972) (xy 359.261677 -354.978529)
			(xy 359.232211 -354.932679) (xy 359.209569 -354.883102) (xy 359.194214 -354.830807) (xy 359.186458 -354.776859)
			(xy 359.185972 -354.749608) (xy 359.186387 -354.724741) (xy 359.192879 -354.675433) (xy 359.198926 -354.65131)
			(xy 359.201982 -354.638333) (xy 359.201957 -354.611681) (xy 359.195033 -354.585945) (xy 359.18168 -354.562879)
			(xy 359.162809 -354.544058) (xy 359.139709 -354.530766) (xy 359.113955 -354.523908) (xy 359.100628 -354.523548)
			(xy 358.127046 -354.523548) (xy 358.112075 -354.524073) (xy 358.08342 -354.532751) (xy 358.058518 -354.549374)
			(xy 358.039513 -354.57251) (xy 358.028043 -354.600167) (xy 358.025096 -354.629962) (xy 358.030924 -354.65933)
			(xy 358.045027 -354.685742) (xy 358.055164 -354.696776) (xy 358.6099 -355.251512) (xy 358.6099 -355.896672)
			(xy 358.968548 -355.896672) (xy 358.988884 -355.875646) (xy 359.034804 -355.839416) (xy 359.059988 -355.824536)
			(xy 359.089198 -355.808534) (xy 359.113832 -355.793384) (xy 359.166477 -355.769449) (xy 359.221984 -355.75322)
			(xy 359.279231 -355.745026) (xy 359.308146 -355.744526) (xy 359.337171 -355.745047) (xy 359.39463 -355.753314)
			(xy 359.450328 -355.769674) (xy 359.503131 -355.793794) (xy 359.551964 -355.825182) (xy 359.595833 -355.863199)
			(xy 359.633846 -355.907073) (xy 359.665228 -355.95591) (xy 359.689342 -356.008715) (xy 359.705696 -356.064415)
			(xy 359.713956 -356.121875) (xy 359.713956 -356.179925) (xy 359.705696 -356.237385) (xy 359.689342 -356.293085)
			(xy 359.665228 -356.34589) (xy 359.633846 -356.394727) (xy 359.595833 -356.438601) (xy 359.551964 -356.476618)
			(xy 359.503131 -356.508006) (xy 359.450328 -356.532126) (xy 359.399989 -356.546912) (xy 361.125006 -356.546912)
			(xy 361.129077 -356.49129) (xy 361.141203 -356.436853) (xy 361.161126 -356.384762) (xy 361.188422 -356.336127)
			(xy 361.222508 -356.291984) (xy 361.262657 -356.253275) (xy 361.308015 -356.220824) (xy 361.357615 -356.195323)
			(xy 361.410399 -356.177316) (xy 361.465242 -356.167186) (xy 361.520976 -356.165149) (xy 361.576413 -356.171249)
			(xy 361.63037 -356.185355) (xy 361.681699 -356.207167) (xy 361.729305 -356.236221) (xy 361.772173 -356.271896)
			(xy 361.80939 -356.313433) (xy 361.840163 -356.359946) (xy 361.863835 -356.410443) (xy 361.879903 -356.46385)
			(xy 361.888023 -356.519026) (xy 361.888532 -356.546912) (xy 361.888023 -356.574798) (xy 361.879903 -356.629974)
			(xy 361.863835 -356.683381) (xy 361.840163 -356.733878) (xy 361.80939 -356.780391) (xy 361.772173 -356.821928)
			(xy 361.729305 -356.857603) (xy 361.681699 -356.886657) (xy 361.63037 -356.908469) (xy 361.576413 -356.922575)
			(xy 361.520976 -356.928675) (xy 361.465242 -356.926638) (xy 361.410399 -356.916508) (xy 361.357615 -356.898501)
			(xy 361.308015 -356.873) (xy 361.262657 -356.840549) (xy 361.222508 -356.80184) (xy 361.188422 -356.757697)
			(xy 361.161126 -356.709062) (xy 361.141203 -356.656971) (xy 361.129077 -356.602534) (xy 361.125006 -356.546912)
			(xy 359.399989 -356.546912) (xy 359.39463 -356.548486) (xy 359.337171 -356.556753) (xy 359.308146 -356.557326)
			(xy 359.280998 -356.556853) (xy 359.22719 -356.549589) (xy 359.174825 -356.535238) (xy 359.14965 -356.525068)
			(xy 359.123039 -356.517437) (xy 359.072189 -356.495554) (xy 359.02503 -356.46656) (xy 358.982551 -356.431062)
			(xy 358.963722 -356.410768) (xy 358.6099 -356.410768) (xy 358.6099 -356.610666) (xy 358.633184 -356.624264)
			(xy 358.676025 -356.657008) (xy 358.713829 -356.695457) (xy 358.745843 -356.738845) (xy 358.771429 -356.786309)
			(xy 358.790078 -356.836902) (xy 358.801417 -356.889617) (xy 358.805222 -356.943403) (xy 358.801417 -356.997189)
			(xy 358.790076 -357.049904) (xy 358.771426 -357.100497) (xy 358.74584 -357.14796) (xy 358.713825 -357.191348)
			(xy 358.676021 -357.229796) (xy 358.633179 -357.262539) (xy 358.6099 -357.276146) (xy 358.6099 -357.481632)
			(xy 359.11536 -357.987092)
		)
		(stroke
			(width 0)
			(type solid)
		)
		(fill yes)
		(layer "In4.Cu")
		(net "PVCCIN_CPU0_VREF")
	)
	(gr_poly
		(pts
			(xy 242.88242 -437.27624) (xy 275.70938 -437.27624) (xy 279.13584 -433.84978) (xy 280.21534 -433.84978)
			(xy 280.75382 -433.3113) (xy 280.75382 -426.72762) (xy 281.63012 -425.85132) (xy 291.45738 -425.85132)
			(xy 292.73246 -424.57624) (xy 292.73246 -417.96208) (xy 290.708334 -415.938208) (xy 281.9654 -415.938208)
			(xy 281.937032 -415.937564) (xy 281.881198 -415.927477) (xy 281.854402 -415.918142) (xy 281.845766 -415.91484)
			(xy 276.97684 -415.91484) (xy 275.86686 -417.02482) (xy 276.170642 -417.02482) (xy 276.174713 -416.969198)
			(xy 276.186839 -416.914761) (xy 276.206762 -416.86267) (xy 276.234058 -416.814035) (xy 276.268144 -416.769892)
			(xy 276.308293 -416.731183) (xy 276.353651 -416.698732) (xy 276.403251 -416.673231) (xy 276.456035 -416.655224)
			(xy 276.510878 -416.645094) (xy 276.566612 -416.643057) (xy 276.622049 -416.649157) (xy 276.676006 -416.663263)
			(xy 276.727335 -416.685075) (xy 276.774941 -416.714129) (xy 276.817809 -416.749804) (xy 276.855026 -416.791341)
			(xy 276.885799 -416.837854) (xy 276.907361 -416.88385) (xy 280.663902 -416.88385) (xy 280.667973 -416.828228)
			(xy 280.680099 -416.773791) (xy 280.700022 -416.7217) (xy 280.727318 -416.673065) (xy 280.761404 -416.628922)
			(xy 280.801553 -416.590213) (xy 280.846911 -416.557762) (xy 280.896511 -416.532261) (xy 280.949295 -416.514254)
			(xy 281.004138 -416.504124) (xy 281.059872 -416.502087) (xy 281.115309 -416.508187) (xy 281.169266 -416.522293)
			(xy 281.220595 -416.544105) (xy 281.268201 -416.573159) (xy 281.311069 -416.608834) (xy 281.348286 -416.650371)
			(xy 281.379059 -416.696884) (xy 281.402731 -416.747381) (xy 281.418799 -416.800788) (xy 281.426919 -416.855964)
			(xy 281.427428 -416.88385) (xy 281.426919 -416.911736) (xy 281.418799 -416.966912) (xy 281.402731 -417.020319)
			(xy 281.379059 -417.070816) (xy 281.348286 -417.117329) (xy 281.311069 -417.158866) (xy 281.268201 -417.194541)
			(xy 281.220595 -417.223595) (xy 281.169266 -417.245407) (xy 281.115309 -417.259513) (xy 281.059872 -417.265613)
			(xy 281.004138 -417.263576) (xy 280.949295 -417.253446) (xy 280.896511 -417.235439) (xy 280.846911 -417.209938)
			(xy 280.801553 -417.177487) (xy 280.761404 -417.138778) (xy 280.727318 -417.094635) (xy 280.700022 -417.046)
			(xy 280.680099 -416.993909) (xy 280.667973 -416.939472) (xy 280.663902 -416.88385) (xy 276.907361 -416.88385)
			(xy 276.909471 -416.888351) (xy 276.925539 -416.941758) (xy 276.933659 -416.996934) (xy 276.934168 -417.02482)
			(xy 276.933659 -417.052706) (xy 276.925539 -417.107882) (xy 276.909471 -417.161289) (xy 276.885799 -417.211786)
			(xy 276.855026 -417.258299) (xy 276.817809 -417.299836) (xy 276.774941 -417.335511) (xy 276.727335 -417.364565)
			(xy 276.676006 -417.386377) (xy 276.622049 -417.400483) (xy 276.566612 -417.406583) (xy 276.510878 -417.404546)
			(xy 276.456035 -417.394416) (xy 276.403251 -417.376409) (xy 276.353651 -417.350908) (xy 276.308293 -417.318457)
			(xy 276.268144 -417.279748) (xy 276.234058 -417.235605) (xy 276.206762 -417.18697) (xy 276.186839 -417.134879)
			(xy 276.174713 -417.080442) (xy 276.170642 -417.02482) (xy 275.86686 -417.02482) (xy 274.52574 -418.36594)
			(xy 274.953982 -418.36594) (xy 274.958053 -418.310318) (xy 274.970179 -418.255881) (xy 274.990102 -418.20379)
			(xy 275.017398 -418.155155) (xy 275.051484 -418.111012) (xy 275.091633 -418.072303) (xy 275.136991 -418.039852)
			(xy 275.186591 -418.014351) (xy 275.239375 -417.996344) (xy 275.294218 -417.986214) (xy 275.349952 -417.984177)
			(xy 275.405389 -417.990277) (xy 275.459346 -418.004383) (xy 275.510675 -418.026195) (xy 275.558281 -418.055249)
			(xy 275.601149 -418.090924) (xy 275.638366 -418.132461) (xy 275.669139 -418.178974) (xy 275.692811 -418.229471)
			(xy 275.708879 -418.282878) (xy 275.716999 -418.338054) (xy 275.717508 -418.36594) (xy 275.716999 -418.393826)
			(xy 275.708879 -418.449002) (xy 275.692811 -418.502409) (xy 275.669139 -418.552906) (xy 275.638366 -418.599419)
			(xy 275.601149 -418.640956) (xy 275.558281 -418.676631) (xy 275.510675 -418.705685) (xy 275.459346 -418.727497)
			(xy 275.405389 -418.741603) (xy 275.349952 -418.747703) (xy 275.294218 -418.745666) (xy 275.239375 -418.735536)
			(xy 275.186591 -418.717529) (xy 275.136991 -418.692028) (xy 275.091633 -418.659577) (xy 275.051484 -418.620868)
			(xy 275.017398 -418.576725) (xy 274.990102 -418.52809) (xy 274.970179 -418.475999) (xy 274.958053 -418.421562)
			(xy 274.953982 -418.36594) (xy 274.52574 -418.36594) (xy 270.7767 -422.11498) (xy 243.33835 -422.11498)
			(xy 243.324552 -422.115446) (xy 243.297968 -422.12285) (xy 243.274337 -422.137103) (xy 243.255387 -422.157163)
			(xy 243.242501 -422.181567) (xy 243.236622 -422.208529) (xy 243.238178 -422.236082) (xy 243.247057 -422.262211)
			(xy 243.262609 -422.285007) (xy 243.272818 -422.294304) (xy 243.293707 -422.312515) (xy 243.330514 -422.353944)
			(xy 243.360932 -422.400267) (xy 243.384319 -422.450507) (xy 243.400183 -422.503605) (xy 243.408188 -422.558441)
			(xy 243.408708 -422.58615) (xy 243.408189 -422.614558) (xy 243.39977 -422.670747) (xy 243.383112 -422.725065)
			(xy 243.358582 -422.776313) (xy 243.326723 -422.823356) (xy 243.288239 -422.865154) (xy 243.243983 -422.900782)
			(xy 243.219732 -422.915588) (xy 243.2077 -422.923181) (xy 243.188072 -422.943761) (xy 243.174877 -422.968954)
			(xy 243.169137 -422.996808) (xy 243.171298 -423.025165) (xy 243.181191 -423.051828) (xy 243.198051 -423.074731)
			(xy 243.209064 -423.083736) (xy 243.231804 -423.101929) (xy 243.272023 -423.144043) (xy 243.305378 -423.191778)
			(xy 243.331094 -423.244026) (xy 243.342679 -423.28084) (xy 282.347922 -423.28084) (xy 282.351993 -423.225218)
			(xy 282.364119 -423.170781) (xy 282.384042 -423.11869) (xy 282.411338 -423.070055) (xy 282.445424 -423.025912)
			(xy 282.485573 -422.987203) (xy 282.530931 -422.954752) (xy 282.580531 -422.929251) (xy 282.633315 -422.911244)
			(xy 282.688158 -422.901114) (xy 282.743892 -422.899077) (xy 282.799329 -422.905177) (xy 282.853286 -422.919283)
			(xy 282.904615 -422.941095) (xy 282.952221 -422.970149) (xy 282.995089 -423.005824) (xy 283.032306 -423.047361)
			(xy 283.063079 -423.093874) (xy 283.086751 -423.144371) (xy 283.102819 -423.197778) (xy 283.110939 -423.252954)
			(xy 283.111448 -423.28084) (xy 283.110939 -423.308726) (xy 283.102819 -423.363902) (xy 283.086751 -423.417309)
			(xy 283.063079 -423.467806) (xy 283.032306 -423.514319) (xy 282.995089 -423.555856) (xy 282.952221 -423.591531)
			(xy 282.904615 -423.620585) (xy 282.853286 -423.642397) (xy 282.799329 -423.656503) (xy 282.743892 -423.662603)
			(xy 282.688158 -423.660566) (xy 282.633315 -423.650436) (xy 282.580531 -423.632429) (xy 282.530931 -423.606928)
			(xy 282.485573 -423.574477) (xy 282.445424 -423.535768) (xy 282.411338 -423.491625) (xy 282.384042 -423.44299)
			(xy 282.364119 -423.390899) (xy 282.351993 -423.336462) (xy 282.347922 -423.28084) (xy 243.342679 -423.28084)
			(xy 243.348575 -423.299574) (xy 243.357414 -423.357133) (xy 243.357908 -423.38625) (xy 243.357422 -423.413501)
			(xy 243.349666 -423.467449) (xy 243.334311 -423.519744) (xy 243.311669 -423.569321) (xy 243.282203 -423.615171)
			(xy 243.246512 -423.656362) (xy 243.205321 -423.692053) (xy 243.159471 -423.721519) (xy 243.109894 -423.744161)
			(xy 243.057599 -423.759516) (xy 243.003651 -423.767272) (xy 242.949149 -423.767272) (xy 242.895201 -423.759516)
			(xy 242.842906 -423.744161) (xy 242.793329 -423.721519) (xy 242.747479 -423.692053) (xy 242.706288 -423.656362)
			(xy 242.670597 -423.615171) (xy 242.641131 -423.569321) (xy 242.618489 -423.519744) (xy 242.603134 -423.467449)
			(xy 242.595378 -423.413501) (xy 242.594892 -423.38625) (xy 242.595411 -423.357842) (xy 242.60383 -423.301653)
			(xy 242.620488 -423.247335) (xy 242.645018 -423.196087) (xy 242.676877 -423.149044) (xy 242.715361 -423.107246)
			(xy 242.759617 -423.071618) (xy 242.783868 -423.056812) (xy 242.7959 -423.049219) (xy 242.815528 -423.028639)
			(xy 242.828723 -423.003446) (xy 242.834463 -422.975592) (xy 242.832302 -422.947235) (xy 242.822409 -422.920572)
			(xy 242.805549 -422.897669) (xy 242.794536 -422.888664) (xy 242.771364 -422.870139) (xy 242.7305 -422.827136)
			(xy 242.69679 -422.778322) (xy 242.671048 -422.724876) (xy 242.661948 -422.69664) (xy 242.657104 -422.682453)
			(xy 242.640479 -422.657523) (xy 242.617331 -422.638497) (xy 242.589655 -422.627012) (xy 242.559837 -422.62406)
			(xy 242.530446 -422.629895) (xy 242.504017 -422.644013) (xy 242.493038 -422.654222) (xy 241.11966 -424.0276)
			(xy 241.11966 -425.152148) (xy 276.956434 -425.152148) (xy 276.956435 -425.097638) (xy 276.964194 -425.043684)
			(xy 276.979553 -424.991382) (xy 277.002198 -424.941799) (xy 277.03167 -424.895943) (xy 277.067367 -424.854749)
			(xy 277.108565 -424.819054) (xy 277.154422 -424.789585) (xy 277.204007 -424.766943) (xy 277.25631 -424.751588)
			(xy 277.310265 -424.743834) (xy 277.33752 -424.743372) (xy 277.360289 -424.743721) (xy 277.405495 -424.749201)
			(xy 277.42769 -424.754294) (xy 277.441172 -424.757127) (xy 277.468696 -424.756194) (xy 277.494973 -424.747948)
			(xy 277.518097 -424.732989) (xy 277.536389 -424.7124) (xy 277.548522 -424.687677) (xy 277.553617 -424.660612)
			(xy 277.552912 -424.646852) (xy 277.551642 -424.61434) (xy 277.552112 -424.587083) (xy 277.559865 -424.533123)
			(xy 277.575219 -424.480815) (xy 277.597861 -424.431226) (xy 277.62733 -424.385363) (xy 277.663026 -424.344162)
			(xy 277.704223 -424.30846) (xy 277.750082 -424.278985) (xy 277.799668 -424.256336) (xy 277.851974 -424.240976)
			(xy 277.905933 -424.233216) (xy 277.960447 -424.233214) (xy 278.014407 -424.240971) (xy 278.066713 -424.256329)
			(xy 278.116301 -424.278975) (xy 278.162161 -424.308448) (xy 278.20336 -424.344147) (xy 278.239058 -424.385347)
			(xy 278.26853 -424.431208) (xy 278.291174 -424.480797) (xy 278.306531 -424.533103) (xy 278.314286 -424.587063)
			(xy 278.314284 -424.641577) (xy 278.306522 -424.695536) (xy 278.29116 -424.747841) (xy 278.268511 -424.797427)
			(xy 278.239034 -424.843285) (xy 278.203331 -424.884481) (xy 278.162129 -424.920176) (xy 278.116266 -424.949644)
			(xy 278.066675 -424.972285) (xy 278.014367 -424.987637) (xy 277.960407 -424.995389) (xy 277.93315 -424.995848)
			(xy 277.910382 -424.995486) (xy 277.865175 -424.990015) (xy 277.84298 -424.984926) (xy 277.829492 -424.982146)
			(xy 277.80198 -424.983087) (xy 277.775716 -424.991331) (xy 277.752601 -425.006283) (xy 277.734312 -425.026857)
			(xy 277.722173 -425.051564) (xy 277.717063 -425.078614) (xy 277.717758 -425.092368) (xy 277.719028 -425.12488)
			(xy 277.718566 -425.152135) (xy 277.710812 -425.20609) (xy 277.695457 -425.258393) (xy 277.672815 -425.307978)
			(xy 277.643346 -425.353835) (xy 277.607651 -425.395033) (xy 277.566457 -425.43073) (xy 277.520601 -425.460202)
			(xy 277.471018 -425.482847) (xy 277.418716 -425.498206) (xy 277.364762 -425.505965) (xy 277.310252 -425.505966)
			(xy 277.256297 -425.498209) (xy 277.203995 -425.482852) (xy 277.154411 -425.460208) (xy 277.108554 -425.430738)
			(xy 277.067358 -425.395042) (xy 277.031662 -425.353846) (xy 277.002192 -425.307989) (xy 276.979548 -425.258405)
			(xy 276.964191 -425.206103) (xy 276.956434 -425.152148) (xy 241.11966 -425.152148) (xy 241.11966 -433.04206)
			(xy 267.01141 -433.04206) (xy 267.01543 -432.866756) (xy 267.027484 -432.69182) (xy 267.047545 -432.517622)
			(xy 267.075571 -432.344526) (xy 267.111504 -432.172897) (xy 267.155267 -432.003095) (xy 267.20677 -431.835479)
			(xy 267.265903 -431.6704) (xy 267.332542 -431.508206) (xy 267.406547 -431.349238) (xy 267.487762 -431.19383)
			(xy 267.576017 -431.042308) (xy 267.671126 -430.894992) (xy 267.772888 -430.752191) (xy 267.881091 -430.614206)
			(xy 267.995506 -430.481327) (xy 268.115893 -430.353833) (xy 268.241998 -430.231992) (xy 268.373557 -430.116061)
			(xy 268.510292 -430.006284) (xy 268.651917 -429.902891) (xy 268.798133 -429.806099) (xy 268.948632 -429.716113)
			(xy 269.103099 -429.633121) (xy 269.261209 -429.557298) (xy 269.422628 -429.488804) (xy 269.587018 -429.427782)
			(xy 269.754033 -429.374362) (xy 269.923321 -429.328654) (xy 270.094527 -429.290756) (xy 270.26729 -429.260747)
			(xy 270.441247 -429.23869) (xy 270.616033 -429.224631) (xy 270.79128 -429.218601) (xy 270.966618 -429.220611)
			(xy 271.14168 -429.230658) (xy 271.316098 -429.248721) (xy 271.489504 -429.274761) (xy 271.661533 -429.308723)
			(xy 271.831825 -429.350537) (xy 272.000021 -429.400114) (xy 272.165767 -429.457351) (xy 272.328714 -429.522126)
			(xy 272.488521 -429.594303) (xy 272.64485 -429.673731) (xy 272.797374 -429.760243) (xy 272.94577 -429.853656)
			(xy 273.089728 -429.953775) (xy 273.228945 -430.060389) (xy 273.363127 -430.173273) (xy 273.491993 -430.29219)
			(xy 273.615272 -430.41689) (xy 273.732703 -430.547111) (xy 273.844042 -430.682578) (xy 273.949052 -430.823008)
			(xy 274.047513 -430.968105) (xy 274.139219 -431.117563) (xy 274.223977 -431.271068) (xy 274.301607 -431.428298)
			(xy 274.371948 -431.588921) (xy 274.43485 -431.752601) (xy 274.490182 -431.918992) (xy 274.537828 -432.087745)
			(xy 274.577686 -432.258505) (xy 274.609674 -432.430913) (xy 274.633724 -432.604606) (xy 274.649786 -432.779219)
			(xy 274.657825 -432.954385) (xy 274.658328 -433.04206) (xy 274.657825 -433.129735) (xy 274.649786 -433.304901)
			(xy 274.633724 -433.479514) (xy 274.609674 -433.653207) (xy 274.577686 -433.825615) (xy 274.537828 -433.996375)
			(xy 274.490182 -434.165128) (xy 274.43485 -434.331519) (xy 274.371948 -434.495199) (xy 274.301607 -434.655822)
			(xy 274.223977 -434.813052) (xy 274.139219 -434.966557) (xy 274.047513 -435.116015) (xy 273.949052 -435.261112)
			(xy 273.844042 -435.401542) (xy 273.732703 -435.537009) (xy 273.615272 -435.66723) (xy 273.491993 -435.79193)
			(xy 273.363127 -435.910847) (xy 273.228945 -436.023731) (xy 273.089728 -436.130345) (xy 272.94577 -436.230464)
			(xy 272.797374 -436.323877) (xy 272.64485 -436.410389) (xy 272.488521 -436.489817) (xy 272.328714 -436.561994)
			(xy 272.165767 -436.626769) (xy 272.000021 -436.684006) (xy 271.831825 -436.733583) (xy 271.661533 -436.775397)
			(xy 271.489504 -436.809359) (xy 271.316098 -436.835399) (xy 271.14168 -436.853462) (xy 270.966618 -436.863509)
			(xy 270.79128 -436.865519) (xy 270.616033 -436.859489) (xy 270.441247 -436.84543) (xy 270.26729 -436.823373)
			(xy 270.094527 -436.793364) (xy 269.923321 -436.755466) (xy 269.754033 -436.709758) (xy 269.587018 -436.656338)
			(xy 269.422628 -436.595316) (xy 269.261209 -436.526822) (xy 269.103099 -436.450999) (xy 268.948632 -436.368007)
			(xy 268.798133 -436.278021) (xy 268.651917 -436.181229) (xy 268.510292 -436.077836) (xy 268.373557 -435.968059)
			(xy 268.241998 -435.852128) (xy 268.115893 -435.730287) (xy 267.995506 -435.602793) (xy 267.881091 -435.469914)
			(xy 267.772888 -435.331929) (xy 267.671126 -435.189128) (xy 267.576017 -435.041812) (xy 267.487762 -434.89029)
			(xy 267.406547 -434.734882) (xy 267.332542 -434.575914) (xy 267.265903 -434.41372) (xy 267.20677 -434.248641)
			(xy 267.155267 -434.081025) (xy 267.111504 -433.911223) (xy 267.075571 -433.739594) (xy 267.047545 -433.566498)
			(xy 267.027484 -433.3923) (xy 267.01543 -433.217364) (xy 267.01141 -433.04206) (xy 241.11966 -433.04206)
			(xy 241.11966 -436.626) (xy 241.79022 -437.29656) (xy 242.8621 -437.29656)
		)
		(stroke
			(width 0)
			(type solid)
		)
		(fill yes)
		(layer "In4.Cu")
		(net "GND")
	)
	(gr_poly
		(pts
			(xy 112.804956 -357.868728) (xy 112.831787 -357.858285) (xy 112.88671 -357.840997) (xy 112.914684 -357.834184)
			(xy 112.92874 -357.830466) (xy 112.954073 -357.816221) (xy 112.974364 -357.795413) (xy 112.987965 -357.769728)
			(xy 112.993774 -357.741251) (xy 112.99132 -357.712291) (xy 112.986566 -357.698548) (xy 112.978475 -357.676594)
			(xy 112.967084 -357.631213) (xy 112.96131 -357.584782) (xy 112.960912 -357.561388) (xy 112.961398 -357.534137)
			(xy 112.969154 -357.480189) (xy 112.984509 -357.427894) (xy 113.007151 -357.378317) (xy 113.036617 -357.332467)
			(xy 113.072308 -357.291276) (xy 113.113499 -357.255585) (xy 113.159349 -357.226119) (xy 113.208926 -357.203477)
			(xy 113.261221 -357.188122) (xy 113.315169 -357.180366) (xy 113.369671 -357.180366) (xy 113.423619 -357.188122)
			(xy 113.475914 -357.203477) (xy 113.525491 -357.226119) (xy 113.571341 -357.255585) (xy 113.612532 -357.291276)
			(xy 113.648223 -357.332467) (xy 113.677689 -357.378317) (xy 113.700331 -357.427894) (xy 113.715686 -357.480189)
			(xy 113.723442 -357.534137) (xy 113.723928 -357.561388) (xy 113.723432 -357.589388) (xy 113.715251 -357.644787)
			(xy 113.699075 -357.6984) (xy 113.687606 -357.723948) (xy 113.681831 -357.73738) (xy 113.677417 -357.766271)
			(xy 113.681362 -357.79523) (xy 113.693343 -357.821887) (xy 113.712379 -357.844063) (xy 113.736914 -357.859943)
			(xy 113.764941 -357.868229) (xy 113.779554 -357.868728) (xy 114.010948 -357.868728) (xy 115.099592 -356.780084)
			(xy 115.099592 -352.9965) (xy 115.1001 -352.975418) (xy 115.1001 -352.417888) (xy 114.92484 -352.242628)
			(xy 111.422434 -352.242628) (xy 111.408199 -352.243111) (xy 111.380838 -352.250983) (xy 111.356711 -352.266097)
			(xy 111.33769 -352.287282) (xy 111.325251 -352.312891) (xy 111.32036 -352.340938) (xy 111.321342 -352.35515)
			(xy 111.322399 -352.365404) (xy 111.323545 -352.38599) (xy 111.323628 -352.396298) (xy 111.323142 -352.42355)
			(xy 111.315386 -352.477499) (xy 111.300031 -352.529795) (xy 111.277391 -352.579374) (xy 111.247925 -352.625226)
			(xy 111.212234 -352.666418) (xy 111.171043 -352.702112) (xy 111.125193 -352.73158) (xy 111.075616 -352.754224)
			(xy 111.02332 -352.769582) (xy 110.969372 -352.777341) (xy 110.94212 -352.777806) (xy 110.913423 -352.777283)
			(xy 110.856679 -352.768678) (xy 110.801862 -352.751675) (xy 110.750208 -352.726657) (xy 110.702883 -352.694187)
			(xy 110.660952 -352.654998) (xy 110.625361 -352.609972) (xy 110.596912 -352.560126) (xy 110.576246 -352.506582)
			(xy 110.56383 -352.450548) (xy 110.561374 -352.421952) (xy 110.559938 -352.407462) (xy 110.549883 -352.380145)
			(xy 110.532528 -352.356778) (xy 110.509282 -352.339259) (xy 110.482037 -352.329014) (xy 110.453008 -352.326875)
			(xy 110.424556 -352.333017) (xy 110.398994 -352.34694) (xy 110.3884 -352.356928) (xy 109.912404 -352.832924)
			(xy 112.35385 -352.832924) (xy 112.357921 -352.777302) (xy 112.370047 -352.722865) (xy 112.38997 -352.670774)
			(xy 112.417266 -352.622139) (xy 112.451352 -352.577996) (xy 112.491501 -352.539287) (xy 112.536859 -352.506836)
			(xy 112.586459 -352.481335) (xy 112.639243 -352.463328) (xy 112.694086 -352.453198) (xy 112.74982 -352.451161)
			(xy 112.805257 -352.457261) (xy 112.859214 -352.471367) (xy 112.910543 -352.493179) (xy 112.958149 -352.522233)
			(xy 113.001017 -352.557908) (xy 113.038234 -352.599445) (xy 113.069007 -352.645958) (xy 113.092679 -352.696455)
			(xy 113.108747 -352.749862) (xy 113.116867 -352.805038) (xy 113.117376 -352.832924) (xy 113.116867 -352.86081)
			(xy 113.108747 -352.915986) (xy 113.092679 -352.969393) (xy 113.069007 -353.01989) (xy 113.038234 -353.066403)
			(xy 113.001017 -353.10794) (xy 112.958149 -353.143615) (xy 112.910543 -353.172669) (xy 112.859214 -353.194481)
			(xy 112.805257 -353.208587) (xy 112.74982 -353.214687) (xy 112.694086 -353.21265) (xy 112.639243 -353.20252)
			(xy 112.586459 -353.184513) (xy 112.536859 -353.159012) (xy 112.491501 -353.126561) (xy 112.451352 -353.087852)
			(xy 112.417266 -353.043709) (xy 112.38997 -352.995074) (xy 112.370047 -352.942983) (xy 112.357921 -352.888546)
			(xy 112.35385 -352.832924) (xy 109.912404 -352.832924) (xy 109.599222 -353.146106) (xy 109.599222 -353.488498)
			(xy 110.4806 -353.488498) (xy 110.484671 -353.432876) (xy 110.496797 -353.378439) (xy 110.51672 -353.326348)
			(xy 110.544016 -353.277713) (xy 110.578102 -353.23357) (xy 110.618251 -353.194861) (xy 110.663609 -353.16241)
			(xy 110.713209 -353.136909) (xy 110.765993 -353.118902) (xy 110.820836 -353.108772) (xy 110.87657 -353.106735)
			(xy 110.932007 -353.112835) (xy 110.985964 -353.126941) (xy 111.037293 -353.148753) (xy 111.084899 -353.177807)
			(xy 111.127767 -353.213482) (xy 111.164984 -353.255019) (xy 111.195757 -353.301532) (xy 111.219429 -353.352029)
			(xy 111.235497 -353.405436) (xy 111.243617 -353.460612) (xy 111.244126 -353.488498) (xy 111.243617 -353.516384)
			(xy 111.235497 -353.57156) (xy 111.219429 -353.624967) (xy 111.195757 -353.675464) (xy 111.164984 -353.721977)
			(xy 111.127767 -353.763514) (xy 111.084899 -353.799189) (xy 111.037293 -353.828243) (xy 110.985964 -353.850055)
			(xy 110.932007 -353.864161) (xy 110.87657 -353.870261) (xy 110.820836 -353.868224) (xy 110.765993 -353.858094)
			(xy 110.713209 -353.840087) (xy 110.663609 -353.814586) (xy 110.618251 -353.782135) (xy 110.578102 -353.743426)
			(xy 110.544016 -353.699283) (xy 110.51672 -353.650648) (xy 110.496797 -353.598557) (xy 110.484671 -353.54412)
			(xy 110.4806 -353.488498) (xy 109.599222 -353.488498) (xy 109.599222 -354.014532) (xy 111.746538 -354.014532)
			(xy 111.760254 -353.984814) (xy 111.771932 -353.960094) (xy 111.801318 -353.913992) (xy 111.836989 -353.87256)
			(xy 111.878212 -353.836649) (xy 111.924142 -353.806995) (xy 111.973838 -353.784206) (xy 112.026279 -353.76875)
			(xy 112.08039 -353.760944) (xy 112.107726 -353.760532) (xy 112.134973 -353.76102) (xy 112.188912 -353.768779)
			(xy 112.241198 -353.784134) (xy 112.290767 -353.806775) (xy 112.336609 -353.836238) (xy 112.377792 -353.871926)
			(xy 112.413477 -353.913111) (xy 112.442938 -353.958956) (xy 112.465575 -354.008526) (xy 112.480927 -354.060813)
			(xy 112.488682 -354.114753) (xy 112.488682 -354.169247) (xy 112.480927 -354.223187) (xy 112.465575 -354.275474)
			(xy 112.442938 -354.325044) (xy 112.413477 -354.370889) (xy 112.377792 -354.412074) (xy 112.336609 -354.447762)
			(xy 112.290767 -354.477225) (xy 112.241198 -354.499866) (xy 112.188912 -354.515221) (xy 112.134973 -354.52298)
			(xy 112.107726 -354.523548) (xy 112.09003 -354.523337) (xy 112.054794 -354.52003) (xy 112.037368 -354.516944)
			(xy 112.023405 -354.519991) (xy 111.995016 -354.523297) (xy 111.980726 -354.523548) (xy 110.01883 -354.523548)
			(xy 110.003861 -354.524075) (xy 109.97521 -354.532756) (xy 109.950312 -354.549379) (xy 109.931311 -354.572514)
			(xy 109.919843 -354.600168) (xy 109.916896 -354.62996) (xy 109.922722 -354.659325) (xy 109.936821 -354.685734)
			(xy 109.946948 -354.696776) (xy 110.409736 -355.159564) (xy 111.223296 -355.159564) (xy 111.227367 -355.103942)
			(xy 111.239493 -355.049505) (xy 111.259416 -354.997414) (xy 111.286712 -354.948779) (xy 111.320798 -354.904636)
			(xy 111.360947 -354.865927) (xy 111.406305 -354.833476) (xy 111.455905 -354.807975) (xy 111.508689 -354.789968)
			(xy 111.563532 -354.779838) (xy 111.619266 -354.777801) (xy 111.674703 -354.783901) (xy 111.72866 -354.798007)
			(xy 111.779989 -354.819819) (xy 111.827595 -354.848873) (xy 111.870463 -354.884548) (xy 111.90768 -354.926085)
			(xy 111.938453 -354.972598) (xy 111.962125 -355.023095) (xy 111.978193 -355.076502) (xy 111.979583 -355.085949)
			(xy 112.248704 -355.085949) (xy 112.248704 -355.031451) (xy 112.25646 -354.977507) (xy 112.271814 -354.925216)
			(xy 112.294453 -354.875643) (xy 112.323917 -354.829796) (xy 112.359606 -354.788609) (xy 112.400793 -354.752919)
			(xy 112.446639 -354.723455) (xy 112.496213 -354.700815) (xy 112.548503 -354.685461) (xy 112.602447 -354.677704)
			(xy 112.629696 -354.677218) (xy 112.658532 -354.67771) (xy 112.715549 -354.68637) (xy 112.770614 -354.703509)
			(xy 112.822475 -354.728737) (xy 112.86995 -354.761479) (xy 112.891316 -354.78085) (xy 112.901981 -354.790196)
			(xy 112.927151 -354.803225) (xy 112.954935 -354.808824) (xy 112.983187 -354.806562) (xy 113.009726 -354.796614)
			(xy 113.032503 -354.779747) (xy 113.04976 -354.757265) (xy 113.060165 -354.730901) (xy 113.062004 -354.716842)
			(xy 113.066116 -354.678952) (xy 113.080998 -354.604199) (xy 113.103262 -354.531304) (xy 113.132687 -354.460993)
			(xy 113.168978 -354.393967) (xy 113.211774 -354.330896) (xy 113.260647 -354.272409) (xy 113.287556 -354.245418)
			(xy 113.297069 -354.23539) (xy 113.310884 -354.211465) (xy 113.317784 -354.184714) (xy 113.317267 -354.157093)
			(xy 113.309369 -354.130619) (xy 113.294667 -354.107229) (xy 113.284762 -354.09759) (xy 113.255689 -354.070477)
			(xy 113.202675 -354.011235) (xy 113.156114 -353.946797) (xy 113.116513 -353.877862) (xy 113.084303 -353.80518)
			(xy 113.059832 -353.729541) (xy 113.043368 -353.651765) (xy 113.035088 -353.572698) (xy 113.034572 -353.532948)
			(xy 113.035061 -353.494303) (xy 113.042881 -353.417409) (xy 113.058439 -353.341701) (xy 113.081577 -353.267955)
			(xy 113.112057 -353.196928) (xy 113.149566 -353.12935) (xy 113.19372 -353.065912) (xy 113.244065 -353.007268)
			(xy 113.300084 -352.954017) (xy 113.361203 -352.906707) (xy 113.426796 -352.865823) (xy 113.496187 -352.831785)
			(xy 113.568667 -352.804942) (xy 113.64349 -352.785569) (xy 113.719889 -352.773865) (xy 113.79708 -352.76995)
			(xy 113.874271 -352.773865) (xy 113.95067 -352.785569) (xy 114.025493 -352.804942) (xy 114.097973 -352.831785)
			(xy 114.167364 -352.865823) (xy 114.232957 -352.906707) (xy 114.294076 -352.954017) (xy 114.350095 -353.007268)
			(xy 114.40044 -353.065912) (xy 114.444594 -353.12935) (xy 114.482103 -353.196928) (xy 114.512583 -353.267955)
			(xy 114.535721 -353.341701) (xy 114.551279 -353.417409) (xy 114.559099 -353.494303) (xy 114.559588 -353.532948)
			(xy 114.559101 -353.57089) (xy 114.551574 -353.6464) (xy 114.536579 -353.720788) (xy 114.514264 -353.793318)
			(xy 114.484852 -353.86327) (xy 114.448632 -353.929952) (xy 114.405964 -353.992705) (xy 114.35727 -354.050905)
			(xy 114.33048 -354.077778) (xy 114.320968 -354.087808) (xy 114.307147 -354.111731) (xy 114.300243 -354.138482)
			(xy 114.30076 -354.166105) (xy 114.30866 -354.19258) (xy 114.323366 -354.215969) (xy 114.333274 -354.225606)
			(xy 114.362401 -354.252663) (xy 114.415411 -354.311914) (xy 114.461967 -354.376362) (xy 114.501561 -354.445305)
			(xy 114.533765 -354.517994) (xy 114.558227 -354.593641) (xy 114.574683 -354.671424) (xy 114.582953 -354.750496)
			(xy 114.583464 -354.790248) (xy 114.583031 -354.830184) (xy 114.574677 -354.909619) (xy 114.558065 -354.987745)
			(xy 114.533379 -355.063707) (xy 114.500887 -355.136672) (xy 114.460947 -355.205842) (xy 114.413995 -355.270457)
			(xy 114.360546 -355.329811) (xy 114.301186 -355.383253) (xy 114.236564 -355.430197) (xy 114.16739 -355.470129)
			(xy 114.094421 -355.502612) (xy 114.018456 -355.527289) (xy 113.940328 -355.543891) (xy 113.860892 -355.552236)
			(xy 113.820956 -355.552756) (xy 113.781642 -355.552255) (xy 113.703433 -355.54416) (xy 113.626471 -355.528059)
			(xy 113.551575 -355.504124) (xy 113.47954 -355.472609) (xy 113.41113 -355.433849) (xy 113.347071 -355.388254)
			(xy 113.288045 -355.33631) (xy 113.234677 -355.278568) (xy 113.187535 -355.21564) (xy 113.166906 -355.18217)
			(xy 113.159252 -355.170194) (xy 113.138548 -355.150737) (xy 113.113282 -355.137742) (xy 113.085413 -355.132218)
			(xy 113.0571 -355.134592) (xy 113.03054 -355.144681) (xy 113.00779 -355.161701) (xy 112.990616 -355.184335)
			(xy 112.985042 -355.19741) (xy 112.974135 -355.223849) (xy 112.945641 -355.273434) (xy 112.910062 -355.318208)
			(xy 112.868196 -355.357167) (xy 112.820981 -355.389438) (xy 112.769477 -355.414296) (xy 112.714839 -355.431184)
			(xy 112.658291 -355.439723) (xy 112.629696 -355.440234) (xy 112.602447 -355.439696) (xy 112.548503 -355.431939)
			(xy 112.496213 -355.416585) (xy 112.446639 -355.393945) (xy 112.400793 -355.364481) (xy 112.359606 -355.328791)
			(xy 112.323917 -355.287604) (xy 112.294453 -355.241757) (xy 112.271814 -355.192184) (xy 112.25646 -355.139893)
			(xy 112.248704 -355.085949) (xy 111.979583 -355.085949) (xy 111.986313 -355.131678) (xy 111.986822 -355.159564)
			(xy 111.986313 -355.18745) (xy 111.978193 -355.242626) (xy 111.962125 -355.296033) (xy 111.938453 -355.34653)
			(xy 111.90768 -355.393043) (xy 111.870463 -355.43458) (xy 111.827595 -355.470255) (xy 111.779989 -355.499309)
			(xy 111.72866 -355.521121) (xy 111.674703 -355.535227) (xy 111.619266 -355.541327) (xy 111.563532 -355.53929)
			(xy 111.508689 -355.52916) (xy 111.455905 -355.511153) (xy 111.406305 -355.485652) (xy 111.360947 -355.453201)
			(xy 111.320798 -355.414492) (xy 111.286712 -355.370349) (xy 111.259416 -355.321714) (xy 111.239493 -355.269623)
			(xy 111.227367 -355.215186) (xy 111.223296 -355.159564) (xy 110.409736 -355.159564) (xy 110.5154 -355.265228)
			(xy 110.5154 -355.896672) (xy 111.084106 -355.896672) (xy 111.102262 -355.87703) (xy 111.143127 -355.842515)
			(xy 111.188413 -355.814049) (xy 111.237232 -355.79219) (xy 111.288626 -355.777366) (xy 111.341587 -355.769869)
			(xy 111.368332 -355.769418) (xy 111.39558 -355.769906) (xy 111.44952 -355.777666) (xy 111.501808 -355.793023)
			(xy 111.551377 -355.815664) (xy 111.597221 -355.845129) (xy 111.638404 -355.880818) (xy 111.67409 -355.922005)
			(xy 111.703551 -355.967851) (xy 111.726188 -356.017422) (xy 111.741541 -356.069711) (xy 111.749296 -356.123652)
			(xy 111.749296 -356.178148) (xy 111.741541 -356.232089) (xy 111.726188 -356.284378) (xy 111.703551 -356.333949)
			(xy 111.67409 -356.379795) (xy 111.638404 -356.420982) (xy 111.597221 -356.456671) (xy 111.551377 -356.486136)
			(xy 111.501808 -356.508777) (xy 111.44952 -356.524134) (xy 111.39558 -356.531894) (xy 111.368332 -356.532434)
			(xy 111.341588 -356.531966) (xy 111.288629 -356.524462) (xy 111.237236 -356.509639) (xy 111.188416 -356.487786)
			(xy 111.143124 -356.459332) (xy 111.102248 -356.424835) (xy 111.084106 -356.40518) (xy 110.5154 -356.40518)
			(xy 110.5154 -356.560882) (xy 110.55269 -356.568248) (xy 113.183922 -356.568248) (xy 113.187993 -356.512626)
			(xy 113.200119 -356.458189) (xy 113.220042 -356.406098) (xy 113.247338 -356.357463) (xy 113.281424 -356.31332)
			(xy 113.321573 -356.274611) (xy 113.366931 -356.24216) (xy 113.416531 -356.216659) (xy 113.469315 -356.198652)
			(xy 113.524158 -356.188522) (xy 113.579892 -356.186485) (xy 113.635329 -356.192585) (xy 113.689286 -356.206691)
			(xy 113.740615 -356.228503) (xy 113.788221 -356.257557) (xy 113.831089 -356.293232) (xy 113.868306 -356.334769)
			(xy 113.899079 -356.381282) (xy 113.922751 -356.431779) (xy 113.938819 -356.485186) (xy 113.946939 -356.540362)
			(xy 113.947448 -356.568248) (xy 113.946939 -356.596134) (xy 113.938819 -356.65131) (xy 113.922751 -356.704717)
			(xy 113.899079 -356.755214) (xy 113.868306 -356.801727) (xy 113.831089 -356.843264) (xy 113.788221 -356.878939)
			(xy 113.740615 -356.907993) (xy 113.689286 -356.929805) (xy 113.635329 -356.943911) (xy 113.579892 -356.950011)
			(xy 113.524158 -356.947974) (xy 113.469315 -356.937844) (xy 113.416531 -356.919837) (xy 113.366931 -356.894336)
			(xy 113.321573 -356.861885) (xy 113.281424 -356.823176) (xy 113.247338 -356.779033) (xy 113.220042 -356.730398)
			(xy 113.200119 -356.678307) (xy 113.187993 -356.62387) (xy 113.183922 -356.568248) (xy 110.55269 -356.568248)
			(xy 110.556548 -356.56901) (xy 110.583616 -356.574802) (xy 110.635837 -356.593156) (xy 110.684857 -356.618865)
			(xy 110.729646 -356.651389) (xy 110.769265 -356.690044) (xy 110.802881 -356.73402) (xy 110.829788 -356.782393)
			(xy 110.849421 -356.834146) (xy 110.861368 -356.888194) (xy 110.865379 -356.943401) (xy 110.861368 -356.998608)
			(xy 110.849421 -357.052656) (xy 110.829787 -357.104409) (xy 110.80288 -357.152782) (xy 110.769263 -357.196757)
			(xy 110.729645 -357.235413) (xy 110.684855 -357.267936) (xy 110.635835 -357.293645) (xy 110.583614 -357.311999)
			(xy 110.556548 -357.317802) (xy 110.5154 -357.32593) (xy 110.5154 -357.563928) (xy 110.8202 -357.868728)
		)
		(stroke
			(width 0)
			(type solid)
		)
		(fill yes)
		(layer "In4.Cu")
		(net "PVCCIN_CPU1_VREF")
	)
	(gr_poly
		(pts
			(xy 408.615134 -184.622948) (xy 408.62996 -184.622449) (xy 408.658368 -184.613949) (xy 408.683136 -184.597646)
			(xy 408.702177 -184.574915) (xy 408.713884 -184.547672) (xy 408.717272 -184.518214) (xy 408.712054 -184.489025)
			(xy 408.69867 -184.462565) (xy 408.688794 -184.451498) (xy 408.669207 -184.430089) (xy 408.636079 -184.382451)
			(xy 408.610544 -184.330347) (xy 408.593191 -184.274978) (xy 408.584421 -184.21762) (xy 408.583892 -184.188608)
			(xy 408.584355 -184.161355) (xy 408.592111 -184.107403) (xy 408.607466 -184.055104) (xy 408.630108 -184.005523)
			(xy 408.659576 -183.959669) (xy 408.69527 -183.918475) (xy 408.736463 -183.882781) (xy 408.782316 -183.853312)
			(xy 408.831897 -183.830669) (xy 408.884195 -183.815313) (xy 408.938147 -183.807555) (xy 408.9654 -183.8071)
			(xy 408.993166 -183.807601) (xy 409.04811 -183.815656) (xy 409.101304 -183.831596) (xy 409.151624 -183.855084)
			(xy 409.198004 -183.885623) (xy 409.239464 -183.922566) (xy 409.275127 -183.965133) (xy 409.304237 -184.012423)
			(xy 409.315666 -184.037732) (xy 409.321721 -184.050569) (xy 409.339703 -184.072516) (xy 409.363025 -184.088673)
			(xy 409.389891 -184.097796) (xy 409.41823 -184.099181) (xy 409.445857 -184.092721) (xy 409.470643 -184.078915)
			(xy 409.48102 -184.069228) (xy 409.53182 -184.018428) (xy 409.53182 -182.739284) (xy 409.507863 -182.72728)
			(xy 409.463277 -182.697559) (xy 409.42329 -182.66189) (xy 409.388688 -182.620976) (xy 409.360152 -182.575622)
			(xy 409.338244 -182.526721) (xy 409.323395 -182.475235) (xy 409.315898 -182.422178) (xy 409.3159 -182.368594)
			(xy 409.323401 -182.315538) (xy 409.338253 -182.264053) (xy 409.360165 -182.215153) (xy 409.388704 -182.169802)
			(xy 409.423309 -182.12889) (xy 409.463299 -182.093224) (xy 409.507887 -182.063506) (xy 409.53182 -182.051452)
			(xy 409.53182 -176.711864) (xy 409.507864 -176.699857) (xy 409.46328 -176.67013) (xy 409.423294 -176.634457)
			(xy 409.388692 -176.593541) (xy 409.360155 -176.548186) (xy 409.338244 -176.499285) (xy 409.32339 -176.447799)
			(xy 409.315886 -176.394741) (xy 409.315412 -176.367948) (xy 409.315929 -176.339208) (xy 409.324546 -176.282376)
			(xy 409.341591 -176.227481) (xy 409.366679 -176.175765) (xy 409.399242 -176.128397) (xy 409.418536 -176.10709)
			(xy 409.428618 -176.095557) (xy 409.441978 -176.068007) (xy 409.446577 -176.037735) (xy 409.441999 -176.00746)
			(xy 409.428658 -175.979901) (xy 409.418536 -175.968406) (xy 409.399262 -175.94708) (xy 409.36669 -175.89972)
			(xy 409.341591 -175.848008) (xy 409.324533 -175.793117) (xy 409.315903 -175.736288) (xy 409.315412 -175.707548)
			(xy 409.315863 -175.680752) (xy 409.323357 -175.627686) (xy 409.338204 -175.576192) (xy 409.360112 -175.527282)
			(xy 409.38865 -175.48192) (xy 409.423255 -175.440998) (xy 409.463247 -175.405322) (xy 409.507839 -175.375595)
			(xy 409.53182 -175.363632) (xy 409.53182 -174.103284) (xy 409.507863 -174.09128) (xy 409.463277 -174.061559)
			(xy 409.42329 -174.02589) (xy 409.388688 -173.984976) (xy 409.360152 -173.939622) (xy 409.338244 -173.890721)
			(xy 409.323395 -173.839235) (xy 409.315898 -173.786178) (xy 409.3159 -173.732594) (xy 409.323401 -173.679538)
			(xy 409.338253 -173.628053) (xy 409.360165 -173.579153) (xy 409.388704 -173.533802) (xy 409.423309 -173.49289)
			(xy 409.463299 -173.457224) (xy 409.507887 -173.427506) (xy 409.53182 -173.415452) (xy 409.53182 -168.075864)
			(xy 409.507864 -168.063857) (xy 409.46328 -168.03413) (xy 409.423294 -167.998457) (xy 409.388692 -167.957541)
			(xy 409.360155 -167.912186) (xy 409.338244 -167.863285) (xy 409.32339 -167.811799) (xy 409.315886 -167.758741)
			(xy 409.315412 -167.731948) (xy 409.315848 -167.705679) (xy 409.323055 -167.653638) (xy 409.337338 -167.603079)
			(xy 409.358428 -167.55496) (xy 409.385924 -167.510192) (xy 409.40228 -167.489632) (xy 409.407917 -167.482096)
			(xy 409.413822 -167.464245) (xy 409.412913 -167.445465) (xy 409.405309 -167.428269) (xy 409.398978 -167.421306)
			(xy 408.71394 -166.736268) (xy 400.37512 -166.736268) (xy 399.481548 -167.62984) (xy 399.481548 -168.923208)
			(xy 399.481077 -168.952337) (xy 399.477002 -168.983152) (xy 399.642589 -168.983152) (xy 399.646611 -168.897432)
			(xy 399.658642 -168.812464) (xy 399.678578 -168.728997) (xy 399.706241 -168.647763) (xy 399.74139 -168.569477)
			(xy 399.783716 -168.494826) (xy 399.832845 -168.424467) (xy 399.888348 -168.359017) (xy 399.949735 -168.299053)
			(xy 400.016468 -168.2451) (xy 400.08796 -168.197633) (xy 400.163582 -168.157069) (xy 400.242671 -168.123765)
			(xy 400.324531 -168.098013) (xy 400.408442 -168.08004) (xy 400.493668 -168.070004) (xy 400.57946 -168.067992)
			(xy 400.665062 -168.074023) (xy 400.749724 -168.088043) (xy 400.832701 -168.109929) (xy 400.913264 -168.13949)
			(xy 400.990704 -168.176464) (xy 401.064343 -168.220528) (xy 401.133531 -168.271294) (xy 401.197662 -168.328315)
			(xy 401.256171 -168.391091) (xy 401.308544 -168.459071) (xy 401.354322 -168.531656) (xy 401.393102 -168.608208)
			(xy 401.424543 -168.688056) (xy 401.448369 -168.770497) (xy 401.46437 -168.854807) (xy 401.472405 -168.940245)
			(xy 401.472908 -168.983152) (xy 401.472405 -169.026059) (xy 401.46437 -169.111497) (xy 401.448369 -169.195807)
			(xy 401.424543 -169.278248) (xy 401.393102 -169.358096) (xy 401.354322 -169.434648) (xy 401.308544 -169.507233)
			(xy 401.256171 -169.575213) (xy 401.197662 -169.637989) (xy 401.133531 -169.69501) (xy 401.064343 -169.745776)
			(xy 400.990704 -169.78984) (xy 400.913264 -169.826814) (xy 400.832701 -169.856375) (xy 400.749724 -169.878261)
			(xy 400.665062 -169.892281) (xy 400.57946 -169.898312) (xy 400.493668 -169.8963) (xy 400.408442 -169.886264)
			(xy 400.324531 -169.868291) (xy 400.242671 -169.842539) (xy 400.163582 -169.809235) (xy 400.08796 -169.768671)
			(xy 400.016468 -169.721204) (xy 399.949735 -169.667251) (xy 399.888348 -169.607287) (xy 399.832845 -169.541837)
			(xy 399.783716 -169.471478) (xy 399.74139 -169.396827) (xy 399.706241 -169.318541) (xy 399.678578 -169.237307)
			(xy 399.658642 -169.15384) (xy 399.646611 -169.068872) (xy 399.642589 -168.983152) (xy 399.477002 -168.983152)
			(xy 399.473439 -169.010091) (xy 399.45832 -169.066353) (xy 399.435981 -169.120157) (xy 399.406803 -169.170581)
			(xy 399.371288 -169.216761) (xy 399.350992 -169.23766) (xy 398.02308 -170.565826) (xy 398.02308 -171.025496)
			(xy 399.668996 -171.025496) (xy 399.668996 -170.9408) (xy 399.677047 -170.856486) (xy 399.693076 -170.77332)
			(xy 399.716937 -170.692053) (xy 399.748416 -170.613423) (xy 399.787227 -170.538142) (xy 399.833017 -170.46689)
			(xy 399.885373 -170.400314) (xy 399.943821 -170.339016) (xy 400.007831 -170.283551) (xy 400.076823 -170.234422)
			(xy 400.150173 -170.192073) (xy 400.227216 -170.156889) (xy 400.307255 -170.129187) (xy 400.389564 -170.109219)
			(xy 400.473399 -170.097166) (xy 400.558 -170.093136) (xy 400.642601 -170.097166) (xy 400.726436 -170.109219)
			(xy 400.808745 -170.129187) (xy 400.888784 -170.156889) (xy 400.965827 -170.192073) (xy 401.039177 -170.234422)
			(xy 401.108169 -170.283551) (xy 401.172179 -170.339016) (xy 401.230627 -170.400314) (xy 401.282983 -170.46689)
			(xy 401.328773 -170.538142) (xy 401.367584 -170.613423) (xy 401.399063 -170.692053) (xy 401.422924 -170.77332)
			(xy 401.438953 -170.856486) (xy 401.447004 -170.9408) (xy 401.447508 -170.983148) (xy 401.447004 -171.025496)
			(xy 401.438953 -171.10981) (xy 401.422924 -171.192976) (xy 401.399063 -171.274243) (xy 401.367584 -171.352873)
			(xy 401.328773 -171.428154) (xy 401.282983 -171.499406) (xy 401.230627 -171.565982) (xy 401.172179 -171.62728)
			(xy 401.108169 -171.682745) (xy 401.039177 -171.731874) (xy 400.965827 -171.774223) (xy 400.888784 -171.809407)
			(xy 400.808745 -171.837109) (xy 400.726436 -171.857077) (xy 400.642601 -171.86913) (xy 400.558 -171.873161)
			(xy 400.473399 -171.86913) (xy 400.389564 -171.857077) (xy 400.307255 -171.837109) (xy 400.227216 -171.809407)
			(xy 400.150173 -171.774223) (xy 400.076823 -171.731874) (xy 400.007831 -171.682745) (xy 399.943821 -171.62728)
			(xy 399.885373 -171.565982) (xy 399.833017 -171.499406) (xy 399.787227 -171.428154) (xy 399.748416 -171.352873)
			(xy 399.716937 -171.274243) (xy 399.693076 -171.192976) (xy 399.677047 -171.10981) (xy 399.668996 -171.025496)
			(xy 398.02308 -171.025496) (xy 398.02308 -175.206152) (xy 399.642589 -175.206152) (xy 399.646611 -175.120432)
			(xy 399.658642 -175.035464) (xy 399.678578 -174.951997) (xy 399.706241 -174.870763) (xy 399.74139 -174.792477)
			(xy 399.783716 -174.717826) (xy 399.832845 -174.647467) (xy 399.888348 -174.582017) (xy 399.949735 -174.522053)
			(xy 400.016468 -174.4681) (xy 400.08796 -174.420633) (xy 400.163582 -174.380069) (xy 400.242671 -174.346765)
			(xy 400.324531 -174.321013) (xy 400.408442 -174.30304) (xy 400.493668 -174.293004) (xy 400.57946 -174.290992)
			(xy 400.665062 -174.297023) (xy 400.749724 -174.311043) (xy 400.832701 -174.332929) (xy 400.913264 -174.36249)
			(xy 400.990704 -174.399464) (xy 401.064343 -174.443528) (xy 401.133531 -174.494294) (xy 401.197662 -174.551315)
			(xy 401.256171 -174.614091) (xy 401.308544 -174.682071) (xy 401.354322 -174.754656) (xy 401.393102 -174.831208)
			(xy 401.424543 -174.911056) (xy 401.448369 -174.993497) (xy 401.46437 -175.077807) (xy 401.472405 -175.163245)
			(xy 401.472908 -175.206152) (xy 401.472405 -175.249059) (xy 401.46437 -175.334497) (xy 401.448369 -175.418807)
			(xy 401.424543 -175.501248) (xy 401.393102 -175.581096) (xy 401.354322 -175.657648) (xy 401.308544 -175.730233)
			(xy 401.256171 -175.798213) (xy 401.197662 -175.860989) (xy 401.133531 -175.91801) (xy 401.064343 -175.968776)
			(xy 400.990704 -176.01284) (xy 400.913264 -176.049814) (xy 400.832701 -176.079375) (xy 400.749724 -176.101261)
			(xy 400.665062 -176.115281) (xy 400.57946 -176.121312) (xy 400.493668 -176.1193) (xy 400.408442 -176.109264)
			(xy 400.324531 -176.091291) (xy 400.242671 -176.065539) (xy 400.163582 -176.032235) (xy 400.08796 -175.991671)
			(xy 400.016468 -175.944204) (xy 399.949735 -175.890251) (xy 399.888348 -175.830287) (xy 399.832845 -175.764837)
			(xy 399.783716 -175.694478) (xy 399.74139 -175.619827) (xy 399.706241 -175.541541) (xy 399.678578 -175.460307)
			(xy 399.658642 -175.37684) (xy 399.646611 -175.291872) (xy 399.642589 -175.206152) (xy 398.02308 -175.206152)
			(xy 398.02308 -177.248496) (xy 399.668996 -177.248496) (xy 399.668996 -177.1638) (xy 399.677047 -177.079486)
			(xy 399.693076 -176.99632) (xy 399.716937 -176.915053) (xy 399.748416 -176.836423) (xy 399.787227 -176.761142)
			(xy 399.833017 -176.68989) (xy 399.885373 -176.623314) (xy 399.943821 -176.562016) (xy 400.007831 -176.506551)
			(xy 400.076823 -176.457422) (xy 400.150173 -176.415073) (xy 400.227216 -176.379889) (xy 400.307255 -176.352187)
			(xy 400.389564 -176.332219) (xy 400.473399 -176.320166) (xy 400.558 -176.316136) (xy 400.642601 -176.320166)
			(xy 400.726436 -176.332219) (xy 400.808745 -176.352187) (xy 400.888784 -176.379889) (xy 400.965827 -176.415073)
			(xy 401.039177 -176.457422) (xy 401.108169 -176.506551) (xy 401.172179 -176.562016) (xy 401.230627 -176.623314)
			(xy 401.282983 -176.68989) (xy 401.328773 -176.761142) (xy 401.367584 -176.836423) (xy 401.399063 -176.915053)
			(xy 401.422924 -176.99632) (xy 401.438953 -177.079486) (xy 401.447004 -177.1638) (xy 401.447508 -177.206148)
			(xy 401.447004 -177.248496) (xy 401.438953 -177.33281) (xy 401.422924 -177.415976) (xy 401.399063 -177.497243)
			(xy 401.367584 -177.575873) (xy 401.328773 -177.651154) (xy 401.282983 -177.722406) (xy 401.230627 -177.788982)
			(xy 401.172179 -177.85028) (xy 401.108169 -177.905745) (xy 401.039177 -177.954874) (xy 400.965827 -177.997223)
			(xy 400.888784 -178.032407) (xy 400.808745 -178.060109) (xy 400.726436 -178.080077) (xy 400.642601 -178.09213)
			(xy 400.558 -178.096161) (xy 400.473399 -178.09213) (xy 400.389564 -178.080077) (xy 400.307255 -178.060109)
			(xy 400.227216 -178.032407) (xy 400.150173 -177.997223) (xy 400.076823 -177.954874) (xy 400.007831 -177.905745)
			(xy 399.943821 -177.85028) (xy 399.885373 -177.788982) (xy 399.833017 -177.722406) (xy 399.787227 -177.651154)
			(xy 399.748416 -177.575873) (xy 399.716937 -177.497243) (xy 399.693076 -177.415976) (xy 399.677047 -177.33281)
			(xy 399.668996 -177.248496) (xy 398.02308 -177.248496) (xy 398.02308 -181.429152) (xy 399.642589 -181.429152)
			(xy 399.646611 -181.343432) (xy 399.658642 -181.258464) (xy 399.678578 -181.174997) (xy 399.706241 -181.093763)
			(xy 399.74139 -181.015477) (xy 399.783716 -180.940826) (xy 399.832845 -180.870467) (xy 399.888348 -180.805017)
			(xy 399.949735 -180.745053) (xy 400.016468 -180.6911) (xy 400.08796 -180.643633) (xy 400.163582 -180.603069)
			(xy 400.242671 -180.569765) (xy 400.324531 -180.544013) (xy 400.408442 -180.52604) (xy 400.493668 -180.516004)
			(xy 400.57946 -180.513992) (xy 400.665062 -180.520023) (xy 400.749724 -180.534043) (xy 400.832701 -180.555929)
			(xy 400.913264 -180.58549) (xy 400.990704 -180.622464) (xy 401.064343 -180.666528) (xy 401.133531 -180.717294)
			(xy 401.197662 -180.774315) (xy 401.256171 -180.837091) (xy 401.308544 -180.905071) (xy 401.354322 -180.977656)
			(xy 401.393102 -181.054208) (xy 401.424543 -181.134056) (xy 401.448369 -181.216497) (xy 401.46437 -181.300807)
			(xy 401.472405 -181.386245) (xy 401.472908 -181.429152) (xy 401.472405 -181.472059) (xy 401.46437 -181.557497)
			(xy 401.448369 -181.641807) (xy 401.424543 -181.724248) (xy 401.393102 -181.804096) (xy 401.354322 -181.880648)
			(xy 401.308544 -181.953233) (xy 401.256171 -182.021213) (xy 401.197662 -182.083989) (xy 401.133531 -182.14101)
			(xy 401.064343 -182.191776) (xy 400.990704 -182.23584) (xy 400.913264 -182.272814) (xy 400.832701 -182.302375)
			(xy 400.749724 -182.324261) (xy 400.665062 -182.338281) (xy 400.57946 -182.344312) (xy 400.493668 -182.3423)
			(xy 400.408442 -182.332264) (xy 400.324531 -182.314291) (xy 400.242671 -182.288539) (xy 400.163582 -182.255235)
			(xy 400.08796 -182.214671) (xy 400.016468 -182.167204) (xy 399.949735 -182.113251) (xy 399.888348 -182.053287)
			(xy 399.832845 -181.987837) (xy 399.783716 -181.917478) (xy 399.74139 -181.842827) (xy 399.706241 -181.764541)
			(xy 399.678578 -181.683307) (xy 399.658642 -181.59984) (xy 399.646611 -181.514872) (xy 399.642589 -181.429152)
			(xy 398.02308 -181.429152) (xy 398.02308 -183.471496) (xy 399.668996 -183.471496) (xy 399.668996 -183.3868)
			(xy 399.677047 -183.302486) (xy 399.693076 -183.21932) (xy 399.716937 -183.138053) (xy 399.748416 -183.059423)
			(xy 399.787227 -182.984142) (xy 399.833017 -182.91289) (xy 399.885373 -182.846314) (xy 399.943821 -182.785016)
			(xy 400.007831 -182.729551) (xy 400.076823 -182.680422) (xy 400.150173 -182.638073) (xy 400.227216 -182.602889)
			(xy 400.307255 -182.575187) (xy 400.389564 -182.555219) (xy 400.473399 -182.543166) (xy 400.558 -182.539136)
			(xy 400.642601 -182.543166) (xy 400.726436 -182.555219) (xy 400.808745 -182.575187) (xy 400.888784 -182.602889)
			(xy 400.965827 -182.638073) (xy 401.039177 -182.680422) (xy 401.108169 -182.729551) (xy 401.172179 -182.785016)
			(xy 401.230627 -182.846314) (xy 401.282983 -182.91289) (xy 401.328773 -182.984142) (xy 401.367584 -183.059423)
			(xy 401.399063 -183.138053) (xy 401.422924 -183.21932) (xy 401.438953 -183.302486) (xy 401.447004 -183.3868)
			(xy 401.447508 -183.429148) (xy 401.447004 -183.471496) (xy 401.438953 -183.55581) (xy 401.422924 -183.638976)
			(xy 401.399063 -183.720243) (xy 401.367584 -183.798873) (xy 401.328773 -183.874154) (xy 401.282983 -183.945406)
			(xy 401.230627 -184.011982) (xy 401.172179 -184.07328) (xy 401.108169 -184.128745) (xy 401.039177 -184.177874)
			(xy 400.965827 -184.220223) (xy 400.888784 -184.255407) (xy 400.808745 -184.283109) (xy 400.726436 -184.303077)
			(xy 400.642601 -184.31513) (xy 400.558 -184.319161) (xy 400.473399 -184.31513) (xy 400.389564 -184.303077)
			(xy 400.307255 -184.283109) (xy 400.227216 -184.255407) (xy 400.150173 -184.220223) (xy 400.076823 -184.177874)
			(xy 400.007831 -184.128745) (xy 399.943821 -184.07328) (xy 399.885373 -184.011982) (xy 399.833017 -183.945406)
			(xy 399.787227 -183.874154) (xy 399.748416 -183.798873) (xy 399.716937 -183.720243) (xy 399.693076 -183.638976)
			(xy 399.677047 -183.55581) (xy 399.668996 -183.471496) (xy 398.02308 -183.471496) (xy 398.02308 -183.761888)
			(xy 398.88414 -184.622948)
		)
		(stroke
			(width 0)
			(type solid)
		)
		(fill yes)
		(layer "In4.Cu")
		(net "PVCCINFAON_CPU0")
	)
	(gr_poly
		(pts
			(xy 71.86168 -160.251648) (xy 72.40905 -160.251648) (xy 72.41032 -160.210246) (xy 72.410944 -160.18309)
			(xy 72.418934 -160.129362) (xy 72.434465 -160.07731) (xy 72.457221 -160.027988) (xy 72.486743 -159.982392)
			(xy 72.522433 -159.941444) (xy 72.56357 -159.905972) (xy 72.609323 -159.876694) (xy 72.658766 -159.854201)
			(xy 72.710899 -159.838948) (xy 72.764669 -159.831244) (xy 72.818987 -159.831244) (xy 72.872757 -159.838948)
			(xy 72.92489 -159.854201) (xy 72.974333 -159.876694) (xy 73.020086 -159.905972) (xy 73.061223 -159.941444)
			(xy 73.096913 -159.982392) (xy 73.126435 -160.027988) (xy 73.149191 -160.07731) (xy 73.164722 -160.129362)
			(xy 73.172712 -160.18309) (xy 73.173336 -160.210246) (xy 73.174606 -160.251648) (xy 73.64476 -160.251648)
			(xy 75.95108 -157.945328) (xy 75.95108 -150.471886) (xy 75.946508 -150.461726) (xy 75.938867 -150.44471)
			(xy 75.92665 -150.409464) (xy 75.922124 -150.391368) (xy 75.917602 -150.370709) (xy 75.912759 -150.328694)
			(xy 75.912472 -150.307548) (xy 75.912472 -149.792182) (xy 75.911943 -149.776753) (xy 75.90274 -149.747301)
			(xy 75.885151 -149.721949) (xy 75.860787 -149.703015) (xy 75.831875 -149.692234) (xy 75.801063 -149.690591)
			(xy 75.78598 -149.693884) (xy 75.785726 -149.693884) (xy 75.782932 -149.694646) (xy 75.76111 -149.699657)
			(xy 75.716672 -149.705136) (xy 75.694286 -149.705568) (xy 75.689206 -149.705568) (xy 75.662088 -149.704892)
			(xy 75.608448 -149.696815) (xy 75.556493 -149.681221) (xy 75.507272 -149.658424) (xy 75.461775 -149.628885)
			(xy 75.420922 -149.593199) (xy 75.385536 -149.552086) (xy 75.356331 -149.506375) (xy 75.333896 -149.456987)
			(xy 75.318683 -149.404919) (xy 75.310999 -149.351222) (xy 75.310999 -149.296977) (xy 75.318683 -149.24328)
			(xy 75.333896 -149.191212) (xy 75.356332 -149.141825) (xy 75.385537 -149.096114) (xy 75.420923 -149.055)
			(xy 75.461776 -149.019314) (xy 75.507272 -148.989775) (xy 75.556494 -148.966979) (xy 75.608449 -148.951385)
			(xy 75.662089 -148.943308) (xy 75.689206 -148.942552) (xy 75.692254 -148.942552) (xy 75.715149 -148.942891)
			(xy 75.760611 -148.948368) (xy 75.782932 -148.953474) (xy 75.785726 -148.954236) (xy 75.78598 -148.954236)
			(xy 75.801052 -148.957482) (xy 75.831819 -148.955764) (xy 75.860678 -148.944957) (xy 75.885006 -148.926042)
			(xy 75.902593 -148.900739) (xy 75.911843 -148.871344) (xy 75.912472 -148.855938) (xy 75.912472 -145.710402)
			(xy 75.75169 -145.549366) (xy 75.512676 -145.310352) (xy 75.489286 -145.285911) (xy 75.45094 -145.230189)
			(xy 75.436476 -145.199608) (xy 75.426062 -145.17751) (xy 75.153774 -145.17751) (xy 75.123346 -145.20589)
			(xy 75.057346 -145.256566) (xy 74.986221 -145.299754) (xy 74.910815 -145.334938) (xy 74.832025 -145.361702)
			(xy 74.75079 -145.379725) (xy 74.668075 -145.388795) (xy 74.62647 -145.389346) (xy 74.586536 -145.388822)
			(xy 74.507107 -145.380471) (xy 74.428985 -145.363863) (xy 74.353027 -145.339181) (xy 74.280065 -145.306695)
			(xy 74.210899 -145.266761) (xy 74.146285 -145.219816) (xy 74.086932 -145.166374) (xy 74.033489 -145.107022)
			(xy 73.986544 -145.042408) (xy 73.946609 -144.973242) (xy 73.914122 -144.90028) (xy 73.889439 -144.824323)
			(xy 73.872831 -144.746201) (xy 73.864479 -144.666772) (xy 73.863962 -144.626838) (xy 73.864431 -144.588575)
			(xy 73.872097 -144.512433) (xy 73.887355 -144.437442) (xy 73.910052 -144.364359) (xy 73.939959 -144.293918)
			(xy 73.976775 -144.226828) (xy 73.998074 -144.195038) (xy 73.976787 -144.16324) (xy 73.939974 -144.096151)
			(xy 73.910069 -144.025711) (xy 73.887371 -143.952629) (xy 73.87211 -143.877641) (xy 73.864439 -143.801501)
			(xy 73.863962 -143.763238) (xy 73.864465 -143.723301) (xy 73.87281 -143.643865) (xy 73.889413 -143.565736)
			(xy 73.914091 -143.489771) (xy 73.946575 -143.416801) (xy 73.986509 -143.347627) (xy 74.033454 -143.283006)
			(xy 74.086898 -143.223646) (xy 74.146253 -143.170197) (xy 74.21087 -143.123246) (xy 74.28004 -143.083306)
			(xy 74.353007 -143.050816) (xy 74.42897 -143.02613) (xy 74.507098 -143.009521) (xy 74.586533 -143.001168)
			(xy 74.62647 -143.00073) (xy 74.66482 -143.001208) (xy 74.741133 -143.008914) (xy 74.816287 -143.024241)
			(xy 74.889523 -143.047035) (xy 74.960101 -143.077064) (xy 75.027308 -143.114027) (xy 75.090466 -143.157549)
			(xy 75.148936 -143.20719) (xy 75.202128 -143.26245) (xy 75.249504 -143.32277) (xy 75.290586 -143.387541)
			(xy 75.308206 -143.421608) (xy 75.32243 -143.449802) (xy 75.404472 -143.449802) (xy 75.404472 -143.297402)
			(xy 74.185018 -142.077948) (xy 63.3222 -142.077948) (xy 63.123572 -142.276576) (xy 63.123572 -144.665192)
			(xy 71.87641 -144.665192) (xy 71.880481 -144.60957) (xy 71.892607 -144.555133) (xy 71.91253 -144.503042)
			(xy 71.939826 -144.454407) (xy 71.973912 -144.410264) (xy 72.014061 -144.371555) (xy 72.059419 -144.339104)
			(xy 72.109019 -144.313603) (xy 72.161803 -144.295596) (xy 72.216646 -144.285466) (xy 72.27238 -144.283429)
			(xy 72.327817 -144.289529) (xy 72.381774 -144.303635) (xy 72.433103 -144.325447) (xy 72.480709 -144.354501)
			(xy 72.523577 -144.390176) (xy 72.560794 -144.431713) (xy 72.591567 -144.478226) (xy 72.615239 -144.528723)
			(xy 72.631307 -144.58213) (xy 72.639427 -144.637306) (xy 72.639936 -144.665192) (xy 72.639427 -144.693078)
			(xy 72.631307 -144.748254) (xy 72.615239 -144.801661) (xy 72.591567 -144.852158) (xy 72.560794 -144.898671)
			(xy 72.523577 -144.940208) (xy 72.480709 -144.975883) (xy 72.433103 -145.004937) (xy 72.381774 -145.026749)
			(xy 72.327817 -145.040855) (xy 72.27238 -145.046955) (xy 72.216646 -145.044918) (xy 72.161803 -145.034788)
			(xy 72.109019 -145.016781) (xy 72.059419 -144.99128) (xy 72.014061 -144.958829) (xy 71.973912 -144.92012)
			(xy 71.939826 -144.875977) (xy 71.91253 -144.827342) (xy 71.892607 -144.775251) (xy 71.880481 -144.720814)
			(xy 71.87641 -144.665192) (xy 63.123572 -144.665192) (xy 63.123572 -146.228308) (xy 69.007995 -146.228308)
			(xy 69.012017 -146.142588) (xy 69.024048 -146.05762) (xy 69.043984 -145.974153) (xy 69.071647 -145.892919)
			(xy 69.106796 -145.814633) (xy 69.149122 -145.739982) (xy 69.198251 -145.669623) (xy 69.253754 -145.604173)
			(xy 69.315141 -145.544209) (xy 69.381874 -145.490256) (xy 69.453366 -145.442789) (xy 69.528988 -145.402225)
			(xy 69.608077 -145.368921) (xy 69.689937 -145.343169) (xy 69.773848 -145.325196) (xy 69.859074 -145.31516)
			(xy 69.944866 -145.313148) (xy 70.030468 -145.319179) (xy 70.11513 -145.333199) (xy 70.198107 -145.355085)
			(xy 70.27867 -145.384646) (xy 70.35611 -145.42162) (xy 70.429749 -145.465684) (xy 70.498937 -145.51645)
			(xy 70.563068 -145.573471) (xy 70.621577 -145.636247) (xy 70.67395 -145.704227) (xy 70.719728 -145.776812)
			(xy 70.758508 -145.853364) (xy 70.789949 -145.933212) (xy 70.813775 -146.015653) (xy 70.829776 -146.099963)
			(xy 70.837811 -146.185401) (xy 70.838314 -146.228308) (xy 70.837811 -146.271215) (xy 70.829776 -146.356653)
			(xy 70.813775 -146.440963) (xy 70.789949 -146.523404) (xy 70.758508 -146.603252) (xy 70.719728 -146.679804)
			(xy 70.67395 -146.752389) (xy 70.621577 -146.820369) (xy 70.563068 -146.883145) (xy 70.498937 -146.940166)
			(xy 70.429749 -146.990932) (xy 70.35611 -147.034996) (xy 70.27867 -147.07197) (xy 70.198107 -147.101531)
			(xy 70.11513 -147.123417) (xy 70.030468 -147.137437) (xy 69.944866 -147.143468) (xy 69.859074 -147.141456)
			(xy 69.773848 -147.13142) (xy 69.689937 -147.113447) (xy 69.608077 -147.087695) (xy 69.528988 -147.054391)
			(xy 69.453366 -147.013827) (xy 69.381874 -146.96636) (xy 69.315141 -146.912407) (xy 69.253754 -146.852443)
			(xy 69.198251 -146.786993) (xy 69.149122 -146.716634) (xy 69.106796 -146.641983) (xy 69.071647 -146.563697)
			(xy 69.043984 -146.482463) (xy 69.024048 -146.398996) (xy 69.012017 -146.314028) (xy 69.007995 -146.228308)
			(xy 63.123572 -146.228308) (xy 63.123572 -148.270652) (xy 69.034402 -148.270652) (xy 69.034402 -148.185956)
			(xy 69.042453 -148.101642) (xy 69.058482 -148.018476) (xy 69.082343 -147.937209) (xy 69.113822 -147.858579)
			(xy 69.152633 -147.783298) (xy 69.198423 -147.712046) (xy 69.250779 -147.64547) (xy 69.309227 -147.584172)
			(xy 69.373237 -147.528707) (xy 69.442229 -147.479578) (xy 69.515579 -147.437229) (xy 69.592622 -147.402045)
			(xy 69.672661 -147.374343) (xy 69.75497 -147.354375) (xy 69.838805 -147.342322) (xy 69.923406 -147.338292)
			(xy 70.008007 -147.342322) (xy 70.091842 -147.354375) (xy 70.174151 -147.374343) (xy 70.25419 -147.402045)
			(xy 70.331233 -147.437229) (xy 70.404583 -147.479578) (xy 70.473575 -147.528707) (xy 70.537585 -147.584172)
			(xy 70.596033 -147.64547) (xy 70.648389 -147.712046) (xy 70.694179 -147.783298) (xy 70.73299 -147.858579)
			(xy 70.764469 -147.937209) (xy 70.78833 -148.018476) (xy 70.804359 -148.101642) (xy 70.81241 -148.185956)
			(xy 70.812914 -148.228304) (xy 70.81241 -148.270652) (xy 70.804359 -148.354966) (xy 70.78833 -148.438132)
			(xy 70.764469 -148.519399) (xy 70.73299 -148.598029) (xy 70.694179 -148.67331) (xy 70.648389 -148.744562)
			(xy 70.596033 -148.811138) (xy 70.537585 -148.872436) (xy 70.473575 -148.927901) (xy 70.404583 -148.97703)
			(xy 70.331233 -149.019379) (xy 70.25419 -149.054563) (xy 70.174151 -149.082265) (xy 70.091842 -149.102233)
			(xy 70.008007 -149.114286) (xy 69.923406 -149.118317) (xy 69.838805 -149.114286) (xy 69.75497 -149.102233)
			(xy 69.672661 -149.082265) (xy 69.592622 -149.054563) (xy 69.515579 -149.019379) (xy 69.442229 -148.97703)
			(xy 69.373237 -148.927901) (xy 69.309227 -148.872436) (xy 69.250779 -148.811138) (xy 69.198423 -148.744562)
			(xy 69.152633 -148.67331) (xy 69.113822 -148.598029) (xy 69.082343 -148.519399) (xy 69.058482 -148.438132)
			(xy 69.042453 -148.354966) (xy 69.034402 -148.270652) (xy 63.123572 -148.270652) (xy 63.123572 -152.364694)
			(xy 69.007995 -152.364694) (xy 69.012017 -152.278974) (xy 69.024048 -152.194006) (xy 69.043984 -152.110539)
			(xy 69.071647 -152.029305) (xy 69.106796 -151.951019) (xy 69.149122 -151.876368) (xy 69.198251 -151.806009)
			(xy 69.253754 -151.740559) (xy 69.315141 -151.680595) (xy 69.381874 -151.626642) (xy 69.453366 -151.579175)
			(xy 69.528988 -151.538611) (xy 69.608077 -151.505307) (xy 69.689937 -151.479555) (xy 69.773848 -151.461582)
			(xy 69.859074 -151.451546) (xy 69.944866 -151.449534) (xy 70.030468 -151.455565) (xy 70.11513 -151.469585)
			(xy 70.198107 -151.491471) (xy 70.27867 -151.521032) (xy 70.35611 -151.558006) (xy 70.429749 -151.60207)
			(xy 70.498937 -151.652836) (xy 70.563068 -151.709857) (xy 70.621577 -151.772633) (xy 70.67395 -151.840613)
			(xy 70.719728 -151.913198) (xy 70.758508 -151.98975) (xy 70.789949 -152.069598) (xy 70.813775 -152.152039)
			(xy 70.829776 -152.236349) (xy 70.837811 -152.321787) (xy 70.838314 -152.364694) (xy 70.837811 -152.407601)
			(xy 70.829776 -152.493039) (xy 70.813775 -152.577349) (xy 70.789949 -152.65979) (xy 70.758508 -152.739638)
			(xy 70.719728 -152.81619) (xy 70.67395 -152.888775) (xy 70.621577 -152.956755) (xy 70.563068 -153.019531)
			(xy 70.498937 -153.076552) (xy 70.429749 -153.127318) (xy 70.35611 -153.171382) (xy 70.27867 -153.208356)
			(xy 70.198107 -153.237917) (xy 70.11513 -153.259803) (xy 70.030468 -153.273823) (xy 69.944866 -153.279854)
			(xy 69.859074 -153.277842) (xy 69.773848 -153.267806) (xy 69.689937 -153.249833) (xy 69.608077 -153.224081)
			(xy 69.528988 -153.190777) (xy 69.453366 -153.150213) (xy 69.381874 -153.102746) (xy 69.315141 -153.048793)
			(xy 69.253754 -152.988829) (xy 69.198251 -152.923379) (xy 69.149122 -152.85302) (xy 69.106796 -152.778369)
			(xy 69.071647 -152.700083) (xy 69.043984 -152.618849) (xy 69.024048 -152.535382) (xy 69.012017 -152.450414)
			(xy 69.007995 -152.364694) (xy 63.123572 -152.364694) (xy 63.123572 -154.407038) (xy 69.034402 -154.407038)
			(xy 69.034402 -154.322342) (xy 69.042453 -154.238028) (xy 69.058482 -154.154862) (xy 69.082343 -154.073595)
			(xy 69.113822 -153.994965) (xy 69.152633 -153.919684) (xy 69.198423 -153.848432) (xy 69.250779 -153.781856)
			(xy 69.309227 -153.720558) (xy 69.373237 -153.665093) (xy 69.442229 -153.615964) (xy 69.515579 -153.573615)
			(xy 69.592622 -153.538431) (xy 69.672661 -153.510729) (xy 69.75497 -153.490761) (xy 69.838805 -153.478708)
			(xy 69.923406 -153.474678) (xy 70.008007 -153.478708) (xy 70.091842 -153.490761) (xy 70.174151 -153.510729)
			(xy 70.25419 -153.538431) (xy 70.331233 -153.573615) (xy 70.404583 -153.615964) (xy 70.473575 -153.665093)
			(xy 70.537585 -153.720558) (xy 70.596033 -153.781856) (xy 70.648389 -153.848432) (xy 70.694179 -153.919684)
			(xy 70.73299 -153.994965) (xy 70.764469 -154.073595) (xy 70.78833 -154.154862) (xy 70.804359 -154.238028)
			(xy 70.81241 -154.322342) (xy 70.812914 -154.36469) (xy 70.81241 -154.407038) (xy 70.804359 -154.491352)
			(xy 70.78833 -154.574518) (xy 70.764469 -154.655785) (xy 70.73299 -154.734415) (xy 70.694179 -154.809696)
			(xy 70.648389 -154.880948) (xy 70.596033 -154.947524) (xy 70.537585 -155.008822) (xy 70.473575 -155.064287)
			(xy 70.404583 -155.113416) (xy 70.331233 -155.155765) (xy 70.25419 -155.190949) (xy 70.174151 -155.218651)
			(xy 70.091842 -155.238619) (xy 70.008007 -155.250672) (xy 69.923406 -155.254703) (xy 69.838805 -155.250672)
			(xy 69.75497 -155.238619) (xy 69.672661 -155.218651) (xy 69.592622 -155.190949) (xy 69.515579 -155.155765)
			(xy 69.442229 -155.113416) (xy 69.373237 -155.064287) (xy 69.309227 -155.008822) (xy 69.250779 -154.947524)
			(xy 69.198423 -154.880948) (xy 69.152633 -154.809696) (xy 69.113822 -154.734415) (xy 69.082343 -154.655785)
			(xy 69.058482 -154.574518) (xy 69.042453 -154.491352) (xy 69.034402 -154.407038) (xy 63.123572 -154.407038)
			(xy 63.123572 -158.49981) (xy 69.007995 -158.49981) (xy 69.012017 -158.41409) (xy 69.024048 -158.329122)
			(xy 69.043984 -158.245655) (xy 69.071647 -158.164421) (xy 69.106796 -158.086135) (xy 69.149122 -158.011484)
			(xy 69.198251 -157.941125) (xy 69.253754 -157.875675) (xy 69.315141 -157.815711) (xy 69.381874 -157.761758)
			(xy 69.453366 -157.714291) (xy 69.528988 -157.673727) (xy 69.608077 -157.640423) (xy 69.689937 -157.614671)
			(xy 69.773848 -157.596698) (xy 69.859074 -157.586662) (xy 69.944866 -157.58465) (xy 70.030468 -157.590681)
			(xy 70.11513 -157.604701) (xy 70.198107 -157.626587) (xy 70.27867 -157.656148) (xy 70.35611 -157.693122)
			(xy 70.429749 -157.737186) (xy 70.498937 -157.787952) (xy 70.563068 -157.844973) (xy 70.621577 -157.907749)
			(xy 70.67395 -157.975729) (xy 70.719728 -158.048314) (xy 70.758508 -158.124866) (xy 70.789949 -158.204714)
			(xy 70.813775 -158.287155) (xy 70.829776 -158.371465) (xy 70.837811 -158.456903) (xy 70.838314 -158.49981)
			(xy 70.837811 -158.542717) (xy 70.829776 -158.628155) (xy 70.813775 -158.712465) (xy 70.789949 -158.794906)
			(xy 70.758508 -158.874754) (xy 70.719728 -158.951306) (xy 70.67395 -159.023891) (xy 70.621577 -159.091871)
			(xy 70.563068 -159.154647) (xy 70.498937 -159.211668) (xy 70.429749 -159.262434) (xy 70.35611 -159.306498)
			(xy 70.27867 -159.343472) (xy 70.198107 -159.373033) (xy 70.11513 -159.394919) (xy 70.030468 -159.408939)
			(xy 69.944866 -159.41497) (xy 69.859074 -159.412958) (xy 69.773848 -159.402922) (xy 69.689937 -159.384949)
			(xy 69.608077 -159.359197) (xy 69.528988 -159.325893) (xy 69.453366 -159.285329) (xy 69.381874 -159.237862)
			(xy 69.315141 -159.183909) (xy 69.253754 -159.123945) (xy 69.198251 -159.058495) (xy 69.149122 -158.988136)
			(xy 69.106796 -158.913485) (xy 69.071647 -158.835199) (xy 69.043984 -158.753965) (xy 69.024048 -158.670498)
			(xy 69.012017 -158.58553) (xy 69.007995 -158.49981) (xy 63.123572 -158.49981) (xy 63.123572 -160.542154)
			(xy 69.034402 -160.542154) (xy 69.034402 -160.457458) (xy 69.042453 -160.373144) (xy 69.058482 -160.289978)
			(xy 69.082343 -160.208711) (xy 69.113822 -160.130081) (xy 69.152633 -160.0548) (xy 69.198423 -159.983548)
			(xy 69.250779 -159.916972) (xy 69.309227 -159.855674) (xy 69.373237 -159.800209) (xy 69.442229 -159.75108)
			(xy 69.515579 -159.708731) (xy 69.592622 -159.673547) (xy 69.672661 -159.645845) (xy 69.75497 -159.625877)
			(xy 69.838805 -159.613824) (xy 69.923406 -159.609794) (xy 70.008007 -159.613824) (xy 70.091842 -159.625877)
			(xy 70.174151 -159.645845) (xy 70.25419 -159.673547) (xy 70.331233 -159.708731) (xy 70.404583 -159.75108)
			(xy 70.473575 -159.800209) (xy 70.537585 -159.855674) (xy 70.596033 -159.916972) (xy 70.648389 -159.983548)
			(xy 70.694179 -160.0548) (xy 70.73299 -160.130081) (xy 70.764469 -160.208711) (xy 70.78833 -160.289978)
			(xy 70.804359 -160.373144) (xy 70.81241 -160.457458) (xy 70.812914 -160.499806) (xy 70.81241 -160.542154)
			(xy 70.804359 -160.626468) (xy 70.78833 -160.709634) (xy 70.764469 -160.790901) (xy 70.73299 -160.869531)
			(xy 70.694179 -160.944812) (xy 70.648389 -161.016064) (xy 70.596033 -161.08264) (xy 70.537585 -161.143938)
			(xy 70.473575 -161.199403) (xy 70.404583 -161.248532) (xy 70.331233 -161.290881) (xy 70.25419 -161.326065)
			(xy 70.174151 -161.353767) (xy 70.091842 -161.373735) (xy 70.008007 -161.385788) (xy 69.923406 -161.389819)
			(xy 69.838805 -161.385788) (xy 69.75497 -161.373735) (xy 69.672661 -161.353767) (xy 69.592622 -161.326065)
			(xy 69.515579 -161.290881) (xy 69.442229 -161.248532) (xy 69.373237 -161.199403) (xy 69.309227 -161.143938)
			(xy 69.250779 -161.08264) (xy 69.198423 -161.016064) (xy 69.152633 -160.944812) (xy 69.113822 -160.869531)
			(xy 69.082343 -160.790901) (xy 69.058482 -160.709634) (xy 69.042453 -160.626468) (xy 69.034402 -160.542154)
			(xy 63.123572 -160.542154) (xy 63.123572 -160.549844) (xy 63.284608 -160.71088) (xy 68.462652 -160.71088)
			(xy 69.36486 -161.613088) (xy 70.50024 -161.613088)
		)
		(stroke
			(width 0)
			(type solid)
		)
		(fill yes)
		(layer "In4.Cu")
		(net "PVCCINFAON_CPU1")
	)
	(gr_poly
		(pts
			(arc
				(start 256.800096 -36.291012)
				(mid 258.932727 -35.407647)
				(end 259.816092 -33.275016)
			)
			(xy 259.817616 -32.284162) (xy 259.817616 -32.275018)
			(arc
				(start 259.817616 -13.780008)
				(mid 260.105375 -13.085295)
				(end 260.800088 -12.797536)
			)
			(arc
				(start 385.601972 -12.797536)
				(mid 387.735681 -11.913725)
				(end 388.619492 -9.780016)
			)
			(xy 388.619492 -3.928364)
			(arc
				(start 388.614158 -3.917442)
				(mid 388.329377 -3.590886)
				(end 388.226808 -3.16992)
			)
			(arc
				(start 388.226808 -3.16992)
				(mid 388.275543 -2.875216)
				(end 388.416546 -2.611882)
			)
			(arc
				(start 388.416546 -2.611882)
				(mid 388.501545 -2.513276)
				(end 388.59968 -2.427732)
			)
			(xy 388.619492 -2.388108) (xy 388.619492 -1.016) (xy 455.184256 -1.016) (xy 455.184256 -2.375154)
			(arc
				(start 455.205338 -2.416048)
				(mid 455.573689 -3.012402)
				(end 455.41184 -3.69443)
			)
			(arc
				(start 455.41184 -3.69443)
				(mid 455.315091 -3.810755)
				(end 455.200512 -3.909568)
			)
			(xy 455.184256 -3.941318)
			(arc
				(start 455.184256 -9.780016)
				(mid 456.068231 -11.91374)
				(end 458.20203 -12.797536)
			)
			(arc
				(start 469.799924 -12.797536)
				(mid 470.494637 -13.085295)
				(end 470.782396 -13.780008)
			)
			(xy 470.782396 -17.620234)
			(arc
				(start 470.808558 -17.664176)
				(mid 470.972568 -17.756784)
				(end 471.13317 -17.855184)
			)
			(arc
				(start 471.13317 -17.855184)
				(mid 471.158695 -17.863037)
				(end 471.184732 -17.856962)
			)
			(arc
				(start 471.262964 -17.814036)
				(mid 471.282207 -17.795414)
				(end 471.28938 -17.769586)
			)
			(arc
				(start 471.28938 -13.780008)
				(mid 470.853128 -12.726804)
				(end 469.799924 -12.290552)
			)
			(arc
				(start 458.20203 -12.290552)
				(mid 456.426813 -11.555233)
				(end 455.691494 -9.780016)
			)
			(xy 455.691494 -1.30556) (xy 455.69378 -1.30556)
			(arc
				(start 455.69378 -0.999998)
				(mid 455.549752 -0.652282)
				(end 455.202036 -0.508254)
			)
			(arc
				(start 388.601966 -0.508254)
				(mid 388.25425 -0.652282)
				(end 388.110222 -0.999998)
			)
			(xy 388.110222 -1.30556) (xy 388.112508 -1.30556)
			(arc
				(start 388.112508 -9.780016)
				(mid 387.377189 -11.555233)
				(end 385.601972 -12.290552)
			)
			(arc
				(start 260.800088 -12.290552)
				(mid 259.746884 -12.726804)
				(end 259.310632 -13.780008)
			)
			(xy 259.310632 -32.275018)
			(arc
				(start 259.308092 -33.275016)
				(mid 258.573517 -35.048437)
				(end 256.800096 -35.783012)
			)
			(arc
				(start 225.300032 -35.783012)
				(mid 223.526611 -35.048437)
				(end 222.792036 -33.275016)
			)
			(arc
				(start 222.792036 -33.275016)
				(mid 222.791401 -32.775015)
				(end 222.789496 -32.275018)
			)
			(xy 222.789496 -32.274764) (xy 222.792036 -32.267144) (xy 222.792036 -30.658308) (xy 222.789496 -30.658308)
			(arc
				(start 222.789496 -13.780008)
				(mid 222.353244 -12.726804)
				(end 221.30004 -12.290552)
			)
			(arc
				(start 196.701918 -12.290552)
				(mid 194.926701 -11.555233)
				(end 194.191382 -9.780016)
			)
			(xy 194.191382 -6.53796) (xy 194.193668 -6.53796)
			(arc
				(start 194.193668 -6.279896)
				(mid 194.04964 -5.93218)
				(end 193.701924 -5.788152)
			)
			(arc
				(start 127.102108 -5.788152)
				(mid 126.754392 -5.93218)
				(end 126.610364 -6.279896)
			)
			(xy 126.610364 -6.53796) (xy 126.61265 -6.53796)
			(arc
				(start 126.61265 -7.744206)
				(mid 126.627618 -7.779963)
				(end 126.66345 -7.794752)
			)
			(arc
				(start 126.687326 -7.78891)
				(mid 126.774244 -7.75555)
				(end 126.86665 -7.744206)
			)
			(arc
				(start 126.86665 -7.744206)
				(mid 126.931475 -7.749794)
				(end 126.994412 -7.766304)
			)
			(arc
				(start 126.994412 -7.766304)
				(mid 127.020815 -7.768359)
				(end 127.044704 -7.756906)
			)
			(arc
				(start 127.044704 -7.756906)
				(mid 127.071589 -7.734537)
				(end 127.099314 -7.713218)
			)
			(xy 127.119888 -7.672832) (xy 127.119888 -6.295898) (xy 193.684144 -6.295898) (xy 193.684144 -7.673086)
			(arc
				(start 193.704718 -7.713472)
				(mid 194.076604 -8.449818)
				(end 193.704718 -9.186164)
			)
			(xy 193.684144 -9.22655)
			(arc
				(start 193.684144 -9.780016)
				(mid 194.260293 -11.553469)
				(end 195.768722 -12.649708)
			)
			(xy 195.782692 -12.65174)
			(arc
				(start 220.45168 -12.65174)
				(mid 220.592749 -12.679912)
				(end 220.712284 -12.759944)
			)
			(arc
				(start 220.735398 -12.783058)
				(mid 220.749044 -12.792784)
				(end 220.765116 -12.797536)
			)
			(arc
				(start 221.30004 -12.797536)
				(mid 221.994753 -13.085295)
				(end 222.282512 -13.780008)
			)
			(arc
				(start 222.282512 -14.314932)
				(mid 222.287254 -14.331009)
				(end 222.29699 -14.34465)
			)
			(arc
				(start 222.312484 -14.360144)
				(mid 222.392512 -14.479681)
				(end 222.420688 -14.620748)
			)
			(xy 222.420688 -30.658308) (xy 222.409004 -30.658308)
			(arc
				(start 222.409004 -34.130742)
				(mid 223.495559 -35.691242)
				(end 225.300032 -36.291012)
			)
		)
		(stroke
			(width 0)
			(type solid)
		)
		(fill yes)
		(layer "In4.Cu")
		(net "GND")
	)
	(gr_poly
		(pts
			(xy 421.460676 -139.972288) (xy 421.813228 -139.619736) (xy 421.831325 -139.602484) (xy 421.872872 -139.574683)
			(xy 421.919043 -139.555517) (xy 421.968065 -139.545722) (xy 421.99306 -139.54506) (xy 423.555414 -139.54506)
			(xy 423.566939 -139.519939) (xy 423.596164 -139.473031) (xy 423.63185 -139.43083) (xy 423.673252 -139.394218)
			(xy 423.719502 -139.363962) (xy 423.769633 -139.340695) (xy 423.822597 -139.324904) (xy 423.877284 -139.316919)
			(xy 423.904918 -139.31646) (xy 423.932169 -139.316947) (xy 423.986117 -139.324705) (xy 424.038411 -139.340062)
			(xy 424.087988 -139.362703) (xy 424.133839 -139.39217) (xy 424.175029 -139.427861) (xy 424.210722 -139.46905)
			(xy 424.24019 -139.5149) (xy 424.262833 -139.564476) (xy 424.278192 -139.61677) (xy 424.285952 -139.670717)
			(xy 424.286426 -139.697968) (xy 424.285952 -139.724482) (xy 424.278572 -139.776993) (xy 424.26399 -139.827977)
			(xy 424.25366 -139.8524) (xy 424.248258 -139.865823) (xy 424.244411 -139.894488) (xy 424.248756 -139.923081)
			(xy 424.260945 -139.949308) (xy 424.28 -139.971065) (xy 424.304392 -139.986605) (xy 424.332163 -139.994681)
			(xy 424.346624 -139.995148) (xy 426.31868 -139.995148) (xy 426.43806 -139.875768) (xy 426.43806 -138.395964)
			(xy 423.848784 -138.395964) (xy 423.723308 -138.270742) (xy 423.723308 -134.558278) (xy 423.848784 -134.433056)
			(xy 426.43806 -134.433056) (xy 426.43806 -133.789674) (xy 426.437607 -133.775941) (xy 426.430281 -133.749468)
			(xy 426.416165 -133.725906) (xy 426.396281 -133.706957) (xy 426.372066 -133.693992) (xy 426.345272 -133.687948)
			(xy 426.317837 -133.689263) (xy 426.291744 -133.697841) (xy 426.280072 -133.705092) (xy 426.248695 -133.725528)
			(xy 426.182656 -133.760836) (xy 426.113473 -133.7895) (xy 426.041813 -133.811242) (xy 425.968367 -133.825855)
			(xy 425.893843 -133.833197) (xy 425.8564 -133.833616) (xy 425.817754 -133.833127) (xy 425.74086 -133.825307)
			(xy 425.665151 -133.809749) (xy 425.591404 -133.786611) (xy 425.520377 -133.75613) (xy 425.452797 -133.718621)
			(xy 425.389359 -133.674467) (xy 425.330714 -133.624121) (xy 425.277463 -133.568101) (xy 425.230153 -133.506981)
			(xy 425.189268 -133.441388) (xy 425.15523 -133.371996) (xy 425.128386 -133.299516) (xy 425.109013 -133.224692)
			(xy 425.097309 -133.148292) (xy 425.093394 -133.0711) (xy 425.097309 -132.993908) (xy 425.109013 -132.917508)
			(xy 425.128386 -132.842684) (xy 425.15523 -132.770204) (xy 425.189268 -132.700812) (xy 425.230153 -132.635219)
			(xy 425.277463 -132.574099) (xy 425.330714 -132.518079) (xy 425.389359 -132.467733) (xy 425.452797 -132.423579)
			(xy 425.520377 -132.38607) (xy 425.591404 -132.355589) (xy 425.665151 -132.332451) (xy 425.74086 -132.316893)
			(xy 425.817754 -132.309073) (xy 425.8564 -132.3086) (xy 425.893841 -132.309059) (xy 425.968363 -132.316399)
			(xy 426.041807 -132.331008) (xy 426.113465 -132.352745) (xy 426.182648 -132.381401) (xy 426.248689 -132.4167)
			(xy 426.280072 -132.437124) (xy 426.291752 -132.444379) (xy 426.317854 -132.452989) (xy 426.345307 -132.454326)
			(xy 426.372121 -132.448291) (xy 426.396355 -132.435323) (xy 426.416251 -132.416361) (xy 426.430369 -132.392778)
			(xy 426.437685 -132.366285) (xy 426.43806 -132.352542) (xy 426.43806 -131.232148) (xy 425.850558 -131.232148)
			(xy 425.843192 -131.234434) (xy 425.806749 -131.245189) (xy 425.732264 -131.26023) (xy 425.65665 -131.267776)
			(xy 425.618656 -131.268216) (xy 425.580663 -131.267744) (xy 425.505054 -131.260192) (xy 425.430568 -131.245168)
			(xy 425.39412 -131.234434) (xy 425.386754 -131.232148) (xy 423.764456 -131.232148) (xy 423.743513 -131.249829)
			(xy 423.69751 -131.279625) (xy 423.647715 -131.302527) (xy 423.595153 -131.318062) (xy 423.540909 -131.325911)
			(xy 423.486099 -131.325911) (xy 423.431855 -131.318062) (xy 423.379293 -131.302527) (xy 423.329498 -131.279625)
			(xy 423.283495 -131.249829) (xy 423.262552 -131.232148) (xy 422.748456 -131.232148) (xy 422.727513 -131.249829)
			(xy 422.68151 -131.279625) (xy 422.631715 -131.302527) (xy 422.579153 -131.318062) (xy 422.524909 -131.325911)
			(xy 422.470099 -131.325911) (xy 422.415855 -131.318062) (xy 422.363293 -131.302527) (xy 422.313498 -131.279625)
			(xy 422.267495 -131.249829) (xy 422.246552 -131.232148) (xy 421.9067 -131.232148) (xy 421.893425 -131.232538)
			(xy 421.867758 -131.239313) (xy 421.844708 -131.252483) (xy 421.825838 -131.271155) (xy 421.812426 -131.294065)
			(xy 421.805381 -131.31966) (xy 421.805179 -131.346206) (xy 421.808148 -131.359148) (xy 421.819426 -131.405834)
			(xy 421.83153 -131.501117) (xy 421.832278 -131.54914) (xy 421.831789 -131.587785) (xy 421.823969 -131.664679)
			(xy 421.808411 -131.740387) (xy 421.785273 -131.814133) (xy 421.754793 -131.88516) (xy 421.717284 -131.952738)
			(xy 421.67313 -132.016176) (xy 421.622785 -132.07482) (xy 421.566766 -132.128071) (xy 421.505647 -132.175381)
			(xy 421.440054 -132.216265) (xy 421.370663 -132.250303) (xy 421.298183 -132.277146) (xy 421.22336 -132.296519)
			(xy 421.146961 -132.308223) (xy 421.06977 -132.312138) (xy 420.992579 -132.308223) (xy 420.91618 -132.296519)
			(xy 420.841357 -132.277146) (xy 420.768877 -132.250303) (xy 420.699486 -132.216265) (xy 420.633893 -132.175381)
			(xy 420.572774 -132.128071) (xy 420.516755 -132.07482) (xy 420.46641 -132.016176) (xy 420.422256 -131.952738)
			(xy 420.384747 -131.88516) (xy 420.354267 -131.814133) (xy 420.331129 -131.740387) (xy 420.315571 -131.664679)
			(xy 420.307751 -131.587785) (xy 420.307262 -131.54914) (xy 420.308002 -131.501116) (xy 420.3201 -131.405832)
			(xy 420.331392 -131.359148) (xy 420.334726 -131.344017) (xy 420.333118 -131.313089) (xy 420.322324 -131.284062)
			(xy 420.303333 -131.259598) (xy 420.277889 -131.241943) (xy 420.248326 -131.232717) (xy 420.23284 -131.232148)
			(xy 419.20668 -131.232148) (xy 419.20668 -131.817872) (xy 419.207173 -131.831643) (xy 419.214607 -131.858165)
			(xy 419.22886 -131.881735) (xy 419.248895 -131.900637) (xy 419.273254 -131.913495) (xy 419.300164 -131.919373)
			(xy 419.327666 -131.917844) (xy 419.353758 -131.909019) (xy 419.36543 -131.901692) (xy 419.389302 -131.886107)
			(xy 419.440692 -131.861431) (xy 419.495181 -131.844672) (xy 419.551556 -131.836203) (xy 419.58006 -131.835652)
			(xy 419.607318 -131.836112) (xy 419.661279 -131.843865) (xy 419.713587 -131.85922) (xy 419.763177 -131.881862)
			(xy 419.80904 -131.911332) (xy 419.850242 -131.94703) (xy 419.885944 -131.988228) (xy 419.915419 -132.034088)
			(xy 419.938066 -132.083676) (xy 419.953426 -132.135982) (xy 419.961185 -132.189942) (xy 419.961185 -132.244458)
			(xy 419.953426 -132.298418) (xy 419.938066 -132.350724) (xy 419.915419 -132.400312) (xy 419.885944 -132.446172)
			(xy 419.850242 -132.48737) (xy 419.80904 -132.523068) (xy 419.763177 -132.552538) (xy 419.713587 -132.57518)
			(xy 419.661279 -132.590535) (xy 419.607318 -132.598288) (xy 419.58006 -132.598668) (xy 419.551556 -132.598137)
			(xy 419.495182 -132.589656) (xy 419.440695 -132.572888) (xy 419.389307 -132.548207) (xy 419.36543 -132.532628)
			(xy 419.353783 -132.525256) (xy 419.327687 -132.516418) (xy 419.300177 -132.514883) (xy 419.27326 -132.520764)
			(xy 419.248897 -132.533632) (xy 419.228866 -132.552549) (xy 419.214625 -132.576136) (xy 419.207214 -132.602673)
			(xy 419.20668 -132.616448) (xy 419.20668 -132.7658) (xy 419.207181 -132.780672) (xy 419.215725 -132.809161)
			(xy 419.232119 -132.833979) (xy 419.254969 -132.853018) (xy 419.282337 -132.864663) (xy 419.311901 -132.867926)
			(xy 419.34115 -132.86253) (xy 419.367603 -132.848933) (xy 419.378638 -132.838952) (xy 419.400103 -132.819114)
			(xy 419.44794 -132.785532) (xy 419.500335 -132.759633) (xy 419.556065 -132.742021) (xy 419.613829 -132.733107)
			(xy 419.643052 -132.732526) (xy 419.670306 -132.732986) (xy 419.724261 -132.740738) (xy 419.776562 -132.75609)
			(xy 419.826146 -132.77873) (xy 419.872003 -132.808197) (xy 419.913199 -132.843892) (xy 419.948894 -132.885086)
			(xy 419.978363 -132.930942) (xy 420.001005 -132.980525) (xy 420.016359 -133.032826) (xy 420.024113 -133.08678)
			(xy 420.02456 -133.114034) (xy 420.024051 -133.14223) (xy 420.015748 -133.198006) (xy 419.999329 -133.251954)
			(xy 419.97515 -133.302899) (xy 419.943739 -133.349731) (xy 419.905778 -133.391432) (xy 419.862094 -133.427093)
			(xy 419.838124 -133.441948) (xy 419.825563 -133.450025) (xy 419.805416 -133.472048) (xy 419.7925 -133.498958)
			(xy 419.78792 -133.528454) (xy 419.792068 -133.558013) (xy 419.804589 -133.585109) (xy 419.824412 -133.607424)
			(xy 419.836854 -133.615684) (xy 419.860225 -133.630691) (xy 419.902769 -133.666397) (xy 419.939692 -133.707888)
			(xy 419.970215 -133.75429) (xy 419.993695 -133.804624) (xy 420.009636 -133.857828) (xy 420.017703 -133.91278)
			(xy 420.01821 -133.94055) (xy 420.017739 -133.967545) (xy 420.010124 -134.020997) (xy 419.995053 -134.072842)
			(xy 419.972827 -134.122046) (xy 419.94389 -134.167627) (xy 419.908818 -134.208675) (xy 419.868311 -134.244372)
			(xy 419.845998 -134.259574) (xy 419.834682 -134.267499) (xy 419.81644 -134.288229) (xy 419.80443 -134.313094)
			(xy 419.799532 -134.340271) (xy 419.802106 -134.367764) (xy 419.811964 -134.393559) (xy 419.828381 -134.415762)
			(xy 419.850154 -134.432746) (xy 419.862762 -134.43839) (xy 419.900235 -134.454539) (xy 419.971816 -134.493723)
			(xy 420.038803 -134.540325) (xy 420.100431 -134.593814) (xy 420.155995 -134.653577) (xy 420.204861 -134.718931)
			(xy 420.24647 -134.78913) (xy 420.280345 -134.863369) (xy 420.306099 -134.940802) (xy 420.323438 -135.020541)
			(xy 420.332165 -135.101677) (xy 420.332546 -135.132976) (xy 420.938775 -135.132976) (xy 420.944107 -135.055023)
			(xy 420.957383 -134.978024) (xy 420.978463 -134.902787) (xy 421.007128 -134.8301) (xy 421.043075 -134.760725)
			(xy 421.085929 -134.69539) (xy 421.135239 -134.63478) (xy 421.190489 -134.579531) (xy 421.2511 -134.530221)
			(xy 421.316435 -134.487369) (xy 421.38581 -134.451423) (xy 421.458498 -134.42276) (xy 421.533736 -134.40168)
			(xy 421.610735 -134.388406) (xy 421.688688 -134.383075) (xy 421.766777 -134.385744) (xy 421.844184 -134.396385)
			(xy 421.920097 -134.414887) (xy 421.99372 -134.441054) (xy 422.06428 -134.474614) (xy 422.131039 -134.515213)
			(xy 422.193296 -134.562427) (xy 422.250398 -134.61576) (xy 422.301747 -134.674653) (xy 422.346804 -134.738489)
			(xy 422.385096 -134.806597) (xy 422.416222 -134.878265) (xy 422.439856 -134.95274) (xy 422.45575 -135.029241)
			(xy 422.463737 -135.106967) (xy 422.46423 -135.146034) (xy 422.463737 -135.185672) (xy 422.455523 -135.264521)
			(xy 422.439177 -135.342094) (xy 422.414875 -135.417553) (xy 422.382879 -135.490085) (xy 422.363646 -135.524748)
			(xy 422.384176 -135.542961) (xy 422.420307 -135.584269) (xy 422.45015 -135.630325) (xy 422.47309 -135.680181)
			(xy 422.488652 -135.732808) (xy 422.496517 -135.787122) (xy 422.496996 -135.814562) (xy 422.496421 -135.844475)
			(xy 422.487063 -135.903565) (xy 422.468587 -135.960466) (xy 422.441447 -136.013782) (xy 422.424352 -136.038336)
			(xy 422.417 -136.049244) (xy 422.407492 -136.073757) (xy 422.404562 -136.099886) (xy 422.408405 -136.125896)
			(xy 422.418765 -136.150062) (xy 422.434956 -136.170778) (xy 422.44518 -136.179052) (xy 422.468223 -136.197173)
			(xy 422.508955 -136.239328) (xy 422.542755 -136.287221) (xy 422.568827 -136.339723) (xy 422.586555 -136.395597)
			(xy 422.595522 -136.453526) (xy 422.596056 -136.482836) (xy 422.59557 -136.510087) (xy 422.587814 -136.564035)
			(xy 422.572459 -136.61633) (xy 422.549817 -136.665907) (xy 422.520351 -136.711757) (xy 422.48466 -136.752948)
			(xy 422.443469 -136.788639) (xy 422.397619 -136.818105) (xy 422.348042 -136.840747) (xy 422.295747 -136.856102)
			(xy 422.241799 -136.863858) (xy 422.187297 -136.863858) (xy 422.133349 -136.856102) (xy 422.081054 -136.840747)
			(xy 422.031477 -136.818105) (xy 421.985627 -136.788639) (xy 421.944436 -136.752948) (xy 421.908745 -136.711757)
			(xy 421.879279 -136.665907) (xy 421.856637 -136.61633) (xy 421.841282 -136.564035) (xy 421.833526 -136.510087)
			(xy 421.83304 -136.482836) (xy 421.833608 -136.452923) (xy 421.842966 -136.393832) (xy 421.861444 -136.33693)
			(xy 421.888587 -136.283615) (xy 421.905684 -136.259062) (xy 421.913053 -136.248163) (xy 421.922569 -136.223647)
			(xy 421.925501 -136.197514) (xy 421.921655 -136.171499) (xy 421.911287 -136.147331) (xy 421.895086 -136.126617)
			(xy 421.884856 -136.118346) (xy 421.86456 -136.102419) (xy 421.828046 -136.065973) (xy 421.79677 -136.024942)
			(xy 421.771304 -135.980074) (xy 421.752109 -135.932186) (xy 421.74541 -135.907272) (xy 421.701722 -135.908542)
			(xy 421.662655 -135.908036) (xy 421.584929 -135.900048) (xy 421.508428 -135.884153) (xy 421.433954 -135.860518)
			(xy 421.362287 -135.82939) (xy 421.294179 -135.791097) (xy 421.230344 -135.746039) (xy 421.171452 -135.69469)
			(xy 421.11812 -135.637587) (xy 421.070907 -135.575329) (xy 421.030308 -135.50857) (xy 420.99675 -135.438009)
			(xy 420.970583 -135.364385) (xy 420.952083 -135.288472) (xy 420.941443 -135.211065) (xy 420.938775 -135.132976)
			(xy 420.332546 -135.132976) (xy 420.332662 -135.142478) (xy 420.332135 -135.182853) (xy 420.323605 -135.263151)
			(xy 420.306637 -135.342097) (xy 420.281422 -135.418809) (xy 420.248243 -135.492427) (xy 420.207469 -135.562127)
			(xy 420.159559 -135.627128) (xy 420.105049 -135.686702) (xy 420.044549 -135.740183) (xy 419.978736 -135.786971)
			(xy 419.943788 -135.807196) (xy 419.931846 -135.814392) (xy 419.912132 -135.834094) (xy 419.898479 -135.858392)
			(xy 419.891904 -135.885477) (xy 419.892896 -135.91333) (xy 419.901383 -135.939878) (xy 419.908736 -135.951722)
			(xy 419.923681 -135.975239) (xy 419.947324 -136.025692) (xy 419.96337 -136.07905) (xy 419.971477 -136.134175)
			(xy 419.971982 -136.162034) (xy 419.971493 -136.189283) (xy 419.963733 -136.243226) (xy 419.948374 -136.295515)
			(xy 419.925731 -136.345086) (xy 419.896264 -136.39093) (xy 419.860572 -136.432114) (xy 419.819382 -136.4678)
			(xy 419.773533 -136.49726) (xy 419.723958 -136.519895) (xy 419.671667 -136.535246) (xy 419.617723 -136.542998)
			(xy 419.590474 -136.543542) (xy 419.560717 -136.542981) (xy 419.501923 -136.533748) (xy 419.445282 -136.515479)
			(xy 419.392173 -136.48862) (xy 419.367716 -136.47166) (xy 419.35612 -136.463843) (xy 419.32986 -136.454259)
			(xy 419.301984 -136.452153) (xy 419.274582 -136.457683) (xy 419.249705 -136.470436) (xy 419.229217 -136.489455)
			(xy 419.214653 -136.513316) (xy 419.207103 -136.540232) (xy 419.20668 -136.55421) (xy 419.20668 -136.785858)
			(xy 419.207124 -136.799827) (xy 419.214702 -136.826719) (xy 419.229277 -136.850555) (xy 419.249761 -136.869556)
			(xy 419.274623 -136.882303) (xy 419.302007 -136.887843) (xy 419.329869 -136.885764) (xy 419.356127 -136.87622)
			(xy 419.367716 -136.868408) (xy 419.392205 -136.851505) (xy 419.44532 -136.824685) (xy 419.501949 -136.806419)
			(xy 419.560724 -136.797149) (xy 419.590474 -136.796526) (xy 419.617726 -136.796987) (xy 419.671675 -136.804741)
			(xy 419.723971 -136.820093) (xy 419.77355 -136.842732) (xy 419.819402 -136.872197) (xy 419.860594 -136.907887)
			(xy 419.896288 -136.949077) (xy 419.925755 -136.994927) (xy 419.948398 -137.044505) (xy 419.963754 -137.0968)
			(xy 419.971511 -137.150748) (xy 419.971511 -137.205252) (xy 419.963754 -137.2592) (xy 419.948398 -137.311495)
			(xy 419.925755 -137.361073) (xy 419.896288 -137.406923) (xy 419.860594 -137.448113) (xy 419.819402 -137.483803)
			(xy 419.77355 -137.513268) (xy 419.723971 -137.535907) (xy 419.671675 -137.551259) (xy 419.617726 -137.559013)
			(xy 419.590474 -137.559542) (xy 419.560717 -137.558981) (xy 419.501923 -137.549748) (xy 419.445282 -137.531479)
			(xy 419.392173 -137.50462) (xy 419.367716 -137.48766) (xy 419.35612 -137.479843) (xy 419.32986 -137.470259)
			(xy 419.301984 -137.468153) (xy 419.274582 -137.473683) (xy 419.249705 -137.486436) (xy 419.229217 -137.505455)
			(xy 419.214653 -137.529316) (xy 419.207103 -137.556232) (xy 419.20668 -137.57021) (xy 419.20668 -137.714482)
			(xy 419.206987 -137.724388) (xy 420.811452 -137.724388) (xy 420.811941 -137.685743) (xy 420.819761 -137.608849)
			(xy 420.835319 -137.533141) (xy 420.858457 -137.459395) (xy 420.888937 -137.388368) (xy 420.926446 -137.32079)
			(xy 420.9706 -137.257352) (xy 421.020945 -137.198708) (xy 421.076964 -137.145457) (xy 421.138083 -137.098147)
			(xy 421.203676 -137.057263) (xy 421.273067 -137.023225) (xy 421.345547 -136.996382) (xy 421.42037 -136.977009)
			(xy 421.496769 -136.965305) (xy 421.57396 -136.96139) (xy 421.651151 -136.965305) (xy 421.72755 -136.977009)
			(xy 421.802373 -136.996382) (xy 421.874853 -137.023225) (xy 421.944244 -137.057263) (xy 422.009837 -137.098147)
			(xy 422.070956 -137.145457) (xy 422.126975 -137.198708) (xy 422.17732 -137.257352) (xy 422.221474 -137.32079)
			(xy 422.258983 -137.388368) (xy 422.289463 -137.459395) (xy 422.312601 -137.533141) (xy 422.328159 -137.608849)
			(xy 422.335979 -137.685743) (xy 422.336468 -137.724388) (xy 422.335878 -137.765404) (xy 422.327083 -137.846964)
			(xy 422.309582 -137.927108) (xy 422.283578 -138.004911) (xy 422.249372 -138.079471) (xy 422.207358 -138.149928)
			(xy 422.158023 -138.215467) (xy 422.101936 -138.275331) (xy 422.039747 -138.328827) (xy 422.006268 -138.35253)
			(xy 421.993945 -138.361614) (xy 421.974992 -138.385642) (xy 421.964005 -138.414205) (xy 421.961967 -138.44474)
			(xy 421.969062 -138.474509) (xy 421.984653 -138.500842) (xy 422.007343 -138.521379) (xy 422.021 -138.528298)
			(xy 422.045347 -138.540166) (xy 422.090718 -138.569745) (xy 422.13145 -138.605444) (xy 422.166725 -138.646543)
			(xy 422.195834 -138.692217) (xy 422.218192 -138.741549) (xy 422.233349 -138.793547) (xy 422.241002 -138.847165)
			(xy 422.241472 -138.874246) (xy 422.240986 -138.901497) (xy 422.23323 -138.955445) (xy 422.217875 -139.00774)
			(xy 422.195233 -139.057317) (xy 422.165767 -139.103167) (xy 422.130076 -139.144358) (xy 422.088885 -139.180049)
			(xy 422.043035 -139.209515) (xy 421.993458 -139.232157) (xy 421.941163 -139.247512) (xy 421.887215 -139.255268)
			(xy 421.832713 -139.255268) (xy 421.778765 -139.247512) (xy 421.72647 -139.232157) (xy 421.676893 -139.209515)
			(xy 421.631043 -139.180049) (xy 421.589852 -139.144358) (xy 421.554161 -139.103167) (xy 421.524695 -139.057317)
			(xy 421.502053 -139.00774) (xy 421.486698 -138.955445) (xy 421.478942 -138.901497) (xy 421.478456 -138.874246)
			(xy 421.479062 -138.843349) (xy 421.489016 -138.782362) (xy 421.50867 -138.723777) (xy 421.537512 -138.669126)
			(xy 421.555672 -138.644122) (xy 421.564435 -138.631571) (xy 421.574835 -138.602798) (xy 421.576261 -138.572237)
			(xy 421.568588 -138.542621) (xy 421.552501 -138.516597) (xy 421.529438 -138.496494) (xy 421.501463 -138.484109)
			(xy 421.48633 -138.481816) (xy 421.447004 -138.476744) (xy 421.369602 -138.45951) (xy 421.294407 -138.434335)
			(xy 421.222231 -138.401492) (xy 421.153854 -138.361335) (xy 421.090014 -138.314297) (xy 421.031401 -138.260888)
			(xy 420.978648 -138.201683) (xy 420.932325 -138.137323) (xy 420.892932 -138.068503) (xy 420.860894 -137.995966)
			(xy 420.836559 -137.920495) (xy 420.820188 -137.842906) (xy 420.811959 -137.764037) (xy 420.811452 -137.724388)
			(xy 419.206987 -137.724388) (xy 419.207115 -137.728531) (xy 419.214754 -137.755571) (xy 419.229485 -137.779498)
			(xy 419.250188 -137.798495) (xy 419.275291 -137.811118) (xy 419.302886 -137.816408) (xy 419.316916 -137.815574)
			(xy 419.333267 -137.814256) (xy 419.366044 -137.812858) (xy 419.382448 -137.81278) (xy 419.421092 -137.813272)
			(xy 419.497984 -137.821095) (xy 419.573689 -137.836658) (xy 419.647432 -137.859799) (xy 419.718456 -137.890281)
			(xy 419.786031 -137.927792) (xy 419.849465 -137.971947) (xy 419.908107 -138.022293) (xy 419.961354 -138.078313)
			(xy 420.008661 -138.139432) (xy 420.049543 -138.205023) (xy 420.083579 -138.274414) (xy 420.110421 -138.346892)
			(xy 420.129792 -138.421713) (xy 420.141496 -138.498111) (xy 420.14541 -138.5753) (xy 420.141496 -138.652489)
			(xy 420.129792 -138.728887) (xy 420.110421 -138.803708) (xy 420.083579 -138.876186) (xy 420.049543 -138.945577)
			(xy 420.008661 -139.011168) (xy 419.961354 -139.072287) (xy 419.908107 -139.128307) (xy 419.849465 -139.178653)
			(xy 419.786031 -139.222808) (xy 419.718456 -139.260319) (xy 419.647432 -139.290801) (xy 419.573689 -139.313942)
			(xy 419.497984 -139.329505) (xy 419.421092 -139.337328) (xy 419.382448 -139.337796) (xy 419.366044 -139.337712)
			(xy 419.333267 -139.336313) (xy 419.316916 -139.335002) (xy 419.302901 -139.33427) (xy 419.275359 -139.339612)
			(xy 419.250308 -139.352243) (xy 419.229637 -139.371211) (xy 419.214903 -139.395086) (xy 419.207218 -139.422068)
			(xy 419.20668 -139.436094) (xy 419.20668 -139.995148) (xy 421.440356 -139.995148)
		)
		(stroke
			(width 0)
			(type solid)
		)
		(fill yes)
		(layer "In4.Cu")
		(net "PVCCINFAON_CPU0_VREF")
	)
	(gr_poly
		(pts
			(arc
				(start 189.85992 -401.03044)
				(mid 189.959323 -401.056418)
				(end 190.030608 -400.982434)
			)
			(arc
				(start 190.030608 -400.982434)
				(mid 190.12392 -400.810128)
				(end 190.29045 -400.706844)
			)
			(xy 190.302642 -400.703034)
			(arc
				(start 191.013588 -399.992342)
				(mid 191.120801 -399.920704)
				(end 191.247268 -399.895568)
			)
			(xy 194.41922 -399.895568) (xy 194.441318 -399.896076) (xy 194.464432 -399.8976) (xy 194.516502 -399.84553)
			(arc
				(start 194.475608 -399.804382)
				(mid 194.403887 -399.697184)
				(end 194.37858 -399.570702)
			)
			(xy 194.37858 -392.529568) (xy 193.594482 -391.745216) (xy 183.799734 -391.745216) (xy 183.429148 -392.116056)
			(arc
				(start 183.429148 -396.230094)
				(mid 183.480066 -396.31815)
				(end 183.581802 -396.317978)
			)
			(arc
				(start 183.581802 -396.317978)
				(mid 183.674486 -396.279202)
				(end 183.77408 -396.265908)
			)
			(arc
				(start 183.77408 -396.265908)
				(mid 184.155588 -396.647416)
				(end 183.77408 -397.028924)
			)
			(arc
				(start 183.77408 -397.028924)
				(mid 183.634632 -397.002425)
				(end 183.514492 -396.926816)
			)
			(arc
				(start 183.514492 -396.926816)
				(mid 183.459573 -396.917546)
				(end 183.429148 -396.964154)
			)
			(xy 183.429148 -397.055594)
			(arc
				(start 183.80202 -397.42872)
				(mid 183.84418 -397.480267)
				(end 183.875172 -397.53921)
			)
			(arc
				(start 183.875172 -397.53921)
				(mid 183.922308 -397.591332)
				(end 183.992012 -397.600424)
			)
			(arc
				(start 183.992012 -397.600424)
				(mid 184.034159 -397.593209)
				(end 184.076848 -397.590772)
			)
			(arc
				(start 184.076848 -397.590772)
				(mid 184.458356 -397.97228)
				(end 184.076848 -398.353788)
			)
			(arc
				(start 184.076848 -398.353788)
				(mid 184.046653 -398.352571)
				(end 184.01665 -398.348962)
			)
			(arc
				(start 184.01665 -398.348962)
				(mid 183.934707 -398.372001)
				(end 183.899048 -398.449292)
			)
			(arc
				(start 183.899048 -398.54632)
				(mid 183.873791 -398.672823)
				(end 183.80202 -398.78)
			)
			(xy 183.429148 -399.153126)
			(arc
				(start 183.429148 -399.49501)
				(mid 183.493116 -399.589384)
				(end 183.604408 -399.56486)
			)
			(arc
				(start 183.604408 -399.56486)
				(mid 183.730566 -399.476772)
				(end 183.881268 -399.445734)
			)
			(arc
				(start 183.881268 -399.445734)
				(mid 184.151035 -399.557475)
				(end 184.262776 -399.827242)
			)
			(arc
				(start 184.262776 -399.827242)
				(mid 184.23146 -399.978616)
				(end 184.142634 -400.105118)
			)
			(arc
				(start 184.142634 -400.105118)
				(mid 184.117861 -400.216468)
				(end 184.21223 -400.280632)
			)
			(arc
				(start 184.75833 -400.280632)
				(mid 184.847858 -400.227066)
				(end 184.842912 -400.122898)
			)
			(arc
				(start 184.842912 -400.122898)
				(mid 184.795065 -400.021747)
				(end 184.77865 -399.911062)
			)
			(arc
				(start 184.77865 -399.911062)
				(mid 185.160158 -399.529554)
				(end 185.541666 -399.911062)
			)
			(arc
				(start 185.541666 -399.911062)
				(mid 185.525246 -400.021746)
				(end 185.477404 -400.122898)
			)
			(arc
				(start 185.477404 -400.122898)
				(mid 185.472533 -400.227025)
				(end 185.561986 -400.280632)
			)
			(arc
				(start 185.88609 -400.280632)
				(mid 185.977127 -400.223626)
				(end 185.9661 -400.116802)
			)
			(arc
				(start 185.9661 -400.116802)
				(mid 185.906456 -400.006395)
				(end 185.885836 -399.882614)
			)
			(arc
				(start 185.885836 -399.882614)
				(mid 185.924571 -399.715118)
				(end 186.032902 -399.581624)
			)
			(arc
				(start 186.032902 -399.581624)
				(mid 186.071936 -399.501614)
				(end 186.032902 -399.421604)
			)
			(arc
				(start 186.032902 -399.421604)
				(mid 185.885823 -399.120614)
				(end 186.032902 -398.819624)
			)
			(arc
				(start 186.032902 -398.819624)
				(mid 186.071936 -398.739614)
				(end 186.032902 -398.659604)
			)
			(arc
				(start 186.032902 -398.659604)
				(mid 185.885823 -398.358614)
				(end 186.032902 -398.057624)
			)
			(arc
				(start 186.032902 -398.057624)
				(mid 186.071936 -397.977614)
				(end 186.032902 -397.897604)
			)
			(arc
				(start 186.032902 -397.897604)
				(mid 185.885823 -397.596614)
				(end 186.032902 -397.295624)
			)
			(arc
				(start 186.032902 -397.295624)
				(mid 186.071936 -397.215614)
				(end 186.032902 -397.135604)
			)
			(arc
				(start 186.032902 -397.135604)
				(mid 185.997568 -397.10439)
				(end 185.966354 -397.069056)
			)
			(arc
				(start 185.966354 -397.069056)
				(mid 185.886344 -397.030022)
				(end 185.806334 -397.069056)
			)
			(arc
				(start 185.806334 -397.069056)
				(mid 185.672846 -397.177399)
				(end 185.505344 -397.216122)
			)
			(arc
				(start 185.505344 -397.216122)
				(mid 185.235577 -397.104381)
				(end 185.123836 -396.834614)
			)
			(arc
				(start 185.123836 -396.834614)
				(mid 185.162571 -396.667118)
				(end 185.270902 -396.533624)
			)
			(arc
				(start 185.270902 -396.533624)
				(mid 185.309936 -396.453614)
				(end 185.270902 -396.373604)
			)
			(arc
				(start 185.270902 -396.373604)
				(mid 185.162559 -396.240116)
				(end 185.123836 -396.072614)
			)
			(arc
				(start 185.123836 -396.072614)
				(mid 185.235577 -395.802847)
				(end 185.505344 -395.691106)
			)
			(arc
				(start 185.505344 -395.691106)
				(mid 185.67284 -395.729841)
				(end 185.806334 -395.838172)
			)
			(arc
				(start 185.806334 -395.838172)
				(mid 185.886344 -395.877206)
				(end 185.966354 -395.838172)
			)
			(arc
				(start 185.966354 -395.838172)
				(mid 186.267344 -395.691093)
				(end 186.568334 -395.838172)
			)
			(arc
				(start 186.568334 -395.838172)
				(mid 186.648344 -395.877206)
				(end 186.728354 -395.838172)
			)
			(arc
				(start 186.728354 -395.838172)
				(mid 187.029344 -395.691093)
				(end 187.330334 -395.838172)
			)
			(arc
				(start 187.330334 -395.838172)
				(mid 187.410344 -395.877206)
				(end 187.490354 -395.838172)
			)
			(arc
				(start 187.490354 -395.838172)
				(mid 187.791344 -395.691093)
				(end 188.092334 -395.838172)
			)
			(arc
				(start 188.092334 -395.838172)
				(mid 188.172344 -395.877206)
				(end 188.252354 -395.838172)
			)
			(arc
				(start 188.252354 -395.838172)
				(mid 188.553344 -395.691093)
				(end 188.854334 -395.838172)
			)
			(arc
				(start 188.854334 -395.838172)
				(mid 188.934344 -395.877206)
				(end 189.014354 -395.838172)
			)
			(arc
				(start 189.014354 -395.838172)
				(mid 189.315344 -395.691093)
				(end 189.616334 -395.838172)
			)
			(arc
				(start 189.616334 -395.838172)
				(mid 189.696344 -395.877206)
				(end 189.776354 -395.838172)
			)
			(arc
				(start 189.776354 -395.838172)
				(mid 190.077344 -395.691093)
				(end 190.378334 -395.838172)
			)
			(arc
				(start 190.378334 -395.838172)
				(mid 190.458344 -395.877206)
				(end 190.538354 -395.838172)
			)
			(arc
				(start 190.538354 -395.838172)
				(mid 190.671842 -395.729829)
				(end 190.839344 -395.691106)
			)
			(arc
				(start 190.839344 -395.691106)
				(mid 191.109111 -395.802847)
				(end 191.220852 -396.072614)
			)
			(arc
				(start 191.220852 -396.072614)
				(mid 191.182117 -396.24011)
				(end 191.073786 -396.373604)
			)
			(arc
				(start 191.073786 -396.373604)
				(mid 191.034752 -396.453614)
				(end 191.073786 -396.533624)
			)
			(arc
				(start 191.073786 -396.533624)
				(mid 191.220865 -396.834614)
				(end 191.073786 -397.135604)
			)
			(arc
				(start 191.073786 -397.135604)
				(mid 191.034752 -397.215614)
				(end 191.073786 -397.295624)
			)
			(arc
				(start 191.073786 -397.295624)
				(mid 191.220865 -397.596614)
				(end 191.073786 -397.897604)
			)
			(arc
				(start 191.073786 -397.897604)
				(mid 191.034752 -397.977614)
				(end 191.073786 -398.057624)
			)
			(arc
				(start 191.073786 -398.057624)
				(mid 191.182129 -398.191112)
				(end 191.220852 -398.358614)
			)
			(arc
				(start 191.220852 -398.358614)
				(mid 191.109111 -398.628381)
				(end 190.839344 -398.740122)
			)
			(arc
				(start 190.839344 -398.740122)
				(mid 190.671848 -398.701387)
				(end 190.538354 -398.593056)
			)
			(arc
				(start 190.538354 -398.593056)
				(mid 190.458344 -398.554022)
				(end 190.378334 -398.593056)
			)
			(arc
				(start 190.378334 -398.593056)
				(mid 190.34712 -398.62839)
				(end 190.311786 -398.659604)
			)
			(arc
				(start 190.311786 -398.659604)
				(mid 190.272752 -398.739614)
				(end 190.311786 -398.819624)
			)
			(arc
				(start 190.311786 -398.819624)
				(mid 190.458865 -399.120614)
				(end 190.311786 -399.421604)
			)
			(arc
				(start 190.311786 -399.421604)
				(mid 190.272752 -399.501614)
				(end 190.311786 -399.581624)
			)
			(arc
				(start 190.311786 -399.581624)
				(mid 190.420129 -399.715112)
				(end 190.458852 -399.882614)
			)
			(arc
				(start 190.458852 -399.882614)
				(mid 190.347111 -400.152381)
				(end 190.077344 -400.264122)
			)
			(arc
				(start 190.077344 -400.264122)
				(mid 189.909848 -400.225387)
				(end 189.776354 -400.117056)
			)
			(arc
				(start 189.776354 -400.117056)
				(mid 189.696344 -400.078022)
				(end 189.616334 -400.117056)
			)
			(arc
				(start 189.616334 -400.117056)
				(mid 189.482846 -400.225399)
				(end 189.315344 -400.264122)
			)
			(arc
				(start 189.315344 -400.264122)
				(mid 189.258191 -400.259855)
				(end 189.202314 -400.247104)
			)
			(arc
				(start 189.202314 -400.247104)
				(mid 189.141608 -400.27353)
				(end 189.158626 -400.337528)
			)
			(arc
				(start 189.158626 -400.337528)
				(mid 189.183842 -400.356435)
				(end 189.20714 -400.37766)
			)
		)
		(stroke
			(width 0)
			(type solid)
		)
		(fill yes)
		(layer "In4.Cu")
		(net "AGND_HSC")
	)
	(gr_poly
		(pts
			(arc
				(start 194.443604 -441.479432)
				(mid 194.479525 -441.464553)
				(end 194.494404 -441.428632)
			)
			(arc
				(start 194.494404 -441.17006)
				(mid 194.790421 -440.455411)
				(end 195.50507 -440.159394)
			)
			(arc
				(start 276.314916 -440.159394)
				(mid 277.029565 -440.455411)
				(end 277.325582 -441.17006)
			)
			(arc
				(start 277.325582 -441.428632)
				(mid 277.340461 -441.464553)
				(end 277.376382 -441.479432)
			)
			(arc
				(start 463.300064 -441.479432)
				(mid 464.353268 -441.04318)
				(end 464.78952 -439.989976)
			)
			(arc
				(start 464.78952 -409.528264)
				(mid 464.980687 -408.567674)
				(end 465.52485 -407.753312)
			)
			(arc
				(start 467.353396 -405.924766)
				(mid 467.676179 -405.441593)
				(end 467.789514 -404.871682)
			)
			(arc
				(start 467.789514 -82.82813)
				(mid 467.980666 -81.867526)
				(end 468.524844 -81.053178)
			)
			(arc
				(start 470.853262 -78.72476)
				(mid 471.176045 -78.241587)
				(end 471.28938 -77.671676)
			)
			(arc
				(start 471.28938 -26.830274)
				(mid 471.282198 -26.804487)
				(end 471.262964 -26.785824)
			)
			(xy 471.17254 -26.736294) (xy 471.145108 -26.73731)
			(arc
				(start 471.13317 -26.744676)
				(mid 470.972569 -26.843078)
				(end 470.808558 -26.935684)
			)
			(arc
				(start 470.808558 -26.935684)
				(mid 470.789062 -26.95436)
				(end 470.781888 -26.980388)
			)
			(arc
				(start 470.781888 -77.672184)
				(mid 470.707176 -78.047677)
				(end 470.494614 -78.366112)
			)
			(arc
				(start 468.166196 -80.69453)
				(mid 467.512084 -81.673433)
				(end 467.282276 -82.82813)
			)
			(xy 467.282276 -115.104926) (xy 467.284816 -115.116356)
			(arc
				(start 467.287864 -115.121944)
				(mid 467.319142 -115.206449)
				(end 467.329774 -115.295934)
			)
			(arc
				(start 467.329774 -115.295934)
				(mid 467.31919 -115.38543)
				(end 467.287864 -115.469924)
			)
			(xy 467.284816 -115.475512) (xy 467.282276 -115.486942) (xy 467.282276 -333.927958) (xy 467.282276 -333.928466)
			(arc
				(start 467.282276 -358.935274)
				(mid 467.282971 -358.943649)
				(end 467.28507 -358.951784)
			)
			(arc
				(start 467.28507 -358.951784)
				(mid 467.514143 -359.844958)
				(end 467.59114 -360.76382)
			)
			(arc
				(start 467.59114 -360.76382)
				(mid 467.514149 -361.682683)
				(end 467.28507 -362.575856)
			)
			(arc
				(start 467.28507 -362.575856)
				(mid 467.283005 -362.583996)
				(end 467.282276 -362.592366)
			)
			(arc
				(start 467.282276 -404.871936)
				(mid 467.207495 -405.247595)
				(end 466.994748 -405.566118)
			)
			(arc
				(start 465.166202 -407.394664)
				(mid 464.512036 -408.373553)
				(end 464.282282 -409.528264)
			)
			(xy 464.282028 -409.528264)
			(arc
				(start 464.282028 -439.989976)
				(mid 463.994417 -440.684329)
				(end 463.300064 -440.97194)
			)
			(xy 410.917898 -440.97194)
			(arc
				(start 410.910024 -440.974734)
				(mid 410.831038 -440.993945)
				(end 410.750004 -441.000388)
			)
			(arc
				(start 410.750004 -441.000388)
				(mid 410.668968 -440.993957)
				(end 410.589984 -440.974734)
			)
			(xy 410.58211 -440.97194) (xy 406.917906 -440.97194)
			(arc
				(start 406.910032 -440.974734)
				(mid 406.831046 -440.993945)
				(end 406.750012 -441.000388)
			)
			(arc
				(start 406.750012 -441.000388)
				(mid 406.668976 -440.993957)
				(end 406.589992 -440.974734)
			)
			(xy 406.582118 -440.97194) (xy 402.917914 -440.97194)
			(arc
				(start 402.91004 -440.974734)
				(mid 402.831054 -440.993945)
				(end 402.75002 -441.000388)
			)
			(arc
				(start 402.75002 -441.000388)
				(mid 402.668984 -440.993957)
				(end 402.59 -440.974734)
			)
			(xy 402.582126 -440.97194) (xy 398.917922 -440.97194)
			(arc
				(start 398.910048 -440.974734)
				(mid 398.831062 -440.993945)
				(end 398.750028 -441.000388)
			)
			(arc
				(start 398.750028 -441.000388)
				(mid 398.668992 -440.993957)
				(end 398.590008 -440.974734)
			)
			(xy 398.582134 -440.97194) (xy 393.917932 -440.97194)
			(arc
				(start 393.910058 -440.974734)
				(mid 393.831072 -440.993945)
				(end 393.750038 -441.000388)
			)
			(arc
				(start 393.750038 -441.000388)
				(mid 393.669002 -440.993957)
				(end 393.590018 -440.974734)
			)
			(xy 393.582144 -440.97194) (xy 389.91794 -440.97194)
			(arc
				(start 389.910066 -440.974734)
				(mid 389.83108 -440.993945)
				(end 389.750046 -441.000388)
			)
			(arc
				(start 389.750046 -441.000388)
				(mid 389.66901 -440.993957)
				(end 389.590026 -440.974734)
			)
			(xy 389.582152 -440.97194) (xy 385.917948 -440.97194)
			(arc
				(start 385.910074 -440.974734)
				(mid 385.831088 -440.993945)
				(end 385.750054 -441.000388)
			)
			(arc
				(start 385.750054 -441.000388)
				(mid 385.669018 -440.993957)
				(end 385.590034 -440.974734)
			)
			(xy 385.58216 -440.97194) (xy 381.917956 -440.97194)
			(arc
				(start 381.910082 -440.974734)
				(mid 381.831096 -440.993945)
				(end 381.750062 -441.000388)
			)
			(arc
				(start 381.750062 -441.000388)
				(mid 381.669026 -440.993957)
				(end 381.590042 -440.974734)
			)
			(xy 381.582168 -440.97194) (xy 343.817956 -440.97194)
			(arc
				(start 343.810082 -440.974734)
				(mid 343.731096 -440.993945)
				(end 343.650062 -441.000388)
			)
			(arc
				(start 343.650062 -441.000388)
				(mid 343.569026 -440.993957)
				(end 343.490042 -440.974734)
			)
			(xy 343.482168 -440.97194) (xy 339.817964 -440.97194)
			(arc
				(start 339.81009 -440.974734)
				(mid 339.731104 -440.993945)
				(end 339.65007 -441.000388)
			)
			(arc
				(start 339.65007 -441.000388)
				(mid 339.569034 -440.993957)
				(end 339.49005 -440.974734)
			)
			(xy 339.482176 -440.97194) (xy 335.817972 -440.97194)
			(arc
				(start 335.810098 -440.974734)
				(mid 335.731112 -440.993945)
				(end 335.650078 -441.000388)
			)
			(arc
				(start 335.650078 -441.000388)
				(mid 335.569042 -440.993957)
				(end 335.490058 -440.974734)
			)
			(xy 335.482184 -440.97194) (xy 331.81798 -440.97194)
			(arc
				(start 331.810106 -440.974734)
				(mid 331.73112 -440.993945)
				(end 331.650086 -441.000388)
			)
			(arc
				(start 331.650086 -441.000388)
				(mid 331.56905 -440.993957)
				(end 331.490066 -440.974734)
			)
			(xy 331.482192 -440.97194) (xy 326.81799 -440.97194)
			(arc
				(start 326.810116 -440.974734)
				(mid 326.73113 -440.993945)
				(end 326.650096 -441.000388)
			)
			(arc
				(start 326.650096 -441.000388)
				(mid 326.56906 -440.993957)
				(end 326.490076 -440.974734)
			)
			(xy 326.482202 -440.97194) (xy 322.817998 -440.97194)
			(arc
				(start 322.810124 -440.974734)
				(mid 322.731138 -440.993945)
				(end 322.650104 -441.000388)
			)
			(arc
				(start 322.650104 -441.000388)
				(mid 322.569068 -440.993957)
				(end 322.490084 -440.974734)
			)
			(xy 322.48221 -440.97194) (xy 318.818006 -440.97194)
			(arc
				(start 318.810132 -440.974734)
				(mid 318.731146 -440.993945)
				(end 318.650112 -441.000388)
			)
			(arc
				(start 318.650112 -441.000388)
				(mid 318.569076 -440.993957)
				(end 318.490092 -440.974734)
			)
			(xy 318.482218 -440.97194) (xy 314.818014 -440.97194)
			(arc
				(start 314.81014 -440.974734)
				(mid 314.731154 -440.993945)
				(end 314.65012 -441.000388)
			)
			(arc
				(start 314.65012 -441.000388)
				(mid 314.569084 -440.993957)
				(end 314.4901 -440.974734)
			)
			(xy 314.482226 -440.97194)
			(arc
				(start 277.82012 -440.97194)
				(mid 277.31587 -440.028787)
				(end 276.314916 -439.652156)
			)
			(arc
				(start 195.50507 -439.652156)
				(mid 194.504157 -440.028834)
				(end 193.999866 -440.97194)
			)
			(xy 154.917902 -440.97194)
			(arc
				(start 154.910028 -440.974734)
				(mid 154.831042 -440.993945)
				(end 154.750008 -441.000388)
			)
			(arc
				(start 154.750008 -441.000388)
				(mid 154.668972 -440.993957)
				(end 154.589988 -440.974734)
			)
			(xy 154.582114 -440.97194) (xy 150.91791 -440.97194)
			(arc
				(start 150.910036 -440.974734)
				(mid 150.83105 -440.993945)
				(end 150.750016 -441.000388)
			)
			(arc
				(start 150.750016 -441.000388)
				(mid 150.66898 -440.993957)
				(end 150.589996 -440.974734)
			)
			(xy 150.582122 -440.97194) (xy 146.917918 -440.97194)
			(arc
				(start 146.910044 -440.974734)
				(mid 146.831058 -440.993945)
				(end 146.750024 -441.000388)
			)
			(arc
				(start 146.750024 -441.000388)
				(mid 146.668988 -440.993957)
				(end 146.590004 -440.974734)
			)
			(xy 146.58213 -440.97194) (xy 142.917926 -440.97194)
			(arc
				(start 142.910052 -440.974734)
				(mid 142.831066 -440.993945)
				(end 142.750032 -441.000388)
			)
			(arc
				(start 142.750032 -441.000388)
				(mid 142.668996 -440.993957)
				(end 142.590012 -440.974734)
			)
			(xy 142.582138 -440.97194) (xy 137.917936 -440.97194)
			(arc
				(start 137.910062 -440.974734)
				(mid 137.831076 -440.993945)
				(end 137.750042 -441.000388)
			)
			(arc
				(start 137.750042 -441.000388)
				(mid 137.669006 -440.993957)
				(end 137.590022 -440.974734)
			)
			(xy 137.582148 -440.97194) (xy 133.917944 -440.97194)
			(arc
				(start 133.91007 -440.974734)
				(mid 133.831084 -440.993945)
				(end 133.75005 -441.000388)
			)
			(arc
				(start 133.75005 -441.000388)
				(mid 133.669014 -440.993957)
				(end 133.59003 -440.974734)
			)
			(xy 133.582156 -440.97194) (xy 129.917952 -440.97194)
			(arc
				(start 129.910078 -440.974734)
				(mid 129.831092 -440.993945)
				(end 129.750058 -441.000388)
			)
			(arc
				(start 129.750058 -441.000388)
				(mid 129.669022 -440.993957)
				(end 129.590038 -440.974734)
			)
			(xy 129.582164 -440.97194) (xy 125.91796 -440.97194)
			(arc
				(start 125.910086 -440.974734)
				(mid 125.8311 -440.993945)
				(end 125.750066 -441.000388)
			)
			(arc
				(start 125.750066 -441.000388)
				(mid 125.66903 -440.993957)
				(end 125.590046 -440.974734)
			)
			(xy 125.582172 -440.97194) (xy 87.81796 -440.97194)
			(arc
				(start 87.810086 -440.974734)
				(mid 87.7311 -440.993945)
				(end 87.650066 -441.000388)
			)
			(arc
				(start 87.650066 -441.000388)
				(mid 87.56903 -440.993957)
				(end 87.490046 -440.974734)
			)
			(xy 87.482172 -440.97194) (xy 83.817968 -440.97194)
			(arc
				(start 83.810094 -440.974734)
				(mid 83.731108 -440.993945)
				(end 83.650074 -441.000388)
			)
			(arc
				(start 83.650074 -441.000388)
				(mid 83.569038 -440.993957)
				(end 83.490054 -440.974734)
			)
			(xy 83.48218 -440.97194) (xy 79.817976 -440.97194)
			(arc
				(start 79.810102 -440.974734)
				(mid 79.731116 -440.993945)
				(end 79.650082 -441.000388)
			)
			(arc
				(start 79.650082 -441.000388)
				(mid 79.569046 -440.993957)
				(end 79.490062 -440.974734)
			)
			(xy 79.482188 -440.97194) (xy 75.817984 -440.97194)
			(arc
				(start 75.81011 -440.974734)
				(mid 75.731124 -440.993945)
				(end 75.65009 -441.000388)
			)
			(arc
				(start 75.65009 -441.000388)
				(mid 75.569054 -440.993957)
				(end 75.49007 -440.974734)
			)
			(xy 75.482196 -440.97194) (xy 70.817994 -440.97194)
			(arc
				(start 70.81012 -440.974734)
				(mid 70.731134 -440.993945)
				(end 70.6501 -441.000388)
			)
			(arc
				(start 70.6501 -441.000388)
				(mid 70.569064 -440.993957)
				(end 70.49008 -440.974734)
			)
			(xy 70.482206 -440.97194) (xy 66.818002 -440.97194)
			(arc
				(start 66.810128 -440.974734)
				(mid 66.731142 -440.993945)
				(end 66.650108 -441.000388)
			)
			(arc
				(start 66.650108 -441.000388)
				(mid 66.569072 -440.993957)
				(end 66.490088 -440.974734)
			)
			(xy 66.482214 -440.97194) (xy 62.81801 -440.97194)
			(arc
				(start 62.810136 -440.974734)
				(mid 62.73115 -440.993945)
				(end 62.650116 -441.000388)
			)
			(arc
				(start 62.650116 -441.000388)
				(mid 62.56908 -440.993957)
				(end 62.490096 -440.974734)
			)
			(xy 62.482222 -440.97194) (xy 58.818018 -440.97194)
			(arc
				(start 58.810144 -440.974734)
				(mid 58.731158 -440.993945)
				(end 58.650124 -441.000388)
			)
			(arc
				(start 58.650124 -441.000388)
				(mid 58.569088 -440.993957)
				(end 58.490104 -440.974734)
			)
			(xy 58.48223 -440.97194)
			(arc
				(start 8.50011 -440.97194)
				(mid 7.805667 -440.684345)
				(end 7.517892 -439.989976)
			)
			(arc
				(start 7.517892 -409.528264)
				(mid 7.287997 -408.373534)
				(end 6.633718 -407.394664)
			)
			(arc
				(start 3.305302 -404.066248)
				(mid 3.092701 -403.747829)
				(end 3.018028 -403.37232)
			)
			(arc
				(start 3.018028 -351.336356)
				(mid 3.016986 -351.326369)
				(end 3.013964 -351.316798)
			)
			(arc
				(start 2.608326 -350.33712)
				(mid 2.585347 -350.311656)
				(end 2.55143 -350.30664)
			)
			(xy 2.533396 -350.310196) (xy 2.510536 -350.338136)
			(arc
				(start 2.510536 -403.371812)
				(mid 2.62388 -403.941719)
				(end 2.946654 -404.424896)
			)
			(arc
				(start 6.27507 -407.753312)
				(mid 6.819424 -408.567623)
				(end 7.010654 -409.528264)
			)
			(arc
				(start 7.010654 -439.989976)
				(mid 7.446906 -441.04318)
				(end 8.50011 -441.479432)
			)
		)
		(stroke
			(width 0)
			(type solid)
		)
		(fill yes)
		(layer "In4.Cu")
		(net "GND")
	)
	(gr_poly
		(pts
			(xy 279.31364 -396.08252) (xy 279.31364 -395.54912) (xy 279.279219 -395.52562) (xy 279.214461 -395.473143)
			(xy 279.154896 -395.41484) (xy 279.101044 -395.351222) (xy 279.053378 -395.282845) (xy 279.012316 -395.210311)
			(xy 278.978218 -395.134254) (xy 278.951383 -395.055341) (xy 278.932046 -394.974265) (xy 278.920376 -394.891735)
			(xy 278.916477 -394.808476) (xy 278.920381 -394.725216) (xy 278.932055 -394.642687) (xy 278.951397 -394.561612)
			(xy 278.978236 -394.482701) (xy 279.012338 -394.406646) (xy 279.053404 -394.334113) (xy 279.101074 -394.26574)
			(xy 279.154929 -394.202124) (xy 279.214498 -394.143824) (xy 279.279258 -394.091351) (xy 279.31364 -394.067792)
			(xy 279.31364 -390.4742) (xy 277.12924 -388.2898) (xy 240.43894 -388.2898) (xy 239.34674 -389.382)
			(xy 239.34674 -394.8085) (xy 243.179528 -394.8085) (xy 243.183558 -394.723892) (xy 243.195613 -394.640051)
			(xy 243.215583 -394.557735) (xy 243.243287 -394.47769) (xy 243.278475 -394.400641) (xy 243.320827 -394.327286)
			(xy 243.36996 -394.258289) (xy 243.42543 -394.194274) (xy 243.486733 -394.135823) (xy 243.553315 -394.083463)
			(xy 243.624573 -394.03767) (xy 243.699861 -393.998857) (xy 243.778498 -393.967377) (xy 243.859771 -393.943515)
			(xy 243.942944 -393.927486) (xy 244.027264 -393.919435) (xy 244.069616 -393.918948) (xy 244.11084 -393.919417)
			(xy 244.192933 -393.927053) (xy 244.273968 -393.94225) (xy 244.35325 -393.964876) (xy 244.430099 -393.994739)
			(xy 244.503857 -394.031582) (xy 244.573891 -394.075088) (xy 244.639601 -394.124886) (xy 244.670326 -394.152374)
			(xy 244.677558 -394.158461) (xy 244.695171 -394.165287) (xy 244.714061 -394.165287) (xy 244.731674 -394.158461)
			(xy 244.738906 -394.152374) (xy 244.769639 -394.124894) (xy 244.835341 -394.075085) (xy 244.905371 -394.03157)
			(xy 244.979128 -393.994723) (xy 245.055977 -393.964858) (xy 245.13526 -393.942233) (xy 245.216297 -393.927041)
			(xy 245.298392 -393.919413) (xy 245.339616 -393.918948) (xy 245.381408 -393.919476) (xy 245.464624 -393.927312)
			(xy 245.546738 -393.942923) (xy 245.627024 -393.96617) (xy 245.704775 -393.996849) (xy 245.779303 -394.034689)
			(xy 245.849951 -394.079356) (xy 245.916096 -394.130456) (xy 245.977154 -394.187537) (xy 246.032585 -394.250097)
			(xy 246.081902 -394.317582) (xy 246.124667 -394.389397) (xy 246.143018 -394.426948) (xy 246.170089 -394.428781)
			(xy 246.223268 -394.43954) (xy 246.274197 -394.458246) (xy 246.321697 -394.484466) (xy 246.364667 -394.51759)
			(xy 246.402111 -394.556853) (xy 246.433163 -394.601345) (xy 246.457102 -394.650034) (xy 246.473374 -394.701792)
			(xy 246.481601 -394.75542) (xy 246.482108 -394.782548) (xy 246.481601 -394.8085) (xy 249.114543 -394.8085)
			(xy 249.118574 -394.723896) (xy 249.130628 -394.640058) (xy 249.150596 -394.557746) (xy 249.178298 -394.477704)
			(xy 249.213483 -394.400658) (xy 249.255833 -394.327305) (xy 249.304963 -394.25831) (xy 249.360429 -394.194298)
			(xy 249.421729 -394.135847) (xy 249.488307 -394.083488) (xy 249.55956 -394.037695) (xy 249.634844 -393.998882)
			(xy 249.713476 -393.967401) (xy 249.794745 -393.943537) (xy 249.877914 -393.927506) (xy 249.96223 -393.919453)
			(xy 250.00458 -393.918948) (xy 250.045803 -393.919439) (xy 250.127896 -393.927072) (xy 250.20893 -393.942266)
			(xy 250.288212 -393.964889) (xy 250.365061 -393.994749) (xy 250.438819 -394.031588) (xy 250.508854 -394.075092)
			(xy 250.574564 -394.124887) (xy 250.60529 -394.152374) (xy 250.612522 -394.158461) (xy 250.630135 -394.165287)
			(xy 250.649025 -394.165287) (xy 250.666638 -394.158461) (xy 250.67387 -394.152374) (xy 250.704576 -394.124863)
			(xy 250.770283 -394.075057) (xy 250.840317 -394.031545) (xy 250.914078 -393.994701) (xy 250.990931 -393.96484)
			(xy 251.070218 -393.942219) (xy 251.151257 -393.927032) (xy 251.233355 -393.91941) (xy 251.27458 -393.918948)
			(xy 251.316356 -393.919458) (xy 251.399539 -393.927298) (xy 251.481621 -393.942901) (xy 251.561879 -393.966129)
			(xy 251.639606 -393.996779) (xy 251.714118 -394.03458) (xy 251.784758 -394.079199) (xy 251.850904 -394.130243)
			(xy 251.911974 -394.187264) (xy 251.96743 -394.249758) (xy 252.016784 -394.317175) (xy 252.059601 -394.388922)
			(xy 252.077982 -394.42644) (xy 252.086364 -394.42644) (xy 252.114351 -394.426946) (xy 252.169636 -394.435698)
			(xy 252.222871 -394.452992) (xy 252.272744 -394.478402) (xy 252.318028 -394.511302) (xy 252.357606 -394.550881)
			(xy 252.390505 -394.596166) (xy 252.415913 -394.646041) (xy 252.433205 -394.699276) (xy 252.441955 -394.754561)
			(xy 252.442472 -394.782548) (xy 252.441992 -394.8085) (xy 255.049428 -394.8085) (xy 255.053459 -394.723891)
			(xy 255.065514 -394.640048) (xy 255.085484 -394.55773) (xy 255.11319 -394.477684) (xy 255.148379 -394.400634)
			(xy 255.190732 -394.327277) (xy 255.239868 -394.258279) (xy 255.295339 -394.194265) (xy 255.356645 -394.135813)
			(xy 255.423229 -394.083453) (xy 255.494489 -394.03766) (xy 255.56978 -393.998849) (xy 255.648419 -393.96737)
			(xy 255.729694 -393.943509) (xy 255.812869 -393.927482) (xy 255.897191 -393.919434) (xy 255.939544 -393.918948)
			(xy 255.980768 -393.919399) (xy 256.062862 -393.927038) (xy 256.143897 -393.942237) (xy 256.223179 -393.964866)
			(xy 256.300029 -393.994731) (xy 256.373786 -394.031576) (xy 256.44382 -394.075085) (xy 256.509529 -394.124885)
			(xy 256.540254 -394.152374) (xy 256.547486 -394.158461) (xy 256.565099 -394.165287) (xy 256.583989 -394.165287)
			(xy 256.601602 -394.158461) (xy 256.608834 -394.152374) (xy 256.639555 -394.12488) (xy 256.70526 -394.075073)
			(xy 256.775292 -394.031559) (xy 256.849049 -393.994713) (xy 256.925901 -393.96485) (xy 257.005185 -393.942227)
			(xy 257.086223 -393.927037) (xy 257.168319 -393.919412) (xy 257.209544 -393.918948) (xy 257.251493 -393.919491)
			(xy 257.335018 -393.927401) (xy 257.417428 -393.943137) (xy 257.497991 -393.96656) (xy 257.575991 -393.997462)
			(xy 257.650737 -394.035568) (xy 257.721565 -394.08054) (xy 257.787845 -394.131979) (xy 257.848989 -394.189427)
			(xy 257.904455 -394.252376) (xy 257.95375 -394.320266) (xy 257.996436 -394.392494) (xy 258.014724 -394.43025)
			(xy 258.027542 -394.428485) (xy 258.053348 -394.426578) (xy 258.066286 -394.42644) (xy 258.067048 -394.42644)
			(xy 258.093699 -394.426845) (xy 258.146403 -394.434796) (xy 258.197335 -394.450512) (xy 258.245356 -394.473643)
			(xy 258.289393 -394.503673) (xy 258.328463 -394.539929) (xy 258.361693 -394.581604) (xy 258.388341 -394.627765)
			(xy 258.407813 -394.677383) (xy 258.419673 -394.729348) (xy 258.423656 -394.7825) (xy 258.421708 -394.8085)
			(xy 260.984428 -394.8085) (xy 260.988458 -394.723893) (xy 261.000513 -394.640052) (xy 261.020483 -394.557736)
			(xy 261.048186 -394.477692) (xy 261.083374 -394.400643) (xy 261.125725 -394.327288) (xy 261.174858 -394.258291)
			(xy 261.230327 -394.194277) (xy 261.29163 -394.135826) (xy 261.358212 -394.083466) (xy 261.429469 -394.037672)
			(xy 261.504756 -393.99886) (xy 261.583392 -393.967379) (xy 261.664664 -393.943516) (xy 261.747837 -393.927487)
			(xy 261.832156 -393.919436) (xy 261.874508 -393.918948) (xy 261.915732 -393.919422) (xy 261.997825 -393.927057)
			(xy 262.078859 -393.942253) (xy 262.158141 -393.964879) (xy 262.234991 -393.994741) (xy 262.308749 -394.031583)
			(xy 262.378783 -394.075089) (xy 262.444493 -394.124886) (xy 262.475218 -394.152374) (xy 262.48245 -394.158461)
			(xy 262.500063 -394.165287) (xy 262.518953 -394.165287) (xy 262.536566 -394.158461) (xy 262.543798 -394.152374)
			(xy 262.574534 -394.124897) (xy 262.640236 -394.075089) (xy 262.710266 -394.031574) (xy 262.784021 -393.994725)
			(xy 262.86087 -393.96486) (xy 262.940153 -393.942234) (xy 263.021189 -393.927042) (xy 263.103284 -393.919413)
			(xy 263.144508 -393.918948) (xy 263.18635 -393.919404) (xy 263.269665 -393.927258) (xy 263.351874 -393.942906)
			(xy 263.432248 -393.966208) (xy 263.510078 -393.996959) (xy 263.584674 -394.034887) (xy 263.655376 -394.079656)
			(xy 263.721559 -394.130869) (xy 263.782638 -394.188075) (xy 263.838071 -394.250766) (xy 263.887369 -394.318389)
			(xy 263.930095 -394.390344) (xy 263.948418 -394.427964) (xy 263.981692 -394.42644) (xy 264.008347 -394.426817)
			(xy 264.061062 -394.434761) (xy 264.112004 -394.450474) (xy 264.160035 -394.473603) (xy 264.204083 -394.503633)
			(xy 264.243162 -394.539893) (xy 264.276401 -394.581572) (xy 264.303057 -394.62774) (xy 264.322533 -394.677365)
			(xy 264.334396 -394.729339) (xy 264.33838 -394.7825) (xy 264.336432 -394.8085) (xy 266.919443 -394.8085)
			(xy 266.923474 -394.723896) (xy 266.935527 -394.640059) (xy 266.955496 -394.557747) (xy 266.983198 -394.477706)
			(xy 267.018382 -394.40066) (xy 267.060731 -394.327308) (xy 267.109861 -394.258313) (xy 267.165326 -394.194301)
			(xy 267.226625 -394.13585) (xy 267.293203 -394.083491) (xy 267.364456 -394.037698) (xy 267.439739 -393.998885)
			(xy 267.51837 -393.967403) (xy 267.599638 -393.943538) (xy 267.682807 -393.927507) (xy 267.767122 -393.919453)
			(xy 267.809472 -393.918948) (xy 267.850695 -393.919444) (xy 267.932787 -393.927077) (xy 268.013822 -393.942269)
			(xy 268.093103 -393.964892) (xy 268.169953 -393.994751) (xy 268.243711 -394.03159) (xy 268.313746 -394.075093)
			(xy 268.379456 -394.124888) (xy 268.410182 -394.152374) (xy 268.417414 -394.158461) (xy 268.435027 -394.165287)
			(xy 268.453917 -394.165287) (xy 268.47153 -394.158461) (xy 268.478762 -394.152374) (xy 268.509471 -394.124866)
			(xy 268.575178 -394.07506) (xy 268.645212 -394.031548) (xy 268.718971 -393.994703) (xy 268.795824 -393.964842)
			(xy 268.87511 -393.942221) (xy 268.95615 -393.927033) (xy 269.038247 -393.91941) (xy 269.079472 -393.918948)
			(xy 269.121265 -393.919428) (xy 269.204483 -393.927269) (xy 269.286598 -393.942885) (xy 269.366885 -393.966137)
			(xy 269.444636 -393.996821) (xy 269.519164 -394.034666) (xy 269.589812 -394.079337) (xy 269.655956 -394.130441)
			(xy 269.717013 -394.187526) (xy 269.772444 -394.250089) (xy 269.821759 -394.317577) (xy 269.864524 -394.389396)
			(xy 269.882874 -394.426948) (xy 269.909949 -394.428731) (xy 269.963129 -394.439499) (xy 270.014058 -394.458212)
			(xy 270.061558 -394.484438) (xy 270.104527 -394.517569) (xy 270.141971 -394.556837) (xy 270.173021 -394.601333)
			(xy 270.19696 -394.650026) (xy 270.213231 -394.701787) (xy 270.221458 -394.755419) (xy 270.221964 -394.782548)
			(xy 270.221496 -394.8085) (xy 272.854328 -394.8085) (xy 272.858359 -394.723891) (xy 272.870414 -394.640048)
			(xy 272.890384 -394.557731) (xy 272.918089 -394.477686) (xy 272.953277 -394.400636) (xy 272.995631 -394.32728)
			(xy 273.044766 -394.258282) (xy 273.100237 -394.194267) (xy 273.161542 -394.135816) (xy 273.228125 -394.083456)
			(xy 273.299385 -394.037663) (xy 273.374675 -393.998851) (xy 273.453313 -393.967372) (xy 273.534587 -393.943511)
			(xy 273.617762 -393.927483) (xy 273.702084 -393.919434) (xy 273.744436 -393.918948) (xy 273.78566 -393.919404)
			(xy 273.867754 -393.927042) (xy 273.948789 -393.942241) (xy 274.028071 -393.964869) (xy 274.10492 -393.994734)
			(xy 274.178678 -394.031578) (xy 274.248712 -394.075086) (xy 274.314421 -394.124886) (xy 274.345146 -394.152374)
			(xy 274.352378 -394.158461) (xy 274.369991 -394.165287) (xy 274.388881 -394.165287) (xy 274.406494 -394.158461)
			(xy 274.413726 -394.152374) (xy 274.44445 -394.124884) (xy 274.510154 -394.075076) (xy 274.580186 -394.031562)
			(xy 274.653943 -393.994716) (xy 274.730794 -393.964852) (xy 274.810078 -393.942228) (xy 274.891116 -393.927038)
			(xy 274.973211 -393.919412) (xy 275.014436 -393.918948) (xy 275.056229 -393.919459) (xy 275.139445 -393.927297)
			(xy 275.221559 -393.942909) (xy 275.301846 -393.966158) (xy 275.379596 -393.996839) (xy 275.454125 -394.034681)
			(xy 275.524773 -394.079349) (xy 275.590918 -394.130451) (xy 275.651975 -394.187533) (xy 275.707406 -394.250094)
			(xy 275.756722 -394.31758) (xy 275.799488 -394.389397) (xy 275.817838 -394.426948) (xy 275.844911 -394.428763)
			(xy 275.898089 -394.439526) (xy 275.949019 -394.458234) (xy 275.996518 -394.484456) (xy 276.039488 -394.517583)
			(xy 276.076932 -394.556848) (xy 276.107984 -394.601341) (xy 276.131922 -394.650031) (xy 276.148194 -394.70179)
			(xy 276.156421 -394.75542) (xy 276.156928 -394.782548) (xy 276.156404 -394.808503) (xy 276.148874 -394.859865)
			(xy 276.133965 -394.909589) (xy 276.111994 -394.956621) (xy 276.083427 -394.999964) (xy 276.048869 -395.038699)
			(xy 276.009052 -395.072006) (xy 275.964821 -395.099179) (xy 275.917114 -395.11964) (xy 275.86694 -395.132958)
			(xy 275.841206 -395.13637) (xy 275.825747 -395.174161) (xy 275.788816 -395.246988) (xy 275.745365 -395.316123)
			(xy 275.695761 -395.380985) (xy 275.64042 -395.441027) (xy 275.579808 -395.495744) (xy 275.514437 -395.544676)
			(xy 275.444856 -395.587409) (xy 275.371651 -395.623585) (xy 275.295438 -395.652899) (xy 275.216859 -395.675104)
			(xy 275.136576 -395.690013) (xy 275.055264 -395.6975) (xy 275.014436 -395.697964) (xy 274.973213 -395.69746)
			(xy 274.891121 -395.689828) (xy 274.810087 -395.674636) (xy 274.730806 -395.652015) (xy 274.653956 -395.622157)
			(xy 274.580198 -395.585319) (xy 274.510163 -395.541817) (xy 274.444452 -395.492024) (xy 274.413726 -395.464538)
			(xy 274.406494 -395.458451) (xy 274.388881 -395.451625) (xy 274.369991 -395.451625) (xy 274.352378 -395.458451)
			(xy 274.345146 -395.464538) (xy 274.314435 -395.492044) (xy 274.248729 -395.54185) (xy 274.178695 -395.585362)
			(xy 274.104936 -395.622207) (xy 274.028083 -395.652068) (xy 273.948797 -395.67469) (xy 273.867758 -395.689878)
			(xy 273.785661 -395.697501) (xy 273.744436 -395.697964) (xy 273.702084 -395.697566) (xy 273.617762 -395.689517)
			(xy 273.534587 -395.673489) (xy 273.453313 -395.649628) (xy 273.374675 -395.618149) (xy 273.299385 -395.579337)
			(xy 273.228125 -395.533544) (xy 273.161542 -395.481184) (xy 273.100237 -395.422733) (xy 273.044766 -395.358718)
			(xy 272.995631 -395.28972) (xy 272.953277 -395.216364) (xy 272.918089 -395.139314) (xy 272.890384 -395.059269)
			(xy 272.870414 -394.976952) (xy 272.858359 -394.893109) (xy 272.854328 -394.8085) (xy 270.221496 -394.8085)
			(xy 270.221496 -394.808506) (xy 270.213964 -394.859873) (xy 270.199053 -394.909601) (xy 270.177077 -394.956636)
			(xy 270.148504 -394.999982) (xy 270.113939 -395.038718) (xy 270.074115 -395.072025) (xy 270.029876 -395.099194)
			(xy 269.98216 -395.119651) (xy 269.93198 -395.132962) (xy 269.906242 -395.13637) (xy 269.890753 -395.174148)
			(xy 269.853824 -395.246974) (xy 269.810375 -395.316109) (xy 269.760773 -395.38097) (xy 269.705435 -395.441012)
			(xy 269.644826 -395.49573) (xy 269.579457 -395.544662) (xy 269.509879 -395.587396) (xy 269.436676 -395.623574)
			(xy 269.360466 -395.652889) (xy 269.28189 -395.675096) (xy 269.201609 -395.690008) (xy 269.120299 -395.697499)
			(xy 269.079472 -395.697964) (xy 269.038248 -395.6975) (xy 268.956155 -395.689862) (xy 268.87512 -395.674665)
			(xy 268.795838 -395.652037) (xy 268.718989 -395.622174) (xy 268.645231 -395.585331) (xy 268.575197 -395.541824)
			(xy 268.509487 -395.492026) (xy 268.478762 -395.464538) (xy 268.47153 -395.458451) (xy 268.453917 -395.451625)
			(xy 268.435027 -395.451625) (xy 268.417414 -395.458451) (xy 268.410182 -395.464538) (xy 268.379456 -395.492026)
			(xy 268.313752 -395.541834) (xy 268.243721 -395.585348) (xy 268.169964 -395.622194) (xy 268.093113 -395.652058)
			(xy 268.013829 -395.674682) (xy 267.932792 -395.689873) (xy 267.850696 -395.6975) (xy 267.809472 -395.697964)
			(xy 267.767122 -395.697547) (xy 267.682807 -395.689493) (xy 267.599638 -395.673462) (xy 267.51837 -395.649597)
			(xy 267.439739 -395.618115) (xy 267.364456 -395.579302) (xy 267.293203 -395.533509) (xy 267.226625 -395.48115)
			(xy 267.165326 -395.422699) (xy 267.109861 -395.358687) (xy 267.060731 -395.289692) (xy 267.018382 -395.21634)
			(xy 266.983198 -395.139294) (xy 266.955496 -395.059253) (xy 266.935527 -394.976941) (xy 266.923474 -394.893104)
			(xy 266.919443 -394.8085) (xy 264.336432 -394.8085) (xy 264.334396 -394.835661) (xy 264.322533 -394.887635)
			(xy 264.303057 -394.93726) (xy 264.276401 -394.983428) (xy 264.243162 -395.025107) (xy 264.204083 -395.061367)
			(xy 264.160035 -395.091397) (xy 264.112004 -395.114526) (xy 264.061062 -395.130239) (xy 264.008347 -395.138183)
			(xy 263.981692 -395.138656) (xy 263.970516 -395.138402) (xy 263.954928 -395.17605) (xy 263.917915 -395.248648)
			(xy 263.874417 -395.317555) (xy 263.824797 -395.382194) (xy 263.769471 -395.442023) (xy 263.708905 -395.496539)
			(xy 263.643605 -395.545287) (xy 263.57412 -395.587856) (xy 263.501032 -395.623891) (xy 263.424953 -395.653088)
			(xy 263.346523 -395.675203) (xy 263.266399 -395.69005) (xy 263.185252 -395.697505) (xy 263.144508 -395.697964)
			(xy 263.103285 -395.697477) (xy 263.021192 -395.689843) (xy 262.940158 -395.674649) (xy 262.860876 -395.652025)
			(xy 262.784027 -395.622164) (xy 262.710269 -395.585324) (xy 262.640234 -395.54182) (xy 262.574524 -395.492025)
			(xy 262.543798 -395.464538) (xy 262.536566 -395.458451) (xy 262.518953 -395.451625) (xy 262.500063 -395.451625)
			(xy 262.48245 -395.458451) (xy 262.475218 -395.464538) (xy 262.444477 -395.492009) (xy 262.378775 -395.541818)
			(xy 262.308747 -395.585333) (xy 262.234992 -395.622182) (xy 262.158144 -395.652048) (xy 262.078861 -395.674675)
			(xy 261.997826 -395.689868) (xy 261.915732 -395.697498) (xy 261.874508 -395.697964) (xy 261.832156 -395.697564)
			(xy 261.747837 -395.689513) (xy 261.664664 -395.673484) (xy 261.583392 -395.649621) (xy 261.504756 -395.61814)
			(xy 261.429469 -395.579328) (xy 261.358212 -395.533534) (xy 261.29163 -395.481174) (xy 261.230327 -395.422723)
			(xy 261.174858 -395.358709) (xy 261.125725 -395.289712) (xy 261.083374 -395.216357) (xy 261.048186 -395.139308)
			(xy 261.020483 -395.059264) (xy 261.000513 -394.976948) (xy 260.988458 -394.893107) (xy 260.984428 -394.8085)
			(xy 258.421708 -394.8085) (xy 258.419673 -394.835652) (xy 258.407813 -394.887617) (xy 258.388341 -394.937235)
			(xy 258.361693 -394.983396) (xy 258.328463 -395.025071) (xy 258.289393 -395.061327) (xy 258.245356 -395.091357)
			(xy 258.197335 -395.114488) (xy 258.146403 -395.130204) (xy 258.093699 -395.138155) (xy 258.067048 -395.138656)
			(xy 258.03606 -395.137386) (xy 258.020546 -395.175113) (xy 257.983557 -395.247826) (xy 257.940067 -395.316846)
			(xy 257.89044 -395.381595) (xy 257.835094 -395.441529) (xy 257.774494 -395.496144) (xy 257.709147 -395.544982)
			(xy 257.639604 -395.587632) (xy 257.566448 -395.623736) (xy 257.490294 -395.65299) (xy 257.411782 -395.67515)
			(xy 257.331571 -395.690029) (xy 257.250334 -395.697502) (xy 257.209544 -395.697964) (xy 257.168321 -395.697455)
			(xy 257.08623 -395.689824) (xy 257.005196 -395.674633) (xy 256.925914 -395.652012) (xy 256.849065 -395.622155)
			(xy 256.775306 -395.585317) (xy 256.705271 -395.541816) (xy 256.63956 -395.492023) (xy 256.608834 -395.464538)
			(xy 256.601602 -395.458451) (xy 256.583989 -395.451625) (xy 256.565099 -395.451625) (xy 256.547486 -395.458451)
			(xy 256.540254 -395.464538) (xy 256.50954 -395.49204) (xy 256.443834 -395.541846) (xy 256.373801 -395.585359)
			(xy 256.300042 -395.622204) (xy 256.22319 -395.652066) (xy 256.143904 -395.674688) (xy 256.062865 -395.689877)
			(xy 255.980769 -395.697501) (xy 255.939544 -395.697964) (xy 255.897191 -395.697566) (xy 255.812869 -395.689518)
			(xy 255.729694 -395.673491) (xy 255.648419 -395.64963) (xy 255.56978 -395.618151) (xy 255.494489 -395.57934)
			(xy 255.423229 -395.533547) (xy 255.356645 -395.481187) (xy 255.295339 -395.422735) (xy 255.239868 -395.358721)
			(xy 255.190732 -395.289723) (xy 255.148379 -395.216366) (xy 255.11319 -395.139316) (xy 255.085484 -395.05927)
			(xy 255.065514 -394.976952) (xy 255.053459 -394.893109) (xy 255.049428 -394.8085) (xy 252.441992 -394.8085)
			(xy 252.441968 -394.809821) (xy 252.433657 -394.863731) (xy 252.417221 -394.915743) (xy 252.393046 -394.964639)
			(xy 252.361695 -395.009276) (xy 252.323904 -395.04861) (xy 252.280556 -395.081721) (xy 252.232666 -395.107832)
			(xy 252.181353 -395.126335) (xy 252.127819 -395.136795) (xy 252.100588 -395.138402) (xy 252.085024 -395.17606)
			(xy 252.048009 -395.248659) (xy 252.004509 -395.317566) (xy 251.954887 -395.382206) (xy 251.89956 -395.442034)
			(xy 251.838991 -395.496551) (xy 251.773689 -395.545298) (xy 251.704202 -395.587866) (xy 251.631111 -395.623899)
			(xy 251.555031 -395.653095) (xy 251.476599 -395.675208) (xy 251.396473 -395.690054) (xy 251.315325 -395.697507)
			(xy 251.27458 -395.697964) (xy 251.233356 -395.697495) (xy 251.151263 -395.689858) (xy 251.070228 -395.674661)
			(xy 250.990947 -395.652035) (xy 250.914097 -395.622172) (xy 250.840339 -395.58533) (xy 250.770305 -395.541823)
			(xy 250.704595 -395.492026) (xy 250.67387 -395.464538) (xy 250.666638 -395.458451) (xy 250.649025 -395.451625)
			(xy 250.630135 -395.451625) (xy 250.612522 -395.458451) (xy 250.60529 -395.464538) (xy 250.574561 -395.492023)
			(xy 250.508857 -395.54183) (xy 250.438827 -395.585344) (xy 250.36507 -395.622192) (xy 250.28822 -395.652056)
			(xy 250.208936 -395.67468) (xy 250.127899 -395.689872) (xy 250.045804 -395.697499) (xy 250.00458 -395.697964)
			(xy 249.96223 -395.697547) (xy 249.877914 -395.689494) (xy 249.794745 -395.673463) (xy 249.713476 -395.649599)
			(xy 249.634844 -395.618118) (xy 249.55956 -395.579305) (xy 249.488307 -395.533512) (xy 249.421729 -395.481153)
			(xy 249.360429 -395.422702) (xy 249.304963 -395.35869) (xy 249.255833 -395.289695) (xy 249.213483 -395.216342)
			(xy 249.178298 -395.139296) (xy 249.150596 -395.059254) (xy 249.130628 -394.976942) (xy 249.118574 -394.893104)
			(xy 249.114543 -394.8085) (xy 246.481601 -394.8085) (xy 246.481601 -394.808504) (xy 246.474071 -394.859867)
			(xy 246.459161 -394.909593) (xy 246.437189 -394.956626) (xy 246.40862 -394.999969) (xy 246.374059 -395.038705)
			(xy 246.334241 -395.072012) (xy 246.290007 -395.099183) (xy 246.242297 -395.119644) (xy 246.192121 -395.132959)
			(xy 246.166386 -395.13637) (xy 246.15086 -395.174132) (xy 246.113933 -395.246957) (xy 246.070488 -395.316091)
			(xy 246.020888 -395.380952) (xy 245.965553 -395.440994) (xy 245.904948 -395.495712) (xy 245.839582 -395.544645)
			(xy 245.770007 -395.587381) (xy 245.696808 -395.62356) (xy 245.620601 -395.652878) (xy 245.542028 -395.675088)
			(xy 245.461749 -395.690002) (xy 245.380442 -395.697497) (xy 245.339616 -395.697964) (xy 245.298393 -395.697472)
			(xy 245.216301 -395.689839) (xy 245.135266 -395.674645) (xy 245.055985 -395.652022) (xy 244.979135 -395.622162)
			(xy 244.905377 -395.585323) (xy 244.835342 -395.541819) (xy 244.769632 -395.492024) (xy 244.738906 -395.464538)
			(xy 244.731674 -395.458451) (xy 244.714061 -395.451625) (xy 244.695171 -395.451625) (xy 244.677558 -395.458451)
			(xy 244.670326 -395.464538) (xy 244.639624 -395.492053) (xy 244.573916 -395.541859) (xy 244.503881 -395.58537)
			(xy 244.43012 -395.622214) (xy 244.353266 -395.652074) (xy 244.273979 -395.674694) (xy 244.192939 -395.68988)
			(xy 244.110841 -395.697502) (xy 244.069616 -395.697964) (xy 244.027264 -395.697565) (xy 243.942944 -395.689514)
			(xy 243.859771 -395.673485) (xy 243.778498 -395.649623) (xy 243.699861 -395.618143) (xy 243.624573 -395.57933)
			(xy 243.553315 -395.533537) (xy 243.486733 -395.481177) (xy 243.42543 -395.422726) (xy 243.36996 -395.358711)
			(xy 243.320827 -395.289714) (xy 243.278475 -395.216359) (xy 243.243287 -395.13931) (xy 243.215583 -395.059265)
			(xy 243.195613 -394.976949) (xy 243.183558 -394.893108) (xy 243.179528 -394.8085) (xy 239.34674 -394.8085)
			(xy 239.34674 -396.17396) (xy 239.57788 -396.4051) (xy 278.99106 -396.4051)
		)
		(stroke
			(width 0)
			(type solid)
		)
		(fill yes)
		(layer "In4.Cu")
		(net "P12V_AUX")
	)
	(gr_poly
		(pts
			(xy 181.433724 -110.255304) (xy 181.42966 -110.229396) (xy 181.42754 -110.21597) (xy 181.42525 -110.188885)
			(xy 181.425088 -110.175294) (xy 181.425598 -110.149307) (xy 181.433729 -110.097973) (xy 181.449791 -110.048543)
			(xy 181.473387 -110.002234) (xy 181.503937 -109.960186) (xy 181.540688 -109.923435) (xy 181.582736 -109.892886)
			(xy 181.629045 -109.86929) (xy 181.678475 -109.853229) (xy 181.729809 -109.845098) (xy 181.755796 -109.844586)
			(xy 181.769387 -109.844755) (xy 181.796472 -109.847041) (xy 181.809898 -109.849158) (xy 181.835806 -109.853222)
			(xy 181.953408 -109.73562) (xy 181.894988 -109.6772) (xy 181.864762 -109.687614) (xy 181.838351 -109.696249)
			(xy 181.783576 -109.705563) (xy 181.755796 -109.706156) (xy 181.729802 -109.705672) (xy 181.678455 -109.697539)
			(xy 181.629012 -109.681473) (xy 181.582692 -109.65787) (xy 181.540634 -109.627311) (xy 181.503874 -109.590549)
			(xy 181.473318 -109.548489) (xy 181.449719 -109.502167) (xy 181.433656 -109.452723) (xy 181.425526 -109.401375)
			(xy 181.425529 -109.349388) (xy 181.433665 -109.298041) (xy 181.449733 -109.248599) (xy 181.473338 -109.202279)
			(xy 181.503899 -109.160223) (xy 181.540662 -109.123465) (xy 181.582723 -109.092911) (xy 181.629047 -109.069313)
			(xy 181.678491 -109.053252) (xy 181.72984 -109.045125) (xy 181.781827 -109.04513) (xy 181.833174 -109.053268)
			(xy 181.882615 -109.069338) (xy 181.928933 -109.092946) (xy 181.970989 -109.123508) (xy 182.007745 -109.160273)
			(xy 182.038297 -109.202336) (xy 182.061893 -109.24866) (xy 182.077951 -109.298106) (xy 182.086076 -109.349454)
			(xy 182.086504 -109.375448) (xy 182.085917 -109.403229) (xy 182.076604 -109.458005) (xy 182.067962 -109.484414)
			(xy 182.057548 -109.51464) (xy 182.115968 -109.57306) (xy 182.23357 -109.455458) (xy 182.229506 -109.42955)
			(xy 182.227388 -109.416124) (xy 182.225102 -109.389039) (xy 182.224934 -109.375448) (xy 182.225414 -109.349457)
			(xy 182.233539 -109.298116) (xy 182.249598 -109.248677) (xy 182.273194 -109.20236) (xy 182.303746 -109.160306)
			(xy 182.340501 -109.12355) (xy 182.382555 -109.092997) (xy 182.428872 -109.0694) (xy 182.47831 -109.053341)
			(xy 182.529651 -109.045214) (xy 182.555642 -109.04474) (xy 182.569232 -109.04491) (xy 182.596318 -109.0472)
			(xy 182.609744 -109.049312) (xy 182.635652 -109.053376) (xy 182.753762 -108.935266) (xy 182.695088 -108.876846)
			(xy 182.665116 -108.887514) (xy 182.638583 -108.896185) (xy 182.583551 -108.905508) (xy 182.555642 -108.906056)
			(xy 182.529647 -108.905576) (xy 182.478297 -108.897449) (xy 182.428851 -108.881389) (xy 182.382526 -108.857791)
			(xy 182.340463 -108.827236) (xy 182.303699 -108.790478) (xy 182.273137 -108.74842) (xy 182.249532 -108.702099)
			(xy 182.233464 -108.652655) (xy 182.225328 -108.601307) (xy 182.225326 -108.549317) (xy 182.233458 -108.497968)
			(xy 182.249523 -108.448523) (xy 182.273125 -108.402201) (xy 182.303683 -108.360141) (xy 182.340445 -108.323379)
			(xy 182.382506 -108.292822) (xy 182.428829 -108.26922) (xy 182.478274 -108.253157) (xy 182.529623 -108.245026)
			(xy 182.581612 -108.245029) (xy 182.632961 -108.253165) (xy 182.682404 -108.269234) (xy 182.728725 -108.29284)
			(xy 182.770782 -108.323403) (xy 182.80754 -108.360168) (xy 182.838094 -108.402231) (xy 182.861691 -108.448557)
			(xy 182.87775 -108.498003) (xy 182.885876 -108.549353) (xy 182.88635 -108.575348) (xy 182.885794 -108.603256)
			(xy 182.876478 -108.658289) (xy 182.867808 -108.684822) (xy 182.85714 -108.714794) (xy 182.91556 -108.773468)
			(xy 183.03367 -108.655358) (xy 183.029606 -108.62945) (xy 183.027488 -108.616024) (xy 183.025202 -108.588939)
			(xy 183.025034 -108.575348) (xy 183.025514 -108.549357) (xy 183.033639 -108.498016) (xy 183.049698 -108.448577)
			(xy 183.073294 -108.40226) (xy 183.103846 -108.360206) (xy 183.140601 -108.32345) (xy 183.182655 -108.292897)
			(xy 183.228972 -108.2693) (xy 183.27841 -108.253241) (xy 183.329751 -108.245114) (xy 183.355742 -108.24464)
			(xy 183.369332 -108.24481) (xy 183.396418 -108.2471) (xy 183.409844 -108.249212) (xy 183.435752 -108.253276)
			(xy 183.553354 -108.135674) (xy 183.494934 -108.077254) (xy 183.464708 -108.087668) (xy 183.438298 -108.096306)
			(xy 183.383523 -108.105625) (xy 183.355742 -108.10621) (xy 183.329752 -108.10573) (xy 183.27841 -108.097605)
			(xy 183.228972 -108.081548) (xy 183.182655 -108.057955) (xy 183.140599 -108.027406) (xy 183.103839 -107.990654)
			(xy 183.073282 -107.948604) (xy 183.049679 -107.902292) (xy 183.033611 -107.852857) (xy 183.025475 -107.801517)
			(xy 183.025471 -107.749537) (xy 183.033599 -107.698196) (xy 183.049658 -107.648759) (xy 183.073253 -107.602442)
			(xy 183.103804 -107.560387) (xy 183.140557 -107.52363) (xy 183.182608 -107.493074) (xy 183.228922 -107.469473)
			(xy 183.278357 -107.453408) (xy 183.329697 -107.445274) (xy 183.381678 -107.445272) (xy 183.433018 -107.453402)
			(xy 183.482455 -107.469463) (xy 183.52877 -107.493061) (xy 183.570824 -107.523613) (xy 183.60758 -107.560368)
			(xy 183.638134 -107.602421) (xy 183.661733 -107.648735) (xy 183.677796 -107.698171) (xy 183.685927 -107.749512)
			(xy 183.68645 -107.775502) (xy 183.685858 -107.803282) (xy 183.676535 -107.858055) (xy 183.667908 -107.884468)
			(xy 183.657494 -107.914694) (xy 183.715914 -107.973114) (xy 183.833516 -107.855512) (xy 183.829452 -107.829604)
			(xy 183.827332 -107.816179) (xy 183.825042 -107.789093) (xy 183.82488 -107.775502) (xy 183.825389 -107.749514)
			(xy 183.83352 -107.698179) (xy 183.84958 -107.648747) (xy 183.873176 -107.602437) (xy 183.903725 -107.560387)
			(xy 183.940477 -107.523634) (xy 183.982525 -107.493083) (xy 184.028834 -107.469486) (xy 184.078265 -107.453423)
			(xy 184.1296 -107.44529) (xy 184.155588 -107.444794) (xy 184.169179 -107.444962) (xy 184.196265 -107.447247)
			(xy 184.20969 -107.449366) (xy 184.235598 -107.45343) (xy 184.353708 -107.33532) (xy 184.295034 -107.2769)
			(xy 184.265062 -107.287568) (xy 184.238528 -107.296236) (xy 184.183496 -107.305551) (xy 184.155588 -107.30611)
			(xy 184.129601 -107.3056) (xy 184.078267 -107.297467) (xy 184.028837 -107.281404) (xy 183.982528 -107.257807)
			(xy 183.940481 -107.227256) (xy 183.903731 -107.190503) (xy 183.873182 -107.148454) (xy 183.849588 -107.102144)
			(xy 183.833528 -107.052713) (xy 183.825399 -107.001379) (xy 183.8254 -106.949404) (xy 183.833532 -106.89807)
			(xy 183.849594 -106.84864) (xy 183.873191 -106.802331) (xy 183.903742 -106.760283) (xy 183.940494 -106.723533)
			(xy 183.982543 -106.692984) (xy 184.028853 -106.669389) (xy 184.078284 -106.653329) (xy 184.129618 -106.645199)
			(xy 184.181592 -106.6452) (xy 184.232927 -106.653331) (xy 184.282357 -106.669393) (xy 184.328666 -106.692989)
			(xy 184.370714 -106.72354) (xy 184.407465 -106.760292) (xy 184.438014 -106.80234) (xy 184.46161 -106.84865)
			(xy 184.47767 -106.89808) (xy 184.485801 -106.949415) (xy 184.486296 -106.975402) (xy 184.485735 -107.003309)
			(xy 184.476413 -107.05834) (xy 184.467754 -107.084876) (xy 184.457086 -107.114848) (xy 184.515506 -107.173522)
			(xy 184.633616 -107.055412) (xy 184.629552 -107.029504) (xy 184.627432 -107.016079) (xy 184.625142 -106.988993)
			(xy 184.62498 -106.975402) (xy 184.625427 -106.950553) (xy 184.632863 -106.901414) (xy 184.647568 -106.853941)
			(xy 184.658 -106.831384) (xy 184.66308 -106.82097) (xy 184.66308 -106.329734) (xy 184.658 -106.31932)
			(xy 184.647573 -106.29676) (xy 184.632855 -106.24929) (xy 184.625412 -106.200151) (xy 184.625411 -106.150452)
			(xy 184.632854 -106.101314) (xy 184.647572 -106.053844) (xy 184.658 -106.031284) (xy 184.66308 -106.02087)
			(xy 184.66308 -101.209348) (xy 184.43448 -100.980748) (xy 180.914548 -100.980748) (xy 180.892935 -101.00153)
			(xy 180.844431 -101.036774) (xy 180.791013 -101.063999) (xy 180.733994 -101.082536) (xy 180.674778 -101.091927)
			(xy 180.6448 -101.092508) (xy 180.616724 -101.092012) (xy 180.561177 -101.083789) (xy 180.507433 -101.067522)
			(xy 180.45665 -101.04356) (xy 180.409923 -101.012421) (xy 180.388768 -100.993956) (xy 180.37429 -100.980748)
			(xy 180.29428 -100.980748) (xy 180.218588 -101.056694) (xy 180.218588 -101.564948) (xy 180.775862 -101.564948)
			(xy 180.779933 -101.509326) (xy 180.792059 -101.454889) (xy 180.811982 -101.402798) (xy 180.839278 -101.354163)
			(xy 180.873364 -101.31002) (xy 180.913513 -101.271311) (xy 180.958871 -101.23886) (xy 181.008471 -101.213359)
			(xy 181.061255 -101.195352) (xy 181.116098 -101.185222) (xy 181.171832 -101.183185) (xy 181.227269 -101.189285)
			(xy 181.281226 -101.203391) (xy 181.332555 -101.225203) (xy 181.380161 -101.254257) (xy 181.423029 -101.289932)
			(xy 181.460246 -101.331469) (xy 181.491019 -101.377982) (xy 181.514691 -101.428479) (xy 181.530759 -101.481886)
			(xy 181.538879 -101.537062) (xy 181.539388 -101.564948) (xy 181.538879 -101.592834) (xy 181.530759 -101.64801)
			(xy 181.514691 -101.701417) (xy 181.491019 -101.751914) (xy 181.460246 -101.798427) (xy 181.423029 -101.839964)
			(xy 181.380161 -101.875639) (xy 181.332555 -101.904693) (xy 181.281226 -101.926505) (xy 181.227269 -101.940611)
			(xy 181.171832 -101.946711) (xy 181.116098 -101.944674) (xy 181.061255 -101.934544) (xy 181.008471 -101.916537)
			(xy 180.958871 -101.891036) (xy 180.913513 -101.858585) (xy 180.873364 -101.819876) (xy 180.839278 -101.775733)
			(xy 180.811982 -101.727098) (xy 180.792059 -101.675007) (xy 180.779933 -101.62057) (xy 180.775862 -101.564948)
			(xy 180.218588 -101.564948) (xy 180.218588 -102.707948) (xy 181.283862 -102.707948) (xy 181.287933 -102.652326)
			(xy 181.300059 -102.597889) (xy 181.319982 -102.545798) (xy 181.347278 -102.497163) (xy 181.381364 -102.45302)
			(xy 181.421513 -102.414311) (xy 181.466871 -102.38186) (xy 181.516471 -102.356359) (xy 181.569255 -102.338352)
			(xy 181.624098 -102.328222) (xy 181.679832 -102.326185) (xy 181.735269 -102.332285) (xy 181.789226 -102.346391)
			(xy 181.840555 -102.368203) (xy 181.888161 -102.397257) (xy 181.931029 -102.432932) (xy 181.968246 -102.474469)
			(xy 181.999019 -102.520982) (xy 182.022691 -102.571479) (xy 182.038759 -102.624886) (xy 182.046879 -102.680062)
			(xy 182.047388 -102.707948) (xy 182.046879 -102.735834) (xy 182.038759 -102.79101) (xy 182.022691 -102.844417)
			(xy 181.999019 -102.894914) (xy 181.968246 -102.941427) (xy 181.931029 -102.982964) (xy 181.888161 -103.018639)
			(xy 181.840555 -103.047693) (xy 181.789226 -103.069505) (xy 181.735269 -103.083611) (xy 181.679832 -103.089711)
			(xy 181.624098 -103.087674) (xy 181.569255 -103.077544) (xy 181.516471 -103.059537) (xy 181.466871 -103.034036)
			(xy 181.421513 -103.001585) (xy 181.381364 -102.962876) (xy 181.347278 -102.918733) (xy 181.319982 -102.870098)
			(xy 181.300059 -102.818007) (xy 181.287933 -102.76357) (xy 181.283862 -102.707948) (xy 180.218588 -102.707948)
			(xy 180.218588 -103.360051) (xy 180.662566 -103.360051) (xy 180.662566 -103.305549) (xy 180.670322 -103.251601)
			(xy 180.685677 -103.199306) (xy 180.708317 -103.149729) (xy 180.737782 -103.103878) (xy 180.773473 -103.062687)
			(xy 180.814662 -103.026994) (xy 180.860511 -102.997527) (xy 180.910088 -102.974884) (xy 180.962382 -102.959526)
			(xy 181.016329 -102.951767) (xy 181.04358 -102.95128) (xy 181.072428 -102.951802) (xy 181.129468 -102.960474)
			(xy 181.184552 -102.977637) (xy 181.236422 -103.002902) (xy 181.283895 -103.03569) (xy 181.325889 -103.075254)
			(xy 181.361444 -103.120692) (xy 181.389751 -103.170967) (xy 181.410162 -103.224931) (xy 181.416706 -103.253032)
			(xy 181.42 -103.266384) (xy 181.432695 -103.290768) (xy 181.45144 -103.310876) (xy 181.474875 -103.325248)
			(xy 181.501296 -103.33284) (xy 181.528785 -103.333101) (xy 181.542182 -103.329994) (xy 181.566306 -103.323951)
			(xy 181.615614 -103.317456) (xy 181.64048 -103.31704) (xy 181.667737 -103.317406) (xy 181.721697 -103.325161)
			(xy 181.774004 -103.340517) (xy 181.823593 -103.363162) (xy 181.869454 -103.392633) (xy 181.910655 -103.428331)
			(xy 181.946355 -103.46953) (xy 181.975829 -103.515389) (xy 181.998476 -103.564977) (xy 182.013835 -103.617283)
			(xy 182.021593 -103.671243) (xy 182.021593 -103.725757) (xy 182.013835 -103.779717) (xy 181.998476 -103.832023)
			(xy 181.975829 -103.881611) (xy 181.946355 -103.92747) (xy 181.910655 -103.968669) (xy 181.869454 -104.004367)
			(xy 181.823593 -104.033838) (xy 181.774004 -104.056483) (xy 181.721697 -104.071839) (xy 181.667737 -104.079594)
			(xy 181.64048 -104.080056) (xy 181.611632 -104.079542) (xy 181.554593 -104.070866) (xy 181.499511 -104.053699)
			(xy 181.447642 -104.028432) (xy 181.40017 -103.995643) (xy 181.358177 -103.956078) (xy 181.322621 -103.910641)
			(xy 181.294313 -103.860367) (xy 181.273899 -103.806404) (xy 181.267354 -103.778304) (xy 181.264083 -103.764944)
			(xy 181.251389 -103.740554) (xy 181.232641 -103.720441) (xy 181.2092 -103.706068) (xy 181.182772 -103.69848)
			(xy 181.155277 -103.698229) (xy 181.141878 -103.701342) (xy 181.117751 -103.707374) (xy 181.068446 -103.713876)
			(xy 181.04358 -103.714296) (xy 181.016329 -103.713833) (xy 180.962382 -103.706074) (xy 180.910088 -103.690716)
			(xy 180.860511 -103.668073) (xy 180.814662 -103.638606) (xy 180.773473 -103.602913) (xy 180.737782 -103.561722)
			(xy 180.708317 -103.515871) (xy 180.685677 -103.466294) (xy 180.670322 -103.413999) (xy 180.662566 -103.360051)
			(xy 180.218588 -103.360051) (xy 180.218588 -105.401443) (xy 182.225444 -105.401443) (xy 182.225444 -105.349469)
			(xy 182.233574 -105.298134) (xy 182.249635 -105.248704) (xy 182.273231 -105.202394) (xy 182.303781 -105.160346)
			(xy 182.340532 -105.123595) (xy 182.38258 -105.093045) (xy 182.42889 -105.069449) (xy 182.47832 -105.053388)
			(xy 182.529655 -105.045258) (xy 182.581629 -105.045258) (xy 182.632964 -105.053388) (xy 182.682394 -105.069449)
			(xy 182.728704 -105.093045) (xy 182.770752 -105.123595) (xy 182.807503 -105.160346) (xy 182.838053 -105.202394)
			(xy 182.861649 -105.248704) (xy 182.87771 -105.298134) (xy 182.88584 -105.349469) (xy 182.88635 -105.375456)
			(xy 182.88584 -105.401443) (xy 183.82539 -105.401443) (xy 183.82539 -105.349469) (xy 183.83352 -105.298134)
			(xy 183.849581 -105.248704) (xy 183.873177 -105.202394) (xy 183.903727 -105.160346) (xy 183.940478 -105.123595)
			(xy 183.982526 -105.093045) (xy 184.028836 -105.069449) (xy 184.078266 -105.053388) (xy 184.129601 -105.045258)
			(xy 184.181575 -105.045258) (xy 184.23291 -105.053388) (xy 184.28234 -105.069449) (xy 184.32865 -105.093045)
			(xy 184.370698 -105.123595) (xy 184.407449 -105.160346) (xy 184.437999 -105.202394) (xy 184.461595 -105.248704)
			(xy 184.477656 -105.298134) (xy 184.485786 -105.349469) (xy 184.486296 -105.375456) (xy 184.485786 -105.401443)
			(xy 184.477656 -105.452778) (xy 184.461595 -105.502208) (xy 184.437999 -105.548518) (xy 184.407449 -105.590566)
			(xy 184.370698 -105.627317) (xy 184.32865 -105.657867) (xy 184.28234 -105.681463) (xy 184.23291 -105.697524)
			(xy 184.181575 -105.705654) (xy 184.129601 -105.705654) (xy 184.078266 -105.697524) (xy 184.028836 -105.681463)
			(xy 183.982526 -105.657867) (xy 183.940478 -105.627317) (xy 183.903727 -105.590566) (xy 183.873177 -105.548518)
			(xy 183.849581 -105.502208) (xy 183.83352 -105.452778) (xy 183.82539 -105.401443) (xy 182.88584 -105.401443)
			(xy 182.87771 -105.452778) (xy 182.861649 -105.502208) (xy 182.838053 -105.548518) (xy 182.807503 -105.590566)
			(xy 182.770752 -105.627317) (xy 182.728704 -105.657867) (xy 182.682394 -105.681463) (xy 182.632964 -105.697524)
			(xy 182.581629 -105.705654) (xy 182.529655 -105.705654) (xy 182.47832 -105.697524) (xy 182.42889 -105.681463)
			(xy 182.38258 -105.657867) (xy 182.340532 -105.627317) (xy 182.303781 -105.590566) (xy 182.273231 -105.548518)
			(xy 182.249635 -105.502208) (xy 182.233574 -105.452778) (xy 182.225444 -105.401443) (xy 180.218588 -105.401443)
			(xy 180.218588 -106.201289) (xy 181.425598 -106.201289) (xy 181.425598 -106.149315) (xy 181.433728 -106.09798)
			(xy 181.449789 -106.04855) (xy 181.473385 -106.00224) (xy 181.503935 -105.960192) (xy 181.540686 -105.923441)
			(xy 181.582734 -105.892891) (xy 181.629044 -105.869295) (xy 181.678474 -105.853234) (xy 181.729809 -105.845104)
			(xy 181.781783 -105.845104) (xy 181.833118 -105.853234) (xy 181.882548 -105.869295) (xy 181.928858 -105.892891)
			(xy 181.970906 -105.923441) (xy 182.007657 -105.960192) (xy 182.038207 -106.00224) (xy 182.061803 -106.04855)
			(xy 182.077864 -106.09798) (xy 182.085994 -106.149315) (xy 182.086504 -106.175302) (xy 182.085994 -106.201289)
			(xy 182.225444 -106.201289) (xy 182.225444 -106.149315) (xy 182.233574 -106.09798) (xy 182.249635 -106.04855)
			(xy 182.273231 -106.00224) (xy 182.303781 -105.960192) (xy 182.340532 -105.923441) (xy 182.38258 -105.892891)
			(xy 182.42889 -105.869295) (xy 182.47832 -105.853234) (xy 182.529655 -105.845104) (xy 182.581629 -105.845104)
			(xy 182.632964 -105.853234) (xy 182.682394 -105.869295) (xy 182.728704 -105.892891) (xy 182.770752 -105.923441)
			(xy 182.807503 -105.960192) (xy 182.838053 -106.00224) (xy 182.861649 -106.04855) (xy 182.87771 -106.09798)
			(xy 182.88584 -106.149315) (xy 182.88635 -106.175302) (xy 182.88584 -106.201289) (xy 182.87771 -106.252624)
			(xy 182.861649 -106.302054) (xy 182.838053 -106.348364) (xy 182.807503 -106.390412) (xy 182.770752 -106.427163)
			(xy 182.728704 -106.457713) (xy 182.682394 -106.481309) (xy 182.632964 -106.49737) (xy 182.581629 -106.5055)
			(xy 182.529655 -106.5055) (xy 182.47832 -106.49737) (xy 182.42889 -106.481309) (xy 182.38258 -106.457713)
			(xy 182.340532 -106.427163) (xy 182.303781 -106.390412) (xy 182.273231 -106.348364) (xy 182.249635 -106.302054)
			(xy 182.233574 -106.252624) (xy 182.225444 -106.201289) (xy 182.085994 -106.201289) (xy 182.077864 -106.252624)
			(xy 182.061803 -106.302054) (xy 182.038207 -106.348364) (xy 182.007657 -106.390412) (xy 181.970906 -106.427163)
			(xy 181.928858 -106.457713) (xy 181.882548 -106.481309) (xy 181.833118 -106.49737) (xy 181.781783 -106.5055)
			(xy 181.729809 -106.5055) (xy 181.678474 -106.49737) (xy 181.629044 -106.481309) (xy 181.582734 -106.457713)
			(xy 181.540686 -106.427163) (xy 181.503935 -106.390412) (xy 181.473385 -106.348364) (xy 181.449789 -106.302054)
			(xy 181.433728 -106.252624) (xy 181.425598 -106.201289) (xy 180.218588 -106.201289) (xy 180.218588 -106.826558)
			(xy 180.043757 -107.001389) (xy 181.425598 -107.001389) (xy 181.425598 -106.949415) (xy 181.433728 -106.89808)
			(xy 181.449789 -106.84865) (xy 181.473385 -106.80234) (xy 181.503935 -106.760292) (xy 181.540686 -106.723541)
			(xy 181.582734 -106.692991) (xy 181.629044 -106.669395) (xy 181.678474 -106.653334) (xy 181.729809 -106.645204)
			(xy 181.781783 -106.645204) (xy 181.833118 -106.653334) (xy 181.882548 -106.669395) (xy 181.928858 -106.692991)
			(xy 181.970906 -106.723541) (xy 182.007657 -106.760292) (xy 182.038207 -106.80234) (xy 182.061803 -106.84865)
			(xy 182.077864 -106.89808) (xy 182.085994 -106.949415) (xy 182.086504 -106.975402) (xy 182.085994 -107.001389)
			(xy 182.225444 -107.001389) (xy 182.225444 -106.949415) (xy 182.233574 -106.89808) (xy 182.249635 -106.84865)
			(xy 182.273231 -106.80234) (xy 182.303781 -106.760292) (xy 182.340532 -106.723541) (xy 182.38258 -106.692991)
			(xy 182.42889 -106.669395) (xy 182.47832 -106.653334) (xy 182.529655 -106.645204) (xy 182.581629 -106.645204)
			(xy 182.632964 -106.653334) (xy 182.682394 -106.669395) (xy 182.728704 -106.692991) (xy 182.770752 -106.723541)
			(xy 182.807503 -106.760292) (xy 182.838053 -106.80234) (xy 182.861649 -106.84865) (xy 182.87771 -106.89808)
			(xy 182.88584 -106.949415) (xy 182.88635 -106.975402) (xy 182.88584 -107.001389) (xy 182.87771 -107.052724)
			(xy 182.861649 -107.102154) (xy 182.838053 -107.148464) (xy 182.807503 -107.190512) (xy 182.770752 -107.227263)
			(xy 182.728704 -107.257813) (xy 182.682394 -107.281409) (xy 182.632964 -107.29747) (xy 182.581629 -107.3056)
			(xy 182.529655 -107.3056) (xy 182.47832 -107.29747) (xy 182.42889 -107.281409) (xy 182.38258 -107.257813)
			(xy 182.340532 -107.227263) (xy 182.303781 -107.190512) (xy 182.273231 -107.148464) (xy 182.249635 -107.102154)
			(xy 182.233574 -107.052724) (xy 182.225444 -107.001389) (xy 182.085994 -107.001389) (xy 182.077864 -107.052724)
			(xy 182.061803 -107.102154) (xy 182.038207 -107.148464) (xy 182.007657 -107.190512) (xy 181.970906 -107.227263)
			(xy 181.928858 -107.257813) (xy 181.882548 -107.281409) (xy 181.833118 -107.29747) (xy 181.781783 -107.3056)
			(xy 181.729809 -107.3056) (xy 181.678474 -107.29747) (xy 181.629044 -107.281409) (xy 181.582734 -107.257813)
			(xy 181.540686 -107.227263) (xy 181.503935 -107.190512) (xy 181.473385 -107.148464) (xy 181.449789 -107.102154)
			(xy 181.433728 -107.052724) (xy 181.425598 -107.001389) (xy 180.043757 -107.001389) (xy 179.888388 -107.156758)
			(xy 179.888388 -107.801489) (xy 180.625498 -107.801489) (xy 180.625498 -107.749515) (xy 180.633628 -107.69818)
			(xy 180.649689 -107.64875) (xy 180.673285 -107.60244) (xy 180.703835 -107.560392) (xy 180.740586 -107.523641)
			(xy 180.782634 -107.493091) (xy 180.828944 -107.469495) (xy 180.878374 -107.453434) (xy 180.929709 -107.445304)
			(xy 180.981683 -107.445304) (xy 181.033018 -107.453434) (xy 181.082448 -107.469495) (xy 181.128758 -107.493091)
			(xy 181.170806 -107.523641) (xy 181.207557 -107.560392) (xy 181.238107 -107.60244) (xy 181.261703 -107.64875)
			(xy 181.277764 -107.69818) (xy 181.285894 -107.749515) (xy 181.286404 -107.775502) (xy 181.285894 -107.801489)
			(xy 181.425598 -107.801489) (xy 181.425598 -107.749515) (xy 181.433728 -107.69818) (xy 181.449789 -107.64875)
			(xy 181.473385 -107.60244) (xy 181.503935 -107.560392) (xy 181.540686 -107.523641) (xy 181.582734 -107.493091)
			(xy 181.629044 -107.469495) (xy 181.678474 -107.453434) (xy 181.729809 -107.445304) (xy 181.781783 -107.445304)
			(xy 181.833118 -107.453434) (xy 181.882548 -107.469495) (xy 181.928858 -107.493091) (xy 181.970906 -107.523641)
			(xy 182.007657 -107.560392) (xy 182.038207 -107.60244) (xy 182.061803 -107.64875) (xy 182.077864 -107.69818)
			(xy 182.085994 -107.749515) (xy 182.086504 -107.775502) (xy 182.085994 -107.801489) (xy 182.225444 -107.801489)
			(xy 182.225444 -107.749515) (xy 182.233574 -107.69818) (xy 182.249635 -107.64875) (xy 182.273231 -107.60244)
			(xy 182.303781 -107.560392) (xy 182.340532 -107.523641) (xy 182.38258 -107.493091) (xy 182.42889 -107.469495)
			(xy 182.47832 -107.453434) (xy 182.529655 -107.445304) (xy 182.581629 -107.445304) (xy 182.632964 -107.453434)
			(xy 182.682394 -107.469495) (xy 182.728704 -107.493091) (xy 182.770752 -107.523641) (xy 182.807503 -107.560392)
			(xy 182.838053 -107.60244) (xy 182.861649 -107.64875) (xy 182.87771 -107.69818) (xy 182.88584 -107.749515)
			(xy 182.88635 -107.775502) (xy 182.88584 -107.801489) (xy 182.87771 -107.852824) (xy 182.861649 -107.902254)
			(xy 182.838053 -107.948564) (xy 182.807503 -107.990612) (xy 182.770752 -108.027363) (xy 182.728704 -108.057913)
			(xy 182.682394 -108.081509) (xy 182.632964 -108.09757) (xy 182.581629 -108.1057) (xy 182.529655 -108.1057)
			(xy 182.47832 -108.09757) (xy 182.42889 -108.081509) (xy 182.38258 -108.057913) (xy 182.340532 -108.027363)
			(xy 182.303781 -107.990612) (xy 182.273231 -107.948564) (xy 182.249635 -107.902254) (xy 182.233574 -107.852824)
			(xy 182.225444 -107.801489) (xy 182.085994 -107.801489) (xy 182.077864 -107.852824) (xy 182.061803 -107.902254)
			(xy 182.038207 -107.948564) (xy 182.007657 -107.990612) (xy 181.970906 -108.027363) (xy 181.928858 -108.057913)
			(xy 181.882548 -108.081509) (xy 181.833118 -108.09757) (xy 181.781783 -108.1057) (xy 181.729809 -108.1057)
			(xy 181.678474 -108.09757) (xy 181.629044 -108.081509) (xy 181.582734 -108.057913) (xy 181.540686 -108.027363)
			(xy 181.503935 -107.990612) (xy 181.473385 -107.948564) (xy 181.449789 -107.902254) (xy 181.433728 -107.852824)
			(xy 181.425598 -107.801489) (xy 181.285894 -107.801489) (xy 181.277764 -107.852824) (xy 181.261703 -107.902254)
			(xy 181.238107 -107.948564) (xy 181.207557 -107.990612) (xy 181.170806 -108.027363) (xy 181.128758 -108.057913)
			(xy 181.082448 -108.081509) (xy 181.033018 -108.09757) (xy 180.981683 -108.1057) (xy 180.929709 -108.1057)
			(xy 180.878374 -108.09757) (xy 180.828944 -108.081509) (xy 180.782634 -108.057913) (xy 180.740586 -108.027363)
			(xy 180.703835 -107.990612) (xy 180.673285 -107.948564) (xy 180.649689 -107.902254) (xy 180.633628 -107.852824)
			(xy 180.625498 -107.801489) (xy 179.888388 -107.801489) (xy 179.888388 -108.601335) (xy 181.425598 -108.601335)
			(xy 181.425598 -108.549361) (xy 181.433728 -108.498026) (xy 181.449789 -108.448596) (xy 181.473385 -108.402286)
			(xy 181.503935 -108.360238) (xy 181.540686 -108.323487) (xy 181.582734 -108.292937) (xy 181.629044 -108.269341)
			(xy 181.678474 -108.25328) (xy 181.729809 -108.24515) (xy 181.781783 -108.24515) (xy 181.833118 -108.25328)
			(xy 181.882548 -108.269341) (xy 181.928858 -108.292937) (xy 181.970906 -108.323487) (xy 182.007657 -108.360238)
			(xy 182.038207 -108.402286) (xy 182.061803 -108.448596) (xy 182.077864 -108.498026) (xy 182.085994 -108.549361)
			(xy 182.086504 -108.575348) (xy 182.085994 -108.601335) (xy 182.077864 -108.65267) (xy 182.061803 -108.7021)
			(xy 182.038207 -108.74841) (xy 182.007657 -108.790458) (xy 181.970906 -108.827209) (xy 181.928858 -108.857759)
			(xy 181.882548 -108.881355) (xy 181.833118 -108.897416) (xy 181.781783 -108.905546) (xy 181.729809 -108.905546)
			(xy 181.678474 -108.897416) (xy 181.629044 -108.881355) (xy 181.582734 -108.857759) (xy 181.540686 -108.827209)
			(xy 181.503935 -108.790458) (xy 181.473385 -108.74841) (xy 181.449789 -108.7021) (xy 181.433728 -108.65267)
			(xy 181.425598 -108.601335) (xy 179.888388 -108.601335) (xy 179.888388 -109.401435) (xy 180.625498 -109.401435)
			(xy 180.625498 -109.349461) (xy 180.633628 -109.298126) (xy 180.649689 -109.248696) (xy 180.673285 -109.202386)
			(xy 180.703835 -109.160338) (xy 180.740586 -109.123587) (xy 180.782634 -109.093037) (xy 180.828944 -109.069441)
			(xy 180.878374 -109.05338) (xy 180.929709 -109.04525) (xy 180.981683 -109.04525) (xy 181.033018 -109.05338)
			(xy 181.082448 -109.069441) (xy 181.128758 -109.093037) (xy 181.170806 -109.123587) (xy 181.207557 -109.160338)
			(xy 181.238107 -109.202386) (xy 181.261703 -109.248696) (xy 181.277764 -109.298126) (xy 181.285894 -109.349461)
			(xy 181.286404 -109.375448) (xy 181.285894 -109.401435) (xy 181.277764 -109.45277) (xy 181.261703 -109.5022)
			(xy 181.238107 -109.54851) (xy 181.207557 -109.590558) (xy 181.170806 -109.627309) (xy 181.128758 -109.657859)
			(xy 181.082448 -109.681455) (xy 181.033018 -109.697516) (xy 180.981683 -109.705646) (xy 180.929709 -109.705646)
			(xy 180.878374 -109.697516) (xy 180.828944 -109.681455) (xy 180.782634 -109.657859) (xy 180.740586 -109.627309)
			(xy 180.703835 -109.590558) (xy 180.673285 -109.54851) (xy 180.649689 -109.5022) (xy 180.633628 -109.45277)
			(xy 180.625498 -109.401435) (xy 179.888388 -109.401435) (xy 179.888388 -110.328202) (xy 180.04028 -110.480348)
			(xy 181.20868 -110.480348)
		)
		(stroke
			(width 0)
			(type solid)
		)
		(fill yes)
		(layer "In4.Cu")
		(net "P3V3_AUX_FPGA_VCCIO3")
	)
	(gr_poly
		(pts
			(xy 272.69948 -78.501748) (xy 272.69948 -64.988948) (xy 272.20037 -64.489838) (xy 269.584678 -64.489838)
			(xy 269.191486 -64.652652) (xy 269.162357 -64.663994) (xy 269.101071 -64.676269) (xy 269.06982 -64.677036)
			(xy 250.964446 -64.677036) (xy 249.296585 -66.3448) (xy 263.172954 -66.3448) (xy 263.177025 -66.289178)
			(xy 263.189151 -66.234741) (xy 263.209074 -66.18265) (xy 263.23637 -66.134015) (xy 263.270456 -66.089872)
			(xy 263.310605 -66.051163) (xy 263.355963 -66.018712) (xy 263.405563 -65.993211) (xy 263.458347 -65.975204)
			(xy 263.51319 -65.965074) (xy 263.568924 -65.963037) (xy 263.624361 -65.969137) (xy 263.678318 -65.983243)
			(xy 263.729647 -66.005055) (xy 263.777253 -66.034109) (xy 263.820121 -66.069784) (xy 263.857338 -66.111321)
			(xy 263.888111 -66.157834) (xy 263.911783 -66.208331) (xy 263.927851 -66.261738) (xy 263.935971 -66.316914)
			(xy 263.93648 -66.3448) (xy 263.935971 -66.372686) (xy 263.927851 -66.427862) (xy 263.911783 -66.481269)
			(xy 263.888111 -66.531766) (xy 263.857338 -66.578279) (xy 263.820121 -66.619816) (xy 263.777253 -66.655491)
			(xy 263.729647 -66.684545) (xy 263.678318 -66.706357) (xy 263.624361 -66.720463) (xy 263.568924 -66.726563)
			(xy 263.51319 -66.724526) (xy 263.458347 -66.714396) (xy 263.405563 -66.696389) (xy 263.355963 -66.670888)
			(xy 263.310605 -66.638437) (xy 263.270456 -66.599728) (xy 263.23637 -66.555585) (xy 263.209074 -66.50695)
			(xy 263.189151 -66.454859) (xy 263.177025 -66.400422) (xy 263.172954 -66.3448) (xy 249.296585 -66.3448)
			(xy 248.552321 -67.08902) (xy 261.67029 -67.08902) (xy 261.674361 -67.033398) (xy 261.686487 -66.978961)
			(xy 261.70641 -66.92687) (xy 261.733706 -66.878235) (xy 261.767792 -66.834092) (xy 261.807941 -66.795383)
			(xy 261.853299 -66.762932) (xy 261.902899 -66.737431) (xy 261.955683 -66.719424) (xy 262.010526 -66.709294)
			(xy 262.06626 -66.707257) (xy 262.121697 -66.713357) (xy 262.175654 -66.727463) (xy 262.226983 -66.749275)
			(xy 262.274589 -66.778329) (xy 262.317457 -66.814004) (xy 262.354674 -66.855541) (xy 262.385447 -66.902054)
			(xy 262.409119 -66.952551) (xy 262.425187 -67.005958) (xy 262.433307 -67.061134) (xy 262.433816 -67.08902)
			(xy 262.433307 -67.116906) (xy 262.425187 -67.172082) (xy 262.409119 -67.225489) (xy 262.385447 -67.275986)
			(xy 262.354674 -67.322499) (xy 262.317457 -67.364036) (xy 262.274589 -67.399711) (xy 262.226983 -67.428765)
			(xy 262.175654 -67.450577) (xy 262.121697 -67.464683) (xy 262.06626 -67.470783) (xy 262.010526 -67.468746)
			(xy 261.955683 -67.458616) (xy 261.902899 -67.440609) (xy 261.853299 -67.415108) (xy 261.807941 -67.382657)
			(xy 261.767792 -67.343948) (xy 261.733706 -67.299805) (xy 261.70641 -67.25117) (xy 261.686487 -67.199079)
			(xy 261.674361 -67.144642) (xy 261.67029 -67.08902) (xy 248.552321 -67.08902) (xy 247.434148 -68.207128)
			(xy 248.911362 -68.207128) (xy 248.915433 -68.151506) (xy 248.927559 -68.097069) (xy 248.947482 -68.044978)
			(xy 248.974778 -67.996343) (xy 249.008864 -67.9522) (xy 249.049013 -67.913491) (xy 249.094371 -67.88104)
			(xy 249.143971 -67.855539) (xy 249.196755 -67.837532) (xy 249.251598 -67.827402) (xy 249.307332 -67.825365)
			(xy 249.362769 -67.831465) (xy 249.416726 -67.845571) (xy 249.468055 -67.867383) (xy 249.515661 -67.896437)
			(xy 249.558529 -67.932112) (xy 249.595746 -67.973649) (xy 249.626519 -68.020162) (xy 249.650191 -68.070659)
			(xy 249.666259 -68.124066) (xy 249.674379 -68.179242) (xy 249.674888 -68.207128) (xy 249.674379 -68.235014)
			(xy 249.666259 -68.29019) (xy 249.650191 -68.343597) (xy 249.626519 -68.394094) (xy 249.595746 -68.440607)
			(xy 249.558529 -68.482144) (xy 249.515661 -68.517819) (xy 249.468055 -68.546873) (xy 249.416726 -68.568685)
			(xy 249.362769 -68.582791) (xy 249.307332 -68.588891) (xy 249.251598 -68.586854) (xy 249.196755 -68.576724)
			(xy 249.143971 -68.558717) (xy 249.094371 -68.533216) (xy 249.049013 -68.500765) (xy 249.008864 -68.462056)
			(xy 248.974778 -68.417913) (xy 248.947482 -68.369278) (xy 248.927559 -68.317187) (xy 248.915433 -68.26275)
			(xy 248.911362 -68.207128) (xy 247.434148 -68.207128) (xy 246.61368 -69.027548) (xy 246.61368 -71.652384)
			(xy 247.39854 -71.652384) (xy 247.398982 -71.625711) (xy 247.406426 -71.572887) (xy 247.421154 -71.521615)
			(xy 247.442878 -71.472893) (xy 247.471175 -71.42767) (xy 247.505494 -71.386829) (xy 247.525032 -71.368666)
			(xy 247.535357 -71.35882) (xy 247.550505 -71.334654) (xy 247.558383 -71.307243) (xy 247.558378 -71.278722)
			(xy 247.550491 -71.251314) (xy 247.535335 -71.227153) (xy 247.525032 -71.217282) (xy 247.505486 -71.199126)
			(xy 247.471158 -71.15829) (xy 247.442856 -71.113068) (xy 247.421133 -71.064343) (xy 247.406413 -71.013066)
			(xy 247.398983 -70.960238) (xy 247.39854 -70.933564) (xy 247.398922 -70.906308) (xy 247.406685 -70.852352)
			(xy 247.422048 -70.800049) (xy 247.444698 -70.750466) (xy 247.474174 -70.70461) (xy 247.509876 -70.663417)
			(xy 247.551078 -70.627724) (xy 247.59694 -70.598258) (xy 247.646528 -70.575618) (xy 247.698834 -70.560267)
			(xy 247.752792 -70.552516) (xy 247.780048 -70.552056) (xy 247.806286 -70.552464) (xy 247.858265 -70.559667)
			(xy 247.908765 -70.57393) (xy 247.956831 -70.594984) (xy 248.001557 -70.622431) (xy 248.042096 -70.655752)
			(xy 248.06021 -70.674738) (xy 248.067739 -70.68211) (xy 248.087024 -70.690541) (xy 248.108072 -70.690541)
			(xy 248.127357 -70.68211) (xy 248.134886 -70.674738) (xy 248.160032 -70.649846) (xy 248.170378 -70.64002)
			(xy 248.185524 -70.615848) (xy 248.1934 -70.588432) (xy 248.193392 -70.559907) (xy 248.185499 -70.532495)
			(xy 248.170338 -70.508333) (xy 248.160032 -70.498462) (xy 248.140476 -70.480316) (xy 248.106149 -70.439478)
			(xy 248.077849 -70.394254) (xy 248.056128 -70.345527) (xy 248.04141 -70.294248) (xy 248.033982 -70.241419)
			(xy 248.03354 -70.214744) (xy 248.034026 -70.187493) (xy 248.041782 -70.133545) (xy 248.057137 -70.08125)
			(xy 248.079779 -70.031673) (xy 248.109245 -69.985823) (xy 248.144936 -69.944632) (xy 248.186127 -69.908941)
			(xy 248.231977 -69.879475) (xy 248.281554 -69.856833) (xy 248.333849 -69.841478) (xy 248.387797 -69.833722)
			(xy 248.442299 -69.833722) (xy 248.496247 -69.841478) (xy 248.548542 -69.856833) (xy 248.598119 -69.879475)
			(xy 248.643969 -69.908941) (xy 248.68516 -69.944632) (xy 248.720851 -69.985823) (xy 248.750317 -70.031673)
			(xy 248.772959 -70.08125) (xy 248.788314 -70.133545) (xy 248.79607 -70.187493) (xy 248.796556 -70.214744)
			(xy 248.796067 -70.241415) (xy 248.788632 -70.294237) (xy 248.773914 -70.345509) (xy 248.752199 -70.394231)
			(xy 248.72391 -70.439455) (xy 248.689599 -70.480298) (xy 248.670064 -70.498462) (xy 248.659811 -70.508377)
			(xy 248.644661 -70.532524) (xy 248.636774 -70.559917) (xy 248.636765 -70.588422) (xy 248.644635 -70.61582)
			(xy 248.659771 -70.639975) (xy 248.670064 -70.649846) (xy 248.689565 -70.668046) (xy 248.72388 -70.708882)
			(xy 248.752172 -70.7541) (xy 248.773889 -70.802819) (xy 248.788608 -70.854087) (xy 248.796041 -70.906906)
			(xy 248.796045 -70.960246) (xy 248.788618 -71.013066) (xy 248.773905 -71.064336) (xy 248.752194 -71.113057)
			(xy 248.723908 -71.158279) (xy 248.689599 -71.199119) (xy 248.670064 -71.217282) (xy 248.659791 -71.227178)
			(xy 248.644642 -71.25133) (xy 248.636757 -71.278728) (xy 248.636752 -71.307238) (xy 248.644627 -71.334638)
			(xy 248.659769 -71.358795) (xy 248.670064 -71.368666) (xy 248.689584 -71.386849) (xy 248.723915 -71.427679)
			(xy 248.75222 -71.472895) (xy 248.773947 -71.521615) (xy 248.788673 -71.572887) (xy 248.796109 -71.625712)
			(xy 248.796556 -71.652384) (xy 248.796094 -71.679035) (xy 248.788674 -71.731818) (xy 248.773975 -71.783053)
			(xy 248.763536 -71.807578) (xy 248.757906 -71.821707) (xy 248.754301 -71.85189) (xy 248.759721 -71.8818)
			(xy 248.773687 -71.9088) (xy 248.794967 -71.930506) (xy 248.821683 -71.945005) (xy 248.85148 -71.951017)
			(xy 248.86666 -71.950072) (xy 248.90476 -71.94804) (xy 248.932014 -71.948493) (xy 248.985968 -71.956245)
			(xy 249.038269 -71.971599) (xy 249.087852 -71.99424) (xy 249.133708 -72.023708) (xy 249.174902 -72.059404)
			(xy 249.210596 -72.100599) (xy 249.240064 -72.146455) (xy 249.262704 -72.196039) (xy 249.278056 -72.24834)
			(xy 249.285808 -72.302294) (xy 249.286268 -72.329548) (xy 249.285779 -72.356918) (xy 249.277968 -72.411096)
			(xy 249.262485 -72.463599) (xy 249.239648 -72.513346) (xy 249.209927 -72.559314) (xy 249.192288 -72.580246)
			(xy 249.183006 -72.591539) (xy 249.170836 -72.61811) (xy 249.166673 -72.647036) (xy 249.170856 -72.67596)
			(xy 249.183045 -72.702522) (xy 249.192288 -72.71385) (xy 249.209975 -72.734745) (xy 249.239697 -72.78072)
			(xy 249.262538 -72.830472) (xy 249.27803 -72.88298) (xy 249.285854 -72.937163) (xy 249.285849 -72.991909)
			(xy 249.278015 -73.046091) (xy 249.262513 -73.098596) (xy 249.239662 -73.148344) (xy 249.209931 -73.194313)
			(xy 249.192288 -73.215246) (xy 249.183006 -73.226539) (xy 249.170836 -73.25311) (xy 249.166673 -73.282036)
			(xy 249.170856 -73.31096) (xy 249.183045 -73.337522) (xy 249.192288 -73.34885) (xy 249.209975 -73.369745)
			(xy 249.239697 -73.41572) (xy 249.262538 -73.465472) (xy 249.27803 -73.51798) (xy 249.285854 -73.572163)
			(xy 249.28585 -73.620122) (xy 252.282704 -73.620122) (xy 252.286775 -73.5645) (xy 252.298901 -73.510063)
			(xy 252.318824 -73.457972) (xy 252.34612 -73.409337) (xy 252.380206 -73.365194) (xy 252.420355 -73.326485)
			(xy 252.465713 -73.294034) (xy 252.515313 -73.268533) (xy 252.568097 -73.250526) (xy 252.62294 -73.240396)
			(xy 252.678674 -73.238359) (xy 252.734111 -73.244459) (xy 252.788068 -73.258565) (xy 252.839397 -73.280377)
			(xy 252.887003 -73.309431) (xy 252.929871 -73.345106) (xy 252.967088 -73.386643) (xy 252.997861 -73.433156)
			(xy 253.021533 -73.483653) (xy 253.037601 -73.53706) (xy 253.045721 -73.592236) (xy 253.04623 -73.620122)
			(xy 253.045721 -73.648008) (xy 253.037601 -73.703184) (xy 253.021533 -73.756591) (xy 252.997861 -73.807088)
			(xy 252.967088 -73.853601) (xy 252.929871 -73.895138) (xy 252.887003 -73.930813) (xy 252.839397 -73.959867)
			(xy 252.788068 -73.981679) (xy 252.734111 -73.995785) (xy 252.678674 -74.001885) (xy 252.62294 -73.999848)
			(xy 252.568097 -73.989718) (xy 252.515313 -73.971711) (xy 252.465713 -73.94621) (xy 252.420355 -73.913759)
			(xy 252.380206 -73.87505) (xy 252.34612 -73.830907) (xy 252.318824 -73.782272) (xy 252.298901 -73.730181)
			(xy 252.286775 -73.675744) (xy 252.282704 -73.620122) (xy 249.28585 -73.620122) (xy 249.285849 -73.626909)
			(xy 249.278015 -73.681091) (xy 249.262513 -73.733596) (xy 249.239662 -73.783344) (xy 249.209931 -73.829313)
			(xy 249.192288 -73.850246) (xy 249.183006 -73.861539) (xy 249.170836 -73.88811) (xy 249.166673 -73.917036)
			(xy 249.170856 -73.94596) (xy 249.183045 -73.972522) (xy 249.192288 -73.98385) (xy 249.209915 -74.004792)
			(xy 249.239629 -74.050762) (xy 249.261619 -74.098658) (xy 260.18693 -74.098658) (xy 260.191001 -74.043036)
			(xy 260.203127 -73.988599) (xy 260.22305 -73.936508) (xy 260.250346 -73.887873) (xy 260.284432 -73.84373)
			(xy 260.324581 -73.805021) (xy 260.369939 -73.77257) (xy 260.419539 -73.747069) (xy 260.472323 -73.729062)
			(xy 260.527166 -73.718932) (xy 260.5829 -73.716895) (xy 260.638337 -73.722995) (xy 260.692294 -73.737101)
			(xy 260.743623 -73.758913) (xy 260.791229 -73.787967) (xy 260.834097 -73.823642) (xy 260.871314 -73.865179)
			(xy 260.902087 -73.911692) (xy 260.925759 -73.962189) (xy 260.932964 -73.986136) (xy 261.8265 -73.986136)
			(xy 261.830571 -73.930514) (xy 261.842697 -73.876077) (xy 261.86262 -73.823986) (xy 261.889916 -73.775351)
			(xy 261.924002 -73.731208) (xy 261.964151 -73.692499) (xy 262.009509 -73.660048) (xy 262.059109 -73.634547)
			(xy 262.111893 -73.61654) (xy 262.166736 -73.60641) (xy 262.22247 -73.604373) (xy 262.277907 -73.610473)
			(xy 262.331864 -73.624579) (xy 262.383193 -73.646391) (xy 262.430799 -73.675445) (xy 262.473667 -73.71112)
			(xy 262.510884 -73.752657) (xy 262.541657 -73.79917) (xy 262.565329 -73.849667) (xy 262.581397 -73.903074)
			(xy 262.589517 -73.95825) (xy 262.590026 -73.986136) (xy 262.589517 -74.014022) (xy 262.581397 -74.069198)
			(xy 262.565329 -74.122605) (xy 262.541657 -74.173102) (xy 262.510884 -74.219615) (xy 262.473667 -74.261152)
			(xy 262.430799 -74.296827) (xy 262.383193 -74.325881) (xy 262.331864 -74.347693) (xy 262.277907 -74.361799)
			(xy 262.22247 -74.367899) (xy 262.166736 -74.365862) (xy 262.111893 -74.355732) (xy 262.059109 -74.337725)
			(xy 262.009509 -74.312224) (xy 261.964151 -74.279773) (xy 261.924002 -74.241064) (xy 261.889916 -74.196921)
			(xy 261.86262 -74.148286) (xy 261.842697 -74.096195) (xy 261.830571 -74.041758) (xy 261.8265 -73.986136)
			(xy 260.932964 -73.986136) (xy 260.941827 -74.015596) (xy 260.949947 -74.070772) (xy 260.950456 -74.098658)
			(xy 260.949947 -74.126544) (xy 260.941827 -74.18172) (xy 260.925759 -74.235127) (xy 260.902087 -74.285624)
			(xy 260.871314 -74.332137) (xy 260.834097 -74.373674) (xy 260.791229 -74.409349) (xy 260.743623 -74.438403)
			(xy 260.692294 -74.460215) (xy 260.638337 -74.474321) (xy 260.5829 -74.480421) (xy 260.527166 -74.478384)
			(xy 260.472323 -74.468254) (xy 260.419539 -74.450247) (xy 260.369939 -74.424746) (xy 260.324581 -74.392295)
			(xy 260.284432 -74.353586) (xy 260.250346 -74.309443) (xy 260.22305 -74.260808) (xy 260.203127 -74.208717)
			(xy 260.191001 -74.15428) (xy 260.18693 -74.098658) (xy 249.261619 -74.098658) (xy 249.262468 -74.100507)
			(xy 249.277961 -74.153005) (xy 249.285793 -74.207179) (xy 249.286268 -74.234548) (xy 249.285867 -74.261802)
			(xy 249.278103 -74.315755) (xy 249.262739 -74.368054) (xy 249.24009 -74.417634) (xy 249.210615 -74.463486)
			(xy 249.174914 -74.504677) (xy 249.133715 -74.540368) (xy 249.087857 -74.569832) (xy 249.038271 -74.59247)
			(xy 248.985969 -74.607821) (xy 248.932014 -74.615573) (xy 248.90476 -74.616056) (xy 248.893495 -74.616003)
			(xy 248.871001 -74.614732) (xy 248.859802 -74.613516) (xy 248.846201 -74.612398) (xy 248.819238 -74.616521)
			(xy 248.79433 -74.627641) (xy 248.773259 -74.644963) (xy 248.757532 -74.667249) (xy 248.748272 -74.692906)
			(xy 248.746141 -74.7201) (xy 248.751293 -74.746886) (xy 248.752552 -74.74966) (xy 258.981954 -74.74966)
			(xy 258.986025 -74.694038) (xy 258.998151 -74.639601) (xy 259.018074 -74.58751) (xy 259.04537 -74.538875)
			(xy 259.079456 -74.494732) (xy 259.119605 -74.456023) (xy 259.164963 -74.423572) (xy 259.214563 -74.398071)
			(xy 259.267347 -74.380064) (xy 259.32219 -74.369934) (xy 259.377924 -74.367897) (xy 259.433361 -74.373997)
			(xy 259.487318 -74.388103) (xy 259.538647 -74.409915) (xy 259.586253 -74.438969) (xy 259.629121 -74.474644)
			(xy 259.666338 -74.516181) (xy 259.697111 -74.562694) (xy 259.720783 -74.613191) (xy 259.736851 -74.666598)
			(xy 259.744971 -74.721774) (xy 259.74548 -74.74966) (xy 259.744971 -74.777546) (xy 259.736851 -74.832722)
			(xy 259.720783 -74.886129) (xy 259.697111 -74.936626) (xy 259.666338 -74.983139) (xy 259.629121 -75.024676)
			(xy 259.586253 -75.060351) (xy 259.538647 -75.089405) (xy 259.487318 -75.111217) (xy 259.433361 -75.125323)
			(xy 259.377924 -75.131423) (xy 259.32219 -75.129386) (xy 259.267347 -75.119256) (xy 259.214563 -75.101249)
			(xy 259.164963 -75.075748) (xy 259.119605 -75.043297) (xy 259.079456 -75.004588) (xy 259.04537 -74.960445)
			(xy 259.018074 -74.91181) (xy 258.998151 -74.859719) (xy 258.986025 -74.805282) (xy 258.981954 -74.74966)
			(xy 248.752552 -74.74966) (xy 248.756932 -74.759312) (xy 248.769435 -74.785829) (xy 248.787091 -74.841731)
			(xy 248.79601 -74.899672) (xy 248.796556 -74.928984) (xy 248.796007 -74.956233) (xy 248.788254 -75.010176)
			(xy 248.772903 -75.062466) (xy 248.750268 -75.11204) (xy 248.720807 -75.157888) (xy 248.685123 -75.199077)
			(xy 248.643939 -75.234769) (xy 248.598096 -75.264237) (xy 248.548526 -75.286881) (xy 248.496238 -75.30224)
			(xy 248.442297 -75.310002) (xy 248.415048 -75.310492) (xy 248.387679 -75.31) (xy 248.333501 -75.302189)
			(xy 248.280998 -75.286706) (xy 248.23125 -75.26387) (xy 248.185283 -75.234151) (xy 248.16435 -75.216512)
			(xy 248.153022 -75.207276) (xy 248.126465 -75.1951) (xy 248.097548 -75.190927) (xy 248.068631 -75.1951)
			(xy 248.042074 -75.207276) (xy 248.030746 -75.216512) (xy 248.009809 -75.234145) (xy 247.963837 -75.263857)
			(xy 247.914091 -75.286694) (xy 247.861592 -75.302187) (xy 247.807417 -75.310017) (xy 247.780048 -75.310492)
			(xy 247.752792 -75.310064) (xy 247.698833 -75.302313) (xy 247.646527 -75.28696) (xy 247.596939 -75.264319)
			(xy 247.551078 -75.234851) (xy 247.509878 -75.199156) (xy 247.474177 -75.15796) (xy 247.444704 -75.112103)
			(xy 247.422057 -75.062518) (xy 247.406698 -75.010214) (xy 247.398939 -74.956256) (xy 247.398939 -74.901744)
			(xy 247.406698 -74.847786) (xy 247.422057 -74.795482) (xy 247.444704 -74.745897) (xy 247.474177 -74.70004)
			(xy 247.509878 -74.658844) (xy 247.551078 -74.623149) (xy 247.596939 -74.593681) (xy 247.646527 -74.57104)
			(xy 247.698833 -74.555687) (xy 247.752792 -74.547936) (xy 247.780048 -74.547476) (xy 247.807418 -74.547954)
			(xy 247.861597 -74.555766) (xy 247.914101 -74.571251) (xy 247.963848 -74.594091) (xy 248.009815 -74.623815)
			(xy 248.030746 -74.641456) (xy 248.042074 -74.650692) (xy 248.068631 -74.662868) (xy 248.097548 -74.667041)
			(xy 248.126465 -74.662868) (xy 248.153022 -74.650692) (xy 248.16435 -74.641456) (xy 248.185284 -74.62382)
			(xy 248.231257 -74.594109) (xy 248.281004 -74.571273) (xy 248.333504 -74.555781) (xy 248.387679 -74.547951)
			(xy 248.415048 -74.547476) (xy 248.426313 -74.547528) (xy 248.448807 -74.5488) (xy 248.460006 -74.550016)
			(xy 248.473603 -74.551239) (xy 248.500583 -74.547112) (xy 248.525505 -74.535982) (xy 248.546585 -74.518644)
			(xy 248.562316 -74.496339) (xy 248.571573 -74.470663) (xy 248.573693 -74.443451) (xy 248.568525 -74.416651)
			(xy 248.562876 -74.40422) (xy 248.550385 -74.377698) (xy 248.532724 -74.321799) (xy 248.523801 -74.263859)
			(xy 248.523252 -74.234548) (xy 248.523734 -74.207178) (xy 248.531546 -74.152999) (xy 248.54703 -74.100496)
			(xy 248.569869 -74.050749) (xy 248.599591 -74.004782) (xy 248.617232 -73.98385) (xy 248.62642 -73.972487)
			(xy 248.638599 -73.945942) (xy 248.642779 -73.917036) (xy 248.63862 -73.888128) (xy 248.62646 -73.861574)
			(xy 248.617232 -73.850246) (xy 248.599638 -73.829275) (xy 248.569911 -73.783314) (xy 248.547063 -73.733574)
			(xy 248.531562 -73.681078) (xy 248.523729 -73.626905) (xy 248.523724 -73.572168) (xy 248.531547 -73.517993)
			(xy 248.547037 -73.465494) (xy 248.569876 -73.415749) (xy 248.599595 -73.369783) (xy 248.617232 -73.34885)
			(xy 248.62642 -73.337487) (xy 248.638599 -73.310942) (xy 248.642779 -73.282036) (xy 248.63862 -73.253128)
			(xy 248.62646 -73.226574) (xy 248.617232 -73.215246) (xy 248.599638 -73.194275) (xy 248.569911 -73.148314)
			(xy 248.547063 -73.098574) (xy 248.531562 -73.046078) (xy 248.523729 -72.991905) (xy 248.523724 -72.937168)
			(xy 248.531547 -72.882993) (xy 248.547037 -72.830494) (xy 248.569876 -72.780749) (xy 248.599595 -72.734783)
			(xy 248.617232 -72.71385) (xy 248.62642 -72.702487) (xy 248.638599 -72.675942) (xy 248.642779 -72.647036)
			(xy 248.63862 -72.618128) (xy 248.62646 -72.591574) (xy 248.617232 -72.580246) (xy 248.599606 -72.559303)
			(xy 248.569891 -72.513334) (xy 248.547052 -72.463589) (xy 248.531558 -72.411091) (xy 248.523727 -72.356917)
			(xy 248.523252 -72.329548) (xy 248.52369 -72.302896) (xy 248.53112 -72.250113) (xy 248.545828 -72.198878)
			(xy 248.556272 -72.174354) (xy 248.561856 -72.160208) (xy 248.565466 -72.130032) (xy 248.560054 -72.100128)
			(xy 248.546096 -72.073132) (xy 248.524823 -72.051428) (xy 248.498114 -72.036929) (xy 248.468324 -72.030916)
			(xy 248.453148 -72.03186) (xy 248.415048 -72.033892) (xy 248.387679 -72.0334) (xy 248.333501 -72.025589)
			(xy 248.280998 -72.010106) (xy 248.23125 -71.98727) (xy 248.185283 -71.957551) (xy 248.16435 -71.939912)
			(xy 248.153022 -71.930676) (xy 248.126465 -71.9185) (xy 248.097548 -71.914327) (xy 248.068631 -71.9185)
			(xy 248.042074 -71.930676) (xy 248.030746 -71.939912) (xy 248.009809 -71.957545) (xy 247.963837 -71.987257)
			(xy 247.914091 -72.010094) (xy 247.861592 -72.025587) (xy 247.807417 -72.033417) (xy 247.780048 -72.033892)
			(xy 247.752796 -72.0334) (xy 247.698845 -72.025649) (xy 247.646547 -72.010298) (xy 247.596966 -71.98766)
			(xy 247.551111 -71.958196) (xy 247.509918 -71.922505) (xy 247.474223 -71.881314) (xy 247.444755 -71.835463)
			(xy 247.422113 -71.785883) (xy 247.406758 -71.733586) (xy 247.399002 -71.679636) (xy 247.39854 -71.652384)
			(xy 246.61368 -71.652384) (xy 246.61368 -74.610468) (xy 248.271792 -76.268834) (xy 249.860685 -76.926948)
			(xy 257.560062 -76.926948) (xy 257.564133 -76.871326) (xy 257.576259 -76.816889) (xy 257.596182 -76.764798)
			(xy 257.623478 -76.716163) (xy 257.657564 -76.67202) (xy 257.697713 -76.633311) (xy 257.743071 -76.60086)
			(xy 257.792671 -76.575359) (xy 257.845455 -76.557352) (xy 257.900298 -76.547222) (xy 257.956032 -76.545185)
			(xy 258.011469 -76.551285) (xy 258.065426 -76.565391) (xy 258.116755 -76.587203) (xy 258.164361 -76.616257)
			(xy 258.207229 -76.651932) (xy 258.244446 -76.693469) (xy 258.275219 -76.739982) (xy 258.298891 -76.790479)
			(xy 258.314959 -76.843886) (xy 258.323079 -76.899062) (xy 258.323588 -76.926948) (xy 258.323079 -76.954834)
			(xy 258.314959 -77.01001) (xy 258.298891 -77.063417) (xy 258.275219 -77.113914) (xy 258.244446 -77.160427)
			(xy 258.207229 -77.201964) (xy 258.164361 -77.237639) (xy 258.116755 -77.266693) (xy 258.065426 -77.288505)
			(xy 258.011469 -77.302611) (xy 257.956032 -77.308711) (xy 257.900298 -77.306674) (xy 257.845455 -77.296544)
			(xy 257.792671 -77.278537) (xy 257.743071 -77.253036) (xy 257.697713 -77.220585) (xy 257.657564 -77.181876)
			(xy 257.623478 -77.137733) (xy 257.596182 -77.089098) (xy 257.576259 -77.037007) (xy 257.564133 -76.98257)
			(xy 257.560062 -76.926948) (xy 249.860685 -76.926948) (xy 252.639255 -78.077822) (xy 262.833104 -78.077822)
			(xy 262.833509 -78.051441) (xy 262.840772 -77.999182) (xy 262.855163 -77.948421) (xy 262.876408 -77.900125)
			(xy 262.904101 -77.855216) (xy 262.937715 -77.814548) (xy 262.97661 -77.778897) (xy 263.020043 -77.748942)
			(xy 263.043416 -77.7367) (xy 263.05576 -77.72997) (xy 263.076497 -77.711003) (xy 263.091265 -77.687094)
			(xy 263.098943 -77.660061) (xy 263.098945 -77.631959) (xy 263.091273 -77.604924) (xy 263.076509 -77.581012)
			(xy 263.055777 -77.562042) (xy 263.043416 -77.555344) (xy 263.020059 -77.543078) (xy 262.976634 -77.513121)
			(xy 262.937747 -77.477469) (xy 262.90414 -77.436803) (xy 262.876451 -77.391898) (xy 262.855209 -77.343608)
			(xy 262.840817 -77.292853) (xy 262.833551 -77.2406) (xy 262.833104 -77.214222) (xy 262.83359 -77.186971)
			(xy 262.841346 -77.133023) (xy 262.856701 -77.080728) (xy 262.879343 -77.031151) (xy 262.908809 -76.985301)
			(xy 262.9445 -76.94411) (xy 262.985691 -76.908419) (xy 263.031541 -76.878953) (xy 263.081118 -76.856311)
			(xy 263.133413 -76.840956) (xy 263.187361 -76.8332) (xy 263.241863 -76.8332) (xy 263.295811 -76.840956)
			(xy 263.348106 -76.856311) (xy 263.397683 -76.878953) (xy 263.443533 -76.908419) (xy 263.484724 -76.94411)
			(xy 263.520415 -76.985301) (xy 263.549881 -77.031151) (xy 263.572523 -77.080728) (xy 263.587878 -77.133023)
			(xy 263.595634 -77.186971) (xy 263.59612 -77.214222) (xy 263.595656 -77.240601) (xy 263.588401 -77.292857)
			(xy 263.574018 -77.343616) (xy 263.552782 -77.39191) (xy 263.525097 -77.43682) (xy 263.491491 -77.477489)
			(xy 263.452604 -77.513142) (xy 263.409177 -77.5431) (xy 263.385808 -77.555344) (xy 263.373433 -77.562015)
			(xy 263.352707 -77.580998) (xy 263.337949 -77.604918) (xy 263.330281 -77.631957) (xy 263.330283 -77.660063)
			(xy 263.337957 -77.6871) (xy 263.352719 -77.711017) (xy 263.373449 -77.729996) (xy 263.385808 -77.7367)
			(xy 263.409189 -77.748922) (xy 263.452614 -77.778887) (xy 263.491499 -77.814545) (xy 263.525104 -77.855217)
			(xy 263.55279 -77.900129) (xy 263.574029 -77.948425) (xy 263.588415 -77.999185) (xy 263.595676 -78.051442)
			(xy 263.59612 -78.077822) (xy 263.595634 -78.105073) (xy 263.587878 -78.159021) (xy 263.572523 -78.211316)
			(xy 263.549881 -78.260893) (xy 263.520415 -78.306743) (xy 263.484724 -78.347934) (xy 263.443533 -78.383625)
			(xy 263.397683 -78.413091) (xy 263.348106 -78.435733) (xy 263.295811 -78.451088) (xy 263.241863 -78.458844)
			(xy 263.187361 -78.458844) (xy 263.133413 -78.451088) (xy 263.081118 -78.435733) (xy 263.031541 -78.413091)
			(xy 262.985691 -78.383625) (xy 262.9445 -78.347934) (xy 262.908809 -78.306743) (xy 262.879343 -78.260893)
			(xy 262.856701 -78.211316) (xy 262.841346 -78.159021) (xy 262.83359 -78.105073) (xy 262.833104 -78.077822)
			(xy 252.639255 -78.077822) (xy 254.372872 -78.79588) (xy 255.282192 -78.79588) (xy 255.30701 -78.796288)
			(xy 255.356216 -78.802807) (xy 255.404149 -78.815694) (xy 255.427226 -78.824836) (xy 255.79697 -78.977998)
			(xy 258.880862 -78.977998) (xy 258.884933 -78.922376) (xy 258.897059 -78.867939) (xy 258.916982 -78.815848)
			(xy 258.944278 -78.767213) (xy 258.978364 -78.72307) (xy 259.018513 -78.684361) (xy 259.063871 -78.65191)
			(xy 259.113471 -78.626409) (xy 259.166255 -78.608402) (xy 259.221098 -78.598272) (xy 259.276832 -78.596235)
			(xy 259.332269 -78.602335) (xy 259.386226 -78.616441) (xy 259.437555 -78.638253) (xy 259.485161 -78.667307)
			(xy 259.528029 -78.702982) (xy 259.565246 -78.744519) (xy 259.596019 -78.791032) (xy 259.619691 -78.841529)
			(xy 259.635759 -78.894936) (xy 259.643879 -78.950112) (xy 259.644388 -78.977998) (xy 259.643879 -79.005884)
			(xy 259.635759 -79.06106) (xy 259.619691 -79.114467) (xy 259.596019 -79.164964) (xy 259.565246 -79.211477)
			(xy 259.528029 -79.253014) (xy 259.485161 -79.288689) (xy 259.437555 -79.317743) (xy 259.386226 -79.339555)
			(xy 259.332269 -79.353661) (xy 259.276832 -79.359761) (xy 259.221098 -79.357724) (xy 259.166255 -79.347594)
			(xy 259.113471 -79.329587) (xy 259.063871 -79.304086) (xy 259.018513 -79.271635) (xy 258.978364 -79.232926)
			(xy 258.944278 -79.188783) (xy 258.916982 -79.140148) (xy 258.897059 -79.088057) (xy 258.884933 -79.03362)
			(xy 258.880862 -78.977998) (xy 255.79697 -78.977998) (xy 257.161284 -79.543148) (xy 271.65808 -79.543148)
		)
		(stroke
			(width 0)
			(type solid)
		)
		(fill yes)
		(layer "In4.Cu")
		(net "GND")
	)
	(gr_poly
		(pts
			(xy 177.19548 -110.378748) (xy 177.19548 -109.78515) (xy 177.195016 -109.771371) (xy 177.187629 -109.74482)
			(xy 177.173408 -109.721214) (xy 177.153389 -109.702273) (xy 177.129032 -109.68938) (xy 177.102113 -109.683473)
			(xy 177.074595 -109.684985) (xy 177.061368 -109.688884) (xy 177.035702 -109.696956) (xy 176.982605 -109.70563)
			(xy 176.955704 -109.706156) (xy 176.929711 -109.705673) (xy 176.878364 -109.697541) (xy 176.828922 -109.681477)
			(xy 176.782602 -109.657876) (xy 176.740543 -109.627319) (xy 176.703783 -109.59056) (xy 176.673226 -109.548502)
			(xy 176.649625 -109.502182) (xy 176.63356 -109.45274) (xy 176.625427 -109.401393) (xy 176.625427 -109.349407)
			(xy 176.63356 -109.29806) (xy 176.649625 -109.248618) (xy 176.673226 -109.202298) (xy 176.703783 -109.16024)
			(xy 176.740543 -109.123481) (xy 176.782602 -109.092924) (xy 176.828922 -109.069323) (xy 176.878364 -109.053259)
			(xy 176.929711 -109.045127) (xy 176.955704 -109.04474) (xy 176.982606 -109.045247) (xy 177.035703 -109.053931)
			(xy 177.061368 -109.062012) (xy 177.074575 -109.065994) (xy 177.102108 -109.06751) (xy 177.129041 -109.061599)
			(xy 177.153408 -109.048692) (xy 177.173429 -109.029733) (xy 177.187644 -109.006105) (xy 177.195012 -108.979533)
			(xy 177.19548 -108.965746) (xy 177.19548 -108.856018) (xy 177.131218 -108.856018) (xy 177.119534 -108.862622)
			(xy 177.094403 -108.876257) (xy 177.04061 -108.895619) (xy 176.98429 -108.905446) (xy 176.955704 -108.906056)
			(xy 176.929711 -108.905573) (xy 176.878364 -108.897441) (xy 176.828922 -108.881377) (xy 176.782602 -108.857776)
			(xy 176.740543 -108.827219) (xy 176.703783 -108.79046) (xy 176.673226 -108.748402) (xy 176.649625 -108.702082)
			(xy 176.63356 -108.65264) (xy 176.625427 -108.601293) (xy 176.625427 -108.549307) (xy 176.63356 -108.49796)
			(xy 176.649625 -108.448518) (xy 176.673226 -108.402198) (xy 176.703783 -108.36014) (xy 176.740543 -108.323381)
			(xy 176.782602 -108.292824) (xy 176.828922 -108.269223) (xy 176.878364 -108.253159) (xy 176.929711 -108.245027)
			(xy 176.955704 -108.24464) (xy 176.982606 -108.245147) (xy 177.035703 -108.253831) (xy 177.061368 -108.261912)
			(xy 177.074575 -108.265894) (xy 177.102108 -108.26741) (xy 177.129041 -108.261499) (xy 177.153408 -108.248592)
			(xy 177.173429 -108.229633) (xy 177.187644 -108.206005) (xy 177.195012 -108.179433) (xy 177.19548 -108.165646)
			(xy 177.19548 -108.056172) (xy 177.131218 -108.056172) (xy 177.119534 -108.062776) (xy 177.094403 -108.076413)
			(xy 177.040611 -108.095777) (xy 176.98429 -108.105606) (xy 176.955704 -108.10621) (xy 176.929714 -108.105727)
			(xy 176.878375 -108.097596) (xy 176.82894 -108.081534) (xy 176.782626 -108.057937) (xy 176.740573 -108.027384)
			(xy 176.703818 -107.99063) (xy 176.673265 -107.948578) (xy 176.649667 -107.902264) (xy 176.633605 -107.852829)
			(xy 176.625473 -107.80149) (xy 176.625473 -107.74951) (xy 176.633605 -107.698171) (xy 176.649667 -107.648736)
			(xy 176.673265 -107.602422) (xy 176.703818 -107.56037) (xy 176.740573 -107.523616) (xy 176.782626 -107.493063)
			(xy 176.82894 -107.469466) (xy 176.878375 -107.453404) (xy 176.929714 -107.445273) (xy 176.955704 -107.444794)
			(xy 176.982606 -107.445301) (xy 177.035704 -107.453984) (xy 177.061368 -107.462066) (xy 177.074578 -107.466047)
			(xy 177.102114 -107.467561) (xy 177.129051 -107.46165) (xy 177.153423 -107.448745) (xy 177.173451 -107.429787)
			(xy 177.187675 -107.40616) (xy 177.195056 -107.379589) (xy 177.19548 -107.3658) (xy 177.19548 -107.256072)
			(xy 177.131218 -107.256072) (xy 177.119534 -107.262676) (xy 177.094403 -107.276313) (xy 177.040611 -107.295677)
			(xy 176.98429 -107.305506) (xy 176.955704 -107.30611) (xy 176.929714 -107.305627) (xy 176.878375 -107.297496)
			(xy 176.82894 -107.281434) (xy 176.782626 -107.257837) (xy 176.740573 -107.227284) (xy 176.703818 -107.19053)
			(xy 176.673265 -107.148478) (xy 176.649667 -107.102164) (xy 176.633605 -107.052729) (xy 176.625473 -107.00139)
			(xy 176.625473 -106.94941) (xy 176.633605 -106.898071) (xy 176.649667 -106.848636) (xy 176.673265 -106.802322)
			(xy 176.703818 -106.76027) (xy 176.740573 -106.723516) (xy 176.782626 -106.692963) (xy 176.82894 -106.669366)
			(xy 176.878375 -106.653304) (xy 176.929714 -106.645173) (xy 176.955704 -106.644694) (xy 176.982606 -106.645201)
			(xy 177.035704 -106.653884) (xy 177.061368 -106.661966) (xy 177.074578 -106.665947) (xy 177.102114 -106.667461)
			(xy 177.129051 -106.66155) (xy 177.153423 -106.648645) (xy 177.173451 -106.629687) (xy 177.187675 -106.60606)
			(xy 177.195056 -106.579489) (xy 177.19548 -106.5657) (xy 177.19548 -106.455972) (xy 177.131218 -106.455972)
			(xy 177.119534 -106.462576) (xy 177.094403 -106.476213) (xy 177.040611 -106.495577) (xy 176.98429 -106.505406)
			(xy 176.955704 -106.50601) (xy 176.929714 -106.505527) (xy 176.878375 -106.497396) (xy 176.82894 -106.481334)
			(xy 176.782626 -106.457737) (xy 176.740573 -106.427184) (xy 176.703818 -106.39043) (xy 176.673265 -106.348378)
			(xy 176.649667 -106.302064) (xy 176.633605 -106.252629) (xy 176.625473 -106.20129) (xy 176.625473 -106.14931)
			(xy 176.633605 -106.097971) (xy 176.649667 -106.048536) (xy 176.673265 -106.002222) (xy 176.703818 -105.96017)
			(xy 176.740573 -105.923416) (xy 176.782626 -105.892863) (xy 176.82894 -105.869266) (xy 176.878375 -105.853204)
			(xy 176.929714 -105.845073) (xy 176.955704 -105.844594) (xy 176.982606 -105.845101) (xy 177.035704 -105.853784)
			(xy 177.061368 -105.861866) (xy 177.074578 -105.865847) (xy 177.102114 -105.867361) (xy 177.129051 -105.86145)
			(xy 177.153423 -105.848545) (xy 177.173451 -105.829587) (xy 177.187675 -105.80596) (xy 177.195056 -105.779389)
			(xy 177.19548 -105.7656) (xy 177.19548 -104.180894) (xy 177.195035 -104.16713) (xy 177.187688 -104.140601)
			(xy 177.173506 -104.117008) (xy 177.153524 -104.098074) (xy 177.129202 -104.085183) (xy 177.102315 -104.079275)
			(xy 177.088546 -104.079548) (xy 177.06848 -104.080056) (xy 177.041226 -104.079569) (xy 176.987274 -104.071809)
			(xy 176.934975 -104.05645) (xy 176.885394 -104.033805) (xy 176.83954 -104.004334) (xy 176.798347 -103.968638)
			(xy 176.762654 -103.927444) (xy 176.733185 -103.881588) (xy 176.710543 -103.832006) (xy 176.695187 -103.779707)
			(xy 176.68743 -103.725754) (xy 176.68743 -103.671246) (xy 176.695187 -103.617293) (xy 176.710543 -103.564994)
			(xy 176.733185 -103.515412) (xy 176.762654 -103.469556) (xy 176.798347 -103.428362) (xy 176.83954 -103.392666)
			(xy 176.885394 -103.363195) (xy 176.934975 -103.34055) (xy 176.987274 -103.325191) (xy 177.041226 -103.317431)
			(xy 177.06848 -103.31704) (xy 177.088546 -103.317548) (xy 177.102305 -103.317807) (xy 177.12916 -103.311847)
			(xy 177.153452 -103.298938) (xy 177.173418 -103.280016) (xy 177.187612 -103.256452) (xy 177.195004 -103.229955)
			(xy 177.19548 -103.216202) (xy 177.19548 -103.191056) (xy 177.19504 -103.177742) (xy 177.188138 -103.152024)
			(xy 177.174816 -103.128968) (xy 177.155981 -103.110145) (xy 177.132917 -103.096837) (xy 177.107194 -103.089951)
			(xy 177.09388 -103.089456) (xy 177.066626 -103.088969) (xy 177.012674 -103.081209) (xy 176.960375 -103.06585)
			(xy 176.910794 -103.043205) (xy 176.86494 -103.013734) (xy 176.823747 -102.978038) (xy 176.788054 -102.936844)
			(xy 176.758585 -102.890988) (xy 176.735943 -102.841406) (xy 176.720587 -102.789107) (xy 176.71283 -102.735154)
			(xy 176.71283 -102.680646) (xy 176.720587 -102.626693) (xy 176.735943 -102.574394) (xy 176.758585 -102.524812)
			(xy 176.788054 -102.478956) (xy 176.823747 -102.437762) (xy 176.86494 -102.402066) (xy 176.910794 -102.372595)
			(xy 176.960375 -102.34995) (xy 177.012674 -102.334591) (xy 177.066626 -102.326831) (xy 177.09388 -102.32644)
			(xy 177.107202 -102.326008) (xy 177.132941 -102.319118) (xy 177.156019 -102.305802) (xy 177.174865 -102.286967)
			(xy 177.188195 -102.263896) (xy 177.1951 -102.238162) (xy 177.19548 -102.22484) (xy 177.19548 -101.209348)
			(xy 177.091594 -101.105716) (xy 176.910492 -101.105716) (xy 176.896902 -101.106148) (xy 176.870687 -101.113324)
			(xy 176.847295 -101.127165) (xy 176.828385 -101.146689) (xy 176.8153 -101.170511) (xy 176.808965 -101.196942)
			(xy 176.809832 -101.224108) (xy 176.817838 -101.250082) (xy 176.832416 -101.273022) (xy 176.842166 -101.2825)
			(xy 176.861509 -101.30065) (xy 176.895493 -101.341374) (xy 176.923506 -101.386414) (xy 176.945009 -101.434902)
			(xy 176.959586 -101.485901) (xy 176.966956 -101.538427) (xy 176.967388 -101.564948) (xy 176.966902 -101.592199)
			(xy 176.959146 -101.646147) (xy 176.943791 -101.698442) (xy 176.921149 -101.748019) (xy 176.891683 -101.793869)
			(xy 176.855992 -101.83506) (xy 176.814801 -101.870751) (xy 176.768951 -101.900217) (xy 176.719374 -101.922859)
			(xy 176.667079 -101.938214) (xy 176.613131 -101.94597) (xy 176.558629 -101.94597) (xy 176.504681 -101.938214)
			(xy 176.452386 -101.922859) (xy 176.402809 -101.900217) (xy 176.356959 -101.870751) (xy 176.315768 -101.83506)
			(xy 176.280077 -101.793869) (xy 176.250611 -101.748019) (xy 176.227969 -101.698442) (xy 176.212614 -101.646147)
			(xy 176.204858 -101.592199) (xy 176.204372 -101.564948) (xy 176.204827 -101.538427) (xy 176.212177 -101.485897)
			(xy 176.226742 -101.434894) (xy 176.248241 -101.386405) (xy 176.276257 -101.341366) (xy 176.310249 -101.300648)
			(xy 176.329594 -101.2825) (xy 176.339367 -101.273041) (xy 176.353953 -101.250098) (xy 176.361965 -101.224118)
			(xy 176.362834 -101.196945) (xy 176.356498 -101.170506) (xy 176.343406 -101.146679) (xy 176.324488 -101.127153)
			(xy 176.301087 -101.113314) (xy 176.274862 -101.106145) (xy 176.261268 -101.105716) (xy 173.387766 -101.105716)
			(xy 173.15688 -101.336348) (xy 173.15688 -102.789228) (xy 175.487582 -102.789228) (xy 175.491653 -102.733606)
			(xy 175.503779 -102.679169) (xy 175.523702 -102.627078) (xy 175.550998 -102.578443) (xy 175.585084 -102.5343)
			(xy 175.625233 -102.495591) (xy 175.670591 -102.46314) (xy 175.720191 -102.437639) (xy 175.772975 -102.419632)
			(xy 175.827818 -102.409502) (xy 175.883552 -102.407465) (xy 175.938989 -102.413565) (xy 175.992946 -102.427671)
			(xy 176.044275 -102.449483) (xy 176.091881 -102.478537) (xy 176.134749 -102.514212) (xy 176.171966 -102.555749)
			(xy 176.202739 -102.602262) (xy 176.226411 -102.652759) (xy 176.242479 -102.706166) (xy 176.250599 -102.761342)
			(xy 176.251108 -102.789228) (xy 176.250599 -102.817114) (xy 176.242479 -102.87229) (xy 176.226411 -102.925697)
			(xy 176.202739 -102.976194) (xy 176.171966 -103.022707) (xy 176.134749 -103.064244) (xy 176.091881 -103.099919)
			(xy 176.044275 -103.128973) (xy 175.992946 -103.150785) (xy 175.938989 -103.164891) (xy 175.883552 -103.170991)
			(xy 175.827818 -103.168954) (xy 175.772975 -103.158824) (xy 175.720191 -103.140817) (xy 175.670591 -103.115316)
			(xy 175.625233 -103.082865) (xy 175.585084 -103.044156) (xy 175.550998 -103.000013) (xy 175.523702 -102.951378)
			(xy 175.503779 -102.899287) (xy 175.491653 -102.84485) (xy 175.487582 -102.789228) (xy 173.15688 -102.789228)
			(xy 173.15688 -105.113074) (xy 173.17666 -105.12882) (xy 173.211656 -105.165305) (xy 173.240687 -105.206694)
			(xy 173.263075 -105.252022) (xy 173.278299 -105.300231) (xy 173.286003 -105.350196) (xy 173.286007 -105.400751)
			(xy 173.2859 -105.401443) (xy 173.42536 -105.401443) (xy 173.42536 -105.349469) (xy 173.43349 -105.298134)
			(xy 173.449551 -105.248704) (xy 173.473147 -105.202394) (xy 173.503697 -105.160346) (xy 173.540448 -105.123595)
			(xy 173.582496 -105.093045) (xy 173.628806 -105.069449) (xy 173.678236 -105.053388) (xy 173.729571 -105.045258)
			(xy 173.781545 -105.045258) (xy 173.83288 -105.053388) (xy 173.88231 -105.069449) (xy 173.92862 -105.093045)
			(xy 173.970668 -105.123595) (xy 174.007419 -105.160346) (xy 174.037969 -105.202394) (xy 174.061565 -105.248704)
			(xy 174.077626 -105.298134) (xy 174.085756 -105.349469) (xy 174.086266 -105.375456) (xy 174.085756 -105.401443)
			(xy 174.22546 -105.401443) (xy 174.22546 -105.349469) (xy 174.23359 -105.298134) (xy 174.249651 -105.248704)
			(xy 174.273247 -105.202394) (xy 174.303797 -105.160346) (xy 174.340548 -105.123595) (xy 174.382596 -105.093045)
			(xy 174.428906 -105.069449) (xy 174.478336 -105.053388) (xy 174.529671 -105.045258) (xy 174.581645 -105.045258)
			(xy 174.63298 -105.053388) (xy 174.68241 -105.069449) (xy 174.72872 -105.093045) (xy 174.770768 -105.123595)
			(xy 174.807519 -105.160346) (xy 174.838069 -105.202394) (xy 174.861665 -105.248704) (xy 174.877726 -105.298134)
			(xy 174.885856 -105.349469) (xy 174.886366 -105.375456) (xy 174.885856 -105.401443) (xy 175.025306 -105.401443)
			(xy 175.025306 -105.349469) (xy 175.033436 -105.298134) (xy 175.049497 -105.248704) (xy 175.073093 -105.202394)
			(xy 175.103643 -105.160346) (xy 175.140394 -105.123595) (xy 175.182442 -105.093045) (xy 175.228752 -105.069449)
			(xy 175.278182 -105.053388) (xy 175.329517 -105.045258) (xy 175.381491 -105.045258) (xy 175.432826 -105.053388)
			(xy 175.482256 -105.069449) (xy 175.528566 -105.093045) (xy 175.570614 -105.123595) (xy 175.607365 -105.160346)
			(xy 175.637915 -105.202394) (xy 175.661511 -105.248704) (xy 175.677572 -105.298134) (xy 175.685702 -105.349469)
			(xy 175.686212 -105.375456) (xy 175.685702 -105.401443) (xy 175.677572 -105.452778) (xy 175.661511 -105.502208)
			(xy 175.637915 -105.548518) (xy 175.607365 -105.590566) (xy 175.570614 -105.627317) (xy 175.528566 -105.657867)
			(xy 175.482256 -105.681463) (xy 175.432826 -105.697524) (xy 175.381491 -105.705654) (xy 175.329517 -105.705654)
			(xy 175.278182 -105.697524) (xy 175.228752 -105.681463) (xy 175.182442 -105.657867) (xy 175.140394 -105.627317)
			(xy 175.103643 -105.590566) (xy 175.073093 -105.548518) (xy 175.049497 -105.502208) (xy 175.033436 -105.452778)
			(xy 175.025306 -105.401443) (xy 174.885856 -105.401443) (xy 174.877726 -105.452778) (xy 174.861665 -105.502208)
			(xy 174.838069 -105.548518) (xy 174.807519 -105.590566) (xy 174.770768 -105.627317) (xy 174.72872 -105.657867)
			(xy 174.68241 -105.681463) (xy 174.63298 -105.697524) (xy 174.581645 -105.705654) (xy 174.529671 -105.705654)
			(xy 174.478336 -105.697524) (xy 174.428906 -105.681463) (xy 174.382596 -105.657867) (xy 174.340548 -105.627317)
			(xy 174.303797 -105.590566) (xy 174.273247 -105.548518) (xy 174.249651 -105.502208) (xy 174.23359 -105.452778)
			(xy 174.22546 -105.401443) (xy 174.085756 -105.401443) (xy 174.077626 -105.452778) (xy 174.061565 -105.502208)
			(xy 174.037969 -105.548518) (xy 174.007419 -105.590566) (xy 173.970668 -105.627317) (xy 173.92862 -105.657867)
			(xy 173.88231 -105.681463) (xy 173.83288 -105.697524) (xy 173.781545 -105.705654) (xy 173.729571 -105.705654)
			(xy 173.678236 -105.697524) (xy 173.628806 -105.681463) (xy 173.582496 -105.657867) (xy 173.540448 -105.627317)
			(xy 173.503697 -105.590566) (xy 173.473147 -105.548518) (xy 173.449551 -105.502208) (xy 173.43349 -105.452778)
			(xy 173.42536 -105.401443) (xy 173.2859 -105.401443) (xy 173.278311 -105.450717) (xy 173.263095 -105.498928)
			(xy 173.240714 -105.54426) (xy 173.21169 -105.585654) (xy 173.1767 -105.622144) (xy 173.15688 -105.637838)
			(xy 173.15688 -105.91292) (xy 173.176656 -105.928666) (xy 173.211645 -105.96515) (xy 173.240669 -106.006537)
			(xy 173.263051 -106.051862) (xy 173.278269 -106.100066) (xy 173.285968 -106.150026) (xy 173.285968 -106.200576)
			(xy 173.285858 -106.201289) (xy 175.025306 -106.201289) (xy 175.025306 -106.149315) (xy 175.033436 -106.09798)
			(xy 175.049497 -106.04855) (xy 175.073093 -106.00224) (xy 175.103643 -105.960192) (xy 175.140394 -105.923441)
			(xy 175.182442 -105.892891) (xy 175.228752 -105.869295) (xy 175.278182 -105.853234) (xy 175.329517 -105.845104)
			(xy 175.381491 -105.845104) (xy 175.432826 -105.853234) (xy 175.482256 -105.869295) (xy 175.528566 -105.892891)
			(xy 175.570614 -105.923441) (xy 175.607365 -105.960192) (xy 175.637915 -106.00224) (xy 175.661511 -106.04855)
			(xy 175.677572 -106.09798) (xy 175.685702 -106.149315) (xy 175.686212 -106.175302) (xy 175.685702 -106.201289)
			(xy 175.677572 -106.252624) (xy 175.661511 -106.302054) (xy 175.637915 -106.348364) (xy 175.607365 -106.390412)
			(xy 175.570614 -106.427163) (xy 175.528566 -106.457713) (xy 175.482256 -106.481309) (xy 175.432826 -106.49737)
			(xy 175.381491 -106.5055) (xy 175.329517 -106.5055) (xy 175.278182 -106.49737) (xy 175.228752 -106.481309)
			(xy 175.182442 -106.457713) (xy 175.140394 -106.427163) (xy 175.103643 -106.390412) (xy 175.073093 -106.348364)
			(xy 175.049497 -106.302054) (xy 175.033436 -106.252624) (xy 175.025306 -106.201289) (xy 173.285858 -106.201289)
			(xy 173.278269 -106.250536) (xy 173.26305 -106.298741) (xy 173.240668 -106.344065) (xy 173.211644 -106.385452)
			(xy 173.176655 -106.421935) (xy 173.15688 -106.437684) (xy 173.15688 -106.71302) (xy 173.176656 -106.728766)
			(xy 173.211645 -106.76525) (xy 173.240669 -106.806637) (xy 173.263051 -106.851962) (xy 173.278269 -106.900166)
			(xy 173.285968 -106.950126) (xy 173.285968 -107.000676) (xy 173.285858 -107.001389) (xy 173.42536 -107.001389)
			(xy 173.42536 -106.949415) (xy 173.43349 -106.89808) (xy 173.449551 -106.84865) (xy 173.473147 -106.80234)
			(xy 173.503697 -106.760292) (xy 173.540448 -106.723541) (xy 173.582496 -106.692991) (xy 173.628806 -106.669395)
			(xy 173.678236 -106.653334) (xy 173.729571 -106.645204) (xy 173.781545 -106.645204) (xy 173.83288 -106.653334)
			(xy 173.88231 -106.669395) (xy 173.92862 -106.692991) (xy 173.970668 -106.723541) (xy 174.007419 -106.760292)
			(xy 174.037969 -106.80234) (xy 174.061565 -106.84865) (xy 174.077626 -106.89808) (xy 174.085756 -106.949415)
			(xy 174.086266 -106.975402) (xy 174.085756 -107.001389) (xy 175.025306 -107.001389) (xy 175.025306 -106.949415)
			(xy 175.033436 -106.89808) (xy 175.049497 -106.84865) (xy 175.073093 -106.80234) (xy 175.103643 -106.760292)
			(xy 175.140394 -106.723541) (xy 175.182442 -106.692991) (xy 175.228752 -106.669395) (xy 175.278182 -106.653334)
			(xy 175.329517 -106.645204) (xy 175.381491 -106.645204) (xy 175.432826 -106.653334) (xy 175.482256 -106.669395)
			(xy 175.528566 -106.692991) (xy 175.570614 -106.723541) (xy 175.607365 -106.760292) (xy 175.637915 -106.80234)
			(xy 175.661511 -106.84865) (xy 175.677572 -106.89808) (xy 175.685702 -106.949415) (xy 175.686212 -106.975402)
			(xy 175.685702 -107.001389) (xy 175.825406 -107.001389) (xy 175.825406 -106.949415) (xy 175.833536 -106.89808)
			(xy 175.849597 -106.84865) (xy 175.873193 -106.80234) (xy 175.903743 -106.760292) (xy 175.940494 -106.723541)
			(xy 175.982542 -106.692991) (xy 176.028852 -106.669395) (xy 176.078282 -106.653334) (xy 176.129617 -106.645204)
			(xy 176.181591 -106.645204) (xy 176.232926 -106.653334) (xy 176.282356 -106.669395) (xy 176.328666 -106.692991)
			(xy 176.370714 -106.723541) (xy 176.407465 -106.760292) (xy 176.438015 -106.80234) (xy 176.461611 -106.84865)
			(xy 176.477672 -106.89808) (xy 176.485802 -106.949415) (xy 176.486312 -106.975402) (xy 176.485802 -107.001389)
			(xy 176.477672 -107.052724) (xy 176.461611 -107.102154) (xy 176.438015 -107.148464) (xy 176.407465 -107.190512)
			(xy 176.370714 -107.227263) (xy 176.328666 -107.257813) (xy 176.282356 -107.281409) (xy 176.232926 -107.29747)
			(xy 176.181591 -107.3056) (xy 176.129617 -107.3056) (xy 176.078282 -107.29747) (xy 176.028852 -107.281409)
			(xy 175.982542 -107.257813) (xy 175.940494 -107.227263) (xy 175.903743 -107.190512) (xy 175.873193 -107.148464)
			(xy 175.849597 -107.102154) (xy 175.833536 -107.052724) (xy 175.825406 -107.001389) (xy 175.685702 -107.001389)
			(xy 175.677572 -107.052724) (xy 175.661511 -107.102154) (xy 175.637915 -107.148464) (xy 175.607365 -107.190512)
			(xy 175.570614 -107.227263) (xy 175.528566 -107.257813) (xy 175.482256 -107.281409) (xy 175.432826 -107.29747)
			(xy 175.381491 -107.3056) (xy 175.329517 -107.3056) (xy 175.278182 -107.29747) (xy 175.228752 -107.281409)
			(xy 175.182442 -107.257813) (xy 175.140394 -107.227263) (xy 175.103643 -107.190512) (xy 175.073093 -107.148464)
			(xy 175.049497 -107.102154) (xy 175.033436 -107.052724) (xy 175.025306 -107.001389) (xy 174.085756 -107.001389)
			(xy 174.077626 -107.052724) (xy 174.061565 -107.102154) (xy 174.037969 -107.148464) (xy 174.007419 -107.190512)
			(xy 173.970668 -107.227263) (xy 173.92862 -107.257813) (xy 173.88231 -107.281409) (xy 173.83288 -107.29747)
			(xy 173.781545 -107.3056) (xy 173.729571 -107.3056) (xy 173.678236 -107.29747) (xy 173.628806 -107.281409)
			(xy 173.582496 -107.257813) (xy 173.540448 -107.227263) (xy 173.503697 -107.190512) (xy 173.473147 -107.148464)
			(xy 173.449551 -107.102154) (xy 173.43349 -107.052724) (xy 173.42536 -107.001389) (xy 173.285858 -107.001389)
			(xy 173.278269 -107.050636) (xy 173.26305 -107.098841) (xy 173.240668 -107.144165) (xy 173.211644 -107.185552)
			(xy 173.176655 -107.222035) (xy 173.15688 -107.237784) (xy 173.15688 -107.51312) (xy 173.176656 -107.528866)
			(xy 173.211645 -107.56535) (xy 173.240669 -107.606737) (xy 173.263051 -107.652062) (xy 173.278269 -107.700267)
			(xy 173.285968 -107.750227) (xy 173.28642 -107.775502) (xy 173.286004 -107.799595) (xy 173.285727 -107.801489)
			(xy 173.42536 -107.801489) (xy 173.42536 -107.749515) (xy 173.43349 -107.69818) (xy 173.449551 -107.64875)
			(xy 173.473147 -107.60244) (xy 173.503697 -107.560392) (xy 173.540448 -107.523641) (xy 173.582496 -107.493091)
			(xy 173.628806 -107.469495) (xy 173.678236 -107.453434) (xy 173.729571 -107.445304) (xy 173.781545 -107.445304)
			(xy 173.83288 -107.453434) (xy 173.88231 -107.469495) (xy 173.92862 -107.493091) (xy 173.970668 -107.523641)
			(xy 174.007419 -107.560392) (xy 174.037969 -107.60244) (xy 174.061565 -107.64875) (xy 174.077626 -107.69818)
			(xy 174.085756 -107.749515) (xy 174.086266 -107.775502) (xy 174.085756 -107.801489) (xy 174.22546 -107.801489)
			(xy 174.22546 -107.749515) (xy 174.23359 -107.69818) (xy 174.249651 -107.64875) (xy 174.273247 -107.60244)
			(xy 174.303797 -107.560392) (xy 174.340548 -107.523641) (xy 174.382596 -107.493091) (xy 174.428906 -107.469495)
			(xy 174.478336 -107.453434) (xy 174.529671 -107.445304) (xy 174.581645 -107.445304) (xy 174.63298 -107.453434)
			(xy 174.68241 -107.469495) (xy 174.72872 -107.493091) (xy 174.770768 -107.523641) (xy 174.807519 -107.560392)
			(xy 174.838069 -107.60244) (xy 174.861665 -107.64875) (xy 174.877726 -107.69818) (xy 174.885856 -107.749515)
			(xy 174.886366 -107.775502) (xy 174.885856 -107.801489) (xy 175.025306 -107.801489) (xy 175.025306 -107.749515)
			(xy 175.033436 -107.69818) (xy 175.049497 -107.64875) (xy 175.073093 -107.60244) (xy 175.103643 -107.560392)
			(xy 175.140394 -107.523641) (xy 175.182442 -107.493091) (xy 175.228752 -107.469495) (xy 175.278182 -107.453434)
			(xy 175.329517 -107.445304) (xy 175.381491 -107.445304) (xy 175.432826 -107.453434) (xy 175.482256 -107.469495)
			(xy 175.528566 -107.493091) (xy 175.570614 -107.523641) (xy 175.607365 -107.560392) (xy 175.637915 -107.60244)
			(xy 175.661511 -107.64875) (xy 175.677572 -107.69818) (xy 175.685702 -107.749515) (xy 175.686212 -107.775502)
			(xy 175.685702 -107.801489) (xy 175.825406 -107.801489) (xy 175.825406 -107.749515) (xy 175.833536 -107.69818)
			(xy 175.849597 -107.64875) (xy 175.873193 -107.60244) (xy 175.903743 -107.560392) (xy 175.940494 -107.523641)
			(xy 175.982542 -107.493091) (xy 176.028852 -107.469495) (xy 176.078282 -107.453434) (xy 176.129617 -107.445304)
			(xy 176.181591 -107.445304) (xy 176.232926 -107.453434) (xy 176.282356 -107.469495) (xy 176.328666 -107.493091)
			(xy 176.370714 -107.523641) (xy 176.407465 -107.560392) (xy 176.438015 -107.60244) (xy 176.461611 -107.64875)
			(xy 176.477672 -107.69818) (xy 176.485802 -107.749515) (xy 176.486312 -107.775502) (xy 176.485802 -107.801489)
			(xy 176.477672 -107.852824) (xy 176.461611 -107.902254) (xy 176.438015 -107.948564) (xy 176.407465 -107.990612)
			(xy 176.370714 -108.027363) (xy 176.328666 -108.057913) (xy 176.282356 -108.081509) (xy 176.232926 -108.09757)
			(xy 176.181591 -108.1057) (xy 176.129617 -108.1057) (xy 176.078282 -108.09757) (xy 176.028852 -108.081509)
			(xy 175.982542 -108.057913) (xy 175.940494 -108.027363) (xy 175.903743 -107.990612) (xy 175.873193 -107.948564)
			(xy 175.849597 -107.902254) (xy 175.833536 -107.852824) (xy 175.825406 -107.801489) (xy 175.685702 -107.801489)
			(xy 175.677572 -107.852824) (xy 175.661511 -107.902254) (xy 175.637915 -107.948564) (xy 175.607365 -107.990612)
			(xy 175.570614 -108.027363) (xy 175.528566 -108.057913) (xy 175.482256 -108.081509) (xy 175.432826 -108.09757)
			(xy 175.381491 -108.1057) (xy 175.329517 -108.1057) (xy 175.278182 -108.09757) (xy 175.228752 -108.081509)
			(xy 175.182442 -108.057913) (xy 175.140394 -108.027363) (xy 175.103643 -107.990612) (xy 175.073093 -107.948564)
			(xy 175.049497 -107.902254) (xy 175.033436 -107.852824) (xy 175.025306 -107.801489) (xy 174.885856 -107.801489)
			(xy 174.877726 -107.852824) (xy 174.861665 -107.902254) (xy 174.838069 -107.948564) (xy 174.807519 -107.990612)
			(xy 174.770768 -108.027363) (xy 174.72872 -108.057913) (xy 174.68241 -108.081509) (xy 174.63298 -108.09757)
			(xy 174.581645 -108.1057) (xy 174.529671 -108.1057) (xy 174.478336 -108.09757) (xy 174.428906 -108.081509)
			(xy 174.382596 -108.057913) (xy 174.340548 -108.027363) (xy 174.303797 -107.990612) (xy 174.273247 -107.948564)
			(xy 174.249651 -107.902254) (xy 174.23359 -107.852824) (xy 174.22546 -107.801489) (xy 174.085756 -107.801489)
			(xy 174.077626 -107.852824) (xy 174.061565 -107.902254) (xy 174.037969 -107.948564) (xy 174.007419 -107.990612)
			(xy 173.970668 -108.027363) (xy 173.92862 -108.057913) (xy 173.88231 -108.081509) (xy 173.83288 -108.09757)
			(xy 173.781545 -108.1057) (xy 173.729571 -108.1057) (xy 173.678236 -108.09757) (xy 173.628806 -108.081509)
			(xy 173.582496 -108.057913) (xy 173.540448 -108.027363) (xy 173.503697 -107.990612) (xy 173.473147 -107.948564)
			(xy 173.449551 -107.902254) (xy 173.43349 -107.852824) (xy 173.42536 -107.801489) (xy 173.285727 -107.801489)
			(xy 173.27904 -107.847275) (xy 173.265216 -107.893434) (xy 173.255432 -107.915456) (xy 173.240446 -107.947714)
			(xy 173.583346 -108.290614) (xy 173.615604 -108.275628) (xy 173.637626 -108.265849) (xy 173.68379 -108.252047)
			(xy 173.731466 -108.245076) (xy 173.755558 -108.24464) (xy 173.781548 -108.24512) (xy 173.832889 -108.253246)
			(xy 173.882326 -108.269305) (xy 173.928642 -108.292902) (xy 173.970695 -108.323454) (xy 174.00745 -108.36021)
			(xy 174.038001 -108.402264) (xy 174.061597 -108.44858) (xy 174.077655 -108.498017) (xy 174.08578 -108.549358)
			(xy 174.086266 -108.575348) (xy 174.085854 -108.599442) (xy 174.085578 -108.601335) (xy 174.22546 -108.601335)
			(xy 174.22546 -108.549361) (xy 174.23359 -108.498026) (xy 174.249651 -108.448596) (xy 174.273247 -108.402286)
			(xy 174.303797 -108.360238) (xy 174.340548 -108.323487) (xy 174.382596 -108.292937) (xy 174.428906 -108.269341)
			(xy 174.478336 -108.25328) (xy 174.529671 -108.24515) (xy 174.581645 -108.24515) (xy 174.63298 -108.25328)
			(xy 174.68241 -108.269341) (xy 174.72872 -108.292937) (xy 174.770768 -108.323487) (xy 174.807519 -108.360238)
			(xy 174.838069 -108.402286) (xy 174.861665 -108.448596) (xy 174.877726 -108.498026) (xy 174.885856 -108.549361)
			(xy 174.886366 -108.575348) (xy 174.885856 -108.601335) (xy 175.025306 -108.601335) (xy 175.025306 -108.549361)
			(xy 175.033436 -108.498026) (xy 175.049497 -108.448596) (xy 175.073093 -108.402286) (xy 175.103643 -108.360238)
			(xy 175.140394 -108.323487) (xy 175.182442 -108.292937) (xy 175.228752 -108.269341) (xy 175.278182 -108.25328)
			(xy 175.329517 -108.24515) (xy 175.381491 -108.24515) (xy 175.432826 -108.25328) (xy 175.482256 -108.269341)
			(xy 175.528566 -108.292937) (xy 175.570614 -108.323487) (xy 175.607365 -108.360238) (xy 175.637915 -108.402286)
			(xy 175.661511 -108.448596) (xy 175.677572 -108.498026) (xy 175.685702 -108.549361) (xy 175.686212 -108.575348)
			(xy 175.685702 -108.601335) (xy 175.825406 -108.601335) (xy 175.825406 -108.549361) (xy 175.833536 -108.498026)
			(xy 175.849597 -108.448596) (xy 175.873193 -108.402286) (xy 175.903743 -108.360238) (xy 175.940494 -108.323487)
			(xy 175.982542 -108.292937) (xy 176.028852 -108.269341) (xy 176.078282 -108.25328) (xy 176.129617 -108.24515)
			(xy 176.181591 -108.24515) (xy 176.232926 -108.25328) (xy 176.282356 -108.269341) (xy 176.328666 -108.292937)
			(xy 176.370714 -108.323487) (xy 176.407465 -108.360238) (xy 176.438015 -108.402286) (xy 176.461611 -108.448596)
			(xy 176.477672 -108.498026) (xy 176.485802 -108.549361) (xy 176.486312 -108.575348) (xy 176.485802 -108.601335)
			(xy 176.477672 -108.65267) (xy 176.461611 -108.7021) (xy 176.438015 -108.74841) (xy 176.407465 -108.790458)
			(xy 176.370714 -108.827209) (xy 176.328666 -108.857759) (xy 176.282356 -108.881355) (xy 176.232926 -108.897416)
			(xy 176.181591 -108.905546) (xy 176.129617 -108.905546) (xy 176.078282 -108.897416) (xy 176.028852 -108.881355)
			(xy 175.982542 -108.857759) (xy 175.940494 -108.827209) (xy 175.903743 -108.790458) (xy 175.873193 -108.74841)
			(xy 175.849597 -108.7021) (xy 175.833536 -108.65267) (xy 175.825406 -108.601335) (xy 175.685702 -108.601335)
			(xy 175.677572 -108.65267) (xy 175.661511 -108.7021) (xy 175.637915 -108.74841) (xy 175.607365 -108.790458)
			(xy 175.570614 -108.827209) (xy 175.528566 -108.857759) (xy 175.482256 -108.881355) (xy 175.432826 -108.897416)
			(xy 175.381491 -108.905546) (xy 175.329517 -108.905546) (xy 175.278182 -108.897416) (xy 175.228752 -108.881355)
			(xy 175.182442 -108.857759) (xy 175.140394 -108.827209) (xy 175.103643 -108.790458) (xy 175.073093 -108.74841)
			(xy 175.049497 -108.7021) (xy 175.033436 -108.65267) (xy 175.025306 -108.601335) (xy 174.885856 -108.601335)
			(xy 174.877726 -108.65267) (xy 174.861665 -108.7021) (xy 174.838069 -108.74841) (xy 174.807519 -108.790458)
			(xy 174.770768 -108.827209) (xy 174.72872 -108.857759) (xy 174.68241 -108.881355) (xy 174.63298 -108.897416)
			(xy 174.581645 -108.905546) (xy 174.529671 -108.905546) (xy 174.478336 -108.897416) (xy 174.428906 -108.881355)
			(xy 174.382596 -108.857759) (xy 174.340548 -108.827209) (xy 174.303797 -108.790458) (xy 174.273247 -108.74841)
			(xy 174.249651 -108.7021) (xy 174.23359 -108.65267) (xy 174.22546 -108.601335) (xy 174.085578 -108.601335)
			(xy 174.078898 -108.647125) (xy 174.065082 -108.693289) (xy 174.055278 -108.715302) (xy 174.040292 -108.74756)
			(xy 174.383446 -109.090714) (xy 174.415704 -109.075728) (xy 174.437726 -109.065949) (xy 174.48389 -109.052147)
			(xy 174.531566 -109.045176) (xy 174.555658 -109.04474) (xy 174.581648 -109.04522) (xy 174.632989 -109.053346)
			(xy 174.682426 -109.069405) (xy 174.728742 -109.093002) (xy 174.770795 -109.123554) (xy 174.80755 -109.16031)
			(xy 174.838101 -109.202364) (xy 174.861697 -109.24868) (xy 174.877755 -109.298117) (xy 174.88588 -109.349458)
			(xy 174.886366 -109.375448) (xy 174.885954 -109.399542) (xy 174.885678 -109.401435) (xy 175.025306 -109.401435)
			(xy 175.025306 -109.349461) (xy 175.033436 -109.298126) (xy 175.049497 -109.248696) (xy 175.073093 -109.202386)
			(xy 175.103643 -109.160338) (xy 175.140394 -109.123587) (xy 175.182442 -109.093037) (xy 175.228752 -109.069441)
			(xy 175.278182 -109.05338) (xy 175.329517 -109.04525) (xy 175.381491 -109.04525) (xy 175.432826 -109.05338)
			(xy 175.482256 -109.069441) (xy 175.528566 -109.093037) (xy 175.570614 -109.123587) (xy 175.607365 -109.160338)
			(xy 175.637915 -109.202386) (xy 175.661511 -109.248696) (xy 175.677572 -109.298126) (xy 175.685702 -109.349461)
			(xy 175.686212 -109.375448) (xy 175.685702 -109.401435) (xy 175.825406 -109.401435) (xy 175.825406 -109.349461)
			(xy 175.833536 -109.298126) (xy 175.849597 -109.248696) (xy 175.873193 -109.202386) (xy 175.903743 -109.160338)
			(xy 175.940494 -109.123587) (xy 175.982542 -109.093037) (xy 176.028852 -109.069441) (xy 176.078282 -109.05338)
			(xy 176.129617 -109.04525) (xy 176.181591 -109.04525) (xy 176.232926 -109.05338) (xy 176.282356 -109.069441)
			(xy 176.328666 -109.093037) (xy 176.370714 -109.123587) (xy 176.407465 -109.160338) (xy 176.438015 -109.202386)
			(xy 176.461611 -109.248696) (xy 176.477672 -109.298126) (xy 176.485802 -109.349461) (xy 176.486312 -109.375448)
			(xy 176.485802 -109.401435) (xy 176.477672 -109.45277) (xy 176.461611 -109.5022) (xy 176.438015 -109.54851)
			(xy 176.407465 -109.590558) (xy 176.370714 -109.627309) (xy 176.328666 -109.657859) (xy 176.282356 -109.681455)
			(xy 176.232926 -109.697516) (xy 176.181591 -109.705646) (xy 176.129617 -109.705646) (xy 176.078282 -109.697516)
			(xy 176.028852 -109.681455) (xy 175.982542 -109.657859) (xy 175.940494 -109.627309) (xy 175.903743 -109.590558)
			(xy 175.873193 -109.54851) (xy 175.849597 -109.5022) (xy 175.833536 -109.45277) (xy 175.825406 -109.401435)
			(xy 175.685702 -109.401435) (xy 175.677572 -109.45277) (xy 175.661511 -109.5022) (xy 175.637915 -109.54851)
			(xy 175.607365 -109.590558) (xy 175.570614 -109.627309) (xy 175.528566 -109.657859) (xy 175.482256 -109.681455)
			(xy 175.432826 -109.697516) (xy 175.381491 -109.705646) (xy 175.329517 -109.705646) (xy 175.278182 -109.697516)
			(xy 175.228752 -109.681455) (xy 175.182442 -109.657859) (xy 175.140394 -109.627309) (xy 175.103643 -109.590558)
			(xy 175.073093 -109.54851) (xy 175.049497 -109.5022) (xy 175.033436 -109.45277) (xy 175.025306 -109.401435)
			(xy 174.885678 -109.401435) (xy 174.878998 -109.447225) (xy 174.865182 -109.493389) (xy 174.855378 -109.515402)
			(xy 174.840392 -109.54766) (xy 175.183292 -109.89056) (xy 175.21555 -109.875574) (xy 175.237571 -109.86579)
			(xy 175.283734 -109.851978) (xy 175.331411 -109.844999) (xy 175.355504 -109.844586) (xy 175.381491 -109.845096)
			(xy 175.432825 -109.853227) (xy 175.482256 -109.869288) (xy 175.528565 -109.892884) (xy 175.570613 -109.923434)
			(xy 175.607365 -109.960185) (xy 175.637915 -110.002233) (xy 175.661511 -110.048542) (xy 175.677573 -110.097973)
			(xy 175.685704 -110.149307) (xy 175.686212 -110.175294) (xy 175.685797 -110.199387) (xy 175.678835 -110.247068)
			(xy 175.665016 -110.29323) (xy 175.655224 -110.315248) (xy 175.640238 -110.347506) (xy 175.74768 -110.454948)
			(xy 177.11928 -110.454948)
		)
		(stroke
			(width 0)
			(type solid)
		)
		(fill yes)
		(layer "In4.Cu")
		(net "P3V3_AUX_FPGA_VCCIO5")
	)
	(gr_poly
		(pts
			(xy 465.316316 -395.996414) (xy 466.93836 -394.37437) (xy 466.93836 -378.996448) (xy 465.741258 -377.799346)
			(xy 438.881012 -377.799346) (xy 438.881012 -378.46127) (xy 438.880443 -378.491239) (xy 438.871109 -378.550445)
			(xy 438.852632 -378.607464) (xy 438.825469 -378.660892) (xy 438.790287 -378.709418) (xy 438.769506 -378.731018)
			(xy 438.704228 -378.796296) (xy 438.682613 -378.817075) (xy 438.634108 -378.852312) (xy 438.580689 -378.879531)
			(xy 438.523671 -378.898062) (xy 438.464457 -378.907449) (xy 438.43448 -378.908056) (xy 438.407228 -378.907569)
			(xy 438.35328 -378.89981) (xy 438.300985 -378.884454) (xy 438.251407 -378.861812) (xy 438.205556 -378.832346)
			(xy 438.164364 -378.796655) (xy 438.128671 -378.755466) (xy 438.099201 -378.709617) (xy 438.076556 -378.660041)
			(xy 438.061196 -378.607747) (xy 438.053433 -378.5538) (xy 438.052972 -378.526548) (xy 438.053528 -378.498222)
			(xy 438.061976 -378.442201) (xy 438.078604 -378.388042) (xy 438.103049 -378.336933) (xy 438.118504 -378.313188)
			(xy 438.118504 -377.799346) (xy 433.923694 -377.799346) (xy 433.908708 -377.814332) (xy 432.645058 -379.077982)
			(xy 432.645058 -379.669548) (xy 460.297782 -379.669548) (xy 460.301853 -379.613926) (xy 460.313979 -379.559489)
			(xy 460.333902 -379.507398) (xy 460.361198 -379.458763) (xy 460.395284 -379.41462) (xy 460.435433 -379.375911)
			(xy 460.480791 -379.34346) (xy 460.530391 -379.317959) (xy 460.583175 -379.299952) (xy 460.638018 -379.289822)
			(xy 460.693752 -379.287785) (xy 460.749189 -379.293885) (xy 460.803146 -379.307991) (xy 460.854475 -379.329803)
			(xy 460.902081 -379.358857) (xy 460.944949 -379.394532) (xy 460.982166 -379.436069) (xy 461.012939 -379.482582)
			(xy 461.036611 -379.533079) (xy 461.052679 -379.586486) (xy 461.060799 -379.641662) (xy 461.061308 -379.669548)
			(xy 461.060799 -379.697434) (xy 461.052679 -379.75261) (xy 461.036611 -379.806017) (xy 461.012939 -379.856514)
			(xy 460.982166 -379.903027) (xy 460.944949 -379.944564) (xy 460.902081 -379.980239) (xy 460.854475 -380.009293)
			(xy 460.803146 -380.031105) (xy 460.749189 -380.045211) (xy 460.693752 -380.051311) (xy 460.638018 -380.049274)
			(xy 460.583175 -380.039144) (xy 460.530391 -380.021137) (xy 460.480791 -379.995636) (xy 460.435433 -379.963185)
			(xy 460.395284 -379.924476) (xy 460.361198 -379.880333) (xy 460.333902 -379.831698) (xy 460.313979 -379.779607)
			(xy 460.301853 -379.72517) (xy 460.297782 -379.669548) (xy 432.645058 -379.669548) (xy 432.645058 -380.05258)
			(xy 438.059828 -380.05258) (xy 438.063899 -379.996958) (xy 438.076025 -379.942521) (xy 438.095948 -379.89043)
			(xy 438.123244 -379.841795) (xy 438.15733 -379.797652) (xy 438.197479 -379.758943) (xy 438.242837 -379.726492)
			(xy 438.292437 -379.700991) (xy 438.345221 -379.682984) (xy 438.400064 -379.672854) (xy 438.455798 -379.670817)
			(xy 438.511235 -379.676917) (xy 438.565192 -379.691023) (xy 438.616521 -379.712835) (xy 438.664127 -379.741889)
			(xy 438.706995 -379.777564) (xy 438.744212 -379.819101) (xy 438.774985 -379.865614) (xy 438.798657 -379.916111)
			(xy 438.814725 -379.969518) (xy 438.822845 -380.024694) (xy 438.823354 -380.05258) (xy 438.822845 -380.080466)
			(xy 438.814725 -380.135642) (xy 438.798657 -380.189049) (xy 438.774985 -380.239546) (xy 438.744212 -380.286059)
			(xy 438.706995 -380.327596) (xy 438.664127 -380.363271) (xy 438.616521 -380.392325) (xy 438.565192 -380.414137)
			(xy 438.511235 -380.428243) (xy 438.455798 -380.434343) (xy 438.400064 -380.432306) (xy 438.345221 -380.422176)
			(xy 438.292437 -380.404169) (xy 438.242837 -380.378668) (xy 438.197479 -380.346217) (xy 438.15733 -380.307508)
			(xy 438.123244 -380.263365) (xy 438.095948 -380.21473) (xy 438.076025 -380.162639) (xy 438.063899 -380.108202)
			(xy 438.059828 -380.05258) (xy 432.645058 -380.05258) (xy 432.645058 -380.807468) (xy 432.645509 -380.820935)
			(xy 432.652627 -380.846914) (xy 432.666297 -380.870124) (xy 432.685564 -380.888948) (xy 432.709086 -380.902072)
			(xy 432.735224 -380.908584) (xy 432.762155 -380.908027) (xy 432.788001 -380.900442) (xy 432.799744 -380.893828)
			(xy 432.822391 -380.880439) (xy 432.870583 -380.859333) (xy 432.921218 -380.845052) (xy 432.973336 -380.837866)
			(xy 432.999642 -380.83744) (xy 433.026888 -380.837929) (xy 433.080824 -380.845689) (xy 433.133107 -380.861046)
			(xy 433.182673 -380.883687) (xy 433.228512 -380.913151) (xy 433.269692 -380.948838) (xy 433.305375 -380.990021)
			(xy 433.334833 -381.035864) (xy 433.357468 -381.085432) (xy 433.37282 -381.137717) (xy 433.380574 -381.191654)
			(xy 433.380574 -381.246146) (xy 433.37282 -381.300083) (xy 433.357468 -381.352368) (xy 433.334833 -381.401936)
			(xy 433.333433 -381.404114) (xy 461.463388 -381.404114) (xy 461.467459 -381.348492) (xy 461.479585 -381.294055)
			(xy 461.499508 -381.241964) (xy 461.526804 -381.193329) (xy 461.56089 -381.149186) (xy 461.601039 -381.110477)
			(xy 461.646397 -381.078026) (xy 461.695997 -381.052525) (xy 461.748781 -381.034518) (xy 461.803624 -381.024388)
			(xy 461.859358 -381.022351) (xy 461.914795 -381.028451) (xy 461.968752 -381.042557) (xy 462.020081 -381.064369)
			(xy 462.067687 -381.093423) (xy 462.110555 -381.129098) (xy 462.147772 -381.170635) (xy 462.178545 -381.217148)
			(xy 462.202217 -381.267645) (xy 462.218285 -381.321052) (xy 462.226405 -381.376228) (xy 462.226914 -381.404114)
			(xy 462.226405 -381.432) (xy 462.218285 -381.487176) (xy 462.202217 -381.540583) (xy 462.193558 -381.559054)
			(xy 463.166712 -381.559054) (xy 463.170783 -381.503432) (xy 463.182909 -381.448995) (xy 463.202832 -381.396904)
			(xy 463.230128 -381.348269) (xy 463.264214 -381.304126) (xy 463.304363 -381.265417) (xy 463.349721 -381.232966)
			(xy 463.399321 -381.207465) (xy 463.452105 -381.189458) (xy 463.506948 -381.179328) (xy 463.562682 -381.177291)
			(xy 463.618119 -381.183391) (xy 463.672076 -381.197497) (xy 463.689681 -381.204978) (xy 464.315048 -381.204978)
			(xy 464.315541 -381.17613) (xy 464.324227 -381.119091) (xy 464.341412 -381.064014) (xy 464.366703 -381.012157)
			(xy 464.399522 -380.964704) (xy 464.418934 -380.943358) (xy 464.429105 -380.931769) (xy 464.442652 -380.904088)
			(xy 464.447314 -380.873626) (xy 464.442667 -380.843161) (xy 464.429135 -380.815473) (xy 464.418934 -380.803912)
			(xy 464.399513 -380.782577) (xy 464.366716 -380.735113) (xy 464.341441 -380.683251) (xy 464.324264 -380.628174)
			(xy 464.315577 -380.571139) (xy 464.315048 -380.542292) (xy 464.31557 -380.515043) (xy 464.323327 -380.461098)
			(xy 464.338681 -380.408807) (xy 464.361319 -380.359233) (xy 464.390782 -380.313384) (xy 464.42647 -380.272195)
			(xy 464.467656 -380.236504) (xy 464.513501 -380.207037) (xy 464.563073 -380.184393) (xy 464.615363 -380.169034)
			(xy 464.669307 -380.161273) (xy 464.696556 -380.160784) (xy 464.725296 -380.161278) (xy 464.782124 -380.169908)
			(xy 464.837015 -380.186966) (xy 464.888727 -380.212064) (xy 464.936088 -380.244635) (xy 464.957414 -380.263908)
			(xy 464.968948 -380.27398) (xy 464.996494 -380.287322) (xy 465.026756 -380.291907) (xy 465.057018 -380.287322)
			(xy 465.084564 -380.27398) (xy 465.096098 -380.263908) (xy 465.117398 -380.244606) (xy 465.164768 -380.212045)
			(xy 465.216486 -380.186959) (xy 465.271383 -380.169916) (xy 465.328215 -380.161301) (xy 465.356956 -380.160784)
			(xy 465.384207 -380.161296) (xy 465.438156 -380.169047) (xy 465.490453 -380.184397) (xy 465.540032 -380.207034)
			(xy 465.585885 -380.236496) (xy 465.627078 -380.272185) (xy 465.662772 -380.313373) (xy 465.692241 -380.359222)
			(xy 465.714885 -380.408799) (xy 465.730242 -380.461093) (xy 465.738 -380.515041) (xy 465.738464 -380.542292)
			(xy 465.737949 -380.571139) (xy 465.729268 -380.628177) (xy 465.712088 -380.683254) (xy 465.686802 -380.735112)
			(xy 465.653988 -380.782565) (xy 465.634578 -380.803912) (xy 465.624387 -380.815468) (xy 465.610927 -380.843173)
			(xy 465.606307 -380.873626) (xy 465.610943 -380.904076) (xy 465.624416 -380.931774) (xy 465.634578 -380.943358)
			(xy 465.653987 -380.964704) (xy 465.686785 -381.012165) (xy 465.712063 -381.064025) (xy 465.729243 -381.119099)
			(xy 465.737933 -381.176132) (xy 465.738464 -381.204978) (xy 465.738024 -381.232232) (xy 465.730269 -381.286186)
			(xy 465.714913 -381.338487) (xy 465.69227 -381.38807) (xy 465.662801 -381.433926) (xy 465.627104 -381.47512)
			(xy 465.585908 -381.510814) (xy 465.540051 -381.540281) (xy 465.490467 -381.562921) (xy 465.438165 -381.578274)
			(xy 465.38421 -381.586026) (xy 465.356956 -381.586486) (xy 465.328217 -381.585966) (xy 465.271391 -381.577339)
			(xy 465.216501 -381.560287) (xy 465.164789 -381.535195) (xy 465.117426 -381.502631) (xy 465.096098 -381.483362)
			(xy 465.084564 -381.47329) (xy 465.057018 -381.459948) (xy 465.026756 -381.455363) (xy 464.996494 -381.459948)
			(xy 464.968948 -381.47329) (xy 464.957414 -381.483362) (xy 464.936105 -381.502654) (xy 464.888738 -381.535217)
			(xy 464.837022 -381.560305) (xy 464.782127 -381.577351) (xy 464.725296 -381.585968) (xy 464.696556 -381.586486)
			(xy 464.669303 -381.586063) (xy 464.615352 -381.5783) (xy 464.563054 -381.562938) (xy 464.513475 -381.54029)
			(xy 464.467624 -381.510817) (xy 464.426434 -381.475119) (xy 464.390743 -381.433923) (xy 464.361278 -381.388067)
			(xy 464.338639 -381.338484) (xy 464.323286 -381.286184) (xy 464.315532 -381.232231) (xy 464.315048 -381.204978)
			(xy 463.689681 -381.204978) (xy 463.723405 -381.219309) (xy 463.771011 -381.248363) (xy 463.813879 -381.284038)
			(xy 463.851096 -381.325575) (xy 463.881869 -381.372088) (xy 463.905541 -381.422585) (xy 463.921609 -381.475992)
			(xy 463.929729 -381.531168) (xy 463.930238 -381.559054) (xy 463.929729 -381.58694) (xy 463.921609 -381.642116)
			(xy 463.905541 -381.695523) (xy 463.881869 -381.74602) (xy 463.851096 -381.792533) (xy 463.813879 -381.83407)
			(xy 463.771011 -381.869745) (xy 463.723405 -381.898799) (xy 463.672076 -381.920611) (xy 463.618119 -381.934717)
			(xy 463.562682 -381.940817) (xy 463.506948 -381.93878) (xy 463.452105 -381.92865) (xy 463.399321 -381.910643)
			(xy 463.349721 -381.885142) (xy 463.304363 -381.852691) (xy 463.264214 -381.813982) (xy 463.230128 -381.769839)
			(xy 463.202832 -381.721204) (xy 463.182909 -381.669113) (xy 463.170783 -381.614676) (xy 463.166712 -381.559054)
			(xy 462.193558 -381.559054) (xy 462.178545 -381.59108) (xy 462.147772 -381.637593) (xy 462.110555 -381.67913)
			(xy 462.067687 -381.714805) (xy 462.020081 -381.743859) (xy 461.968752 -381.765671) (xy 461.914795 -381.779777)
			(xy 461.859358 -381.785877) (xy 461.803624 -381.78384) (xy 461.748781 -381.77371) (xy 461.695997 -381.755703)
			(xy 461.646397 -381.730202) (xy 461.601039 -381.697751) (xy 461.56089 -381.659042) (xy 461.526804 -381.614899)
			(xy 461.499508 -381.566264) (xy 461.479585 -381.514173) (xy 461.467459 -381.459736) (xy 461.463388 -381.404114)
			(xy 433.333433 -381.404114) (xy 433.305375 -381.447779) (xy 433.269692 -381.488962) (xy 433.228512 -381.524649)
			(xy 433.182673 -381.554113) (xy 433.133107 -381.576754) (xy 433.080824 -381.592111) (xy 433.026888 -381.599871)
			(xy 432.999642 -381.600456) (xy 432.973336 -381.600032) (xy 432.921219 -381.592841) (xy 432.870583 -381.578561)
			(xy 432.822388 -381.557463) (xy 432.799744 -381.544068) (xy 432.788042 -381.537389) (xy 432.762191 -381.529824)
			(xy 432.735261 -381.529284) (xy 432.709128 -381.535809) (xy 432.685612 -381.548943) (xy 432.666351 -381.567772)
			(xy 432.652686 -381.590983) (xy 432.64557 -381.616962) (xy 432.645058 -381.630428) (xy 432.645058 -382.524553)
			(xy 437.679785 -382.524553) (xy 437.679785 -382.470047) (xy 437.687543 -382.416096) (xy 437.7029 -382.363799)
			(xy 437.725544 -382.31422) (xy 437.755014 -382.268368) (xy 437.79071 -382.227177) (xy 437.831905 -382.191487)
			(xy 437.87776 -382.162022) (xy 437.927342 -382.139384) (xy 437.979641 -382.124033) (xy 438.033593 -382.116282)
			(xy 438.060846 -382.115822) (xy 438.090076 -382.11638) (xy 438.147851 -382.125317) (xy 438.203586 -382.142959)
			(xy 438.25598 -382.168894) (xy 438.303805 -382.202516) (xy 438.345945 -382.243038) (xy 438.364122 -382.265936)
			(xy 438.37256 -382.276333) (xy 438.393764 -382.29267) (xy 438.418483 -382.302943) (xy 438.445021 -382.306448)
			(xy 438.471559 -382.302943) (xy 438.496278 -382.29267) (xy 438.517482 -382.276333) (xy 438.52592 -382.265936)
			(xy 438.544107 -382.243043) (xy 438.586231 -382.2025) (xy 438.634051 -382.168863) (xy 438.686444 -382.14292)
			(xy 438.742184 -382.125279) (xy 438.799964 -382.116353) (xy 438.829196 -382.115822) (xy 438.856451 -382.116225)
			(xy 438.910407 -382.123982) (xy 438.962709 -382.139339) (xy 439.012294 -382.161983) (xy 439.058151 -382.191453)
			(xy 439.099348 -382.227149) (xy 439.135045 -382.268346) (xy 439.164515 -382.314203) (xy 439.171008 -382.32842)
			(xy 456.932282 -382.32842) (xy 456.936353 -382.272798) (xy 456.948479 -382.218361) (xy 456.968402 -382.16627)
			(xy 456.995698 -382.117635) (xy 457.029784 -382.073492) (xy 457.069933 -382.034783) (xy 457.115291 -382.002332)
			(xy 457.164891 -381.976831) (xy 457.217675 -381.958824) (xy 457.272518 -381.948694) (xy 457.328252 -381.946657)
			(xy 457.383689 -381.952757) (xy 457.437646 -381.966863) (xy 457.488975 -381.988675) (xy 457.536581 -382.017729)
			(xy 457.579449 -382.053404) (xy 457.616666 -382.094941) (xy 457.647439 -382.141454) (xy 457.671111 -382.191951)
			(xy 457.687179 -382.245358) (xy 457.695299 -382.300534) (xy 457.695808 -382.32842) (xy 457.695299 -382.356306)
			(xy 457.687179 -382.411482) (xy 457.678163 -382.44145) (xy 458.634082 -382.44145) (xy 458.638153 -382.385828)
			(xy 458.650279 -382.331391) (xy 458.670202 -382.2793) (xy 458.697498 -382.230665) (xy 458.731584 -382.186522)
			(xy 458.771733 -382.147813) (xy 458.817091 -382.115362) (xy 458.866691 -382.089861) (xy 458.919475 -382.071854)
			(xy 458.974318 -382.061724) (xy 459.030052 -382.059687) (xy 459.085489 -382.065787) (xy 459.139446 -382.079893)
			(xy 459.190775 -382.101705) (xy 459.238381 -382.130759) (xy 459.281249 -382.166434) (xy 459.318466 -382.207971)
			(xy 459.349239 -382.254484) (xy 459.372911 -382.304981) (xy 459.388979 -382.358388) (xy 459.389017 -382.358646)
			(xy 459.737458 -382.358646) (xy 459.741529 -382.303024) (xy 459.753655 -382.248587) (xy 459.773578 -382.196496)
			(xy 459.800874 -382.147861) (xy 459.83496 -382.103718) (xy 459.875109 -382.065009) (xy 459.920467 -382.032558)
			(xy 459.970067 -382.007057) (xy 460.022851 -381.98905) (xy 460.077694 -381.97892) (xy 460.133428 -381.976883)
			(xy 460.188865 -381.982983) (xy 460.242822 -381.997089) (xy 460.294151 -382.018901) (xy 460.341757 -382.047955)
			(xy 460.384625 -382.08363) (xy 460.421842 -382.125167) (xy 460.452615 -382.17168) (xy 460.476287 -382.222177)
			(xy 460.492355 -382.275584) (xy 460.500475 -382.33076) (xy 460.500984 -382.358646) (xy 460.500475 -382.386532)
			(xy 460.492355 -382.441708) (xy 460.476287 -382.495115) (xy 460.452615 -382.545612) (xy 460.421842 -382.592125)
			(xy 460.384625 -382.633662) (xy 460.341757 -382.669337) (xy 460.294151 -382.698391) (xy 460.242822 -382.720203)
			(xy 460.188865 -382.734309) (xy 460.133428 -382.740409) (xy 460.077694 -382.738372) (xy 460.022851 -382.728242)
			(xy 459.970067 -382.710235) (xy 459.920467 -382.684734) (xy 459.875109 -382.652283) (xy 459.83496 -382.613574)
			(xy 459.800874 -382.569431) (xy 459.773578 -382.520796) (xy 459.753655 -382.468705) (xy 459.741529 -382.414268)
			(xy 459.737458 -382.358646) (xy 459.389017 -382.358646) (xy 459.397099 -382.413564) (xy 459.397608 -382.44145)
			(xy 459.397099 -382.469336) (xy 459.388979 -382.524512) (xy 459.372911 -382.577919) (xy 459.349239 -382.628416)
			(xy 459.318466 -382.674929) (xy 459.281249 -382.716466) (xy 459.238381 -382.752141) (xy 459.190775 -382.781195)
			(xy 459.139446 -382.803007) (xy 459.085489 -382.817113) (xy 459.030052 -382.823213) (xy 458.974318 -382.821176)
			(xy 458.919475 -382.811046) (xy 458.866691 -382.793039) (xy 458.817091 -382.767538) (xy 458.771733 -382.735087)
			(xy 458.731584 -382.696378) (xy 458.697498 -382.652235) (xy 458.670202 -382.6036) (xy 458.650279 -382.551509)
			(xy 458.638153 -382.497072) (xy 458.634082 -382.44145) (xy 457.678163 -382.44145) (xy 457.671111 -382.464889)
			(xy 457.647439 -382.515386) (xy 457.616666 -382.561899) (xy 457.579449 -382.603436) (xy 457.536581 -382.639111)
			(xy 457.488975 -382.668165) (xy 457.437646 -382.689977) (xy 457.383689 -382.704083) (xy 457.328252 -382.710183)
			(xy 457.272518 -382.708146) (xy 457.217675 -382.698016) (xy 457.164891 -382.680009) (xy 457.115291 -382.654508)
			(xy 457.069933 -382.622057) (xy 457.029784 -382.583348) (xy 456.995698 -382.539205) (xy 456.968402 -382.49057)
			(xy 456.948479 -382.438479) (xy 456.936353 -382.384042) (xy 456.932282 -382.32842) (xy 439.171008 -382.32842)
			(xy 439.18716 -382.363787) (xy 439.202517 -382.416089) (xy 439.210275 -382.470045) (xy 439.210275 -382.524555)
			(xy 439.202517 -382.578511) (xy 439.18716 -382.630813) (xy 439.164515 -382.680397) (xy 439.135045 -382.726254)
			(xy 439.099348 -382.767451) (xy 439.058151 -382.803147) (xy 439.012294 -382.832617) (xy 438.962709 -382.855261)
			(xy 438.910407 -382.870618) (xy 438.856451 -382.878375) (xy 438.829196 -382.878838) (xy 438.799966 -382.878266)
			(xy 438.742192 -382.869334) (xy 438.686456 -382.851696) (xy 438.634062 -382.825763) (xy 438.586236 -382.792143)
			(xy 438.544097 -382.751622) (xy 438.52592 -382.728724) (xy 438.517509 -382.718283) (xy 438.496323 -382.701865)
			(xy 438.471591 -382.691536) (xy 438.445021 -382.688012) (xy 438.418451 -382.691536) (xy 438.393719 -382.701865)
			(xy 438.372533 -382.718283) (xy 438.364122 -382.728724) (xy 438.345962 -382.751639) (xy 438.303829 -382.792173)
			(xy 438.256003 -382.825801) (xy 438.203604 -382.851735) (xy 438.14786 -382.869367) (xy 438.090079 -382.878283)
			(xy 438.060846 -382.878838) (xy 438.033593 -382.878318) (xy 437.979641 -382.870567) (xy 437.927342 -382.855216)
			(xy 437.87776 -382.832578) (xy 437.831905 -382.803113) (xy 437.79071 -382.767423) (xy 437.755014 -382.726232)
			(xy 437.725544 -382.68038) (xy 437.7029 -382.630801) (xy 437.687543 -382.578504) (xy 437.679785 -382.524553)
			(xy 432.645058 -382.524553) (xy 432.645058 -382.903853) (xy 442.76693 -382.903853) (xy 442.76693 -382.849347)
			(xy 442.774686 -382.795396) (xy 442.790041 -382.743098) (xy 442.812682 -382.693518) (xy 442.842148 -382.647664)
			(xy 442.87784 -382.606469) (xy 442.91903 -382.570773) (xy 442.964881 -382.541302) (xy 443.014459 -382.518656)
			(xy 443.066755 -382.503295) (xy 443.120705 -382.495533) (xy 443.147958 -382.495044) (xy 443.176875 -382.495576)
			(xy 443.234046 -382.5043) (xy 443.289245 -382.521554) (xy 443.341207 -382.546943) (xy 443.388742 -382.579885)
			(xy 443.430758 -382.619625) (xy 443.448948 -382.64211) (xy 443.458845 -382.653915) (xy 443.484169 -382.671434)
			(xy 443.513562 -382.68061) (xy 443.544354 -382.68061) (xy 443.573747 -382.671434) (xy 443.599071 -382.653915)
			(xy 443.608968 -382.64211) (xy 443.62718 -382.619644) (xy 443.669195 -382.579907) (xy 443.716725 -382.546966)
			(xy 443.768683 -382.521574) (xy 443.823877 -382.504314) (xy 443.881043 -382.495581) (xy 443.909958 -382.495044)
			(xy 443.937209 -382.4956) (xy 443.991158 -382.503351) (xy 444.043454 -382.518702) (xy 444.093034 -382.541339)
			(xy 444.138886 -382.570802) (xy 444.180079 -382.606492) (xy 444.215772 -382.64768) (xy 444.245241 -382.69353)
			(xy 444.267883 -382.743106) (xy 444.28324 -382.795401) (xy 444.290997 -382.849349) (xy 444.290997 -382.903851)
			(xy 444.28324 -382.957799) (xy 444.26958 -383.004314) (xy 460.372458 -383.004314) (xy 460.376529 -382.948692)
			(xy 460.388655 -382.894255) (xy 460.408578 -382.842164) (xy 460.435874 -382.793529) (xy 460.46996 -382.749386)
			(xy 460.510109 -382.710677) (xy 460.555467 -382.678226) (xy 460.605067 -382.652725) (xy 460.657851 -382.634718)
			(xy 460.712694 -382.624588) (xy 460.768428 -382.622551) (xy 460.823865 -382.628651) (xy 460.877822 -382.642757)
			(xy 460.929151 -382.664569) (xy 460.976757 -382.693623) (xy 461.019625 -382.729298) (xy 461.056842 -382.770835)
			(xy 461.087615 -382.817348) (xy 461.111287 -382.867845) (xy 461.127355 -382.921252) (xy 461.135475 -382.976428)
			(xy 461.135984 -383.004314) (xy 461.135475 -383.0322) (xy 461.127355 -383.087376) (xy 461.111287 -383.140783)
			(xy 461.087615 -383.19128) (xy 461.056842 -383.237793) (xy 461.019625 -383.27933) (xy 460.976757 -383.315005)
			(xy 460.929151 -383.344059) (xy 460.877822 -383.365871) (xy 460.823865 -383.379977) (xy 460.768428 -383.386077)
			(xy 460.712694 -383.38404) (xy 460.657851 -383.37391) (xy 460.605067 -383.355903) (xy 460.555467 -383.330402)
			(xy 460.510109 -383.297951) (xy 460.46996 -383.259242) (xy 460.435874 -383.215099) (xy 460.408578 -383.166464)
			(xy 460.388655 -383.114373) (xy 460.376529 -383.059936) (xy 460.372458 -383.004314) (xy 444.26958 -383.004314)
			(xy 444.267883 -383.010094) (xy 444.245241 -383.05967) (xy 444.215772 -383.10552) (xy 444.180079 -383.146708)
			(xy 444.138886 -383.182398) (xy 444.093034 -383.211861) (xy 444.043454 -383.234498) (xy 443.991158 -383.249849)
			(xy 443.937209 -383.2576) (xy 443.909958 -383.25806) (xy 443.881042 -383.257515) (xy 443.823871 -383.248794)
			(xy 443.768672 -383.231542) (xy 443.71671 -383.206156) (xy 443.669176 -383.173216) (xy 443.627158 -383.133478)
			(xy 443.608968 -383.110994) (xy 443.599071 -383.099189) (xy 443.573747 -383.08167) (xy 443.544354 -383.072494)
			(xy 443.513562 -383.072494) (xy 443.484169 -383.08167) (xy 443.458845 -383.099189) (xy 443.448948 -383.110994)
			(xy 443.430728 -383.133453) (xy 443.388715 -383.17319) (xy 443.341186 -383.206132) (xy 443.28923 -383.231525)
			(xy 443.234038 -383.248786) (xy 443.176872 -383.257522) (xy 443.147958 -383.25806) (xy 443.120705 -383.257667)
			(xy 443.066755 -383.249905) (xy 443.014459 -383.234544) (xy 442.964881 -383.211898) (xy 442.91903 -383.182427)
			(xy 442.87784 -383.146731) (xy 442.842148 -383.105536) (xy 442.812682 -383.059682) (xy 442.790041 -383.010102)
			(xy 442.774686 -382.957804) (xy 442.76693 -382.903853) (xy 432.645058 -382.903853) (xy 432.645058 -384.569253)
			(xy 437.679785 -384.569253) (xy 437.679785 -384.514747) (xy 437.687543 -384.460796) (xy 437.7029 -384.408499)
			(xy 437.725544 -384.35892) (xy 437.755014 -384.313068) (xy 437.79071 -384.271877) (xy 437.831905 -384.236187)
			(xy 437.87776 -384.206722) (xy 437.927342 -384.184084) (xy 437.979641 -384.168733) (xy 438.033593 -384.160982)
			(xy 438.060846 -384.160522) (xy 438.090076 -384.16108) (xy 438.147851 -384.170017) (xy 438.203586 -384.187659)
			(xy 438.25598 -384.213594) (xy 438.303805 -384.247216) (xy 438.345945 -384.287738) (xy 438.364122 -384.310636)
			(xy 438.37256 -384.321033) (xy 438.393764 -384.33737) (xy 438.418483 -384.347643) (xy 438.445021 -384.351148)
			(xy 438.471559 -384.347643) (xy 438.496278 -384.33737) (xy 438.517482 -384.321033) (xy 438.52592 -384.310636)
			(xy 438.544107 -384.287743) (xy 438.586231 -384.2472) (xy 438.634051 -384.213563) (xy 438.686444 -384.18762)
			(xy 438.742184 -384.169979) (xy 438.799964 -384.161053) (xy 438.829196 -384.160522) (xy 438.856451 -384.160925)
			(xy 438.910407 -384.168682) (xy 438.962709 -384.184039) (xy 439.012294 -384.206683) (xy 439.058151 -384.236153)
			(xy 439.099348 -384.271849) (xy 439.135045 -384.313046) (xy 439.164515 -384.358903) (xy 439.18716 -384.408487)
			(xy 439.202517 -384.460789) (xy 439.210275 -384.514745) (xy 439.210275 -384.569255) (xy 439.202517 -384.623211)
			(xy 439.18716 -384.675513) (xy 439.164515 -384.725097) (xy 439.135045 -384.770954) (xy 439.099348 -384.812151)
			(xy 439.058151 -384.847847) (xy 439.012294 -384.877317) (xy 438.962709 -384.899961) (xy 438.910407 -384.915318)
			(xy 438.856451 -384.923075) (xy 438.829196 -384.923538) (xy 438.799966 -384.922966) (xy 438.742192 -384.914034)
			(xy 438.686456 -384.896396) (xy 438.634062 -384.870463) (xy 438.586236 -384.836843) (xy 438.544097 -384.796322)
			(xy 438.52592 -384.773424) (xy 438.517509 -384.762983) (xy 438.496323 -384.746565) (xy 438.471591 -384.736236)
			(xy 438.445021 -384.732712) (xy 438.418451 -384.736236) (xy 438.393719 -384.746565) (xy 438.372533 -384.762983)
			(xy 438.364122 -384.773424) (xy 438.345962 -384.796339) (xy 438.303829 -384.836873) (xy 438.256003 -384.870501)
			(xy 438.203604 -384.896435) (xy 438.14786 -384.914067) (xy 438.090079 -384.922983) (xy 438.060846 -384.923538)
			(xy 438.033593 -384.923018) (xy 437.979641 -384.915267) (xy 437.927342 -384.899916) (xy 437.87776 -384.877278)
			(xy 437.831905 -384.847813) (xy 437.79071 -384.812123) (xy 437.755014 -384.770932) (xy 437.725544 -384.72508)
			(xy 437.7029 -384.675501) (xy 437.687543 -384.623204) (xy 437.679785 -384.569253) (xy 432.645058 -384.569253)
			(xy 432.645058 -385.760468) (xy 432.645509 -385.773935) (xy 432.652627 -385.799914) (xy 432.666297 -385.823124)
			(xy 432.685564 -385.841948) (xy 432.709086 -385.855072) (xy 432.735224 -385.861584) (xy 432.762155 -385.861027)
			(xy 432.788001 -385.853442) (xy 432.799744 -385.846828) (xy 432.822391 -385.833439) (xy 432.870583 -385.812333)
			(xy 432.921218 -385.798052) (xy 432.973336 -385.790866) (xy 432.999642 -385.79044) (xy 433.026888 -385.790929)
			(xy 433.080824 -385.798689) (xy 433.133107 -385.814046) (xy 433.182673 -385.836687) (xy 433.228512 -385.866151)
			(xy 433.269692 -385.901838) (xy 433.305375 -385.943021) (xy 433.334833 -385.988864) (xy 433.357468 -386.038432)
			(xy 433.37282 -386.090717) (xy 433.380574 -386.144654) (xy 433.380574 -386.199146) (xy 433.37282 -386.253083)
			(xy 433.357468 -386.305368) (xy 433.337608 -386.348858) (xy 438.101609 -386.348858) (xy 438.101609 -386.294342)
			(xy 438.109368 -386.240381) (xy 438.124728 -386.188074) (xy 438.147376 -386.138485) (xy 438.176851 -386.092624)
			(xy 438.212554 -386.051425) (xy 438.253756 -386.015727) (xy 438.29962 -385.986257) (xy 438.349211 -385.963614)
			(xy 438.40152 -385.94826) (xy 438.455482 -385.940506) (xy 438.48274 -385.940046) (xy 438.511656 -385.94059)
			(xy 438.568827 -385.949311) (xy 438.624026 -385.966563) (xy 438.675988 -385.991949) (xy 438.723523 -386.024889)
			(xy 438.76554 -386.064628) (xy 438.78373 -386.087112) (xy 438.793627 -386.098917) (xy 438.818951 -386.116436)
			(xy 438.848344 -386.125612) (xy 438.879136 -386.125612) (xy 438.908529 -386.116436) (xy 438.933853 -386.098917)
			(xy 438.94375 -386.087112) (xy 438.960503 -386.066329) (xy 438.998857 -386.029199) (xy 439.042011 -385.997777)
			(xy 439.089125 -385.972678) (xy 439.139277 -385.954392) (xy 439.191488 -385.943275) (xy 439.24474 -385.939545)
			(xy 439.297992 -385.943275) (xy 439.350203 -385.954392) (xy 439.400355 -385.972678) (xy 439.447469 -385.997777)
			(xy 439.490623 -386.029199) (xy 439.528977 -386.066329) (xy 439.54573 -386.087112) (xy 439.555627 -386.098917)
			(xy 439.580951 -386.116436) (xy 439.610344 -386.125612) (xy 439.641136 -386.125612) (xy 439.670529 -386.116436)
			(xy 439.695853 -386.098917) (xy 439.70575 -386.087112) (xy 439.722503 -386.066329) (xy 439.760857 -386.029199)
			(xy 439.804011 -385.997777) (xy 439.851125 -385.972678) (xy 439.901277 -385.954392) (xy 439.953488 -385.943275)
			(xy 440.00674 -385.939545) (xy 440.059992 -385.943275) (xy 440.112203 -385.954392) (xy 440.162355 -385.972678)
			(xy 440.209469 -385.997777) (xy 440.252623 -386.029199) (xy 440.290977 -386.066329) (xy 440.30773 -386.087112)
			(xy 440.317627 -386.098917) (xy 440.342951 -386.116436) (xy 440.372344 -386.125612) (xy 440.403136 -386.125612)
			(xy 440.432529 -386.116436) (xy 440.457853 -386.098917) (xy 440.46775 -386.087112) (xy 440.485972 -386.064655)
			(xy 440.527985 -386.024918) (xy 440.575513 -385.991975) (xy 440.627469 -385.966582) (xy 440.682661 -385.94932)
			(xy 440.739826 -385.940585) (xy 440.76874 -385.940046) (xy 440.795986 -385.940627) (xy 440.849923 -385.948387)
			(xy 440.902206 -385.963744) (xy 440.951773 -385.986384) (xy 440.997612 -386.015848) (xy 441.038793 -386.051535)
			(xy 441.074476 -386.09272) (xy 441.103935 -386.138563) (xy 441.12657 -386.188131) (xy 441.141921 -386.240416)
			(xy 441.149676 -386.294354) (xy 441.149676 -386.348846) (xy 441.141921 -386.402784) (xy 441.12657 -386.455069)
			(xy 441.103935 -386.504637) (xy 441.074476 -386.55048) (xy 441.038793 -386.591665) (xy 440.997612 -386.627352)
			(xy 440.951773 -386.656816) (xy 440.902206 -386.679456) (xy 440.849923 -386.694813) (xy 440.795986 -386.702573)
			(xy 440.76874 -386.703062) (xy 440.739823 -386.702529) (xy 440.682652 -386.693805) (xy 440.627453 -386.676551)
			(xy 440.575491 -386.651162) (xy 440.527957 -386.618221) (xy 440.48594 -386.578481) (xy 440.46775 -386.555996)
			(xy 440.457853 -386.544191) (xy 440.432529 -386.526672) (xy 440.403136 -386.517496) (xy 440.372344 -386.517496)
			(xy 440.342951 -386.526672) (xy 440.317627 -386.544191) (xy 440.30773 -386.555996) (xy 440.290977 -386.576779)
			(xy 440.252623 -386.613909) (xy 440.209469 -386.645331) (xy 440.162355 -386.67043) (xy 440.112203 -386.688716)
			(xy 440.059992 -386.699833) (xy 440.00674 -386.703563) (xy 439.953488 -386.699833) (xy 439.901277 -386.688716)
			(xy 439.851125 -386.67043) (xy 439.804011 -386.645331) (xy 439.760857 -386.613909) (xy 439.722503 -386.576779)
			(xy 439.70575 -386.555996) (xy 439.695853 -386.544191) (xy 439.670529 -386.526672) (xy 439.641136 -386.517496)
			(xy 439.610344 -386.517496) (xy 439.580951 -386.526672) (xy 439.555627 -386.544191) (xy 439.54573 -386.555996)
			(xy 439.528977 -386.576779) (xy 439.490623 -386.613909) (xy 439.447469 -386.645331) (xy 439.400355 -386.67043)
			(xy 439.350203 -386.688716) (xy 439.297992 -386.699833) (xy 439.24474 -386.703563) (xy 439.191488 -386.699833)
			(xy 439.139277 -386.688716) (xy 439.089125 -386.67043) (xy 439.042011 -386.645331) (xy 438.998857 -386.613909)
			(xy 438.960503 -386.576779) (xy 438.94375 -386.555996) (xy 438.933853 -386.544191) (xy 438.908529 -386.526672)
			(xy 438.879136 -386.517496) (xy 438.848344 -386.517496) (xy 438.818951 -386.526672) (xy 438.793627 -386.544191)
			(xy 438.78373 -386.555996) (xy 438.765521 -386.578464) (xy 438.723505 -386.618201) (xy 438.675974 -386.651142)
			(xy 438.624016 -386.676533) (xy 438.568822 -386.693792) (xy 438.511655 -386.702525) (xy 438.48274 -386.703062)
			(xy 438.455482 -386.702694) (xy 438.40152 -386.69494) (xy 438.349211 -386.679586) (xy 438.29962 -386.656943)
			(xy 438.253756 -386.627473) (xy 438.212554 -386.591775) (xy 438.176851 -386.550576) (xy 438.147376 -386.504715)
			(xy 438.124728 -386.455126) (xy 438.109368 -386.402819) (xy 438.101609 -386.348858) (xy 433.337608 -386.348858)
			(xy 433.334833 -386.354936) (xy 433.305375 -386.400779) (xy 433.269692 -386.441962) (xy 433.228512 -386.477649)
			(xy 433.182673 -386.507113) (xy 433.133107 -386.529754) (xy 433.080824 -386.545111) (xy 433.026888 -386.552871)
			(xy 432.999642 -386.553456) (xy 432.973336 -386.553032) (xy 432.921219 -386.545841) (xy 432.870583 -386.531561)
			(xy 432.822388 -386.510463) (xy 432.799744 -386.497068) (xy 432.788042 -386.490389) (xy 432.762191 -386.482824)
			(xy 432.735261 -386.482284) (xy 432.709128 -386.488809) (xy 432.685612 -386.501943) (xy 432.666351 -386.520772)
			(xy 432.652686 -386.543983) (xy 432.64557 -386.569962) (xy 432.645058 -386.583428) (xy 432.645058 -387.371153)
			(xy 442.672159 -387.371153) (xy 442.672159 -387.316647) (xy 442.679917 -387.262695) (xy 442.695273 -387.210396)
			(xy 442.717917 -387.160816) (xy 442.747386 -387.114962) (xy 442.783081 -387.07377) (xy 442.824275 -387.038076)
			(xy 442.87013 -387.008609) (xy 442.919711 -386.985968) (xy 442.972011 -386.970613) (xy 443.025963 -386.962858)
			(xy 443.053216 -386.962396) (xy 443.082132 -386.962938) (xy 443.139304 -386.971657) (xy 443.194504 -386.988908)
			(xy 443.246467 -387.014295) (xy 443.294001 -387.047236) (xy 443.336017 -387.086977) (xy 443.354206 -387.109462)
			(xy 443.364103 -387.121267) (xy 443.389427 -387.138786) (xy 443.41882 -387.147962) (xy 443.449612 -387.147962)
			(xy 443.479005 -387.138786) (xy 443.504329 -387.121267) (xy 443.514226 -387.109462) (xy 443.532393 -387.086958)
			(xy 443.574419 -387.047226) (xy 443.621959 -387.01429) (xy 443.673925 -386.988906) (xy 443.729126 -386.971654)
			(xy 443.786299 -386.962929) (xy 443.815216 -386.962396) (xy 443.842467 -386.962875) (xy 443.896413 -386.970633)
			(xy 443.948707 -386.98599) (xy 443.998282 -387.008632) (xy 444.044131 -387.038099) (xy 444.08532 -387.073791)
			(xy 444.12101 -387.114981) (xy 444.150475 -387.160832) (xy 444.173116 -387.210408) (xy 444.18847 -387.262702)
			(xy 444.191125 -387.281166) (xy 455.690476 -387.281166) (xy 455.694547 -387.225544) (xy 455.706673 -387.171107)
			(xy 455.726596 -387.119016) (xy 455.753892 -387.070381) (xy 455.787978 -387.026238) (xy 455.828127 -386.987529)
			(xy 455.873485 -386.955078) (xy 455.923085 -386.929577) (xy 455.975869 -386.91157) (xy 456.030712 -386.90144)
			(xy 456.086446 -386.899403) (xy 456.141883 -386.905503) (xy 456.19584 -386.919609) (xy 456.247169 -386.941421)
			(xy 456.294775 -386.970475) (xy 456.337643 -387.00615) (xy 456.37486 -387.047687) (xy 456.405633 -387.0942)
			(xy 456.429305 -387.144697) (xy 456.445373 -387.198104) (xy 456.453493 -387.25328) (xy 456.454002 -387.281166)
			(xy 456.453493 -387.309052) (xy 456.445373 -387.364228) (xy 456.429305 -387.417635) (xy 456.405633 -387.468132)
			(xy 456.37486 -387.514645) (xy 456.337643 -387.556182) (xy 456.294775 -387.591857) (xy 456.247169 -387.620911)
			(xy 456.19584 -387.642723) (xy 456.141883 -387.656829) (xy 456.086446 -387.662929) (xy 456.030712 -387.660892)
			(xy 455.975869 -387.650762) (xy 455.923085 -387.632755) (xy 455.873485 -387.607254) (xy 455.828127 -387.574803)
			(xy 455.787978 -387.536094) (xy 455.753892 -387.491951) (xy 455.726596 -387.443316) (xy 455.706673 -387.391225)
			(xy 455.694547 -387.336788) (xy 455.690476 -387.281166) (xy 444.191125 -387.281166) (xy 444.196226 -387.316649)
			(xy 444.196226 -387.371151) (xy 444.18847 -387.425098) (xy 444.173116 -387.477392) (xy 444.150475 -387.526968)
			(xy 444.12101 -387.572819) (xy 444.08532 -387.614009) (xy 444.044131 -387.649701) (xy 443.998282 -387.679168)
			(xy 443.948707 -387.70181) (xy 443.896413 -387.717167) (xy 443.842467 -387.724925) (xy 443.815216 -387.725412)
			(xy 443.786298 -387.724916) (xy 443.729124 -387.716187) (xy 443.673923 -387.698927) (xy 443.621961 -387.673531)
			(xy 443.574428 -387.640582) (xy 443.532414 -387.600835) (xy 443.514226 -387.578346) (xy 443.504329 -387.566541)
			(xy 443.479005 -387.549022) (xy 443.449612 -387.539846) (xy 443.41882 -387.539846) (xy 443.389427 -387.549022)
			(xy 443.364103 -387.566541) (xy 443.354206 -387.578346) (xy 443.336023 -387.600836) (xy 443.294 -387.640569)
			(xy 443.246463 -387.673506) (xy 443.194501 -387.698893) (xy 443.139302 -387.716148) (xy 443.082132 -387.724877)
			(xy 443.053216 -387.725412) (xy 443.025963 -387.724942) (xy 442.972011 -387.717187) (xy 442.919711 -387.701832)
			(xy 442.87013 -387.679191) (xy 442.824275 -387.649724) (xy 442.783081 -387.61403) (xy 442.747386 -387.572838)
			(xy 442.717917 -387.526984) (xy 442.695273 -387.477404) (xy 442.679917 -387.425105) (xy 442.672159 -387.371153)
			(xy 432.645058 -387.371153) (xy 432.645058 -388.760253) (xy 438.101685 -388.760253) (xy 438.101685 -388.705747)
			(xy 438.109443 -388.651797) (xy 438.1248 -388.5995) (xy 438.147443 -388.549921) (xy 438.176913 -388.50407)
			(xy 438.212608 -388.46288) (xy 438.253802 -388.427189) (xy 438.299657 -388.397724) (xy 438.349238 -388.375086)
			(xy 438.401536 -388.359734) (xy 438.455487 -388.351983) (xy 438.48274 -388.351522) (xy 438.511656 -388.352075)
			(xy 438.568826 -388.360796) (xy 438.624024 -388.378046) (xy 438.675986 -388.403431) (xy 438.723521 -388.436369)
			(xy 438.765539 -388.476105) (xy 438.78373 -388.498588) (xy 438.793627 -388.510393) (xy 438.818951 -388.527912)
			(xy 438.848344 -388.537088) (xy 438.879136 -388.537088) (xy 438.908529 -388.527912) (xy 438.933853 -388.510393)
			(xy 438.94375 -388.498588) (xy 438.960503 -388.477805) (xy 438.998857 -388.440675) (xy 439.042011 -388.409253)
			(xy 439.089125 -388.384154) (xy 439.139277 -388.365868) (xy 439.191488 -388.354751) (xy 439.24474 -388.351021)
			(xy 439.297992 -388.354751) (xy 439.350203 -388.365868) (xy 439.400355 -388.384154) (xy 439.447469 -388.409253)
			(xy 439.490623 -388.440675) (xy 439.528977 -388.477805) (xy 439.54573 -388.498588) (xy 439.555627 -388.510393)
			(xy 439.580951 -388.527912) (xy 439.610344 -388.537088) (xy 439.641136 -388.537088) (xy 439.670529 -388.527912)
			(xy 439.695853 -388.510393) (xy 439.70575 -388.498588) (xy 439.722503 -388.477805) (xy 439.760857 -388.440675)
			(xy 439.804011 -388.409253) (xy 439.851125 -388.384154) (xy 439.901277 -388.365868) (xy 439.953488 -388.354751)
			(xy 440.00674 -388.351021) (xy 440.059992 -388.354751) (xy 440.112203 -388.365868) (xy 440.162355 -388.384154)
			(xy 440.209469 -388.409253) (xy 440.252623 -388.440675) (xy 440.290977 -388.477805) (xy 440.30773 -388.498588)
			(xy 440.317627 -388.510393) (xy 440.342951 -388.527912) (xy 440.372344 -388.537088) (xy 440.403136 -388.537088)
			(xy 440.432529 -388.527912) (xy 440.457853 -388.510393) (xy 440.46775 -388.498588) (xy 440.485966 -388.476126)
			(xy 440.527981 -388.43639) (xy 440.575511 -388.403449) (xy 440.627467 -388.378057) (xy 440.68266 -388.360796)
			(xy 440.739826 -388.352061) (xy 440.76874 -388.351522) (xy 440.795992 -388.351951) (xy 440.849939 -388.359712)
			(xy 440.902233 -388.375072) (xy 440.951809 -388.397717) (xy 440.997658 -388.427187) (xy 441.038847 -388.462881)
			(xy 441.074537 -388.504074) (xy 441.104002 -388.549926) (xy 441.126642 -388.599504) (xy 441.141996 -388.6518)
			(xy 441.149752 -388.705748) (xy 441.149752 -388.760252) (xy 441.141996 -388.8142) (xy 441.126642 -388.866496)
			(xy 441.104002 -388.916074) (xy 441.074537 -388.961926) (xy 441.038847 -389.003119) (xy 440.997658 -389.038813)
			(xy 440.951809 -389.068283) (xy 440.902233 -389.090928) (xy 440.849939 -389.106288) (xy 440.795992 -389.114049)
			(xy 440.76874 -389.114538) (xy 440.739823 -389.114015) (xy 440.682651 -389.10529) (xy 440.627451 -389.088035)
			(xy 440.575489 -389.062644) (xy 440.527955 -389.0297) (xy 440.485939 -388.989958) (xy 440.46775 -388.967472)
			(xy 440.457853 -388.955667) (xy 440.432529 -388.938148) (xy 440.403136 -388.928972) (xy 440.372344 -388.928972)
			(xy 440.342951 -388.938148) (xy 440.317627 -388.955667) (xy 440.30773 -388.967472) (xy 440.290977 -388.988255)
			(xy 440.252623 -389.025385) (xy 440.209469 -389.056807) (xy 440.162355 -389.081906) (xy 440.112203 -389.100192)
			(xy 440.059992 -389.111309) (xy 440.00674 -389.115039) (xy 439.953488 -389.111309) (xy 439.901277 -389.100192)
			(xy 439.851125 -389.081906) (xy 439.804011 -389.056807) (xy 439.760857 -389.025385) (xy 439.722503 -388.988255)
			(xy 439.70575 -388.967472) (xy 439.695853 -388.955667) (xy 439.670529 -388.938148) (xy 439.641136 -388.928972)
			(xy 439.610344 -388.928972) (xy 439.580951 -388.938148) (xy 439.555627 -388.955667) (xy 439.54573 -388.967472)
			(xy 439.528977 -388.988255) (xy 439.490623 -389.025385) (xy 439.447469 -389.056807) (xy 439.400355 -389.081906)
			(xy 439.350203 -389.100192) (xy 439.297992 -389.111309) (xy 439.24474 -389.115039) (xy 439.191488 -389.111309)
			(xy 439.139277 -389.100192) (xy 439.089125 -389.081906) (xy 439.042011 -389.056807) (xy 438.998857 -389.025385)
			(xy 438.960503 -388.988255) (xy 438.94375 -388.967472) (xy 438.933853 -388.955667) (xy 438.908529 -388.938148)
			(xy 438.879136 -388.928972) (xy 438.848344 -388.928972) (xy 438.818951 -388.938148) (xy 438.793627 -388.955667)
			(xy 438.78373 -388.967472) (xy 438.765515 -388.989935) (xy 438.723501 -389.029673) (xy 438.675971 -389.062615)
			(xy 438.624015 -389.088007) (xy 438.568821 -389.105268) (xy 438.511655 -389.114001) (xy 438.48274 -389.114538)
			(xy 438.455487 -389.114017) (xy 438.401536 -389.106266) (xy 438.349238 -389.090914) (xy 438.299657 -389.068276)
			(xy 438.253802 -389.038811) (xy 438.212608 -389.00312) (xy 438.176913 -388.96193) (xy 438.147443 -388.916079)
			(xy 438.1248 -388.8665) (xy 438.109443 -388.814203) (xy 438.101685 -388.760253) (xy 432.645058 -388.760253)
			(xy 432.645058 -391.094468) (xy 432.645509 -391.107935) (xy 432.652627 -391.133914) (xy 432.666297 -391.157124)
			(xy 432.685564 -391.175948) (xy 432.709086 -391.189072) (xy 432.735224 -391.195584) (xy 432.762155 -391.195027)
			(xy 432.788001 -391.187442) (xy 432.799744 -391.180828) (xy 432.822391 -391.167439) (xy 432.870583 -391.146333)
			(xy 432.921218 -391.132052) (xy 432.973336 -391.124866) (xy 432.999642 -391.12444) (xy 433.026888 -391.124929)
			(xy 433.080824 -391.132689) (xy 433.133107 -391.148046) (xy 433.182673 -391.170687) (xy 433.228512 -391.200151)
			(xy 433.269692 -391.235838) (xy 433.305375 -391.277021) (xy 433.334833 -391.322864) (xy 433.357468 -391.372432)
			(xy 433.37282 -391.424717) (xy 433.380574 -391.478654) (xy 433.380574 -391.533146) (xy 433.37282 -391.587083)
			(xy 433.357468 -391.639368) (xy 433.334833 -391.688936) (xy 433.305375 -391.734779) (xy 433.269692 -391.775962)
			(xy 433.228512 -391.811649) (xy 433.182673 -391.841113) (xy 433.133107 -391.863754) (xy 433.080824 -391.879111)
			(xy 433.026888 -391.886871) (xy 432.999642 -391.887456) (xy 432.973336 -391.887032) (xy 432.921219 -391.879841)
			(xy 432.870583 -391.865561) (xy 432.822388 -391.844463) (xy 432.799744 -391.831068) (xy 432.788042 -391.824389)
			(xy 432.762191 -391.816824) (xy 432.735261 -391.816284) (xy 432.709128 -391.822809) (xy 432.685612 -391.835943)
			(xy 432.666351 -391.854772) (xy 432.652686 -391.877983) (xy 432.64557 -391.903962) (xy 432.645058 -391.917428)
			(xy 432.645058 -393.67079) (xy 432.65979 -393.685776) (xy 434.970428 -395.996414) (xy 434.985414 -396.011146)
			(xy 465.30133 -396.011146)
		)
		(stroke
			(width 0)
			(type solid)
		)
		(fill yes)
		(layer "In4.Cu")
		(net "GND")
	)
	(gr_poly
		(pts
			(xy 437.02986 -109.195108) (xy 437.02986 -96.995488) (xy 436.72633 -96.691958) (xy 436.716176 -96.682473)
			(xy 436.691968 -96.668857) (xy 436.664986 -96.662271) (xy 436.637228 -96.663203) (xy 436.610749 -96.671584)
			(xy 436.587509 -96.686792) (xy 436.569229 -96.707703) (xy 436.557263 -96.732767) (xy 436.552497 -96.760129)
			(xy 436.553356 -96.774) (xy 436.555388 -96.812608) (xy 436.554901 -96.839857) (xy 436.547144 -96.893801)
			(xy 436.531789 -96.946092) (xy 436.509149 -96.995666) (xy 436.479684 -97.041512) (xy 436.443995 -97.082699)
			(xy 436.402807 -97.118388) (xy 436.35696 -97.147852) (xy 436.307386 -97.170492) (xy 436.255095 -97.185846)
			(xy 436.201151 -97.193602) (xy 436.146652 -97.193602) (xy 436.092708 -97.185846) (xy 436.040417 -97.170493)
			(xy 435.990843 -97.147853) (xy 435.944995 -97.11839) (xy 435.903807 -97.082701) (xy 435.868117 -97.041515)
			(xy 435.838652 -96.995668) (xy 435.816012 -96.946095) (xy 435.800656 -96.893804) (xy 435.792899 -96.83986)
			(xy 435.792897 -96.785361) (xy 435.800652 -96.731417) (xy 435.816004 -96.679125) (xy 435.838642 -96.629551)
			(xy 435.868105 -96.583703) (xy 435.903792 -96.542514) (xy 435.944978 -96.506823) (xy 435.990824 -96.477357)
			(xy 436.040397 -96.454715) (xy 436.092687 -96.439358) (xy 436.146631 -96.4316) (xy 436.17388 -96.4311)
			(xy 436.212488 -96.433132) (xy 436.226351 -96.434045) (xy 436.253707 -96.429261) (xy 436.278762 -96.417283)
			(xy 436.299663 -96.398997) (xy 436.314864 -96.375756) (xy 436.323242 -96.349279) (xy 436.324175 -96.321524)
			(xy 436.317596 -96.294543) (xy 436.303991 -96.270333) (xy 436.29453 -96.260158) (xy 435.86654 -95.832168)
			(xy 415.82594 -95.832168) (xy 415.17824 -96.479868) (xy 415.17824 -96.812608) (xy 434.902862 -96.812608)
			(xy 434.906933 -96.756986) (xy 434.919059 -96.702549) (xy 434.938982 -96.650458) (xy 434.966278 -96.601823)
			(xy 435.000364 -96.55768) (xy 435.040513 -96.518971) (xy 435.085871 -96.48652) (xy 435.135471 -96.461019)
			(xy 435.188255 -96.443012) (xy 435.243098 -96.432882) (xy 435.298832 -96.430845) (xy 435.354269 -96.436945)
			(xy 435.408226 -96.451051) (xy 435.459555 -96.472863) (xy 435.507161 -96.501917) (xy 435.550029 -96.537592)
			(xy 435.587246 -96.579129) (xy 435.618019 -96.625642) (xy 435.641691 -96.676139) (xy 435.657759 -96.729546)
			(xy 435.665879 -96.784722) (xy 435.666388 -96.812608) (xy 435.665879 -96.840494) (xy 435.657759 -96.89567)
			(xy 435.641691 -96.949077) (xy 435.618019 -96.999574) (xy 435.587246 -97.046087) (xy 435.550029 -97.087624)
			(xy 435.507161 -97.123299) (xy 435.459555 -97.152353) (xy 435.408226 -97.174165) (xy 435.354269 -97.188271)
			(xy 435.298832 -97.194371) (xy 435.243098 -97.192334) (xy 435.188255 -97.182204) (xy 435.135471 -97.164197)
			(xy 435.085871 -97.138696) (xy 435.040513 -97.106245) (xy 435.000364 -97.067536) (xy 434.966278 -97.023393)
			(xy 434.938982 -96.974758) (xy 434.919059 -96.922667) (xy 434.906933 -96.86823) (xy 434.902862 -96.812608)
			(xy 415.17824 -96.812608) (xy 415.17824 -97.701608) (xy 434.902862 -97.701608) (xy 434.906933 -97.645986)
			(xy 434.919059 -97.591549) (xy 434.938982 -97.539458) (xy 434.966278 -97.490823) (xy 435.000364 -97.44668)
			(xy 435.040513 -97.407971) (xy 435.085871 -97.37552) (xy 435.135471 -97.350019) (xy 435.188255 -97.332012)
			(xy 435.243098 -97.321882) (xy 435.298832 -97.319845) (xy 435.354269 -97.325945) (xy 435.408226 -97.340051)
			(xy 435.459555 -97.361863) (xy 435.507161 -97.390917) (xy 435.550029 -97.426592) (xy 435.587246 -97.468129)
			(xy 435.618019 -97.514642) (xy 435.641691 -97.565139) (xy 435.657759 -97.618546) (xy 435.665879 -97.673722)
			(xy 435.666388 -97.701608) (xy 435.791862 -97.701608) (xy 435.795933 -97.645986) (xy 435.808059 -97.591549)
			(xy 435.827982 -97.539458) (xy 435.855278 -97.490823) (xy 435.889364 -97.44668) (xy 435.929513 -97.407971)
			(xy 435.974871 -97.37552) (xy 436.024471 -97.350019) (xy 436.077255 -97.332012) (xy 436.132098 -97.321882)
			(xy 436.187832 -97.319845) (xy 436.243269 -97.325945) (xy 436.297226 -97.340051) (xy 436.348555 -97.361863)
			(xy 436.396161 -97.390917) (xy 436.439029 -97.426592) (xy 436.476246 -97.468129) (xy 436.507019 -97.514642)
			(xy 436.530691 -97.565139) (xy 436.546759 -97.618546) (xy 436.554879 -97.673722) (xy 436.555388 -97.701608)
			(xy 436.554879 -97.729494) (xy 436.546759 -97.78467) (xy 436.530691 -97.838077) (xy 436.507019 -97.888574)
			(xy 436.476246 -97.935087) (xy 436.439029 -97.976624) (xy 436.396161 -98.012299) (xy 436.348555 -98.041353)
			(xy 436.297226 -98.063165) (xy 436.243269 -98.077271) (xy 436.187832 -98.083371) (xy 436.132098 -98.081334)
			(xy 436.077255 -98.071204) (xy 436.024471 -98.053197) (xy 435.974871 -98.027696) (xy 435.929513 -97.995245)
			(xy 435.889364 -97.956536) (xy 435.855278 -97.912393) (xy 435.827982 -97.863758) (xy 435.808059 -97.811667)
			(xy 435.795933 -97.75723) (xy 435.791862 -97.701608) (xy 435.666388 -97.701608) (xy 435.665879 -97.729494)
			(xy 435.657759 -97.78467) (xy 435.641691 -97.838077) (xy 435.618019 -97.888574) (xy 435.587246 -97.935087)
			(xy 435.550029 -97.976624) (xy 435.507161 -98.012299) (xy 435.459555 -98.041353) (xy 435.408226 -98.063165)
			(xy 435.354269 -98.077271) (xy 435.298832 -98.083371) (xy 435.243098 -98.081334) (xy 435.188255 -98.071204)
			(xy 435.135471 -98.053197) (xy 435.085871 -98.027696) (xy 435.040513 -97.995245) (xy 435.000364 -97.956536)
			(xy 434.966278 -97.912393) (xy 434.938982 -97.863758) (xy 434.919059 -97.811667) (xy 434.906933 -97.75723)
			(xy 434.902862 -97.701608) (xy 415.17824 -97.701608) (xy 415.17824 -98.590608) (xy 434.902862 -98.590608)
			(xy 434.906933 -98.534986) (xy 434.919059 -98.480549) (xy 434.938982 -98.428458) (xy 434.966278 -98.379823)
			(xy 435.000364 -98.33568) (xy 435.040513 -98.296971) (xy 435.085871 -98.26452) (xy 435.135471 -98.239019)
			(xy 435.188255 -98.221012) (xy 435.243098 -98.210882) (xy 435.298832 -98.208845) (xy 435.354269 -98.214945)
			(xy 435.408226 -98.229051) (xy 435.459555 -98.250863) (xy 435.507161 -98.279917) (xy 435.550029 -98.315592)
			(xy 435.587246 -98.357129) (xy 435.618019 -98.403642) (xy 435.641691 -98.454139) (xy 435.657759 -98.507546)
			(xy 435.665879 -98.562722) (xy 435.666388 -98.590608) (xy 435.791862 -98.590608) (xy 435.795933 -98.534986)
			(xy 435.808059 -98.480549) (xy 435.827982 -98.428458) (xy 435.855278 -98.379823) (xy 435.889364 -98.33568)
			(xy 435.929513 -98.296971) (xy 435.974871 -98.26452) (xy 436.024471 -98.239019) (xy 436.077255 -98.221012)
			(xy 436.132098 -98.210882) (xy 436.187832 -98.208845) (xy 436.243269 -98.214945) (xy 436.297226 -98.229051)
			(xy 436.348555 -98.250863) (xy 436.396161 -98.279917) (xy 436.439029 -98.315592) (xy 436.476246 -98.357129)
			(xy 436.507019 -98.403642) (xy 436.530691 -98.454139) (xy 436.546759 -98.507546) (xy 436.554879 -98.562722)
			(xy 436.555388 -98.590608) (xy 436.554879 -98.618494) (xy 436.546759 -98.67367) (xy 436.530691 -98.727077)
			(xy 436.507019 -98.777574) (xy 436.476246 -98.824087) (xy 436.439029 -98.865624) (xy 436.396161 -98.901299)
			(xy 436.348555 -98.930353) (xy 436.297226 -98.952165) (xy 436.243269 -98.966271) (xy 436.187832 -98.972371)
			(xy 436.132098 -98.970334) (xy 436.077255 -98.960204) (xy 436.024471 -98.942197) (xy 435.974871 -98.916696)
			(xy 435.929513 -98.884245) (xy 435.889364 -98.845536) (xy 435.855278 -98.801393) (xy 435.827982 -98.752758)
			(xy 435.808059 -98.700667) (xy 435.795933 -98.64623) (xy 435.791862 -98.590608) (xy 435.666388 -98.590608)
			(xy 435.665879 -98.618494) (xy 435.657759 -98.67367) (xy 435.641691 -98.727077) (xy 435.618019 -98.777574)
			(xy 435.587246 -98.824087) (xy 435.550029 -98.865624) (xy 435.507161 -98.901299) (xy 435.459555 -98.930353)
			(xy 435.408226 -98.952165) (xy 435.354269 -98.966271) (xy 435.298832 -98.972371) (xy 435.243098 -98.970334)
			(xy 435.188255 -98.960204) (xy 435.135471 -98.942197) (xy 435.085871 -98.916696) (xy 435.040513 -98.884245)
			(xy 435.000364 -98.845536) (xy 434.966278 -98.801393) (xy 434.938982 -98.752758) (xy 434.919059 -98.700667)
			(xy 434.906933 -98.64623) (xy 434.902862 -98.590608) (xy 415.17824 -98.590608) (xy 415.17824 -99.479608)
			(xy 434.902862 -99.479608) (xy 434.906933 -99.423986) (xy 434.919059 -99.369549) (xy 434.938982 -99.317458)
			(xy 434.966278 -99.268823) (xy 435.000364 -99.22468) (xy 435.040513 -99.185971) (xy 435.085871 -99.15352)
			(xy 435.135471 -99.128019) (xy 435.188255 -99.110012) (xy 435.243098 -99.099882) (xy 435.298832 -99.097845)
			(xy 435.354269 -99.103945) (xy 435.408226 -99.118051) (xy 435.459555 -99.139863) (xy 435.507161 -99.168917)
			(xy 435.550029 -99.204592) (xy 435.587246 -99.246129) (xy 435.618019 -99.292642) (xy 435.641691 -99.343139)
			(xy 435.657759 -99.396546) (xy 435.665879 -99.451722) (xy 435.666388 -99.479608) (xy 435.791862 -99.479608)
			(xy 435.795933 -99.423986) (xy 435.808059 -99.369549) (xy 435.827982 -99.317458) (xy 435.855278 -99.268823)
			(xy 435.889364 -99.22468) (xy 435.929513 -99.185971) (xy 435.974871 -99.15352) (xy 436.024471 -99.128019)
			(xy 436.077255 -99.110012) (xy 436.132098 -99.099882) (xy 436.187832 -99.097845) (xy 436.243269 -99.103945)
			(xy 436.297226 -99.118051) (xy 436.348555 -99.139863) (xy 436.396161 -99.168917) (xy 436.439029 -99.204592)
			(xy 436.476246 -99.246129) (xy 436.507019 -99.292642) (xy 436.530691 -99.343139) (xy 436.546759 -99.396546)
			(xy 436.554879 -99.451722) (xy 436.555388 -99.479608) (xy 436.554879 -99.507494) (xy 436.546759 -99.56267)
			(xy 436.530691 -99.616077) (xy 436.507019 -99.666574) (xy 436.476246 -99.713087) (xy 436.439029 -99.754624)
			(xy 436.396161 -99.790299) (xy 436.348555 -99.819353) (xy 436.297226 -99.841165) (xy 436.243269 -99.855271)
			(xy 436.187832 -99.861371) (xy 436.132098 -99.859334) (xy 436.077255 -99.849204) (xy 436.024471 -99.831197)
			(xy 435.974871 -99.805696) (xy 435.929513 -99.773245) (xy 435.889364 -99.734536) (xy 435.855278 -99.690393)
			(xy 435.827982 -99.641758) (xy 435.808059 -99.589667) (xy 435.795933 -99.53523) (xy 435.791862 -99.479608)
			(xy 435.666388 -99.479608) (xy 435.665879 -99.507494) (xy 435.657759 -99.56267) (xy 435.641691 -99.616077)
			(xy 435.618019 -99.666574) (xy 435.587246 -99.713087) (xy 435.550029 -99.754624) (xy 435.507161 -99.790299)
			(xy 435.459555 -99.819353) (xy 435.408226 -99.841165) (xy 435.354269 -99.855271) (xy 435.298832 -99.861371)
			(xy 435.243098 -99.859334) (xy 435.188255 -99.849204) (xy 435.135471 -99.831197) (xy 435.085871 -99.805696)
			(xy 435.040513 -99.773245) (xy 435.000364 -99.734536) (xy 434.966278 -99.690393) (xy 434.938982 -99.641758)
			(xy 434.919059 -99.589667) (xy 434.906933 -99.53523) (xy 434.902862 -99.479608) (xy 415.17824 -99.479608)
			(xy 415.17824 -102.63945) (xy 429.495968 -102.63945) (xy 429.495968 -102.58495) (xy 429.503724 -102.531003)
			(xy 429.519077 -102.47871) (xy 429.541717 -102.429134) (xy 429.57118 -102.383284) (xy 429.606869 -102.342093)
			(xy 429.648057 -102.306401) (xy 429.693904 -102.276933) (xy 429.743478 -102.254289) (xy 429.79577 -102.238931)
			(xy 429.849716 -102.23117) (xy 429.876966 -102.230682) (xy 429.903569 -102.231164) (xy 429.95626 -102.238541)
			(xy 430.007415 -102.25317) (xy 430.056039 -102.274767) (xy 430.10119 -102.302914) (xy 430.14199 -102.337062)
			(xy 430.177648 -102.376551) (xy 430.192942 -102.398322) (xy 430.201276 -102.409802) (xy 430.22302 -102.428006)
			(xy 430.248933 -102.439524) (xy 430.277016 -102.443464) (xy 430.305099 -102.439524) (xy 430.331012 -102.428006)
			(xy 430.352756 -102.409802) (xy 430.36109 -102.398322) (xy 430.376374 -102.376544) (xy 430.412042 -102.337065)
			(xy 430.452848 -102.302923) (xy 430.498 -102.274779) (xy 430.546623 -102.253178) (xy 430.597775 -102.238539)
			(xy 430.650463 -102.231145) (xy 430.677066 -102.230682) (xy 430.704318 -102.231187) (xy 430.758266 -102.238939)
			(xy 430.810563 -102.25429) (xy 430.860142 -102.276928) (xy 430.905995 -102.306392) (xy 430.947188 -102.342081)
			(xy 430.982882 -102.38327) (xy 431.012351 -102.429119) (xy 431.034994 -102.478696) (xy 431.050352 -102.53099)
			(xy 431.05811 -102.584938) (xy 431.058574 -102.61219) (xy 431.058169 -102.636998) (xy 431.057848 -102.639451)
			(xy 431.370468 -102.639451) (xy 431.370468 -102.584949) (xy 431.378224 -102.531001) (xy 431.393579 -102.478706)
			(xy 431.41622 -102.429128) (xy 431.445685 -102.383277) (xy 431.481376 -102.342086) (xy 431.522566 -102.306394)
			(xy 431.568416 -102.276926) (xy 431.617993 -102.254284) (xy 431.670287 -102.238927) (xy 431.724235 -102.231169)
			(xy 431.751486 -102.230682) (xy 431.780451 -102.231233) (xy 431.837715 -102.240002) (xy 431.892995 -102.257325)
			(xy 431.945022 -102.282805) (xy 431.9926 -102.315856) (xy 432.034635 -102.355719) (xy 432.070163 -102.401477)
			(xy 432.084734 -102.426516) (xy 432.092088 -102.438728) (xy 432.112316 -102.458797) (xy 432.137304 -102.472494)
			(xy 432.165104 -102.47875) (xy 432.19355 -102.47708) (xy 432.220426 -102.467612) (xy 432.243639 -102.451085)
			(xy 432.252882 -102.440232) (xy 432.271098 -102.418176) (xy 432.313 -102.379236) (xy 432.360242 -102.346983)
			(xy 432.411768 -102.322139) (xy 432.466423 -102.30526) (xy 432.522985 -102.296724) (xy 432.551586 -102.296214)
			(xy 432.578841 -102.296632) (xy 432.632797 -102.304388) (xy 432.685099 -102.319743) (xy 432.734684 -102.342386)
			(xy 432.780542 -102.371856) (xy 432.821738 -102.407552) (xy 432.857436 -102.448747) (xy 432.886907 -102.494604)
			(xy 432.909552 -102.544188) (xy 432.924909 -102.59649) (xy 432.932667 -102.650445) (xy 432.932667 -102.704955)
			(xy 432.924909 -102.75891) (xy 432.909552 -102.811212) (xy 432.886907 -102.860796) (xy 432.857436 -102.906653)
			(xy 432.821738 -102.947848) (xy 432.780542 -102.983544) (xy 432.734684 -103.013014) (xy 432.685099 -103.035657)
			(xy 432.632797 -103.051012) (xy 432.578841 -103.058768) (xy 432.551586 -103.05923) (xy 432.522618 -103.058746)
			(xy 432.465349 -103.049971) (xy 432.410065 -103.032639) (xy 432.358036 -103.007149) (xy 432.310459 -102.974086)
			(xy 432.268427 -102.934212) (xy 432.232905 -102.888441) (xy 432.218338 -102.863396) (xy 432.211021 -102.851159)
			(xy 432.190786 -102.831086) (xy 432.16579 -102.817388) (xy 432.137982 -102.811133) (xy 432.109529 -102.812809)
			(xy 432.082648 -102.822285) (xy 432.059433 -102.838822) (xy 432.05019 -102.84968) (xy 432.031993 -102.871752)
			(xy 431.990086 -102.91069) (xy 431.94284 -102.942941) (xy 431.891311 -102.967782) (xy 431.836652 -102.984658)
			(xy 431.780088 -102.99319) (xy 431.751486 -102.993698) (xy 431.724235 -102.993231) (xy 431.670287 -102.985473)
			(xy 431.617993 -102.970116) (xy 431.568416 -102.947474) (xy 431.522566 -102.918006) (xy 431.481376 -102.882314)
			(xy 431.445685 -102.841123) (xy 431.41622 -102.795272) (xy 431.393579 -102.745694) (xy 431.378224 -102.693399)
			(xy 431.370468 -102.639451) (xy 431.057848 -102.639451) (xy 431.051732 -102.686194) (xy 431.038953 -102.734135)
			(xy 431.029872 -102.757224) (xy 431.025139 -102.769969) (xy 431.0218 -102.796937) (xy 431.025686 -102.823832)
			(xy 431.036521 -102.848752) (xy 431.053541 -102.869936) (xy 431.075541 -102.885887) (xy 431.100967 -102.895476)
			(xy 431.114454 -102.897178) (xy 431.142478 -102.90029) (xy 431.197232 -102.913751) (xy 431.249408 -102.935124)
			(xy 431.29787 -102.963943) (xy 431.341562 -102.999582) (xy 431.379534 -103.041264) (xy 431.410956 -103.08808)
			(xy 431.435146 -103.139011) (xy 431.451576 -103.192948) (xy 431.459889 -103.248716) (xy 431.460402 -103.276908)
			(xy 431.459916 -103.304159) (xy 431.45216 -103.358107) (xy 431.436805 -103.410402) (xy 431.414163 -103.459979)
			(xy 431.384697 -103.505829) (xy 431.349006 -103.54702) (xy 431.307815 -103.582711) (xy 431.261965 -103.612177)
			(xy 431.212388 -103.634819) (xy 431.160093 -103.650174) (xy 431.106145 -103.65793) (xy 431.051643 -103.65793)
			(xy 430.997695 -103.650174) (xy 430.9454 -103.634819) (xy 430.895823 -103.612177) (xy 430.849973 -103.582711)
			(xy 430.808782 -103.54702) (xy 430.773091 -103.505829) (xy 430.743625 -103.459979) (xy 430.720983 -103.410402)
			(xy 430.705628 -103.358107) (xy 430.697872 -103.304159) (xy 430.697386 -103.276908) (xy 430.697793 -103.2521)
			(xy 430.704229 -103.202905) (xy 430.717007 -103.154963) (xy 430.726088 -103.131874) (xy 430.730856 -103.11914)
			(xy 430.734198 -103.092165) (xy 430.730311 -103.065263) (xy 430.71947 -103.040337) (xy 430.702443 -103.019151)
			(xy 430.680433 -103.003201) (xy 430.654997 -102.993618) (xy 430.641506 -102.99192) (xy 430.613609 -102.988818)
			(xy 430.559087 -102.975477) (xy 430.50711 -102.95429) (xy 430.458798 -102.925714) (xy 430.415195 -102.890368)
			(xy 430.377243 -102.849014) (xy 430.36109 -102.826058) (xy 430.352756 -102.814578) (xy 430.331012 -102.796374)
			(xy 430.305099 -102.784856) (xy 430.277016 -102.780916) (xy 430.248933 -102.784856) (xy 430.22302 -102.796374)
			(xy 430.201276 -102.814578) (xy 430.192942 -102.826058) (xy 430.177632 -102.847817) (xy 430.141968 -102.887297)
			(xy 430.101167 -102.921441) (xy 430.05602 -102.949588) (xy 430.007401 -102.971192) (xy 429.956253 -102.985835)
			(xy 429.903567 -102.993232) (xy 429.876966 -102.993698) (xy 429.849716 -102.99323) (xy 429.79577 -102.985469)
			(xy 429.743478 -102.970111) (xy 429.693904 -102.947467) (xy 429.648057 -102.917999) (xy 429.606869 -102.882307)
			(xy 429.57118 -102.841116) (xy 429.541717 -102.795266) (xy 429.519077 -102.74569) (xy 429.503724 -102.693397)
			(xy 429.495968 -102.63945) (xy 415.17824 -102.63945) (xy 415.17824 -104.501188) (xy 418.035232 -104.501188)
			(xy 418.035683 -104.473817) (xy 418.043503 -104.419637) (xy 418.058996 -104.367134) (xy 418.081841 -104.317387)
			(xy 418.111569 -104.271421) (xy 418.129212 -104.25049) (xy 418.138459 -104.239171) (xy 418.150634 -104.21261)
			(xy 418.154804 -104.183691) (xy 418.150629 -104.154773) (xy 418.13845 -104.128214) (xy 418.129212 -104.116886)
			(xy 418.111602 -104.095931) (xy 418.081885 -104.049965) (xy 418.059043 -104.000223) (xy 418.043546 -103.947727)
			(xy 418.03571 -103.893556) (xy 418.035232 -103.866188) (xy 418.035644 -103.838933) (xy 418.043403 -103.784978)
			(xy 418.058763 -103.732677) (xy 418.08141 -103.683094) (xy 418.110883 -103.637239) (xy 418.146582 -103.596045)
			(xy 418.187781 -103.560352) (xy 418.23364 -103.530885) (xy 418.283226 -103.508245) (xy 418.335529 -103.492892)
			(xy 418.389485 -103.48514) (xy 418.41674 -103.48468) (xy 418.442319 -103.485084) (xy 418.493018 -103.491932)
			(xy 418.542348 -103.505486) (xy 418.589428 -103.525504) (xy 418.633414 -103.551628) (xy 418.673519 -103.583389)
			(xy 418.691568 -103.60152) (xy 418.701199 -103.61092) (xy 418.724293 -103.624724) (xy 418.750189 -103.632019)
			(xy 418.777092 -103.6323) (xy 418.803136 -103.625548) (xy 418.826513 -103.612231) (xy 418.836348 -103.603044)
			(xy 418.857913 -103.582417) (xy 418.906289 -103.547481) (xy 418.959517 -103.520507) (xy 419.016298 -103.502155)
			(xy 419.075244 -103.492872) (xy 419.10508 -103.4923) (xy 419.132333 -103.492774) (xy 419.186284 -103.500528)
			(xy 419.238582 -103.515882) (xy 419.288162 -103.538523) (xy 419.334016 -103.56799) (xy 419.375209 -103.603682)
			(xy 419.410903 -103.644874) (xy 419.440371 -103.690727) (xy 419.463013 -103.740307) (xy 419.478369 -103.792605)
			(xy 419.486125 -103.846555) (xy 419.486588 -103.873808) (xy 419.48613 -103.901179) (xy 419.47831 -103.955358)
			(xy 419.46282 -104.007861) (xy 419.439976 -104.057608) (xy 419.41025 -104.103575) (xy 419.392608 -104.124506)
			(xy 419.383363 -104.135827) (xy 419.371185 -104.162387) (xy 419.367014 -104.191306) (xy 419.371189 -104.220225)
			(xy 419.383369 -104.246783) (xy 419.392608 -104.25811) (xy 419.410266 -104.279026) (xy 419.439975 -104.325004)
			(xy 419.462807 -104.374755) (xy 419.478294 -104.427259) (xy 419.486117 -104.481438) (xy 419.486588 -104.508808)
			(xy 419.486152 -104.536062) (xy 419.478393 -104.590015) (xy 419.463035 -104.642314) (xy 419.440391 -104.691896)
			(xy 419.41092 -104.73775) (xy 419.375223 -104.778943) (xy 419.334028 -104.814637) (xy 419.288171 -104.844104)
			(xy 419.238588 -104.866745) (xy 419.186287 -104.882099) (xy 419.132334 -104.889854) (xy 419.10508 -104.890316)
			(xy 419.079501 -104.8899) (xy 419.028803 -104.883055) (xy 418.979473 -104.869503) (xy 418.932393 -104.849487)
			(xy 418.888407 -104.823365) (xy 418.848301 -104.791606) (xy 418.830252 -104.773476) (xy 418.820603 -104.764096)
			(xy 418.797514 -104.750292) (xy 418.771623 -104.742994) (xy 418.744724 -104.742709) (xy 418.718683 -104.749456)
			(xy 418.695307 -104.762768) (xy 418.685472 -104.771952) (xy 418.663898 -104.792569) (xy 418.615524 -104.827506)
			(xy 418.562298 -104.854482) (xy 418.50552 -104.872837) (xy 418.446576 -104.882123) (xy 418.41674 -104.882696)
			(xy 418.389488 -104.882207) (xy 418.335537 -104.874456) (xy 418.283239 -104.859104) (xy 418.233658 -104.836465)
			(xy 418.187804 -104.807) (xy 418.146611 -104.771309) (xy 418.110916 -104.730118) (xy 418.081448 -104.684267)
			(xy 418.058806 -104.634687) (xy 418.04345 -104.58239) (xy 418.035695 -104.52844) (xy 418.035232 -104.501188)
			(xy 415.17824 -104.501188) (xy 415.17824 -105.827322) (xy 429.906682 -105.827322) (xy 429.910753 -105.7717)
			(xy 429.922879 -105.717263) (xy 429.942802 -105.665172) (xy 429.970098 -105.616537) (xy 430.004184 -105.572394)
			(xy 430.044333 -105.533685) (xy 430.089691 -105.501234) (xy 430.139291 -105.475733) (xy 430.192075 -105.457726)
			(xy 430.246918 -105.447596) (xy 430.302652 -105.445559) (xy 430.358089 -105.451659) (xy 430.412046 -105.465765)
			(xy 430.463375 -105.487577) (xy 430.510981 -105.516631) (xy 430.553849 -105.552306) (xy 430.591066 -105.593843)
			(xy 430.614291 -105.628948) (xy 433.069492 -105.628948) (xy 433.069988 -105.601579) (xy 433.077799 -105.547401)
			(xy 433.093281 -105.494898) (xy 433.116116 -105.445151) (xy 433.145834 -105.399183) (xy 433.163472 -105.37825)
			(xy 433.172664 -105.366889) (xy 433.184851 -105.340344) (xy 433.189034 -105.311436) (xy 433.184871 -105.282526)
			(xy 433.172704 -105.255972) (xy 433.163472 -105.244646) (xy 433.145837 -105.223711) (xy 433.116125 -105.177739)
			(xy 433.093289 -105.127992) (xy 433.077797 -105.075492) (xy 433.069967 -105.021317) (xy 433.069492 -104.993948)
			(xy 433.069991 -104.965775) (xy 433.078298 -104.910045) (xy 433.094709 -104.856142) (xy 433.118868 -104.805238)
			(xy 433.150249 -104.75844) (xy 433.188171 -104.716765) (xy 433.231808 -104.681118) (xy 433.280212 -104.652276)
			(xy 433.332331 -104.630864) (xy 433.35956 -104.623616) (xy 433.373871 -104.619591) (xy 433.399467 -104.604497)
			(xy 433.419628 -104.582668) (xy 433.432644 -104.555955) (xy 433.437411 -104.526624) (xy 433.433523 -104.497164)
			(xy 433.427886 -104.483408) (xy 433.417375 -104.458766) (xy 433.402561 -104.407283) (xy 433.395071 -104.354238)
			(xy 433.394612 -104.327452) (xy 433.395098 -104.300201) (xy 433.402854 -104.246253) (xy 433.418209 -104.193958)
			(xy 433.440851 -104.144381) (xy 433.470317 -104.098531) (xy 433.506008 -104.05734) (xy 433.547199 -104.021649)
			(xy 433.593049 -103.992183) (xy 433.642626 -103.969541) (xy 433.694921 -103.954186) (xy 433.748869 -103.94643)
			(xy 433.803371 -103.94643) (xy 433.857319 -103.954186) (xy 433.909614 -103.969541) (xy 433.959191 -103.992183)
			(xy 434.005041 -104.021649) (xy 434.046232 -104.05734) (xy 434.081923 -104.098531) (xy 434.111389 -104.144381)
			(xy 434.134031 -104.193958) (xy 434.149386 -104.246253) (xy 434.157142 -104.300201) (xy 434.157628 -104.327452)
			(xy 434.157175 -104.354753) (xy 434.149421 -104.4088) (xy 434.134021 -104.461184) (xy 434.123084 -104.486202)
			(xy 434.117403 -104.499723) (xy 434.113306 -104.528754) (xy 434.117603 -104.557756) (xy 434.129943 -104.584351)
			(xy 434.149314 -104.606359) (xy 434.174127 -104.621976) (xy 434.188108 -104.62641) (xy 434.214542 -104.634228)
			(xy 434.264983 -104.656465) (xy 434.311697 -104.685732) (xy 434.353711 -104.721419) (xy 434.390149 -104.762783)
			(xy 434.420254 -104.808961) (xy 434.443397 -104.858992) (xy 434.459097 -104.911834) (xy 434.467026 -104.966386)
			(xy 434.467508 -104.993948) (xy 434.467009 -105.021317) (xy 434.459199 -105.075495) (xy 434.443718 -105.127997)
			(xy 434.420883 -105.177745) (xy 434.391166 -105.223713) (xy 434.373528 -105.244646) (xy 434.364243 -105.255938)
			(xy 434.352068 -105.282508) (xy 434.347903 -105.311436) (xy 434.352088 -105.340362) (xy 434.364282 -105.366923)
			(xy 434.373528 -105.37825) (xy 434.391161 -105.399187) (xy 434.420873 -105.445159) (xy 434.44371 -105.494905)
			(xy 434.459202 -105.547404) (xy 434.467033 -105.601579) (xy 434.467508 -105.628948) (xy 434.467067 -105.6562)
			(xy 434.459304 -105.71015) (xy 434.443943 -105.762445) (xy 434.421296 -105.812023) (xy 434.391825 -105.857873)
			(xy 434.356129 -105.899063) (xy 434.314934 -105.934753) (xy 434.269081 -105.964219) (xy 434.2195 -105.986859)
			(xy 434.167203 -106.002214) (xy 434.113252 -106.00997) (xy 434.086 -106.010456) (xy 434.058629 -106.010001)
			(xy 434.004449 -106.002182) (xy 433.951946 -105.986691) (xy 433.902199 -105.963847) (xy 433.856233 -105.934119)
			(xy 433.835302 -105.916476) (xy 433.823974 -105.90724) (xy 433.797417 -105.895064) (xy 433.7685 -105.890891)
			(xy 433.739583 -105.895064) (xy 433.713026 -105.90724) (xy 433.701698 -105.916476) (xy 433.680774 -105.934126)
			(xy 433.6348 -105.963837) (xy 433.58505 -105.986671) (xy 433.532547 -106.00216) (xy 433.47837 -106.009984)
			(xy 433.451 -106.010456) (xy 433.423751 -106.009922) (xy 433.369807 -106.002167) (xy 433.317516 -105.986814)
			(xy 433.267942 -105.964177) (xy 433.222094 -105.934715) (xy 433.180905 -105.899029) (xy 433.145214 -105.857844)
			(xy 433.115746 -105.812) (xy 433.093102 -105.762429) (xy 433.077743 -105.71014) (xy 433.069981 -105.656197)
			(xy 433.069492 -105.628948) (xy 430.614291 -105.628948) (xy 430.621839 -105.640356) (xy 430.645511 -105.690853)
			(xy 430.661579 -105.74426) (xy 430.669699 -105.799436) (xy 430.670208 -105.827322) (xy 430.669699 -105.855208)
			(xy 430.661579 -105.910384) (xy 430.645511 -105.963791) (xy 430.621839 -106.014288) (xy 430.591066 -106.060801)
			(xy 430.553849 -106.102338) (xy 430.510981 -106.138013) (xy 430.463375 -106.167067) (xy 430.412046 -106.188879)
			(xy 430.358089 -106.202985) (xy 430.302652 -106.209085) (xy 430.246918 -106.207048) (xy 430.192075 -106.196918)
			(xy 430.139291 -106.178911) (xy 430.089691 -106.15341) (xy 430.044333 -106.120959) (xy 430.004184 -106.08225)
			(xy 429.970098 -106.038107) (xy 429.942802 -105.989472) (xy 429.922879 -105.937381) (xy 429.910753 -105.882944)
			(xy 429.906682 -105.827322) (xy 415.17824 -105.827322) (xy 415.17824 -107.15117) (xy 428.930814 -107.15117)
			(xy 428.934885 -107.095548) (xy 428.947011 -107.041111) (xy 428.966934 -106.98902) (xy 428.99423 -106.940385)
			(xy 429.028316 -106.896242) (xy 429.068465 -106.857533) (xy 429.113823 -106.825082) (xy 429.163423 -106.799581)
			(xy 429.216207 -106.781574) (xy 429.27105 -106.771444) (xy 429.326784 -106.769407) (xy 429.368344 -106.77398)
			(xy 433.340254 -106.77398) (xy 433.344325 -106.718358) (xy 433.356451 -106.663921) (xy 433.376374 -106.61183)
			(xy 433.40367 -106.563195) (xy 433.437756 -106.519052) (xy 433.477905 -106.480343) (xy 433.523263 -106.447892)
			(xy 433.572863 -106.422391) (xy 433.625647 -106.404384) (xy 433.68049 -106.394254) (xy 433.736224 -106.392217)
			(xy 433.791661 -106.398317) (xy 433.845618 -106.412423) (xy 433.896947 -106.434235) (xy 433.944553 -106.463289)
			(xy 433.987421 -106.498964) (xy 434.024638 -106.540501) (xy 434.055411 -106.587014) (xy 434.079083 -106.637511)
			(xy 434.095151 -106.690918) (xy 434.103271 -106.746094) (xy 434.10378 -106.77398) (xy 434.103271 -106.801866)
			(xy 434.095151 -106.857042) (xy 434.079083 -106.910449) (xy 434.055411 -106.960946) (xy 434.024638 -107.007459)
			(xy 433.987421 -107.048996) (xy 433.944553 -107.084671) (xy 433.896947 -107.113725) (xy 433.845618 -107.135537)
			(xy 433.791661 -107.149643) (xy 433.736224 -107.155743) (xy 433.68049 -107.153706) (xy 433.625647 -107.143576)
			(xy 433.572863 -107.125569) (xy 433.523263 -107.100068) (xy 433.477905 -107.067617) (xy 433.437756 -107.028908)
			(xy 433.40367 -106.984765) (xy 433.376374 -106.93613) (xy 433.356451 -106.884039) (xy 433.344325 -106.829602)
			(xy 433.340254 -106.77398) (xy 429.368344 -106.77398) (xy 429.382221 -106.775507) (xy 429.436178 -106.789613)
			(xy 429.487507 -106.811425) (xy 429.535113 -106.840479) (xy 429.577981 -106.876154) (xy 429.615198 -106.917691)
			(xy 429.645971 -106.964204) (xy 429.669643 -107.014701) (xy 429.685711 -107.068108) (xy 429.693831 -107.123284)
			(xy 429.69434 -107.15117) (xy 429.693831 -107.179056) (xy 429.685711 -107.234232) (xy 429.677688 -107.260898)
			(xy 430.263552 -107.260898) (xy 430.267623 -107.205276) (xy 430.279749 -107.150839) (xy 430.299672 -107.098748)
			(xy 430.326968 -107.050113) (xy 430.361054 -107.00597) (xy 430.401203 -106.967261) (xy 430.446561 -106.93481)
			(xy 430.496161 -106.909309) (xy 430.548945 -106.891302) (xy 430.603788 -106.881172) (xy 430.659522 -106.879135)
			(xy 430.714959 -106.885235) (xy 430.768916 -106.899341) (xy 430.820245 -106.921153) (xy 430.867851 -106.950207)
			(xy 430.910719 -106.985882) (xy 430.947936 -107.027419) (xy 430.978709 -107.073932) (xy 431.002381 -107.124429)
			(xy 431.018449 -107.177836) (xy 431.026569 -107.233012) (xy 431.027078 -107.260898) (xy 431.026569 -107.288784)
			(xy 431.018449 -107.34396) (xy 431.002381 -107.397367) (xy 430.978709 -107.447864) (xy 430.947936 -107.494377)
			(xy 430.910719 -107.535914) (xy 430.867851 -107.571589) (xy 430.820245 -107.600643) (xy 430.768916 -107.622455)
			(xy 430.714959 -107.636561) (xy 430.659522 -107.642661) (xy 430.603788 -107.640624) (xy 430.548945 -107.630494)
			(xy 430.496161 -107.612487) (xy 430.446561 -107.586986) (xy 430.401203 -107.554535) (xy 430.361054 -107.515826)
			(xy 430.326968 -107.471683) (xy 430.299672 -107.423048) (xy 430.279749 -107.370957) (xy 430.267623 -107.31652)
			(xy 430.263552 -107.260898) (xy 429.677688 -107.260898) (xy 429.669643 -107.287639) (xy 429.645971 -107.338136)
			(xy 429.615198 -107.384649) (xy 429.577981 -107.426186) (xy 429.535113 -107.461861) (xy 429.487507 -107.490915)
			(xy 429.436178 -107.512727) (xy 429.382221 -107.526833) (xy 429.326784 -107.532933) (xy 429.27105 -107.530896)
			(xy 429.216207 -107.520766) (xy 429.163423 -107.502759) (xy 429.113823 -107.477258) (xy 429.068465 -107.444807)
			(xy 429.028316 -107.406098) (xy 428.99423 -107.361955) (xy 428.966934 -107.31332) (xy 428.947011 -107.261229)
			(xy 428.934885 -107.206792) (xy 428.930814 -107.15117) (xy 415.17824 -107.15117) (xy 415.17824 -107.645708)
			(xy 431.703478 -107.645708) (xy 431.707549 -107.590086) (xy 431.719675 -107.535649) (xy 431.739598 -107.483558)
			(xy 431.766894 -107.434923) (xy 431.80098 -107.39078) (xy 431.841129 -107.352071) (xy 431.886487 -107.31962)
			(xy 431.936087 -107.294119) (xy 431.988871 -107.276112) (xy 432.043714 -107.265982) (xy 432.099448 -107.263945)
			(xy 432.154885 -107.270045) (xy 432.208842 -107.284151) (xy 432.260171 -107.305963) (xy 432.307777 -107.335017)
			(xy 432.350645 -107.370692) (xy 432.387862 -107.412229) (xy 432.418635 -107.458742) (xy 432.442307 -107.509239)
			(xy 432.458375 -107.562646) (xy 432.466495 -107.617822) (xy 432.467004 -107.645708) (xy 432.466495 -107.673594)
			(xy 432.458375 -107.72877) (xy 432.442307 -107.782177) (xy 432.418635 -107.832674) (xy 432.387862 -107.879187)
			(xy 432.350645 -107.920724) (xy 432.307777 -107.956399) (xy 432.260171 -107.985453) (xy 432.208842 -108.007265)
			(xy 432.154885 -108.021371) (xy 432.099448 -108.027471) (xy 432.043714 -108.025434) (xy 431.988871 -108.015304)
			(xy 431.936087 -107.997297) (xy 431.886487 -107.971796) (xy 431.841129 -107.939345) (xy 431.80098 -107.900636)
			(xy 431.766894 -107.856493) (xy 431.739598 -107.807858) (xy 431.719675 -107.755767) (xy 431.707549 -107.70133)
			(xy 431.703478 -107.645708) (xy 415.17824 -107.645708) (xy 415.17824 -111.435388) (xy 415.205164 -111.462312)
			(xy 415.215011 -111.471578) (xy 415.238461 -111.485018) (xy 415.264618 -111.491826) (xy 415.291645 -111.491524)
			(xy 415.317644 -111.484132) (xy 415.340787 -111.47017) (xy 415.359449 -111.450618) (xy 415.37232 -111.426851)
			(xy 415.375852 -111.413798) (xy 415.382204 -111.388733) (xy 415.400761 -111.34047) (xy 415.42567 -111.295158)
			(xy 415.456474 -111.253627) (xy 415.492607 -111.21664) (xy 415.512758 -111.200438) (xy 415.52457 -111.190542)
			(xy 415.542101 -111.165217) (xy 415.551286 -111.135818) (xy 415.551291 -111.105017) (xy 415.542116 -111.075614)
			(xy 415.524594 -111.050283) (xy 415.512758 -111.040418) (xy 415.491973 -111.023665) (xy 415.454839 -110.985311)
			(xy 415.423414 -110.942155) (xy 415.398311 -110.89504) (xy 415.380022 -110.844886) (xy 415.368902 -110.792672)
			(xy 415.36517 -110.739417) (xy 415.368897 -110.686163) (xy 415.380012 -110.633947) (xy 415.398297 -110.583791)
			(xy 415.423395 -110.536674) (xy 415.454817 -110.493516) (xy 415.491947 -110.455158) (xy 415.512758 -110.438438)
			(xy 415.52457 -110.428542) (xy 415.542101 -110.403217) (xy 415.551286 -110.373818) (xy 415.551291 -110.343017)
			(xy 415.542116 -110.313614) (xy 415.524594 -110.288283) (xy 415.512758 -110.278418) (xy 415.491973 -110.261665)
			(xy 415.454839 -110.223311) (xy 415.423414 -110.180155) (xy 415.398311 -110.13304) (xy 415.380022 -110.082886)
			(xy 415.368902 -110.030672) (xy 415.36517 -109.977417) (xy 415.368897 -109.924163) (xy 415.380012 -109.871947)
			(xy 415.398297 -109.821791) (xy 415.423395 -109.774674) (xy 415.454817 -109.731516) (xy 415.491947 -109.693158)
			(xy 415.512758 -109.676438) (xy 415.52457 -109.666542) (xy 415.542101 -109.641217) (xy 415.551286 -109.611818)
			(xy 415.551291 -109.581017) (xy 415.542116 -109.551614) (xy 415.524594 -109.526283) (xy 415.512758 -109.516418)
			(xy 415.491973 -109.499665) (xy 415.454839 -109.461311) (xy 415.423414 -109.418155) (xy 415.398311 -109.37104)
			(xy 415.380022 -109.320886) (xy 415.368902 -109.268672) (xy 415.36517 -109.215417) (xy 415.368897 -109.162163)
			(xy 415.380012 -109.109947) (xy 415.398297 -109.059791) (xy 415.423395 -109.012674) (xy 415.454817 -108.969516)
			(xy 415.491947 -108.931158) (xy 415.512758 -108.914438) (xy 415.52457 -108.904542) (xy 415.542101 -108.879217)
			(xy 415.551286 -108.849818) (xy 415.551291 -108.819017) (xy 415.542116 -108.789614) (xy 415.524594 -108.764283)
			(xy 415.512758 -108.754418) (xy 415.490272 -108.736229) (xy 415.450531 -108.694213) (xy 415.417588 -108.646679)
			(xy 415.3922 -108.594717) (xy 415.374948 -108.539517) (xy 415.366227 -108.482345) (xy 415.365692 -108.453428)
			(xy 415.366153 -108.426174) (xy 415.373907 -108.37222) (xy 415.389261 -108.319919) (xy 415.411902 -108.270335)
			(xy 415.441369 -108.224478) (xy 415.477063 -108.183282) (xy 415.518256 -108.147586) (xy 415.56411 -108.118115)
			(xy 415.613692 -108.095471) (xy 415.665992 -108.080113) (xy 415.719946 -108.072355) (xy 415.7472 -108.07192)
			(xy 415.776116 -108.072454) (xy 415.833287 -108.081181) (xy 415.888486 -108.098436) (xy 415.940449 -108.123823)
			(xy 415.987986 -108.156761) (xy 416.030008 -108.196495) (xy 416.04819 -108.218986) (xy 416.058087 -108.230791)
			(xy 416.083411 -108.24831) (xy 416.112804 -108.257486) (xy 416.143596 -108.257486) (xy 416.172989 -108.24831)
			(xy 416.198313 -108.230791) (xy 416.20821 -108.218986) (xy 416.2264 -108.1965) (xy 416.268416 -108.156758)
			(xy 416.31595 -108.123812) (xy 416.367912 -108.098419) (xy 416.423111 -108.08116) (xy 416.480283 -108.072431)
			(xy 416.5092 -108.07192) (xy 416.536452 -108.072383) (xy 416.590402 -108.08014) (xy 416.642698 -108.095497)
			(xy 416.692276 -108.11814) (xy 416.738127 -108.147608) (xy 416.779318 -108.183302) (xy 416.815009 -108.224495)
			(xy 416.844474 -108.270348) (xy 416.867113 -108.319928) (xy 416.882465 -108.372226) (xy 416.890219 -108.426176)
			(xy 416.890708 -108.453428) (xy 416.890172 -108.482344) (xy 416.881441 -108.539513) (xy 416.864185 -108.59471)
			(xy 416.838797 -108.646671) (xy 416.805859 -108.694206) (xy 416.766126 -108.736227) (xy 416.743642 -108.754418)
			(xy 416.731838 -108.764314) (xy 416.714324 -108.789634) (xy 416.705152 -108.819023) (xy 416.705157 -108.849811)
			(xy 416.714339 -108.879197) (xy 416.731862 -108.904512) (xy 416.743642 -108.914438) (xy 416.764423 -108.931192)
			(xy 416.801549 -108.969544) (xy 416.832967 -109.012698) (xy 416.858062 -109.05981) (xy 416.876345 -109.10996)
			(xy 416.887458 -109.162169) (xy 416.891186 -109.215417) (xy 416.887454 -109.268665) (xy 416.876335 -109.320873)
			(xy 416.858048 -109.371022) (xy 416.832948 -109.418131) (xy 416.801527 -109.461282) (xy 416.764397 -109.499631)
			(xy 416.743642 -109.516418) (xy 416.731838 -109.526314) (xy 416.714324 -109.551634) (xy 416.705152 -109.581023)
			(xy 416.705157 -109.611811) (xy 416.714339 -109.641197) (xy 416.72959 -109.66323) (xy 433.334158 -109.66323)
			(xy 433.338229 -109.607608) (xy 433.350355 -109.553171) (xy 433.370278 -109.50108) (xy 433.397574 -109.452445)
			(xy 433.43166 -109.408302) (xy 433.471809 -109.369593) (xy 433.517167 -109.337142) (xy 433.566767 -109.311641)
			(xy 433.619551 -109.293634) (xy 433.674394 -109.283504) (xy 433.730128 -109.281467) (xy 433.785565 -109.287567)
			(xy 433.839522 -109.301673) (xy 433.890851 -109.323485) (xy 433.938457 -109.352539) (xy 433.981325 -109.388214)
			(xy 434.018542 -109.429751) (xy 434.049315 -109.476264) (xy 434.072987 -109.526761) (xy 434.089055 -109.580168)
			(xy 434.097175 -109.635344) (xy 434.097684 -109.66323) (xy 434.097175 -109.691116) (xy 434.089055 -109.746292)
			(xy 434.072987 -109.799699) (xy 434.049315 -109.850196) (xy 434.018542 -109.896709) (xy 433.981325 -109.938246)
			(xy 433.938457 -109.973921) (xy 433.890851 -110.002975) (xy 433.839522 -110.024787) (xy 433.785565 -110.038893)
			(xy 433.730128 -110.044993) (xy 433.674394 -110.042956) (xy 433.619551 -110.032826) (xy 433.566767 -110.014819)
			(xy 433.517167 -109.989318) (xy 433.471809 -109.956867) (xy 433.43166 -109.918158) (xy 433.397574 -109.874015)
			(xy 433.370278 -109.82538) (xy 433.350355 -109.773289) (xy 433.338229 -109.718852) (xy 433.334158 -109.66323)
			(xy 416.72959 -109.66323) (xy 416.731862 -109.666512) (xy 416.743642 -109.676438) (xy 416.764423 -109.693192)
			(xy 416.801549 -109.731544) (xy 416.832967 -109.774698) (xy 416.858062 -109.82181) (xy 416.876345 -109.87196)
			(xy 416.887458 -109.924169) (xy 416.891186 -109.977417) (xy 416.887454 -110.030665) (xy 416.876335 -110.082873)
			(xy 416.858048 -110.133022) (xy 416.832948 -110.180131) (xy 416.801527 -110.223282) (xy 416.764397 -110.261631)
			(xy 416.743642 -110.278418) (xy 416.740612 -110.280958) (xy 419.761922 -110.280958) (xy 419.765993 -110.225336)
			(xy 419.778119 -110.170899) (xy 419.798042 -110.118808) (xy 419.825338 -110.070173) (xy 419.859424 -110.02603)
			(xy 419.899573 -109.987321) (xy 419.944931 -109.95487) (xy 419.994531 -109.929369) (xy 420.047315 -109.911362)
			(xy 420.102158 -109.901232) (xy 420.157892 -109.899195) (xy 420.213329 -109.905295) (xy 420.267286 -109.919401)
			(xy 420.318615 -109.941213) (xy 420.366221 -109.970267) (xy 420.409089 -110.005942) (xy 420.446306 -110.047479)
			(xy 420.477079 -110.093992) (xy 420.500751 -110.144489) (xy 420.516819 -110.197896) (xy 420.524939 -110.253072)
			(xy 420.525369 -110.27664) (xy 428.913542 -110.27664) (xy 428.917613 -110.221018) (xy 428.929739 -110.166581)
			(xy 428.949662 -110.11449) (xy 428.976958 -110.065855) (xy 429.011044 -110.021712) (xy 429.051193 -109.983003)
			(xy 429.096551 -109.950552) (xy 429.146151 -109.925051) (xy 429.198935 -109.907044) (xy 429.253778 -109.896914)
			(xy 429.309512 -109.894877) (xy 429.364949 -109.900977) (xy 429.418906 -109.915083) (xy 429.470235 -109.936895)
			(xy 429.517841 -109.965949) (xy 429.560709 -110.001624) (xy 429.597926 -110.043161) (xy 429.628699 -110.089674)
			(xy 429.652371 -110.140171) (xy 429.668439 -110.193578) (xy 429.676559 -110.248754) (xy 429.677068 -110.27664)
			(xy 429.676559 -110.304526) (xy 429.668439 -110.359702) (xy 429.652371 -110.413109) (xy 429.628699 -110.463606)
			(xy 429.597926 -110.510119) (xy 429.560709 -110.551656) (xy 429.517841 -110.587331) (xy 429.470235 -110.616385)
			(xy 429.418906 -110.638197) (xy 429.364949 -110.652303) (xy 429.309512 -110.658403) (xy 429.253778 -110.656366)
			(xy 429.198935 -110.646236) (xy 429.146151 -110.628229) (xy 429.096551 -110.602728) (xy 429.051193 -110.570277)
			(xy 429.011044 -110.531568) (xy 428.976958 -110.487425) (xy 428.949662 -110.43879) (xy 428.929739 -110.386699)
			(xy 428.917613 -110.332262) (xy 428.913542 -110.27664) (xy 420.525369 -110.27664) (xy 420.525448 -110.280958)
			(xy 420.524939 -110.308844) (xy 420.516819 -110.36402) (xy 420.500751 -110.417427) (xy 420.477079 -110.467924)
			(xy 420.446306 -110.514437) (xy 420.409089 -110.555974) (xy 420.366221 -110.591649) (xy 420.318615 -110.620703)
			(xy 420.267286 -110.642515) (xy 420.213329 -110.656621) (xy 420.157892 -110.662721) (xy 420.102158 -110.660684)
			(xy 420.047315 -110.650554) (xy 419.994531 -110.632547) (xy 419.944931 -110.607046) (xy 419.899573 -110.574595)
			(xy 419.859424 -110.535886) (xy 419.825338 -110.491743) (xy 419.798042 -110.443108) (xy 419.778119 -110.391017)
			(xy 419.765993 -110.33658) (xy 419.761922 -110.280958) (xy 416.740612 -110.280958) (xy 416.731838 -110.288314)
			(xy 416.714324 -110.313634) (xy 416.705152 -110.343023) (xy 416.705157 -110.373811) (xy 416.714339 -110.403197)
			(xy 416.731862 -110.428512) (xy 416.743642 -110.438438) (xy 416.764423 -110.455192) (xy 416.801549 -110.493544)
			(xy 416.832967 -110.536698) (xy 416.858062 -110.58381) (xy 416.876345 -110.63396) (xy 416.887458 -110.686169)
			(xy 416.891186 -110.739417) (xy 416.887454 -110.792665) (xy 416.876335 -110.844873) (xy 416.858048 -110.895022)
			(xy 416.832948 -110.942131) (xy 416.801527 -110.985282) (xy 416.764397 -111.023631) (xy 416.743642 -111.040418)
			(xy 416.731838 -111.050314) (xy 416.714324 -111.075634) (xy 416.705152 -111.105023) (xy 416.705157 -111.135811)
			(xy 416.714339 -111.165197) (xy 416.731862 -111.190512) (xy 416.743642 -111.200438) (xy 416.76613 -111.218626)
			(xy 416.805877 -111.26064) (xy 416.838825 -111.308173) (xy 416.864219 -111.360136) (xy 416.881477 -111.415337)
			(xy 416.890205 -111.47251) (xy 416.890708 -111.501428) (xy 416.890344 -111.525698) (xy 416.884229 -111.57385)
			(xy 416.878516 -111.59744) (xy 416.875182 -111.612551) (xy 416.876772 -111.643439) (xy 416.887527 -111.672439)
			(xy 416.906462 -111.696895) (xy 416.931844 -111.714569) (xy 416.96135 -111.723843) (xy 416.976814 -111.72444)
			(xy 434.500274 -111.72444)
		)
		(stroke
			(width 0)
			(type solid)
		)
		(fill yes)
		(layer "In4.Cu")
		(net "GND")
	)
	(gr_poly
		(pts
			(xy 98.857816 -222.716598) (xy 98.881551 -222.714118) (xy 98.929203 -222.711448) (xy 98.953066 -222.711264)
			(xy 98.97693 -222.711439) (xy 99.024582 -222.714107) (xy 99.048316 -222.716598) (xy 99.057382 -222.717175)
			(xy 99.074966 -222.712664) (xy 99.089886 -222.702324) (xy 99.100283 -222.687443) (xy 99.102926 -222.678752)
			(xy 99.110306 -222.652535) (xy 99.132445 -222.602778) (xy 99.162434 -222.557318) (xy 99.199464 -222.517385)
			(xy 99.242536 -222.484057) (xy 99.290484 -222.458233) (xy 99.342015 -222.440613) (xy 99.395736 -222.43167)
			(xy 99.422966 -222.431102) (xy 99.450187 -222.431663) (xy 99.50389 -222.440598) (xy 99.555402 -222.458217)
			(xy 99.603328 -222.484042) (xy 99.646373 -222.517375) (xy 99.68337 -222.557313) (xy 99.71332 -222.602776)
			(xy 99.735412 -222.652534) (xy 99.742752 -222.678752) (xy 99.745415 -222.687459) (xy 99.755879 -222.702343)
			(xy 99.770884 -222.712632) (xy 99.788538 -222.71703) (xy 99.797616 -222.716344) (xy 99.988116 -222.716344)
			(xy 99.997205 -222.717043) (xy 100.014896 -222.712699) (xy 100.029927 -222.702408) (xy 100.040376 -222.687487)
			(xy 100.04298 -222.678752) (xy 100.050319 -222.65253) (xy 100.072387 -222.602755) (xy 100.102324 -222.557277)
			(xy 100.139319 -222.517327) (xy 100.182368 -222.483991) (xy 100.230304 -222.458172) (xy 100.281828 -222.440569)
			(xy 100.335542 -222.431661) (xy 100.362766 -222.431102) (xy 100.387528 -222.431541) (xy 100.436498 -222.438928)
			(xy 100.483817 -222.45354) (xy 100.528425 -222.475052) (xy 100.569323 -222.50298) (xy 100.605594 -222.536699)
			(xy 100.621338 -222.555816) (xy 100.630612 -222.566712) (xy 100.653918 -222.583288) (xy 100.68091 -222.592742)
			(xy 100.709466 -222.594331) (xy 100.73734 -222.587931) (xy 100.762342 -222.574043) (xy 100.772722 -222.564198)
			(xy 100.98405 -222.35287) (xy 100.98405 -222.264732) (xy 100.926392 -222.264732) (xy 100.919788 -222.26651)
			(xy 100.898364 -222.272002) (xy 100.854526 -222.277869) (xy 100.832412 -222.278194) (xy 100.806443 -222.277686)
			(xy 100.755144 -222.269563) (xy 100.705747 -222.253516) (xy 100.659469 -222.22994) (xy 100.617448 -222.199414)
			(xy 100.58072 -222.162691) (xy 100.550188 -222.120675) (xy 100.526604 -222.074401) (xy 100.510549 -222.025006)
			(xy 100.502418 -221.973709) (xy 100.501958 -221.94774) (xy 100.502568 -221.919759) (xy 100.512015 -221.8646)
			(xy 100.520754 -221.838012) (xy 100.528374 -221.815914) (xy 100.324666 -221.463108) (xy 100.301806 -221.45879)
			(xy 100.276879 -221.453638) (xy 100.228882 -221.436693) (xy 100.184052 -221.412586) (xy 100.143451 -221.381889)
			(xy 100.108038 -221.345327) (xy 100.078652 -221.303766) (xy 100.055989 -221.258189) (xy 100.040585 -221.209676)
			(xy 100.032805 -221.159374) (xy 100.032312 -221.133924) (xy 100.032821 -221.107957) (xy 100.040946 -221.056662)
			(xy 100.056994 -221.007269) (xy 100.080572 -220.960995) (xy 100.111098 -220.918979) (xy 100.147821 -220.882256)
			(xy 100.189837 -220.85173) (xy 100.236111 -220.828152) (xy 100.285504 -220.812104) (xy 100.336799 -220.803979)
			(xy 100.388733 -220.803979) (xy 100.440028 -220.812104) (xy 100.489421 -220.828152) (xy 100.535695 -220.85173)
			(xy 100.577711 -220.882256) (xy 100.614434 -220.918979) (xy 100.64496 -220.960995) (xy 100.668538 -221.007269)
			(xy 100.684586 -221.056662) (xy 100.692711 -221.107957) (xy 100.69322 -221.133924) (xy 100.692605 -221.161904)
			(xy 100.68315 -221.21706) (xy 100.674424 -221.243652) (xy 100.666804 -221.26575) (xy 100.870512 -221.618556)
			(xy 100.893372 -221.622874) (xy 100.919788 -221.62897) (xy 100.926392 -221.630748) (xy 100.98405 -221.630748)
			(xy 100.98405 -221.222062) (xy 100.982526 -221.215966) (xy 100.977674 -221.195803) (xy 100.972448 -221.15466)
			(xy 100.972112 -221.133924) (xy 100.972454 -221.113188) (xy 100.97768 -221.072047) (xy 100.982526 -221.051882)
			(xy 100.98405 -221.045786) (xy 100.98405 -220.749114) (xy 100.983605 -220.734792) (xy 100.975726 -220.707257)
			(xy 100.960501 -220.682999) (xy 100.93913 -220.663932) (xy 100.9133 -220.651559) (xy 100.885048 -220.646857)
			(xy 100.870766 -220.648022) (xy 100.861276 -220.649077) (xy 100.842214 -220.65022) (xy 100.832666 -220.650308)
			(xy 100.806704 -220.649796) (xy 100.75542 -220.641669) (xy 100.706039 -220.62562) (xy 100.659776 -220.602043)
			(xy 100.617771 -220.571521) (xy 100.581057 -220.534803) (xy 100.550539 -220.492795) (xy 100.526967 -220.446529)
			(xy 100.510923 -220.397147) (xy 100.502801 -220.345862) (xy 100.502801 -220.293938) (xy 100.510923 -220.242653)
			(xy 100.526967 -220.193271) (xy 100.550539 -220.147005) (xy 100.581057 -220.104997) (xy 100.617771 -220.068279)
			(xy 100.659776 -220.037757) (xy 100.706039 -220.01418) (xy 100.75542 -219.998131) (xy 100.806704 -219.990004)
			(xy 100.832666 -219.9894) (xy 100.842214 -219.989493) (xy 100.861275 -219.990638) (xy 100.870766 -219.991686)
			(xy 100.885041 -219.992842) (xy 100.913272 -219.988101) (xy 100.939079 -219.975715) (xy 100.960438 -219.956655)
			(xy 100.975672 -219.932419) (xy 100.983584 -219.904908) (xy 100.98405 -219.890594) (xy 100.98405 -219.594176)
			(xy 100.982526 -219.58808) (xy 100.979493 -219.575921) (xy 100.975044 -219.551256) (xy 100.973636 -219.538804)
			(xy 100.971598 -219.523477) (xy 100.959531 -219.495027) (xy 100.939492 -219.471501) (xy 100.913325 -219.455059)
			(xy 100.883434 -219.447214) (xy 100.867972 -219.447364) (xy 100.832412 -219.44838) (xy 100.79736 -219.447364)
			(xy 100.7819 -219.447196) (xy 100.752018 -219.455072) (xy 100.725857 -219.471522) (xy 100.70581 -219.49504)
			(xy 100.693712 -219.523477) (xy 100.691696 -219.538804) (xy 100.688482 -219.565653) (xy 100.674437 -219.617867)
			(xy 100.652076 -219.667096) (xy 100.621996 -219.712027) (xy 100.585 -219.751459) (xy 100.542076 -219.784339)
			(xy 100.49437 -219.809789) (xy 100.443156 -219.827129) (xy 100.389801 -219.835898) (xy 100.362766 -219.836492)
			(xy 100.336799 -219.83598) (xy 100.285506 -219.827852) (xy 100.236116 -219.811801) (xy 100.189844 -219.788222)
			(xy 100.14783 -219.757696) (xy 100.111107 -219.720974) (xy 100.08058 -219.67896) (xy 100.057001 -219.632688)
			(xy 100.040949 -219.583298) (xy 100.03282 -219.532005) (xy 100.032312 -219.506038) (xy 100.032809 -219.479947)
			(xy 100.041019 -219.428415) (xy 100.057225 -219.378813) (xy 100.081025 -219.332374) (xy 100.111827 -219.290252)
			(xy 100.148865 -219.253494) (xy 100.169726 -219.237814) (xy 100.18197 -219.228355) (xy 100.200555 -219.203636)
			(xy 100.210907 -219.174494) (xy 100.212082 -219.143591) (xy 100.203972 -219.113747) (xy 100.196142 -219.1004)
			(xy 100.1776 -219.070174) (xy 100.021136 -218.799156) (xy 100.00178 -218.764644) (xy 99.969588 -218.692355)
			(xy 99.956874 -218.654884) (xy 99.934598 -218.629451) (xy 99.894154 -218.575266) (xy 99.876102 -218.54668)
			(xy 99.870508 -218.538518) (xy 99.854524 -218.526886) (xy 99.835327 -218.522163) (xy 99.81577 -218.52505)
			(xy 99.807014 -218.529662) (xy 99.781325 -218.544423) (xy 99.728051 -218.57036) (xy 99.700588 -218.581478)
			(xy 99.704398 -218.609005) (xy 99.708463 -218.664433) (xy 99.708716 -218.692222) (xy 99.708304 -218.728133)
			(xy 99.701516 -218.799632) (xy 99.687973 -218.870165) (xy 99.667799 -218.939094) (xy 99.641175 -219.005798)
			(xy 99.608342 -219.069675) (xy 99.589336 -219.100146) (xy 99.581456 -219.113453) (xy 99.573318 -219.143276)
			(xy 99.574455 -219.174167) (xy 99.584763 -219.203311) (xy 99.603301 -219.228048) (xy 99.615498 -219.23756)
			(xy 99.636457 -219.253184) (xy 99.673625 -219.28994) (xy 99.704535 -219.332095) (xy 99.728414 -219.378595)
			(xy 99.744666 -219.428278) (xy 99.752883 -219.479901) (xy 99.75342 -219.506038) (xy 99.752908 -219.532002)
			(xy 99.744779 -219.583291) (xy 99.728726 -219.632676) (xy 99.705146 -219.678942) (xy 99.674618 -219.72095)
			(xy 99.637895 -219.757665) (xy 99.595881 -219.788184) (xy 99.549609 -219.811754) (xy 99.500221 -219.827795)
			(xy 99.44893 -219.835914) (xy 99.422966 -219.836492) (xy 99.39593 -219.835951) (xy 99.342581 -219.827149)
			(xy 99.291373 -219.809785) (xy 99.243673 -219.784321) (xy 99.200751 -219.751437) (xy 99.16375 -219.712008)
			(xy 99.133657 -219.667085) (xy 99.111273 -219.617865) (xy 99.097195 -219.565658) (xy 99.094036 -219.538804)
			(xy 99.091998 -219.523477) (xy 99.079931 -219.495027) (xy 99.059892 -219.471501) (xy 99.033725 -219.455059)
			(xy 99.003834 -219.447214) (xy 98.988372 -219.447364) (xy 98.952812 -219.44838) (xy 98.91776 -219.447364)
			(xy 98.9023 -219.447196) (xy 98.872418 -219.455072) (xy 98.846257 -219.471522) (xy 98.82621 -219.49504)
			(xy 98.814112 -219.523477) (xy 98.812096 -219.538804) (xy 98.808882 -219.565653) (xy 98.794837 -219.617867)
			(xy 98.772476 -219.667096) (xy 98.742396 -219.712027) (xy 98.7054 -219.751459) (xy 98.662476 -219.784339)
			(xy 98.61477 -219.809789) (xy 98.563556 -219.827129) (xy 98.510201 -219.835898) (xy 98.483166 -219.836492)
			(xy 98.457199 -219.83598) (xy 98.405906 -219.827852) (xy 98.356516 -219.811801) (xy 98.310244 -219.788222)
			(xy 98.26823 -219.757696) (xy 98.231507 -219.720974) (xy 98.20098 -219.67896) (xy 98.177401 -219.632688)
			(xy 98.161349 -219.583298) (xy 98.15322 -219.532005) (xy 98.152712 -219.506038) (xy 98.153209 -219.479947)
			(xy 98.161419 -219.428415) (xy 98.177625 -219.378813) (xy 98.201425 -219.332374) (xy 98.232227 -219.290252)
			(xy 98.269265 -219.253494) (xy 98.290126 -219.237814) (xy 98.30237 -219.228355) (xy 98.320955 -219.203636)
			(xy 98.331307 -219.174494) (xy 98.332482 -219.143591) (xy 98.324372 -219.113747) (xy 98.316542 -219.1004)
			(xy 98.298 -219.070174) (xy 98.141536 -218.799156) (xy 98.12218 -218.764644) (xy 98.089988 -218.692355)
			(xy 98.077274 -218.654884) (xy 98.054998 -218.629451) (xy 98.014554 -218.575266) (xy 97.996502 -218.54668)
			(xy 97.990908 -218.538518) (xy 97.974924 -218.526886) (xy 97.955727 -218.522163) (xy 97.93617 -218.52505)
			(xy 97.927414 -218.529662) (xy 97.901725 -218.544423) (xy 97.848451 -218.57036) (xy 97.820988 -218.581478)
			(xy 97.824798 -218.609005) (xy 97.828863 -218.664433) (xy 97.829116 -218.692222) (xy 97.828704 -218.728133)
			(xy 97.821916 -218.799632) (xy 97.808373 -218.870165) (xy 97.788199 -218.939094) (xy 97.761575 -219.005798)
			(xy 97.728742 -219.069675) (xy 97.709736 -219.100146) (xy 97.701856 -219.113453) (xy 97.693718 -219.143276)
			(xy 97.694855 -219.174167) (xy 97.705163 -219.203311) (xy 97.723701 -219.228048) (xy 97.735898 -219.23756)
			(xy 97.756857 -219.253184) (xy 97.794025 -219.28994) (xy 97.824935 -219.332095) (xy 97.848814 -219.378595)
			(xy 97.865066 -219.428278) (xy 97.873283 -219.479901) (xy 97.87382 -219.506038) (xy 97.873308 -219.532002)
			(xy 97.865179 -219.583291) (xy 97.849126 -219.632676) (xy 97.825546 -219.678942) (xy 97.795018 -219.72095)
			(xy 97.758295 -219.757665) (xy 97.716281 -219.788184) (xy 97.670009 -219.811754) (xy 97.620621 -219.827795)
			(xy 97.56933 -219.835914) (xy 97.543366 -219.836492) (xy 97.51633 -219.835951) (xy 97.462981 -219.827149)
			(xy 97.411773 -219.809785) (xy 97.364073 -219.784321) (xy 97.321151 -219.751437) (xy 97.28415 -219.712008)
			(xy 97.254057 -219.667085) (xy 97.231673 -219.617865) (xy 97.217595 -219.565658) (xy 97.214436 -219.538804)
			(xy 97.212398 -219.523477) (xy 97.200331 -219.495027) (xy 97.180292 -219.471501) (xy 97.154125 -219.455059)
			(xy 97.124234 -219.447214) (xy 97.108772 -219.447364) (xy 97.073212 -219.44838) (xy 97.03816 -219.447364)
			(xy 97.0227 -219.447196) (xy 96.992818 -219.455072) (xy 96.966657 -219.471522) (xy 96.94661 -219.49504)
			(xy 96.934512 -219.523477) (xy 96.932496 -219.538804) (xy 96.929282 -219.565653) (xy 96.915237 -219.617867)
			(xy 96.892876 -219.667096) (xy 96.862796 -219.712027) (xy 96.8258 -219.751459) (xy 96.782876 -219.784339)
			(xy 96.73517 -219.809789) (xy 96.683956 -219.827129) (xy 96.630601 -219.835898) (xy 96.603566 -219.836492)
			(xy 96.577599 -219.83598) (xy 96.526306 -219.827852) (xy 96.476916 -219.811801) (xy 96.430644 -219.788222)
			(xy 96.38863 -219.757696) (xy 96.351907 -219.720974) (xy 96.32138 -219.67896) (xy 96.297801 -219.632688)
			(xy 96.281749 -219.583298) (xy 96.27362 -219.532005) (xy 96.273112 -219.506038) (xy 96.273609 -219.479947)
			(xy 96.281819 -219.428415) (xy 96.298025 -219.378813) (xy 96.321825 -219.332374) (xy 96.352627 -219.290252)
			(xy 96.389665 -219.253494) (xy 96.410526 -219.237814) (xy 96.42277 -219.228355) (xy 96.441355 -219.203636)
			(xy 96.451707 -219.174494) (xy 96.452882 -219.143591) (xy 96.444772 -219.113747) (xy 96.436942 -219.1004)
			(xy 96.4184 -219.070174) (xy 96.261936 -218.799156) (xy 96.24258 -218.764644) (xy 96.210388 -218.692355)
			(xy 96.197674 -218.654884) (xy 96.175398 -218.629451) (xy 96.134954 -218.575266) (xy 96.116902 -218.54668)
			(xy 96.111308 -218.538518) (xy 96.095324 -218.526886) (xy 96.076127 -218.522163) (xy 96.05657 -218.52505)
			(xy 96.047814 -218.529662) (xy 96.022125 -218.544423) (xy 95.968851 -218.57036) (xy 95.941388 -218.581478)
			(xy 95.945198 -218.609005) (xy 95.949263 -218.664433) (xy 95.949516 -218.692222) (xy 95.949104 -218.728133)
			(xy 95.942316 -218.799632) (xy 95.928773 -218.870165) (xy 95.908599 -218.939094) (xy 95.881975 -219.005798)
			(xy 95.849142 -219.069675) (xy 95.830136 -219.100146) (xy 95.822256 -219.113453) (xy 95.814118 -219.143276)
			(xy 95.815255 -219.174167) (xy 95.825563 -219.203311) (xy 95.844101 -219.228048) (xy 95.856298 -219.23756)
			(xy 95.877257 -219.253184) (xy 95.914425 -219.28994) (xy 95.945335 -219.332095) (xy 95.969214 -219.378595)
			(xy 95.985466 -219.428278) (xy 95.993683 -219.479901) (xy 95.99422 -219.506038) (xy 95.993708 -219.532002)
			(xy 95.985579 -219.583291) (xy 95.969526 -219.632676) (xy 95.945946 -219.678942) (xy 95.915418 -219.72095)
			(xy 95.878695 -219.757665) (xy 95.836681 -219.788184) (xy 95.790409 -219.811754) (xy 95.741021 -219.827795)
			(xy 95.68973 -219.835914) (xy 95.663766 -219.836492) (xy 95.63673 -219.835951) (xy 95.583381 -219.827149)
			(xy 95.532173 -219.809785) (xy 95.484473 -219.784321) (xy 95.441551 -219.751437) (xy 95.40455 -219.712008)
			(xy 95.374457 -219.667085) (xy 95.352073 -219.617865) (xy 95.337995 -219.565658) (xy 95.334836 -219.538804)
			(xy 95.332798 -219.523477) (xy 95.320731 -219.495027) (xy 95.300692 -219.471501) (xy 95.274525 -219.455059)
			(xy 95.244634 -219.447214) (xy 95.229172 -219.447364) (xy 95.193612 -219.44838) (xy 95.15856 -219.447364)
			(xy 95.1431 -219.447196) (xy 95.113218 -219.455072) (xy 95.087057 -219.471522) (xy 95.06701 -219.49504)
			(xy 95.054912 -219.523477) (xy 95.052896 -219.538804) (xy 95.049682 -219.565653) (xy 95.035637 -219.617867)
			(xy 95.013276 -219.667096) (xy 94.983196 -219.712027) (xy 94.9462 -219.751459) (xy 94.903276 -219.784339)
			(xy 94.85557 -219.809789) (xy 94.804356 -219.827129) (xy 94.751001 -219.835898) (xy 94.723966 -219.836492)
			(xy 94.697999 -219.83598) (xy 94.646706 -219.827852) (xy 94.597316 -219.811801) (xy 94.551044 -219.788222)
			(xy 94.50903 -219.757696) (xy 94.472307 -219.720974) (xy 94.44178 -219.67896) (xy 94.418201 -219.632688)
			(xy 94.402149 -219.583298) (xy 94.39402 -219.532005) (xy 94.393512 -219.506038) (xy 94.394009 -219.479947)
			(xy 94.402219 -219.428415) (xy 94.418425 -219.378813) (xy 94.442225 -219.332374) (xy 94.473027 -219.290252)
			(xy 94.510065 -219.253494) (xy 94.530926 -219.237814) (xy 94.54317 -219.228355) (xy 94.561755 -219.203636)
			(xy 94.572107 -219.174494) (xy 94.573282 -219.143591) (xy 94.565172 -219.113747) (xy 94.557342 -219.1004)
			(xy 94.5388 -219.070174) (xy 94.382336 -218.799156) (xy 94.36298 -218.764644) (xy 94.330788 -218.692355)
			(xy 94.318074 -218.654884) (xy 94.295798 -218.629451) (xy 94.255354 -218.575266) (xy 94.237302 -218.54668)
			(xy 94.231708 -218.538518) (xy 94.215724 -218.526886) (xy 94.196527 -218.522163) (xy 94.17697 -218.52505)
			(xy 94.168214 -218.529662) (xy 94.142525 -218.544423) (xy 94.089251 -218.57036) (xy 94.061788 -218.581478)
			(xy 94.065598 -218.609005) (xy 94.069663 -218.664433) (xy 94.069916 -218.692222) (xy 94.069504 -218.728133)
			(xy 94.062716 -218.799632) (xy 94.049173 -218.870165) (xy 94.028999 -218.939094) (xy 94.002375 -219.005798)
			(xy 93.969542 -219.069675) (xy 93.950536 -219.100146) (xy 93.942656 -219.113453) (xy 93.934518 -219.143276)
			(xy 93.935655 -219.174167) (xy 93.945963 -219.203311) (xy 93.964501 -219.228048) (xy 93.976698 -219.23756)
			(xy 93.997657 -219.253184) (xy 94.034825 -219.28994) (xy 94.065735 -219.332095) (xy 94.089614 -219.378595)
			(xy 94.105866 -219.428278) (xy 94.114083 -219.479901) (xy 94.11462 -219.506038) (xy 94.114108 -219.532002)
			(xy 94.105979 -219.583291) (xy 94.089926 -219.632676) (xy 94.066346 -219.678942) (xy 94.035818 -219.72095)
			(xy 93.999095 -219.757665) (xy 93.957081 -219.788184) (xy 93.910809 -219.811754) (xy 93.861421 -219.827795)
			(xy 93.81013 -219.835914) (xy 93.784166 -219.836492) (xy 93.75713 -219.835951) (xy 93.703781 -219.827149)
			(xy 93.652573 -219.809785) (xy 93.604873 -219.784321) (xy 93.561951 -219.751437) (xy 93.52495 -219.712008)
			(xy 93.494857 -219.667085) (xy 93.472473 -219.617865) (xy 93.458395 -219.565658) (xy 93.455236 -219.538804)
			(xy 93.453198 -219.523477) (xy 93.441131 -219.495027) (xy 93.421092 -219.471501) (xy 93.394925 -219.455059)
			(xy 93.365034 -219.447214) (xy 93.349572 -219.447364) (xy 93.314012 -219.44838) (xy 93.27896 -219.447364)
			(xy 93.2635 -219.447196) (xy 93.233618 -219.455072) (xy 93.207457 -219.471522) (xy 93.18741 -219.49504)
			(xy 93.175312 -219.523477) (xy 93.173296 -219.538804) (xy 93.170082 -219.565653) (xy 93.156037 -219.617867)
			(xy 93.133676 -219.667096) (xy 93.103596 -219.712027) (xy 93.0666 -219.751459) (xy 93.023676 -219.784339)
			(xy 92.97597 -219.809789) (xy 92.924756 -219.827129) (xy 92.871401 -219.835898) (xy 92.844366 -219.836492)
			(xy 92.818399 -219.83598) (xy 92.767106 -219.827852) (xy 92.717716 -219.811801) (xy 92.671444 -219.788222)
			(xy 92.62943 -219.757696) (xy 92.592707 -219.720974) (xy 92.56218 -219.67896) (xy 92.538601 -219.632688)
			(xy 92.522549 -219.583298) (xy 92.51442 -219.532005) (xy 92.513912 -219.506038) (xy 92.514409 -219.479947)
			(xy 92.522619 -219.428415) (xy 92.538825 -219.378813) (xy 92.562625 -219.332374) (xy 92.593427 -219.290252)
			(xy 92.630465 -219.253494) (xy 92.651326 -219.237814) (xy 92.66357 -219.228355) (xy 92.682155 -219.203636)
			(xy 92.692507 -219.174494) (xy 92.693682 -219.143591) (xy 92.685572 -219.113747) (xy 92.677742 -219.1004)
			(xy 92.6592 -219.070174) (xy 92.502736 -218.799156) (xy 92.48338 -218.764644) (xy 92.451188 -218.692355)
			(xy 92.438474 -218.654884) (xy 92.416198 -218.629451) (xy 92.375754 -218.575266) (xy 92.357702 -218.54668)
			(xy 92.352108 -218.538518) (xy 92.336124 -218.526886) (xy 92.316927 -218.522163) (xy 92.29737 -218.52505)
			(xy 92.288614 -218.529662) (xy 92.262925 -218.544423) (xy 92.209651 -218.57036) (xy 92.182188 -218.581478)
			(xy 92.185998 -218.609005) (xy 92.190063 -218.664433) (xy 92.190316 -218.692222) (xy 92.189904 -218.728133)
			(xy 92.183116 -218.799632) (xy 92.169573 -218.870165) (xy 92.149399 -218.939094) (xy 92.122775 -219.005798)
			(xy 92.089942 -219.069675) (xy 92.070936 -219.100146) (xy 92.063056 -219.113453) (xy 92.054918 -219.143276)
			(xy 92.056055 -219.174167) (xy 92.066363 -219.203311) (xy 92.084901 -219.228048) (xy 92.097098 -219.23756)
			(xy 92.118057 -219.253184) (xy 92.155225 -219.28994) (xy 92.186135 -219.332095) (xy 92.210014 -219.378595)
			(xy 92.226266 -219.428278) (xy 92.234483 -219.479901) (xy 92.23502 -219.506038) (xy 92.234512 -219.532294)
			(xy 92.226206 -219.584146) (xy 92.209807 -219.634033) (xy 92.185728 -219.6807) (xy 92.154575 -219.722974)
			(xy 92.136214 -219.74175) (xy 92.129953 -219.748377) (xy 92.122195 -219.764858) (xy 92.120721 -219.783015)
			(xy 92.125718 -219.800533) (xy 92.13088 -219.808044) (xy 92.15861 -219.846867) (xy 92.206338 -219.92948)
			(xy 92.22613 -219.97289) (xy 92.230138 -219.981028) (xy 92.242791 -219.99401) (xy 92.25917 -220.001777)
			(xy 92.277229 -220.003358) (xy 92.286074 -220.001338) (xy 92.307676 -219.995736) (xy 92.351898 -219.98974)
			(xy 92.374212 -219.9894) (xy 92.40018 -219.98991) (xy 92.451476 -219.998036) (xy 92.50087 -220.014085)
			(xy 92.547146 -220.037662) (xy 92.589164 -220.068188) (xy 92.62589 -220.10491) (xy 92.65642 -220.146925)
			(xy 92.680002 -220.193198) (xy 92.696056 -220.242591) (xy 92.704187 -220.293886) (xy 92.704666 -220.319854)
			(xy 92.704194 -220.345303) (xy 92.704114 -220.345821) (xy 92.984321 -220.345821) (xy 92.984321 -220.293887)
			(xy 92.992446 -220.242592) (xy 93.008494 -220.193199) (xy 93.032072 -220.146925) (xy 93.062598 -220.104909)
			(xy 93.099321 -220.068186) (xy 93.141337 -220.03766) (xy 93.187611 -220.014082) (xy 93.237004 -219.998034)
			(xy 93.288299 -219.989909) (xy 93.340233 -219.989909) (xy 93.391528 -219.998034) (xy 93.440921 -220.014082)
			(xy 93.487195 -220.03766) (xy 93.529211 -220.068186) (xy 93.565934 -220.104909) (xy 93.59646 -220.146925)
			(xy 93.620038 -220.193199) (xy 93.636086 -220.242592) (xy 93.644211 -220.293887) (xy 93.64472 -220.319854)
			(xy 93.644211 -220.345821) (xy 93.636086 -220.397116) (xy 93.620038 -220.446509) (xy 93.59646 -220.492783)
			(xy 93.565934 -220.534799) (xy 93.529211 -220.571522) (xy 93.487195 -220.602048) (xy 93.440921 -220.625626)
			(xy 93.391528 -220.641674) (xy 93.340233 -220.649799) (xy 93.288299 -220.649799) (xy 93.237004 -220.641674)
			(xy 93.187611 -220.625626) (xy 93.141337 -220.602048) (xy 93.099321 -220.571522) (xy 93.062598 -220.534799)
			(xy 93.032072 -220.492783) (xy 93.008494 -220.446509) (xy 92.992446 -220.397116) (xy 92.984321 -220.345821)
			(xy 92.704114 -220.345821) (xy 92.696386 -220.395598) (xy 92.680964 -220.444102) (xy 92.658292 -220.489671)
			(xy 92.628905 -220.531228) (xy 92.593497 -220.56779) (xy 92.552905 -220.598496) (xy 92.508087 -220.622618)
			(xy 92.460102 -220.639589) (xy 92.435172 -220.64472) (xy 92.412312 -220.649038) (xy 92.208604 -221.002098)
			(xy 92.216224 -221.024196) (xy 92.224488 -221.049135) (xy 92.233937 -221.100815) (xy 92.23502 -221.127066)
			(xy 92.235835 -221.141755) (xy 92.244829 -221.169753) (xy 92.261416 -221.194035) (xy 92.284227 -221.212594)
			(xy 92.311376 -221.223895) (xy 92.325952 -221.225872) (xy 92.34311 -221.227791) (xy 92.377281 -221.232747)
			(xy 92.394278 -221.235778) (xy 92.409023 -221.23791) (xy 92.438607 -221.234518) (xy 92.465956 -221.222738)
			(xy 92.488746 -221.203573) (xy 92.505042 -221.17865) (xy 92.513459 -221.150086) (xy 92.513912 -221.135194)
			(xy 92.513912 -221.133924) (xy 92.514421 -221.107957) (xy 92.522546 -221.056662) (xy 92.538594 -221.007269)
			(xy 92.562172 -220.960995) (xy 92.592698 -220.918979) (xy 92.629421 -220.882256) (xy 92.671437 -220.85173)
			(xy 92.717711 -220.828152) (xy 92.767104 -220.812104) (xy 92.818399 -220.803979) (xy 92.870333 -220.803979)
			(xy 92.921628 -220.812104) (xy 92.971021 -220.828152) (xy 93.017295 -220.85173) (xy 93.059311 -220.882256)
			(xy 93.096034 -220.918979) (xy 93.12656 -220.960995) (xy 93.150138 -221.007269) (xy 93.166186 -221.056662)
			(xy 93.174311 -221.107957) (xy 93.17482 -221.133924) (xy 93.453712 -221.133924) (xy 93.454158 -221.108472)
			(xy 93.461946 -221.058168) (xy 93.477357 -221.009654) (xy 93.500027 -220.964077) (xy 93.529418 -220.922517)
			(xy 93.564836 -220.885956) (xy 93.605443 -220.855259) (xy 93.650276 -220.831154) (xy 93.698277 -220.81421)
			(xy 93.723206 -220.809058) (xy 93.746066 -220.80474) (xy 93.949774 -220.45168) (xy 93.942154 -220.429582)
			(xy 93.933414 -220.402995) (xy 93.923968 -220.347835) (xy 93.923358 -220.319854) (xy 93.923867 -220.293887)
			(xy 93.931992 -220.242592) (xy 93.94804 -220.193199) (xy 93.971618 -220.146925) (xy 94.002144 -220.104909)
			(xy 94.038867 -220.068186) (xy 94.080883 -220.03766) (xy 94.127157 -220.014082) (xy 94.17655 -219.998034)
			(xy 94.227845 -219.989909) (xy 94.279779 -219.989909) (xy 94.331074 -219.998034) (xy 94.380467 -220.014082)
			(xy 94.426741 -220.03766) (xy 94.468757 -220.068186) (xy 94.50548 -220.104909) (xy 94.536006 -220.146925)
			(xy 94.559584 -220.193199) (xy 94.575632 -220.242592) (xy 94.583757 -220.293887) (xy 94.584266 -220.319854)
			(xy 94.583818 -220.345306) (xy 94.583738 -220.345821) (xy 94.863921 -220.345821) (xy 94.863921 -220.293887)
			(xy 94.872046 -220.242592) (xy 94.888094 -220.193199) (xy 94.911672 -220.146925) (xy 94.942198 -220.104909)
			(xy 94.978921 -220.068186) (xy 95.020937 -220.03766) (xy 95.067211 -220.014082) (xy 95.116604 -219.998034)
			(xy 95.167899 -219.989909) (xy 95.219833 -219.989909) (xy 95.271128 -219.998034) (xy 95.320521 -220.014082)
			(xy 95.366795 -220.03766) (xy 95.408811 -220.068186) (xy 95.445534 -220.104909) (xy 95.47606 -220.146925)
			(xy 95.499638 -220.193199) (xy 95.515686 -220.242592) (xy 95.523811 -220.293887) (xy 95.52432 -220.319854)
			(xy 95.523811 -220.345821) (xy 95.515686 -220.397116) (xy 95.499638 -220.446509) (xy 95.47606 -220.492783)
			(xy 95.445534 -220.534799) (xy 95.408811 -220.571522) (xy 95.366795 -220.602048) (xy 95.320521 -220.625626)
			(xy 95.271128 -220.641674) (xy 95.219833 -220.649799) (xy 95.167899 -220.649799) (xy 95.116604 -220.641674)
			(xy 95.067211 -220.625626) (xy 95.020937 -220.602048) (xy 94.978921 -220.571522) (xy 94.942198 -220.534799)
			(xy 94.911672 -220.492783) (xy 94.888094 -220.446509) (xy 94.872046 -220.397116) (xy 94.863921 -220.345821)
			(xy 94.583738 -220.345821) (xy 94.576033 -220.395611) (xy 94.560623 -220.444126) (xy 94.537955 -220.489704)
			(xy 94.508563 -220.531265) (xy 94.473145 -220.567826) (xy 94.432538 -220.598523) (xy 94.387703 -220.622627)
			(xy 94.339702 -220.639569) (xy 94.314772 -220.64472) (xy 94.291912 -220.649038) (xy 94.088204 -221.002098)
			(xy 94.095824 -221.024196) (xy 94.104561 -221.050784) (xy 94.114009 -221.105943) (xy 94.11462 -221.133924)
			(xy 94.114111 -221.159891) (xy 94.105986 -221.211186) (xy 94.089938 -221.260579) (xy 94.06636 -221.306853)
			(xy 94.035834 -221.348869) (xy 93.999111 -221.385592) (xy 93.957095 -221.416118) (xy 93.910821 -221.439696)
			(xy 93.861428 -221.455744) (xy 93.810133 -221.463869) (xy 93.758199 -221.463869) (xy 93.706904 -221.455744)
			(xy 93.657511 -221.439696) (xy 93.611237 -221.416118) (xy 93.569221 -221.385592) (xy 93.532498 -221.348869)
			(xy 93.501972 -221.306853) (xy 93.478394 -221.260579) (xy 93.462346 -221.211186) (xy 93.454221 -221.159891)
			(xy 93.453712 -221.133924) (xy 93.17482 -221.133924) (xy 93.174205 -221.161904) (xy 93.16475 -221.21706)
			(xy 93.156024 -221.243652) (xy 93.148404 -221.26575) (xy 93.352112 -221.618556) (xy 93.374972 -221.622874)
			(xy 93.401147 -221.628327) (xy 93.451411 -221.646549) (xy 93.498087 -221.672624) (xy 93.539958 -221.705871)
			(xy 93.575931 -221.745423) (xy 93.60507 -221.79025) (xy 93.626614 -221.839182) (xy 93.633798 -221.864936)
			(xy 93.636491 -221.87362) (xy 93.646978 -221.888457) (xy 93.661967 -221.898725) (xy 93.679591 -221.903144)
			(xy 93.688662 -221.902528) (xy 93.731964 -221.898252) (xy 93.818978 -221.897372) (xy 93.905639 -221.905248)
			(xy 93.991069 -221.921801) (xy 94.0744 -221.946864) (xy 94.154787 -221.980181) (xy 94.19336 -222.000318)
			(xy 94.203012 -222.005652) (xy 94.216474 -222.013526) (xy 94.22513 -222.018088) (xy 94.244034 -222.023108)
			(xy 94.253812 -222.023432) (xy 94.263738 -222.023132) (xy 94.282909 -222.017973) (xy 94.291658 -222.013272)
			(xy 94.325774 -221.994076) (xy 94.39683 -221.961213) (xy 94.470565 -221.934906) (xy 94.546375 -221.91537)
			(xy 94.623641 -221.902766) (xy 94.70173 -221.897195) (xy 94.780003 -221.898704) (xy 94.818962 -221.902528)
			(xy 94.828058 -221.903148) (xy 94.845722 -221.898683) (xy 94.860716 -221.888333) (xy 94.871155 -221.8734)
			(xy 94.873826 -221.864682) (xy 94.881954 -221.838012) (xy 94.889574 -221.815914) (xy 94.685866 -221.463108)
			(xy 94.663006 -221.45879) (xy 94.638079 -221.453638) (xy 94.590082 -221.436693) (xy 94.545252 -221.412586)
			(xy 94.504651 -221.381889) (xy 94.469238 -221.345327) (xy 94.439852 -221.303766) (xy 94.417189 -221.258189)
			(xy 94.401785 -221.209676) (xy 94.394005 -221.159374) (xy 94.393512 -221.133924) (xy 94.394021 -221.107957)
			(xy 94.402146 -221.056662) (xy 94.418194 -221.007269) (xy 94.441772 -220.960995) (xy 94.472298 -220.918979)
			(xy 94.509021 -220.882256) (xy 94.551037 -220.85173) (xy 94.597311 -220.828152) (xy 94.646704 -220.812104)
			(xy 94.697999 -220.803979) (xy 94.749933 -220.803979) (xy 94.801228 -220.812104) (xy 94.850621 -220.828152)
			(xy 94.896895 -220.85173) (xy 94.938911 -220.882256) (xy 94.975634 -220.918979) (xy 95.00616 -220.960995)
			(xy 95.029738 -221.007269) (xy 95.045786 -221.056662) (xy 95.053911 -221.107957) (xy 95.05442 -221.133924)
			(xy 95.333312 -221.133924) (xy 95.333758 -221.108472) (xy 95.341546 -221.058168) (xy 95.356957 -221.009654)
			(xy 95.379627 -220.964077) (xy 95.409018 -220.922517) (xy 95.444436 -220.885956) (xy 95.485043 -220.855259)
			(xy 95.529876 -220.831154) (xy 95.577877 -220.81421) (xy 95.602806 -220.809058) (xy 95.625666 -220.80474)
			(xy 95.829374 -220.45168) (xy 95.821754 -220.429582) (xy 95.813014 -220.402995) (xy 95.803568 -220.347835)
			(xy 95.802958 -220.319854) (xy 95.803467 -220.293887) (xy 95.811592 -220.242592) (xy 95.82764 -220.193199)
			(xy 95.851218 -220.146925) (xy 95.881744 -220.104909) (xy 95.918467 -220.068186) (xy 95.960483 -220.03766)
			(xy 96.006757 -220.014082) (xy 96.05615 -219.998034) (xy 96.107445 -219.989909) (xy 96.159379 -219.989909)
			(xy 96.210674 -219.998034) (xy 96.260067 -220.014082) (xy 96.306341 -220.03766) (xy 96.348357 -220.068186)
			(xy 96.38508 -220.104909) (xy 96.415606 -220.146925) (xy 96.439184 -220.193199) (xy 96.455232 -220.242592)
			(xy 96.463357 -220.293887) (xy 96.463866 -220.319854) (xy 96.463418 -220.345306) (xy 96.463338 -220.345821)
			(xy 96.743521 -220.345821) (xy 96.743521 -220.293887) (xy 96.751646 -220.242592) (xy 96.767694 -220.193199)
			(xy 96.791272 -220.146925) (xy 96.821798 -220.104909) (xy 96.858521 -220.068186) (xy 96.900537 -220.03766)
			(xy 96.946811 -220.014082) (xy 96.996204 -219.998034) (xy 97.047499 -219.989909) (xy 97.099433 -219.989909)
			(xy 97.150728 -219.998034) (xy 97.200121 -220.014082) (xy 97.246395 -220.03766) (xy 97.288411 -220.068186)
			(xy 97.325134 -220.104909) (xy 97.35566 -220.146925) (xy 97.379238 -220.193199) (xy 97.395286 -220.242592)
			(xy 97.403411 -220.293887) (xy 97.40392 -220.319854) (xy 97.403411 -220.345821) (xy 97.395286 -220.397116)
			(xy 97.379238 -220.446509) (xy 97.35566 -220.492783) (xy 97.325134 -220.534799) (xy 97.288411 -220.571522)
			(xy 97.246395 -220.602048) (xy 97.200121 -220.625626) (xy 97.150728 -220.641674) (xy 97.099433 -220.649799)
			(xy 97.047499 -220.649799) (xy 96.996204 -220.641674) (xy 96.946811 -220.625626) (xy 96.900537 -220.602048)
			(xy 96.858521 -220.571522) (xy 96.821798 -220.534799) (xy 96.791272 -220.492783) (xy 96.767694 -220.446509)
			(xy 96.751646 -220.397116) (xy 96.743521 -220.345821) (xy 96.463338 -220.345821) (xy 96.455633 -220.395611)
			(xy 96.440223 -220.444126) (xy 96.417555 -220.489704) (xy 96.388163 -220.531265) (xy 96.352745 -220.567826)
			(xy 96.312138 -220.598523) (xy 96.267303 -220.622627) (xy 96.219302 -220.639569) (xy 96.194372 -220.64472)
			(xy 96.171512 -220.649038) (xy 95.967804 -221.002098) (xy 95.975424 -221.024196) (xy 95.984161 -221.050784)
			(xy 95.993609 -221.105943) (xy 95.99422 -221.133924) (xy 95.993711 -221.159891) (xy 95.985586 -221.211186)
			(xy 95.969538 -221.260579) (xy 95.94596 -221.306853) (xy 95.915434 -221.348869) (xy 95.878711 -221.385592)
			(xy 95.836695 -221.416118) (xy 95.790421 -221.439696) (xy 95.741028 -221.455744) (xy 95.689733 -221.463869)
			(xy 95.637799 -221.463869) (xy 95.586504 -221.455744) (xy 95.537111 -221.439696) (xy 95.490837 -221.416118)
			(xy 95.448821 -221.385592) (xy 95.412098 -221.348869) (xy 95.381572 -221.306853) (xy 95.357994 -221.260579)
			(xy 95.341946 -221.211186) (xy 95.333821 -221.159891) (xy 95.333312 -221.133924) (xy 95.05442 -221.133924)
			(xy 95.053805 -221.161904) (xy 95.04435 -221.21706) (xy 95.035624 -221.243652) (xy 95.028004 -221.26575)
			(xy 95.231712 -221.618556) (xy 95.254572 -221.622874) (xy 95.280747 -221.628327) (xy 95.331011 -221.646549)
			(xy 95.377687 -221.672624) (xy 95.419558 -221.705871) (xy 95.455531 -221.745423) (xy 95.48467 -221.79025)
			(xy 95.506214 -221.839182) (xy 95.513398 -221.864936) (xy 95.516091 -221.87362) (xy 95.526578 -221.888457)
			(xy 95.541567 -221.898725) (xy 95.559191 -221.903144) (xy 95.568262 -221.902528) (xy 95.611564 -221.898252)
			(xy 95.698578 -221.897372) (xy 95.785239 -221.905248) (xy 95.870669 -221.921801) (xy 95.954 -221.946864)
			(xy 96.034387 -221.980181) (xy 96.07296 -222.000318) (xy 96.082612 -222.005652) (xy 96.096074 -222.013526)
			(xy 96.10473 -222.018088) (xy 96.123634 -222.023108) (xy 96.133412 -222.023432) (xy 96.143338 -222.023132)
			(xy 96.162509 -222.017973) (xy 96.171258 -222.013272) (xy 96.205375 -221.994081) (xy 96.276433 -221.961233)
			(xy 96.350171 -221.93495) (xy 96.425985 -221.915446) (xy 96.503253 -221.902881) (xy 96.581341 -221.89736)
			(xy 96.659608 -221.898926) (xy 96.698562 -221.902782) (xy 96.707656 -221.903401) (xy 96.725315 -221.898935)
			(xy 96.740302 -221.888582) (xy 96.750729 -221.873646) (xy 96.753426 -221.864936) (xy 96.761554 -221.838012)
			(xy 96.769174 -221.815914) (xy 96.565466 -221.463108) (xy 96.542606 -221.45879) (xy 96.517679 -221.453638)
			(xy 96.469682 -221.436693) (xy 96.424852 -221.412586) (xy 96.384251 -221.381889) (xy 96.348838 -221.345327)
			(xy 96.319452 -221.303766) (xy 96.296789 -221.258189) (xy 96.281385 -221.209676) (xy 96.273605 -221.159374)
			(xy 96.273112 -221.133924) (xy 96.273621 -221.107957) (xy 96.281746 -221.056662) (xy 96.297794 -221.007269)
			(xy 96.321372 -220.960995) (xy 96.351898 -220.918979) (xy 96.388621 -220.882256) (xy 96.430637 -220.85173)
			(xy 96.476911 -220.828152) (xy 96.526304 -220.812104) (xy 96.577599 -220.803979) (xy 96.629533 -220.803979)
			(xy 96.680828 -220.812104) (xy 96.730221 -220.828152) (xy 96.776495 -220.85173) (xy 96.818511 -220.882256)
			(xy 96.855234 -220.918979) (xy 96.88576 -220.960995) (xy 96.909338 -221.007269) (xy 96.925386 -221.056662)
			(xy 96.933511 -221.107957) (xy 96.93402 -221.133924) (xy 97.212912 -221.133924) (xy 97.213358 -221.108472)
			(xy 97.221146 -221.058168) (xy 97.236557 -221.009654) (xy 97.259227 -220.964077) (xy 97.288618 -220.922517)
			(xy 97.324036 -220.885956) (xy 97.364643 -220.855259) (xy 97.409476 -220.831154) (xy 97.457477 -220.81421)
			(xy 97.482406 -220.809058) (xy 97.505266 -220.80474) (xy 97.708974 -220.45168) (xy 97.701354 -220.429582)
			(xy 97.692614 -220.402995) (xy 97.683168 -220.347835) (xy 97.682558 -220.319854) (xy 97.683067 -220.293887)
			(xy 97.691192 -220.242592) (xy 97.70724 -220.193199) (xy 97.730818 -220.146925) (xy 97.761344 -220.104909)
			(xy 97.798067 -220.068186) (xy 97.840083 -220.03766) (xy 97.886357 -220.014082) (xy 97.93575 -219.998034)
			(xy 97.987045 -219.989909) (xy 98.038979 -219.989909) (xy 98.090274 -219.998034) (xy 98.139667 -220.014082)
			(xy 98.185941 -220.03766) (xy 98.227957 -220.068186) (xy 98.26468 -220.104909) (xy 98.295206 -220.146925)
			(xy 98.318784 -220.193199) (xy 98.334832 -220.242592) (xy 98.342957 -220.293887) (xy 98.343466 -220.319854)
			(xy 98.343018 -220.345306) (xy 98.342938 -220.345821) (xy 98.623121 -220.345821) (xy 98.623121 -220.293887)
			(xy 98.631246 -220.242592) (xy 98.647294 -220.193199) (xy 98.670872 -220.146925) (xy 98.701398 -220.104909)
			(xy 98.738121 -220.068186) (xy 98.780137 -220.03766) (xy 98.826411 -220.014082) (xy 98.875804 -219.998034)
			(xy 98.927099 -219.989909) (xy 98.979033 -219.989909) (xy 99.030328 -219.998034) (xy 99.079721 -220.014082)
			(xy 99.125995 -220.03766) (xy 99.168011 -220.068186) (xy 99.204734 -220.104909) (xy 99.23526 -220.146925)
			(xy 99.258838 -220.193199) (xy 99.274886 -220.242592) (xy 99.283011 -220.293887) (xy 99.28352 -220.319854)
			(xy 99.283011 -220.345821) (xy 99.274886 -220.397116) (xy 99.258838 -220.446509) (xy 99.23526 -220.492783)
			(xy 99.204734 -220.534799) (xy 99.168011 -220.571522) (xy 99.125995 -220.602048) (xy 99.079721 -220.625626)
			(xy 99.030328 -220.641674) (xy 98.979033 -220.649799) (xy 98.927099 -220.649799) (xy 98.875804 -220.641674)
			(xy 98.826411 -220.625626) (xy 98.780137 -220.602048) (xy 98.738121 -220.571522) (xy 98.701398 -220.534799)
			(xy 98.670872 -220.492783) (xy 98.647294 -220.446509) (xy 98.631246 -220.397116) (xy 98.623121 -220.345821)
			(xy 98.342938 -220.345821) (xy 98.335233 -220.395611) (xy 98.319823 -220.444126) (xy 98.297155 -220.489704)
			(xy 98.267763 -220.531265) (xy 98.232345 -220.567826) (xy 98.191738 -220.598523) (xy 98.146903 -220.622627)
			(xy 98.098902 -220.639569) (xy 98.073972 -220.64472) (xy 98.051112 -220.649038) (xy 97.847404 -221.002098)
			(xy 97.855024 -221.024196) (xy 97.863761 -221.050784) (xy 97.873209 -221.105943) (xy 97.87382 -221.133924)
			(xy 98.152712 -221.133924) (xy 98.153221 -221.107957) (xy 98.161346 -221.056662) (xy 98.177394 -221.007269)
			(xy 98.200972 -220.960995) (xy 98.231498 -220.918979) (xy 98.268221 -220.882256) (xy 98.310237 -220.85173)
			(xy 98.356511 -220.828152) (xy 98.405904 -220.812104) (xy 98.457199 -220.803979) (xy 98.509133 -220.803979)
			(xy 98.560428 -220.812104) (xy 98.609821 -220.828152) (xy 98.656095 -220.85173) (xy 98.698111 -220.882256)
			(xy 98.734834 -220.918979) (xy 98.76536 -220.960995) (xy 98.788938 -221.007269) (xy 98.804986 -221.056662)
			(xy 98.813111 -221.107957) (xy 98.81362 -221.133924) (xy 99.092512 -221.133924) (xy 99.092958 -221.108472)
			(xy 99.100746 -221.058168) (xy 99.116157 -221.009654) (xy 99.138827 -220.964077) (xy 99.168218 -220.922517)
			(xy 99.203636 -220.885956) (xy 99.244243 -220.855259) (xy 99.289076 -220.831154) (xy 99.337077 -220.81421)
			(xy 99.362006 -220.809058) (xy 99.384866 -220.80474) (xy 99.588574 -220.45168) (xy 99.580954 -220.429582)
			(xy 99.572214 -220.402995) (xy 99.562768 -220.347835) (xy 99.562158 -220.319854) (xy 99.562667 -220.293887)
			(xy 99.570792 -220.242592) (xy 99.58684 -220.193199) (xy 99.610418 -220.146925) (xy 99.640944 -220.104909)
			(xy 99.677667 -220.068186) (xy 99.719683 -220.03766) (xy 99.765957 -220.014082) (xy 99.81535 -219.998034)
			(xy 99.866645 -219.989909) (xy 99.918579 -219.989909) (xy 99.969874 -219.998034) (xy 100.019267 -220.014082)
			(xy 100.065541 -220.03766) (xy 100.107557 -220.068186) (xy 100.14428 -220.104909) (xy 100.174806 -220.146925)
			(xy 100.198384 -220.193199) (xy 100.214432 -220.242592) (xy 100.222557 -220.293887) (xy 100.223066 -220.319854)
			(xy 100.222618 -220.345306) (xy 100.214833 -220.395611) (xy 100.199423 -220.444126) (xy 100.176755 -220.489704)
			(xy 100.147363 -220.531265) (xy 100.111945 -220.567826) (xy 100.071338 -220.598523) (xy 100.026503 -220.622627)
			(xy 99.978502 -220.639569) (xy 99.953572 -220.64472) (xy 99.930712 -220.649038) (xy 99.727004 -221.002098)
			(xy 99.734624 -221.024196) (xy 99.743361 -221.050784) (xy 99.752809 -221.105943) (xy 99.75342 -221.133924)
			(xy 99.752911 -221.159891) (xy 99.744786 -221.211186) (xy 99.728738 -221.260579) (xy 99.70516 -221.306853)
			(xy 99.674634 -221.348869) (xy 99.637911 -221.385592) (xy 99.595895 -221.416118) (xy 99.549621 -221.439696)
			(xy 99.500228 -221.455744) (xy 99.448933 -221.463869) (xy 99.396999 -221.463869) (xy 99.345704 -221.455744)
			(xy 99.296311 -221.439696) (xy 99.250037 -221.416118) (xy 99.208021 -221.385592) (xy 99.171298 -221.348869)
			(xy 99.140772 -221.306853) (xy 99.117194 -221.260579) (xy 99.101146 -221.211186) (xy 99.093021 -221.159891)
			(xy 99.092512 -221.133924) (xy 98.81362 -221.133924) (xy 98.813072 -221.16191) (xy 98.803619 -221.217078)
			(xy 98.794824 -221.243652) (xy 98.787204 -221.26575) (xy 98.990912 -221.618556) (xy 99.013772 -221.622874)
			(xy 99.0387 -221.628011) (xy 99.086685 -221.644981) (xy 99.131503 -221.669103) (xy 99.172095 -221.699808)
			(xy 99.207503 -221.736369) (xy 99.23689 -221.777925) (xy 99.259563 -221.823493) (xy 99.274985 -221.871997)
			(xy 99.282793 -221.922292) (xy 99.283266 -221.94774) (xy 99.282757 -221.973707) (xy 99.274632 -222.025002)
			(xy 99.258584 -222.074395) (xy 99.235006 -222.120669) (xy 99.20448 -222.162685) (xy 99.167757 -222.199408)
			(xy 99.125741 -222.229934) (xy 99.079467 -222.253512) (xy 99.030074 -222.26956) (xy 98.978779 -222.277685)
			(xy 98.926845 -222.277685) (xy 98.87555 -222.26956) (xy 98.826157 -222.253512) (xy 98.779883 -222.229934)
			(xy 98.737867 -222.199408) (xy 98.701144 -222.162685) (xy 98.670618 -222.120669) (xy 98.64704 -222.074395)
			(xy 98.630992 -222.025002) (xy 98.622867 -221.973707) (xy 98.622358 -221.94774) (xy 98.622918 -221.919754)
			(xy 98.632363 -221.864587) (xy 98.641154 -221.838012) (xy 98.648774 -221.815914) (xy 98.445066 -221.463108)
			(xy 98.422206 -221.45879) (xy 98.397282 -221.45363) (xy 98.349295 -221.436669) (xy 98.304474 -221.412553)
			(xy 98.263879 -221.381853) (xy 98.228468 -221.345294) (xy 98.19908 -221.303739) (xy 98.176407 -221.258171)
			(xy 98.160987 -221.209667) (xy 98.153182 -221.159372) (xy 98.152712 -221.133924) (xy 97.87382 -221.133924)
			(xy 97.873311 -221.159891) (xy 97.865186 -221.211186) (xy 97.849138 -221.260579) (xy 97.82556 -221.306853)
			(xy 97.795034 -221.348869) (xy 97.758311 -221.385592) (xy 97.716295 -221.416118) (xy 97.670021 -221.439696)
			(xy 97.620628 -221.455744) (xy 97.569333 -221.463869) (xy 97.517399 -221.463869) (xy 97.466104 -221.455744)
			(xy 97.416711 -221.439696) (xy 97.370437 -221.416118) (xy 97.328421 -221.385592) (xy 97.291698 -221.348869)
			(xy 97.261172 -221.306853) (xy 97.237594 -221.260579) (xy 97.221546 -221.211186) (xy 97.213421 -221.159891)
			(xy 97.212912 -221.133924) (xy 96.93402 -221.133924) (xy 96.933405 -221.161904) (xy 96.92395 -221.21706)
			(xy 96.915224 -221.243652) (xy 96.907604 -221.26575) (xy 97.111312 -221.618556) (xy 97.134172 -221.622874)
			(xy 97.159102 -221.628025) (xy 97.207104 -221.644967) (xy 97.251939 -221.669071) (xy 97.292547 -221.699767)
			(xy 97.327966 -221.736328) (xy 97.357358 -221.77789) (xy 97.380027 -221.823467) (xy 97.395437 -221.871983)
			(xy 97.403224 -221.922288) (xy 97.403666 -221.94774) (xy 97.403158 -221.973997) (xy 97.394852 -222.025849)
			(xy 97.378455 -222.075737) (xy 97.354378 -222.122406) (xy 97.323229 -222.164683) (xy 97.30486 -222.183452)
			(xy 97.298605 -222.190081) (xy 97.290856 -222.206562) (xy 97.289384 -222.224715) (xy 97.294376 -222.242229)
			(xy 97.299526 -222.249746) (xy 97.327285 -222.28855) (xy 97.375019 -222.371164) (xy 97.394776 -222.414592)
			(xy 97.398768 -222.42279) (xy 97.411458 -222.435865) (xy 97.427935 -222.443642) (xy 97.446095 -222.445126)
			(xy 97.454974 -222.44304) (xy 97.476638 -222.437425) (xy 97.520989 -222.43143) (xy 97.543366 -222.431102)
			(xy 97.570587 -222.431663) (xy 97.62429 -222.440598) (xy 97.675802 -222.458217) (xy 97.723728 -222.484042)
			(xy 97.766773 -222.517375) (xy 97.80377 -222.557313) (xy 97.83372 -222.602776) (xy 97.855812 -222.652534)
			(xy 97.863152 -222.678752) (xy 97.865815 -222.687459) (xy 97.876279 -222.702343) (xy 97.891284 -222.712632)
			(xy 97.908938 -222.71703) (xy 97.918016 -222.716344) (xy 98.108516 -222.716344) (xy 98.117605 -222.717043)
			(xy 98.135296 -222.712699) (xy 98.150327 -222.702408) (xy 98.160776 -222.687487) (xy 98.16338 -222.678752)
			(xy 98.170719 -222.65253) (xy 98.192787 -222.602755) (xy 98.222724 -222.557277) (xy 98.259719 -222.517327)
			(xy 98.302768 -222.483991) (xy 98.350704 -222.458172) (xy 98.402228 -222.440569) (xy 98.455942 -222.431661)
			(xy 98.483166 -222.431102) (xy 98.5104 -222.431654) (xy 98.564132 -222.440577) (xy 98.615674 -222.458186)
			(xy 98.663633 -222.484006) (xy 98.706711 -222.517338) (xy 98.743743 -222.557281) (xy 98.773727 -222.602753)
			(xy 98.795851 -222.652525) (xy 98.803206 -222.678752) (xy 98.805829 -222.687457) (xy 98.816209 -222.702367)
			(xy 98.831141 -222.712716) (xy 98.848745 -222.717204)
		)
		(stroke
			(width 0)
			(type solid)
		)
		(fill yes)
		(layer "In4.Cu")
		(net "PVCCFA_EHV_FIVRA_CPU1")
	)
	(gr_poly
		(pts
			(xy 254.940308 -58.39206) (xy 254.953008 -58.363866) (xy 254.964714 -58.339177) (xy 254.994142 -58.293141)
			(xy 255.029837 -58.251773) (xy 255.071067 -58.21592) (xy 255.11699 -58.186315) (xy 255.166667 -58.163565)
			(xy 255.219081 -58.148133) (xy 255.273161 -58.140336) (xy 255.30048 -58.139838) (xy 255.325412 -58.14024)
			(xy 255.374854 -58.146727) (xy 255.42303 -58.159592) (xy 255.469123 -58.178617) (xy 255.512348 -58.203478)
			(xy 255.532382 -58.218324) (xy 255.54343 -58.226214) (xy 255.568577 -58.236415) (xy 255.595523 -58.239642)
			(xy 255.622369 -58.235667) (xy 255.647223 -58.224769) (xy 255.668335 -58.207718) (xy 255.676654 -58.196988)
			(xy 255.692068 -58.17627) (xy 255.727586 -58.138785) (xy 255.76784 -58.106439) (xy 255.812092 -58.079824)
			(xy 255.859532 -58.059426) (xy 255.909292 -58.045621) (xy 255.96046 -58.03866) (xy 255.98628 -58.038238)
			(xy 256.015303 -58.038786) (xy 256.072679 -58.047588) (xy 256.128061 -58.064977) (xy 256.18017 -58.090552)
			(xy 256.227806 -58.123722) (xy 256.26987 -58.163724) (xy 256.305391 -58.209634) (xy 256.333551 -58.260393)
			(xy 256.344166 -58.287412) (xy 256.35712 -58.322464) (xy 256.59461 -58.31078) (xy 256.60223 -58.271664)
			(xy 256.607636 -58.245865) (xy 256.624607 -58.19596) (xy 256.648286 -58.148867) (xy 256.678223 -58.105482)
			(xy 256.713848 -58.066631) (xy 256.754482 -58.033054) (xy 256.799352 -58.005392) (xy 256.847602 -57.984169)
			(xy 256.898315 -57.969792) (xy 256.950524 -57.962532) (xy 256.97688 -57.962038) (xy 257.004085 -57.96252)
			(xy 257.057942 -57.970252) (xy 257.110152 -57.985562) (xy 257.159656 -58.00814) (xy 257.205448 -58.037525)
			(xy 257.246596 -58.073122) (xy 257.282267 -58.114207) (xy 257.311734 -58.159946) (xy 257.334399 -58.20941)
			(xy 257.34264 -58.235342) (xy 257.35407 -58.273442) (xy 260.370066 -58.12536) (xy 261.24408 -57.251346)
			(xy 261.24408 -42.443146) (xy 260.78688 -41.985946) (xy 254.661162 -41.985946) (xy 254.661162 -42.037)
			(xy 254.661162 -42.03954) (xy 254.660676 -42.066791) (xy 254.65292 -42.120739) (xy 254.637565 -42.173034)
			(xy 254.614923 -42.222611) (xy 254.585457 -42.268461) (xy 254.549766 -42.309652) (xy 254.508575 -42.345343)
			(xy 254.462725 -42.374809) (xy 254.413148 -42.397451) (xy 254.360853 -42.412806) (xy 254.306905 -42.420562)
			(xy 254.252403 -42.420562) (xy 254.198455 -42.412806) (xy 254.14616 -42.397451) (xy 254.096583 -42.374809)
			(xy 254.050733 -42.345343) (xy 254.009542 -42.309652) (xy 253.973851 -42.268461) (xy 253.944385 -42.222611)
			(xy 253.921743 -42.173034) (xy 253.906388 -42.120739) (xy 253.898632 -42.066791) (xy 253.898146 -42.03954)
			(xy 253.898146 -42.037) (xy 253.898146 -41.985946) (xy 252.62332 -41.985946) (xy 251.78766 -42.821606)
			(xy 251.78766 -43.714162) (xy 251.805012 -43.736814) (xy 251.833507 -43.786248) (xy 251.852639 -43.835066)
			(xy 252.707392 -43.835066) (xy 252.711463 -43.779444) (xy 252.723589 -43.725007) (xy 252.743512 -43.672916)
			(xy 252.770808 -43.624281) (xy 252.804894 -43.580138) (xy 252.845043 -43.541429) (xy 252.890401 -43.508978)
			(xy 252.940001 -43.483477) (xy 252.992785 -43.46547) (xy 253.047628 -43.45534) (xy 253.103362 -43.453303)
			(xy 253.158799 -43.459403) (xy 253.212756 -43.473509) (xy 253.264085 -43.495321) (xy 253.311691 -43.524375)
			(xy 253.354559 -43.56005) (xy 253.391776 -43.601587) (xy 253.422549 -43.6481) (xy 253.446221 -43.698597)
			(xy 253.462289 -43.752004) (xy 253.470409 -43.80718) (xy 253.470918 -43.835066) (xy 253.470409 -43.862952)
			(xy 253.462289 -43.918128) (xy 253.446221 -43.971535) (xy 253.422549 -44.022032) (xy 253.391776 -44.068545)
			(xy 253.354559 -44.110082) (xy 253.311691 -44.145757) (xy 253.264085 -44.174811) (xy 253.212756 -44.196623)
			(xy 253.158799 -44.210729) (xy 253.103362 -44.216829) (xy 253.047628 -44.214792) (xy 252.992785 -44.204662)
			(xy 252.940001 -44.186655) (xy 252.890401 -44.161154) (xy 252.845043 -44.128703) (xy 252.804894 -44.089994)
			(xy 252.770808 -44.045851) (xy 252.743512 -43.997216) (xy 252.723589 -43.945125) (xy 252.711463 -43.890688)
			(xy 252.707392 -43.835066) (xy 251.852639 -43.835066) (xy 251.854327 -43.839373) (xy 251.867006 -43.895005)
			(xy 251.871264 -43.951905) (xy 251.867005 -44.008804) (xy 251.854324 -44.064436) (xy 251.833503 -44.11756)
			(xy 251.805007 -44.166994) (xy 251.78766 -44.18965) (xy 251.78766 -44.398946) (xy 254.359662 -44.398946)
			(xy 254.363733 -44.343324) (xy 254.375859 -44.288887) (xy 254.395782 -44.236796) (xy 254.423078 -44.188161)
			(xy 254.457164 -44.144018) (xy 254.497313 -44.105309) (xy 254.542671 -44.072858) (xy 254.592271 -44.047357)
			(xy 254.645055 -44.02935) (xy 254.699898 -44.01922) (xy 254.755632 -44.017183) (xy 254.811069 -44.023283)
			(xy 254.865026 -44.037389) (xy 254.916355 -44.059201) (xy 254.963961 -44.088255) (xy 255.006829 -44.12393)
			(xy 255.044046 -44.165467) (xy 255.074819 -44.21198) (xy 255.098491 -44.262477) (xy 255.114559 -44.315884)
			(xy 255.122679 -44.37106) (xy 255.123188 -44.398946) (xy 255.122679 -44.426832) (xy 255.114559 -44.482008)
			(xy 255.098491 -44.535415) (xy 255.074819 -44.585912) (xy 255.044046 -44.632425) (xy 255.024045 -44.654748)
			(xy 257.251224 -44.654748) (xy 257.251224 -44.600252) (xy 257.25898 -44.546311) (xy 257.274333 -44.494023)
			(xy 257.296971 -44.444451) (xy 257.326434 -44.398606) (xy 257.362121 -44.357421) (xy 257.403306 -44.321734)
			(xy 257.449151 -44.292271) (xy 257.498723 -44.269633) (xy 257.551011 -44.25428) (xy 257.604952 -44.246524)
			(xy 257.6322 -44.246038) (xy 257.659775 -44.24649) (xy 257.714349 -44.254444) (xy 257.76721 -44.270171)
			(xy 257.817256 -44.293343) (xy 257.863445 -44.323479) (xy 257.904815 -44.359949) (xy 257.92303 -44.380658)
			(xy 257.932928 -44.391556) (xy 257.957578 -44.407631) (xy 257.985786 -44.416015) (xy 258.015214 -44.416015)
			(xy 258.043422 -44.407631) (xy 258.068072 -44.391556) (xy 258.07797 -44.380658) (xy 258.096184 -44.35995)
			(xy 258.137553 -44.323481) (xy 258.183743 -44.29335) (xy 258.23379 -44.270184) (xy 258.286652 -44.254466)
			(xy 258.341226 -44.246525) (xy 258.3688 -44.246038) (xy 258.395097 -44.246493) (xy 258.447194 -44.253711)
			(xy 258.497804 -44.268023) (xy 258.545965 -44.289158) (xy 258.590763 -44.316715) (xy 258.631346 -44.350169)
			(xy 258.64947 -44.369228) (xy 258.658799 -44.378871) (xy 258.681467 -44.393214) (xy 258.70709 -44.401152)
			(xy 258.733897 -44.402136) (xy 258.760033 -44.396096) (xy 258.783691 -44.383452) (xy 258.793742 -44.374562)
			(xy 258.815073 -44.355295) (xy 258.862433 -44.322728) (xy 258.914144 -44.297634) (xy 258.969034 -44.280582)
			(xy 259.025861 -44.271959) (xy 259.0546 -44.271438) (xy 259.082175 -44.27189) (xy 259.136749 -44.279844)
			(xy 259.18961 -44.295571) (xy 259.239656 -44.318743) (xy 259.285845 -44.348879) (xy 259.327215 -44.385349)
			(xy 259.34543 -44.406058) (xy 259.355328 -44.416956) (xy 259.379978 -44.433031) (xy 259.408186 -44.441415)
			(xy 259.437614 -44.441415) (xy 259.465822 -44.433031) (xy 259.490472 -44.416956) (xy 259.50037 -44.406058)
			(xy 259.518584 -44.38535) (xy 259.559953 -44.348881) (xy 259.606143 -44.31875) (xy 259.65619 -44.295584)
			(xy 259.709052 -44.279866) (xy 259.763626 -44.271925) (xy 259.7912 -44.271438) (xy 259.818455 -44.271832)
			(xy 259.872409 -44.279589) (xy 259.92471 -44.294946) (xy 259.974293 -44.31759) (xy 260.020149 -44.34706)
			(xy 260.061344 -44.382756) (xy 260.09704 -44.423951) (xy 260.12651 -44.469807) (xy 260.149154 -44.51939)
			(xy 260.164511 -44.571691) (xy 260.172268 -44.625645) (xy 260.172268 -44.680155) (xy 260.164511 -44.734109)
			(xy 260.149154 -44.78641) (xy 260.12651 -44.835993) (xy 260.09704 -44.881849) (xy 260.061344 -44.923044)
			(xy 260.020149 -44.95874) (xy 259.974293 -44.98821) (xy 259.92471 -45.010854) (xy 259.872409 -45.026211)
			(xy 259.818455 -45.033968) (xy 259.7912 -45.034454) (xy 259.763625 -45.034004) (xy 259.70905 -45.026051)
			(xy 259.65619 -45.010324) (xy 259.606143 -44.987151) (xy 259.559954 -44.957015) (xy 259.518585 -44.920543)
			(xy 259.50037 -44.899834) (xy 259.490472 -44.888936) (xy 259.465822 -44.872861) (xy 259.437614 -44.864477)
			(xy 259.408186 -44.864477) (xy 259.379978 -44.872861) (xy 259.355328 -44.888936) (xy 259.34543 -44.899834)
			(xy 259.327214 -44.920541) (xy 259.285846 -44.95701) (xy 259.239656 -44.987142) (xy 259.189609 -45.010308)
			(xy 259.136748 -45.026026) (xy 259.082174 -45.033967) (xy 259.0546 -45.034454) (xy 259.028303 -45.034002)
			(xy 258.976205 -45.026784) (xy 258.925596 -45.012471) (xy 258.877435 -44.991335) (xy 258.832637 -44.963778)
			(xy 258.792054 -44.930324) (xy 258.77393 -44.911264) (xy 258.764602 -44.901618) (xy 258.741937 -44.887261)
			(xy 258.716312 -44.879316) (xy 258.689501 -44.878332) (xy 258.663362 -44.884377) (xy 258.639706 -44.897033)
			(xy 258.629658 -44.90593) (xy 258.608326 -44.925195) (xy 258.560966 -44.957764) (xy 258.509256 -44.982858)
			(xy 258.454366 -44.999909) (xy 258.397539 -45.008533) (xy 258.3688 -45.009054) (xy 258.341225 -45.008604)
			(xy 258.28665 -45.000651) (xy 258.23379 -44.984924) (xy 258.183743 -44.961751) (xy 258.137554 -44.931615)
			(xy 258.096185 -44.895143) (xy 258.07797 -44.874434) (xy 258.068072 -44.863536) (xy 258.043422 -44.847461)
			(xy 258.015214 -44.839077) (xy 257.985786 -44.839077) (xy 257.957578 -44.847461) (xy 257.932928 -44.863536)
			(xy 257.92303 -44.874434) (xy 257.904814 -44.895141) (xy 257.863446 -44.93161) (xy 257.817256 -44.961742)
			(xy 257.767209 -44.984908) (xy 257.714348 -45.000626) (xy 257.659774 -45.008567) (xy 257.6322 -45.009054)
			(xy 257.604952 -45.008476) (xy 257.551011 -45.00072) (xy 257.498723 -44.985367) (xy 257.449151 -44.962729)
			(xy 257.403306 -44.933266) (xy 257.362121 -44.897579) (xy 257.326434 -44.856394) (xy 257.296971 -44.810549)
			(xy 257.274333 -44.760977) (xy 257.25898 -44.708689) (xy 257.251224 -44.654748) (xy 255.024045 -44.654748)
			(xy 255.006829 -44.673962) (xy 254.963961 -44.709637) (xy 254.916355 -44.738691) (xy 254.865026 -44.760503)
			(xy 254.811069 -44.774609) (xy 254.755632 -44.780709) (xy 254.699898 -44.778672) (xy 254.645055 -44.768542)
			(xy 254.592271 -44.750535) (xy 254.542671 -44.725034) (xy 254.497313 -44.692583) (xy 254.457164 -44.653874)
			(xy 254.423078 -44.609731) (xy 254.395782 -44.561096) (xy 254.375859 -44.509005) (xy 254.363733 -44.454568)
			(xy 254.359662 -44.398946) (xy 251.78766 -44.398946) (xy 251.78766 -46.265846) (xy 252.36678 -46.844966)
			(xy 252.36678 -47.065946) (xy 253.419862 -47.065946) (xy 253.423933 -47.010324) (xy 253.436059 -46.955887)
			(xy 253.455982 -46.903796) (xy 253.483278 -46.855161) (xy 253.517364 -46.811018) (xy 253.557513 -46.772309)
			(xy 253.602871 -46.739858) (xy 253.652471 -46.714357) (xy 253.705255 -46.69635) (xy 253.760098 -46.68622)
			(xy 253.815832 -46.684183) (xy 253.871269 -46.690283) (xy 253.925226 -46.704389) (xy 253.976555 -46.726201)
			(xy 254.024161 -46.755255) (xy 254.067029 -46.79093) (xy 254.104246 -46.832467) (xy 254.135019 -46.87898)
			(xy 254.158691 -46.929477) (xy 254.174759 -46.982884) (xy 254.182879 -47.03806) (xy 254.183388 -47.065946)
			(xy 254.308862 -47.065946) (xy 254.312933 -47.010324) (xy 254.325059 -46.955887) (xy 254.344982 -46.903796)
			(xy 254.372278 -46.855161) (xy 254.406364 -46.811018) (xy 254.446513 -46.772309) (xy 254.491871 -46.739858)
			(xy 254.541471 -46.714357) (xy 254.594255 -46.69635) (xy 254.649098 -46.68622) (xy 254.704832 -46.684183)
			(xy 254.760269 -46.690283) (xy 254.814226 -46.704389) (xy 254.865555 -46.726201) (xy 254.913161 -46.755255)
			(xy 254.956029 -46.79093) (xy 254.993246 -46.832467) (xy 255.024019 -46.87898) (xy 255.047691 -46.929477)
			(xy 255.063759 -46.982884) (xy 255.071879 -47.03806) (xy 255.072388 -47.065946) (xy 255.197862 -47.065946)
			(xy 255.201933 -47.010324) (xy 255.214059 -46.955887) (xy 255.233982 -46.903796) (xy 255.261278 -46.855161)
			(xy 255.295364 -46.811018) (xy 255.335513 -46.772309) (xy 255.380871 -46.739858) (xy 255.430471 -46.714357)
			(xy 255.483255 -46.69635) (xy 255.538098 -46.68622) (xy 255.593832 -46.684183) (xy 255.649269 -46.690283)
			(xy 255.703226 -46.704389) (xy 255.754555 -46.726201) (xy 255.802161 -46.755255) (xy 255.845029 -46.79093)
			(xy 255.882246 -46.832467) (xy 255.913019 -46.87898) (xy 255.936691 -46.929477) (xy 255.952759 -46.982884)
			(xy 255.960879 -47.03806) (xy 255.961388 -47.065946) (xy 255.960891 -47.093148) (xy 256.667024 -47.093148)
			(xy 256.667024 -47.038652) (xy 256.67478 -46.984711) (xy 256.690133 -46.932423) (xy 256.712771 -46.882851)
			(xy 256.742234 -46.837006) (xy 256.777921 -46.795821) (xy 256.819106 -46.760134) (xy 256.864951 -46.730671)
			(xy 256.914523 -46.708033) (xy 256.966811 -46.69268) (xy 257.020752 -46.684924) (xy 257.048 -46.684438)
			(xy 257.075575 -46.68489) (xy 257.130149 -46.692844) (xy 257.18301 -46.708571) (xy 257.233056 -46.731743)
			(xy 257.279245 -46.761879) (xy 257.320615 -46.798349) (xy 257.33883 -46.819058) (xy 257.348728 -46.829956)
			(xy 257.373378 -46.846031) (xy 257.401586 -46.854415) (xy 257.431014 -46.854415) (xy 257.459222 -46.846031)
			(xy 257.483872 -46.829956) (xy 257.49377 -46.819058) (xy 257.511985 -46.798352) (xy 257.553356 -46.761887)
			(xy 257.599546 -46.73176) (xy 257.649593 -46.708597) (xy 257.702454 -46.692881) (xy 257.757026 -46.684941)
			(xy 257.812174 -46.684941) (xy 257.866746 -46.692881) (xy 257.919607 -46.708597) (xy 257.969654 -46.73176)
			(xy 258.015844 -46.761887) (xy 258.057215 -46.798352) (xy 258.07543 -46.819058) (xy 258.085328 -46.829956)
			(xy 258.109978 -46.846031) (xy 258.138186 -46.854415) (xy 258.167614 -46.854415) (xy 258.195822 -46.846031)
			(xy 258.220472 -46.829956) (xy 258.23037 -46.819058) (xy 258.248584 -46.79835) (xy 258.289953 -46.761881)
			(xy 258.336143 -46.73175) (xy 258.38619 -46.708584) (xy 258.439052 -46.692866) (xy 258.493626 -46.684925)
			(xy 258.5212 -46.684438) (xy 258.548455 -46.684832) (xy 258.602409 -46.692589) (xy 258.65471 -46.707946)
			(xy 258.704293 -46.73059) (xy 258.750149 -46.76006) (xy 258.791344 -46.795756) (xy 258.82704 -46.836951)
			(xy 258.85651 -46.882807) (xy 258.879154 -46.93239) (xy 258.894511 -46.984691) (xy 258.902268 -47.038645)
			(xy 258.902268 -47.093155) (xy 258.894511 -47.147109) (xy 258.879154 -47.19941) (xy 258.85651 -47.248993)
			(xy 258.82704 -47.294849) (xy 258.791344 -47.336044) (xy 258.750149 -47.37174) (xy 258.704293 -47.40121)
			(xy 258.65471 -47.423854) (xy 258.602409 -47.439211) (xy 258.548455 -47.446968) (xy 258.5212 -47.447454)
			(xy 258.493625 -47.447004) (xy 258.43905 -47.439051) (xy 258.38619 -47.423324) (xy 258.336143 -47.400151)
			(xy 258.289954 -47.370015) (xy 258.248585 -47.333543) (xy 258.23037 -47.312834) (xy 258.220472 -47.301936)
			(xy 258.195822 -47.285861) (xy 258.167614 -47.277477) (xy 258.138186 -47.277477) (xy 258.109978 -47.285861)
			(xy 258.085328 -47.301936) (xy 258.07543 -47.312834) (xy 258.057215 -47.33354) (xy 258.015844 -47.370005)
			(xy 257.969654 -47.400132) (xy 257.919607 -47.423295) (xy 257.866746 -47.439011) (xy 257.812174 -47.446951)
			(xy 257.757026 -47.446951) (xy 257.702454 -47.439011) (xy 257.649593 -47.423295) (xy 257.599546 -47.400132)
			(xy 257.553356 -47.370005) (xy 257.511985 -47.33354) (xy 257.49377 -47.312834) (xy 257.483872 -47.301936)
			(xy 257.459222 -47.285861) (xy 257.431014 -47.277477) (xy 257.401586 -47.277477) (xy 257.373378 -47.285861)
			(xy 257.348728 -47.301936) (xy 257.33883 -47.312834) (xy 257.320614 -47.333541) (xy 257.279246 -47.37001)
			(xy 257.233056 -47.400142) (xy 257.183009 -47.423308) (xy 257.130148 -47.439026) (xy 257.075574 -47.446967)
			(xy 257.048 -47.447454) (xy 257.020752 -47.446876) (xy 256.966811 -47.43912) (xy 256.914523 -47.423767)
			(xy 256.864951 -47.401129) (xy 256.819106 -47.371666) (xy 256.777921 -47.335979) (xy 256.742234 -47.294794)
			(xy 256.712771 -47.248949) (xy 256.690133 -47.199377) (xy 256.67478 -47.147089) (xy 256.667024 -47.093148)
			(xy 255.960891 -47.093148) (xy 255.960879 -47.093832) (xy 255.952759 -47.149008) (xy 255.936691 -47.202415)
			(xy 255.913019 -47.252912) (xy 255.882246 -47.299425) (xy 255.845029 -47.340962) (xy 255.802161 -47.376637)
			(xy 255.754555 -47.405691) (xy 255.703226 -47.427503) (xy 255.649269 -47.441609) (xy 255.593832 -47.447709)
			(xy 255.538098 -47.445672) (xy 255.483255 -47.435542) (xy 255.430471 -47.417535) (xy 255.380871 -47.392034)
			(xy 255.335513 -47.359583) (xy 255.295364 -47.320874) (xy 255.261278 -47.276731) (xy 255.233982 -47.228096)
			(xy 255.214059 -47.176005) (xy 255.201933 -47.121568) (xy 255.197862 -47.065946) (xy 255.072388 -47.065946)
			(xy 255.071879 -47.093832) (xy 255.063759 -47.149008) (xy 255.047691 -47.202415) (xy 255.024019 -47.252912)
			(xy 254.993246 -47.299425) (xy 254.956029 -47.340962) (xy 254.913161 -47.376637) (xy 254.865555 -47.405691)
			(xy 254.814226 -47.427503) (xy 254.760269 -47.441609) (xy 254.704832 -47.447709) (xy 254.649098 -47.445672)
			(xy 254.594255 -47.435542) (xy 254.541471 -47.417535) (xy 254.491871 -47.392034) (xy 254.446513 -47.359583)
			(xy 254.406364 -47.320874) (xy 254.372278 -47.276731) (xy 254.344982 -47.228096) (xy 254.325059 -47.176005)
			(xy 254.312933 -47.121568) (xy 254.308862 -47.065946) (xy 254.183388 -47.065946) (xy 254.182879 -47.093832)
			(xy 254.174759 -47.149008) (xy 254.158691 -47.202415) (xy 254.135019 -47.252912) (xy 254.104246 -47.299425)
			(xy 254.067029 -47.340962) (xy 254.024161 -47.376637) (xy 253.976555 -47.405691) (xy 253.925226 -47.427503)
			(xy 253.871269 -47.441609) (xy 253.815832 -47.447709) (xy 253.760098 -47.445672) (xy 253.705255 -47.435542)
			(xy 253.652471 -47.417535) (xy 253.602871 -47.392034) (xy 253.557513 -47.359583) (xy 253.517364 -47.320874)
			(xy 253.483278 -47.276731) (xy 253.455982 -47.228096) (xy 253.436059 -47.176005) (xy 253.423933 -47.121568)
			(xy 253.419862 -47.065946) (xy 252.36678 -47.065946) (xy 252.36678 -48.386746) (xy 258.861812 -48.386746)
			(xy 258.865883 -48.331124) (xy 258.878009 -48.276687) (xy 258.897932 -48.224596) (xy 258.925228 -48.175961)
			(xy 258.959314 -48.131818) (xy 258.999463 -48.093109) (xy 259.044821 -48.060658) (xy 259.094421 -48.035157)
			(xy 259.147205 -48.01715) (xy 259.202048 -48.00702) (xy 259.257782 -48.004983) (xy 259.313219 -48.011083)
			(xy 259.367176 -48.025189) (xy 259.418505 -48.047001) (xy 259.466111 -48.076055) (xy 259.508979 -48.11173)
			(xy 259.546196 -48.153267) (xy 259.576969 -48.19978) (xy 259.600641 -48.250277) (xy 259.616709 -48.303684)
			(xy 259.624829 -48.35886) (xy 259.625338 -48.386746) (xy 259.624829 -48.414632) (xy 259.616709 -48.469808)
			(xy 259.600641 -48.523215) (xy 259.576969 -48.573712) (xy 259.546196 -48.620225) (xy 259.508979 -48.661762)
			(xy 259.466111 -48.697437) (xy 259.418505 -48.726491) (xy 259.367176 -48.748303) (xy 259.313219 -48.762409)
			(xy 259.257782 -48.768509) (xy 259.202048 -48.766472) (xy 259.147205 -48.756342) (xy 259.094421 -48.738335)
			(xy 259.044821 -48.712834) (xy 258.999463 -48.680383) (xy 258.959314 -48.641674) (xy 258.925228 -48.597531)
			(xy 258.897932 -48.548896) (xy 258.878009 -48.496805) (xy 258.865883 -48.442368) (xy 258.861812 -48.386746)
			(xy 252.36678 -48.386746) (xy 252.36678 -48.8165) (xy 253.187506 -48.8165) (xy 253.191489 -48.763355)
			(xy 253.203347 -48.711398) (xy 253.222817 -48.661788) (xy 253.249462 -48.615633) (xy 253.282689 -48.573965)
			(xy 253.321754 -48.537715) (xy 253.365786 -48.507691) (xy 253.4138 -48.484565) (xy 253.464725 -48.468853)
			(xy 253.517423 -48.460906) (xy 253.54407 -48.460406) (xy 253.57139 -48.460944) (xy 253.625391 -48.469278)
			(xy 253.677487 -48.485754) (xy 253.726459 -48.509989) (xy 253.771159 -48.541412) (xy 253.791212 -48.559974)
			(xy 253.802834 -48.570371) (xy 253.830768 -48.584195) (xy 253.86157 -48.588951) (xy 253.892372 -48.584195)
			(xy 253.920306 -48.570371) (xy 253.931928 -48.559974) (xy 253.951933 -48.541352) (xy 253.996629 -48.509898)
			(xy 254.04561 -48.485651) (xy 254.097723 -48.469181) (xy 254.151742 -48.460877) (xy 254.17907 -48.460406)
			(xy 254.205724 -48.460849) (xy 254.258436 -48.46879) (xy 254.309376 -48.484499) (xy 254.357406 -48.507625)
			(xy 254.401452 -48.537652) (xy 254.44053 -48.573909) (xy 254.473768 -48.615585) (xy 254.500423 -48.661749)
			(xy 254.5199 -48.711371) (xy 254.531762 -48.763342) (xy 254.535746 -48.8165) (xy 254.531762 -48.869658)
			(xy 254.5199 -48.921629) (xy 254.500423 -48.971251) (xy 254.473768 -49.017415) (xy 254.44053 -49.059091)
			(xy 254.401452 -49.095348) (xy 254.357406 -49.125375) (xy 254.309376 -49.148501) (xy 254.258436 -49.16421)
			(xy 254.205724 -49.172151) (xy 254.17907 -49.172622) (xy 254.151749 -49.172113) (xy 254.097747 -49.163771)
			(xy 254.045651 -49.147287) (xy 253.996679 -49.123047) (xy 253.95198 -49.091618) (xy 253.931928 -49.073054)
			(xy 253.920306 -49.062657) (xy 253.892372 -49.048833) (xy 253.86157 -49.044077) (xy 253.830768 -49.048833)
			(xy 253.802834 -49.062657) (xy 253.791212 -49.073054) (xy 253.771179 -49.091645) (xy 253.726492 -49.123106)
			(xy 253.677519 -49.14736) (xy 253.625411 -49.163837) (xy 253.571396 -49.172148) (xy 253.54407 -49.172622)
			(xy 253.517423 -49.172094) (xy 253.464725 -49.164147) (xy 253.4138 -49.148435) (xy 253.365786 -49.125309)
			(xy 253.321754 -49.095285) (xy 253.282689 -49.059035) (xy 253.249462 -49.017367) (xy 253.222817 -48.971212)
			(xy 253.203347 -48.921602) (xy 253.191489 -48.869645) (xy 253.187506 -48.8165) (xy 252.36678 -48.8165)
			(xy 252.36678 -49.7167) (xy 253.187482 -49.7167) (xy 253.191465 -49.663552) (xy 253.203324 -49.611591)
			(xy 253.222795 -49.561977) (xy 253.249442 -49.51582) (xy 253.282671 -49.474149) (xy 253.321739 -49.437896)
			(xy 253.365774 -49.40787) (xy 253.413792 -49.384742) (xy 253.46472 -49.369029) (xy 253.517421 -49.361082)
			(xy 253.54407 -49.360582) (xy 253.57139 -49.361126) (xy 253.62539 -49.36946) (xy 253.677486 -49.385935)
			(xy 253.726458 -49.410168) (xy 253.771159 -49.441589) (xy 253.791212 -49.46015) (xy 253.802834 -49.470547)
			(xy 253.830768 -49.484371) (xy 253.86157 -49.489127) (xy 253.892372 -49.484371) (xy 253.920306 -49.470547)
			(xy 253.931928 -49.46015) (xy 253.951945 -49.441541) (xy 253.996636 -49.410082) (xy 254.045613 -49.385831)
			(xy 254.097725 -49.369359) (xy 254.151743 -49.361053) (xy 254.17907 -49.360582) (xy 254.205722 -49.361073)
			(xy 254.258431 -49.369014) (xy 254.309367 -49.384722) (xy 254.357394 -49.407846) (xy 254.401437 -49.437871)
			(xy 254.440513 -49.474125) (xy 254.473748 -49.515798) (xy 254.500402 -49.56196) (xy 254.519877 -49.611578)
			(xy 254.531738 -49.663545) (xy 254.535722 -49.7167) (xy 254.531738 -49.769855) (xy 254.519877 -49.821822)
			(xy 254.500402 -49.87144) (xy 254.473748 -49.917602) (xy 254.440513 -49.959275) (xy 254.401437 -49.995529)
			(xy 254.357394 -50.025554) (xy 254.309367 -50.048678) (xy 254.258431 -50.064386) (xy 254.205722 -50.072327)
			(xy 254.17907 -50.072798) (xy 254.151749 -50.072296) (xy 254.097746 -50.063953) (xy 254.045649 -50.047468)
			(xy 253.996678 -50.023226) (xy 253.95198 -49.991795) (xy 253.931928 -49.97323) (xy 253.920306 -49.962833)
			(xy 253.892372 -49.949009) (xy 253.86157 -49.944253) (xy 253.830768 -49.949009) (xy 253.802834 -49.962833)
			(xy 253.791212 -49.97323) (xy 253.771191 -49.991834) (xy 253.7265 -50.02329) (xy 253.677523 -50.047541)
			(xy 253.625413 -50.064015) (xy 253.571396 -50.072324) (xy 253.54407 -50.072798) (xy 253.517421 -50.072318)
			(xy 253.46472 -50.064371) (xy 253.413792 -50.048658) (xy 253.365774 -50.02553) (xy 253.321739 -49.995504)
			(xy 253.282671 -49.959251) (xy 253.249442 -49.91758) (xy 253.222795 -49.871423) (xy 253.203324 -49.821809)
			(xy 253.191465 -49.769848) (xy 253.187482 -49.7167) (xy 252.36678 -49.7167) (xy 252.36678 -50.6166)
			(xy 253.187504 -50.6166) (xy 253.191487 -50.563455) (xy 253.203345 -50.511497) (xy 253.222815 -50.461887)
			(xy 253.249461 -50.415732) (xy 253.282687 -50.374064) (xy 253.321753 -50.337813) (xy 253.365785 -50.307789)
			(xy 253.4138 -50.284663) (xy 253.464725 -50.268951) (xy 253.517423 -50.261004) (xy 253.54407 -50.260504)
			(xy 253.57139 -50.261042) (xy 253.625391 -50.269376) (xy 253.677487 -50.285853) (xy 253.726459 -50.310087)
			(xy 253.771159 -50.34151) (xy 253.791212 -50.360072) (xy 253.802834 -50.370469) (xy 253.830768 -50.384293)
			(xy 253.86157 -50.389049) (xy 253.892372 -50.384293) (xy 253.920306 -50.370469) (xy 253.931928 -50.360072)
			(xy 253.951933 -50.341449) (xy 253.996628 -50.309995) (xy 254.045609 -50.285748) (xy 254.097723 -50.269279)
			(xy 254.151742 -50.260975) (xy 254.17907 -50.260504) (xy 254.205724 -50.260951) (xy 254.258436 -50.268892)
			(xy 254.309375 -50.284601) (xy 254.357405 -50.307727) (xy 254.40145 -50.337754) (xy 254.43235 -50.366422)
			(xy 255.680462 -50.366422) (xy 255.684533 -50.3108) (xy 255.696659 -50.256363) (xy 255.716582 -50.204272)
			(xy 255.743878 -50.155637) (xy 255.777964 -50.111494) (xy 255.818113 -50.072785) (xy 255.863471 -50.040334)
			(xy 255.913071 -50.014833) (xy 255.965855 -49.996826) (xy 256.020698 -49.986696) (xy 256.076432 -49.984659)
			(xy 256.131869 -49.990759) (xy 256.185826 -50.004865) (xy 256.237155 -50.026677) (xy 256.284761 -50.055731)
			(xy 256.327629 -50.091406) (xy 256.364846 -50.132943) (xy 256.395619 -50.179456) (xy 256.419291 -50.229953)
			(xy 256.435359 -50.28336) (xy 256.443479 -50.338536) (xy 256.443988 -50.366422) (xy 256.443479 -50.394308)
			(xy 256.435359 -50.449484) (xy 256.419291 -50.502891) (xy 256.395619 -50.553388) (xy 256.364846 -50.599901)
			(xy 256.327629 -50.641438) (xy 256.284761 -50.677113) (xy 256.237155 -50.706167) (xy 256.185826 -50.727979)
			(xy 256.131869 -50.742085) (xy 256.076432 -50.748185) (xy 256.020698 -50.746148) (xy 255.965855 -50.736018)
			(xy 255.913071 -50.718011) (xy 255.863471 -50.69251) (xy 255.818113 -50.660059) (xy 255.777964 -50.62135)
			(xy 255.743878 -50.577207) (xy 255.716582 -50.528572) (xy 255.696659 -50.476481) (xy 255.684533 -50.422044)
			(xy 255.680462 -50.366422) (xy 254.43235 -50.366422) (xy 254.440529 -50.37401) (xy 254.473767 -50.415686)
			(xy 254.500421 -50.46185) (xy 254.519898 -50.511472) (xy 254.53176 -50.563442) (xy 254.535744 -50.6166)
			(xy 254.53176 -50.669758) (xy 254.519898 -50.721728) (xy 254.500421 -50.77135) (xy 254.473767 -50.817514)
			(xy 254.440529 -50.85919) (xy 254.40145 -50.895446) (xy 254.357405 -50.925473) (xy 254.309375 -50.948599)
			(xy 254.258436 -50.964308) (xy 254.205724 -50.972249) (xy 254.17907 -50.97272) (xy 254.151749 -50.972212)
			(xy 254.097747 -50.96387) (xy 254.045651 -50.947386) (xy 253.996679 -50.923145) (xy 253.95198 -50.891716)
			(xy 253.931928 -50.873152) (xy 253.920306 -50.862755) (xy 253.892372 -50.848931) (xy 253.86157 -50.844175)
			(xy 253.830768 -50.848931) (xy 253.802834 -50.862755) (xy 253.791212 -50.873152) (xy 253.771179 -50.891743)
			(xy 253.726492 -50.923204) (xy 253.677519 -50.947458) (xy 253.625411 -50.963935) (xy 253.571396 -50.972246)
			(xy 253.54407 -50.97272) (xy 253.517423 -50.972196) (xy 253.464725 -50.964249) (xy 253.4138 -50.948537)
			(xy 253.365785 -50.925411) (xy 253.321753 -50.895387) (xy 253.282687 -50.859136) (xy 253.249461 -50.817468)
			(xy 253.222815 -50.771313) (xy 253.203345 -50.721703) (xy 253.191487 -50.669745) (xy 253.187504 -50.6166)
			(xy 252.36678 -50.6166) (xy 252.36678 -51.5165) (xy 253.187527 -51.5165) (xy 253.191509 -51.463358)
			(xy 253.203367 -51.411404) (xy 253.222835 -51.361797) (xy 253.249479 -51.315645) (xy 253.282704 -51.273979)
			(xy 253.321767 -51.237731) (xy 253.365796 -51.207709) (xy 253.413808 -51.184584) (xy 253.46473 -51.168873)
			(xy 253.517425 -51.160926) (xy 253.54407 -51.160426) (xy 253.57139 -51.160958) (xy 253.625392 -51.169293)
			(xy 253.677488 -51.18577) (xy 253.72646 -51.210006) (xy 253.77116 -51.241431) (xy 253.791212 -51.259994)
			(xy 253.802834 -51.270391) (xy 253.830768 -51.284215) (xy 253.86157 -51.288971) (xy 253.892372 -51.284215)
			(xy 253.920306 -51.270391) (xy 253.931928 -51.259994) (xy 253.951936 -51.241375) (xy 253.99663 -51.20992)
			(xy 254.045611 -51.185672) (xy 254.097724 -51.169202) (xy 254.151743 -51.160897) (xy 254.17907 -51.160426)
			(xy 254.205725 -51.160829) (xy 254.258441 -51.168771) (xy 254.309383 -51.184481) (xy 254.357416 -51.207608)
			(xy 254.401464 -51.237637) (xy 254.440545 -51.273895) (xy 254.473785 -51.315573) (xy 254.494197 -51.350926)
			(xy 256.493262 -51.350926) (xy 256.497333 -51.295304) (xy 256.509459 -51.240867) (xy 256.529382 -51.188776)
			(xy 256.556678 -51.140141) (xy 256.590764 -51.095998) (xy 256.630913 -51.057289) (xy 256.676271 -51.024838)
			(xy 256.725871 -50.999337) (xy 256.778655 -50.98133) (xy 256.833498 -50.9712) (xy 256.889232 -50.969163)
			(xy 256.944669 -50.975263) (xy 256.998626 -50.989369) (xy 257.049955 -51.011181) (xy 257.097561 -51.040235)
			(xy 257.140429 -51.07591) (xy 257.177646 -51.117447) (xy 257.208419 -51.16396) (xy 257.232091 -51.214457)
			(xy 257.248159 -51.267864) (xy 257.256279 -51.32304) (xy 257.256788 -51.350926) (xy 257.256279 -51.378812)
			(xy 257.248159 -51.433988) (xy 257.232091 -51.487395) (xy 257.208419 -51.537892) (xy 257.177646 -51.584405)
			(xy 257.140429 -51.625942) (xy 257.097561 -51.661617) (xy 257.049955 -51.690671) (xy 256.998626 -51.712483)
			(xy 256.944669 -51.726589) (xy 256.889232 -51.732689) (xy 256.833498 -51.730652) (xy 256.778655 -51.720522)
			(xy 256.725871 -51.702515) (xy 256.676271 -51.677014) (xy 256.630913 -51.644563) (xy 256.590764 -51.605854)
			(xy 256.556678 -51.561711) (xy 256.529382 -51.513076) (xy 256.509459 -51.460985) (xy 256.497333 -51.406548)
			(xy 256.493262 -51.350926) (xy 254.494197 -51.350926) (xy 254.500441 -51.361741) (xy 254.519919 -51.411365)
			(xy 254.531782 -51.463339) (xy 254.535766 -51.5165) (xy 254.531782 -51.569661) (xy 254.519919 -51.621635)
			(xy 254.500441 -51.671259) (xy 254.473785 -51.717427) (xy 254.440545 -51.759105) (xy 254.401464 -51.795363)
			(xy 254.357416 -51.825392) (xy 254.309383 -51.848519) (xy 254.258441 -51.864229) (xy 254.205725 -51.872171)
			(xy 254.17907 -51.872642) (xy 254.151748 -51.872156) (xy 254.097744 -51.863811) (xy 254.045646 -51.847323)
			(xy 253.996675 -51.823077) (xy 253.951978 -51.791642) (xy 253.931928 -51.773074) (xy 253.920306 -51.762677)
			(xy 253.892372 -51.748853) (xy 253.86157 -51.744097) (xy 253.830768 -51.748853) (xy 253.802834 -51.762677)
			(xy 253.791212 -51.773074) (xy 253.771182 -51.791668) (xy 253.726494 -51.823128) (xy 253.67752 -51.847382)
			(xy 253.625411 -51.863857) (xy 253.571396 -51.872168) (xy 253.54407 -51.872642) (xy 253.517425 -51.872074)
			(xy 253.46473 -51.864127) (xy 253.413808 -51.848416) (xy 253.365796 -51.825291) (xy 253.321767 -51.795269)
			(xy 253.282704 -51.759021) (xy 253.249479 -51.717355) (xy 253.222835 -51.671203) (xy 253.203367 -51.621596)
			(xy 253.191509 -51.569642) (xy 253.187527 -51.5165) (xy 252.36678 -51.5165) (xy 252.36678 -51.764946)
			(xy 251.59462 -52.537106) (xy 243.65966 -52.537106) (xy 243.33708 -52.859686) (xy 243.33708 -52.939696)
			(xy 256.159252 -52.939696) (xy 256.163323 -52.884074) (xy 256.175449 -52.829637) (xy 256.195372 -52.777546)
			(xy 256.222668 -52.728911) (xy 256.256754 -52.684768) (xy 256.296903 -52.646059) (xy 256.342261 -52.613608)
			(xy 256.391861 -52.588107) (xy 256.444645 -52.5701) (xy 256.499488 -52.55997) (xy 256.555222 -52.557933)
			(xy 256.610659 -52.564033) (xy 256.664616 -52.578139) (xy 256.715945 -52.599951) (xy 256.763551 -52.629005)
			(xy 256.806419 -52.66468) (xy 256.843636 -52.706217) (xy 256.874409 -52.75273) (xy 256.898081 -52.803227)
			(xy 256.914149 -52.856634) (xy 256.922269 -52.91181) (xy 256.922778 -52.939696) (xy 256.922269 -52.967582)
			(xy 256.914149 -53.022758) (xy 256.898081 -53.076165) (xy 256.874409 -53.126662) (xy 256.843636 -53.173175)
			(xy 256.806419 -53.214712) (xy 256.763551 -53.250387) (xy 256.715945 -53.279441) (xy 256.664616 -53.301253)
			(xy 256.610659 -53.315359) (xy 256.555222 -53.321459) (xy 256.499488 -53.319422) (xy 256.444645 -53.309292)
			(xy 256.391861 -53.291285) (xy 256.342261 -53.265784) (xy 256.296903 -53.233333) (xy 256.256754 -53.194624)
			(xy 256.222668 -53.150481) (xy 256.195372 -53.101846) (xy 256.175449 -53.049755) (xy 256.163323 -52.995318)
			(xy 256.159252 -52.939696) (xy 243.33708 -52.939696) (xy 243.33708 -53.603906) (xy 253.772922 -53.603906)
			(xy 253.776993 -53.548284) (xy 253.789119 -53.493847) (xy 253.809042 -53.441756) (xy 253.836338 -53.393121)
			(xy 253.870424 -53.348978) (xy 253.910573 -53.310269) (xy 253.955931 -53.277818) (xy 254.005531 -53.252317)
			(xy 254.058315 -53.23431) (xy 254.113158 -53.22418) (xy 254.168892 -53.222143) (xy 254.224329 -53.228243)
			(xy 254.278286 -53.242349) (xy 254.329615 -53.264161) (xy 254.377221 -53.293215) (xy 254.420089 -53.32889)
			(xy 254.457306 -53.370427) (xy 254.488079 -53.41694) (xy 254.511751 -53.467437) (xy 254.527819 -53.520844)
			(xy 254.535939 -53.57602) (xy 254.536123 -53.586126) (xy 255.050542 -53.586126) (xy 255.054613 -53.530504)
			(xy 255.066739 -53.476067) (xy 255.086662 -53.423976) (xy 255.113958 -53.375341) (xy 255.148044 -53.331198)
			(xy 255.188193 -53.292489) (xy 255.233551 -53.260038) (xy 255.283151 -53.234537) (xy 255.335935 -53.21653)
			(xy 255.390778 -53.2064) (xy 255.446512 -53.204363) (xy 255.501949 -53.210463) (xy 255.555906 -53.224569)
			(xy 255.607235 -53.246381) (xy 255.654841 -53.275435) (xy 255.697709 -53.31111) (xy 255.734926 -53.352647)
			(xy 255.765699 -53.39916) (xy 255.789371 -53.449657) (xy 255.805439 -53.503064) (xy 255.813559 -53.55824)
			(xy 255.814068 -53.586126) (xy 255.813559 -53.614012) (xy 255.805439 -53.669188) (xy 255.789371 -53.722595)
			(xy 255.765699 -53.773092) (xy 255.734926 -53.819605) (xy 255.697709 -53.861142) (xy 255.654841 -53.896817)
			(xy 255.607235 -53.925871) (xy 255.555906 -53.947683) (xy 255.501949 -53.961789) (xy 255.446512 -53.967889)
			(xy 255.390778 -53.965852) (xy 255.335935 -53.955722) (xy 255.283151 -53.937715) (xy 255.233551 -53.912214)
			(xy 255.188193 -53.879763) (xy 255.148044 -53.841054) (xy 255.113958 -53.796911) (xy 255.086662 -53.748276)
			(xy 255.066739 -53.696185) (xy 255.054613 -53.641748) (xy 255.050542 -53.586126) (xy 254.536123 -53.586126)
			(xy 254.536448 -53.603906) (xy 254.535939 -53.631792) (xy 254.527819 -53.686968) (xy 254.511751 -53.740375)
			(xy 254.488079 -53.790872) (xy 254.457306 -53.837385) (xy 254.420089 -53.878922) (xy 254.377221 -53.914597)
			(xy 254.329615 -53.943651) (xy 254.278286 -53.965463) (xy 254.224329 -53.979569) (xy 254.168892 -53.985669)
			(xy 254.113158 -53.983632) (xy 254.058315 -53.973502) (xy 254.005531 -53.955495) (xy 253.955931 -53.929994)
			(xy 253.910573 -53.897543) (xy 253.870424 -53.858834) (xy 253.836338 -53.814691) (xy 253.809042 -53.766056)
			(xy 253.789119 -53.713965) (xy 253.776993 -53.659528) (xy 253.772922 -53.603906) (xy 243.33708 -53.603906)
			(xy 243.33708 -54.304946) (xy 243.413299 -54.381146) (xy 258.64769 -54.381146) (xy 258.651761 -54.325524)
			(xy 258.663887 -54.271087) (xy 258.68381 -54.218996) (xy 258.711106 -54.170361) (xy 258.745192 -54.126218)
			(xy 258.785341 -54.087509) (xy 258.830699 -54.055058) (xy 258.880299 -54.029557) (xy 258.933083 -54.01155)
			(xy 258.987926 -54.00142) (xy 259.04366 -53.999383) (xy 259.099097 -54.005483) (xy 259.153054 -54.019589)
			(xy 259.204383 -54.041401) (xy 259.251989 -54.070455) (xy 259.294857 -54.10613) (xy 259.332074 -54.147667)
			(xy 259.362847 -54.19418) (xy 259.386519 -54.244677) (xy 259.402587 -54.298084) (xy 259.410707 -54.35326)
			(xy 259.411216 -54.381146) (xy 259.410707 -54.409032) (xy 259.402587 -54.464208) (xy 259.386519 -54.517615)
			(xy 259.362847 -54.568112) (xy 259.332074 -54.614625) (xy 259.294857 -54.656162) (xy 259.251989 -54.691837)
			(xy 259.204383 -54.720891) (xy 259.153054 -54.742703) (xy 259.099097 -54.756809) (xy 259.04366 -54.762909)
			(xy 258.987926 -54.760872) (xy 258.933083 -54.750742) (xy 258.880299 -54.732735) (xy 258.830699 -54.707234)
			(xy 258.785341 -54.674783) (xy 258.745192 -54.636074) (xy 258.711106 -54.591931) (xy 258.68381 -54.543296)
			(xy 258.663887 -54.491205) (xy 258.651761 -54.436768) (xy 258.64769 -54.381146) (xy 243.413299 -54.381146)
			(xy 244.054554 -55.022242) (xy 248.993912 -55.022242) (xy 248.997983 -54.96662) (xy 249.010109 -54.912183)
			(xy 249.030032 -54.860092) (xy 249.057328 -54.811457) (xy 249.091414 -54.767314) (xy 249.131563 -54.728605)
			(xy 249.176921 -54.696154) (xy 249.226521 -54.670653) (xy 249.279305 -54.652646) (xy 249.334148 -54.642516)
			(xy 249.389882 -54.640479) (xy 249.445319 -54.646579) (xy 249.499276 -54.660685) (xy 249.550605 -54.682497)
			(xy 249.598211 -54.711551) (xy 249.641079 -54.747226) (xy 249.678296 -54.788763) (xy 249.709069 -54.835276)
			(xy 249.732741 -54.885773) (xy 249.748809 -54.93918) (xy 249.756929 -54.994356) (xy 249.757438 -55.022242)
			(xy 249.756929 -55.050128) (xy 249.753557 -55.073042) (xy 251.127512 -55.073042) (xy 251.131583 -55.01742)
			(xy 251.143709 -54.962983) (xy 251.163632 -54.910892) (xy 251.190928 -54.862257) (xy 251.225014 -54.818114)
			(xy 251.265163 -54.779405) (xy 251.310521 -54.746954) (xy 251.360121 -54.721453) (xy 251.412905 -54.703446)
			(xy 251.467748 -54.693316) (xy 251.523482 -54.691279) (xy 251.578919 -54.697379) (xy 251.632876 -54.711485)
			(xy 251.684205 -54.733297) (xy 251.731811 -54.762351) (xy 251.774679 -54.798026) (xy 251.811896 -54.839563)
			(xy 251.842669 -54.886076) (xy 251.866341 -54.936573) (xy 251.882409 -54.98998) (xy 251.890529 -55.045156)
			(xy 251.891038 -55.073042) (xy 251.890529 -55.100928) (xy 251.882409 -55.156104) (xy 251.866341 -55.209511)
			(xy 251.842669 -55.260008) (xy 251.811896 -55.306521) (xy 251.774679 -55.348058) (xy 251.731811 -55.383733)
			(xy 251.684205 -55.412787) (xy 251.632876 -55.434599) (xy 251.578919 -55.448705) (xy 251.523482 -55.454805)
			(xy 251.467748 -55.452768) (xy 251.412905 -55.442638) (xy 251.360121 -55.424631) (xy 251.310521 -55.39913)
			(xy 251.265163 -55.366679) (xy 251.225014 -55.32797) (xy 251.190928 -55.283827) (xy 251.163632 -55.235192)
			(xy 251.143709 -55.183101) (xy 251.131583 -55.128664) (xy 251.127512 -55.073042) (xy 249.753557 -55.073042)
			(xy 249.748809 -55.105304) (xy 249.732741 -55.158711) (xy 249.709069 -55.209208) (xy 249.678296 -55.255721)
			(xy 249.641079 -55.297258) (xy 249.598211 -55.332933) (xy 249.550605 -55.361987) (xy 249.499276 -55.383799)
			(xy 249.445319 -55.397905) (xy 249.389882 -55.404005) (xy 249.334148 -55.401968) (xy 249.279305 -55.391838)
			(xy 249.226521 -55.373831) (xy 249.176921 -55.34833) (xy 249.131563 -55.315879) (xy 249.091414 -55.27717)
			(xy 249.057328 -55.233027) (xy 249.030032 -55.184392) (xy 249.010109 -55.132301) (xy 248.997983 -55.077864)
			(xy 248.993912 -55.022242) (xy 244.054554 -55.022242) (xy 244.363748 -55.33136) (xy 244.489478 -55.33136)
			(xy 244.533159 -55.331852) (xy 244.62018 -55.339582) (xy 244.706179 -55.354955) (xy 244.790488 -55.377854)
			(xy 244.872449 -55.408098) (xy 244.912134 -55.426356) (xy 245.816582 -55.854092) (xy 253.921512 -55.854092)
			(xy 253.925583 -55.79847) (xy 253.937709 -55.744033) (xy 253.957632 -55.691942) (xy 253.984928 -55.643307)
			(xy 254.019014 -55.599164) (xy 254.059163 -55.560455) (xy 254.104521 -55.528004) (xy 254.154121 -55.502503)
			(xy 254.206905 -55.484496) (xy 254.261748 -55.474366) (xy 254.317482 -55.472329) (xy 254.372919 -55.478429)
			(xy 254.376794 -55.479442) (xy 258.534152 -55.479442) (xy 258.538223 -55.42382) (xy 258.550349 -55.369383)
			(xy 258.570272 -55.317292) (xy 258.597568 -55.268657) (xy 258.631654 -55.224514) (xy 258.671803 -55.185805)
			(xy 258.717161 -55.153354) (xy 258.766761 -55.127853) (xy 258.819545 -55.109846) (xy 258.874388 -55.099716)
			(xy 258.930122 -55.097679) (xy 258.985559 -55.103779) (xy 259.039516 -55.117885) (xy 259.090845 -55.139697)
			(xy 259.138451 -55.168751) (xy 259.181319 -55.204426) (xy 259.218536 -55.245963) (xy 259.249309 -55.292476)
			(xy 259.272981 -55.342973) (xy 259.289049 -55.39638) (xy 259.297169 -55.451556) (xy 259.297678 -55.479442)
			(xy 259.297169 -55.507328) (xy 259.289049 -55.562504) (xy 259.272981 -55.615911) (xy 259.249309 -55.666408)
			(xy 259.218536 -55.712921) (xy 259.181319 -55.754458) (xy 259.138451 -55.790133) (xy 259.090845 -55.819187)
			(xy 259.039516 -55.840999) (xy 258.985559 -55.855105) (xy 258.930122 -55.861205) (xy 258.874388 -55.859168)
			(xy 258.819545 -55.849038) (xy 258.766761 -55.831031) (xy 258.717161 -55.80553) (xy 258.671803 -55.773079)
			(xy 258.631654 -55.73437) (xy 258.597568 -55.690227) (xy 258.570272 -55.641592) (xy 258.550349 -55.589501)
			(xy 258.538223 -55.535064) (xy 258.534152 -55.479442) (xy 254.376794 -55.479442) (xy 254.426876 -55.492535)
			(xy 254.478205 -55.514347) (xy 254.525811 -55.543401) (xy 254.568679 -55.579076) (xy 254.605896 -55.620613)
			(xy 254.636669 -55.667126) (xy 254.660341 -55.717623) (xy 254.676409 -55.77103) (xy 254.684529 -55.826206)
			(xy 254.685038 -55.854092) (xy 254.684529 -55.881978) (xy 254.676409 -55.937154) (xy 254.660341 -55.990561)
			(xy 254.636669 -56.041058) (xy 254.605896 -56.087571) (xy 254.568679 -56.129108) (xy 254.525811 -56.164783)
			(xy 254.478205 -56.193837) (xy 254.426876 -56.215649) (xy 254.372919 -56.229755) (xy 254.317482 -56.235855)
			(xy 254.261748 -56.233818) (xy 254.206905 -56.223688) (xy 254.154121 -56.205681) (xy 254.104521 -56.18018)
			(xy 254.059163 -56.147729) (xy 254.019014 -56.10902) (xy 253.984928 -56.064877) (xy 253.957632 -56.016242)
			(xy 253.937709 -55.964151) (xy 253.925583 -55.909714) (xy 253.921512 -55.854092) (xy 245.816582 -55.854092)
			(xy 247.172716 -56.495442) (xy 258.534152 -56.495442) (xy 258.538223 -56.43982) (xy 258.550349 -56.385383)
			(xy 258.570272 -56.333292) (xy 258.597568 -56.284657) (xy 258.631654 -56.240514) (xy 258.671803 -56.201805)
			(xy 258.717161 -56.169354) (xy 258.766761 -56.143853) (xy 258.819545 -56.125846) (xy 258.874388 -56.115716)
			(xy 258.930122 -56.113679) (xy 258.985559 -56.119779) (xy 259.039516 -56.133885) (xy 259.090845 -56.155697)
			(xy 259.138451 -56.184751) (xy 259.181319 -56.220426) (xy 259.218536 -56.261963) (xy 259.249309 -56.308476)
			(xy 259.272981 -56.358973) (xy 259.289049 -56.41238) (xy 259.297169 -56.467556) (xy 259.297678 -56.495442)
			(xy 259.297169 -56.523328) (xy 259.289049 -56.578504) (xy 259.272981 -56.631911) (xy 259.249309 -56.682408)
			(xy 259.218536 -56.728921) (xy 259.181319 -56.770458) (xy 259.138451 -56.806133) (xy 259.090845 -56.835187)
			(xy 259.039516 -56.856999) (xy 258.985559 -56.871105) (xy 258.930122 -56.877205) (xy 258.874388 -56.875168)
			(xy 258.819545 -56.865038) (xy 258.766761 -56.847031) (xy 258.717161 -56.82153) (xy 258.671803 -56.789079)
			(xy 258.631654 -56.75037) (xy 258.597568 -56.706227) (xy 258.570272 -56.657592) (xy 258.550349 -56.605501)
			(xy 258.538223 -56.551064) (xy 258.534152 -56.495442) (xy 247.172716 -56.495442) (xy 249.321047 -57.511442)
			(xy 258.578602 -57.511442) (xy 258.582673 -57.45582) (xy 258.594799 -57.401383) (xy 258.614722 -57.349292)
			(xy 258.642018 -57.300657) (xy 258.676104 -57.256514) (xy 258.716253 -57.217805) (xy 258.761611 -57.185354)
			(xy 258.811211 -57.159853) (xy 258.863995 -57.141846) (xy 258.918838 -57.131716) (xy 258.974572 -57.129679)
			(xy 259.030009 -57.135779) (xy 259.083966 -57.149885) (xy 259.135295 -57.171697) (xy 259.182901 -57.200751)
			(xy 259.225769 -57.236426) (xy 259.262986 -57.277963) (xy 259.293759 -57.324476) (xy 259.317431 -57.374973)
			(xy 259.333499 -57.42838) (xy 259.341619 -57.483556) (xy 259.342128 -57.511442) (xy 259.341619 -57.539328)
			(xy 259.333499 -57.594504) (xy 259.317431 -57.647911) (xy 259.293759 -57.698408) (xy 259.262986 -57.744921)
			(xy 259.225769 -57.786458) (xy 259.182901 -57.822133) (xy 259.135295 -57.851187) (xy 259.083966 -57.872999)
			(xy 259.030009 -57.887105) (xy 258.974572 -57.893205) (xy 258.918838 -57.891168) (xy 258.863995 -57.881038)
			(xy 258.811211 -57.863031) (xy 258.761611 -57.83753) (xy 258.716253 -57.805079) (xy 258.676104 -57.76637)
			(xy 258.642018 -57.722227) (xy 258.614722 -57.673592) (xy 258.594799 -57.621501) (xy 258.582673 -57.567064)
			(xy 258.578602 -57.511442) (xy 249.321047 -57.511442) (xy 250.583192 -58.108342) (xy 251.43333 -58.46064)
			(xy 253.542546 -58.46064)
		)
		(stroke
			(width 0)
			(type solid)
		)
		(fill yes)
		(layer "In4.Cu")
		(net "GND")
	)
	(gr_poly
		(pts
			(xy 183.32323 -35.04819) (xy 183.341215 -35.030836) (xy 183.381628 -35.001436) (xy 183.426147 -34.978727)
			(xy 183.473672 -34.96327) (xy 183.523032 -34.955446) (xy 183.54802 -34.954972) (xy 186.896248 -34.954972)
			(xy 187.230004 -34.621216) (xy 187.23356 -34.607246) (xy 187.240655 -34.579837) (xy 187.261839 -34.527336)
			(xy 187.290556 -34.478546) (xy 187.326175 -34.43454) (xy 187.367912 -34.396288) (xy 187.414849 -34.364632)
			(xy 187.465952 -34.340266) (xy 187.520097 -34.323729) (xy 187.576093 -34.315383) (xy 187.6044 -34.314892)
			(xy 187.631651 -34.315378) (xy 187.685599 -34.323134) (xy 187.737894 -34.338489) (xy 187.787471 -34.361131)
			(xy 187.833321 -34.390597) (xy 187.874512 -34.426288) (xy 187.910203 -34.467479) (xy 187.939669 -34.513329)
			(xy 187.962311 -34.562906) (xy 187.977666 -34.615201) (xy 187.985422 -34.669149) (xy 187.985908 -34.6964)
			(xy 187.985386 -34.724702) (xy 187.977008 -34.780682) (xy 187.960451 -34.834809) (xy 187.936078 -34.885897)
			(xy 187.904424 -34.932822) (xy 187.866184 -34.974555) (xy 187.822198 -35.010181) (xy 187.773431 -35.038916)
			(xy 187.720953 -35.06013) (xy 187.693554 -35.06724) (xy 187.679584 -35.070796) (xy 187.616846 -35.133534)
			(xy 187.610155 -35.140967) (xy 187.602573 -35.15945) (xy 187.602628 -35.179428) (xy 187.610313 -35.197869)
			(xy 187.624461 -35.211974) (xy 187.642925 -35.219603) (xy 187.652914 -35.220148) (xy 190.33744 -35.220148)
			(xy 190.352563 -35.219604) (xy 190.381488 -35.210762) (xy 190.406554 -35.193835) (xy 190.425563 -35.170308)
			(xy 190.436846 -35.142246) (xy 190.439415 -35.112109) (xy 190.436754 -35.097212) (xy 190.43282 -35.077508)
			(xy 190.428619 -35.037547) (xy 190.428372 -35.017456) (xy 190.428858 -34.990205) (xy 190.436614 -34.936257)
			(xy 190.451969 -34.883962) (xy 190.474611 -34.834385) (xy 190.504077 -34.788535) (xy 190.539768 -34.747344)
			(xy 190.580959 -34.711653) (xy 190.626809 -34.682187) (xy 190.676386 -34.659545) (xy 190.728681 -34.64419)
			(xy 190.782629 -34.636434) (xy 190.837131 -34.636434) (xy 190.891079 -34.64419) (xy 190.943374 -34.659545)
			(xy 190.992951 -34.682187) (xy 191.038801 -34.711653) (xy 191.079992 -34.747344) (xy 191.115683 -34.788535)
			(xy 191.145149 -34.834385) (xy 191.167791 -34.883962) (xy 191.183146 -34.936257) (xy 191.190902 -34.990205)
			(xy 191.191388 -35.017456) (xy 191.191142 -35.037547) (xy 191.186937 -35.077508) (xy 191.183006 -35.097212)
			(xy 191.180377 -35.112103) (xy 191.182968 -35.142214) (xy 191.194258 -35.170249) (xy 191.21326 -35.193751)
			(xy 191.238308 -35.210663) (xy 191.267209 -35.219503) (xy 191.28232 -35.220148) (xy 192.02908 -35.220148)
			(xy 192.30848 -34.940748) (xy 192.30848 -33.797748) (xy 186.59348 -28.082748) (xy 176.38268 -28.082748)
			(xy 175.13808 -26.838148) (xy 175.13808 -19.497548) (xy 174.80788 -19.167348) (xy 173.348904 -19.167348)
			(xy 173.33498 -19.167738) (xy 173.308149 -19.175183) (xy 173.284328 -19.189601) (xy 173.265289 -19.209921)
			(xy 173.252451 -19.234629) (xy 173.246767 -19.261888) (xy 173.247304 -19.275806) (xy 173.24832 -19.301968)
			(xy 173.247834 -19.329219) (xy 173.240078 -19.383167) (xy 173.224723 -19.435462) (xy 173.202081 -19.485039)
			(xy 173.172615 -19.530889) (xy 173.136924 -19.57208) (xy 173.095733 -19.607771) (xy 173.049883 -19.637237)
			(xy 173.000306 -19.659879) (xy 172.948011 -19.675234) (xy 172.894063 -19.68299) (xy 172.839561 -19.68299)
			(xy 172.785613 -19.675234) (xy 172.733318 -19.659879) (xy 172.683741 -19.637237) (xy 172.637891 -19.607771)
			(xy 172.5967 -19.57208) (xy 172.561009 -19.530889) (xy 172.531543 -19.485039) (xy 172.508901 -19.435462)
			(xy 172.493546 -19.383167) (xy 172.48579 -19.329219) (xy 172.485304 -19.301968) (xy 172.48632 -19.275806)
			(xy 172.486823 -19.261892) (xy 172.481123 -19.23465) (xy 172.468282 -19.209956) (xy 172.449254 -19.189644)
			(xy 172.42545 -19.175221) (xy 172.398637 -19.167757) (xy 172.38472 -19.167348) (xy 171.502324 -19.167348)
			(xy 171.484116 -19.189208) (xy 171.442324 -19.227805) (xy 171.39526 -19.259764) (xy 171.34397 -19.284375)
			(xy 171.289592 -19.301092) (xy 171.233335 -19.309543) (xy 171.20489 -19.310096) (xy 171.171146 -19.309377)
			(xy 171.104711 -19.297497) (xy 171.07281 -19.286474) (xy 171.04233 -19.275298) (xy 170.74388 -19.573748)
			(xy 170.74388 -20.485608) (xy 170.951142 -20.485608) (xy 170.955213 -20.429986) (xy 170.967339 -20.375549)
			(xy 170.987262 -20.323458) (xy 171.014558 -20.274823) (xy 171.048644 -20.23068) (xy 171.088793 -20.191971)
			(xy 171.134151 -20.15952) (xy 171.183751 -20.134019) (xy 171.236535 -20.116012) (xy 171.291378 -20.105882)
			(xy 171.347112 -20.103845) (xy 171.402549 -20.109945) (xy 171.456506 -20.124051) (xy 171.507835 -20.145863)
			(xy 171.555441 -20.174917) (xy 171.598309 -20.210592) (xy 171.635526 -20.252129) (xy 171.666299 -20.298642)
			(xy 171.689971 -20.349139) (xy 171.706039 -20.402546) (xy 171.714159 -20.457722) (xy 171.714668 -20.485608)
			(xy 171.714159 -20.513494) (xy 171.706039 -20.56867) (xy 171.689971 -20.622077) (xy 171.666299 -20.672574)
			(xy 171.635526 -20.719087) (xy 171.598309 -20.760624) (xy 171.555441 -20.796299) (xy 171.507835 -20.825353)
			(xy 171.456506 -20.847165) (xy 171.402549 -20.861271) (xy 171.347112 -20.867371) (xy 171.291378 -20.865334)
			(xy 171.236535 -20.855204) (xy 171.183751 -20.837197) (xy 171.134151 -20.811696) (xy 171.088793 -20.779245)
			(xy 171.048644 -20.740536) (xy 171.014558 -20.696393) (xy 170.987262 -20.647758) (xy 170.967339 -20.595667)
			(xy 170.955213 -20.54123) (xy 170.951142 -20.485608) (xy 170.74388 -20.485608) (xy 170.74388 -21.702014)
			(xy 170.74642 -21.709634) (xy 170.754974 -21.738148) (xy 170.764167 -21.796963) (xy 170.764708 -21.826728)
			(xy 170.764175 -21.856494) (xy 170.754981 -21.915309) (xy 170.74642 -21.943822) (xy 170.74388 -21.951442)
			(xy 170.74388 -22.148292) (xy 170.828208 -22.148292) (xy 170.841416 -22.117304) (xy 170.852751 -22.09179)
			(xy 170.881786 -22.044106) (xy 170.91746 -22.001162) (xy 170.959012 -21.963876) (xy 171.005555 -21.933044)
			(xy 171.056095 -21.909325) (xy 171.109551 -21.893225) (xy 171.164784 -21.885088) (xy 171.192698 -21.88464)
			(xy 171.219948 -21.885103) (xy 171.273892 -21.892859) (xy 171.326183 -21.908213) (xy 171.375758 -21.930852)
			(xy 171.421605 -21.960317) (xy 171.462793 -21.996006) (xy 171.498482 -22.037193) (xy 171.527947 -22.083041)
			(xy 171.550587 -22.132615) (xy 171.565941 -22.184906) (xy 171.573697 -22.23885) (xy 171.573697 -22.29335)
			(xy 171.565941 -22.347294) (xy 171.550587 -22.399585) (xy 171.527947 -22.449159) (xy 171.498482 -22.495007)
			(xy 171.462793 -22.536194) (xy 171.421605 -22.571883) (xy 171.375758 -22.601348) (xy 171.326183 -22.623987)
			(xy 171.273892 -22.639341) (xy 171.219948 -22.647097) (xy 171.192698 -22.647656) (xy 171.167179 -22.64723)
			(xy 171.116597 -22.640427) (xy 171.067372 -22.626944) (xy 171.020384 -22.60702) (xy 170.97647 -22.581011)
			(xy 170.936414 -22.549382) (xy 170.918378 -22.531324) (xy 170.907493 -22.520883) (xy 170.881101 -22.506315)
			(xy 170.851605 -22.500089) (xy 170.821576 -22.502749) (xy 170.793633 -22.514063) (xy 170.770213 -22.533044)
			(xy 170.753357 -22.558037) (xy 170.744535 -22.586863) (xy 170.74388 -22.601936) (xy 170.74388 -22.723348)
			(xy 171.784262 -22.723348) (xy 171.788333 -22.667726) (xy 171.800459 -22.613289) (xy 171.820382 -22.561198)
			(xy 171.847678 -22.512563) (xy 171.881764 -22.46842) (xy 171.921913 -22.429711) (xy 171.967271 -22.39726)
			(xy 172.016871 -22.371759) (xy 172.069655 -22.353752) (xy 172.124498 -22.343622) (xy 172.180232 -22.341585)
			(xy 172.235669 -22.347685) (xy 172.289626 -22.361791) (xy 172.340955 -22.383603) (xy 172.388561 -22.412657)
			(xy 172.431429 -22.448332) (xy 172.468646 -22.489869) (xy 172.499419 -22.536382) (xy 172.523091 -22.586879)
			(xy 172.539159 -22.640286) (xy 172.547279 -22.695462) (xy 172.547788 -22.723348) (xy 172.547279 -22.751234)
			(xy 172.539159 -22.80641) (xy 172.523091 -22.859817) (xy 172.499419 -22.910314) (xy 172.468646 -22.956827)
			(xy 172.431429 -22.998364) (xy 172.388561 -23.034039) (xy 172.340955 -23.063093) (xy 172.289626 -23.084905)
			(xy 172.235669 -23.099011) (xy 172.180232 -23.105111) (xy 172.124498 -23.103074) (xy 172.069655 -23.092944)
			(xy 172.016871 -23.074937) (xy 171.967271 -23.049436) (xy 171.921913 -23.016985) (xy 171.881764 -22.978276)
			(xy 171.847678 -22.934133) (xy 171.820382 -22.885498) (xy 171.800459 -22.833407) (xy 171.788333 -22.77897)
			(xy 171.784262 -22.723348) (xy 170.74388 -22.723348) (xy 170.74388 -22.85746) (xy 170.765423 -22.874152)
			(xy 170.803971 -22.912673) (xy 170.836643 -22.956291) (xy 170.862773 -23.004115) (xy 170.881827 -23.055173)
			(xy 170.893418 -23.108423) (xy 170.89731 -23.162781) (xy 170.893424 -23.217139) (xy 170.881838 -23.27039)
			(xy 170.862789 -23.32145) (xy 170.836664 -23.369277) (xy 170.803997 -23.412898) (xy 170.765452 -23.451423)
			(xy 170.74388 -23.468076) (xy 170.74388 -26.666748) (xy 171.777698 -26.666748) (xy 171.777698 -26.612252)
			(xy 171.785453 -26.558311) (xy 171.800805 -26.506022) (xy 171.823442 -26.45645) (xy 171.852903 -26.410604)
			(xy 171.888589 -26.369417) (xy 171.929772 -26.333727) (xy 171.975615 -26.304262) (xy 172.025184 -26.281619)
			(xy 172.077472 -26.266262) (xy 172.131412 -26.258501) (xy 172.15866 -26.258012) (xy 172.185096 -26.258433)
			(xy 172.237461 -26.265724) (xy 172.28832 -26.280173) (xy 172.336698 -26.301502) (xy 172.381669 -26.329303)
			(xy 172.422373 -26.363046) (xy 172.458031 -26.402082) (xy 172.473366 -26.42362) (xy 172.482357 -26.435682)
			(xy 172.505832 -26.454465) (xy 172.533759 -26.465597) (xy 172.563718 -26.468116) (xy 172.593112 -26.461801)
			(xy 172.619393 -26.447202) (xy 172.640285 -26.425582) (xy 172.64761 -26.412444) (xy 172.659887 -26.389266)
			(xy 172.689873 -26.34623) (xy 172.725473 -26.307711) (xy 172.766017 -26.274434) (xy 172.810739 -26.247028)
			(xy 172.858795 -26.22601) (xy 172.909279 -26.211776) (xy 172.961236 -26.204596) (xy 172.987462 -26.204164)
			(xy 173.014715 -26.204681) (xy 173.068666 -26.212433) (xy 173.120964 -26.227784) (xy 173.170546 -26.250423)
			(xy 173.2164 -26.279888) (xy 173.257594 -26.315579) (xy 173.293289 -26.356769) (xy 173.322759 -26.402621)
			(xy 173.345402 -26.4522) (xy 173.360759 -26.504497) (xy 173.368517 -26.558447) (xy 173.368517 -26.612953)
			(xy 173.360759 -26.666903) (xy 173.345402 -26.7192) (xy 173.322759 -26.768779) (xy 173.293289 -26.814631)
			(xy 173.257594 -26.855821) (xy 173.2164 -26.891512) (xy 173.170546 -26.920977) (xy 173.120964 -26.943616)
			(xy 173.068666 -26.958967) (xy 173.014715 -26.966719) (xy 172.987462 -26.96718) (xy 172.961027 -26.966746)
			(xy 172.908661 -26.959457) (xy 172.857803 -26.945012) (xy 172.809425 -26.923685) (xy 172.764454 -26.895885)
			(xy 172.723749 -26.862145) (xy 172.688091 -26.823109) (xy 172.672756 -26.801572) (xy 172.663864 -26.789432)
			(xy 172.640365 -26.770649) (xy 172.612416 -26.759521) (xy 172.582438 -26.757013) (xy 172.553028 -26.763343)
			(xy 172.526735 -26.77796) (xy 172.505838 -26.7996) (xy 172.498512 -26.812748) (xy 172.486215 -26.835915)
			(xy 172.456232 -26.87895) (xy 172.420635 -26.91747) (xy 172.380094 -26.950748) (xy 172.335375 -26.978156)
			(xy 172.287321 -26.999176) (xy 172.23684 -27.013412) (xy 172.184885 -27.020595) (xy 172.15866 -27.021028)
			(xy 172.131412 -27.020499) (xy 172.077472 -27.012738) (xy 172.025184 -26.997381) (xy 171.975615 -26.974738)
			(xy 171.929772 -26.945273) (xy 171.888589 -26.909583) (xy 171.852903 -26.868396) (xy 171.823442 -26.82255)
			(xy 171.800805 -26.772978) (xy 171.785453 -26.720689) (xy 171.777698 -26.666748) (xy 170.74388 -26.666748)
			(xy 170.74388 -27.63774) (xy 170.744358 -27.651648) (xy 170.75187 -27.678431) (xy 170.766325 -27.702197)
			(xy 170.786653 -27.721184) (xy 170.811348 -27.733987) (xy 170.83858 -27.739657) (xy 170.866333 -27.737773)
			(xy 170.89255 -27.728475) (xy 170.904154 -27.720798) (xy 170.928481 -27.704209) (xy 170.981165 -27.677919)
			(xy 171.037262 -27.660032) (xy 171.09544 -27.650972) (xy 171.12488 -27.65044) (xy 171.152133 -27.650902)
			(xy 171.206083 -27.658657) (xy 171.258381 -27.674012) (xy 171.30796 -27.696654) (xy 171.353812 -27.726122)
			(xy 171.395003 -27.761816) (xy 171.430695 -27.80301) (xy 171.46016 -27.848864) (xy 171.482798 -27.898446)
			(xy 171.498149 -27.950744) (xy 171.5059 -28.004695) (xy 171.506388 -28.031948) (xy 171.505938 -28.058744)
			(xy 171.498447 -28.111809) (xy 171.483605 -28.163304) (xy 171.461704 -28.212216) (xy 171.433174 -28.257582)
			(xy 171.398577 -28.29851) (xy 171.37888 -28.316682) (xy 171.368607 -28.3265) (xy 171.353463 -28.350531)
			(xy 171.345514 -28.377801) (xy 171.345375 -28.406206) (xy 171.353056 -28.433553) (xy 171.367964 -28.457732)
			(xy 171.388948 -28.476876) (xy 171.401486 -28.48356) (xy 171.425087 -28.495709) (xy 171.46898 -28.525559)
			(xy 171.508312 -28.561204) (xy 171.542324 -28.601956) (xy 171.570359 -28.64703) (xy 171.591878 -28.695553)
			(xy 171.600253 -28.72486) (xy 174.124112 -28.72486) (xy 174.124575 -28.698208) (xy 174.132012 -28.645427)
			(xy 174.146724 -28.594193) (xy 174.168422 -28.545506) (xy 174.196685 -28.500313) (xy 174.230963 -28.459493)
			(xy 174.270589 -28.423841) (xy 174.31479 -28.39405) (xy 174.362708 -28.370701) (xy 174.413408 -28.354249)
			(xy 174.43958 -28.349194) (xy 174.453331 -28.346366) (xy 174.47862 -28.334198) (xy 174.499643 -28.315607)
			(xy 174.514814 -28.291997) (xy 174.522988 -28.265149) (xy 174.523549 -28.237091) (xy 174.516453 -28.209938)
			(xy 174.502236 -28.185742) (xy 174.492412 -28.175712) (xy 174.474221 -28.157679) (xy 174.442384 -28.117553)
			(xy 174.416201 -28.073528) (xy 174.396143 -28.026396) (xy 174.38257 -27.977005) (xy 174.375727 -27.926241)
			(xy 174.375318 -27.90063) (xy 174.375804 -27.873379) (xy 174.38356 -27.819431) (xy 174.398915 -27.767136)
			(xy 174.421557 -27.717559) (xy 174.451023 -27.671709) (xy 174.486714 -27.630518) (xy 174.527905 -27.594827)
			(xy 174.573755 -27.565361) (xy 174.623332 -27.542719) (xy 174.675627 -27.527364) (xy 174.729575 -27.519608)
			(xy 174.784077 -27.519608) (xy 174.838025 -27.527364) (xy 174.89032 -27.542719) (xy 174.939897 -27.565361)
			(xy 174.985747 -27.594827) (xy 175.026938 -27.630518) (xy 175.062629 -27.671709) (xy 175.092095 -27.717559)
			(xy 175.114737 -27.767136) (xy 175.130092 -27.819431) (xy 175.137848 -27.873379) (xy 175.138334 -27.90063)
			(xy 175.137803 -27.927278) (xy 175.130368 -27.980053) (xy 175.115661 -28.03128) (xy 175.093968 -28.079962)
			(xy 175.065711 -28.125152) (xy 175.031441 -28.165969) (xy 174.991824 -28.20162) (xy 174.947631 -28.231411)
			(xy 174.899722 -28.254761) (xy 174.84903 -28.271218) (xy 174.822866 -28.276296) (xy 174.809122 -28.279158)
			(xy 174.78383 -28.291316) (xy 174.762802 -28.3099) (xy 174.747628 -28.333506) (xy 174.739451 -28.360351)
			(xy 174.738891 -28.388408) (xy 174.745988 -28.415558) (xy 174.760208 -28.439751) (xy 174.770034 -28.449778)
			(xy 174.78821 -28.467826) (xy 174.820051 -28.507948) (xy 174.846237 -28.551969) (xy 174.866298 -28.599098)
			(xy 174.879873 -28.648488) (xy 174.886718 -28.699249) (xy 174.887128 -28.72486) (xy 174.886664 -28.751206)
			(xy 174.879435 -28.8034) (xy 174.865096 -28.854104) (xy 174.843918 -28.902353) (xy 174.816306 -28.947231)
			(xy 174.782782 -28.987884) (xy 174.763684 -29.006038) (xy 174.753683 -29.01594) (xy 174.738953 -29.039903)
			(xy 174.731317 -29.066975) (xy 174.731356 -29.095103) (xy 174.739065 -29.122154) (xy 174.753862 -29.146076)
			(xy 174.763938 -29.155898) (xy 174.783138 -29.17405) (xy 174.816857 -29.214727) (xy 174.841886 -29.255212)
			(xy 176.187862 -29.255212) (xy 176.188401 -29.227892) (xy 176.196736 -29.173892) (xy 176.213214 -29.121796)
			(xy 176.237447 -29.072824) (xy 176.268869 -29.028123) (xy 176.28743 -29.00807) (xy 176.297817 -28.996439)
			(xy 176.311645 -28.968509) (xy 176.316404 -28.937709) (xy 176.311651 -28.906908) (xy 176.297827 -28.878975)
			(xy 176.28743 -28.867354) (xy 176.268809 -28.847348) (xy 176.237352 -28.802654) (xy 176.213104 -28.753673)
			(xy 176.196635 -28.701559) (xy 176.188332 -28.64754) (xy 176.187862 -28.620212) (xy 176.18836 -28.593563)
			(xy 176.196303 -28.540859) (xy 176.212013 -28.489929) (xy 176.235139 -28.441908) (xy 176.265163 -28.397871)
			(xy 176.301415 -28.3588) (xy 176.343086 -28.325569) (xy 176.389244 -28.29892) (xy 176.438858 -28.279448)
			(xy 176.49082 -28.267588) (xy 176.54397 -28.263605) (xy 176.59712 -28.267588) (xy 176.649082 -28.279448)
			(xy 176.698696 -28.29892) (xy 176.744854 -28.325569) (xy 176.786525 -28.3588) (xy 176.822777 -28.397871)
			(xy 176.852801 -28.441908) (xy 176.875927 -28.489929) (xy 176.891637 -28.540859) (xy 176.89958 -28.593563)
			(xy 176.900078 -28.620212) (xy 176.89957 -28.647533) (xy 176.89123 -28.701536) (xy 176.874746 -28.753633)
			(xy 176.850505 -28.802604) (xy 176.819075 -28.847302) (xy 176.80051 -28.867354) (xy 176.790105 -28.878968)
			(xy 176.776287 -28.906905) (xy 176.771535 -28.937709) (xy 176.776292 -28.968511) (xy 176.790115 -28.996446)
			(xy 176.80051 -29.00807) (xy 176.819102 -29.028102) (xy 176.850561 -29.07279) (xy 176.874814 -29.121764)
			(xy 176.89129 -29.173872) (xy 176.899602 -29.227886) (xy 176.900078 -29.255212) (xy 177.087784 -29.255212)
			(xy 177.088317 -29.227892) (xy 177.096653 -29.173891) (xy 177.113131 -29.121795) (xy 177.137366 -29.072823)
			(xy 177.16879 -29.028123) (xy 177.187352 -29.00807) (xy 177.197737 -28.996438) (xy 177.211562 -28.968508)
			(xy 177.21632 -28.937709) (xy 177.211568 -28.906909) (xy 177.197747 -28.878976) (xy 177.187352 -28.867354)
			(xy 177.168734 -28.847345) (xy 177.137277 -28.802652) (xy 177.113027 -28.753672) (xy 177.096557 -28.701559)
			(xy 177.088254 -28.647539) (xy 177.087784 -28.620212) (xy 177.088282 -28.593563) (xy 177.096225 -28.540859)
			(xy 177.111935 -28.489929) (xy 177.135061 -28.441908) (xy 177.165085 -28.397871) (xy 177.201337 -28.3588)
			(xy 177.243008 -28.325569) (xy 177.289166 -28.29892) (xy 177.33878 -28.279448) (xy 177.390742 -28.267588)
			(xy 177.443892 -28.263605) (xy 177.497042 -28.267588) (xy 177.549004 -28.279448) (xy 177.598618 -28.29892)
			(xy 177.644776 -28.325569) (xy 177.686447 -28.3588) (xy 177.722699 -28.397871) (xy 177.752723 -28.441908)
			(xy 177.775849 -28.489929) (xy 177.791559 -28.540859) (xy 177.799502 -28.593563) (xy 177.8 -28.620212)
			(xy 177.799486 -28.647533) (xy 177.791146 -28.701535) (xy 177.774664 -28.753631) (xy 177.750424 -28.802603)
			(xy 177.718996 -28.847302) (xy 177.700432 -28.867354) (xy 177.690025 -28.878967) (xy 177.676204 -28.906904)
			(xy 177.671452 -28.937709) (xy 177.676209 -28.968512) (xy 177.690035 -28.996447) (xy 177.700432 -29.00807)
			(xy 177.719028 -29.028099) (xy 177.750485 -29.072788) (xy 177.774737 -29.121763) (xy 177.791213 -29.173871)
			(xy 177.799524 -29.227886) (xy 177.8 -29.255212) (xy 177.987706 -29.255212) (xy 177.988233 -29.227892)
			(xy 177.996569 -29.17389) (xy 178.013049 -29.121794) (xy 178.037285 -29.072822) (xy 178.068711 -29.028122)
			(xy 178.087274 -29.00807) (xy 178.097657 -28.996437) (xy 178.111479 -28.968507) (xy 178.116236 -28.937709)
			(xy 178.111485 -28.90691) (xy 178.097667 -28.878977) (xy 178.087274 -28.867354) (xy 178.068643 -28.847357)
			(xy 178.03719 -28.802659) (xy 178.012945 -28.753676) (xy 177.996477 -28.701561) (xy 177.988176 -28.64754)
			(xy 177.987706 -28.620212) (xy 177.988204 -28.593563) (xy 177.996147 -28.540859) (xy 178.011857 -28.489929)
			(xy 178.034983 -28.441908) (xy 178.065007 -28.397871) (xy 178.101259 -28.3588) (xy 178.14293 -28.325569)
			(xy 178.189088 -28.29892) (xy 178.238702 -28.279448) (xy 178.290664 -28.267588) (xy 178.343814 -28.263605)
			(xy 178.396964 -28.267588) (xy 178.448926 -28.279448) (xy 178.49854 -28.29892) (xy 178.544698 -28.325569)
			(xy 178.586369 -28.3588) (xy 178.622621 -28.397871) (xy 178.652645 -28.441908) (xy 178.675771 -28.489929)
			(xy 178.691481 -28.540859) (xy 178.699424 -28.593563) (xy 178.699922 -28.620212) (xy 178.699402 -28.647533)
			(xy 178.691063 -28.701534) (xy 178.674581 -28.75363) (xy 178.650344 -28.802602) (xy 178.618917 -28.847301)
			(xy 178.600354 -28.867354) (xy 178.589945 -28.878966) (xy 178.576121 -28.906903) (xy 178.571367 -28.937709)
			(xy 178.576126 -28.968513) (xy 178.589955 -28.996448) (xy 178.600354 -29.00807) (xy 178.618936 -29.028111)
			(xy 178.650399 -29.072795) (xy 178.674655 -29.121767) (xy 178.691133 -29.173873) (xy 178.699446 -29.227887)
			(xy 178.699922 -29.255212) (xy 178.887882 -29.255212) (xy 178.888415 -29.227892) (xy 178.896751 -29.173891)
			(xy 178.91323 -29.121795) (xy 178.937464 -29.072823) (xy 178.968888 -29.028123) (xy 178.98745 -29.00807)
			(xy 178.997835 -28.996438) (xy 179.011661 -28.968508) (xy 179.016419 -28.937709) (xy 179.011666 -28.906908)
			(xy 178.997845 -28.878976) (xy 178.98745 -28.867354) (xy 178.968832 -28.847345) (xy 178.937374 -28.802652)
			(xy 178.913125 -28.753672) (xy 178.896655 -28.701559) (xy 178.888352 -28.647539) (xy 178.887882 -28.620212)
			(xy 178.88838 -28.593563) (xy 178.896323 -28.540859) (xy 178.912033 -28.489929) (xy 178.935159 -28.441908)
			(xy 178.965183 -28.397871) (xy 179.001435 -28.3588) (xy 179.043106 -28.325569) (xy 179.089264 -28.29892)
			(xy 179.138878 -28.279448) (xy 179.19084 -28.267588) (xy 179.24399 -28.263605) (xy 179.29714 -28.267588)
			(xy 179.349102 -28.279448) (xy 179.398716 -28.29892) (xy 179.444874 -28.325569) (xy 179.486545 -28.3588)
			(xy 179.522797 -28.397871) (xy 179.552821 -28.441908) (xy 179.575947 -28.489929) (xy 179.591657 -28.540859)
			(xy 179.5996 -28.593563) (xy 179.600098 -28.620212) (xy 179.599585 -28.647533) (xy 179.591245 -28.701535)
			(xy 179.574762 -28.753632) (xy 179.550523 -28.802603) (xy 179.519094 -28.847302) (xy 179.50053 -28.867354)
			(xy 179.490123 -28.878967) (xy 179.476303 -28.906904) (xy 179.47155 -28.937709) (xy 179.476308 -28.968512)
			(xy 179.490133 -28.996447) (xy 179.50053 -29.00807) (xy 179.519125 -29.028099) (xy 179.550583 -29.072788)
			(xy 179.574835 -29.121763) (xy 179.591311 -29.173871) (xy 179.599622 -29.227886) (xy 179.600098 -29.255212)
			(xy 179.5996 -29.281861) (xy 179.591657 -29.334565) (xy 179.575947 -29.385495) (xy 179.552821 -29.433516)
			(xy 179.522797 -29.477553) (xy 179.486545 -29.516624) (xy 179.444874 -29.549855) (xy 179.398716 -29.576504)
			(xy 179.349102 -29.595976) (xy 179.29714 -29.607836) (xy 179.24399 -29.61182) (xy 179.19084 -29.607836)
			(xy 179.138878 -29.595976) (xy 179.089264 -29.576504) (xy 179.043106 -29.549855) (xy 179.001435 -29.516624)
			(xy 178.965183 -29.477553) (xy 178.935159 -29.433516) (xy 178.912033 -29.385495) (xy 178.896323 -29.334565)
			(xy 178.88838 -29.281861) (xy 178.887882 -29.255212) (xy 178.699922 -29.255212) (xy 178.699424 -29.281861)
			(xy 178.691481 -29.334565) (xy 178.675771 -29.385495) (xy 178.652645 -29.433516) (xy 178.622621 -29.477553)
			(xy 178.586369 -29.516624) (xy 178.544698 -29.549855) (xy 178.49854 -29.576504) (xy 178.448926 -29.595976)
			(xy 178.396964 -29.607836) (xy 178.343814 -29.61182) (xy 178.290664 -29.607836) (xy 178.238702 -29.595976)
			(xy 178.189088 -29.576504) (xy 178.14293 -29.549855) (xy 178.101259 -29.516624) (xy 178.065007 -29.477553)
			(xy 178.034983 -29.433516) (xy 178.011857 -29.385495) (xy 177.996147 -29.334565) (xy 177.988204 -29.281861)
			(xy 177.987706 -29.255212) (xy 177.8 -29.255212) (xy 177.799502 -29.281861) (xy 177.791559 -29.334565)
			(xy 177.775849 -29.385495) (xy 177.752723 -29.433516) (xy 177.722699 -29.477553) (xy 177.686447 -29.516624)
			(xy 177.644776 -29.549855) (xy 177.598618 -29.576504) (xy 177.549004 -29.595976) (xy 177.497042 -29.607836)
			(xy 177.443892 -29.61182) (xy 177.390742 -29.607836) (xy 177.33878 -29.595976) (xy 177.289166 -29.576504)
			(xy 177.243008 -29.549855) (xy 177.201337 -29.516624) (xy 177.165085 -29.477553) (xy 177.135061 -29.433516)
			(xy 177.111935 -29.385495) (xy 177.096225 -29.334565) (xy 177.088282 -29.281861) (xy 177.087784 -29.255212)
			(xy 176.900078 -29.255212) (xy 176.89958 -29.281861) (xy 176.891637 -29.334565) (xy 176.875927 -29.385495)
			(xy 176.852801 -29.433516) (xy 176.822777 -29.477553) (xy 176.786525 -29.516624) (xy 176.744854 -29.549855)
			(xy 176.698696 -29.576504) (xy 176.649082 -29.595976) (xy 176.59712 -29.607836) (xy 176.54397 -29.61182)
			(xy 176.49082 -29.607836) (xy 176.438858 -29.595976) (xy 176.389244 -29.576504) (xy 176.343086 -29.549855)
			(xy 176.301415 -29.516624) (xy 176.265163 -29.477553) (xy 176.235139 -29.433516) (xy 176.212013 -29.385495)
			(xy 176.196303 -29.334565) (xy 176.18836 -29.281861) (xy 176.187862 -29.255212) (xy 174.841886 -29.255212)
			(xy 174.844641 -29.259668) (xy 174.865959 -29.308012) (xy 174.880402 -29.358836) (xy 174.887694 -29.411166)
			(xy 174.888144 -29.437584) (xy 174.887658 -29.464835) (xy 174.879902 -29.518783) (xy 174.864547 -29.571078)
			(xy 174.841905 -29.620655) (xy 174.812439 -29.666505) (xy 174.776748 -29.707696) (xy 174.735557 -29.743387)
			(xy 174.689707 -29.772853) (xy 174.64013 -29.795495) (xy 174.587835 -29.81085) (xy 174.533887 -29.818606)
			(xy 174.479385 -29.818606) (xy 174.425437 -29.81085) (xy 174.373142 -29.795495) (xy 174.323565 -29.772853)
			(xy 174.277715 -29.743387) (xy 174.236524 -29.707696) (xy 174.200833 -29.666505) (xy 174.171367 -29.620655)
			(xy 174.148725 -29.571078) (xy 174.13337 -29.518783) (xy 174.125614 -29.464835) (xy 174.125128 -29.437584)
			(xy 174.125537 -29.411236) (xy 174.132774 -29.359038) (xy 174.147123 -29.308333) (xy 174.168311 -29.260084)
			(xy 174.195934 -29.215207) (xy 174.229468 -29.174558) (xy 174.248572 -29.156406) (xy 174.258625 -29.146554)
			(xy 174.273344 -29.122575) (xy 174.280968 -29.095492) (xy 174.280919 -29.067355) (xy 174.2732 -29.040298)
			(xy 174.258397 -29.016371) (xy 174.248318 -29.006546) (xy 174.229102 -28.98841) (xy 174.195382 -28.947731)
			(xy 174.167599 -28.902787) (xy 174.146283 -28.854439) (xy 174.131844 -28.803612) (xy 174.124558 -28.751279)
			(xy 174.124112 -28.72486) (xy 171.600253 -28.72486) (xy 171.606463 -28.746591) (xy 171.613834 -28.799158)
			(xy 171.614338 -28.825698) (xy 171.613852 -28.852949) (xy 171.606096 -28.906897) (xy 171.590741 -28.959192)
			(xy 171.568099 -29.008769) (xy 171.538633 -29.054619) (xy 171.502942 -29.09581) (xy 171.461751 -29.131501)
			(xy 171.415901 -29.160967) (xy 171.366324 -29.183609) (xy 171.314029 -29.198964) (xy 171.260081 -29.20672)
			(xy 171.205579 -29.20672) (xy 171.151631 -29.198964) (xy 171.099336 -29.183609) (xy 171.049759 -29.160967)
			(xy 171.003909 -29.131501) (xy 170.962718 -29.09581) (xy 170.927027 -29.054619) (xy 170.897561 -29.008769)
			(xy 170.874919 -28.959192) (xy 170.859564 -28.906897) (xy 170.851808 -28.852949) (xy 170.851322 -28.825698)
			(xy 170.851775 -28.798904) (xy 170.859273 -28.745843) (xy 170.874122 -28.694353) (xy 170.896028 -28.645447)
			(xy 170.924561 -28.600087) (xy 170.959161 -28.559165) (xy 170.97883 -28.540964) (xy 170.989095 -28.531147)
			(xy 171.004222 -28.507121) (xy 171.012157 -28.479861) (xy 171.012288 -28.451469) (xy 171.004603 -28.424137)
			(xy 170.989697 -28.399973) (xy 170.968719 -28.380842) (xy 170.956224 -28.374086) (xy 170.942679 -28.367261)
			(xy 170.916613 -28.351749) (xy 170.904154 -28.343098) (xy 170.89254 -28.335417) (xy 170.866316 -28.326086)
			(xy 170.838547 -28.32418) (xy 170.811295 -28.329839) (xy 170.786581 -28.342645) (xy 170.766242 -28.361647)
			(xy 170.751786 -28.385433) (xy 170.744288 -28.412239) (xy 170.74388 -28.426156) (xy 170.74388 -31.816548)
			(xy 171.230798 -32.303466) (xy 171.285916 -32.248348) (xy 171.280582 -32.221678) (xy 171.277633 -32.206161)
			(xy 171.274455 -32.174733) (xy 171.274232 -32.15894) (xy 171.274232 -29.959554) (xy 171.259186 -29.935976)
			(xy 171.235419 -29.885345) (xy 171.219307 -29.831786) (xy 171.211194 -29.776446) (xy 171.210732 -29.74848)
			(xy 171.211197 -29.721229) (xy 171.218956 -29.667282) (xy 171.234314 -29.614989) (xy 171.256959 -29.565414)
			(xy 171.286428 -29.519567) (xy 171.322122 -29.47838) (xy 171.363315 -29.442692) (xy 171.409167 -29.41323)
			(xy 171.458746 -29.390593) (xy 171.511041 -29.375243) (xy 171.564989 -29.367492) (xy 171.59224 -29.366972)
			(xy 171.620347 -29.367491) (xy 171.675947 -29.375782) (xy 171.702984 -29.383482) (xy 171.716684 -29.38716)
			(xy 171.745035 -29.387621) (xy 171.772415 -29.380252) (xy 171.796705 -29.365622) (xy 171.816023 -29.344866)
			(xy 171.828872 -29.31959) (xy 171.832016 -29.305758) (xy 171.838231 -29.277245) (xy 171.858153 -29.222395)
			(xy 171.886188 -29.171216) (xy 171.921684 -29.124897) (xy 171.963813 -29.084519) (xy 172.011596 -29.05102)
			(xy 172.063918 -29.025181) (xy 172.119563 -29.007603) (xy 172.177235 -28.998697) (xy 172.206412 -28.998164)
			(xy 172.233665 -28.998651) (xy 172.287615 -29.006409) (xy 172.339912 -29.021766) (xy 172.389492 -29.04441)
			(xy 172.435344 -29.073879) (xy 172.476536 -29.109573) (xy 172.512229 -29.150766) (xy 172.541696 -29.196619)
			(xy 172.564338 -29.246199) (xy 172.579693 -29.298497) (xy 172.58745 -29.352447) (xy 172.58745 -29.406953)
			(xy 172.579693 -29.460903) (xy 172.564338 -29.513201) (xy 172.541696 -29.562781) (xy 172.512229 -29.608634)
			(xy 172.476536 -29.649827) (xy 172.435344 -29.685521) (xy 172.389492 -29.71499) (xy 172.339912 -29.737634)
			(xy 172.287615 -29.752991) (xy 172.233665 -29.760749) (xy 172.206412 -29.76118) (xy 172.178304 -29.760664)
			(xy 172.122702 -29.75238) (xy 172.095668 -29.74467) (xy 172.08197 -29.741) (xy 172.053626 -29.740551)
			(xy 172.026254 -29.747926) (xy 172.001972 -29.762554) (xy 171.982659 -29.783304) (xy 171.969807 -29.808571)
			(xy 171.966636 -29.822394) (xy 171.962304 -29.841952) (xy 180.652674 -29.841952) (xy 180.653185 -29.814379)
			(xy 180.661129 -29.759809) (xy 180.676846 -29.70695) (xy 180.700008 -29.656904) (xy 180.730132 -29.610713)
			(xy 180.766591 -29.56934) (xy 180.787294 -29.551122) (xy 180.798239 -29.541272) (xy 180.814311 -29.516608)
			(xy 180.822689 -29.488388) (xy 180.82268 -29.45895) (xy 180.814284 -29.430735) (xy 180.798198 -29.406081)
			(xy 180.787294 -29.396182) (xy 180.76657 -29.377985) (xy 180.730101 -29.336613) (xy 180.69997 -29.29042)
			(xy 180.676807 -29.24037) (xy 180.661093 -29.187504) (xy 180.653157 -29.132928) (xy 180.652674 -29.105352)
			(xy 180.653133 -29.0781) (xy 180.660896 -29.024153) (xy 180.676256 -28.971859) (xy 180.698901 -28.922282)
			(xy 180.728371 -28.876433) (xy 180.764065 -28.835244) (xy 180.805257 -28.799553) (xy 180.851109 -28.770087)
			(xy 180.900687 -28.747445) (xy 180.952982 -28.732089) (xy 181.00693 -28.724331) (xy 181.034182 -28.723844)
			(xy 181.061439 -28.724338) (xy 181.115398 -28.732103) (xy 181.167704 -28.747462) (xy 181.217293 -28.770105)
			(xy 181.263159 -28.799569) (xy 181.304368 -28.835257) (xy 181.340083 -28.876443) (xy 181.355238 -28.899104)
			(xy 181.363519 -28.911031) (xy 181.385455 -28.930035) (xy 181.411855 -28.94209) (xy 181.440582 -28.94622)
			(xy 181.469309 -28.94209) (xy 181.495709 -28.930035) (xy 181.517645 -28.911031) (xy 181.525926 -28.899104)
			(xy 181.541103 -28.876457) (xy 181.576806 -28.835261) (xy 181.618008 -28.799565) (xy 181.66387 -28.770094)
			(xy 181.713459 -28.747449) (xy 181.765765 -28.732091) (xy 181.819725 -28.724331) (xy 181.846982 -28.723844)
			(xy 181.874231 -28.724395) (xy 181.928173 -28.732148) (xy 181.980464 -28.747498) (xy 182.030038 -28.770134)
			(xy 182.075886 -28.799593) (xy 182.117075 -28.835278) (xy 182.152767 -28.876461) (xy 182.182235 -28.922304)
			(xy 182.204879 -28.971874) (xy 182.220238 -29.024162) (xy 182.228 -29.078103) (xy 182.22849 -29.105352)
			(xy 182.227995 -29.132926) (xy 182.220049 -29.187497) (xy 182.20433 -29.240357) (xy 182.181165 -29.290403)
			(xy 182.151038 -29.336593) (xy 182.114575 -29.377965) (xy 182.09387 -29.396182) (xy 182.083024 -29.406131)
			(xy 182.066955 -29.430768) (xy 182.058569 -29.458962) (xy 182.05856 -29.488376) (xy 182.066929 -29.516575)
			(xy 182.082983 -29.541222) (xy 182.09387 -29.551122) (xy 182.114589 -29.569325) (xy 182.15106 -29.610695)
			(xy 182.181192 -29.656886) (xy 182.204357 -29.706936) (xy 182.220071 -29.7598) (xy 182.228007 -29.814377)
			(xy 182.22849 -29.841952) (xy 182.228 -29.869204) (xy 182.220249 -29.923155) (xy 182.204898 -29.975454)
			(xy 182.18226 -30.025035) (xy 182.152795 -30.070889) (xy 182.117104 -30.112083) (xy 182.075913 -30.147777)
			(xy 182.030061 -30.177246) (xy 181.980482 -30.199888) (xy 181.928185 -30.215243) (xy 181.874234 -30.222998)
			(xy 181.846982 -30.22346) (xy 181.819724 -30.222991) (xy 181.765764 -30.215222) (xy 181.713458 -30.199858)
			(xy 181.663868 -30.177211) (xy 181.618003 -30.147743) (xy 181.576795 -30.112051) (xy 181.541081 -30.070862)
			(xy 181.525926 -30.0482) (xy 181.517645 -30.036273) (xy 181.495709 -30.017269) (xy 181.469309 -30.005214)
			(xy 181.440582 -30.001084) (xy 181.411855 -30.005214) (xy 181.385455 -30.017269) (xy 181.363519 -30.036273)
			(xy 181.355238 -30.0482) (xy 181.340086 -30.070864) (xy 181.304378 -30.11206) (xy 181.263172 -30.147755)
			(xy 181.217306 -30.177224) (xy 181.167713 -30.199866) (xy 181.115403 -30.21522) (xy 181.061441 -30.222975)
			(xy 181.034182 -30.22346) (xy 181.006926 -30.223062) (xy 180.952971 -30.215301) (xy 180.900669 -30.19994)
			(xy 180.851085 -30.177292) (xy 180.80523 -30.147818) (xy 180.764036 -30.112117) (xy 180.728343 -30.070917)
			(xy 180.698876 -30.025057) (xy 180.676237 -29.975469) (xy 180.660885 -29.923165) (xy 180.653134 -29.869208)
			(xy 180.652674 -29.841952) (xy 171.962304 -29.841952) (xy 171.959321 -29.855419) (xy 171.934664 -29.918401)
			(xy 171.917614 -29.947616) (xy 171.910248 -29.959808) (xy 171.910248 -30.039818) (xy 171.910807 -30.050893)
			(xy 171.920134 -30.070983) (xy 171.937049 -30.085284) (xy 171.958411 -30.091139) (xy 171.980254 -30.087463)
			(xy 171.98975 -30.081728) (xy 172.013765 -30.065785) (xy 172.065583 -30.04054) (xy 172.12061 -30.02338)
			(xy 172.177592 -30.014694) (xy 172.206412 -30.014164) (xy 172.233665 -30.014651) (xy 172.287615 -30.022409)
			(xy 172.339912 -30.037766) (xy 172.389492 -30.06041) (xy 172.435344 -30.089879) (xy 172.476536 -30.125573)
			(xy 172.512229 -30.166766) (xy 172.541696 -30.212619) (xy 172.564338 -30.262199) (xy 172.579693 -30.314497)
			(xy 172.58745 -30.368447) (xy 172.58745 -30.422953) (xy 172.579693 -30.476903) (xy 172.564338 -30.529201)
			(xy 172.541696 -30.578781) (xy 172.512229 -30.624634) (xy 172.476536 -30.665827) (xy 172.435344 -30.701521)
			(xy 172.389492 -30.73099) (xy 172.339912 -30.753634) (xy 172.287615 -30.768991) (xy 172.233665 -30.776749)
			(xy 172.206412 -30.77718) (xy 172.180041 -30.776759) (xy 172.127797 -30.769529) (xy 172.077052 -30.755151)
			(xy 172.052742 -30.744922) (xy 172.039337 -30.739582) (xy 172.010739 -30.735832) (xy 171.982235 -30.740231)
			(xy 171.956099 -30.752428) (xy 171.934418 -30.771449) (xy 171.918923 -30.795775) (xy 171.910851 -30.823465)
			(xy 171.910248 -30.837886) (xy 171.910248 -31.446248) (xy 176.813144 -31.446248) (xy 176.813145 -31.39174)
			(xy 176.820904 -31.337786) (xy 176.836262 -31.285486) (xy 176.858907 -31.235903) (xy 176.888378 -31.190049)
			(xy 176.924075 -31.148855) (xy 176.965271 -31.113161) (xy 177.011128 -31.083693) (xy 177.060712 -31.061052)
			(xy 177.113013 -31.045698) (xy 177.166968 -31.037943) (xy 177.221476 -31.037946) (xy 177.27543 -31.045707)
			(xy 177.327729 -31.061067) (xy 177.377311 -31.083715) (xy 177.423164 -31.113188) (xy 177.464356 -31.148886)
			(xy 177.500048 -31.190084) (xy 177.529514 -31.235942) (xy 177.552154 -31.285527) (xy 177.567506 -31.337829)
			(xy 177.575258 -31.391784) (xy 177.575718 -31.419038) (xy 177.575718 -31.428944) (xy 177.575825 -31.44294)
			(xy 177.582765 -31.470045) (xy 177.5968 -31.49425) (xy 177.616878 -31.513737) (xy 177.64149 -31.527045)
			(xy 177.66879 -31.533174) (xy 177.696728 -31.531664) (xy 177.723209 -31.522629) (xy 177.734976 -31.51505)
			(xy 177.759047 -31.498984) (xy 177.811029 -31.473548) (xy 177.866258 -31.45626) (xy 177.923464 -31.447515)
			(xy 177.9524 -31.446978) (xy 177.979653 -31.447455) (xy 178.033604 -31.455212) (xy 178.085903 -31.470569)
			(xy 178.135483 -31.493212) (xy 178.181336 -31.52268) (xy 178.222529 -31.558374) (xy 178.258223 -31.599567)
			(xy 178.287691 -31.645421) (xy 178.310333 -31.695002) (xy 178.325689 -31.7473) (xy 178.333445 -31.801252)
			(xy 178.333444 -31.855758) (xy 178.325687 -31.909709) (xy 178.312618 -31.954216) (xy 179.198014 -31.954216)
			(xy 179.202085 -31.898594) (xy 179.214211 -31.844157) (xy 179.234134 -31.792066) (xy 179.26143 -31.743431)
			(xy 179.295516 -31.699288) (xy 179.335665 -31.660579) (xy 179.381023 -31.628128) (xy 179.430623 -31.602627)
			(xy 179.483407 -31.58462) (xy 179.53825 -31.57449) (xy 179.593984 -31.572453) (xy 179.649421 -31.578553)
			(xy 179.703378 -31.592659) (xy 179.754707 -31.614471) (xy 179.802313 -31.643525) (xy 179.806794 -31.647254)
			(xy 182.48193 -31.647254) (xy 182.48193 -31.592746) (xy 182.489687 -31.538793) (xy 182.505043 -31.486493)
			(xy 182.527686 -31.436911) (xy 182.557154 -31.391056) (xy 182.592848 -31.349861) (xy 182.634041 -31.314165)
			(xy 182.679895 -31.284694) (xy 182.729476 -31.262049) (xy 182.781776 -31.246691) (xy 182.835728 -31.238931)
			(xy 182.862982 -31.238444) (xy 182.890239 -31.238938) (xy 182.944198 -31.246703) (xy 182.996504 -31.262062)
			(xy 183.046093 -31.284705) (xy 183.091959 -31.314169) (xy 183.133168 -31.349857) (xy 183.168883 -31.391043)
			(xy 183.184038 -31.413704) (xy 183.192319 -31.425631) (xy 183.214255 -31.444635) (xy 183.240655 -31.45669)
			(xy 183.269382 -31.46082) (xy 183.298109 -31.45669) (xy 183.324509 -31.444635) (xy 183.346445 -31.425631)
			(xy 183.354726 -31.413704) (xy 183.369903 -31.391057) (xy 183.405606 -31.349861) (xy 183.446808 -31.314165)
			(xy 183.49267 -31.284694) (xy 183.542259 -31.262049) (xy 183.594565 -31.246691) (xy 183.648525 -31.238931)
			(xy 183.675782 -31.238444) (xy 183.703032 -31.239002) (xy 183.756978 -31.246756) (xy 183.809272 -31.262108)
			(xy 183.858848 -31.284747) (xy 183.904698 -31.314211) (xy 183.945887 -31.3499) (xy 183.981578 -31.391088)
			(xy 184.011044 -31.436936) (xy 184.033685 -31.486511) (xy 184.04904 -31.538804) (xy 184.056797 -31.59275)
			(xy 184.056797 -31.64725) (xy 184.04904 -31.701196) (xy 184.033685 -31.753489) (xy 184.011044 -31.803064)
			(xy 183.981578 -31.848912) (xy 183.945887 -31.8901) (xy 183.904698 -31.925789) (xy 183.858848 -31.955253)
			(xy 183.809272 -31.977892) (xy 183.756978 -31.993244) (xy 183.703032 -32.000998) (xy 183.675782 -32.00146)
			(xy 183.648524 -32.000991) (xy 183.594564 -31.993222) (xy 183.542258 -31.977858) (xy 183.492668 -31.955211)
			(xy 183.446803 -31.925743) (xy 183.405595 -31.890051) (xy 183.369881 -31.848862) (xy 183.354726 -31.8262)
			(xy 183.346445 -31.814273) (xy 183.324509 -31.795269) (xy 183.298109 -31.783214) (xy 183.269382 -31.779084)
			(xy 183.240655 -31.783214) (xy 183.214255 -31.795269) (xy 183.192319 -31.814273) (xy 183.184038 -31.8262)
			(xy 183.168886 -31.848864) (xy 183.133178 -31.89006) (xy 183.091972 -31.925755) (xy 183.046106 -31.955224)
			(xy 182.996513 -31.977866) (xy 182.944203 -31.99322) (xy 182.890241 -32.000975) (xy 182.862982 -32.00146)
			(xy 182.835728 -32.001069) (xy 182.781776 -31.993309) (xy 182.729476 -31.977951) (xy 182.679895 -31.955306)
			(xy 182.634041 -31.925835) (xy 182.592848 -31.890139) (xy 182.557154 -31.848944) (xy 182.527686 -31.803089)
			(xy 182.505043 -31.753507) (xy 182.489687 -31.701207) (xy 182.48193 -31.647254) (xy 179.806794 -31.647254)
			(xy 179.845181 -31.6792) (xy 179.882398 -31.720737) (xy 179.913171 -31.76725) (xy 179.936843 -31.817747)
			(xy 179.952911 -31.871154) (xy 179.961031 -31.92633) (xy 179.96154 -31.954216) (xy 179.961031 -31.982102)
			(xy 179.952911 -32.037278) (xy 179.936843 -32.090685) (xy 179.913171 -32.141182) (xy 179.882398 -32.187695)
			(xy 179.845181 -32.229232) (xy 179.802313 -32.264907) (xy 179.754707 -32.293961) (xy 179.703378 -32.315773)
			(xy 179.649421 -32.329879) (xy 179.593984 -32.335979) (xy 179.53825 -32.333942) (xy 179.483407 -32.323812)
			(xy 179.430623 -32.305805) (xy 179.381023 -32.280304) (xy 179.335665 -32.247853) (xy 179.295516 -32.209144)
			(xy 179.26143 -32.165001) (xy 179.234134 -32.116366) (xy 179.214211 -32.064275) (xy 179.202085 -32.009838)
			(xy 179.198014 -31.954216) (xy 178.312618 -31.954216) (xy 178.31033 -31.962007) (xy 178.287686 -32.011587)
			(xy 178.258217 -32.05744) (xy 178.222523 -32.098632) (xy 178.181329 -32.134326) (xy 178.135475 -32.163793)
			(xy 178.085894 -32.186435) (xy 178.033595 -32.20179) (xy 177.979644 -32.209545) (xy 177.925138 -32.209544)
			(xy 177.871186 -32.201786) (xy 177.818889 -32.186428) (xy 177.769309 -32.163784) (xy 177.723456 -32.134314)
			(xy 177.682264 -32.098619) (xy 177.646572 -32.057425) (xy 177.617105 -32.011571) (xy 177.594464 -31.961989)
			(xy 177.579109 -31.909691) (xy 177.571354 -31.855739) (xy 177.570892 -31.828486) (xy 177.570892 -31.81858)
			(xy 177.570823 -31.804585) (xy 177.563868 -31.777484) (xy 177.549822 -31.753286) (xy 177.52974 -31.733805)
			(xy 177.505126 -31.7205) (xy 177.477827 -31.714371) (xy 177.449888 -31.715875) (xy 177.423405 -31.724901)
			(xy 177.411634 -31.732474) (xy 177.387554 -31.748527) (xy 177.335576 -31.773968) (xy 177.28035 -31.791261)
			(xy 177.223145 -31.800008) (xy 177.19421 -31.800546) (xy 177.166956 -31.800056) (xy 177.113002 -31.7923)
			(xy 177.060701 -31.776944) (xy 177.011118 -31.754301) (xy 176.965262 -31.724832) (xy 176.924066 -31.689136)
			(xy 176.888371 -31.647942) (xy 176.858901 -31.602086) (xy 176.836258 -31.552503) (xy 176.820901 -31.500202)
			(xy 176.813144 -31.446248) (xy 171.910248 -31.446248) (xy 171.910248 -32.027368) (xy 172.418502 -32.535622)
			(xy 180.552342 -32.535622) (xy 180.556413 -32.48) (xy 180.568539 -32.425563) (xy 180.588462 -32.373472)
			(xy 180.615758 -32.324837) (xy 180.649844 -32.280694) (xy 180.689993 -32.241985) (xy 180.735351 -32.209534)
			(xy 180.784951 -32.184033) (xy 180.837735 -32.166026) (xy 180.892578 -32.155896) (xy 180.948312 -32.153859)
			(xy 181.003749 -32.159959) (xy 181.057706 -32.174065) (xy 181.109035 -32.195877) (xy 181.156641 -32.224931)
			(xy 181.199509 -32.260606) (xy 181.236726 -32.302143) (xy 181.267499 -32.348656) (xy 181.291171 -32.399153)
			(xy 181.307239 -32.45256) (xy 181.315359 -32.507736) (xy 181.315868 -32.535622) (xy 181.315359 -32.563508)
			(xy 181.307239 -32.618684) (xy 181.291171 -32.672091) (xy 181.267499 -32.722588) (xy 181.236726 -32.769101)
			(xy 181.199509 -32.810638) (xy 181.156641 -32.846313) (xy 181.109035 -32.875367) (xy 181.057706 -32.897179)
			(xy 181.003749 -32.911285) (xy 180.948312 -32.917385) (xy 180.892578 -32.915348) (xy 180.837735 -32.905218)
			(xy 180.784951 -32.887211) (xy 180.735351 -32.86171) (xy 180.689993 -32.829259) (xy 180.649844 -32.79055)
			(xy 180.615758 -32.746407) (xy 180.588462 -32.697772) (xy 180.568539 -32.645681) (xy 180.556413 -32.591244)
			(xy 180.552342 -32.535622) (xy 172.418502 -32.535622) (xy 173.433232 -33.550352) (xy 184.716674 -33.550352)
			(xy 184.717124 -33.524036) (xy 184.724346 -33.471902) (xy 184.73866 -33.421254) (xy 184.759795 -33.373052)
			(xy 184.787351 -33.328211) (xy 184.820804 -33.287578) (xy 184.839864 -33.269428) (xy 184.849935 -33.259663)
			(xy 184.864636 -33.235778) (xy 184.87227 -33.208791) (xy 184.872261 -33.180745) (xy 184.864609 -33.153762)
			(xy 184.849894 -33.129887) (xy 184.839864 -33.120076) (xy 184.820785 -33.10194) (xy 184.787305 -33.061322)
			(xy 184.759732 -33.016482) (xy 184.738593 -32.968274) (xy 184.72429 -32.917616) (xy 184.717093 -32.865472)
			(xy 184.716674 -32.839152) (xy 184.717185 -32.811579) (xy 184.725129 -32.757009) (xy 184.740846 -32.70415)
			(xy 184.764008 -32.654104) (xy 184.794132 -32.607913) (xy 184.830591 -32.56654) (xy 184.851294 -32.548322)
			(xy 184.862239 -32.538472) (xy 184.878311 -32.513808) (xy 184.886689 -32.485588) (xy 184.88668 -32.45615)
			(xy 184.878284 -32.427935) (xy 184.862198 -32.403281) (xy 184.851294 -32.393382) (xy 184.83057 -32.375185)
			(xy 184.794101 -32.333813) (xy 184.76397 -32.28762) (xy 184.740807 -32.23757) (xy 184.725093 -32.184704)
			(xy 184.717157 -32.130128) (xy 184.716674 -32.102552) (xy 184.71716 -32.075301) (xy 184.724916 -32.021353)
			(xy 184.740271 -31.969058) (xy 184.762913 -31.919481) (xy 184.792379 -31.873631) (xy 184.82807 -31.83244)
			(xy 184.869261 -31.796749) (xy 184.915111 -31.767283) (xy 184.964688 -31.744641) (xy 185.016983 -31.729286)
			(xy 185.070931 -31.72153) (xy 185.125433 -31.72153) (xy 185.179381 -31.729286) (xy 185.231676 -31.744641)
			(xy 185.281253 -31.767283) (xy 185.327103 -31.796749) (xy 185.368294 -31.83244) (xy 185.403985 -31.873631)
			(xy 185.433451 -31.919481) (xy 185.456093 -31.969058) (xy 185.471448 -32.021353) (xy 185.479204 -32.075301)
			(xy 185.47969 -32.102552) (xy 185.479195 -32.130126) (xy 185.471249 -32.184697) (xy 185.45553 -32.237557)
			(xy 185.432365 -32.287603) (xy 185.402238 -32.333793) (xy 185.365775 -32.375165) (xy 185.34507 -32.393382)
			(xy 185.334224 -32.403331) (xy 185.318155 -32.427968) (xy 185.309769 -32.456162) (xy 185.30976 -32.485576)
			(xy 185.318129 -32.513775) (xy 185.334183 -32.538422) (xy 185.34507 -32.548322) (xy 185.365789 -32.566525)
			(xy 185.40226 -32.607895) (xy 185.432392 -32.654086) (xy 185.455557 -32.704136) (xy 185.471271 -32.757)
			(xy 185.479207 -32.811577) (xy 185.47969 -32.839152) (xy 185.479255 -32.865469) (xy 185.472031 -32.917604)
			(xy 185.457715 -32.968252) (xy 185.436577 -33.016454) (xy 185.409019 -33.061296) (xy 185.375562 -33.101927)
			(xy 185.3565 -33.120076) (xy 185.346528 -33.129934) (xy 185.331828 -33.153793) (xy 185.324184 -33.180755)
			(xy 185.324175 -33.20878) (xy 185.331802 -33.235747) (xy 185.346487 -33.259616) (xy 185.3565 -33.269428)
			(xy 185.375593 -33.287549) (xy 185.40907 -33.328172) (xy 185.436638 -33.373016) (xy 185.457775 -33.421226)
			(xy 185.472076 -33.471886) (xy 185.479271 -33.524032) (xy 185.47969 -33.550352) (xy 185.479204 -33.577603)
			(xy 185.471448 -33.631551) (xy 185.456093 -33.683846) (xy 185.433451 -33.733423) (xy 185.403985 -33.779273)
			(xy 185.368294 -33.820464) (xy 185.327103 -33.856155) (xy 185.281253 -33.885621) (xy 185.231676 -33.908263)
			(xy 185.179381 -33.923618) (xy 185.125433 -33.931374) (xy 185.070931 -33.931374) (xy 185.016983 -33.923618)
			(xy 184.964688 -33.908263) (xy 184.915111 -33.885621) (xy 184.869261 -33.856155) (xy 184.82807 -33.820464)
			(xy 184.792379 -33.779273) (xy 184.762913 -33.733423) (xy 184.740271 -33.683846) (xy 184.724916 -33.631551)
			(xy 184.71716 -33.577603) (xy 184.716674 -33.550352) (xy 173.433232 -33.550352) (xy 174.222534 -34.339654)
			(xy 181.84693 -34.339654) (xy 181.84693 -34.285146) (xy 181.854687 -34.231193) (xy 181.870043 -34.178893)
			(xy 181.892686 -34.129311) (xy 181.922154 -34.083456) (xy 181.957848 -34.042261) (xy 181.999041 -34.006565)
			(xy 182.044895 -33.977094) (xy 182.094476 -33.954449) (xy 182.146776 -33.939091) (xy 182.200728 -33.931331)
			(xy 182.227982 -33.930844) (xy 182.256899 -33.931359) (xy 182.314071 -33.940086) (xy 182.369271 -33.957344)
			(xy 182.421233 -33.982736) (xy 182.468767 -34.015681) (xy 182.510783 -34.055424) (xy 182.528972 -34.07791)
			(xy 182.538869 -34.089715) (xy 182.564193 -34.107234) (xy 182.593586 -34.11641) (xy 182.624378 -34.11641)
			(xy 182.653771 -34.107234) (xy 182.679095 -34.089715) (xy 182.688992 -34.07791) (xy 182.70719 -34.055432)
			(xy 182.749208 -34.015696) (xy 182.796741 -33.982756) (xy 182.848701 -33.957367) (xy 182.903898 -33.94011)
			(xy 182.961066 -33.931379) (xy 182.989982 -33.930844) (xy 183.017232 -33.931402) (xy 183.071178 -33.939156)
			(xy 183.123472 -33.954508) (xy 183.173048 -33.977147) (xy 183.218898 -34.006611) (xy 183.260087 -34.0423)
			(xy 183.295778 -34.083488) (xy 183.325244 -34.129336) (xy 183.347885 -34.178911) (xy 183.36324 -34.231204)
			(xy 183.370997 -34.28515) (xy 183.370997 -34.33965) (xy 183.36324 -34.393596) (xy 183.347885 -34.445889)
			(xy 183.325244 -34.495464) (xy 183.295778 -34.541312) (xy 183.260087 -34.5825) (xy 183.218898 -34.618189)
			(xy 183.173048 -34.647653) (xy 183.123472 -34.670292) (xy 183.071178 -34.685644) (xy 183.017232 -34.693398)
			(xy 182.989982 -34.69386) (xy 182.961067 -34.693298) (xy 182.903897 -34.68458) (xy 182.848698 -34.667332)
			(xy 182.796736 -34.641948) (xy 182.749201 -34.609012) (xy 182.707183 -34.569277) (xy 182.688992 -34.546794)
			(xy 182.679095 -34.534989) (xy 182.653771 -34.51747) (xy 182.624378 -34.508294) (xy 182.593586 -34.508294)
			(xy 182.564193 -34.51747) (xy 182.538869 -34.534989) (xy 182.528972 -34.546794) (xy 182.510795 -34.56929)
			(xy 182.468773 -34.609024) (xy 182.421235 -34.641962) (xy 182.369271 -34.667348) (xy 182.314071 -34.684602)
			(xy 182.256899 -34.693327) (xy 182.227982 -34.69386) (xy 182.200728 -34.693469) (xy 182.146776 -34.685709)
			(xy 182.094476 -34.670351) (xy 182.044895 -34.647706) (xy 181.999041 -34.618235) (xy 181.957848 -34.582539)
			(xy 181.922154 -34.541344) (xy 181.892686 -34.495489) (xy 181.870043 -34.445907) (xy 181.854687 -34.393607)
			(xy 181.84693 -34.339654) (xy 174.222534 -34.339654) (xy 175.103028 -35.220148) (xy 183.151272 -35.220148)
		)
		(stroke
			(width 0)
			(type solid)
		)
		(fill yes)
		(layer "In4.Cu")
		(net "GND")
	)
	(gr_poly
		(pts
			(xy 200.05548 -38.623748) (xy 200.05548 -31.104332) (xy 200.012554 -31.097474) (xy 199.98604 -31.09291)
			(xy 199.934549 -31.077314) (xy 199.885753 -31.054655) (xy 199.840615 -31.02538) (xy 199.820022 -31.008066)
			(xy 199.808694 -30.99883) (xy 199.782137 -30.986654) (xy 199.75322 -30.982481) (xy 199.724303 -30.986654)
			(xy 199.697746 -30.99883) (xy 199.686418 -31.008066) (xy 199.665488 -31.02571) (xy 199.619522 -31.055441)
			(xy 199.569776 -31.078289) (xy 199.517272 -31.093783) (xy 199.463091 -31.101605) (xy 199.43572 -31.102046)
			(xy 199.408467 -31.101562) (xy 199.354515 -31.093808) (xy 199.302216 -31.078455) (xy 199.252633 -31.055815)
			(xy 199.206778 -31.02635) (xy 199.165582 -30.990659) (xy 199.129885 -30.949469) (xy 199.100413 -30.903618)
			(xy 199.077766 -30.854039) (xy 199.062405 -30.801742) (xy 199.054643 -30.747791) (xy 199.054212 -30.720538)
			(xy 199.054653 -30.69501) (xy 199.061534 -30.644418) (xy 199.067928 -30.6197) (xy 199.071503 -30.604613)
			(xy 199.070377 -30.573642) (xy 199.060018 -30.544434) (xy 199.041379 -30.519674) (xy 199.016176 -30.501639)
			(xy 199.001634 -30.496256) (xy 198.977628 -30.487907) (xy 198.931887 -30.465745) (xy 198.889486 -30.437718)
			(xy 198.870062 -30.421326) (xy 198.858734 -30.41209) (xy 198.832177 -30.399914) (xy 198.80326 -30.395741)
			(xy 198.774343 -30.399914) (xy 198.747786 -30.41209) (xy 198.736458 -30.421326) (xy 198.715525 -30.438965)
			(xy 198.669557 -30.468684) (xy 198.61981 -30.49152) (xy 198.567307 -30.507003) (xy 198.513129 -30.514815)
			(xy 198.48576 -30.515306) (xy 198.458511 -30.514817) (xy 198.404568 -30.507056) (xy 198.352278 -30.491698)
			(xy 198.302706 -30.469055) (xy 198.256861 -30.439587) (xy 198.215676 -30.403896) (xy 198.179989 -30.362707)
			(xy 198.150526 -30.316859) (xy 198.127888 -30.267285) (xy 198.112535 -30.214993) (xy 198.10478 -30.161049)
			(xy 198.10478 -30.106551) (xy 198.112535 -30.052607) (xy 198.127888 -30.000315) (xy 198.150526 -29.950741)
			(xy 198.179989 -29.904893) (xy 198.215676 -29.863704) (xy 198.256861 -29.828013) (xy 198.302706 -29.798545)
			(xy 198.352278 -29.775902) (xy 198.404568 -29.760544) (xy 198.458511 -29.752783) (xy 198.48576 -29.75229)
			(xy 198.513129 -29.752766) (xy 198.567303 -29.760597) (xy 198.619802 -29.776091) (xy 198.669547 -29.798928)
			(xy 198.715519 -29.82864) (xy 198.736458 -29.84627) (xy 198.747786 -29.855506) (xy 198.774343 -29.867682)
			(xy 198.80326 -29.871855) (xy 198.832177 -29.867682) (xy 198.858734 -29.855506) (xy 198.870062 -29.84627)
			(xy 198.890995 -29.828629) (xy 198.936963 -29.798905) (xy 198.986709 -29.776059) (xy 199.039211 -29.760563)
			(xy 199.093389 -29.752734) (xy 199.148131 -29.752734) (xy 199.202309 -29.760563) (xy 199.254811 -29.776059)
			(xy 199.304557 -29.798905) (xy 199.350525 -29.828629) (xy 199.371458 -29.84627) (xy 199.382786 -29.855506)
			(xy 199.409343 -29.867682) (xy 199.43826 -29.871855) (xy 199.467177 -29.867682) (xy 199.493734 -29.855506)
			(xy 199.505062 -29.84627) (xy 199.525995 -29.828633) (xy 199.571964 -29.798917) (xy 199.621711 -29.776083)
			(xy 199.674214 -29.760603) (xy 199.728391 -29.752794) (xy 199.75576 -29.75229) (xy 199.78264 -29.752752)
			(xy 199.835867 -29.7603) (xy 199.88751 -29.775237) (xy 199.912224 -29.785818) (xy 199.925652 -29.791299)
			(xy 199.954366 -29.795284) (xy 199.983042 -29.791037) (xy 200.009369 -29.7789) (xy 200.031222 -29.759853)
			(xy 200.04684 -29.735431) (xy 200.054964 -29.707603) (xy 200.05548 -29.693108) (xy 200.05548 -29.428948)
			(xy 195.25615 -24.629618) (xy 195.246178 -24.620309) (xy 195.222445 -24.606877) (xy 195.196002 -24.600209)
			(xy 195.168738 -24.600784) (xy 195.1426 -24.608559) (xy 195.119454 -24.622979) (xy 195.109846 -24.632666)
			(xy 195.091709 -24.651656) (xy 195.051125 -24.684981) (xy 195.006355 -24.712426) (xy 194.958246 -24.733475)
			(xy 194.907704 -24.747728) (xy 194.855686 -24.754918) (xy 194.82943 -24.755348) (xy 194.802176 -24.754864)
			(xy 194.748223 -24.747111) (xy 194.695923 -24.731759) (xy 194.646339 -24.70912) (xy 194.600482 -24.679656)
			(xy 194.559285 -24.643965) (xy 194.523586 -24.602774) (xy 194.494113 -24.556922) (xy 194.471465 -24.507343)
			(xy 194.456103 -24.455045) (xy 194.448341 -24.401094) (xy 194.447922 -24.37384) (xy 194.448362 -24.347586)
			(xy 194.455564 -24.295573) (xy 194.469825 -24.245038) (xy 194.490875 -24.196933) (xy 194.518318 -24.152166)
			(xy 194.551635 -24.111581) (xy 194.570604 -24.093424) (xy 194.580344 -24.083857) (xy 194.594796 -24.060707)
			(xy 194.602587 -24.034552) (xy 194.603157 -24.007267) (xy 194.596466 -23.980809) (xy 194.582993 -23.957076)
			(xy 194.573652 -23.94712) (xy 190.91148 -20.284948) (xy 184.285128 -20.284948) (xy 184.285128 -20.340828)
			(xy 184.284615 -20.365811) (xy 184.276762 -20.415158) (xy 184.2613 -20.462673) (xy 184.238608 -20.507191)
			(xy 184.209243 -20.547619) (xy 184.19191 -20.565618) (xy 183.40578 -21.351748) (xy 185.246262 -21.351748)
			(xy 185.250333 -21.296126) (xy 185.262459 -21.241689) (xy 185.282382 -21.189598) (xy 185.309678 -21.140963)
			(xy 185.343764 -21.09682) (xy 185.383913 -21.058111) (xy 185.429271 -21.02566) (xy 185.478871 -21.000159)
			(xy 185.531655 -20.982152) (xy 185.586498 -20.972022) (xy 185.642232 -20.969985) (xy 185.697669 -20.976085)
			(xy 185.751626 -20.990191) (xy 185.802955 -21.012003) (xy 185.850561 -21.041057) (xy 185.893429 -21.076732)
			(xy 185.930646 -21.118269) (xy 185.961419 -21.164782) (xy 185.985091 -21.215279) (xy 186.001159 -21.268686)
			(xy 186.009279 -21.323862) (xy 186.009788 -21.351748) (xy 186.009279 -21.379634) (xy 186.001159 -21.43481)
			(xy 185.985091 -21.488217) (xy 185.961419 -21.538714) (xy 185.930646 -21.585227) (xy 185.893429 -21.626764)
			(xy 185.850561 -21.662439) (xy 185.802955 -21.691493) (xy 185.751626 -21.713305) (xy 185.697669 -21.727411)
			(xy 185.642232 -21.733511) (xy 185.586498 -21.731474) (xy 185.531655 -21.721344) (xy 185.478871 -21.703337)
			(xy 185.429271 -21.677836) (xy 185.383913 -21.645385) (xy 185.343764 -21.606676) (xy 185.309678 -21.562533)
			(xy 185.282382 -21.513898) (xy 185.262459 -21.461807) (xy 185.250333 -21.40737) (xy 185.246262 -21.351748)
			(xy 183.40578 -21.351748) (xy 183.025796 -21.731732) (xy 183.02224 -21.745702) (xy 183.015143 -21.773108)
			(xy 182.993954 -21.825604) (xy 182.965234 -21.874389) (xy 182.929613 -21.918388) (xy 182.887876 -21.956635)
			(xy 182.840941 -21.988287) (xy 182.78984 -22.012649) (xy 182.735698 -22.029184) (xy 182.679706 -22.037528)
			(xy 182.6514 -22.038056) (xy 182.624148 -22.03757) (xy 182.570197 -22.029814) (xy 182.5179 -22.014459)
			(xy 182.468319 -21.991819) (xy 182.422466 -21.962353) (xy 182.381271 -21.926663) (xy 182.345575 -21.885473)
			(xy 182.316104 -21.839623) (xy 182.293457 -21.790045) (xy 182.278096 -21.73775) (xy 182.270333 -21.6838)
			(xy 182.269892 -21.656548) (xy 182.270411 -21.628244) (xy 182.278783 -21.572259) (xy 182.295336 -21.518126)
			(xy 182.319706 -21.467033) (xy 182.351358 -21.420101) (xy 182.389597 -21.378362) (xy 182.433585 -21.342732)
			(xy 182.482354 -21.313992) (xy 182.534835 -21.292774) (xy 182.562246 -21.285708) (xy 182.576216 -21.282152)
			(xy 183.399938 -20.45843) (xy 183.410153 -20.447464) (xy 183.424278 -20.42105) (xy 183.430136 -20.391675)
			(xy 183.427222 -20.361863) (xy 183.415787 -20.334178) (xy 183.396814 -20.310999) (xy 183.371934 -20.29432)
			(xy 183.343286 -20.285573) (xy 183.32831 -20.284948) (xy 181.359048 -20.284948) (xy 181.353968 -20.329652)
			(xy 181.350223 -20.357145) (xy 181.335811 -20.410727) (xy 181.313791 -20.461656) (xy 181.284627 -20.508858)
			(xy 181.248935 -20.55134) (xy 181.207466 -20.588205) (xy 181.161096 -20.618675) (xy 181.110801 -20.642108)
			(xy 181.057643 -20.65801) (xy 181.002743 -20.666046) (xy 180.947257 -20.666046) (xy 180.892357 -20.65801)
			(xy 180.839199 -20.642108) (xy 180.788904 -20.618675) (xy 180.742534 -20.588205) (xy 180.701065 -20.55134)
			(xy 180.665373 -20.508858) (xy 180.636209 -20.461656) (xy 180.614189 -20.410727) (xy 180.599777 -20.357145)
			(xy 180.596032 -20.329652) (xy 180.590952 -20.284948) (xy 180.39588 -20.284948) (xy 179.22748 -19.116548)
			(xy 178.296316 -19.116548) (xy 178.284124 -19.149314) (xy 178.274098 -19.174594) (xy 178.247915 -19.222258)
			(xy 178.21523 -19.265722) (xy 178.176705 -19.304105) (xy 178.13312 -19.336629) (xy 178.085359 -19.362635)
			(xy 178.03439 -19.381597) (xy 177.981244 -19.39313) (xy 177.927 -19.397) (xy 177.872756 -19.39313)
			(xy 177.81961 -19.381597) (xy 177.768641 -19.362635) (xy 177.72088 -19.336629) (xy 177.677295 -19.304105)
			(xy 177.63877 -19.265722) (xy 177.606085 -19.222258) (xy 177.579902 -19.174594) (xy 177.569876 -19.149314)
			(xy 177.557684 -19.116548) (xy 176.73828 -19.116548) (xy 175.54448 -20.310348) (xy 175.54448 -21.121953)
			(xy 177.607155 -21.121953) (xy 177.607155 -21.067447) (xy 177.614913 -21.013494) (xy 177.630269 -20.961195)
			(xy 177.652913 -20.911614) (xy 177.682382 -20.865761) (xy 177.718077 -20.824568) (xy 177.759272 -20.788874)
			(xy 177.805127 -20.759406) (xy 177.854709 -20.736765) (xy 177.907008 -20.72141) (xy 177.96096 -20.713654)
			(xy 177.988214 -20.713192) (xy 178.01495 -20.713723) (xy 178.067896 -20.721205) (xy 178.119278 -20.736006)
			(xy 178.168091 -20.757837) (xy 178.213377 -20.786269) (xy 178.25425 -20.820747) (xy 178.289908 -20.860593)
			(xy 178.319653 -20.905028) (xy 178.342903 -20.953181) (xy 178.359201 -21.004109) (xy 178.368229 -21.056813)
			(xy 178.369468 -21.083524) (xy 178.370391 -21.09818) (xy 178.37959 -21.126055) (xy 178.396329 -21.150169)
			(xy 178.419228 -21.168535) (xy 178.446401 -21.179639) (xy 178.475609 -21.182567) (xy 178.490118 -21.180298)
			(xy 178.507917 -21.177104) (xy 178.543918 -21.173667) (xy 178.562 -21.17344) (xy 178.5885 -21.173845)
			(xy 178.640991 -21.181169) (xy 178.691963 -21.19569) (xy 178.740433 -21.217129) (xy 178.785467 -21.245073)
			(xy 178.826199 -21.278982) (xy 178.861844 -21.318205) (xy 178.891715 -21.361985) (xy 178.903884 -21.38553)
			(xy 178.911077 -21.398787) (xy 178.931754 -21.420723) (xy 178.957923 -21.435686) (xy 178.987316 -21.442379)
			(xy 179.017384 -21.44022) (xy 179.031646 -21.435314) (xy 179.053625 -21.42716) (xy 179.099093 -21.41574)
			(xy 179.14562 -21.409997) (xy 179.16906 -21.40966) (xy 179.196312 -21.410185) (xy 179.250263 -21.417936)
			(xy 179.302561 -21.433288) (xy 179.352142 -21.455926) (xy 179.397997 -21.48539) (xy 179.439191 -21.521081)
			(xy 179.474886 -21.562271) (xy 179.504355 -21.608122) (xy 179.526998 -21.657701) (xy 179.542355 -21.709998)
			(xy 179.550113 -21.763948) (xy 179.550113 -21.818452) (xy 179.542355 -21.872402) (xy 179.526998 -21.924699)
			(xy 179.504355 -21.974278) (xy 179.474886 -22.020129) (xy 179.439191 -22.061319) (xy 179.397997 -22.09701)
			(xy 179.352142 -22.126474) (xy 179.302561 -22.149112) (xy 179.250263 -22.164464) (xy 179.196312 -22.172215)
			(xy 179.16906 -22.172676) (xy 179.142562 -22.172213) (xy 179.090074 -22.164897) (xy 179.039104 -22.150384)
			(xy 178.990635 -22.128954) (xy 178.9456 -22.101018) (xy 178.904867 -22.067116) (xy 178.86922 -22.027901)
			(xy 178.839346 -21.984128) (xy 178.827176 -21.960586) (xy 178.820019 -21.947307) (xy 178.799334 -21.925367)
			(xy 178.773155 -21.910406) (xy 178.743752 -21.903719) (xy 178.713678 -21.905889) (xy 178.699414 -21.910802)
			(xy 178.67743 -21.918939) (xy 178.631964 -21.930365) (xy 178.58544 -21.936116) (xy 178.562 -21.936456)
			(xy 178.53526 -21.936056) (xy 178.482307 -21.928561) (xy 178.430919 -21.913746) (xy 178.382102 -21.891902)
			(xy 178.336814 -21.863456) (xy 178.295941 -21.828965) (xy 178.260284 -21.789105) (xy 178.230541 -21.744658)
			(xy 178.207296 -21.696493) (xy 178.191003 -21.645554) (xy 178.181982 -21.59284) (xy 178.180746 -21.566124)
			(xy 178.179768 -21.551473) (xy 178.170582 -21.523601) (xy 178.153855 -21.499487) (xy 178.130966 -21.48112)
			(xy 178.103802 -21.470013) (xy 178.074601 -21.467083) (xy 178.060096 -21.46935) (xy 178.042297 -21.472543)
			(xy 178.006296 -21.475981) (xy 177.988214 -21.476208) (xy 177.96096 -21.475746) (xy 177.907008 -21.46799)
			(xy 177.854709 -21.452635) (xy 177.805127 -21.429994) (xy 177.759272 -21.400526) (xy 177.718077 -21.364832)
			(xy 177.682382 -21.323639) (xy 177.652913 -21.277786) (xy 177.630269 -21.228205) (xy 177.614913 -21.175906)
			(xy 177.607155 -21.121953) (xy 175.54448 -21.121953) (xy 175.54448 -23.109936) (xy 184.407554 -23.109936)
			(xy 184.411625 -23.054314) (xy 184.423751 -22.999877) (xy 184.443674 -22.947786) (xy 184.47097 -22.899151)
			(xy 184.505056 -22.855008) (xy 184.545205 -22.816299) (xy 184.590563 -22.783848) (xy 184.640163 -22.758347)
			(xy 184.692947 -22.74034) (xy 184.74779 -22.73021) (xy 184.803524 -22.728173) (xy 184.858961 -22.734273)
			(xy 184.912918 -22.748379) (xy 184.964247 -22.770191) (xy 185.011853 -22.799245) (xy 185.054721 -22.83492)
			(xy 185.091938 -22.876457) (xy 185.122711 -22.92297) (xy 185.146383 -22.973467) (xy 185.162451 -23.026874)
			(xy 185.170571 -23.08205) (xy 185.17108 -23.109936) (xy 185.170765 -23.127208) (xy 187.533024 -23.127208)
			(xy 187.537095 -23.071586) (xy 187.549221 -23.017149) (xy 187.569144 -22.965058) (xy 187.59644 -22.916423)
			(xy 187.630526 -22.87228) (xy 187.670675 -22.833571) (xy 187.716033 -22.80112) (xy 187.765633 -22.775619)
			(xy 187.818417 -22.757612) (xy 187.87326 -22.747482) (xy 187.928994 -22.745445) (xy 187.984431 -22.751545)
			(xy 188.038388 -22.765651) (xy 188.089717 -22.787463) (xy 188.137323 -22.816517) (xy 188.180191 -22.852192)
			(xy 188.217408 -22.893729) (xy 188.248181 -22.940242) (xy 188.271853 -22.990739) (xy 188.287921 -23.044146)
			(xy 188.296041 -23.099322) (xy 188.29655 -23.127208) (xy 188.296041 -23.155094) (xy 188.287921 -23.21027)
			(xy 188.271853 -23.263677) (xy 188.248181 -23.314174) (xy 188.217408 -23.360687) (xy 188.180191 -23.402224)
			(xy 188.137323 -23.437899) (xy 188.089717 -23.466953) (xy 188.038388 -23.488765) (xy 187.984431 -23.502871)
			(xy 187.928994 -23.508971) (xy 187.87326 -23.506934) (xy 187.818417 -23.496804) (xy 187.765633 -23.478797)
			(xy 187.716033 -23.453296) (xy 187.670675 -23.420845) (xy 187.630526 -23.382136) (xy 187.59644 -23.337993)
			(xy 187.569144 -23.289358) (xy 187.549221 -23.237267) (xy 187.537095 -23.18283) (xy 187.533024 -23.127208)
			(xy 185.170765 -23.127208) (xy 185.170571 -23.137822) (xy 185.162451 -23.192998) (xy 185.146383 -23.246405)
			(xy 185.122711 -23.296902) (xy 185.091938 -23.343415) (xy 185.054721 -23.384952) (xy 185.011853 -23.420627)
			(xy 184.964247 -23.449681) (xy 184.912918 -23.471493) (xy 184.858961 -23.485599) (xy 184.803524 -23.491699)
			(xy 184.74779 -23.489662) (xy 184.692947 -23.479532) (xy 184.640163 -23.461525) (xy 184.590563 -23.436024)
			(xy 184.545205 -23.403573) (xy 184.505056 -23.364864) (xy 184.47097 -23.320721) (xy 184.443674 -23.272086)
			(xy 184.423751 -23.219995) (xy 184.411625 -23.165558) (xy 184.407554 -23.109936) (xy 175.54448 -23.109936)
			(xy 175.54448 -23.510748) (xy 191.982342 -23.510748) (xy 191.986413 -23.455126) (xy 191.998539 -23.400689)
			(xy 192.018462 -23.348598) (xy 192.045758 -23.299963) (xy 192.079844 -23.25582) (xy 192.119993 -23.217111)
			(xy 192.165351 -23.18466) (xy 192.214951 -23.159159) (xy 192.267735 -23.141152) (xy 192.322578 -23.131022)
			(xy 192.378312 -23.128985) (xy 192.433749 -23.135085) (xy 192.487706 -23.149191) (xy 192.539035 -23.171003)
			(xy 192.586641 -23.200057) (xy 192.629509 -23.235732) (xy 192.666726 -23.277269) (xy 192.697499 -23.323782)
			(xy 192.721171 -23.374279) (xy 192.737239 -23.427686) (xy 192.745359 -23.482862) (xy 192.745868 -23.510748)
			(xy 192.745359 -23.538634) (xy 192.737239 -23.59381) (xy 192.721171 -23.647217) (xy 192.697499 -23.697714)
			(xy 192.666726 -23.744227) (xy 192.629509 -23.785764) (xy 192.586641 -23.821439) (xy 192.539035 -23.850493)
			(xy 192.487706 -23.872305) (xy 192.433749 -23.886411) (xy 192.378312 -23.892511) (xy 192.322578 -23.890474)
			(xy 192.267735 -23.880344) (xy 192.214951 -23.862337) (xy 192.165351 -23.836836) (xy 192.119993 -23.804385)
			(xy 192.079844 -23.765676) (xy 192.045758 -23.721533) (xy 192.018462 -23.672898) (xy 191.998539 -23.620807)
			(xy 191.986413 -23.56637) (xy 191.982342 -23.510748) (xy 175.54448 -23.510748) (xy 175.54448 -24.126952)
			(xy 186.503562 -24.126952) (xy 186.507633 -24.07133) (xy 186.519759 -24.016893) (xy 186.539682 -23.964802)
			(xy 186.566978 -23.916167) (xy 186.601064 -23.872024) (xy 186.641213 -23.833315) (xy 186.686571 -23.800864)
			(xy 186.736171 -23.775363) (xy 186.788955 -23.757356) (xy 186.843798 -23.747226) (xy 186.899532 -23.745189)
			(xy 186.954969 -23.751289) (xy 187.008926 -23.765395) (xy 187.060255 -23.787207) (xy 187.107861 -23.816261)
			(xy 187.150729 -23.851936) (xy 187.187946 -23.893473) (xy 187.218719 -23.939986) (xy 187.242391 -23.990483)
			(xy 187.256244 -24.036528) (xy 188.856872 -24.036528) (xy 188.860943 -23.980906) (xy 188.873069 -23.926469)
			(xy 188.892992 -23.874378) (xy 188.920288 -23.825743) (xy 188.954374 -23.7816) (xy 188.994523 -23.742891)
			(xy 189.039881 -23.71044) (xy 189.089481 -23.684939) (xy 189.142265 -23.666932) (xy 189.197108 -23.656802)
			(xy 189.252842 -23.654765) (xy 189.308279 -23.660865) (xy 189.362236 -23.674971) (xy 189.413565 -23.696783)
			(xy 189.461171 -23.725837) (xy 189.504039 -23.761512) (xy 189.541256 -23.803049) (xy 189.572029 -23.849562)
			(xy 189.595701 -23.900059) (xy 189.611769 -23.953466) (xy 189.619889 -24.008642) (xy 189.620398 -24.036528)
			(xy 189.619889 -24.064414) (xy 189.611769 -24.11959) (xy 189.595701 -24.172997) (xy 189.572029 -24.223494)
			(xy 189.541256 -24.270007) (xy 189.504039 -24.311544) (xy 189.461171 -24.347219) (xy 189.413565 -24.376273)
			(xy 189.362236 -24.398085) (xy 189.308279 -24.412191) (xy 189.252842 -24.418291) (xy 189.197108 -24.416254)
			(xy 189.142265 -24.406124) (xy 189.089481 -24.388117) (xy 189.039881 -24.362616) (xy 188.994523 -24.330165)
			(xy 188.954374 -24.291456) (xy 188.920288 -24.247313) (xy 188.892992 -24.198678) (xy 188.873069 -24.146587)
			(xy 188.860943 -24.09215) (xy 188.856872 -24.036528) (xy 187.256244 -24.036528) (xy 187.258459 -24.04389)
			(xy 187.266579 -24.099066) (xy 187.267088 -24.126952) (xy 187.266579 -24.154838) (xy 187.258459 -24.210014)
			(xy 187.242391 -24.263421) (xy 187.218719 -24.313918) (xy 187.187946 -24.360431) (xy 187.150729 -24.401968)
			(xy 187.107861 -24.437643) (xy 187.060255 -24.466697) (xy 187.008926 -24.488509) (xy 186.954969 -24.502615)
			(xy 186.899532 -24.508715) (xy 186.843798 -24.506678) (xy 186.788955 -24.496548) (xy 186.736171 -24.478541)
			(xy 186.686571 -24.45304) (xy 186.641213 -24.420589) (xy 186.601064 -24.38188) (xy 186.566978 -24.337737)
			(xy 186.539682 -24.289102) (xy 186.519759 -24.237011) (xy 186.507633 -24.182574) (xy 186.503562 -24.126952)
			(xy 175.54448 -24.126952) (xy 175.54448 -24.906732) (xy 184.535824 -24.906732) (xy 184.539895 -24.85111)
			(xy 184.552021 -24.796673) (xy 184.571944 -24.744582) (xy 184.59924 -24.695947) (xy 184.633326 -24.651804)
			(xy 184.673475 -24.613095) (xy 184.718833 -24.580644) (xy 184.768433 -24.555143) (xy 184.821217 -24.537136)
			(xy 184.87606 -24.527006) (xy 184.931794 -24.524969) (xy 184.987231 -24.531069) (xy 185.041188 -24.545175)
			(xy 185.092517 -24.566987) (xy 185.140123 -24.596041) (xy 185.182991 -24.631716) (xy 185.220208 -24.673253)
			(xy 185.228674 -24.686049) (xy 191.338206 -24.686049) (xy 191.338206 -24.631551) (xy 191.345962 -24.577607)
			(xy 191.361316 -24.525316) (xy 191.383956 -24.475743) (xy 191.41342 -24.429896) (xy 191.449109 -24.388709)
			(xy 191.490296 -24.35302) (xy 191.536143 -24.323556) (xy 191.585716 -24.300916) (xy 191.638007 -24.285562)
			(xy 191.691951 -24.277806) (xy 191.7192 -24.27732) (xy 191.744806 -24.277739) (xy 191.795561 -24.284561)
			(xy 191.844948 -24.298108) (xy 191.892081 -24.318138) (xy 191.936111 -24.344291) (xy 191.956436 -24.35987)
			(xy 191.968626 -24.368901) (xy 191.996881 -24.379922) (xy 192.027124 -24.38217) (xy 192.056698 -24.375449)
			(xy 192.082999 -24.360349) (xy 192.103714 -24.3382) (xy 192.110868 -24.324818) (xy 192.122938 -24.301012)
			(xy 192.152705 -24.256709) (xy 192.188359 -24.216989) (xy 192.229202 -24.182629) (xy 192.274438 -24.1543)
			(xy 192.323182 -24.132555) (xy 192.374481 -24.117818) (xy 192.427335 -24.110379) (xy 192.454022 -24.109934)
			(xy 192.481275 -24.110337) (xy 192.535227 -24.118097) (xy 192.587524 -24.133456) (xy 192.637104 -24.156101)
			(xy 192.682957 -24.185571) (xy 192.724149 -24.221266) (xy 192.759842 -24.262461) (xy 192.78931 -24.308315)
			(xy 192.811952 -24.357896) (xy 192.827307 -24.410195) (xy 192.835064 -24.464147) (xy 192.835064 -24.518653)
			(xy 192.827307 -24.572605) (xy 192.811952 -24.624904) (xy 192.78931 -24.674485) (xy 192.759842 -24.720339)
			(xy 192.724149 -24.761534) (xy 192.682957 -24.797229) (xy 192.637104 -24.826699) (xy 192.587524 -24.849344)
			(xy 192.535227 -24.864703) (xy 192.481275 -24.872463) (xy 192.454022 -24.87295) (xy 192.428416 -24.872525)
			(xy 192.377661 -24.865706) (xy 192.328273 -24.85216) (xy 192.281141 -24.832131) (xy 192.237111 -24.805979)
			(xy 192.216786 -24.7904) (xy 192.204572 -24.781406) (xy 192.176326 -24.770387) (xy 192.146091 -24.768136)
			(xy 192.116524 -24.77485) (xy 192.090227 -24.789939) (xy 192.069511 -24.812077) (xy 192.062354 -24.825452)
			(xy 192.050254 -24.849242) (xy 192.020492 -24.893546) (xy 191.984844 -24.933267) (xy 191.944005 -24.967629)
			(xy 191.898773 -24.99596) (xy 191.850033 -25.017708) (xy 191.798737 -25.032447) (xy 191.745886 -25.039889)
			(xy 191.7192 -25.040336) (xy 191.691951 -25.039794) (xy 191.638007 -25.032038) (xy 191.585716 -25.016684)
			(xy 191.536143 -24.994044) (xy 191.490296 -24.96458) (xy 191.449109 -24.928891) (xy 191.41342 -24.887704)
			(xy 191.383956 -24.841857) (xy 191.361316 -24.792284) (xy 191.345962 -24.739993) (xy 191.338206 -24.686049)
			(xy 185.228674 -24.686049) (xy 185.250981 -24.719766) (xy 185.274653 -24.770263) (xy 185.290721 -24.82367)
			(xy 185.298841 -24.878846) (xy 185.29935 -24.906732) (xy 185.298841 -24.934618) (xy 185.290721 -24.989794)
			(xy 185.274653 -25.043201) (xy 185.250981 -25.093698) (xy 185.239036 -25.111752) (xy 186.187787 -25.111752)
			(xy 186.187787 -25.057248) (xy 186.195545 -25.003297) (xy 186.210902 -24.951001) (xy 186.233545 -24.901422)
			(xy 186.263015 -24.855571) (xy 186.29871 -24.81438) (xy 186.339904 -24.77869) (xy 186.385759 -24.749225)
			(xy 186.43534 -24.726587) (xy 186.487639 -24.711236) (xy 186.541589 -24.703484) (xy 186.568842 -24.703024)
			(xy 186.59571 -24.703435) (xy 186.648915 -24.710969) (xy 186.700535 -24.725895) (xy 186.74955 -24.74792)
			(xy 186.794988 -24.776605) (xy 186.835951 -24.811385) (xy 186.871626 -24.851569) (xy 186.88685 -24.873712)
			(xy 186.894833 -24.885065) (xy 186.915799 -24.903239) (xy 186.940887 -24.915089) (xy 186.96824 -24.91974)
			(xy 186.995835 -24.916846) (xy 187.021629 -24.906623) (xy 187.043713 -24.889826) (xy 187.052458 -24.879046)
			(xy 187.070614 -24.856048) (xy 187.112791 -24.815376) (xy 187.16069 -24.78163) (xy 187.213185 -24.755603)
			(xy 187.269041 -24.737906) (xy 187.326946 -24.728955) (xy 187.356242 -24.728424) (xy 187.383496 -24.728839)
			(xy 187.437448 -24.736602) (xy 187.489746 -24.751964) (xy 187.539325 -24.774612) (xy 187.585177 -24.804086)
			(xy 187.626368 -24.839785) (xy 187.662058 -24.880982) (xy 187.691523 -24.92684) (xy 187.714162 -24.976424)
			(xy 187.729514 -25.028725) (xy 187.737266 -25.082678) (xy 187.73775 -25.109932) (xy 187.737215 -25.138492)
			(xy 187.728715 -25.194976) (xy 187.711882 -25.249559) (xy 187.687091 -25.301018) (xy 187.654898 -25.348201)
			(xy 187.616024 -25.390052) (xy 187.57134 -25.425632) (xy 187.521846 -25.454146) (xy 187.495434 -25.465024)
			(xy 187.481627 -25.470993) (xy 187.458057 -25.489659) (xy 187.440926 -25.514368) (xy 187.431714 -25.542989)
			(xy 187.431335 -25.565862) (xy 192.072004 -25.565862) (xy 192.076075 -25.51024) (xy 192.088201 -25.455803)
			(xy 192.108124 -25.403712) (xy 192.13542 -25.355077) (xy 192.169506 -25.310934) (xy 192.209655 -25.272225)
			(xy 192.255013 -25.239774) (xy 192.304613 -25.214273) (xy 192.357397 -25.196266) (xy 192.41224 -25.186136)
			(xy 192.467974 -25.184099) (xy 192.523411 -25.190199) (xy 192.577368 -25.204305) (xy 192.628697 -25.226117)
			(xy 192.676303 -25.255171) (xy 192.719171 -25.290846) (xy 192.756388 -25.332383) (xy 192.787161 -25.378896)
			(xy 192.792172 -25.389586) (xy 194.451476 -25.389586) (xy 194.455547 -25.333964) (xy 194.467673 -25.279527)
			(xy 194.487596 -25.227436) (xy 194.514892 -25.178801) (xy 194.548978 -25.134658) (xy 194.589127 -25.095949)
			(xy 194.634485 -25.063498) (xy 194.684085 -25.037997) (xy 194.736869 -25.01999) (xy 194.791712 -25.00986)
			(xy 194.847446 -25.007823) (xy 194.902883 -25.013923) (xy 194.95684 -25.028029) (xy 195.008169 -25.049841)
			(xy 195.055775 -25.078895) (xy 195.098643 -25.11457) (xy 195.13586 -25.156107) (xy 195.166633 -25.20262)
			(xy 195.190305 -25.253117) (xy 195.206373 -25.306524) (xy 195.214493 -25.3617) (xy 195.215002 -25.389586)
			(xy 195.214493 -25.417472) (xy 195.206373 -25.472648) (xy 195.190305 -25.526055) (xy 195.166633 -25.576552)
			(xy 195.13586 -25.623065) (xy 195.098643 -25.664602) (xy 195.055775 -25.700277) (xy 195.008169 -25.729331)
			(xy 194.95684 -25.751143) (xy 194.902883 -25.765249) (xy 194.847446 -25.771349) (xy 194.791712 -25.769312)
			(xy 194.736869 -25.759182) (xy 194.684085 -25.741175) (xy 194.634485 -25.715674) (xy 194.589127 -25.683223)
			(xy 194.548978 -25.644514) (xy 194.514892 -25.600371) (xy 194.487596 -25.551736) (xy 194.467673 -25.499645)
			(xy 194.455547 -25.445208) (xy 194.451476 -25.389586) (xy 192.792172 -25.389586) (xy 192.810833 -25.429393)
			(xy 192.826901 -25.4828) (xy 192.835021 -25.537976) (xy 192.83553 -25.565862) (xy 192.835021 -25.593748)
			(xy 192.826901 -25.648924) (xy 192.810833 -25.702331) (xy 192.787161 -25.752828) (xy 192.756388 -25.799341)
			(xy 192.719171 -25.840878) (xy 192.676303 -25.876553) (xy 192.628697 -25.905607) (xy 192.577368 -25.927419)
			(xy 192.523411 -25.941525) (xy 192.467974 -25.947625) (xy 192.41224 -25.945588) (xy 192.357397 -25.935458)
			(xy 192.304613 -25.917451) (xy 192.255013 -25.89195) (xy 192.209655 -25.859499) (xy 192.169506 -25.82079)
			(xy 192.13542 -25.776647) (xy 192.108124 -25.728012) (xy 192.088201 -25.675921) (xy 192.076075 -25.621484)
			(xy 192.072004 -25.565862) (xy 187.431335 -25.565862) (xy 187.431216 -25.573051) (xy 187.439473 -25.601962)
			(xy 187.447174 -25.614884) (xy 187.461683 -25.638136) (xy 187.484563 -25.687938) (xy 187.500081 -25.740501)
			(xy 187.507917 -25.794745) (xy 187.508388 -25.822148) (xy 187.507902 -25.849399) (xy 187.500146 -25.903347)
			(xy 187.484791 -25.955642) (xy 187.462149 -26.005219) (xy 187.432683 -26.051069) (xy 187.396992 -26.09226)
			(xy 187.355801 -26.127951) (xy 187.309951 -26.157417) (xy 187.260374 -26.180059) (xy 187.208079 -26.195414)
			(xy 187.154131 -26.20317) (xy 187.099629 -26.20317) (xy 187.045681 -26.195414) (xy 186.993386 -26.180059)
			(xy 186.943809 -26.157417) (xy 186.897959 -26.127951) (xy 186.856768 -26.09226) (xy 186.821077 -26.051069)
			(xy 186.791611 -26.005219) (xy 186.768969 -25.955642) (xy 186.753614 -25.903347) (xy 186.745858 -25.849399)
			(xy 186.745372 -25.822148) (xy 186.745876 -25.793587) (xy 186.754379 -25.737101) (xy 186.771217 -25.682517)
			(xy 186.796012 -25.631056) (xy 186.828209 -25.583873) (xy 186.867087 -25.542023) (xy 186.911776 -25.506444)
			(xy 186.961274 -25.477933) (xy 186.987688 -25.467056) (xy 187.001447 -25.460992) (xy 187.025007 -25.442343)
			(xy 187.042134 -25.417655) (xy 187.051352 -25.389056) (xy 187.051867 -25.359013) (xy 187.043634 -25.330116)
			(xy 187.035948 -25.317196) (xy 187.026658 -25.302503) (xy 187.010508 -25.271718) (xy 187.00369 -25.255728)
			(xy 186.99951 -25.246922) (xy 186.985892 -25.233007) (xy 186.968062 -25.225187) (xy 186.948601 -25.224593)
			(xy 186.930327 -25.231312) (xy 186.915886 -25.244372) (xy 186.911234 -25.252934) (xy 186.899117 -25.276582)
			(xy 186.869258 -25.320534) (xy 186.833591 -25.359921) (xy 186.792807 -25.393981) (xy 186.747693 -25.422055)
			(xy 186.699122 -25.443602) (xy 186.648031 -25.458203) (xy 186.59541 -25.465579) (xy 186.568842 -25.46604)
			(xy 186.541589 -25.465516) (xy 186.487639 -25.457764) (xy 186.43534 -25.442413) (xy 186.385759 -25.419775)
			(xy 186.339904 -25.39031) (xy 186.29871 -25.35462) (xy 186.263015 -25.313429) (xy 186.233545 -25.267578)
			(xy 186.210902 -25.217999) (xy 186.195545 -25.165703) (xy 186.187787 -25.111752) (xy 185.239036 -25.111752)
			(xy 185.220208 -25.140211) (xy 185.182991 -25.181748) (xy 185.140123 -25.217423) (xy 185.092517 -25.246477)
			(xy 185.041188 -25.268289) (xy 184.987231 -25.282395) (xy 184.931794 -25.288495) (xy 184.87606 -25.286458)
			(xy 184.821217 -25.276328) (xy 184.768433 -25.258321) (xy 184.718833 -25.23282) (xy 184.673475 -25.200369)
			(xy 184.633326 -25.16166) (xy 184.59924 -25.117517) (xy 184.571944 -25.068882) (xy 184.552021 -25.016791)
			(xy 184.539895 -24.962354) (xy 184.535824 -24.906732) (xy 175.54448 -24.906732) (xy 175.54448 -26.240232)
			(xy 180.575964 -26.240232) (xy 180.580035 -26.18461) (xy 180.592161 -26.130173) (xy 180.612084 -26.078082)
			(xy 180.63938 -26.029447) (xy 180.673466 -25.985304) (xy 180.713615 -25.946595) (xy 180.758973 -25.914144)
			(xy 180.808573 -25.888643) (xy 180.861357 -25.870636) (xy 180.9162 -25.860506) (xy 180.971934 -25.858469)
			(xy 181.027371 -25.864569) (xy 181.081328 -25.878675) (xy 181.13121 -25.899872) (xy 184.537094 -25.899872)
			(xy 184.541165 -25.84425) (xy 184.553291 -25.789813) (xy 184.573214 -25.737722) (xy 184.60051 -25.689087)
			(xy 184.634596 -25.644944) (xy 184.674745 -25.606235) (xy 184.720103 -25.573784) (xy 184.769703 -25.548283)
			(xy 184.822487 -25.530276) (xy 184.87733 -25.520146) (xy 184.933064 -25.518109) (xy 184.988501 -25.524209)
			(xy 185.042458 -25.538315) (xy 185.093787 -25.560127) (xy 185.141393 -25.589181) (xy 185.184261 -25.624856)
			(xy 185.221478 -25.666393) (xy 185.252251 -25.712906) (xy 185.275923 -25.763403) (xy 185.291991 -25.81681)
			(xy 185.300111 -25.871986) (xy 185.30062 -25.899872) (xy 185.300111 -25.927758) (xy 185.291991 -25.982934)
			(xy 185.275923 -26.036341) (xy 185.252251 -26.086838) (xy 185.221478 -26.133351) (xy 185.184261 -26.174888)
			(xy 185.141393 -26.210563) (xy 185.093787 -26.239617) (xy 185.042458 -26.261429) (xy 184.988501 -26.275535)
			(xy 184.933064 -26.281635) (xy 184.87733 -26.279598) (xy 184.822487 -26.269468) (xy 184.769703 -26.251461)
			(xy 184.720103 -26.22596) (xy 184.674745 -26.193509) (xy 184.634596 -26.1548) (xy 184.60051 -26.110657)
			(xy 184.573214 -26.062022) (xy 184.553291 -26.009931) (xy 184.541165 -25.955494) (xy 184.537094 -25.899872)
			(xy 181.13121 -25.899872) (xy 181.132657 -25.900487) (xy 181.180263 -25.929541) (xy 181.223131 -25.965216)
			(xy 181.260348 -26.006753) (xy 181.291121 -26.053266) (xy 181.314793 -26.103763) (xy 181.330861 -26.15717)
			(xy 181.338981 -26.212346) (xy 181.33949 -26.240232) (xy 181.338981 -26.268118) (xy 181.330861 -26.323294)
			(xy 181.314793 -26.376701) (xy 181.291121 -26.427198) (xy 181.260348 -26.473711) (xy 181.223131 -26.515248)
			(xy 181.180263 -26.550923) (xy 181.132657 -26.579977) (xy 181.081328 -26.601789) (xy 181.027371 -26.615895)
			(xy 180.971934 -26.621995) (xy 180.9162 -26.619958) (xy 180.861357 -26.609828) (xy 180.808573 -26.591821)
			(xy 180.758973 -26.56632) (xy 180.713615 -26.533869) (xy 180.673466 -26.49516) (xy 180.63938 -26.451017)
			(xy 180.612084 -26.402382) (xy 180.592161 -26.350291) (xy 180.580035 -26.295854) (xy 180.575964 -26.240232)
			(xy 175.54448 -26.240232) (xy 175.54448 -26.457148) (xy 176.40808 -27.320748) (xy 180.45176 -27.320748)
			(xy 180.467084 -27.320231) (xy 180.496357 -27.311154) (xy 180.521622 -27.293805) (xy 180.540605 -27.269743)
			(xy 180.551599 -27.241135) (xy 180.553615 -27.210553) (xy 180.550566 -27.195526) (xy 180.545698 -27.173817)
			(xy 180.540475 -27.129633) (xy 180.540152 -27.107388) (xy 180.540638 -27.080137) (xy 180.548394 -27.026189)
			(xy 180.563749 -26.973894) (xy 180.586391 -26.924317) (xy 180.615857 -26.878467) (xy 180.651548 -26.837276)
			(xy 180.692739 -26.801585) (xy 180.738589 -26.772119) (xy 180.788166 -26.749477) (xy 180.840461 -26.734122)
			(xy 180.894409 -26.726366) (xy 180.948911 -26.726366) (xy 181.002859 -26.734122) (xy 181.055154 -26.749477)
			(xy 181.104731 -26.772119) (xy 181.130799 -26.788872) (xy 184.537094 -26.788872) (xy 184.541165 -26.73325)
			(xy 184.553291 -26.678813) (xy 184.573214 -26.626722) (xy 184.60051 -26.578087) (xy 184.634596 -26.533944)
			(xy 184.674745 -26.495235) (xy 184.720103 -26.462784) (xy 184.769703 -26.437283) (xy 184.822487 -26.419276)
			(xy 184.87733 -26.409146) (xy 184.933064 -26.407109) (xy 184.988501 -26.413209) (xy 185.042458 -26.427315)
			(xy 185.093787 -26.449127) (xy 185.141393 -26.478181) (xy 185.184261 -26.513856) (xy 185.221478 -26.555393)
			(xy 185.252251 -26.601906) (xy 185.275923 -26.652403) (xy 185.291991 -26.70581) (xy 185.300111 -26.760986)
			(xy 185.30062 -26.788872) (xy 185.300111 -26.816758) (xy 185.291991 -26.871934) (xy 185.275923 -26.925341)
			(xy 185.252251 -26.975838) (xy 185.221478 -27.022351) (xy 185.184261 -27.063888) (xy 185.156407 -27.087068)
			(xy 190.295782 -27.087068) (xy 190.299853 -27.031446) (xy 190.311979 -26.977009) (xy 190.331902 -26.924918)
			(xy 190.359198 -26.876283) (xy 190.393284 -26.83214) (xy 190.433433 -26.793431) (xy 190.478791 -26.76098)
			(xy 190.528391 -26.735479) (xy 190.581175 -26.717472) (xy 190.636018 -26.707342) (xy 190.691752 -26.705305)
			(xy 190.747189 -26.711405) (xy 190.801146 -26.725511) (xy 190.852475 -26.747323) (xy 190.900081 -26.776377)
			(xy 190.942949 -26.812052) (xy 190.980166 -26.853589) (xy 191.010939 -26.900102) (xy 191.034611 -26.950599)
			(xy 191.050679 -27.004006) (xy 191.058799 -27.059182) (xy 191.059308 -27.087068) (xy 191.058799 -27.114954)
			(xy 191.050679 -27.17013) (xy 191.034611 -27.223537) (xy 191.010939 -27.274034) (xy 190.980166 -27.320547)
			(xy 190.942949 -27.362084) (xy 190.900081 -27.397759) (xy 190.852475 -27.426813) (xy 190.801146 -27.448625)
			(xy 190.747189 -27.462731) (xy 190.691752 -27.468831) (xy 190.636018 -27.466794) (xy 190.581175 -27.456664)
			(xy 190.528391 -27.438657) (xy 190.478791 -27.413156) (xy 190.433433 -27.380705) (xy 190.393284 -27.341996)
			(xy 190.359198 -27.297853) (xy 190.331902 -27.249218) (xy 190.311979 -27.197127) (xy 190.299853 -27.14269)
			(xy 190.295782 -27.087068) (xy 185.156407 -27.087068) (xy 185.141393 -27.099563) (xy 185.093787 -27.128617)
			(xy 185.042458 -27.150429) (xy 184.988501 -27.164535) (xy 184.933064 -27.170635) (xy 184.87733 -27.168598)
			(xy 184.822487 -27.158468) (xy 184.769703 -27.140461) (xy 184.720103 -27.11496) (xy 184.674745 -27.082509)
			(xy 184.634596 -27.0438) (xy 184.60051 -26.999657) (xy 184.573214 -26.951022) (xy 184.553291 -26.898931)
			(xy 184.541165 -26.844494) (xy 184.537094 -26.788872) (xy 181.130799 -26.788872) (xy 181.150581 -26.801585)
			(xy 181.191772 -26.837276) (xy 181.227463 -26.878467) (xy 181.256929 -26.924317) (xy 181.279571 -26.973894)
			(xy 181.294926 -27.026189) (xy 181.302682 -27.080137) (xy 181.303168 -27.107388) (xy 181.302814 -27.129632)
			(xy 181.297596 -27.173813) (xy 181.292754 -27.195526) (xy 181.289707 -27.210547) (xy 181.291747 -27.241116)
			(xy 181.302751 -27.269708) (xy 181.321731 -27.293758) (xy 181.346984 -27.311104) (xy 181.376242 -27.320192)
			(xy 181.39156 -27.320748) (xy 185.084466 -27.320748) (xy 185.099663 -27.298495) (xy 185.135322 -27.258097)
			(xy 185.176315 -27.223122) (xy 185.221824 -27.194267) (xy 185.270942 -27.172107) (xy 185.322691 -27.157084)
			(xy 185.376039 -27.149497) (xy 185.429925 -27.149497) (xy 185.483273 -27.157084) (xy 185.535022 -27.172107)
			(xy 185.58414 -27.194267) (xy 185.629649 -27.223122) (xy 185.670642 -27.258097) (xy 185.706301 -27.298495)
			(xy 185.721498 -27.320748) (xy 186.31408 -27.320748) (xy 186.6138 -27.620468) (xy 187.910214 -27.620468)
			(xy 187.914285 -27.564846) (xy 187.926411 -27.510409) (xy 187.946334 -27.458318) (xy 187.97363 -27.409683)
			(xy 188.007716 -27.36554) (xy 188.047865 -27.326831) (xy 188.093223 -27.29438) (xy 188.142823 -27.268879)
			(xy 188.195607 -27.250872) (xy 188.25045 -27.240742) (xy 188.306184 -27.238705) (xy 188.361621 -27.244805)
			(xy 188.415578 -27.258911) (xy 188.466907 -27.280723) (xy 188.514513 -27.309777) (xy 188.557381 -27.345452)
			(xy 188.594598 -27.386989) (xy 188.625371 -27.433502) (xy 188.649043 -27.483999) (xy 188.665111 -27.537406)
			(xy 188.67098 -27.577288) (xy 189.414402 -27.577288) (xy 189.418473 -27.521666) (xy 189.430599 -27.467229)
			(xy 189.450522 -27.415138) (xy 189.477818 -27.366503) (xy 189.511904 -27.32236) (xy 189.552053 -27.283651)
			(xy 189.597411 -27.2512) (xy 189.647011 -27.225699) (xy 189.699795 -27.207692) (xy 189.754638 -27.197562)
			(xy 189.810372 -27.195525) (xy 189.865809 -27.201625) (xy 189.919766 -27.215731) (xy 189.971095 -27.237543)
			(xy 190.018701 -27.266597) (xy 190.061569 -27.302272) (xy 190.098786 -27.343809) (xy 190.129559 -27.390322)
			(xy 190.153231 -27.440819) (xy 190.169299 -27.494226) (xy 190.170907 -27.505152) (xy 191.295274 -27.505152)
			(xy 191.295802 -27.476235) (xy 191.304525 -27.419063) (xy 191.321779 -27.363863) (xy 191.347169 -27.311901)
			(xy 191.380112 -27.264367) (xy 191.419854 -27.222351) (xy 191.44234 -27.204162) (xy 191.454198 -27.19432)
			(xy 191.471723 -27.168983) (xy 191.480898 -27.139574) (xy 191.480889 -27.108767) (xy 191.471697 -27.079363)
			(xy 191.454157 -27.054037) (xy 191.44234 -27.044142) (xy 191.419885 -27.025917) (xy 191.380146 -26.983906)
			(xy 191.347203 -26.936378) (xy 191.321809 -26.884423) (xy 191.304547 -26.829231) (xy 191.295812 -26.772066)
			(xy 191.295274 -26.743152) (xy 191.29576 -26.715901) (xy 191.303516 -26.661953) (xy 191.318871 -26.609658)
			(xy 191.341513 -26.560081) (xy 191.370979 -26.514231) (xy 191.40667 -26.47304) (xy 191.447861 -26.437349)
			(xy 191.493711 -26.407883) (xy 191.543288 -26.385241) (xy 191.595583 -26.369886) (xy 191.649531 -26.36213)
			(xy 191.704033 -26.36213) (xy 191.757981 -26.369886) (xy 191.810276 -26.385241) (xy 191.819229 -26.38933)
			(xy 195.016118 -26.38933) (xy 195.020189 -26.333708) (xy 195.032315 -26.279271) (xy 195.052238 -26.22718)
			(xy 195.079534 -26.178545) (xy 195.11362 -26.134402) (xy 195.153769 -26.095693) (xy 195.199127 -26.063242)
			(xy 195.248727 -26.037741) (xy 195.301511 -26.019734) (xy 195.356354 -26.009604) (xy 195.412088 -26.007567)
			(xy 195.467525 -26.013667) (xy 195.521482 -26.027773) (xy 195.572811 -26.049585) (xy 195.620417 -26.078639)
			(xy 195.663285 -26.114314) (xy 195.700502 -26.155851) (xy 195.731275 -26.202364) (xy 195.754947 -26.252861)
			(xy 195.771015 -26.306268) (xy 195.779135 -26.361444) (xy 195.779644 -26.38933) (xy 195.779135 -26.417216)
			(xy 195.771015 -26.472392) (xy 195.754947 -26.525799) (xy 195.731275 -26.576296) (xy 195.700502 -26.622809)
			(xy 195.663285 -26.664346) (xy 195.620417 -26.700021) (xy 195.572811 -26.729075) (xy 195.521482 -26.750887)
			(xy 195.467525 -26.764993) (xy 195.412088 -26.771093) (xy 195.356354 -26.769056) (xy 195.301511 -26.758926)
			(xy 195.248727 -26.740919) (xy 195.199127 -26.715418) (xy 195.153769 -26.682967) (xy 195.11362 -26.644258)
			(xy 195.079534 -26.600115) (xy 195.052238 -26.55148) (xy 195.032315 -26.499389) (xy 195.020189 -26.444952)
			(xy 195.016118 -26.38933) (xy 191.819229 -26.38933) (xy 191.859853 -26.407883) (xy 191.905703 -26.437349)
			(xy 191.946894 -26.47304) (xy 191.982585 -26.514231) (xy 192.012051 -26.560081) (xy 192.034693 -26.609658)
			(xy 192.050048 -26.661953) (xy 192.057804 -26.715901) (xy 192.05829 -26.743152) (xy 192.057741 -26.772068)
			(xy 192.049019 -26.829238) (xy 192.031767 -26.884436) (xy 192.006381 -26.936398) (xy 191.973443 -26.983933)
			(xy 191.933707 -27.025951) (xy 191.911224 -27.044142) (xy 191.899466 -27.054091) (xy 191.881945 -27.0794)
			(xy 191.872764 -27.10878) (xy 191.872755 -27.139561) (xy 191.881919 -27.168947) (xy 191.899425 -27.194265)
			(xy 191.911224 -27.204162) (xy 191.933694 -27.222368) (xy 191.973429 -27.264386) (xy 192.006369 -27.311918)
			(xy 192.031759 -27.363876) (xy 192.049019 -27.41907) (xy 192.050102 -27.426158) (xy 195.140832 -27.426158)
			(xy 195.144903 -27.370536) (xy 195.157029 -27.316099) (xy 195.176952 -27.264008) (xy 195.204248 -27.215373)
			(xy 195.238334 -27.17123) (xy 195.278483 -27.132521) (xy 195.323841 -27.10007) (xy 195.373441 -27.074569)
			(xy 195.426225 -27.056562) (xy 195.481068 -27.046432) (xy 195.536802 -27.044395) (xy 195.592239 -27.050495)
			(xy 195.646196 -27.064601) (xy 195.697525 -27.086413) (xy 195.745131 -27.115467) (xy 195.787999 -27.151142)
			(xy 195.825216 -27.192679) (xy 195.855989 -27.239192) (xy 195.879661 -27.289689) (xy 195.895729 -27.343096)
			(xy 195.903849 -27.398272) (xy 195.904358 -27.426158) (xy 195.903849 -27.454044) (xy 195.895729 -27.50922)
			(xy 195.879661 -27.562627) (xy 195.855989 -27.613124) (xy 195.825216 -27.659637) (xy 195.787999 -27.701174)
			(xy 195.745131 -27.736849) (xy 195.697525 -27.765903) (xy 195.646196 -27.787715) (xy 195.592239 -27.801821)
			(xy 195.536802 -27.807921) (xy 195.481068 -27.805884) (xy 195.426225 -27.795754) (xy 195.373441 -27.777747)
			(xy 195.323841 -27.752246) (xy 195.278483 -27.719795) (xy 195.238334 -27.681086) (xy 195.204248 -27.636943)
			(xy 195.176952 -27.588308) (xy 195.157029 -27.536217) (xy 195.144903 -27.48178) (xy 195.140832 -27.426158)
			(xy 192.050102 -27.426158) (xy 192.057752 -27.476237) (xy 192.05829 -27.505152) (xy 192.057804 -27.532403)
			(xy 192.050048 -27.586351) (xy 192.034693 -27.638646) (xy 192.012051 -27.688223) (xy 191.982585 -27.734073)
			(xy 191.946894 -27.775264) (xy 191.905703 -27.810955) (xy 191.859853 -27.840421) (xy 191.810276 -27.863063)
			(xy 191.757981 -27.878418) (xy 191.704033 -27.886174) (xy 191.649531 -27.886174) (xy 191.595583 -27.878418)
			(xy 191.543288 -27.863063) (xy 191.493711 -27.840421) (xy 191.447861 -27.810955) (xy 191.40667 -27.775264)
			(xy 191.370979 -27.734073) (xy 191.341513 -27.688223) (xy 191.318871 -27.638646) (xy 191.303516 -27.586351)
			(xy 191.29576 -27.532403) (xy 191.295274 -27.505152) (xy 190.170907 -27.505152) (xy 190.177419 -27.549402)
			(xy 190.177928 -27.577288) (xy 190.177419 -27.605174) (xy 190.169299 -27.66035) (xy 190.153231 -27.713757)
			(xy 190.129559 -27.764254) (xy 190.098786 -27.810767) (xy 190.061569 -27.852304) (xy 190.018701 -27.887979)
			(xy 189.971095 -27.917033) (xy 189.919766 -27.938845) (xy 189.865809 -27.952951) (xy 189.810372 -27.959051)
			(xy 189.754638 -27.957014) (xy 189.699795 -27.946884) (xy 189.647011 -27.928877) (xy 189.597411 -27.903376)
			(xy 189.552053 -27.870925) (xy 189.511904 -27.832216) (xy 189.477818 -27.788073) (xy 189.450522 -27.739438)
			(xy 189.430599 -27.687347) (xy 189.418473 -27.63291) (xy 189.414402 -27.577288) (xy 188.67098 -27.577288)
			(xy 188.673231 -27.592582) (xy 188.67374 -27.620468) (xy 188.673231 -27.648354) (xy 188.665111 -27.70353)
			(xy 188.649043 -27.756937) (xy 188.625371 -27.807434) (xy 188.594598 -27.853947) (xy 188.557381 -27.895484)
			(xy 188.514513 -27.931159) (xy 188.466907 -27.960213) (xy 188.415578 -27.982025) (xy 188.361621 -27.996131)
			(xy 188.306184 -28.002231) (xy 188.25045 -28.000194) (xy 188.195607 -27.990064) (xy 188.142823 -27.972057)
			(xy 188.093223 -27.946556) (xy 188.047865 -27.914105) (xy 188.007716 -27.875396) (xy 187.97363 -27.831253)
			(xy 187.946334 -27.782618) (xy 187.926411 -27.730527) (xy 187.914285 -27.67609) (xy 187.910214 -27.620468)
			(xy 186.6138 -27.620468) (xy 187.393072 -28.39974) (xy 192.757042 -28.39974) (xy 192.761113 -28.344118)
			(xy 192.773239 -28.289681) (xy 192.793162 -28.23759) (xy 192.820458 -28.188955) (xy 192.854544 -28.144812)
			(xy 192.894693 -28.106103) (xy 192.940051 -28.073652) (xy 192.989651 -28.048151) (xy 193.042435 -28.030144)
			(xy 193.097278 -28.020014) (xy 193.153012 -28.017977) (xy 193.208449 -28.024077) (xy 193.262406 -28.038183)
			(xy 193.313735 -28.059995) (xy 193.361341 -28.089049) (xy 193.404209 -28.124724) (xy 193.441426 -28.166261)
			(xy 193.472199 -28.212774) (xy 193.495871 -28.263271) (xy 193.511939 -28.316678) (xy 193.520059 -28.371854)
			(xy 193.520466 -28.394152) (xy 195.485256 -28.394152) (xy 195.489327 -28.33853) (xy 195.501453 -28.284093)
			(xy 195.521376 -28.232002) (xy 195.548672 -28.183367) (xy 195.582758 -28.139224) (xy 195.622907 -28.100515)
			(xy 195.668265 -28.068064) (xy 195.717865 -28.042563) (xy 195.770649 -28.024556) (xy 195.825492 -28.014426)
			(xy 195.881226 -28.012389) (xy 195.936663 -28.018489) (xy 195.99062 -28.032595) (xy 196.041949 -28.054407)
			(xy 196.089555 -28.083461) (xy 196.132423 -28.119136) (xy 196.16964 -28.160673) (xy 196.200413 -28.207186)
			(xy 196.224085 -28.257683) (xy 196.240153 -28.31109) (xy 196.248273 -28.366266) (xy 196.248782 -28.394152)
			(xy 196.248273 -28.422038) (xy 196.240153 -28.477214) (xy 196.224085 -28.530621) (xy 196.200413 -28.581118)
			(xy 196.16964 -28.627631) (xy 196.132423 -28.669168) (xy 196.089555 -28.704843) (xy 196.041949 -28.733897)
			(xy 195.99062 -28.755709) (xy 195.936663 -28.769815) (xy 195.881226 -28.775915) (xy 195.825492 -28.773878)
			(xy 195.770649 -28.763748) (xy 195.717865 -28.745741) (xy 195.668265 -28.72024) (xy 195.622907 -28.687789)
			(xy 195.582758 -28.64908) (xy 195.548672 -28.604937) (xy 195.521376 -28.556302) (xy 195.501453 -28.504211)
			(xy 195.489327 -28.449774) (xy 195.485256 -28.394152) (xy 193.520466 -28.394152) (xy 193.520568 -28.39974)
			(xy 193.520059 -28.427626) (xy 193.511939 -28.482802) (xy 193.495871 -28.536209) (xy 193.472199 -28.586706)
			(xy 193.441426 -28.633219) (xy 193.404209 -28.674756) (xy 193.361341 -28.710431) (xy 193.313735 -28.739485)
			(xy 193.262406 -28.761297) (xy 193.208449 -28.775403) (xy 193.153012 -28.781503) (xy 193.097278 -28.779466)
			(xy 193.042435 -28.769336) (xy 192.989651 -28.751329) (xy 192.940051 -28.725828) (xy 192.894693 -28.693377)
			(xy 192.854544 -28.654668) (xy 192.820458 -28.610525) (xy 192.793162 -28.56189) (xy 192.773239 -28.509799)
			(xy 192.761113 -28.455362) (xy 192.757042 -28.39974) (xy 187.393072 -28.39974) (xy 188.110114 -29.116782)
			(xy 196.199504 -29.116782) (xy 196.203575 -29.06116) (xy 196.215701 -29.006723) (xy 196.235624 -28.954632)
			(xy 196.26292 -28.905997) (xy 196.297006 -28.861854) (xy 196.337155 -28.823145) (xy 196.382513 -28.790694)
			(xy 196.432113 -28.765193) (xy 196.484897 -28.747186) (xy 196.53974 -28.737056) (xy 196.595474 -28.735019)
			(xy 196.650911 -28.741119) (xy 196.704868 -28.755225) (xy 196.756197 -28.777037) (xy 196.803803 -28.806091)
			(xy 196.846671 -28.841766) (xy 196.883888 -28.883303) (xy 196.914661 -28.929816) (xy 196.938333 -28.980313)
			(xy 196.954401 -29.03372) (xy 196.962521 -29.088896) (xy 196.96303 -29.116782) (xy 196.962521 -29.144668)
			(xy 196.954401 -29.199844) (xy 196.938333 -29.253251) (xy 196.914661 -29.303748) (xy 196.883888 -29.350261)
			(xy 196.846671 -29.391798) (xy 196.803803 -29.427473) (xy 196.756197 -29.456527) (xy 196.704868 -29.478339)
			(xy 196.650911 -29.492445) (xy 196.595474 -29.498545) (xy 196.53974 -29.496508) (xy 196.484897 -29.486378)
			(xy 196.432113 -29.468371) (xy 196.382513 -29.44287) (xy 196.337155 -29.410419) (xy 196.297006 -29.37171)
			(xy 196.26292 -29.327567) (xy 196.235624 -29.278932) (xy 196.215701 -29.226841) (xy 196.203575 -29.172404)
			(xy 196.199504 -29.116782) (xy 188.110114 -29.116782) (xy 188.530484 -29.537152) (xy 189.618364 -29.537152)
			(xy 189.622435 -29.48153) (xy 189.634561 -29.427093) (xy 189.654484 -29.375002) (xy 189.68178 -29.326367)
			(xy 189.715866 -29.282224) (xy 189.756015 -29.243515) (xy 189.801373 -29.211064) (xy 189.850973 -29.185563)
			(xy 189.903757 -29.167556) (xy 189.9586 -29.157426) (xy 190.014334 -29.155389) (xy 190.069771 -29.161489)
			(xy 190.123728 -29.175595) (xy 190.175057 -29.197407) (xy 190.222663 -29.226461) (xy 190.265531 -29.262136)
			(xy 190.302748 -29.303673) (xy 190.333521 -29.350186) (xy 190.357193 -29.400683) (xy 190.373261 -29.45409)
			(xy 190.381381 -29.509266) (xy 190.38189 -29.537152) (xy 190.381381 -29.565038) (xy 190.373261 -29.620214)
			(xy 190.357193 -29.673621) (xy 190.333521 -29.724118) (xy 190.302748 -29.770631) (xy 190.265531 -29.812168)
			(xy 190.232489 -29.839666) (xy 196.907402 -29.839666) (xy 196.911473 -29.784044) (xy 196.923599 -29.729607)
			(xy 196.943522 -29.677516) (xy 196.970818 -29.628881) (xy 197.004904 -29.584738) (xy 197.045053 -29.546029)
			(xy 197.090411 -29.513578) (xy 197.140011 -29.488077) (xy 197.192795 -29.47007) (xy 197.247638 -29.45994)
			(xy 197.303372 -29.457903) (xy 197.358809 -29.464003) (xy 197.412766 -29.478109) (xy 197.464095 -29.499921)
			(xy 197.511701 -29.528975) (xy 197.554569 -29.56465) (xy 197.591786 -29.606187) (xy 197.622559 -29.6527)
			(xy 197.646231 -29.703197) (xy 197.662299 -29.756604) (xy 197.670419 -29.81178) (xy 197.670928 -29.839666)
			(xy 197.670419 -29.867552) (xy 197.662299 -29.922728) (xy 197.646231 -29.976135) (xy 197.622559 -30.026632)
			(xy 197.591786 -30.073145) (xy 197.554569 -30.114682) (xy 197.511701 -30.150357) (xy 197.464095 -30.179411)
			(xy 197.412766 -30.201223) (xy 197.358809 -30.215329) (xy 197.303372 -30.221429) (xy 197.247638 -30.219392)
			(xy 197.192795 -30.209262) (xy 197.140011 -30.191255) (xy 197.090411 -30.165754) (xy 197.045053 -30.133303)
			(xy 197.004904 -30.094594) (xy 196.970818 -30.050451) (xy 196.943522 -30.001816) (xy 196.923599 -29.949725)
			(xy 196.911473 -29.895288) (xy 196.907402 -29.839666) (xy 190.232489 -29.839666) (xy 190.222663 -29.847843)
			(xy 190.175057 -29.876897) (xy 190.123728 -29.898709) (xy 190.069771 -29.912815) (xy 190.014334 -29.918915)
			(xy 189.9586 -29.916878) (xy 189.903757 -29.906748) (xy 189.850973 -29.888741) (xy 189.801373 -29.86324)
			(xy 189.756015 -29.830789) (xy 189.715866 -29.79208) (xy 189.68178 -29.747937) (xy 189.654484 -29.699302)
			(xy 189.634561 -29.647211) (xy 189.622435 -29.592774) (xy 189.618364 -29.537152) (xy 188.530484 -29.537152)
			(xy 190.463424 -31.470092) (xy 193.21018 -31.470092) (xy 193.210666 -31.442841) (xy 193.218422 -31.388893)
			(xy 193.233777 -31.336598) (xy 193.256419 -31.287021) (xy 193.285885 -31.241171) (xy 193.321576 -31.19998)
			(xy 193.362767 -31.164289) (xy 193.408617 -31.134823) (xy 193.458194 -31.112181) (xy 193.510489 -31.096826)
			(xy 193.564437 -31.08907) (xy 193.618939 -31.08907) (xy 193.672887 -31.096826) (xy 193.725182 -31.112181)
			(xy 193.774759 -31.134823) (xy 193.820609 -31.164289) (xy 193.8618 -31.19998) (xy 193.897491 -31.241171)
			(xy 193.926957 -31.287021) (xy 193.949599 -31.336598) (xy 193.964954 -31.388893) (xy 193.97271 -31.442841)
			(xy 193.973196 -31.470092) (xy 193.972756 -31.495942) (xy 193.965782 -31.54717) (xy 193.95196 -31.596989)
			(xy 193.931544 -31.644487) (xy 193.904905 -31.688797) (xy 193.872533 -31.729108) (xy 193.85407 -31.747206)
			(xy 193.844244 -31.757079) (xy 193.829947 -31.780975) (xy 193.822647 -31.807848) (xy 193.822887 -31.835693)
			(xy 193.830649 -31.862436) (xy 193.845355 -31.886082) (xy 193.85534 -31.895796) (xy 193.874554 -31.913976)
			(xy 193.908342 -31.954671) (xy 193.936186 -31.999643) (xy 193.957552 -32.04803) (xy 193.972031 -32.098903)
			(xy 193.979345 -32.151289) (xy 193.9798 -32.177736) (xy 193.979236 -32.206651) (xy 193.970516 -32.26382)
			(xy 193.953267 -32.319018) (xy 193.927884 -32.37098) (xy 193.894949 -32.418515) (xy 193.855216 -32.460534)
			(xy 193.832734 -32.478726) (xy 193.820891 -32.488583) (xy 193.80337 -32.513917) (xy 193.794196 -32.543321)
			(xy 193.794203 -32.574123) (xy 193.80339 -32.603523) (xy 193.820921 -32.62885) (xy 193.832734 -32.638746)
			(xy 193.855199 -32.656959) (xy 193.894934 -32.698975) (xy 193.927874 -32.746506) (xy 193.953265 -32.798463)
			(xy 193.970526 -32.853656) (xy 193.979261 -32.910821) (xy 193.9798 -32.939736) (xy 193.979314 -32.966987)
			(xy 193.971558 -33.020935) (xy 193.956203 -33.07323) (xy 193.933561 -33.122807) (xy 193.904095 -33.168657)
			(xy 193.868404 -33.209848) (xy 193.827213 -33.245539) (xy 193.781363 -33.275005) (xy 193.731786 -33.297647)
			(xy 193.679491 -33.313002) (xy 193.625543 -33.320758) (xy 193.571041 -33.320758) (xy 193.517093 -33.313002)
			(xy 193.464798 -33.297647) (xy 193.415221 -33.275005) (xy 193.369371 -33.245539) (xy 193.32818 -33.209848)
			(xy 193.292489 -33.168657) (xy 193.263023 -33.122807) (xy 193.240381 -33.07323) (xy 193.225026 -33.020935)
			(xy 193.21727 -32.966987) (xy 193.216784 -32.939736) (xy 193.217297 -32.910819) (xy 193.226022 -32.853646)
			(xy 193.243279 -32.798445) (xy 193.268672 -32.746483) (xy 193.301618 -32.69895) (xy 193.341363 -32.656935)
			(xy 193.36385 -32.638746) (xy 193.375623 -32.628811) (xy 193.393147 -32.6035) (xy 193.402331 -32.574115)
			(xy 193.402337 -32.543329) (xy 193.393167 -32.51394) (xy 193.375653 -32.488621) (xy 193.36385 -32.478726)
			(xy 193.341369 -32.460533) (xy 193.301635 -32.418512) (xy 193.268698 -32.370977) (xy 193.243309 -32.319017)
			(xy 193.226052 -32.26382) (xy 193.217321 -32.206652) (xy 193.216784 -32.177736) (xy 193.217217 -32.151885)
			(xy 193.224189 -32.100656) (xy 193.238011 -32.050836) (xy 193.258428 -32.003337) (xy 193.285069 -31.959028)
			(xy 193.317445 -31.918719) (xy 193.33591 -31.900622) (xy 193.34571 -31.890724) (xy 193.360011 -31.866836)
			(xy 193.367316 -31.839969) (xy 193.367082 -31.812128) (xy 193.359324 -31.785389) (xy 193.344622 -31.761745)
			(xy 193.33464 -31.752032) (xy 193.315388 -31.733891) (xy 193.281603 -31.693187) (xy 193.253765 -31.648207)
			(xy 193.232406 -31.599813) (xy 193.217935 -31.548932) (xy 193.21063 -31.496541) (xy 193.21018 -31.470092)
			(xy 190.463424 -31.470092) (xy 194.332606 -35.339274) (xy 194.342579 -35.34859) (xy 194.366314 -35.362034)
			(xy 194.392764 -35.368712) (xy 194.420037 -35.368146) (xy 194.446186 -35.360376) (xy 194.469343 -35.345957)
			(xy 194.47891 -35.336226) (xy 194.497047 -35.317234) (xy 194.53763 -35.283905) (xy 194.582399 -35.256455)
			(xy 194.630508 -35.235402) (xy 194.68105 -35.221143) (xy 194.733069 -35.213947) (xy 194.759326 -35.213544)
			(xy 194.786577 -35.214032) (xy 194.840525 -35.221791) (xy 194.892819 -35.237148) (xy 194.942396 -35.25979)
			(xy 194.988247 -35.289256) (xy 195.029438 -35.324947) (xy 195.065131 -35.366136) (xy 195.0946 -35.411985)
			(xy 195.117245 -35.46156) (xy 195.132605 -35.513854) (xy 195.140367 -35.567801) (xy 195.140834 -35.595052)
			(xy 195.140394 -35.621306) (xy 195.133192 -35.673318) (xy 195.118931 -35.723853) (xy 195.09788 -35.771957)
			(xy 195.070436 -35.816723) (xy 195.037117 -35.857306) (xy 195.018152 -35.875468) (xy 195.008414 -35.885036)
			(xy 194.993966 -35.908188) (xy 194.986178 -35.934343) (xy 194.985606 -35.961627) (xy 194.992293 -35.988084)
			(xy 195.005759 -36.011821) (xy 195.015104 -36.021772) (xy 195.43268 -36.439348) (xy 196.066662 -36.439348)
			(xy 196.070733 -36.383726) (xy 196.082859 -36.329289) (xy 196.102782 -36.277198) (xy 196.130078 -36.228563)
			(xy 196.164164 -36.18442) (xy 196.204313 -36.145711) (xy 196.249671 -36.11326) (xy 196.299271 -36.087759)
			(xy 196.352055 -36.069752) (xy 196.406898 -36.059622) (xy 196.462632 -36.057585) (xy 196.518069 -36.063685)
			(xy 196.572026 -36.077791) (xy 196.623355 -36.099603) (xy 196.670961 -36.128657) (xy 196.713829 -36.164332)
			(xy 196.751046 -36.205869) (xy 196.781819 -36.252382) (xy 196.805491 -36.302879) (xy 196.821559 -36.356286)
			(xy 196.829679 -36.411462) (xy 196.830188 -36.439348) (xy 196.829679 -36.467234) (xy 196.821559 -36.52241)
			(xy 196.805491 -36.575817) (xy 196.781819 -36.626314) (xy 196.751046 -36.672827) (xy 196.713829 -36.714364)
			(xy 196.670961 -36.750039) (xy 196.623355 -36.779093) (xy 196.572026 -36.800905) (xy 196.518069 -36.815011)
			(xy 196.462632 -36.821111) (xy 196.406898 -36.819074) (xy 196.352055 -36.808944) (xy 196.299271 -36.790937)
			(xy 196.249671 -36.765436) (xy 196.204313 -36.732985) (xy 196.164164 -36.694276) (xy 196.130078 -36.650133)
			(xy 196.102782 -36.601498) (xy 196.082859 -36.549407) (xy 196.070733 -36.49497) (xy 196.066662 -36.439348)
			(xy 195.43268 -36.439348) (xy 195.81368 -36.820348) (xy 195.81368 -38.268148) (xy 196.212714 -38.667182)
			(xy 196.229224 -38.669722) (xy 196.255697 -38.67425) (xy 196.307114 -38.689765) (xy 196.355848 -38.712337)
			(xy 196.400936 -38.741518) (xy 196.441486 -38.776733) (xy 196.476698 -38.817286) (xy 196.505877 -38.862376)
			(xy 196.528444 -38.911111) (xy 196.543956 -38.96253) (xy 196.548502 -38.989) (xy 196.551042 -39.00551)
			(xy 196.60108 -39.055548) (xy 199.62368 -39.055548)
		)
		(stroke
			(width 0)
			(type solid)
		)
		(fill yes)
		(layer "In4.Cu")
		(net "P12V_SCM_R")
	)
	(gr_poly
		(pts
			(xy 339.863938 -287.65754) (xy 339.870647 -287.669346) (xy 339.889185 -287.689177) (xy 339.912289 -287.703426)
			(xy 339.938331 -287.711089) (xy 339.965471 -287.711625) (xy 339.991794 -287.704996) (xy 340.015444 -287.691669)
			(xy 340.034749 -287.672586) (xy 340.041992 -287.661096) (xy 340.063582 -287.623504) (xy 340.08494 -287.587495)
			(xy 340.133013 -287.518944) (xy 340.159594 -287.486598) (xy 340.144188 -287.465079) (xy 340.11971 -287.418162)
			(xy 340.103033 -287.36794) (xy 340.094582 -287.315699) (xy 340.094062 -287.28924) (xy 340.094542 -287.263269)
			(xy 340.102662 -287.211966) (xy 340.118709 -287.162565) (xy 340.142286 -287.116283) (xy 340.172815 -287.07426)
			(xy 340.209542 -287.03753) (xy 340.251563 -287.006999) (xy 340.297843 -286.983418) (xy 340.347243 -286.967368)
			(xy 340.398545 -286.959244) (xy 340.424516 -286.958786) (xy 340.452008 -286.959333) (xy 340.506235 -286.968432)
			(xy 340.558209 -286.986377) (xy 340.606498 -287.012673) (xy 340.649771 -287.046595) (xy 340.686836 -287.087209)
			(xy 340.716671 -287.133396) (xy 340.728046 -287.15843) (xy 340.7693 -287.151621) (xy 340.852606 -287.14437)
			(xy 340.894416 -287.143952) (xy 340.936162 -287.144405) (xy 341.019337 -287.151655) (xy 341.060532 -287.15843)
			(xy 341.071911 -287.133395) (xy 341.101728 -287.087191) (xy 341.138784 -287.046563) (xy 341.182057 -287.012632)
			(xy 341.230351 -286.986336) (xy 341.282333 -286.9684) (xy 341.336567 -286.959321) (xy 341.364062 -286.958786)
			(xy 341.390032 -286.959266) (xy 341.441333 -286.967387) (xy 341.490733 -286.983434) (xy 341.537013 -287.007012)
			(xy 341.579034 -287.037541) (xy 341.615761 -287.074268) (xy 341.646289 -287.116289) (xy 341.669867 -287.162569)
			(xy 341.685914 -287.211968) (xy 341.694034 -287.26327) (xy 341.694516 -287.28924) (xy 341.693993 -287.315656)
			(xy 341.685575 -287.367812) (xy 341.66896 -287.417962) (xy 341.644572 -287.464828) (xy 341.629238 -287.486344)
			(xy 341.661846 -287.526284) (xy 341.71925 -287.61194) (xy 341.743792 -287.657286) (xy 341.750478 -287.669103)
			(xy 341.768982 -287.688959) (xy 341.792066 -287.703233) (xy 341.818097 -287.710915) (xy 341.845232 -287.711462)
			(xy 341.871551 -287.704834) (xy 341.895191 -287.6915) (xy 341.914479 -287.672405) (xy 341.921592 -287.660842)
			(xy 341.943182 -287.623504) (xy 341.964477 -287.587561) (xy 342.012423 -287.519136) (xy 342.03894 -287.486852)
			(xy 342.023528 -287.4653) (xy 341.999041 -287.418318) (xy 341.982358 -287.368032) (xy 341.973905 -287.31573)
			(xy 341.973408 -287.28924) (xy 341.973888 -287.263268) (xy 341.982008 -287.211961) (xy 341.998053 -287.162557)
			(xy 342.02163 -287.116271) (xy 342.052158 -287.074243) (xy 342.088884 -287.037509) (xy 342.130905 -287.006971)
			(xy 342.177185 -286.983383) (xy 342.226585 -286.967326) (xy 342.27789 -286.959194) (xy 342.303862 -286.958786)
			(xy 342.331352 -286.959336) (xy 342.385574 -286.968442) (xy 342.437542 -286.986391) (xy 342.485825 -287.012691)
			(xy 342.529092 -287.046615) (xy 342.566151 -287.087229) (xy 342.59598 -287.133414) (xy 342.607392 -287.15843)
			(xy 342.64871 -287.151616) (xy 342.732142 -287.144369) (xy 342.774016 -287.143952) (xy 342.815762 -287.144405)
			(xy 342.898937 -287.151655) (xy 342.940132 -287.15843) (xy 342.951511 -287.133395) (xy 342.981328 -287.087191)
			(xy 343.018384 -287.046563) (xy 343.061657 -287.012632) (xy 343.109951 -286.986336) (xy 343.161933 -286.9684)
			(xy 343.216167 -286.959321) (xy 343.243662 -286.958786) (xy 343.269632 -286.959266) (xy 343.320933 -286.967387)
			(xy 343.370333 -286.983434) (xy 343.416613 -287.007012) (xy 343.458634 -287.037541) (xy 343.495361 -287.074268)
			(xy 343.525889 -287.116289) (xy 343.549467 -287.162569) (xy 343.565514 -287.211968) (xy 343.573634 -287.26327)
			(xy 343.574116 -287.28924) (xy 343.573593 -287.315656) (xy 343.565175 -287.367812) (xy 343.54856 -287.417962)
			(xy 343.524172 -287.464828) (xy 343.508838 -287.486344) (xy 343.541446 -287.526284) (xy 343.59885 -287.61194)
			(xy 343.623392 -287.657286) (xy 343.630078 -287.669103) (xy 343.648582 -287.688959) (xy 343.671666 -287.703233)
			(xy 343.697697 -287.710915) (xy 343.724832 -287.711462) (xy 343.751151 -287.704834) (xy 343.774791 -287.6915)
			(xy 343.794079 -287.672405) (xy 343.801192 -287.660842) (xy 343.822782 -287.623504) (xy 343.844077 -287.587561)
			(xy 343.892023 -287.519136) (xy 343.91854 -287.486852) (xy 343.903128 -287.4653) (xy 343.878641 -287.418318)
			(xy 343.861958 -287.368032) (xy 343.853505 -287.31573) (xy 343.853008 -287.28924) (xy 343.853488 -287.263268)
			(xy 343.861608 -287.211961) (xy 343.877653 -287.162557) (xy 343.90123 -287.116271) (xy 343.931758 -287.074243)
			(xy 343.968484 -287.037509) (xy 344.010505 -287.006971) (xy 344.056785 -286.983383) (xy 344.106185 -286.967326)
			(xy 344.15749 -286.959194) (xy 344.183462 -286.958786) (xy 344.210952 -286.959336) (xy 344.265174 -286.968442)
			(xy 344.317142 -286.986391) (xy 344.365425 -287.012691) (xy 344.408692 -287.046615) (xy 344.445751 -287.087229)
			(xy 344.47558 -287.133414) (xy 344.486992 -287.15843) (xy 344.52831 -287.151616) (xy 344.611742 -287.144369)
			(xy 344.653616 -287.143952) (xy 344.695362 -287.144405) (xy 344.778537 -287.151655) (xy 344.819732 -287.15843)
			(xy 344.831111 -287.133395) (xy 344.860928 -287.087191) (xy 344.897984 -287.046563) (xy 344.941257 -287.012632)
			(xy 344.989551 -286.986336) (xy 345.041533 -286.9684) (xy 345.095767 -286.959321) (xy 345.123262 -286.958786)
			(xy 345.149232 -286.959266) (xy 345.200533 -286.967387) (xy 345.249933 -286.983434) (xy 345.296213 -287.007012)
			(xy 345.338234 -287.037541) (xy 345.374961 -287.074268) (xy 345.405489 -287.116289) (xy 345.429067 -287.162569)
			(xy 345.445114 -287.211968) (xy 345.453234 -287.26327) (xy 345.453716 -287.28924) (xy 345.453193 -287.315656)
			(xy 345.444775 -287.367812) (xy 345.42816 -287.417962) (xy 345.403772 -287.464828) (xy 345.388438 -287.486344)
			(xy 345.421046 -287.526284) (xy 345.47845 -287.61194) (xy 345.502992 -287.657286) (xy 345.509678 -287.669103)
			(xy 345.528182 -287.688959) (xy 345.551266 -287.703233) (xy 345.577297 -287.710915) (xy 345.604432 -287.711462)
			(xy 345.630751 -287.704834) (xy 345.654391 -287.6915) (xy 345.673679 -287.672405) (xy 345.680792 -287.660842)
			(xy 345.702382 -287.623504) (xy 345.723677 -287.587561) (xy 345.771623 -287.519136) (xy 345.79814 -287.486852)
			(xy 345.782728 -287.4653) (xy 345.758241 -287.418318) (xy 345.741558 -287.368032) (xy 345.733105 -287.31573)
			(xy 345.732608 -287.28924) (xy 345.733088 -287.263268) (xy 345.741208 -287.211961) (xy 345.757253 -287.162557)
			(xy 345.78083 -287.116271) (xy 345.811358 -287.074243) (xy 345.848084 -287.037509) (xy 345.890105 -287.006971)
			(xy 345.936385 -286.983383) (xy 345.985785 -286.967326) (xy 346.03709 -286.959194) (xy 346.063062 -286.958786)
			(xy 346.090552 -286.959336) (xy 346.144774 -286.968442) (xy 346.196742 -286.986391) (xy 346.245025 -287.012691)
			(xy 346.288292 -287.046615) (xy 346.325351 -287.087229) (xy 346.35518 -287.133414) (xy 346.366592 -287.15843)
			(xy 346.40791 -287.151616) (xy 346.491342 -287.144369) (xy 346.533216 -287.143952) (xy 346.574962 -287.144405)
			(xy 346.658137 -287.151655) (xy 346.699332 -287.15843) (xy 346.710711 -287.133395) (xy 346.740528 -287.087191)
			(xy 346.777584 -287.046563) (xy 346.820857 -287.012632) (xy 346.869151 -286.986336) (xy 346.921133 -286.9684)
			(xy 346.975367 -286.959321) (xy 347.002862 -286.958786) (xy 347.028832 -286.959266) (xy 347.080133 -286.967387)
			(xy 347.129533 -286.983434) (xy 347.175813 -287.007012) (xy 347.217834 -287.037541) (xy 347.254561 -287.074268)
			(xy 347.285089 -287.116289) (xy 347.308667 -287.162569) (xy 347.324714 -287.211968) (xy 347.332834 -287.26327)
			(xy 347.333316 -287.28924) (xy 347.332793 -287.315656) (xy 347.324375 -287.367812) (xy 347.30776 -287.417962)
			(xy 347.283372 -287.464828) (xy 347.268038 -287.486344) (xy 347.300646 -287.526284) (xy 347.35805 -287.61194)
			(xy 347.382592 -287.657286) (xy 347.389278 -287.669103) (xy 347.407782 -287.688959) (xy 347.430866 -287.703233)
			(xy 347.456897 -287.710915) (xy 347.484032 -287.711462) (xy 347.510351 -287.704834) (xy 347.533991 -287.6915)
			(xy 347.553279 -287.672405) (xy 347.560392 -287.660842) (xy 347.581982 -287.623504) (xy 347.603277 -287.587561)
			(xy 347.651223 -287.519136) (xy 347.67774 -287.486852) (xy 347.662328 -287.4653) (xy 347.637841 -287.418318)
			(xy 347.621158 -287.368032) (xy 347.612705 -287.31573) (xy 347.612208 -287.28924) (xy 347.612688 -287.263268)
			(xy 347.620808 -287.211961) (xy 347.636853 -287.162557) (xy 347.66043 -287.116271) (xy 347.690958 -287.074243)
			(xy 347.727684 -287.037509) (xy 347.769705 -287.006971) (xy 347.815985 -286.983383) (xy 347.865385 -286.967326)
			(xy 347.91669 -286.959194) (xy 347.942662 -286.958786) (xy 347.970152 -286.959336) (xy 348.024374 -286.968442)
			(xy 348.076342 -286.986391) (xy 348.124625 -287.012691) (xy 348.167892 -287.046615) (xy 348.204951 -287.087229)
			(xy 348.23478 -287.133414) (xy 348.246192 -287.15843) (xy 348.28751 -287.151616) (xy 348.370942 -287.144369)
			(xy 348.412816 -287.143952) (xy 348.454562 -287.144405) (xy 348.537737 -287.151655) (xy 348.578932 -287.15843)
			(xy 348.590311 -287.133395) (xy 348.620128 -287.087191) (xy 348.657184 -287.046563) (xy 348.700457 -287.012632)
			(xy 348.748751 -286.986336) (xy 348.800733 -286.9684) (xy 348.854967 -286.959321) (xy 348.882462 -286.958786)
			(xy 348.908432 -286.959266) (xy 348.959733 -286.967387) (xy 349.009133 -286.983434) (xy 349.055413 -287.007012)
			(xy 349.097434 -287.037541) (xy 349.134161 -287.074268) (xy 349.164689 -287.116289) (xy 349.188267 -287.162569)
			(xy 349.204314 -287.211968) (xy 349.212434 -287.26327) (xy 349.212916 -287.28924) (xy 349.212393 -287.315656)
			(xy 349.203975 -287.367812) (xy 349.18736 -287.417962) (xy 349.162972 -287.464828) (xy 349.147638 -287.486344)
			(xy 349.180246 -287.526284) (xy 349.23765 -287.61194) (xy 349.262192 -287.657286) (xy 349.268878 -287.669103)
			(xy 349.287382 -287.688959) (xy 349.310466 -287.703233) (xy 349.336497 -287.710915) (xy 349.363632 -287.711462)
			(xy 349.389951 -287.704834) (xy 349.413591 -287.6915) (xy 349.432879 -287.672405) (xy 349.439992 -287.660842)
			(xy 349.461582 -287.623504) (xy 349.482877 -287.587561) (xy 349.530823 -287.519136) (xy 349.55734 -287.486852)
			(xy 349.541928 -287.4653) (xy 349.517441 -287.418318) (xy 349.500758 -287.368032) (xy 349.492305 -287.31573)
			(xy 349.491808 -287.28924) (xy 349.492288 -287.263268) (xy 349.500408 -287.211961) (xy 349.516453 -287.162557)
			(xy 349.54003 -287.116271) (xy 349.570558 -287.074243) (xy 349.607284 -287.037509) (xy 349.649305 -287.006971)
			(xy 349.695585 -286.983383) (xy 349.744985 -286.967326) (xy 349.79629 -286.959194) (xy 349.822262 -286.958786)
			(xy 349.849752 -286.959336) (xy 349.903974 -286.968442) (xy 349.955942 -286.986391) (xy 350.004225 -287.012691)
			(xy 350.047492 -287.046615) (xy 350.084551 -287.087229) (xy 350.11438 -287.133414) (xy 350.125792 -287.15843)
			(xy 350.16711 -287.151616) (xy 350.250542 -287.144369) (xy 350.292416 -287.143952) (xy 350.334162 -287.144405)
			(xy 350.417337 -287.151655) (xy 350.458532 -287.15843) (xy 350.469911 -287.133395) (xy 350.499728 -287.087191)
			(xy 350.536784 -287.046563) (xy 350.580057 -287.012632) (xy 350.628351 -286.986336) (xy 350.680333 -286.9684)
			(xy 350.734567 -286.959321) (xy 350.762062 -286.958786) (xy 350.788032 -286.959266) (xy 350.839333 -286.967387)
			(xy 350.888733 -286.983434) (xy 350.935013 -287.007012) (xy 350.977034 -287.037541) (xy 351.013761 -287.074268)
			(xy 351.044289 -287.116289) (xy 351.067867 -287.162569) (xy 351.083914 -287.211968) (xy 351.092034 -287.26327)
			(xy 351.092516 -287.28924) (xy 351.091993 -287.315656) (xy 351.083575 -287.367812) (xy 351.06696 -287.417962)
			(xy 351.042572 -287.464828) (xy 351.027238 -287.486344) (xy 351.059846 -287.526284) (xy 351.11725 -287.61194)
			(xy 351.141792 -287.657286) (xy 351.148478 -287.669103) (xy 351.166982 -287.688959) (xy 351.190066 -287.703233)
			(xy 351.216097 -287.710915) (xy 351.243232 -287.711462) (xy 351.269551 -287.704834) (xy 351.293191 -287.6915)
			(xy 351.312479 -287.672405) (xy 351.319592 -287.660842) (xy 351.341182 -287.623504) (xy 351.362477 -287.587561)
			(xy 351.410423 -287.519136) (xy 351.43694 -287.486852) (xy 351.421528 -287.4653) (xy 351.397041 -287.418318)
			(xy 351.380358 -287.368032) (xy 351.371905 -287.31573) (xy 351.371408 -287.28924) (xy 351.371888 -287.263268)
			(xy 351.380008 -287.211961) (xy 351.396053 -287.162557) (xy 351.41963 -287.116271) (xy 351.450158 -287.074243)
			(xy 351.486884 -287.037509) (xy 351.528905 -287.006971) (xy 351.575185 -286.983383) (xy 351.624585 -286.967326)
			(xy 351.67589 -286.959194) (xy 351.701862 -286.958786) (xy 351.726938 -286.95926) (xy 351.776513 -286.966845)
			(xy 351.824378 -286.981818) (xy 351.869438 -287.003836) (xy 351.89033 -287.017714) (xy 351.901964 -287.025232)
			(xy 351.928112 -287.03434) (xy 351.955745 -287.036085) (xy 351.98283 -287.030338) (xy 352.007374 -287.017522)
			(xy 352.02757 -286.998581) (xy 352.041931 -286.974908) (xy 352.0494 -286.948246) (xy 352.049842 -286.934402)
			(xy 352.049842 -286.784034) (xy 352.022156 -286.770064) (xy 351.999192 -286.757857) (xy 351.957084 -286.727338)
			(xy 351.920276 -286.690601) (xy 351.889675 -286.648552) (xy 351.866038 -286.602229) (xy 351.849948 -286.552776)
			(xy 351.841801 -286.501413) (xy 351.8418 -286.449408) (xy 351.849943 -286.398045) (xy 351.86603 -286.348591)
			(xy 351.889664 -286.302267) (xy 351.920262 -286.260216) (xy 351.957067 -286.223476) (xy 351.999173 -286.192954)
			(xy 352.022156 -286.180784) (xy 352.049842 -286.166814) (xy 352.049842 -286.016192) (xy 352.049386 -286.002342)
			(xy 352.041952 -285.975659) (xy 352.027609 -285.951963) (xy 352.007414 -285.933005) (xy 351.982861 -285.920184)
			(xy 351.955763 -285.914447) (xy 351.92812 -285.916219) (xy 351.901976 -285.925368) (xy 351.89033 -285.93288)
			(xy 351.869464 -285.946802) (xy 351.824407 -285.968846) (xy 351.776532 -285.983814) (xy 351.726943 -285.991359)
			(xy 351.701862 -285.991808) (xy 351.675896 -285.991322) (xy 351.624604 -285.983192) (xy 351.575216 -285.967138)
			(xy 351.528947 -285.943556) (xy 351.486936 -285.913026) (xy 351.450219 -285.8763) (xy 351.4197 -285.834282)
			(xy 351.396129 -285.788007) (xy 351.380088 -285.738614) (xy 351.371971 -285.68732) (xy 351.371408 -285.661354)
			(xy 351.37188 -285.635907) (xy 351.379687 -285.585614) (xy 351.39511 -285.537112) (xy 351.417783 -285.491547)
			(xy 351.447172 -285.449995) (xy 351.482582 -285.413438) (xy 351.523177 -285.38274) (xy 351.567996 -285.358626)
			(xy 351.615982 -285.341666) (xy 351.640902 -285.336488) (xy 351.664016 -285.33217) (xy 351.867978 -284.978856)
			(xy 351.860104 -284.956758) (xy 351.851445 -284.930287) (xy 351.842128 -284.875383) (xy 351.841562 -284.847538)
			(xy 351.842076 -284.822034) (xy 351.849986 -284.771643) (xy 351.85731 -284.747208) (xy 351.866708 -284.717744)
			(xy 351.632266 -284.483302) (xy 351.575116 -284.483302) (xy 351.560961 -284.483762) (xy 351.533735 -284.491523)
			(xy 351.509681 -284.506454) (xy 351.490646 -284.527409) (xy 351.478089 -284.552783) (xy 351.472973 -284.580627)
			(xy 351.47569 -284.608807) (xy 351.486032 -284.635161) (xy 351.494344 -284.646624) (xy 351.510342 -284.668395)
			(xy 351.535777 -284.716057) (xy 351.553118 -284.767221) (xy 351.561903 -284.820526) (xy 351.562416 -284.847538)
			(xy 351.561907 -284.873505) (xy 351.553782 -284.9248) (xy 351.537734 -284.974193) (xy 351.514156 -285.020467)
			(xy 351.48363 -285.062483) (xy 351.446907 -285.099206) (xy 351.404891 -285.129732) (xy 351.358617 -285.15331)
			(xy 351.309224 -285.169358) (xy 351.257929 -285.177483) (xy 351.205995 -285.177483) (xy 351.1547 -285.169358)
			(xy 351.105307 -285.15331) (xy 351.059033 -285.129732) (xy 351.017017 -285.099206) (xy 350.980294 -285.062483)
			(xy 350.949768 -285.020467) (xy 350.92619 -284.974193) (xy 350.910142 -284.9248) (xy 350.902017 -284.873505)
			(xy 350.901508 -284.847538) (xy 350.90205 -284.820529) (xy 350.910842 -284.767231) (xy 350.928182 -284.716072)
			(xy 350.953608 -284.668412) (xy 350.96958 -284.646624) (xy 350.977811 -284.635103) (xy 350.988177 -284.608766)
			(xy 350.990915 -284.580595) (xy 350.985813 -284.552755) (xy 350.973265 -284.527385) (xy 350.954235 -284.506434)
			(xy 350.930184 -284.491513) (xy 350.90296 -284.483767) (xy 350.888808 -284.483302) (xy 350.63557 -284.483302)
			(xy 350.621419 -284.483767) (xy 350.594205 -284.491536) (xy 350.570164 -284.506468) (xy 350.551138 -284.527421)
			(xy 350.538587 -284.552787) (xy 350.533473 -284.580622) (xy 350.536187 -284.608793) (xy 350.546521 -284.63514)
			(xy 350.554798 -284.646624) (xy 350.570798 -284.668394) (xy 350.596237 -284.716055) (xy 350.61358 -284.76722)
			(xy 350.622366 -284.820526) (xy 350.62287 -284.847538) (xy 350.622396 -284.873011) (xy 350.614572 -284.923352)
			(xy 350.599115 -284.971896) (xy 350.576391 -285.017493) (xy 350.546939 -285.059062) (xy 350.511456 -285.095619)
			(xy 350.470783 -285.126297) (xy 350.425884 -285.15037) (xy 350.377822 -285.167268) (xy 350.352868 -285.172404)
			(xy 350.330008 -285.176722) (xy 350.1263 -285.529528) (xy 350.13392 -285.551626) (xy 350.142717 -285.5782)
			(xy 350.152174 -285.633368) (xy 350.152716 -285.661354) (xy 350.431608 -285.661354) (xy 350.432117 -285.635387)
			(xy 350.440242 -285.584092) (xy 350.45629 -285.534699) (xy 350.479868 -285.488425) (xy 350.510394 -285.446409)
			(xy 350.547117 -285.409686) (xy 350.589133 -285.37916) (xy 350.635407 -285.355582) (xy 350.6848 -285.339534)
			(xy 350.736095 -285.331409) (xy 350.788029 -285.331409) (xy 350.839324 -285.339534) (xy 350.888717 -285.355582)
			(xy 350.934991 -285.37916) (xy 350.977007 -285.409686) (xy 351.01373 -285.446409) (xy 351.044256 -285.488425)
			(xy 351.067834 -285.534699) (xy 351.083882 -285.584092) (xy 351.092007 -285.635387) (xy 351.092516 -285.661354)
			(xy 351.091984 -285.689264) (xy 351.082655 -285.744297) (xy 351.073974 -285.770828) (xy 351.0661 -285.792926)
			(xy 351.270062 -286.14624) (xy 351.293176 -286.150558) (xy 351.318101 -286.155707) (xy 351.366085 -286.172676)
			(xy 351.410902 -286.196798) (xy 351.451493 -286.227501) (xy 351.486901 -286.264061) (xy 351.516289 -286.305615)
			(xy 351.538962 -286.351181) (xy 351.554386 -286.399683) (xy 351.562196 -286.449976) (xy 351.56267 -286.475424)
			(xy 351.562161 -286.501391) (xy 351.554036 -286.552686) (xy 351.537988 -286.602079) (xy 351.51441 -286.648353)
			(xy 351.483884 -286.690369) (xy 351.447161 -286.727092) (xy 351.405145 -286.757618) (xy 351.358871 -286.781196)
			(xy 351.309478 -286.797244) (xy 351.258183 -286.805369) (xy 351.206249 -286.805369) (xy 351.154954 -286.797244)
			(xy 351.105561 -286.781196) (xy 351.059287 -286.757618) (xy 351.017271 -286.727092) (xy 350.980548 -286.690369)
			(xy 350.950022 -286.648353) (xy 350.926444 -286.602079) (xy 350.910396 -286.552686) (xy 350.902271 -286.501391)
			(xy 350.901762 -286.475424) (xy 350.902317 -286.447438) (xy 350.911765 -286.39227) (xy 350.920558 -286.365696)
			(xy 350.928178 -286.343598) (xy 350.72447 -285.990538) (xy 350.701356 -285.98622) (xy 350.676428 -285.981024)
			(xy 350.628405 -285.964101) (xy 350.583545 -285.940014) (xy 350.542911 -285.909331) (xy 350.507464 -285.872779)
			(xy 350.478041 -285.831223) (xy 350.455341 -285.785646) (xy 350.439899 -285.737126) (xy 350.432082 -285.686813)
			(xy 350.431608 -285.661354) (xy 350.152716 -285.661354) (xy 350.152207 -285.687321) (xy 350.144082 -285.738616)
			(xy 350.128034 -285.788009) (xy 350.104456 -285.834283) (xy 350.07393 -285.876299) (xy 350.037207 -285.913022)
			(xy 349.995191 -285.943548) (xy 349.948917 -285.967126) (xy 349.899524 -285.983174) (xy 349.848229 -285.991299)
			(xy 349.796295 -285.991299) (xy 349.745 -285.983174) (xy 349.695607 -285.967126) (xy 349.649333 -285.943548)
			(xy 349.607317 -285.913022) (xy 349.570594 -285.876299) (xy 349.540068 -285.834283) (xy 349.51649 -285.788009)
			(xy 349.500442 -285.738616) (xy 349.492317 -285.687321) (xy 349.491808 -285.661354) (xy 349.49228 -285.635907)
			(xy 349.500087 -285.585614) (xy 349.51551 -285.537112) (xy 349.538183 -285.491547) (xy 349.567572 -285.449995)
			(xy 349.602982 -285.413438) (xy 349.643577 -285.38274) (xy 349.688396 -285.358626) (xy 349.736382 -285.341666)
			(xy 349.761302 -285.336488) (xy 349.784416 -285.33217) (xy 349.988378 -284.978856) (xy 349.980504 -284.956758)
			(xy 349.971845 -284.930287) (xy 349.962528 -284.875383) (xy 349.961962 -284.847538) (xy 349.962504 -284.820529)
			(xy 349.971295 -284.76723) (xy 349.988633 -284.716069) (xy 350.014056 -284.668408) (xy 350.030034 -284.646624)
			(xy 350.038262 -284.6351) (xy 350.048623 -284.60876) (xy 350.051357 -284.580587) (xy 350.046256 -284.552746)
			(xy 350.03371 -284.527374) (xy 350.014683 -284.506418) (xy 349.990636 -284.491489) (xy 349.963415 -284.483731)
			(xy 349.949262 -284.483302) (xy 349.69577 -284.483302) (xy 349.681619 -284.483767) (xy 349.654405 -284.491536)
			(xy 349.630364 -284.506468) (xy 349.611338 -284.527421) (xy 349.598787 -284.552787) (xy 349.593673 -284.580622)
			(xy 349.596387 -284.608793) (xy 349.606721 -284.63514) (xy 349.614998 -284.646624) (xy 349.630998 -284.668394)
			(xy 349.656437 -284.716055) (xy 349.67378 -284.76722) (xy 349.682566 -284.820526) (xy 349.68307 -284.847538)
			(xy 349.682561 -284.873505) (xy 349.674436 -284.9248) (xy 349.658388 -284.974193) (xy 349.63481 -285.020467)
			(xy 349.604284 -285.062483) (xy 349.567561 -285.099206) (xy 349.525545 -285.129732) (xy 349.479271 -285.15331)
			(xy 349.429878 -285.169358) (xy 349.378583 -285.177483) (xy 349.326649 -285.177483) (xy 349.275354 -285.169358)
			(xy 349.225961 -285.15331) (xy 349.179687 -285.129732) (xy 349.137671 -285.099206) (xy 349.100948 -285.062483)
			(xy 349.070422 -285.020467) (xy 349.046844 -284.974193) (xy 349.030796 -284.9248) (xy 349.022671 -284.873505)
			(xy 349.022162 -284.847538) (xy 349.022704 -284.820529) (xy 349.031495 -284.76723) (xy 349.048833 -284.716069)
			(xy 349.074256 -284.668408) (xy 349.090234 -284.646624) (xy 349.098462 -284.6351) (xy 349.108823 -284.60876)
			(xy 349.111557 -284.580587) (xy 349.106456 -284.552746) (xy 349.09391 -284.527374) (xy 349.074883 -284.506418)
			(xy 349.050836 -284.491489) (xy 349.023615 -284.483731) (xy 349.009462 -284.483302) (xy 348.75597 -284.483302)
			(xy 348.741819 -284.483767) (xy 348.714605 -284.491536) (xy 348.690564 -284.506468) (xy 348.671538 -284.527421)
			(xy 348.658987 -284.552787) (xy 348.653873 -284.580622) (xy 348.656587 -284.608793) (xy 348.666921 -284.63514)
			(xy 348.675198 -284.646624) (xy 348.691198 -284.668394) (xy 348.716637 -284.716055) (xy 348.73398 -284.76722)
			(xy 348.742766 -284.820526) (xy 348.74327 -284.847538) (xy 348.742796 -284.873011) (xy 348.734972 -284.923352)
			(xy 348.719515 -284.971896) (xy 348.696791 -285.017493) (xy 348.667339 -285.059062) (xy 348.631856 -285.095619)
			(xy 348.591183 -285.126297) (xy 348.546284 -285.15037) (xy 348.498222 -285.167268) (xy 348.473268 -285.172404)
			(xy 348.450408 -285.176722) (xy 348.2467 -285.529528) (xy 348.25432 -285.551626) (xy 348.263117 -285.5782)
			(xy 348.272574 -285.633368) (xy 348.273116 -285.661354) (xy 348.552008 -285.661354) (xy 348.552517 -285.635387)
			(xy 348.560642 -285.584092) (xy 348.57669 -285.534699) (xy 348.600268 -285.488425) (xy 348.630794 -285.446409)
			(xy 348.667517 -285.409686) (xy 348.709533 -285.37916) (xy 348.755807 -285.355582) (xy 348.8052 -285.339534)
			(xy 348.856495 -285.331409) (xy 348.908429 -285.331409) (xy 348.959724 -285.339534) (xy 349.009117 -285.355582)
			(xy 349.055391 -285.37916) (xy 349.097407 -285.409686) (xy 349.13413 -285.446409) (xy 349.164656 -285.488425)
			(xy 349.188234 -285.534699) (xy 349.204282 -285.584092) (xy 349.212407 -285.635387) (xy 349.212916 -285.661354)
			(xy 349.212384 -285.689264) (xy 349.203055 -285.744297) (xy 349.194374 -285.770828) (xy 349.1865 -285.792926)
			(xy 349.390462 -286.14624) (xy 349.413576 -286.150558) (xy 349.438501 -286.155707) (xy 349.486485 -286.172676)
			(xy 349.531302 -286.196798) (xy 349.571893 -286.227501) (xy 349.607301 -286.264061) (xy 349.636689 -286.305615)
			(xy 349.659362 -286.351181) (xy 349.674786 -286.399683) (xy 349.682596 -286.449976) (xy 349.68307 -286.475424)
			(xy 349.682561 -286.501391) (xy 349.962217 -286.501391) (xy 349.962217 -286.449457) (xy 349.970342 -286.398162)
			(xy 349.98639 -286.348769) (xy 350.009968 -286.302495) (xy 350.040494 -286.260479) (xy 350.077217 -286.223756)
			(xy 350.119233 -286.19323) (xy 350.165507 -286.169652) (xy 350.2149 -286.153604) (xy 350.266195 -286.145479)
			(xy 350.318129 -286.145479) (xy 350.369424 -286.153604) (xy 350.418817 -286.169652) (xy 350.465091 -286.19323)
			(xy 350.507107 -286.223756) (xy 350.54383 -286.260479) (xy 350.574356 -286.302495) (xy 350.597934 -286.348769)
			(xy 350.613982 -286.398162) (xy 350.622107 -286.449457) (xy 350.622616 -286.475424) (xy 350.622107 -286.501391)
			(xy 350.613982 -286.552686) (xy 350.597934 -286.602079) (xy 350.574356 -286.648353) (xy 350.54383 -286.690369)
			(xy 350.507107 -286.727092) (xy 350.465091 -286.757618) (xy 350.418817 -286.781196) (xy 350.369424 -286.797244)
			(xy 350.318129 -286.805369) (xy 350.266195 -286.805369) (xy 350.2149 -286.797244) (xy 350.165507 -286.781196)
			(xy 350.119233 -286.757618) (xy 350.077217 -286.727092) (xy 350.040494 -286.690369) (xy 350.009968 -286.648353)
			(xy 349.98639 -286.602079) (xy 349.970342 -286.552686) (xy 349.962217 -286.501391) (xy 349.682561 -286.501391)
			(xy 349.674436 -286.552686) (xy 349.658388 -286.602079) (xy 349.63481 -286.648353) (xy 349.604284 -286.690369)
			(xy 349.567561 -286.727092) (xy 349.525545 -286.757618) (xy 349.479271 -286.781196) (xy 349.429878 -286.797244)
			(xy 349.378583 -286.805369) (xy 349.326649 -286.805369) (xy 349.275354 -286.797244) (xy 349.225961 -286.781196)
			(xy 349.179687 -286.757618) (xy 349.137671 -286.727092) (xy 349.100948 -286.690369) (xy 349.070422 -286.648353)
			(xy 349.046844 -286.602079) (xy 349.030796 -286.552686) (xy 349.022671 -286.501391) (xy 349.022162 -286.475424)
			(xy 349.022717 -286.447438) (xy 349.032165 -286.39227) (xy 349.040958 -286.365696) (xy 349.048578 -286.343598)
			(xy 348.84487 -285.990538) (xy 348.821756 -285.98622) (xy 348.796828 -285.981024) (xy 348.748805 -285.964101)
			(xy 348.703945 -285.940014) (xy 348.663311 -285.909331) (xy 348.627864 -285.872779) (xy 348.598441 -285.831223)
			(xy 348.575741 -285.785646) (xy 348.560299 -285.737126) (xy 348.552482 -285.686813) (xy 348.552008 -285.661354)
			(xy 348.273116 -285.661354) (xy 348.272607 -285.687321) (xy 348.264482 -285.738616) (xy 348.248434 -285.788009)
			(xy 348.224856 -285.834283) (xy 348.19433 -285.876299) (xy 348.157607 -285.913022) (xy 348.115591 -285.943548)
			(xy 348.069317 -285.967126) (xy 348.019924 -285.983174) (xy 347.968629 -285.991299) (xy 347.916695 -285.991299)
			(xy 347.8654 -285.983174) (xy 347.816007 -285.967126) (xy 347.769733 -285.943548) (xy 347.727717 -285.913022)
			(xy 347.690994 -285.876299) (xy 347.660468 -285.834283) (xy 347.63689 -285.788009) (xy 347.620842 -285.738616)
			(xy 347.612717 -285.687321) (xy 347.612208 -285.661354) (xy 347.61268 -285.635907) (xy 347.620487 -285.585614)
			(xy 347.63591 -285.537112) (xy 347.658583 -285.491547) (xy 347.687972 -285.449995) (xy 347.723382 -285.413438)
			(xy 347.763977 -285.38274) (xy 347.808796 -285.358626) (xy 347.856782 -285.341666) (xy 347.881702 -285.336488)
			(xy 347.904816 -285.33217) (xy 348.108778 -284.978856) (xy 348.100904 -284.956758) (xy 348.092245 -284.930287)
			(xy 348.082928 -284.875383) (xy 348.082362 -284.847538) (xy 348.082904 -284.820529) (xy 348.091695 -284.76723)
			(xy 348.109033 -284.716069) (xy 348.134456 -284.668408) (xy 348.150434 -284.646624) (xy 348.158662 -284.6351)
			(xy 348.169023 -284.60876) (xy 348.171757 -284.580587) (xy 348.166656 -284.552746) (xy 348.15411 -284.527374)
			(xy 348.135083 -284.506418) (xy 348.111036 -284.491489) (xy 348.083815 -284.483731) (xy 348.069662 -284.483302)
			(xy 346.87637 -284.483302) (xy 346.862219 -284.483767) (xy 346.835005 -284.491536) (xy 346.810964 -284.506468)
			(xy 346.791938 -284.527421) (xy 346.779387 -284.552787) (xy 346.774273 -284.580622) (xy 346.776987 -284.608793)
			(xy 346.787321 -284.63514) (xy 346.795598 -284.646624) (xy 346.811598 -284.668394) (xy 346.837037 -284.716055)
			(xy 346.85438 -284.76722) (xy 346.863166 -284.820526) (xy 346.86367 -284.847538) (xy 346.863196 -284.873011)
			(xy 346.855372 -284.923352) (xy 346.839915 -284.971896) (xy 346.817191 -285.017493) (xy 346.787739 -285.059062)
			(xy 346.752256 -285.095619) (xy 346.711583 -285.126297) (xy 346.666684 -285.15037) (xy 346.618622 -285.167268)
			(xy 346.593668 -285.172404) (xy 346.570808 -285.176722) (xy 346.3671 -285.529528) (xy 346.37472 -285.551626)
			(xy 346.383517 -285.5782) (xy 346.392974 -285.633368) (xy 346.393516 -285.661354) (xy 346.672408 -285.661354)
			(xy 346.672917 -285.635387) (xy 346.681042 -285.584092) (xy 346.69709 -285.534699) (xy 346.720668 -285.488425)
			(xy 346.751194 -285.446409) (xy 346.787917 -285.409686) (xy 346.829933 -285.37916) (xy 346.876207 -285.355582)
			(xy 346.9256 -285.339534) (xy 346.976895 -285.331409) (xy 347.028829 -285.331409) (xy 347.080124 -285.339534)
			(xy 347.129517 -285.355582) (xy 347.175791 -285.37916) (xy 347.217807 -285.409686) (xy 347.25453 -285.446409)
			(xy 347.285056 -285.488425) (xy 347.308634 -285.534699) (xy 347.324682 -285.584092) (xy 347.332807 -285.635387)
			(xy 347.333316 -285.661354) (xy 347.332784 -285.689264) (xy 347.323455 -285.744297) (xy 347.314774 -285.770828)
			(xy 347.3069 -285.792926) (xy 347.510862 -286.14624) (xy 347.533976 -286.150558) (xy 347.558901 -286.155707)
			(xy 347.606885 -286.172676) (xy 347.651702 -286.196798) (xy 347.692293 -286.227501) (xy 347.727701 -286.264061)
			(xy 347.757089 -286.305615) (xy 347.779762 -286.351181) (xy 347.795186 -286.399683) (xy 347.802996 -286.449976)
			(xy 347.80347 -286.475424) (xy 347.802961 -286.501391) (xy 348.082617 -286.501391) (xy 348.082617 -286.449457)
			(xy 348.090742 -286.398162) (xy 348.10679 -286.348769) (xy 348.130368 -286.302495) (xy 348.160894 -286.260479)
			(xy 348.197617 -286.223756) (xy 348.239633 -286.19323) (xy 348.285907 -286.169652) (xy 348.3353 -286.153604)
			(xy 348.386595 -286.145479) (xy 348.438529 -286.145479) (xy 348.489824 -286.153604) (xy 348.539217 -286.169652)
			(xy 348.585491 -286.19323) (xy 348.627507 -286.223756) (xy 348.66423 -286.260479) (xy 348.694756 -286.302495)
			(xy 348.718334 -286.348769) (xy 348.734382 -286.398162) (xy 348.742507 -286.449457) (xy 348.743016 -286.475424)
			(xy 348.742507 -286.501391) (xy 348.734382 -286.552686) (xy 348.718334 -286.602079) (xy 348.694756 -286.648353)
			(xy 348.66423 -286.690369) (xy 348.627507 -286.727092) (xy 348.585491 -286.757618) (xy 348.539217 -286.781196)
			(xy 348.489824 -286.797244) (xy 348.438529 -286.805369) (xy 348.386595 -286.805369) (xy 348.3353 -286.797244)
			(xy 348.285907 -286.781196) (xy 348.239633 -286.757618) (xy 348.197617 -286.727092) (xy 348.160894 -286.690369)
			(xy 348.130368 -286.648353) (xy 348.10679 -286.602079) (xy 348.090742 -286.552686) (xy 348.082617 -286.501391)
			(xy 347.802961 -286.501391) (xy 347.794836 -286.552686) (xy 347.778788 -286.602079) (xy 347.75521 -286.648353)
			(xy 347.724684 -286.690369) (xy 347.687961 -286.727092) (xy 347.645945 -286.757618) (xy 347.599671 -286.781196)
			(xy 347.550278 -286.797244) (xy 347.498983 -286.805369) (xy 347.447049 -286.805369) (xy 347.395754 -286.797244)
			(xy 347.346361 -286.781196) (xy 347.300087 -286.757618) (xy 347.258071 -286.727092) (xy 347.221348 -286.690369)
			(xy 347.190822 -286.648353) (xy 347.167244 -286.602079) (xy 347.151196 -286.552686) (xy 347.143071 -286.501391)
			(xy 347.142562 -286.475424) (xy 347.143117 -286.447438) (xy 347.152565 -286.39227) (xy 347.161358 -286.365696)
			(xy 347.168978 -286.343598) (xy 346.96527 -285.990538) (xy 346.942156 -285.98622) (xy 346.917228 -285.981024)
			(xy 346.869205 -285.964101) (xy 346.824345 -285.940014) (xy 346.783711 -285.909331) (xy 346.748264 -285.872779)
			(xy 346.718841 -285.831223) (xy 346.696141 -285.785646) (xy 346.680699 -285.737126) (xy 346.672882 -285.686813)
			(xy 346.672408 -285.661354) (xy 346.393516 -285.661354) (xy 346.393007 -285.687321) (xy 346.384882 -285.738616)
			(xy 346.368834 -285.788009) (xy 346.345256 -285.834283) (xy 346.31473 -285.876299) (xy 346.278007 -285.913022)
			(xy 346.235991 -285.943548) (xy 346.189717 -285.967126) (xy 346.140324 -285.983174) (xy 346.089029 -285.991299)
			(xy 346.037095 -285.991299) (xy 345.9858 -285.983174) (xy 345.936407 -285.967126) (xy 345.890133 -285.943548)
			(xy 345.848117 -285.913022) (xy 345.811394 -285.876299) (xy 345.780868 -285.834283) (xy 345.75729 -285.788009)
			(xy 345.741242 -285.738616) (xy 345.733117 -285.687321) (xy 345.732608 -285.661354) (xy 345.73308 -285.635907)
			(xy 345.740887 -285.585614) (xy 345.75631 -285.537112) (xy 345.778983 -285.491547) (xy 345.808372 -285.449995)
			(xy 345.843782 -285.413438) (xy 345.884377 -285.38274) (xy 345.929196 -285.358626) (xy 345.977182 -285.341666)
			(xy 346.002102 -285.336488) (xy 346.025216 -285.33217) (xy 346.229178 -284.978856) (xy 346.221304 -284.956758)
			(xy 346.212645 -284.930287) (xy 346.203328 -284.875383) (xy 346.202762 -284.847538) (xy 346.203304 -284.820529)
			(xy 346.212095 -284.76723) (xy 346.229433 -284.716069) (xy 346.254856 -284.668408) (xy 346.270834 -284.646624)
			(xy 346.279062 -284.6351) (xy 346.289423 -284.60876) (xy 346.292157 -284.580587) (xy 346.287056 -284.552746)
			(xy 346.27451 -284.527374) (xy 346.255483 -284.506418) (xy 346.231436 -284.491489) (xy 346.204215 -284.483731)
			(xy 346.190062 -284.483302) (xy 344.99677 -284.483302) (xy 344.982619 -284.483767) (xy 344.955405 -284.491536)
			(xy 344.931364 -284.506468) (xy 344.912338 -284.527421) (xy 344.899787 -284.552787) (xy 344.894673 -284.580622)
			(xy 344.897387 -284.608793) (xy 344.907721 -284.63514) (xy 344.915998 -284.646624) (xy 344.931998 -284.668394)
			(xy 344.957437 -284.716055) (xy 344.97478 -284.76722) (xy 344.983566 -284.820526) (xy 344.98407 -284.847538)
			(xy 344.983596 -284.873011) (xy 344.975772 -284.923352) (xy 344.960315 -284.971896) (xy 344.937591 -285.017493)
			(xy 344.908139 -285.059062) (xy 344.872656 -285.095619) (xy 344.831983 -285.126297) (xy 344.787084 -285.15037)
			(xy 344.739022 -285.167268) (xy 344.714068 -285.172404) (xy 344.691208 -285.176722) (xy 344.4875 -285.529528)
			(xy 344.49512 -285.551626) (xy 344.503917 -285.5782) (xy 344.513374 -285.633368) (xy 344.513916 -285.661354)
			(xy 344.792808 -285.661354) (xy 344.793317 -285.635387) (xy 344.801442 -285.584092) (xy 344.81749 -285.534699)
			(xy 344.841068 -285.488425) (xy 344.871594 -285.446409) (xy 344.908317 -285.409686) (xy 344.950333 -285.37916)
			(xy 344.996607 -285.355582) (xy 345.046 -285.339534) (xy 345.097295 -285.331409) (xy 345.149229 -285.331409)
			(xy 345.200524 -285.339534) (xy 345.249917 -285.355582) (xy 345.296191 -285.37916) (xy 345.338207 -285.409686)
			(xy 345.37493 -285.446409) (xy 345.405456 -285.488425) (xy 345.429034 -285.534699) (xy 345.445082 -285.584092)
			(xy 345.453207 -285.635387) (xy 345.453716 -285.661354) (xy 345.453184 -285.689264) (xy 345.443855 -285.744297)
			(xy 345.435174 -285.770828) (xy 345.4273 -285.792926) (xy 345.631262 -286.14624) (xy 345.654376 -286.150558)
			(xy 345.679301 -286.155707) (xy 345.727285 -286.172676) (xy 345.772102 -286.196798) (xy 345.812693 -286.227501)
			(xy 345.848101 -286.264061) (xy 345.877489 -286.305615) (xy 345.900162 -286.351181) (xy 345.915586 -286.399683)
			(xy 345.923396 -286.449976) (xy 345.92387 -286.475424) (xy 345.923361 -286.501391) (xy 346.203017 -286.501391)
			(xy 346.203017 -286.449457) (xy 346.211142 -286.398162) (xy 346.22719 -286.348769) (xy 346.250768 -286.302495)
			(xy 346.281294 -286.260479) (xy 346.318017 -286.223756) (xy 346.360033 -286.19323) (xy 346.406307 -286.169652)
			(xy 346.4557 -286.153604) (xy 346.506995 -286.145479) (xy 346.558929 -286.145479) (xy 346.610224 -286.153604)
			(xy 346.659617 -286.169652) (xy 346.705891 -286.19323) (xy 346.747907 -286.223756) (xy 346.78463 -286.260479)
			(xy 346.815156 -286.302495) (xy 346.838734 -286.348769) (xy 346.854782 -286.398162) (xy 346.862907 -286.449457)
			(xy 346.863416 -286.475424) (xy 346.862907 -286.501391) (xy 346.854782 -286.552686) (xy 346.838734 -286.602079)
			(xy 346.815156 -286.648353) (xy 346.78463 -286.690369) (xy 346.747907 -286.727092) (xy 346.705891 -286.757618)
			(xy 346.659617 -286.781196) (xy 346.610224 -286.797244) (xy 346.558929 -286.805369) (xy 346.506995 -286.805369)
			(xy 346.4557 -286.797244) (xy 346.406307 -286.781196) (xy 346.360033 -286.757618) (xy 346.318017 -286.727092)
			(xy 346.281294 -286.690369) (xy 346.250768 -286.648353) (xy 346.22719 -286.602079) (xy 346.211142 -286.552686)
			(xy 346.203017 -286.501391) (xy 345.923361 -286.501391) (xy 345.915236 -286.552686) (xy 345.899188 -286.602079)
			(xy 345.87561 -286.648353) (xy 345.845084 -286.690369) (xy 345.808361 -286.727092) (xy 345.766345 -286.757618)
			(xy 345.720071 -286.781196) (xy 345.670678 -286.797244) (xy 345.619383 -286.805369) (xy 345.567449 -286.805369)
			(xy 345.516154 -286.797244) (xy 345.466761 -286.781196) (xy 345.420487 -286.757618) (xy 345.378471 -286.727092)
			(xy 345.341748 -286.690369) (xy 345.311222 -286.648353) (xy 345.287644 -286.602079) (xy 345.271596 -286.552686)
			(xy 345.263471 -286.501391) (xy 345.262962 -286.475424) (xy 345.263517 -286.447438) (xy 345.272965 -286.39227)
			(xy 345.281758 -286.365696) (xy 345.289378 -286.343598) (xy 345.08567 -285.990538) (xy 345.062556 -285.98622)
			(xy 345.037628 -285.981024) (xy 344.989605 -285.964101) (xy 344.944745 -285.940014) (xy 344.904111 -285.909331)
			(xy 344.868664 -285.872779) (xy 344.839241 -285.831223) (xy 344.816541 -285.785646) (xy 344.801099 -285.737126)
			(xy 344.793282 -285.686813) (xy 344.792808 -285.661354) (xy 344.513916 -285.661354) (xy 344.513407 -285.687321)
			(xy 344.505282 -285.738616) (xy 344.489234 -285.788009) (xy 344.465656 -285.834283) (xy 344.43513 -285.876299)
			(xy 344.398407 -285.913022) (xy 344.356391 -285.943548) (xy 344.310117 -285.967126) (xy 344.260724 -285.983174)
			(xy 344.209429 -285.991299) (xy 344.157495 -285.991299) (xy 344.1062 -285.983174) (xy 344.056807 -285.967126)
			(xy 344.010533 -285.943548) (xy 343.968517 -285.913022) (xy 343.931794 -285.876299) (xy 343.901268 -285.834283)
			(xy 343.87769 -285.788009) (xy 343.861642 -285.738616) (xy 343.853517 -285.687321) (xy 343.853008 -285.661354)
			(xy 343.85348 -285.635907) (xy 343.861287 -285.585614) (xy 343.87671 -285.537112) (xy 343.899383 -285.491547)
			(xy 343.928772 -285.449995) (xy 343.964182 -285.413438) (xy 344.004777 -285.38274) (xy 344.049596 -285.358626)
			(xy 344.097582 -285.341666) (xy 344.122502 -285.336488) (xy 344.145616 -285.33217) (xy 344.349578 -284.978856)
			(xy 344.341704 -284.956758) (xy 344.333045 -284.930287) (xy 344.323728 -284.875383) (xy 344.323162 -284.847538)
			(xy 344.323704 -284.820529) (xy 344.332495 -284.76723) (xy 344.349833 -284.716069) (xy 344.375256 -284.668408)
			(xy 344.391234 -284.646624) (xy 344.399462 -284.6351) (xy 344.409823 -284.60876) (xy 344.412557 -284.580587)
			(xy 344.407456 -284.552746) (xy 344.39491 -284.527374) (xy 344.375883 -284.506418) (xy 344.351836 -284.491489)
			(xy 344.324615 -284.483731) (xy 344.310462 -284.483302) (xy 343.11717 -284.483302) (xy 343.103019 -284.483767)
			(xy 343.075805 -284.491536) (xy 343.051764 -284.506468) (xy 343.032738 -284.527421) (xy 343.020187 -284.552787)
			(xy 343.015073 -284.580622) (xy 343.017787 -284.608793) (xy 343.028121 -284.63514) (xy 343.036398 -284.646624)
			(xy 343.052398 -284.668394) (xy 343.077837 -284.716055) (xy 343.09518 -284.76722) (xy 343.103966 -284.820526)
			(xy 343.10447 -284.847538) (xy 343.103996 -284.873011) (xy 343.096172 -284.923352) (xy 343.080715 -284.971896)
			(xy 343.057991 -285.017493) (xy 343.028539 -285.059062) (xy 342.993056 -285.095619) (xy 342.952383 -285.126297)
			(xy 342.907484 -285.15037) (xy 342.859422 -285.167268) (xy 342.834468 -285.172404) (xy 342.811608 -285.176722)
			(xy 342.6079 -285.529528) (xy 342.61552 -285.551626) (xy 342.624317 -285.5782) (xy 342.633774 -285.633368)
			(xy 342.634316 -285.661354) (xy 342.913208 -285.661354) (xy 342.913717 -285.635387) (xy 342.921842 -285.584092)
			(xy 342.93789 -285.534699) (xy 342.961468 -285.488425) (xy 342.991994 -285.446409) (xy 343.028717 -285.409686)
			(xy 343.070733 -285.37916) (xy 343.117007 -285.355582) (xy 343.1664 -285.339534) (xy 343.217695 -285.331409)
			(xy 343.269629 -285.331409) (xy 343.320924 -285.339534) (xy 343.370317 -285.355582) (xy 343.416591 -285.37916)
			(xy 343.458607 -285.409686) (xy 343.49533 -285.446409) (xy 343.525856 -285.488425) (xy 343.549434 -285.534699)
			(xy 343.565482 -285.584092) (xy 343.573607 -285.635387) (xy 343.574116 -285.661354) (xy 343.573584 -285.689264)
			(xy 343.564255 -285.744297) (xy 343.555574 -285.770828) (xy 343.5477 -285.792926) (xy 343.751662 -286.14624)
			(xy 343.774776 -286.150558) (xy 343.799701 -286.155707) (xy 343.847685 -286.172676) (xy 343.892502 -286.196798)
			(xy 343.933093 -286.227501) (xy 343.968501 -286.264061) (xy 343.997889 -286.305615) (xy 344.020562 -286.351181)
			(xy 344.035986 -286.399683) (xy 344.043796 -286.449976) (xy 344.04427 -286.475424) (xy 344.043761 -286.501391)
			(xy 344.323417 -286.501391) (xy 344.323417 -286.449457) (xy 344.331542 -286.398162) (xy 344.34759 -286.348769)
			(xy 344.371168 -286.302495) (xy 344.401694 -286.260479) (xy 344.438417 -286.223756) (xy 344.480433 -286.19323)
			(xy 344.526707 -286.169652) (xy 344.5761 -286.153604) (xy 344.627395 -286.145479) (xy 344.679329 -286.145479)
			(xy 344.730624 -286.153604) (xy 344.780017 -286.169652) (xy 344.826291 -286.19323) (xy 344.868307 -286.223756)
			(xy 344.90503 -286.260479) (xy 344.935556 -286.302495) (xy 344.959134 -286.348769) (xy 344.975182 -286.398162)
			(xy 344.983307 -286.449457) (xy 344.983816 -286.475424) (xy 344.983307 -286.501391) (xy 344.975182 -286.552686)
			(xy 344.959134 -286.602079) (xy 344.935556 -286.648353) (xy 344.90503 -286.690369) (xy 344.868307 -286.727092)
			(xy 344.826291 -286.757618) (xy 344.780017 -286.781196) (xy 344.730624 -286.797244) (xy 344.679329 -286.805369)
			(xy 344.627395 -286.805369) (xy 344.5761 -286.797244) (xy 344.526707 -286.781196) (xy 344.480433 -286.757618)
			(xy 344.438417 -286.727092) (xy 344.401694 -286.690369) (xy 344.371168 -286.648353) (xy 344.34759 -286.602079)
			(xy 344.331542 -286.552686) (xy 344.323417 -286.501391) (xy 344.043761 -286.501391) (xy 344.035636 -286.552686)
			(xy 344.019588 -286.602079) (xy 343.99601 -286.648353) (xy 343.965484 -286.690369) (xy 343.928761 -286.727092)
			(xy 343.886745 -286.757618) (xy 343.840471 -286.781196) (xy 343.791078 -286.797244) (xy 343.739783 -286.805369)
			(xy 343.687849 -286.805369) (xy 343.636554 -286.797244) (xy 343.587161 -286.781196) (xy 343.540887 -286.757618)
			(xy 343.498871 -286.727092) (xy 343.462148 -286.690369) (xy 343.431622 -286.648353) (xy 343.408044 -286.602079)
			(xy 343.391996 -286.552686) (xy 343.383871 -286.501391) (xy 343.383362 -286.475424) (xy 343.383917 -286.447438)
			(xy 343.393365 -286.39227) (xy 343.402158 -286.365696) (xy 343.409778 -286.343598) (xy 343.20607 -285.990538)
			(xy 343.182956 -285.98622) (xy 343.158028 -285.981024) (xy 343.110005 -285.964101) (xy 343.065145 -285.940014)
			(xy 343.024511 -285.909331) (xy 342.989064 -285.872779) (xy 342.959641 -285.831223) (xy 342.936941 -285.785646)
			(xy 342.921499 -285.737126) (xy 342.913682 -285.686813) (xy 342.913208 -285.661354) (xy 342.634316 -285.661354)
			(xy 342.633807 -285.687321) (xy 342.625682 -285.738616) (xy 342.609634 -285.788009) (xy 342.586056 -285.834283)
			(xy 342.55553 -285.876299) (xy 342.518807 -285.913022) (xy 342.476791 -285.943548) (xy 342.430517 -285.967126)
			(xy 342.381124 -285.983174) (xy 342.329829 -285.991299) (xy 342.277895 -285.991299) (xy 342.2266 -285.983174)
			(xy 342.177207 -285.967126) (xy 342.130933 -285.943548) (xy 342.088917 -285.913022) (xy 342.052194 -285.876299)
			(xy 342.021668 -285.834283) (xy 341.99809 -285.788009) (xy 341.982042 -285.738616) (xy 341.973917 -285.687321)
			(xy 341.973408 -285.661354) (xy 341.97388 -285.635907) (xy 341.981687 -285.585614) (xy 341.99711 -285.537112)
			(xy 342.019783 -285.491547) (xy 342.049172 -285.449995) (xy 342.084582 -285.413438) (xy 342.125177 -285.38274)
			(xy 342.169996 -285.358626) (xy 342.217982 -285.341666) (xy 342.242902 -285.336488) (xy 342.266016 -285.33217)
			(xy 342.469978 -284.978856) (xy 342.462104 -284.956758) (xy 342.453445 -284.930287) (xy 342.444128 -284.875383)
			(xy 342.443562 -284.847538) (xy 342.444104 -284.820529) (xy 342.452895 -284.76723) (xy 342.470233 -284.716069)
			(xy 342.495656 -284.668408) (xy 342.511634 -284.646624) (xy 342.519862 -284.6351) (xy 342.530223 -284.60876)
			(xy 342.532957 -284.580587) (xy 342.527856 -284.552746) (xy 342.51531 -284.527374) (xy 342.496283 -284.506418)
			(xy 342.472236 -284.491489) (xy 342.445015 -284.483731) (xy 342.430862 -284.483302) (xy 341.23757 -284.483302)
			(xy 341.223419 -284.483767) (xy 341.196205 -284.491536) (xy 341.172164 -284.506468) (xy 341.153138 -284.527421)
			(xy 341.140587 -284.552787) (xy 341.135473 -284.580622) (xy 341.138187 -284.608793) (xy 341.148521 -284.63514)
			(xy 341.156798 -284.646624) (xy 341.172798 -284.668394) (xy 341.198237 -284.716055) (xy 341.21558 -284.76722)
			(xy 341.224366 -284.820526) (xy 341.22487 -284.847538) (xy 341.224396 -284.873011) (xy 341.216572 -284.923352)
			(xy 341.201115 -284.971896) (xy 341.178391 -285.017493) (xy 341.148939 -285.059062) (xy 341.113456 -285.095619)
			(xy 341.072783 -285.126297) (xy 341.027884 -285.15037) (xy 340.979822 -285.167268) (xy 340.954868 -285.172404)
			(xy 340.932008 -285.176722) (xy 340.7283 -285.529528) (xy 340.73592 -285.551626) (xy 340.744717 -285.5782)
			(xy 340.754174 -285.633368) (xy 340.754716 -285.661354) (xy 341.033608 -285.661354) (xy 341.034117 -285.635387)
			(xy 341.042242 -285.584092) (xy 341.05829 -285.534699) (xy 341.081868 -285.488425) (xy 341.112394 -285.446409)
			(xy 341.149117 -285.409686) (xy 341.191133 -285.37916) (xy 341.237407 -285.355582) (xy 341.2868 -285.339534)
			(xy 341.338095 -285.331409) (xy 341.390029 -285.331409) (xy 341.441324 -285.339534) (xy 341.490717 -285.355582)
			(xy 341.536991 -285.37916) (xy 341.579007 -285.409686) (xy 341.61573 -285.446409) (xy 341.646256 -285.488425)
			(xy 341.669834 -285.534699) (xy 341.685882 -285.584092) (xy 341.694007 -285.635387) (xy 341.694516 -285.661354)
			(xy 341.693984 -285.689264) (xy 341.684655 -285.744297) (xy 341.675974 -285.770828) (xy 341.6681 -285.792926)
			(xy 341.872062 -286.14624) (xy 341.895176 -286.150558) (xy 341.920101 -286.155707) (xy 341.968085 -286.172676)
			(xy 342.012902 -286.196798) (xy 342.053493 -286.227501) (xy 342.088901 -286.264061) (xy 342.118289 -286.305615)
			(xy 342.140962 -286.351181) (xy 342.156386 -286.399683) (xy 342.164196 -286.449976) (xy 342.16467 -286.475424)
			(xy 342.164161 -286.501391) (xy 342.443817 -286.501391) (xy 342.443817 -286.449457) (xy 342.451942 -286.398162)
			(xy 342.46799 -286.348769) (xy 342.491568 -286.302495) (xy 342.522094 -286.260479) (xy 342.558817 -286.223756)
			(xy 342.600833 -286.19323) (xy 342.647107 -286.169652) (xy 342.6965 -286.153604) (xy 342.747795 -286.145479)
			(xy 342.799729 -286.145479) (xy 342.851024 -286.153604) (xy 342.900417 -286.169652) (xy 342.946691 -286.19323)
			(xy 342.988707 -286.223756) (xy 343.02543 -286.260479) (xy 343.055956 -286.302495) (xy 343.079534 -286.348769)
			(xy 343.095582 -286.398162) (xy 343.103707 -286.449457) (xy 343.104216 -286.475424) (xy 343.103707 -286.501391)
			(xy 343.095582 -286.552686) (xy 343.079534 -286.602079) (xy 343.055956 -286.648353) (xy 343.02543 -286.690369)
			(xy 342.988707 -286.727092) (xy 342.946691 -286.757618) (xy 342.900417 -286.781196) (xy 342.851024 -286.797244)
			(xy 342.799729 -286.805369) (xy 342.747795 -286.805369) (xy 342.6965 -286.797244) (xy 342.647107 -286.781196)
			(xy 342.600833 -286.757618) (xy 342.558817 -286.727092) (xy 342.522094 -286.690369) (xy 342.491568 -286.648353)
			(xy 342.46799 -286.602079) (xy 342.451942 -286.552686) (xy 342.443817 -286.501391) (xy 342.164161 -286.501391)
			(xy 342.156036 -286.552686) (xy 342.139988 -286.602079) (xy 342.11641 -286.648353) (xy 342.085884 -286.690369)
			(xy 342.049161 -286.727092) (xy 342.007145 -286.757618) (xy 341.960871 -286.781196) (xy 341.911478 -286.797244)
			(xy 341.860183 -286.805369) (xy 341.808249 -286.805369) (xy 341.756954 -286.797244) (xy 341.707561 -286.781196)
			(xy 341.661287 -286.757618) (xy 341.619271 -286.727092) (xy 341.582548 -286.690369) (xy 341.552022 -286.648353)
			(xy 341.528444 -286.602079) (xy 341.512396 -286.552686) (xy 341.504271 -286.501391) (xy 341.503762 -286.475424)
			(xy 341.504317 -286.447438) (xy 341.513765 -286.39227) (xy 341.522558 -286.365696) (xy 341.530178 -286.343598)
			(xy 341.32647 -285.990538) (xy 341.303356 -285.98622) (xy 341.278428 -285.981024) (xy 341.230405 -285.964101)
			(xy 341.185545 -285.940014) (xy 341.144911 -285.909331) (xy 341.109464 -285.872779) (xy 341.080041 -285.831223)
			(xy 341.057341 -285.785646) (xy 341.041899 -285.737126) (xy 341.034082 -285.686813) (xy 341.033608 -285.661354)
			(xy 340.754716 -285.661354) (xy 340.754207 -285.687321) (xy 340.746082 -285.738616) (xy 340.730034 -285.788009)
			(xy 340.706456 -285.834283) (xy 340.67593 -285.876299) (xy 340.639207 -285.913022) (xy 340.597191 -285.943548)
			(xy 340.550917 -285.967126) (xy 340.501524 -285.983174) (xy 340.450229 -285.991299) (xy 340.398295 -285.991299)
			(xy 340.347 -285.983174) (xy 340.297607 -285.967126) (xy 340.251333 -285.943548) (xy 340.209317 -285.913022)
			(xy 340.172594 -285.876299) (xy 340.142068 -285.834283) (xy 340.11849 -285.788009) (xy 340.102442 -285.738616)
			(xy 340.094317 -285.687321) (xy 340.093808 -285.661354) (xy 340.09428 -285.635907) (xy 340.102087 -285.585614)
			(xy 340.11751 -285.537112) (xy 340.140183 -285.491547) (xy 340.169572 -285.449995) (xy 340.204982 -285.413438)
			(xy 340.245577 -285.38274) (xy 340.290396 -285.358626) (xy 340.338382 -285.341666) (xy 340.363302 -285.336488)
			(xy 340.386416 -285.33217) (xy 340.590378 -284.978856) (xy 340.582504 -284.956758) (xy 340.573845 -284.930287)
			(xy 340.564528 -284.875383) (xy 340.563962 -284.847538) (xy 340.564504 -284.820529) (xy 340.573295 -284.76723)
			(xy 340.590633 -284.716069) (xy 340.616056 -284.668408) (xy 340.632034 -284.646624) (xy 340.640262 -284.6351)
			(xy 340.650623 -284.60876) (xy 340.653357 -284.580587) (xy 340.648256 -284.552746) (xy 340.63571 -284.527374)
			(xy 340.616683 -284.506418) (xy 340.592636 -284.491489) (xy 340.565415 -284.483731) (xy 340.551262 -284.483302)
			(xy 340.03742 -284.483302) (xy 338.875624 -285.645098) (xy 338.875423 -285.661354) (xy 339.154262 -285.661354)
			(xy 339.154771 -285.635387) (xy 339.162896 -285.584092) (xy 339.178944 -285.534699) (xy 339.202522 -285.488425)
			(xy 339.233048 -285.446409) (xy 339.269771 -285.409686) (xy 339.311787 -285.37916) (xy 339.358061 -285.355582)
			(xy 339.407454 -285.339534) (xy 339.458749 -285.331409) (xy 339.510683 -285.331409) (xy 339.561978 -285.339534)
			(xy 339.611371 -285.355582) (xy 339.657645 -285.37916) (xy 339.699661 -285.409686) (xy 339.736384 -285.446409)
			(xy 339.76691 -285.488425) (xy 339.790488 -285.534699) (xy 339.806536 -285.584092) (xy 339.814661 -285.635387)
			(xy 339.81517 -285.661354) (xy 339.814607 -285.689339) (xy 339.805164 -285.744507) (xy 339.796374 -285.771082)
			(xy 339.788754 -285.79318) (xy 339.992462 -286.14624) (xy 340.015576 -286.150558) (xy 340.040501 -286.155707)
			(xy 340.088485 -286.172676) (xy 340.133302 -286.196798) (xy 340.173893 -286.227501) (xy 340.209301 -286.264061)
			(xy 340.238689 -286.305615) (xy 340.261362 -286.351181) (xy 340.276786 -286.399683) (xy 340.284596 -286.449976)
			(xy 340.28507 -286.475424) (xy 340.284561 -286.501391) (xy 340.564471 -286.501391) (xy 340.564471 -286.449457)
			(xy 340.572596 -286.398162) (xy 340.588644 -286.348769) (xy 340.612222 -286.302495) (xy 340.642748 -286.260479)
			(xy 340.679471 -286.223756) (xy 340.721487 -286.19323) (xy 340.767761 -286.169652) (xy 340.817154 -286.153604)
			(xy 340.868449 -286.145479) (xy 340.920383 -286.145479) (xy 340.971678 -286.153604) (xy 341.021071 -286.169652)
			(xy 341.067345 -286.19323) (xy 341.109361 -286.223756) (xy 341.146084 -286.260479) (xy 341.17661 -286.302495)
			(xy 341.200188 -286.348769) (xy 341.216236 -286.398162) (xy 341.224361 -286.449457) (xy 341.22487 -286.475424)
			(xy 341.224361 -286.501391) (xy 341.216236 -286.552686) (xy 341.200188 -286.602079) (xy 341.17661 -286.648353)
			(xy 341.146084 -286.690369) (xy 341.109361 -286.727092) (xy 341.067345 -286.757618) (xy 341.021071 -286.781196)
			(xy 340.971678 -286.797244) (xy 340.920383 -286.805369) (xy 340.868449 -286.805369) (xy 340.817154 -286.797244)
			(xy 340.767761 -286.781196) (xy 340.721487 -286.757618) (xy 340.679471 -286.727092) (xy 340.642748 -286.690369)
			(xy 340.612222 -286.648353) (xy 340.588644 -286.602079) (xy 340.572596 -286.552686) (xy 340.564471 -286.501391)
			(xy 340.284561 -286.501391) (xy 340.276436 -286.552686) (xy 340.260388 -286.602079) (xy 340.23681 -286.648353)
			(xy 340.206284 -286.690369) (xy 340.169561 -286.727092) (xy 340.127545 -286.757618) (xy 340.081271 -286.781196)
			(xy 340.031878 -286.797244) (xy 339.980583 -286.805369) (xy 339.928649 -286.805369) (xy 339.877354 -286.797244)
			(xy 339.827961 -286.781196) (xy 339.781687 -286.757618) (xy 339.739671 -286.727092) (xy 339.702948 -286.690369)
			(xy 339.672422 -286.648353) (xy 339.648844 -286.602079) (xy 339.632796 -286.552686) (xy 339.624671 -286.501391)
			(xy 339.624162 -286.475424) (xy 339.624717 -286.447438) (xy 339.634165 -286.39227) (xy 339.642958 -286.365696)
			(xy 339.650578 -286.343598) (xy 339.44687 -285.990538) (xy 339.423756 -285.98622) (xy 339.398831 -285.981068)
			(xy 339.350846 -285.964102) (xy 339.306027 -285.939983) (xy 339.265434 -285.909281) (xy 339.230025 -285.872721)
			(xy 339.200638 -285.831166) (xy 339.177964 -285.785599) (xy 339.162542 -285.737096) (xy 339.154734 -285.686802)
			(xy 339.154262 -285.661354) (xy 338.875423 -285.661354) (xy 338.87537 -285.665672) (xy 338.874564 -285.691205)
			(xy 338.866053 -285.741572) (xy 338.849893 -285.790031) (xy 338.82647 -285.835426) (xy 338.796341 -285.876677)
			(xy 338.760224 -285.9128) (xy 338.718979 -285.942937) (xy 338.673589 -285.966369) (xy 338.625133 -285.982538)
			(xy 338.574767 -285.991058) (xy 338.549234 -285.991808) (xy 338.52866 -285.992062) (xy 338.295488 -286.225234)
			(xy 338.325968 -286.260794) (xy 338.340854 -286.27882) (xy 338.365929 -286.318277) (xy 338.385186 -286.360876)
			(xy 338.398241 -286.405766) (xy 338.404833 -286.452049) (xy 338.405216 -286.475424) (xy 338.404731 -286.501391)
			(xy 338.684617 -286.501391) (xy 338.684617 -286.449457) (xy 338.692742 -286.398162) (xy 338.70879 -286.348769)
			(xy 338.732368 -286.302495) (xy 338.762894 -286.260479) (xy 338.799617 -286.223756) (xy 338.841633 -286.19323)
			(xy 338.887907 -286.169652) (xy 338.9373 -286.153604) (xy 338.988595 -286.145479) (xy 339.040529 -286.145479)
			(xy 339.091824 -286.153604) (xy 339.141217 -286.169652) (xy 339.187491 -286.19323) (xy 339.229507 -286.223756)
			(xy 339.26623 -286.260479) (xy 339.296756 -286.302495) (xy 339.320334 -286.348769) (xy 339.336382 -286.398162)
			(xy 339.344507 -286.449457) (xy 339.345016 -286.475424) (xy 339.344507 -286.501391) (xy 339.336382 -286.552686)
			(xy 339.320334 -286.602079) (xy 339.296756 -286.648353) (xy 339.26623 -286.690369) (xy 339.229507 -286.727092)
			(xy 339.187491 -286.757618) (xy 339.141217 -286.781196) (xy 339.091824 -286.797244) (xy 339.040529 -286.805369)
			(xy 338.988595 -286.805369) (xy 338.9373 -286.797244) (xy 338.887907 -286.781196) (xy 338.841633 -286.757618)
			(xy 338.799617 -286.727092) (xy 338.762894 -286.690369) (xy 338.732368 -286.648353) (xy 338.70879 -286.602079)
			(xy 338.692742 -286.552686) (xy 338.684617 -286.501391) (xy 338.404731 -286.501391) (xy 338.396603 -286.552685)
			(xy 338.380551 -286.602076) (xy 338.356969 -286.648347) (xy 338.326439 -286.69036) (xy 338.289713 -286.72708)
			(xy 338.247694 -286.757602) (xy 338.201419 -286.781174) (xy 338.152025 -286.797218) (xy 338.100729 -286.805336)
			(xy 338.074762 -286.805878) (xy 338.051389 -286.80547) (xy 338.005111 -286.798874) (xy 337.960225 -286.785818)
			(xy 337.917629 -286.766564) (xy 337.878173 -286.741496) (xy 337.860132 -286.72663) (xy 337.824572 -286.69615)
			(xy 337.676744 -286.843978) (xy 337.676744 -286.964628) (xy 337.711288 -286.976312) (xy 337.735457 -286.98504)
			(xy 337.780961 -287.008906) (xy 337.822222 -287.039529) (xy 337.858244 -287.076171) (xy 337.888158 -287.117949)
			(xy 337.911243 -287.163855) (xy 337.926942 -287.212781) (xy 337.934876 -287.263548) (xy 337.935316 -287.28924)
			(xy 337.93477 -287.315696) (xy 337.926296 -287.367926) (xy 337.909619 -287.418142) (xy 337.885164 -287.465065)
			(xy 337.869784 -287.486598) (xy 337.902379 -287.52648) (xy 337.959779 -287.612011) (xy 337.984338 -287.657286)
			(xy 337.991024 -287.669096) (xy 338.009525 -287.688941) (xy 338.032603 -287.703204) (xy 338.058625 -287.710878)
			(xy 338.08575 -287.711418) (xy 338.112057 -287.704787) (xy 338.135685 -287.691453) (xy 338.15496 -287.672362)
			(xy 338.162138 -287.660842) (xy 338.183728 -287.623504) (xy 338.20508 -287.587431) (xy 338.253154 -287.518753)
			(xy 338.27974 -287.486344) (xy 338.26439 -287.46484) (xy 338.240008 -287.41797) (xy 338.223403 -287.367815)
			(xy 338.214998 -287.315656) (xy 338.214462 -287.28924) (xy 338.214942 -287.263269) (xy 338.223062 -287.211966)
			(xy 338.239109 -287.162565) (xy 338.262686 -287.116283) (xy 338.293215 -287.07426) (xy 338.329942 -287.03753)
			(xy 338.371963 -287.006999) (xy 338.418243 -286.983418) (xy 338.467643 -286.967368) (xy 338.518945 -286.959244)
			(xy 338.544916 -286.958786) (xy 338.572408 -286.959333) (xy 338.626635 -286.968432) (xy 338.678609 -286.986377)
			(xy 338.726898 -287.012673) (xy 338.770171 -287.046595) (xy 338.807236 -287.087209) (xy 338.837071 -287.133396)
			(xy 338.848446 -287.15843) (xy 338.889639 -287.151642) (xy 338.972816 -287.144391) (xy 339.014562 -287.143952)
			(xy 339.056435 -287.144387) (xy 339.139866 -287.151635) (xy 339.181186 -287.15843) (xy 339.192564 -287.133393)
			(xy 339.22238 -287.087184) (xy 339.259435 -287.046551) (xy 339.302707 -287.012614) (xy 339.351001 -286.986312)
			(xy 339.402983 -286.968369) (xy 339.45722 -286.959282) (xy 339.484716 -286.958786) (xy 339.510683 -286.95927)
			(xy 339.561978 -286.967397) (xy 339.61137 -286.983449) (xy 339.657643 -287.00703) (xy 339.699656 -287.03756)
			(xy 339.736376 -287.074286) (xy 339.766899 -287.116305) (xy 339.790472 -287.162582) (xy 339.806516 -287.211976)
			(xy 339.814634 -287.263273) (xy 339.81517 -287.28924) (xy 339.814644 -287.315728) (xy 339.806194 -287.368027)
			(xy 339.789516 -287.41831) (xy 339.765036 -287.465292) (xy 339.749638 -287.486852) (xy 339.782169 -287.526741)
			(xy 339.839444 -287.612269)
		)
		(stroke
			(width 0)
			(type solid)
		)
		(fill yes)
		(layer "In4.Cu")
		(net "PVCCFA_EHV_FIVRA_CPU0")
	)
	(gr_poly
		(pts
			(xy 91.92387 -287.65754) (xy 91.930579 -287.669355) (xy 91.949121 -287.689203) (xy 91.972235 -287.703468)
			(xy 91.998289 -287.711144) (xy 92.025445 -287.711689) (xy 92.051786 -287.705064) (xy 92.075453 -287.691738)
			(xy 92.094777 -287.67265) (xy 92.101924 -287.661096) (xy 92.123514 -287.623504) (xy 92.144872 -287.587495)
			(xy 92.192947 -287.518945) (xy 92.219526 -287.486598) (xy 92.204119 -287.46508) (xy 92.179639 -287.418163)
			(xy 92.162959 -287.36794) (xy 92.154508 -287.3157) (xy 92.153994 -287.28924) (xy 92.154474 -287.26327)
			(xy 92.162594 -287.211969) (xy 92.178641 -287.16257) (xy 92.202219 -287.11629) (xy 92.232748 -287.07427)
			(xy 92.269476 -287.037543) (xy 92.311497 -287.007015) (xy 92.357777 -286.983438) (xy 92.407177 -286.967392)
			(xy 92.458478 -286.959273) (xy 92.484448 -286.958786) (xy 92.511939 -286.959335) (xy 92.566162 -286.968439)
			(xy 92.618132 -286.986387) (xy 92.666416 -287.012685) (xy 92.709685 -287.046609) (xy 92.746746 -287.087223)
			(xy 92.776577 -287.133408) (xy 92.787978 -287.15843) (xy 92.829233 -287.151623) (xy 92.912538 -287.144374)
			(xy 92.954348 -287.143952) (xy 92.996093 -287.144407) (xy 93.079269 -287.151659) (xy 93.120464 -287.15843)
			(xy 93.131844 -287.133396) (xy 93.161661 -287.087196) (xy 93.198718 -287.046571) (xy 93.241991 -287.012644)
			(xy 93.290286 -286.986353) (xy 93.342267 -286.968422) (xy 93.3965 -286.959347) (xy 93.423994 -286.958786)
			(xy 93.449962 -286.959268) (xy 93.50126 -286.967393) (xy 93.550655 -286.983443) (xy 93.59693 -287.007023)
			(xy 93.638947 -287.037552) (xy 93.67567 -287.074279) (xy 93.706195 -287.116299) (xy 93.72977 -287.162577)
			(xy 93.745815 -287.211973) (xy 93.753934 -287.263271) (xy 93.754448 -287.28924) (xy 93.753925 -287.315656)
			(xy 93.745508 -287.367812) (xy 93.728894 -287.417964) (xy 93.704508 -287.464831) (xy 93.68917 -287.486344)
			(xy 93.721777 -287.526285) (xy 93.77918 -287.611942) (xy 93.803724 -287.657286) (xy 93.810411 -287.669098)
			(xy 93.828912 -287.688946) (xy 93.851991 -287.703213) (xy 93.878016 -287.710889) (xy 93.905144 -287.711431)
			(xy 93.931455 -287.704801) (xy 93.955087 -287.691468) (xy 93.974366 -287.672375) (xy 93.981524 -287.660842)
			(xy 94.003114 -287.623504) (xy 94.02441 -287.587561) (xy 94.072357 -287.519137) (xy 94.098872 -287.486852)
			(xy 94.083458 -287.465301) (xy 94.058969 -287.418319) (xy 94.042285 -287.368033) (xy 94.033831 -287.315731)
			(xy 94.03334 -287.28924) (xy 94.03382 -287.263268) (xy 94.04194 -287.211964) (xy 94.057986 -287.162562)
			(xy 94.081564 -287.116278) (xy 94.112091 -287.074253) (xy 94.148818 -287.037521) (xy 94.190839 -287.006988)
			(xy 94.237119 -286.983404) (xy 94.286519 -286.967351) (xy 94.337823 -286.959223) (xy 94.363794 -286.958786)
			(xy 94.391283 -286.959339) (xy 94.445501 -286.968449) (xy 94.497465 -286.986402) (xy 94.545743 -287.012703)
			(xy 94.589006 -287.046628) (xy 94.626061 -287.087242) (xy 94.655887 -287.133426) (xy 94.667324 -287.15843)
			(xy 94.708641 -287.151613) (xy 94.792074 -287.14436) (xy 94.833948 -287.143952) (xy 94.875693 -287.144407)
			(xy 94.958869 -287.151659) (xy 95.000064 -287.15843) (xy 95.011444 -287.133396) (xy 95.041261 -287.087196)
			(xy 95.078318 -287.046571) (xy 95.121591 -287.012644) (xy 95.169886 -286.986353) (xy 95.221867 -286.968422)
			(xy 95.2761 -286.959347) (xy 95.303594 -286.958786) (xy 95.329562 -286.959268) (xy 95.38086 -286.967393)
			(xy 95.430255 -286.983443) (xy 95.47653 -287.007023) (xy 95.518547 -287.037552) (xy 95.55527 -287.074279)
			(xy 95.585795 -287.116299) (xy 95.60937 -287.162577) (xy 95.625415 -287.211973) (xy 95.633534 -287.263271)
			(xy 95.634048 -287.28924) (xy 95.633525 -287.315656) (xy 95.625108 -287.367812) (xy 95.608494 -287.417964)
			(xy 95.584108 -287.464831) (xy 95.56877 -287.486344) (xy 95.601377 -287.526285) (xy 95.65878 -287.611942)
			(xy 95.683324 -287.657286) (xy 95.690011 -287.669098) (xy 95.708512 -287.688946) (xy 95.731591 -287.703213)
			(xy 95.757616 -287.710889) (xy 95.784744 -287.711431) (xy 95.811055 -287.704801) (xy 95.834687 -287.691468)
			(xy 95.853966 -287.672375) (xy 95.861124 -287.660842) (xy 95.882714 -287.623504) (xy 95.90401 -287.587561)
			(xy 95.951957 -287.519137) (xy 95.978472 -287.486852) (xy 95.963058 -287.465301) (xy 95.938569 -287.418319)
			(xy 95.921885 -287.368033) (xy 95.913431 -287.315731) (xy 95.91294 -287.28924) (xy 95.91342 -287.263268)
			(xy 95.92154 -287.211964) (xy 95.937586 -287.162562) (xy 95.961164 -287.116278) (xy 95.991691 -287.074253)
			(xy 96.028418 -287.037521) (xy 96.070439 -287.006988) (xy 96.116719 -286.983404) (xy 96.166119 -286.967351)
			(xy 96.217423 -286.959223) (xy 96.243394 -286.958786) (xy 96.270883 -286.959339) (xy 96.325101 -286.968449)
			(xy 96.377065 -286.986402) (xy 96.425343 -287.012703) (xy 96.468606 -287.046628) (xy 96.505661 -287.087242)
			(xy 96.535487 -287.133426) (xy 96.546924 -287.15843) (xy 96.588241 -287.151613) (xy 96.671674 -287.14436)
			(xy 96.713548 -287.143952) (xy 96.755293 -287.144407) (xy 96.838469 -287.151659) (xy 96.879664 -287.15843)
			(xy 96.891044 -287.133396) (xy 96.920861 -287.087196) (xy 96.957918 -287.046571) (xy 97.001191 -287.012644)
			(xy 97.049486 -286.986353) (xy 97.101467 -286.968422) (xy 97.1557 -286.959347) (xy 97.183194 -286.958786)
			(xy 97.209162 -286.959268) (xy 97.26046 -286.967393) (xy 97.309855 -286.983443) (xy 97.35613 -287.007023)
			(xy 97.398147 -287.037552) (xy 97.43487 -287.074279) (xy 97.465395 -287.116299) (xy 97.48897 -287.162577)
			(xy 97.505015 -287.211973) (xy 97.513134 -287.263271) (xy 97.513648 -287.28924) (xy 97.513125 -287.315656)
			(xy 97.504708 -287.367812) (xy 97.488094 -287.417964) (xy 97.463708 -287.464831) (xy 97.44837 -287.486344)
			(xy 97.480977 -287.526285) (xy 97.53838 -287.611942) (xy 97.562924 -287.657286) (xy 97.569611 -287.669098)
			(xy 97.588112 -287.688946) (xy 97.611191 -287.703213) (xy 97.637216 -287.710889) (xy 97.664344 -287.711431)
			(xy 97.690655 -287.704801) (xy 97.714287 -287.691468) (xy 97.733566 -287.672375) (xy 97.740724 -287.660842)
			(xy 97.762314 -287.623504) (xy 97.78361 -287.587561) (xy 97.831557 -287.519137) (xy 97.858072 -287.486852)
			(xy 97.842658 -287.465301) (xy 97.818169 -287.418319) (xy 97.801485 -287.368033) (xy 97.793031 -287.315731)
			(xy 97.79254 -287.28924) (xy 97.79302 -287.263268) (xy 97.80114 -287.211964) (xy 97.817186 -287.162562)
			(xy 97.840764 -287.116278) (xy 97.871291 -287.074253) (xy 97.908018 -287.037521) (xy 97.950039 -287.006988)
			(xy 97.996319 -286.983404) (xy 98.045719 -286.967351) (xy 98.097023 -286.959223) (xy 98.122994 -286.958786)
			(xy 98.150483 -286.959339) (xy 98.204701 -286.968449) (xy 98.256665 -286.986402) (xy 98.304943 -287.012703)
			(xy 98.348206 -287.046628) (xy 98.385261 -287.087242) (xy 98.415087 -287.133426) (xy 98.426524 -287.15843)
			(xy 98.467841 -287.151613) (xy 98.551274 -287.14436) (xy 98.593148 -287.143952) (xy 98.634893 -287.144407)
			(xy 98.718069 -287.151659) (xy 98.759264 -287.15843) (xy 98.770644 -287.133396) (xy 98.800461 -287.087196)
			(xy 98.837518 -287.046571) (xy 98.880791 -287.012644) (xy 98.929086 -286.986353) (xy 98.981067 -286.968422)
			(xy 99.0353 -286.959347) (xy 99.062794 -286.958786) (xy 99.088762 -286.959268) (xy 99.14006 -286.967393)
			(xy 99.189455 -286.983443) (xy 99.23573 -287.007023) (xy 99.277747 -287.037552) (xy 99.31447 -287.074279)
			(xy 99.344995 -287.116299) (xy 99.36857 -287.162577) (xy 99.384615 -287.211973) (xy 99.392734 -287.263271)
			(xy 99.393248 -287.28924) (xy 99.392725 -287.315656) (xy 99.384308 -287.367812) (xy 99.367694 -287.417964)
			(xy 99.343308 -287.464831) (xy 99.32797 -287.486344) (xy 99.360577 -287.526285) (xy 99.41798 -287.611942)
			(xy 99.442524 -287.657286) (xy 99.449211 -287.669098) (xy 99.467712 -287.688946) (xy 99.490791 -287.703213)
			(xy 99.516816 -287.710889) (xy 99.543944 -287.711431) (xy 99.570255 -287.704801) (xy 99.593887 -287.691468)
			(xy 99.613166 -287.672375) (xy 99.620324 -287.660842) (xy 99.641914 -287.623504) (xy 99.66321 -287.587561)
			(xy 99.711157 -287.519137) (xy 99.737672 -287.486852) (xy 99.722258 -287.465301) (xy 99.697769 -287.418319)
			(xy 99.681085 -287.368033) (xy 99.672631 -287.315731) (xy 99.67214 -287.28924) (xy 99.67262 -287.263268)
			(xy 99.68074 -287.211964) (xy 99.696786 -287.162562) (xy 99.720364 -287.116278) (xy 99.750891 -287.074253)
			(xy 99.787618 -287.037521) (xy 99.829639 -287.006988) (xy 99.875919 -286.983404) (xy 99.925319 -286.967351)
			(xy 99.976623 -286.959223) (xy 100.002594 -286.958786) (xy 100.030083 -286.959339) (xy 100.084301 -286.968449)
			(xy 100.136265 -286.986402) (xy 100.184543 -287.012703) (xy 100.227806 -287.046628) (xy 100.264861 -287.087242)
			(xy 100.294687 -287.133426) (xy 100.306124 -287.15843) (xy 100.347441 -287.151613) (xy 100.430874 -287.14436)
			(xy 100.472748 -287.143952) (xy 100.514493 -287.144407) (xy 100.597669 -287.151659) (xy 100.638864 -287.15843)
			(xy 100.650244 -287.133396) (xy 100.680061 -287.087196) (xy 100.717118 -287.046571) (xy 100.760391 -287.012644)
			(xy 100.808686 -286.986353) (xy 100.860667 -286.968422) (xy 100.9149 -286.959347) (xy 100.942394 -286.958786)
			(xy 100.968362 -286.959268) (xy 101.01966 -286.967393) (xy 101.069055 -286.983443) (xy 101.11533 -287.007023)
			(xy 101.157347 -287.037552) (xy 101.19407 -287.074279) (xy 101.224595 -287.116299) (xy 101.24817 -287.162577)
			(xy 101.264215 -287.211973) (xy 101.272334 -287.263271) (xy 101.272848 -287.28924) (xy 101.272325 -287.315656)
			(xy 101.263908 -287.367812) (xy 101.247294 -287.417964) (xy 101.222908 -287.464831) (xy 101.20757 -287.486344)
			(xy 101.240177 -287.526285) (xy 101.29758 -287.611942) (xy 101.322124 -287.657286) (xy 101.328811 -287.669098)
			(xy 101.347312 -287.688946) (xy 101.370391 -287.703213) (xy 101.396416 -287.710889) (xy 101.423544 -287.711431)
			(xy 101.449855 -287.704801) (xy 101.473487 -287.691468) (xy 101.492766 -287.672375) (xy 101.499924 -287.660842)
			(xy 101.521514 -287.623504) (xy 101.54281 -287.587561) (xy 101.590757 -287.519137) (xy 101.617272 -287.486852)
			(xy 101.601858 -287.465301) (xy 101.577369 -287.418319) (xy 101.560685 -287.368033) (xy 101.552231 -287.315731)
			(xy 101.55174 -287.28924) (xy 101.55222 -287.263268) (xy 101.56034 -287.211964) (xy 101.576386 -287.162562)
			(xy 101.599964 -287.116278) (xy 101.630491 -287.074253) (xy 101.667218 -287.037521) (xy 101.709239 -287.006988)
			(xy 101.755519 -286.983404) (xy 101.804919 -286.967351) (xy 101.856223 -286.959223) (xy 101.882194 -286.958786)
			(xy 101.909683 -286.959339) (xy 101.963901 -286.968449) (xy 102.015865 -286.986402) (xy 102.064143 -287.012703)
			(xy 102.107406 -287.046628) (xy 102.144461 -287.087242) (xy 102.174287 -287.133426) (xy 102.185724 -287.15843)
			(xy 102.227041 -287.151613) (xy 102.310474 -287.14436) (xy 102.352348 -287.143952) (xy 102.394093 -287.144407)
			(xy 102.477269 -287.151659) (xy 102.518464 -287.15843) (xy 102.529844 -287.133396) (xy 102.559661 -287.087196)
			(xy 102.596718 -287.046571) (xy 102.639991 -287.012644) (xy 102.688286 -286.986353) (xy 102.740267 -286.968422)
			(xy 102.7945 -286.959347) (xy 102.821994 -286.958786) (xy 102.847962 -286.959268) (xy 102.89926 -286.967393)
			(xy 102.948655 -286.983443) (xy 102.99493 -287.007023) (xy 103.036947 -287.037552) (xy 103.07367 -287.074279)
			(xy 103.104195 -287.116299) (xy 103.12777 -287.162577) (xy 103.143815 -287.211973) (xy 103.151934 -287.263271)
			(xy 103.152448 -287.28924) (xy 103.151925 -287.315656) (xy 103.143508 -287.367812) (xy 103.126894 -287.417964)
			(xy 103.102508 -287.464831) (xy 103.08717 -287.486344) (xy 103.119777 -287.526285) (xy 103.17718 -287.611942)
			(xy 103.201724 -287.657286) (xy 103.208411 -287.669098) (xy 103.226912 -287.688946) (xy 103.249991 -287.703213)
			(xy 103.276016 -287.710889) (xy 103.303144 -287.711431) (xy 103.329455 -287.704801) (xy 103.353087 -287.691468)
			(xy 103.372366 -287.672375) (xy 103.379524 -287.660842) (xy 103.401114 -287.623504) (xy 103.42241 -287.587561)
			(xy 103.470357 -287.519137) (xy 103.496872 -287.486852) (xy 103.481458 -287.465301) (xy 103.456969 -287.418319)
			(xy 103.440285 -287.368033) (xy 103.431831 -287.315731) (xy 103.43134 -287.28924) (xy 103.43182 -287.263268)
			(xy 103.43994 -287.211964) (xy 103.455986 -287.162562) (xy 103.479564 -287.116278) (xy 103.510091 -287.074253)
			(xy 103.546818 -287.037521) (xy 103.588839 -287.006988) (xy 103.635119 -286.983404) (xy 103.684519 -286.967351)
			(xy 103.735823 -286.959223) (xy 103.761794 -286.958786) (xy 103.786871 -286.959255) (xy 103.836451 -286.966831)
			(xy 103.884322 -286.981796) (xy 103.929389 -287.003807) (xy 103.950262 -287.017714) (xy 103.961895 -287.025227)
			(xy 103.988036 -287.034327) (xy 104.015662 -287.036066) (xy 104.042738 -287.030316) (xy 104.067273 -287.017501)
			(xy 104.087461 -286.998563) (xy 104.101816 -286.974896) (xy 104.109282 -286.948242) (xy 104.109774 -286.934402)
			(xy 104.109774 -286.784034) (xy 104.082088 -286.770064) (xy 104.059122 -286.757859) (xy 104.01701 -286.727342)
			(xy 103.980199 -286.690605) (xy 103.949595 -286.648556) (xy 103.925956 -286.602233) (xy 103.909863 -286.552779)
			(xy 103.901716 -286.501414) (xy 103.901714 -286.449408) (xy 103.909858 -286.398043) (xy 103.925947 -286.348587)
			(xy 103.949584 -286.302262) (xy 103.980184 -286.260211) (xy 104.016994 -286.223473) (xy 104.059103 -286.192953)
			(xy 104.082088 -286.180784) (xy 104.109774 -286.166814) (xy 104.109774 -286.016192) (xy 104.109318 -286.002339)
			(xy 104.101884 -285.975651) (xy 104.087539 -285.95195) (xy 104.067342 -285.932985) (xy 104.042786 -285.920159)
			(xy 104.015683 -285.914417) (xy 103.988035 -285.916183) (xy 103.961884 -285.925328) (xy 103.950262 -285.93288)
			(xy 103.929396 -285.946804) (xy 103.88434 -285.968853) (xy 103.836465 -285.983825) (xy 103.786875 -285.991375)
			(xy 103.761794 -285.991808) (xy 103.735826 -285.991325) (xy 103.684531 -285.983199) (xy 103.635138 -285.967148)
			(xy 103.588864 -285.943567) (xy 103.54685 -285.913037) (xy 103.510129 -285.876311) (xy 103.479606 -285.834291)
			(xy 103.456032 -285.788014) (xy 103.439989 -285.738619) (xy 103.431871 -285.687322) (xy 103.43134 -285.661354)
			(xy 103.431812 -285.635905) (xy 103.439618 -285.585609) (xy 103.45504 -285.537104) (xy 103.477711 -285.491535)
			(xy 103.507099 -285.449977) (xy 103.542507 -285.413414) (xy 103.583099 -285.382709) (xy 103.627918 -285.358586)
			(xy 103.675903 -285.341616) (xy 103.700834 -285.336488) (xy 103.723948 -285.33217) (xy 103.92791 -284.978856)
			(xy 103.920036 -284.956758) (xy 103.911377 -284.930288) (xy 103.902059 -284.875383) (xy 103.901494 -284.847538)
			(xy 103.902008 -284.822034) (xy 103.909919 -284.771643) (xy 103.917242 -284.747208) (xy 103.92664 -284.717744)
			(xy 103.692198 -284.483302) (xy 103.635048 -284.483302) (xy 103.6209 -284.48377) (xy 103.593691 -284.491542)
			(xy 103.569655 -284.506475) (xy 103.550635 -284.527426) (xy 103.538087 -284.552789) (xy 103.532973 -284.58062)
			(xy 103.535685 -284.608787) (xy 103.546015 -284.63513) (xy 103.554276 -284.646624) (xy 103.570273 -284.668396)
			(xy 103.595706 -284.716058) (xy 103.613045 -284.767222) (xy 103.621828 -284.820526) (xy 103.622348 -284.847538)
			(xy 103.621839 -284.873505) (xy 103.613714 -284.9248) (xy 103.597666 -284.974193) (xy 103.574088 -285.020467)
			(xy 103.543562 -285.062483) (xy 103.506839 -285.099206) (xy 103.464823 -285.129732) (xy 103.418549 -285.15331)
			(xy 103.369156 -285.169358) (xy 103.317861 -285.177483) (xy 103.265927 -285.177483) (xy 103.214632 -285.169358)
			(xy 103.165239 -285.15331) (xy 103.118965 -285.129732) (xy 103.076949 -285.099206) (xy 103.040226 -285.062483)
			(xy 103.0097 -285.020467) (xy 102.986122 -284.974193) (xy 102.970074 -284.9248) (xy 102.961949 -284.873505)
			(xy 102.96144 -284.847538) (xy 102.961982 -284.820529) (xy 102.970772 -284.76723) (xy 102.988109 -284.716068)
			(xy 103.013532 -284.668406) (xy 103.029512 -284.646624) (xy 103.037741 -284.635101) (xy 103.048104 -284.608762)
			(xy 103.05084 -284.58059) (xy 103.045739 -284.55275) (xy 103.033192 -284.527378) (xy 103.014163 -284.506425)
			(xy 102.990114 -284.491498) (xy 102.962892 -284.483746) (xy 102.94874 -284.483302) (xy 102.695502 -284.483302)
			(xy 102.681348 -284.483763) (xy 102.654126 -284.491527) (xy 102.630076 -284.506458) (xy 102.611044 -284.527413)
			(xy 102.598488 -284.552784) (xy 102.593373 -284.580626) (xy 102.596089 -284.608803) (xy 102.606429 -284.635154)
			(xy 102.61473 -284.646624) (xy 102.630729 -284.668395) (xy 102.656165 -284.716056) (xy 102.673507 -284.767221)
			(xy 102.682291 -284.820526) (xy 102.682802 -284.847538) (xy 102.682328 -284.873009) (xy 102.674503 -284.923347)
			(xy 102.659045 -284.971888) (xy 102.636319 -285.01748) (xy 102.606865 -285.059044) (xy 102.57138 -285.095595)
			(xy 102.530706 -285.126266) (xy 102.485805 -285.150331) (xy 102.437744 -285.167218) (xy 102.4128 -285.172404)
			(xy 102.38994 -285.176722) (xy 102.186232 -285.529528) (xy 102.193852 -285.551626) (xy 102.20265 -285.5782)
			(xy 102.21211 -285.633367) (xy 102.212648 -285.661354) (xy 102.49154 -285.661354) (xy 102.492049 -285.635387)
			(xy 102.500174 -285.584092) (xy 102.516222 -285.534699) (xy 102.5398 -285.488425) (xy 102.570326 -285.446409)
			(xy 102.607049 -285.409686) (xy 102.649065 -285.37916) (xy 102.695339 -285.355582) (xy 102.744732 -285.339534)
			(xy 102.796027 -285.331409) (xy 102.847961 -285.331409) (xy 102.899256 -285.339534) (xy 102.948649 -285.355582)
			(xy 102.994923 -285.37916) (xy 103.036939 -285.409686) (xy 103.073662 -285.446409) (xy 103.104188 -285.488425)
			(xy 103.127766 -285.534699) (xy 103.143814 -285.584092) (xy 103.151939 -285.635387) (xy 103.152448 -285.661354)
			(xy 103.151915 -285.689264) (xy 103.142586 -285.744297) (xy 103.133906 -285.770828) (xy 103.126032 -285.792926)
			(xy 103.329994 -286.14624) (xy 103.353108 -286.150558) (xy 103.378023 -286.155756) (xy 103.426006 -286.172716)
			(xy 103.470824 -286.196829) (xy 103.511417 -286.227525) (xy 103.546827 -286.264079) (xy 103.576217 -286.305628)
			(xy 103.598892 -286.35119) (xy 103.614317 -286.399688) (xy 103.622128 -286.449978) (xy 103.622602 -286.475424)
			(xy 103.622093 -286.501391) (xy 103.613968 -286.552686) (xy 103.59792 -286.602079) (xy 103.574342 -286.648353)
			(xy 103.543816 -286.690369) (xy 103.507093 -286.727092) (xy 103.465077 -286.757618) (xy 103.418803 -286.781196)
			(xy 103.36941 -286.797244) (xy 103.318115 -286.805369) (xy 103.266181 -286.805369) (xy 103.214886 -286.797244)
			(xy 103.165493 -286.781196) (xy 103.119219 -286.757618) (xy 103.077203 -286.727092) (xy 103.04048 -286.690369)
			(xy 103.009954 -286.648353) (xy 102.986376 -286.602079) (xy 102.970328 -286.552686) (xy 102.962203 -286.501391)
			(xy 102.961694 -286.475424) (xy 102.962253 -286.447438) (xy 102.971699 -286.392271) (xy 102.98049 -286.365696)
			(xy 102.98811 -286.343598) (xy 102.784402 -285.990538) (xy 102.761288 -285.98622) (xy 102.736349 -285.981073)
			(xy 102.688326 -285.964141) (xy 102.643468 -285.940045) (xy 102.602835 -285.909355) (xy 102.56739 -285.872796)
			(xy 102.53797 -285.831235) (xy 102.515271 -285.785654) (xy 102.49983 -285.737131) (xy 102.492014 -285.686814)
			(xy 102.49154 -285.661354) (xy 102.212648 -285.661354) (xy 102.212139 -285.687321) (xy 102.204014 -285.738616)
			(xy 102.187966 -285.788009) (xy 102.164388 -285.834283) (xy 102.133862 -285.876299) (xy 102.097139 -285.913022)
			(xy 102.055123 -285.943548) (xy 102.008849 -285.967126) (xy 101.959456 -285.983174) (xy 101.908161 -285.991299)
			(xy 101.856227 -285.991299) (xy 101.804932 -285.983174) (xy 101.755539 -285.967126) (xy 101.709265 -285.943548)
			(xy 101.667249 -285.913022) (xy 101.630526 -285.876299) (xy 101.6 -285.834283) (xy 101.576422 -285.788009)
			(xy 101.560374 -285.738616) (xy 101.552249 -285.687321) (xy 101.55174 -285.661354) (xy 101.552212 -285.635905)
			(xy 101.560018 -285.585609) (xy 101.57544 -285.537104) (xy 101.598111 -285.491535) (xy 101.627499 -285.449977)
			(xy 101.662907 -285.413414) (xy 101.703499 -285.382709) (xy 101.748318 -285.358586) (xy 101.796303 -285.341616)
			(xy 101.821234 -285.336488) (xy 101.844348 -285.33217) (xy 102.04831 -284.978856) (xy 102.040436 -284.956758)
			(xy 102.031777 -284.930288) (xy 102.022459 -284.875383) (xy 102.021894 -284.847538) (xy 102.022436 -284.820529)
			(xy 102.031227 -284.767231) (xy 102.048567 -284.716071) (xy 102.073993 -284.668411) (xy 102.089966 -284.646624)
			(xy 102.098198 -284.635103) (xy 102.108565 -284.608767) (xy 102.111303 -284.580597) (xy 102.106202 -284.552757)
			(xy 102.093653 -284.527388) (xy 102.074622 -284.506438) (xy 102.05057 -284.491519) (xy 102.023346 -284.483777)
			(xy 102.009194 -284.483302) (xy 101.755702 -284.483302) (xy 101.741548 -284.483763) (xy 101.714326 -284.491527)
			(xy 101.690276 -284.506458) (xy 101.671244 -284.527413) (xy 101.658688 -284.552784) (xy 101.653573 -284.580626)
			(xy 101.656289 -284.608803) (xy 101.666629 -284.635154) (xy 101.67493 -284.646624) (xy 101.690929 -284.668395)
			(xy 101.716365 -284.716056) (xy 101.733707 -284.767221) (xy 101.742491 -284.820526) (xy 101.743002 -284.847538)
			(xy 101.742493 -284.873505) (xy 101.734368 -284.9248) (xy 101.71832 -284.974193) (xy 101.694742 -285.020467)
			(xy 101.664216 -285.062483) (xy 101.627493 -285.099206) (xy 101.585477 -285.129732) (xy 101.539203 -285.15331)
			(xy 101.48981 -285.169358) (xy 101.438515 -285.177483) (xy 101.386581 -285.177483) (xy 101.335286 -285.169358)
			(xy 101.285893 -285.15331) (xy 101.239619 -285.129732) (xy 101.197603 -285.099206) (xy 101.16088 -285.062483)
			(xy 101.130354 -285.020467) (xy 101.106776 -284.974193) (xy 101.090728 -284.9248) (xy 101.082603 -284.873505)
			(xy 101.082094 -284.847538) (xy 101.082636 -284.820529) (xy 101.091427 -284.767231) (xy 101.108767 -284.716071)
			(xy 101.134193 -284.668411) (xy 101.150166 -284.646624) (xy 101.158398 -284.635103) (xy 101.168765 -284.608767)
			(xy 101.171503 -284.580597) (xy 101.166402 -284.552757) (xy 101.153853 -284.527388) (xy 101.134822 -284.506438)
			(xy 101.11077 -284.491519) (xy 101.083546 -284.483777) (xy 101.069394 -284.483302) (xy 100.815902 -284.483302)
			(xy 100.801748 -284.483763) (xy 100.774526 -284.491527) (xy 100.750476 -284.506458) (xy 100.731444 -284.527413)
			(xy 100.718888 -284.552784) (xy 100.713773 -284.580626) (xy 100.716489 -284.608803) (xy 100.726829 -284.635154)
			(xy 100.73513 -284.646624) (xy 100.751129 -284.668395) (xy 100.776565 -284.716056) (xy 100.793907 -284.767221)
			(xy 100.802691 -284.820526) (xy 100.803202 -284.847538) (xy 100.802728 -284.873009) (xy 100.794903 -284.923347)
			(xy 100.779445 -284.971888) (xy 100.756719 -285.01748) (xy 100.727265 -285.059044) (xy 100.69178 -285.095595)
			(xy 100.651106 -285.126266) (xy 100.606205 -285.150331) (xy 100.558144 -285.167218) (xy 100.5332 -285.172404)
			(xy 100.51034 -285.176722) (xy 100.306632 -285.529528) (xy 100.314252 -285.551626) (xy 100.32305 -285.5782)
			(xy 100.33251 -285.633367) (xy 100.333048 -285.661354) (xy 100.61194 -285.661354) (xy 100.612449 -285.635387)
			(xy 100.620574 -285.584092) (xy 100.636622 -285.534699) (xy 100.6602 -285.488425) (xy 100.690726 -285.446409)
			(xy 100.727449 -285.409686) (xy 100.769465 -285.37916) (xy 100.815739 -285.355582) (xy 100.865132 -285.339534)
			(xy 100.916427 -285.331409) (xy 100.968361 -285.331409) (xy 101.019656 -285.339534) (xy 101.069049 -285.355582)
			(xy 101.115323 -285.37916) (xy 101.157339 -285.409686) (xy 101.194062 -285.446409) (xy 101.224588 -285.488425)
			(xy 101.248166 -285.534699) (xy 101.264214 -285.584092) (xy 101.272339 -285.635387) (xy 101.272848 -285.661354)
			(xy 101.272315 -285.689264) (xy 101.262986 -285.744297) (xy 101.254306 -285.770828) (xy 101.246432 -285.792926)
			(xy 101.450394 -286.14624) (xy 101.473508 -286.150558) (xy 101.498423 -286.155756) (xy 101.546406 -286.172716)
			(xy 101.591224 -286.196829) (xy 101.631817 -286.227525) (xy 101.667227 -286.264079) (xy 101.696617 -286.305628)
			(xy 101.719292 -286.35119) (xy 101.734717 -286.399688) (xy 101.742528 -286.449978) (xy 101.743002 -286.475424)
			(xy 101.742493 -286.501391) (xy 102.022149 -286.501391) (xy 102.022149 -286.449457) (xy 102.030274 -286.398162)
			(xy 102.046322 -286.348769) (xy 102.0699 -286.302495) (xy 102.100426 -286.260479) (xy 102.137149 -286.223756)
			(xy 102.179165 -286.19323) (xy 102.225439 -286.169652) (xy 102.274832 -286.153604) (xy 102.326127 -286.145479)
			(xy 102.378061 -286.145479) (xy 102.429356 -286.153604) (xy 102.478749 -286.169652) (xy 102.525023 -286.19323)
			(xy 102.567039 -286.223756) (xy 102.603762 -286.260479) (xy 102.634288 -286.302495) (xy 102.657866 -286.348769)
			(xy 102.673914 -286.398162) (xy 102.682039 -286.449457) (xy 102.682548 -286.475424) (xy 102.682039 -286.501391)
			(xy 102.673914 -286.552686) (xy 102.657866 -286.602079) (xy 102.634288 -286.648353) (xy 102.603762 -286.690369)
			(xy 102.567039 -286.727092) (xy 102.525023 -286.757618) (xy 102.478749 -286.781196) (xy 102.429356 -286.797244)
			(xy 102.378061 -286.805369) (xy 102.326127 -286.805369) (xy 102.274832 -286.797244) (xy 102.225439 -286.781196)
			(xy 102.179165 -286.757618) (xy 102.137149 -286.727092) (xy 102.100426 -286.690369) (xy 102.0699 -286.648353)
			(xy 102.046322 -286.602079) (xy 102.030274 -286.552686) (xy 102.022149 -286.501391) (xy 101.742493 -286.501391)
			(xy 101.734368 -286.552686) (xy 101.71832 -286.602079) (xy 101.694742 -286.648353) (xy 101.664216 -286.690369)
			(xy 101.627493 -286.727092) (xy 101.585477 -286.757618) (xy 101.539203 -286.781196) (xy 101.48981 -286.797244)
			(xy 101.438515 -286.805369) (xy 101.386581 -286.805369) (xy 101.335286 -286.797244) (xy 101.285893 -286.781196)
			(xy 101.239619 -286.757618) (xy 101.197603 -286.727092) (xy 101.16088 -286.690369) (xy 101.130354 -286.648353)
			(xy 101.106776 -286.602079) (xy 101.090728 -286.552686) (xy 101.082603 -286.501391) (xy 101.082094 -286.475424)
			(xy 101.082653 -286.447438) (xy 101.092099 -286.392271) (xy 101.10089 -286.365696) (xy 101.10851 -286.343598)
			(xy 100.904802 -285.990538) (xy 100.881688 -285.98622) (xy 100.856749 -285.981073) (xy 100.808726 -285.964141)
			(xy 100.763868 -285.940045) (xy 100.723235 -285.909355) (xy 100.68779 -285.872796) (xy 100.65837 -285.831235)
			(xy 100.635671 -285.785654) (xy 100.62023 -285.737131) (xy 100.612414 -285.686814) (xy 100.61194 -285.661354)
			(xy 100.333048 -285.661354) (xy 100.332539 -285.687321) (xy 100.324414 -285.738616) (xy 100.308366 -285.788009)
			(xy 100.284788 -285.834283) (xy 100.254262 -285.876299) (xy 100.217539 -285.913022) (xy 100.175523 -285.943548)
			(xy 100.129249 -285.967126) (xy 100.079856 -285.983174) (xy 100.028561 -285.991299) (xy 99.976627 -285.991299)
			(xy 99.925332 -285.983174) (xy 99.875939 -285.967126) (xy 99.829665 -285.943548) (xy 99.787649 -285.913022)
			(xy 99.750926 -285.876299) (xy 99.7204 -285.834283) (xy 99.696822 -285.788009) (xy 99.680774 -285.738616)
			(xy 99.672649 -285.687321) (xy 99.67214 -285.661354) (xy 99.672612 -285.635905) (xy 99.680418 -285.585609)
			(xy 99.69584 -285.537104) (xy 99.718511 -285.491535) (xy 99.747899 -285.449977) (xy 99.783307 -285.413414)
			(xy 99.823899 -285.382709) (xy 99.868718 -285.358586) (xy 99.916703 -285.341616) (xy 99.941634 -285.336488)
			(xy 99.964748 -285.33217) (xy 100.16871 -284.978856) (xy 100.160836 -284.956758) (xy 100.152177 -284.930288)
			(xy 100.142859 -284.875383) (xy 100.142294 -284.847538) (xy 100.142836 -284.820529) (xy 100.151627 -284.767231)
			(xy 100.168967 -284.716071) (xy 100.194393 -284.668411) (xy 100.210366 -284.646624) (xy 100.218598 -284.635103)
			(xy 100.228965 -284.608767) (xy 100.231703 -284.580597) (xy 100.226602 -284.552757) (xy 100.214053 -284.527388)
			(xy 100.195022 -284.506438) (xy 100.17097 -284.491519) (xy 100.143746 -284.483777) (xy 100.129594 -284.483302)
			(xy 98.936302 -284.483302) (xy 98.922148 -284.483763) (xy 98.894926 -284.491527) (xy 98.870876 -284.506458)
			(xy 98.851844 -284.527413) (xy 98.839288 -284.552784) (xy 98.834173 -284.580626) (xy 98.836889 -284.608803)
			(xy 98.847229 -284.635154) (xy 98.85553 -284.646624) (xy 98.871529 -284.668395) (xy 98.896965 -284.716056)
			(xy 98.914307 -284.767221) (xy 98.923091 -284.820526) (xy 98.923602 -284.847538) (xy 98.923128 -284.873009)
			(xy 98.915303 -284.923347) (xy 98.899845 -284.971888) (xy 98.877119 -285.01748) (xy 98.847665 -285.059044)
			(xy 98.81218 -285.095595) (xy 98.771506 -285.126266) (xy 98.726605 -285.150331) (xy 98.678544 -285.167218)
			(xy 98.6536 -285.172404) (xy 98.63074 -285.176722) (xy 98.427032 -285.529528) (xy 98.434652 -285.551626)
			(xy 98.44345 -285.5782) (xy 98.45291 -285.633367) (xy 98.453448 -285.661354) (xy 98.73234 -285.661354)
			(xy 98.732849 -285.635387) (xy 98.740974 -285.584092) (xy 98.757022 -285.534699) (xy 98.7806 -285.488425)
			(xy 98.811126 -285.446409) (xy 98.847849 -285.409686) (xy 98.889865 -285.37916) (xy 98.936139 -285.355582)
			(xy 98.985532 -285.339534) (xy 99.036827 -285.331409) (xy 99.088761 -285.331409) (xy 99.140056 -285.339534)
			(xy 99.189449 -285.355582) (xy 99.235723 -285.37916) (xy 99.277739 -285.409686) (xy 99.314462 -285.446409)
			(xy 99.344988 -285.488425) (xy 99.368566 -285.534699) (xy 99.384614 -285.584092) (xy 99.392739 -285.635387)
			(xy 99.393248 -285.661354) (xy 99.392715 -285.689264) (xy 99.383386 -285.744297) (xy 99.374706 -285.770828)
			(xy 99.366832 -285.792926) (xy 99.570794 -286.14624) (xy 99.593908 -286.150558) (xy 99.618823 -286.155756)
			(xy 99.666806 -286.172716) (xy 99.711624 -286.196829) (xy 99.752217 -286.227525) (xy 99.787627 -286.264079)
			(xy 99.817017 -286.305628) (xy 99.839692 -286.35119) (xy 99.855117 -286.399688) (xy 99.862928 -286.449978)
			(xy 99.863402 -286.475424) (xy 99.862893 -286.501391) (xy 100.142549 -286.501391) (xy 100.142549 -286.449457)
			(xy 100.150674 -286.398162) (xy 100.166722 -286.348769) (xy 100.1903 -286.302495) (xy 100.220826 -286.260479)
			(xy 100.257549 -286.223756) (xy 100.299565 -286.19323) (xy 100.345839 -286.169652) (xy 100.395232 -286.153604)
			(xy 100.446527 -286.145479) (xy 100.498461 -286.145479) (xy 100.549756 -286.153604) (xy 100.599149 -286.169652)
			(xy 100.645423 -286.19323) (xy 100.687439 -286.223756) (xy 100.724162 -286.260479) (xy 100.754688 -286.302495)
			(xy 100.778266 -286.348769) (xy 100.794314 -286.398162) (xy 100.802439 -286.449457) (xy 100.802948 -286.475424)
			(xy 100.802439 -286.501391) (xy 100.794314 -286.552686) (xy 100.778266 -286.602079) (xy 100.754688 -286.648353)
			(xy 100.724162 -286.690369) (xy 100.687439 -286.727092) (xy 100.645423 -286.757618) (xy 100.599149 -286.781196)
			(xy 100.549756 -286.797244) (xy 100.498461 -286.805369) (xy 100.446527 -286.805369) (xy 100.395232 -286.797244)
			(xy 100.345839 -286.781196) (xy 100.299565 -286.757618) (xy 100.257549 -286.727092) (xy 100.220826 -286.690369)
			(xy 100.1903 -286.648353) (xy 100.166722 -286.602079) (xy 100.150674 -286.552686) (xy 100.142549 -286.501391)
			(xy 99.862893 -286.501391) (xy 99.854768 -286.552686) (xy 99.83872 -286.602079) (xy 99.815142 -286.648353)
			(xy 99.784616 -286.690369) (xy 99.747893 -286.727092) (xy 99.705877 -286.757618) (xy 99.659603 -286.781196)
			(xy 99.61021 -286.797244) (xy 99.558915 -286.805369) (xy 99.506981 -286.805369) (xy 99.455686 -286.797244)
			(xy 99.406293 -286.781196) (xy 99.360019 -286.757618) (xy 99.318003 -286.727092) (xy 99.28128 -286.690369)
			(xy 99.250754 -286.648353) (xy 99.227176 -286.602079) (xy 99.211128 -286.552686) (xy 99.203003 -286.501391)
			(xy 99.202494 -286.475424) (xy 99.203053 -286.447438) (xy 99.212499 -286.392271) (xy 99.22129 -286.365696)
			(xy 99.22891 -286.343598) (xy 99.025202 -285.990538) (xy 99.002088 -285.98622) (xy 98.977149 -285.981073)
			(xy 98.929126 -285.964141) (xy 98.884268 -285.940045) (xy 98.843635 -285.909355) (xy 98.80819 -285.872796)
			(xy 98.77877 -285.831235) (xy 98.756071 -285.785654) (xy 98.74063 -285.737131) (xy 98.732814 -285.686814)
			(xy 98.73234 -285.661354) (xy 98.453448 -285.661354) (xy 98.452939 -285.687321) (xy 98.444814 -285.738616)
			(xy 98.428766 -285.788009) (xy 98.405188 -285.834283) (xy 98.374662 -285.876299) (xy 98.337939 -285.913022)
			(xy 98.295923 -285.943548) (xy 98.249649 -285.967126) (xy 98.200256 -285.983174) (xy 98.148961 -285.991299)
			(xy 98.097027 -285.991299) (xy 98.045732 -285.983174) (xy 97.996339 -285.967126) (xy 97.950065 -285.943548)
			(xy 97.908049 -285.913022) (xy 97.871326 -285.876299) (xy 97.8408 -285.834283) (xy 97.817222 -285.788009)
			(xy 97.801174 -285.738616) (xy 97.793049 -285.687321) (xy 97.79254 -285.661354) (xy 97.793012 -285.635905)
			(xy 97.800818 -285.585609) (xy 97.81624 -285.537104) (xy 97.838911 -285.491535) (xy 97.868299 -285.449977)
			(xy 97.903707 -285.413414) (xy 97.944299 -285.382709) (xy 97.989118 -285.358586) (xy 98.037103 -285.341616)
			(xy 98.062034 -285.336488) (xy 98.085148 -285.33217) (xy 98.28911 -284.978856) (xy 98.281236 -284.956758)
			(xy 98.272577 -284.930288) (xy 98.263259 -284.875383) (xy 98.262694 -284.847538) (xy 98.263236 -284.820529)
			(xy 98.272027 -284.767231) (xy 98.289367 -284.716071) (xy 98.314793 -284.668411) (xy 98.330766 -284.646624)
			(xy 98.338998 -284.635103) (xy 98.349365 -284.608767) (xy 98.352103 -284.580597) (xy 98.347002 -284.552757)
			(xy 98.334453 -284.527388) (xy 98.315422 -284.506438) (xy 98.29137 -284.491519) (xy 98.264146 -284.483777)
			(xy 98.249994 -284.483302) (xy 97.056702 -284.483302) (xy 97.042548 -284.483763) (xy 97.015326 -284.491527)
			(xy 96.991276 -284.506458) (xy 96.972244 -284.527413) (xy 96.959688 -284.552784) (xy 96.954573 -284.580626)
			(xy 96.957289 -284.608803) (xy 96.967629 -284.635154) (xy 96.97593 -284.646624) (xy 96.991929 -284.668395)
			(xy 97.017365 -284.716056) (xy 97.034707 -284.767221) (xy 97.043491 -284.820526) (xy 97.044002 -284.847538)
			(xy 97.043528 -284.873009) (xy 97.035703 -284.923347) (xy 97.020245 -284.971888) (xy 96.997519 -285.01748)
			(xy 96.968065 -285.059044) (xy 96.93258 -285.095595) (xy 96.891906 -285.126266) (xy 96.847005 -285.150331)
			(xy 96.798944 -285.167218) (xy 96.774 -285.172404) (xy 96.75114 -285.176722) (xy 96.547432 -285.529528)
			(xy 96.555052 -285.551626) (xy 96.56385 -285.5782) (xy 96.57331 -285.633367) (xy 96.573848 -285.661354)
			(xy 96.85274 -285.661354) (xy 96.853249 -285.635387) (xy 96.861374 -285.584092) (xy 96.877422 -285.534699)
			(xy 96.901 -285.488425) (xy 96.931526 -285.446409) (xy 96.968249 -285.409686) (xy 97.010265 -285.37916)
			(xy 97.056539 -285.355582) (xy 97.105932 -285.339534) (xy 97.157227 -285.331409) (xy 97.209161 -285.331409)
			(xy 97.260456 -285.339534) (xy 97.309849 -285.355582) (xy 97.356123 -285.37916) (xy 97.398139 -285.409686)
			(xy 97.434862 -285.446409) (xy 97.465388 -285.488425) (xy 97.488966 -285.534699) (xy 97.505014 -285.584092)
			(xy 97.513139 -285.635387) (xy 97.513648 -285.661354) (xy 97.513115 -285.689264) (xy 97.503786 -285.744297)
			(xy 97.495106 -285.770828) (xy 97.487232 -285.792926) (xy 97.691194 -286.14624) (xy 97.714308 -286.150558)
			(xy 97.739223 -286.155756) (xy 97.787206 -286.172716) (xy 97.832024 -286.196829) (xy 97.872617 -286.227525)
			(xy 97.908027 -286.264079) (xy 97.937417 -286.305628) (xy 97.960092 -286.35119) (xy 97.975517 -286.399688)
			(xy 97.983328 -286.449978) (xy 97.983802 -286.475424) (xy 97.983293 -286.501391) (xy 98.262949 -286.501391)
			(xy 98.262949 -286.449457) (xy 98.271074 -286.398162) (xy 98.287122 -286.348769) (xy 98.3107 -286.302495)
			(xy 98.341226 -286.260479) (xy 98.377949 -286.223756) (xy 98.419965 -286.19323) (xy 98.466239 -286.169652)
			(xy 98.515632 -286.153604) (xy 98.566927 -286.145479) (xy 98.618861 -286.145479) (xy 98.670156 -286.153604)
			(xy 98.719549 -286.169652) (xy 98.765823 -286.19323) (xy 98.807839 -286.223756) (xy 98.844562 -286.260479)
			(xy 98.875088 -286.302495) (xy 98.898666 -286.348769) (xy 98.914714 -286.398162) (xy 98.922839 -286.449457)
			(xy 98.923348 -286.475424) (xy 98.922839 -286.501391) (xy 98.914714 -286.552686) (xy 98.898666 -286.602079)
			(xy 98.875088 -286.648353) (xy 98.844562 -286.690369) (xy 98.807839 -286.727092) (xy 98.765823 -286.757618)
			(xy 98.719549 -286.781196) (xy 98.670156 -286.797244) (xy 98.618861 -286.805369) (xy 98.566927 -286.805369)
			(xy 98.515632 -286.797244) (xy 98.466239 -286.781196) (xy 98.419965 -286.757618) (xy 98.377949 -286.727092)
			(xy 98.341226 -286.690369) (xy 98.3107 -286.648353) (xy 98.287122 -286.602079) (xy 98.271074 -286.552686)
			(xy 98.262949 -286.501391) (xy 97.983293 -286.501391) (xy 97.975168 -286.552686) (xy 97.95912 -286.602079)
			(xy 97.935542 -286.648353) (xy 97.905016 -286.690369) (xy 97.868293 -286.727092) (xy 97.826277 -286.757618)
			(xy 97.780003 -286.781196) (xy 97.73061 -286.797244) (xy 97.679315 -286.805369) (xy 97.627381 -286.805369)
			(xy 97.576086 -286.797244) (xy 97.526693 -286.781196) (xy 97.480419 -286.757618) (xy 97.438403 -286.727092)
			(xy 97.40168 -286.690369) (xy 97.371154 -286.648353) (xy 97.347576 -286.602079) (xy 97.331528 -286.552686)
			(xy 97.323403 -286.501391) (xy 97.322894 -286.475424) (xy 97.323453 -286.447438) (xy 97.332899 -286.392271)
			(xy 97.34169 -286.365696) (xy 97.34931 -286.343598) (xy 97.145602 -285.990538) (xy 97.122488 -285.98622)
			(xy 97.097549 -285.981073) (xy 97.049526 -285.964141) (xy 97.004668 -285.940045) (xy 96.964035 -285.909355)
			(xy 96.92859 -285.872796) (xy 96.89917 -285.831235) (xy 96.876471 -285.785654) (xy 96.86103 -285.737131)
			(xy 96.853214 -285.686814) (xy 96.85274 -285.661354) (xy 96.573848 -285.661354) (xy 96.573339 -285.687321)
			(xy 96.565214 -285.738616) (xy 96.549166 -285.788009) (xy 96.525588 -285.834283) (xy 96.495062 -285.876299)
			(xy 96.458339 -285.913022) (xy 96.416323 -285.943548) (xy 96.370049 -285.967126) (xy 96.320656 -285.983174)
			(xy 96.269361 -285.991299) (xy 96.217427 -285.991299) (xy 96.166132 -285.983174) (xy 96.116739 -285.967126)
			(xy 96.070465 -285.943548) (xy 96.028449 -285.913022) (xy 95.991726 -285.876299) (xy 95.9612 -285.834283)
			(xy 95.937622 -285.788009) (xy 95.921574 -285.738616) (xy 95.913449 -285.687321) (xy 95.91294 -285.661354)
			(xy 95.913412 -285.635905) (xy 95.921218 -285.585609) (xy 95.93664 -285.537104) (xy 95.959311 -285.491535)
			(xy 95.988699 -285.449977) (xy 96.024107 -285.413414) (xy 96.064699 -285.382709) (xy 96.109518 -285.358586)
			(xy 96.157503 -285.341616) (xy 96.182434 -285.336488) (xy 96.205548 -285.33217) (xy 96.40951 -284.978856)
			(xy 96.401636 -284.956758) (xy 96.392977 -284.930288) (xy 96.383659 -284.875383) (xy 96.383094 -284.847538)
			(xy 96.383636 -284.820529) (xy 96.392427 -284.767231) (xy 96.409767 -284.716071) (xy 96.435193 -284.668411)
			(xy 96.451166 -284.646624) (xy 96.459398 -284.635103) (xy 96.469765 -284.608767) (xy 96.472503 -284.580597)
			(xy 96.467402 -284.552757) (xy 96.454853 -284.527388) (xy 96.435822 -284.506438) (xy 96.41177 -284.491519)
			(xy 96.384546 -284.483777) (xy 96.370394 -284.483302) (xy 95.177102 -284.483302) (xy 95.162948 -284.483763)
			(xy 95.135726 -284.491527) (xy 95.111676 -284.506458) (xy 95.092644 -284.527413) (xy 95.080088 -284.552784)
			(xy 95.074973 -284.580626) (xy 95.077689 -284.608803) (xy 95.088029 -284.635154) (xy 95.09633 -284.646624)
			(xy 95.112329 -284.668395) (xy 95.137765 -284.716056) (xy 95.155107 -284.767221) (xy 95.163891 -284.820526)
			(xy 95.164402 -284.847538) (xy 95.163928 -284.873009) (xy 95.156103 -284.923347) (xy 95.140645 -284.971888)
			(xy 95.117919 -285.01748) (xy 95.088465 -285.059044) (xy 95.05298 -285.095595) (xy 95.012306 -285.126266)
			(xy 94.967405 -285.150331) (xy 94.919344 -285.167218) (xy 94.8944 -285.172404) (xy 94.87154 -285.176722)
			(xy 94.667832 -285.529528) (xy 94.675452 -285.551626) (xy 94.68425 -285.5782) (xy 94.69371 -285.633367)
			(xy 94.694248 -285.661354) (xy 94.97314 -285.661354) (xy 94.973649 -285.635387) (xy 94.981774 -285.584092)
			(xy 94.997822 -285.534699) (xy 95.0214 -285.488425) (xy 95.051926 -285.446409) (xy 95.088649 -285.409686)
			(xy 95.130665 -285.37916) (xy 95.176939 -285.355582) (xy 95.226332 -285.339534) (xy 95.277627 -285.331409)
			(xy 95.329561 -285.331409) (xy 95.380856 -285.339534) (xy 95.430249 -285.355582) (xy 95.476523 -285.37916)
			(xy 95.518539 -285.409686) (xy 95.555262 -285.446409) (xy 95.585788 -285.488425) (xy 95.609366 -285.534699)
			(xy 95.625414 -285.584092) (xy 95.633539 -285.635387) (xy 95.634048 -285.661354) (xy 95.633515 -285.689264)
			(xy 95.624186 -285.744297) (xy 95.615506 -285.770828) (xy 95.607632 -285.792926) (xy 95.811594 -286.14624)
			(xy 95.834708 -286.150558) (xy 95.859623 -286.155756) (xy 95.907606 -286.172716) (xy 95.952424 -286.196829)
			(xy 95.993017 -286.227525) (xy 96.028427 -286.264079) (xy 96.057817 -286.305628) (xy 96.080492 -286.35119)
			(xy 96.095917 -286.399688) (xy 96.103728 -286.449978) (xy 96.104202 -286.475424) (xy 96.103693 -286.501391)
			(xy 96.383349 -286.501391) (xy 96.383349 -286.449457) (xy 96.391474 -286.398162) (xy 96.407522 -286.348769)
			(xy 96.4311 -286.302495) (xy 96.461626 -286.260479) (xy 96.498349 -286.223756) (xy 96.540365 -286.19323)
			(xy 96.586639 -286.169652) (xy 96.636032 -286.153604) (xy 96.687327 -286.145479) (xy 96.739261 -286.145479)
			(xy 96.790556 -286.153604) (xy 96.839949 -286.169652) (xy 96.886223 -286.19323) (xy 96.928239 -286.223756)
			(xy 96.964962 -286.260479) (xy 96.995488 -286.302495) (xy 97.019066 -286.348769) (xy 97.035114 -286.398162)
			(xy 97.043239 -286.449457) (xy 97.043748 -286.475424) (xy 97.043239 -286.501391) (xy 97.035114 -286.552686)
			(xy 97.019066 -286.602079) (xy 96.995488 -286.648353) (xy 96.964962 -286.690369) (xy 96.928239 -286.727092)
			(xy 96.886223 -286.757618) (xy 96.839949 -286.781196) (xy 96.790556 -286.797244) (xy 96.739261 -286.805369)
			(xy 96.687327 -286.805369) (xy 96.636032 -286.797244) (xy 96.586639 -286.781196) (xy 96.540365 -286.757618)
			(xy 96.498349 -286.727092) (xy 96.461626 -286.690369) (xy 96.4311 -286.648353) (xy 96.407522 -286.602079)
			(xy 96.391474 -286.552686) (xy 96.383349 -286.501391) (xy 96.103693 -286.501391) (xy 96.095568 -286.552686)
			(xy 96.07952 -286.602079) (xy 96.055942 -286.648353) (xy 96.025416 -286.690369) (xy 95.988693 -286.727092)
			(xy 95.946677 -286.757618) (xy 95.900403 -286.781196) (xy 95.85101 -286.797244) (xy 95.799715 -286.805369)
			(xy 95.747781 -286.805369) (xy 95.696486 -286.797244) (xy 95.647093 -286.781196) (xy 95.600819 -286.757618)
			(xy 95.558803 -286.727092) (xy 95.52208 -286.690369) (xy 95.491554 -286.648353) (xy 95.467976 -286.602079)
			(xy 95.451928 -286.552686) (xy 95.443803 -286.501391) (xy 95.443294 -286.475424) (xy 95.443853 -286.447438)
			(xy 95.453299 -286.392271) (xy 95.46209 -286.365696) (xy 95.46971 -286.343598) (xy 95.266002 -285.990538)
			(xy 95.242888 -285.98622) (xy 95.217949 -285.981073) (xy 95.169926 -285.964141) (xy 95.125068 -285.940045)
			(xy 95.084435 -285.909355) (xy 95.04899 -285.872796) (xy 95.01957 -285.831235) (xy 94.996871 -285.785654)
			(xy 94.98143 -285.737131) (xy 94.973614 -285.686814) (xy 94.97314 -285.661354) (xy 94.694248 -285.661354)
			(xy 94.693739 -285.687321) (xy 94.685614 -285.738616) (xy 94.669566 -285.788009) (xy 94.645988 -285.834283)
			(xy 94.615462 -285.876299) (xy 94.578739 -285.913022) (xy 94.536723 -285.943548) (xy 94.490449 -285.967126)
			(xy 94.441056 -285.983174) (xy 94.389761 -285.991299) (xy 94.337827 -285.991299) (xy 94.286532 -285.983174)
			(xy 94.237139 -285.967126) (xy 94.190865 -285.943548) (xy 94.148849 -285.913022) (xy 94.112126 -285.876299)
			(xy 94.0816 -285.834283) (xy 94.058022 -285.788009) (xy 94.041974 -285.738616) (xy 94.033849 -285.687321)
			(xy 94.03334 -285.661354) (xy 94.033812 -285.635905) (xy 94.041618 -285.585609) (xy 94.05704 -285.537104)
			(xy 94.079711 -285.491535) (xy 94.109099 -285.449977) (xy 94.144507 -285.413414) (xy 94.185099 -285.382709)
			(xy 94.229918 -285.358586) (xy 94.277903 -285.341616) (xy 94.302834 -285.336488) (xy 94.325948 -285.33217)
			(xy 94.52991 -284.978856) (xy 94.522036 -284.956758) (xy 94.513377 -284.930288) (xy 94.504059 -284.875383)
			(xy 94.503494 -284.847538) (xy 94.504036 -284.820529) (xy 94.512827 -284.767231) (xy 94.530167 -284.716071)
			(xy 94.555593 -284.668411) (xy 94.571566 -284.646624) (xy 94.579798 -284.635103) (xy 94.590165 -284.608767)
			(xy 94.592903 -284.580597) (xy 94.587802 -284.552757) (xy 94.575253 -284.527388) (xy 94.556222 -284.506438)
			(xy 94.53217 -284.491519) (xy 94.504946 -284.483777) (xy 94.490794 -284.483302) (xy 93.297502 -284.483302)
			(xy 93.283348 -284.483763) (xy 93.256126 -284.491527) (xy 93.232076 -284.506458) (xy 93.213044 -284.527413)
			(xy 93.200488 -284.552784) (xy 93.195373 -284.580626) (xy 93.198089 -284.608803) (xy 93.208429 -284.635154)
			(xy 93.21673 -284.646624) (xy 93.232729 -284.668395) (xy 93.258165 -284.716056) (xy 93.275507 -284.767221)
			(xy 93.284291 -284.820526) (xy 93.284802 -284.847538) (xy 93.284328 -284.873009) (xy 93.276503 -284.923347)
			(xy 93.261045 -284.971888) (xy 93.238319 -285.01748) (xy 93.208865 -285.059044) (xy 93.17338 -285.095595)
			(xy 93.132706 -285.126266) (xy 93.087805 -285.150331) (xy 93.039744 -285.167218) (xy 93.0148 -285.172404)
			(xy 92.99194 -285.176722) (xy 92.788232 -285.529528) (xy 92.795852 -285.551626) (xy 92.80465 -285.5782)
			(xy 92.81411 -285.633367) (xy 92.814648 -285.661354) (xy 93.09354 -285.661354) (xy 93.094049 -285.635387)
			(xy 93.102174 -285.584092) (xy 93.118222 -285.534699) (xy 93.1418 -285.488425) (xy 93.172326 -285.446409)
			(xy 93.209049 -285.409686) (xy 93.251065 -285.37916) (xy 93.297339 -285.355582) (xy 93.346732 -285.339534)
			(xy 93.398027 -285.331409) (xy 93.449961 -285.331409) (xy 93.501256 -285.339534) (xy 93.550649 -285.355582)
			(xy 93.596923 -285.37916) (xy 93.638939 -285.409686) (xy 93.675662 -285.446409) (xy 93.706188 -285.488425)
			(xy 93.729766 -285.534699) (xy 93.745814 -285.584092) (xy 93.753939 -285.635387) (xy 93.754448 -285.661354)
			(xy 93.753915 -285.689264) (xy 93.744586 -285.744297) (xy 93.735906 -285.770828) (xy 93.728032 -285.792926)
			(xy 93.931994 -286.14624) (xy 93.955108 -286.150558) (xy 93.980023 -286.155756) (xy 94.028006 -286.172716)
			(xy 94.072824 -286.196829) (xy 94.113417 -286.227525) (xy 94.148827 -286.264079) (xy 94.178217 -286.305628)
			(xy 94.200892 -286.35119) (xy 94.216317 -286.399688) (xy 94.224128 -286.449978) (xy 94.224602 -286.475424)
			(xy 94.224093 -286.501391) (xy 94.503749 -286.501391) (xy 94.503749 -286.449457) (xy 94.511874 -286.398162)
			(xy 94.527922 -286.348769) (xy 94.5515 -286.302495) (xy 94.582026 -286.260479) (xy 94.618749 -286.223756)
			(xy 94.660765 -286.19323) (xy 94.707039 -286.169652) (xy 94.756432 -286.153604) (xy 94.807727 -286.145479)
			(xy 94.859661 -286.145479) (xy 94.910956 -286.153604) (xy 94.960349 -286.169652) (xy 95.006623 -286.19323)
			(xy 95.048639 -286.223756) (xy 95.085362 -286.260479) (xy 95.115888 -286.302495) (xy 95.139466 -286.348769)
			(xy 95.155514 -286.398162) (xy 95.163639 -286.449457) (xy 95.164148 -286.475424) (xy 95.163639 -286.501391)
			(xy 95.155514 -286.552686) (xy 95.139466 -286.602079) (xy 95.115888 -286.648353) (xy 95.085362 -286.690369)
			(xy 95.048639 -286.727092) (xy 95.006623 -286.757618) (xy 94.960349 -286.781196) (xy 94.910956 -286.797244)
			(xy 94.859661 -286.805369) (xy 94.807727 -286.805369) (xy 94.756432 -286.797244) (xy 94.707039 -286.781196)
			(xy 94.660765 -286.757618) (xy 94.618749 -286.727092) (xy 94.582026 -286.690369) (xy 94.5515 -286.648353)
			(xy 94.527922 -286.602079) (xy 94.511874 -286.552686) (xy 94.503749 -286.501391) (xy 94.224093 -286.501391)
			(xy 94.215968 -286.552686) (xy 94.19992 -286.602079) (xy 94.176342 -286.648353) (xy 94.145816 -286.690369)
			(xy 94.109093 -286.727092) (xy 94.067077 -286.757618) (xy 94.020803 -286.781196) (xy 93.97141 -286.797244)
			(xy 93.920115 -286.805369) (xy 93.868181 -286.805369) (xy 93.816886 -286.797244) (xy 93.767493 -286.781196)
			(xy 93.721219 -286.757618) (xy 93.679203 -286.727092) (xy 93.64248 -286.690369) (xy 93.611954 -286.648353)
			(xy 93.588376 -286.602079) (xy 93.572328 -286.552686) (xy 93.564203 -286.501391) (xy 93.563694 -286.475424)
			(xy 93.564253 -286.447438) (xy 93.573699 -286.392271) (xy 93.58249 -286.365696) (xy 93.59011 -286.343598)
			(xy 93.386402 -285.990538) (xy 93.363288 -285.98622) (xy 93.338349 -285.981073) (xy 93.290326 -285.964141)
			(xy 93.245468 -285.940045) (xy 93.204835 -285.909355) (xy 93.16939 -285.872796) (xy 93.13997 -285.831235)
			(xy 93.117271 -285.785654) (xy 93.10183 -285.737131) (xy 93.094014 -285.686814) (xy 93.09354 -285.661354)
			(xy 92.814648 -285.661354) (xy 92.814139 -285.687321) (xy 92.806014 -285.738616) (xy 92.789966 -285.788009)
			(xy 92.766388 -285.834283) (xy 92.735862 -285.876299) (xy 92.699139 -285.913022) (xy 92.657123 -285.943548)
			(xy 92.610849 -285.967126) (xy 92.561456 -285.983174) (xy 92.510161 -285.991299) (xy 92.458227 -285.991299)
			(xy 92.406932 -285.983174) (xy 92.357539 -285.967126) (xy 92.311265 -285.943548) (xy 92.269249 -285.913022)
			(xy 92.232526 -285.876299) (xy 92.202 -285.834283) (xy 92.178422 -285.788009) (xy 92.162374 -285.738616)
			(xy 92.154249 -285.687321) (xy 92.15374 -285.661354) (xy 92.154212 -285.635905) (xy 92.162018 -285.585609)
			(xy 92.17744 -285.537104) (xy 92.200111 -285.491535) (xy 92.229499 -285.449977) (xy 92.264907 -285.413414)
			(xy 92.305499 -285.382709) (xy 92.350318 -285.358586) (xy 92.398303 -285.341616) (xy 92.423234 -285.336488)
			(xy 92.446348 -285.33217) (xy 92.65031 -284.978856) (xy 92.642436 -284.956758) (xy 92.633777 -284.930288)
			(xy 92.624459 -284.875383) (xy 92.623894 -284.847538) (xy 92.624436 -284.820529) (xy 92.633227 -284.767231)
			(xy 92.650567 -284.716071) (xy 92.675993 -284.668411) (xy 92.691966 -284.646624) (xy 92.700198 -284.635103)
			(xy 92.710565 -284.608767) (xy 92.713303 -284.580597) (xy 92.708202 -284.552757) (xy 92.695653 -284.527388)
			(xy 92.676622 -284.506438) (xy 92.65257 -284.491519) (xy 92.625346 -284.483777) (xy 92.611194 -284.483302)
			(xy 92.097352 -284.483302) (xy 90.935556 -285.645098) (xy 90.935355 -285.661354) (xy 91.214194 -285.661354)
			(xy 91.214703 -285.635387) (xy 91.222828 -285.584092) (xy 91.238876 -285.534699) (xy 91.262454 -285.488425)
			(xy 91.29298 -285.446409) (xy 91.329703 -285.409686) (xy 91.371719 -285.37916) (xy 91.417993 -285.355582)
			(xy 91.467386 -285.339534) (xy 91.518681 -285.331409) (xy 91.570615 -285.331409) (xy 91.62191 -285.339534)
			(xy 91.671303 -285.355582) (xy 91.717577 -285.37916) (xy 91.759593 -285.409686) (xy 91.796316 -285.446409)
			(xy 91.826842 -285.488425) (xy 91.85042 -285.534699) (xy 91.866468 -285.584092) (xy 91.874593 -285.635387)
			(xy 91.875102 -285.661354) (xy 91.874538 -285.689339) (xy 91.865095 -285.744507) (xy 91.856306 -285.771082)
			(xy 91.848686 -285.79318) (xy 92.052394 -286.14624) (xy 92.075508 -286.150558) (xy 92.100423 -286.155756)
			(xy 92.148406 -286.172716) (xy 92.193224 -286.196829) (xy 92.233817 -286.227525) (xy 92.269227 -286.264079)
			(xy 92.298617 -286.305628) (xy 92.321292 -286.35119) (xy 92.336717 -286.399688) (xy 92.344528 -286.449978)
			(xy 92.345002 -286.475424) (xy 92.344493 -286.501391) (xy 92.624403 -286.501391) (xy 92.624403 -286.449457)
			(xy 92.632528 -286.398162) (xy 92.648576 -286.348769) (xy 92.672154 -286.302495) (xy 92.70268 -286.260479)
			(xy 92.739403 -286.223756) (xy 92.781419 -286.19323) (xy 92.827693 -286.169652) (xy 92.877086 -286.153604)
			(xy 92.928381 -286.145479) (xy 92.980315 -286.145479) (xy 93.03161 -286.153604) (xy 93.081003 -286.169652)
			(xy 93.127277 -286.19323) (xy 93.169293 -286.223756) (xy 93.206016 -286.260479) (xy 93.236542 -286.302495)
			(xy 93.26012 -286.348769) (xy 93.276168 -286.398162) (xy 93.284293 -286.449457) (xy 93.284802 -286.475424)
			(xy 93.284293 -286.501391) (xy 93.276168 -286.552686) (xy 93.26012 -286.602079) (xy 93.236542 -286.648353)
			(xy 93.206016 -286.690369) (xy 93.169293 -286.727092) (xy 93.127277 -286.757618) (xy 93.081003 -286.781196)
			(xy 93.03161 -286.797244) (xy 92.980315 -286.805369) (xy 92.928381 -286.805369) (xy 92.877086 -286.797244)
			(xy 92.827693 -286.781196) (xy 92.781419 -286.757618) (xy 92.739403 -286.727092) (xy 92.70268 -286.690369)
			(xy 92.672154 -286.648353) (xy 92.648576 -286.602079) (xy 92.632528 -286.552686) (xy 92.624403 -286.501391)
			(xy 92.344493 -286.501391) (xy 92.336368 -286.552686) (xy 92.32032 -286.602079) (xy 92.296742 -286.648353)
			(xy 92.266216 -286.690369) (xy 92.229493 -286.727092) (xy 92.187477 -286.757618) (xy 92.141203 -286.781196)
			(xy 92.09181 -286.797244) (xy 92.040515 -286.805369) (xy 91.988581 -286.805369) (xy 91.937286 -286.797244)
			(xy 91.887893 -286.781196) (xy 91.841619 -286.757618) (xy 91.799603 -286.727092) (xy 91.76288 -286.690369)
			(xy 91.732354 -286.648353) (xy 91.708776 -286.602079) (xy 91.692728 -286.552686) (xy 91.684603 -286.501391)
			(xy 91.684094 -286.475424) (xy 91.684653 -286.447438) (xy 91.694099 -286.392271) (xy 91.70289 -286.365696)
			(xy 91.71051 -286.343598) (xy 91.506802 -285.990538) (xy 91.483688 -285.98622) (xy 91.458768 -285.981045)
			(xy 91.410783 -285.964083) (xy 91.365964 -285.939968) (xy 91.32537 -285.909269) (xy 91.28996 -285.872712)
			(xy 91.260571 -285.83116) (xy 91.237897 -285.785595) (xy 91.222474 -285.737094) (xy 91.214666 -285.686801)
			(xy 91.214194 -285.661354) (xy 90.935355 -285.661354) (xy 90.935302 -285.665672) (xy 90.934496 -285.691206)
			(xy 90.925985 -285.741575) (xy 90.909826 -285.790036) (xy 90.886403 -285.835433) (xy 90.856275 -285.876686)
			(xy 90.820159 -285.912813) (xy 90.778914 -285.942953) (xy 90.733524 -285.966389) (xy 90.685068 -285.982562)
			(xy 90.634701 -285.991087) (xy 90.609166 -285.991808) (xy 90.588592 -285.992062) (xy 90.35542 -286.225234)
			(xy 90.3859 -286.260794) (xy 90.400789 -286.278819) (xy 90.425868 -286.318274) (xy 90.44513 -286.360873)
			(xy 90.458188 -286.405764) (xy 90.464781 -286.452048) (xy 90.465148 -286.475424) (xy 90.464637 -286.50139)
			(xy 90.464637 -286.501391) (xy 90.744549 -286.501391) (xy 90.744549 -286.449457) (xy 90.752674 -286.398162)
			(xy 90.768722 -286.348769) (xy 90.7923 -286.302495) (xy 90.822826 -286.260479) (xy 90.859549 -286.223756)
			(xy 90.901565 -286.19323) (xy 90.947839 -286.169652) (xy 90.997232 -286.153604) (xy 91.048527 -286.145479)
			(xy 91.100461 -286.145479) (xy 91.151756 -286.153604) (xy 91.201149 -286.169652) (xy 91.247423 -286.19323)
			(xy 91.289439 -286.223756) (xy 91.326162 -286.260479) (xy 91.356688 -286.302495) (xy 91.380266 -286.348769)
			(xy 91.396314 -286.398162) (xy 91.404439 -286.449457) (xy 91.404948 -286.475424) (xy 91.404439 -286.501391)
			(xy 91.396314 -286.552686) (xy 91.380266 -286.602079) (xy 91.356688 -286.648353) (xy 91.326162 -286.690369)
			(xy 91.289439 -286.727092) (xy 91.247423 -286.757618) (xy 91.201149 -286.781196) (xy 91.151756 -286.797244)
			(xy 91.100461 -286.805369) (xy 91.048527 -286.805369) (xy 90.997232 -286.797244) (xy 90.947839 -286.781196)
			(xy 90.901565 -286.757618) (xy 90.859549 -286.727092) (xy 90.822826 -286.690369) (xy 90.7923 -286.648353)
			(xy 90.768722 -286.602079) (xy 90.752674 -286.552686) (xy 90.744549 -286.501391) (xy 90.464637 -286.501391)
			(xy 90.45651 -286.552682) (xy 90.440459 -286.602071) (xy 90.41688 -286.648341) (xy 90.386353 -286.690353)
			(xy 90.34963 -286.727072) (xy 90.307615 -286.757595) (xy 90.261343 -286.78117) (xy 90.211952 -286.797217)
			(xy 90.16066 -286.805339) (xy 90.134694 -286.805878) (xy 90.11132 -286.805473) (xy 90.06504 -286.79888)
			(xy 90.020152 -286.785828) (xy 89.977553 -286.766576) (xy 89.938094 -286.741511) (xy 89.920064 -286.72663)
			(xy 89.884504 -286.69615) (xy 89.736676 -286.843978) (xy 89.736676 -286.964628) (xy 89.77122 -286.976312)
			(xy 89.795387 -286.985042) (xy 89.840888 -287.00891) (xy 89.882145 -287.039535) (xy 89.918163 -287.076178)
			(xy 89.948074 -287.117955) (xy 89.971156 -287.16386) (xy 89.986854 -287.212784) (xy 89.994787 -287.263549)
			(xy 89.995248 -287.28924) (xy 89.994702 -287.315696) (xy 89.986229 -287.367927) (xy 89.969553 -287.418144)
			(xy 89.9451 -287.465067) (xy 89.929716 -287.486598) (xy 89.96231 -287.526481) (xy 90.019708 -287.612012)
			(xy 90.04427 -287.657286) (xy 90.050956 -287.669092) (xy 90.069454 -287.688928) (xy 90.092528 -287.703185)
			(xy 90.118545 -287.710852) (xy 90.145662 -287.711388) (xy 90.171961 -287.704755) (xy 90.19558 -287.691421)
			(xy 90.214848 -287.672332) (xy 90.22207 -287.660842) (xy 90.24366 -287.623504) (xy 90.265011 -287.58743)
			(xy 90.313082 -287.51875) (xy 90.339672 -287.486344) (xy 90.324325 -287.464838) (xy 90.299948 -287.417968)
			(xy 90.283347 -287.367813) (xy 90.274943 -287.315655) (xy 90.274394 -287.28924) (xy 90.274874 -287.26327)
			(xy 90.282994 -287.211969) (xy 90.299041 -287.16257) (xy 90.322619 -287.11629) (xy 90.353148 -287.07427)
			(xy 90.389876 -287.037543) (xy 90.431897 -287.007015) (xy 90.478177 -286.983438) (xy 90.527577 -286.967392)
			(xy 90.578878 -286.959273) (xy 90.604848 -286.958786) (xy 90.632339 -286.959335) (xy 90.686562 -286.968439)
			(xy 90.738532 -286.986387) (xy 90.786816 -287.012685) (xy 90.830085 -287.046609) (xy 90.867146 -287.087223)
			(xy 90.896977 -287.133408) (xy 90.908378 -287.15843) (xy 90.949571 -287.151644) (xy 91.032748 -287.144395)
			(xy 91.074494 -287.143952) (xy 91.116367 -287.144388) (xy 91.199797 -287.151639) (xy 91.241118 -287.15843)
			(xy 91.252497 -287.133394) (xy 91.282313 -287.087189) (xy 91.319369 -287.046559) (xy 91.362641 -287.012627)
			(xy 91.410935 -286.986329) (xy 91.462918 -286.968391) (xy 91.517153 -286.959309) (xy 91.544648 -286.958786)
			(xy 91.570612 -286.959299) (xy 91.621898 -286.967429) (xy 91.671282 -286.983483) (xy 91.717546 -287.007064)
			(xy 91.759552 -287.037592) (xy 91.796266 -287.074315) (xy 91.826782 -287.116329) (xy 91.850351 -287.162599)
			(xy 91.866391 -287.211987) (xy 91.874508 -287.263276) (xy 91.875102 -287.28924) (xy 91.874576 -287.315728)
			(xy 91.866124 -287.368026) (xy 91.849443 -287.418307) (xy 91.824959 -287.465286) (xy 91.80957 -287.486852)
			(xy 91.8421 -287.526741) (xy 91.899374 -287.612271)
		)
		(stroke
			(width 0)
			(type solid)
		)
		(fill yes)
		(layer "In4.Cu")
		(net "PVCCFA_EHV_FIVRA_CPU1")
	)
	(gr_poly
		(pts
			(xy 224.875344 -76.15682) (xy 224.875344 -75.37704) (xy 224.875803 -75.346049) (xy 224.883334 -75.284528)
			(xy 224.898289 -75.224378) (xy 224.920447 -75.166493) (xy 224.949477 -75.111731) (xy 224.984951 -75.060905)
			(xy 225.026341 -75.014769) (xy 225.073033 -74.974007) (xy 225.124334 -74.939225) (xy 225.151696 -74.924666)
			(xy 225.151696 -69.517514) (xy 225.015044 -69.380862) (xy 225.004803 -69.371241) (xy 224.98029 -69.357529)
			(xy 224.952967 -69.351019) (xy 224.924904 -69.352204) (xy 224.898227 -69.360994) (xy 224.874958 -69.376724)
			(xy 224.856857 -69.398202) (xy 224.850706 -69.410834) (xy 224.838997 -69.435549) (xy 224.809557 -69.481637)
			(xy 224.773842 -69.523052) (xy 224.732584 -69.558949) (xy 224.686626 -69.588592) (xy 224.63691 -69.611375)
			(xy 224.584451 -69.626831) (xy 224.530324 -69.634645) (xy 224.50298 -69.635116) (xy 224.475729 -69.634629)
			(xy 224.421783 -69.62687) (xy 224.369491 -69.611513) (xy 224.319915 -69.588871) (xy 224.274067 -69.559404)
			(xy 224.232878 -69.523713) (xy 224.197188 -69.482523) (xy 224.167723 -69.436674) (xy 224.145082 -69.387098)
			(xy 224.129727 -69.334805) (xy 224.12197 -69.280859) (xy 224.121472 -69.253608) (xy 224.121854 -69.229031)
			(xy 224.12817 -69.180284) (xy 224.140696 -69.132752) (xy 224.159227 -69.087224) (xy 224.171002 -69.065648)
			(xy 224.177987 -69.052177) (xy 224.184522 -69.02256) (xy 224.182074 -68.99233) (xy 224.170859 -68.964151)
			(xy 224.151865 -68.940507) (xy 224.126766 -68.923481) (xy 224.097774 -68.914574) (xy 224.08261 -68.91401)
			(xy 223.601788 -68.91401) (xy 223.590612 -68.919598) (xy 223.56334 -68.933088) (xy 223.505579 -68.9522)
			(xy 223.445518 -68.961911) (xy 223.415098 -68.962524) (xy 223.384677 -68.961914) (xy 223.324613 -68.952216)
			(xy 223.266852 -68.933098) (xy 223.239584 -68.919598) (xy 223.228408 -68.91401) (xy 220.955108 -68.91401)
			(xy 220.535754 -68.494656) (xy 220.506798 -68.503546) (xy 220.479699 -68.511259) (xy 220.423971 -68.519541)
			(xy 220.3958 -68.520056) (xy 220.368548 -68.51957) (xy 220.314597 -68.511814) (xy 220.2623 -68.496459)
			(xy 220.212719 -68.473819) (xy 220.166866 -68.444353) (xy 220.125671 -68.408663) (xy 220.089975 -68.367473)
			(xy 220.060504 -68.321623) (xy 220.037857 -68.272045) (xy 220.022496 -68.21975) (xy 220.014733 -68.1658)
			(xy 220.014292 -68.138548) (xy 220.014801 -68.110378) (xy 220.023095 -68.05465) (xy 220.030802 -68.02755)
			(xy 220.039692 -67.998594) (xy 218.59621 -66.555112) (xy 204.992224 -66.555112) (xy 193.280284 -54.843172)
			(xy 180.443886 -54.843172) (xy 180.169566 -55.117492) (xy 180.169566 -55.916068) (xy 182.426862 -55.916068)
			(xy 182.430933 -55.860446) (xy 182.443059 -55.806009) (xy 182.462982 -55.753918) (xy 182.490278 -55.705283)
			(xy 182.524364 -55.66114) (xy 182.564513 -55.622431) (xy 182.609871 -55.58998) (xy 182.659471 -55.564479)
			(xy 182.712255 -55.546472) (xy 182.767098 -55.536342) (xy 182.822832 -55.534305) (xy 182.878269 -55.540405)
			(xy 182.932226 -55.554511) (xy 182.983555 -55.576323) (xy 183.031161 -55.605377) (xy 183.074029 -55.641052)
			(xy 183.111246 -55.682589) (xy 183.142019 -55.729102) (xy 183.165691 -55.779599) (xy 183.181759 -55.833006)
			(xy 183.189879 -55.888182) (xy 183.190388 -55.916068) (xy 183.189879 -55.943954) (xy 183.181759 -55.99913)
			(xy 183.165691 -56.052537) (xy 183.142019 -56.103034) (xy 183.111246 -56.149547) (xy 183.074029 -56.191084)
			(xy 183.031161 -56.226759) (xy 182.983555 -56.255813) (xy 182.932226 -56.277625) (xy 182.878269 -56.291731)
			(xy 182.822832 -56.297831) (xy 182.767098 -56.295794) (xy 182.712255 -56.285664) (xy 182.659471 -56.267657)
			(xy 182.609871 -56.242156) (xy 182.564513 -56.209705) (xy 182.524364 -56.170996) (xy 182.490278 -56.126853)
			(xy 182.462982 -56.078218) (xy 182.443059 -56.026127) (xy 182.430933 -55.97169) (xy 182.426862 -55.916068)
			(xy 180.169566 -55.916068) (xy 180.169566 -57.311798) (xy 180.279294 -57.421526) (xy 182.61076 -57.421526)
			(xy 183.955182 -58.765948) (xy 185.728862 -58.765948) (xy 185.732933 -58.710326) (xy 185.745059 -58.655889)
			(xy 185.764982 -58.603798) (xy 185.792278 -58.555163) (xy 185.826364 -58.51102) (xy 185.866513 -58.472311)
			(xy 185.911871 -58.43986) (xy 185.961471 -58.414359) (xy 186.014255 -58.396352) (xy 186.069098 -58.386222)
			(xy 186.124832 -58.384185) (xy 186.180269 -58.390285) (xy 186.234226 -58.404391) (xy 186.285555 -58.426203)
			(xy 186.333161 -58.455257) (xy 186.376029 -58.490932) (xy 186.413246 -58.532469) (xy 186.444019 -58.578982)
			(xy 186.467691 -58.629479) (xy 186.483759 -58.682886) (xy 186.491879 -58.738062) (xy 186.492388 -58.765948)
			(xy 186.491879 -58.793834) (xy 186.483759 -58.84901) (xy 186.467691 -58.902417) (xy 186.444019 -58.952914)
			(xy 186.413246 -58.999427) (xy 186.376029 -59.040964) (xy 186.333161 -59.076639) (xy 186.285555 -59.105693)
			(xy 186.234226 -59.127505) (xy 186.180269 -59.141611) (xy 186.124832 -59.147711) (xy 186.069098 -59.145674)
			(xy 186.014255 -59.135544) (xy 185.961471 -59.117537) (xy 185.911871 -59.092036) (xy 185.866513 -59.059585)
			(xy 185.826364 -59.020876) (xy 185.792278 -58.976733) (xy 185.764982 -58.928098) (xy 185.745059 -58.876007)
			(xy 185.732933 -58.82157) (xy 185.728862 -58.765948) (xy 183.955182 -58.765948) (xy 185.733182 -60.543948)
			(xy 186.109862 -60.543948) (xy 186.113933 -60.488326) (xy 186.126059 -60.433889) (xy 186.145982 -60.381798)
			(xy 186.173278 -60.333163) (xy 186.207364 -60.28902) (xy 186.247513 -60.250311) (xy 186.292871 -60.21786)
			(xy 186.342471 -60.192359) (xy 186.395255 -60.174352) (xy 186.450098 -60.164222) (xy 186.505832 -60.162185)
			(xy 186.561269 -60.168285) (xy 186.615226 -60.182391) (xy 186.666555 -60.204203) (xy 186.714161 -60.233257)
			(xy 186.757029 -60.268932) (xy 186.794246 -60.310469) (xy 186.825019 -60.356982) (xy 186.848691 -60.407479)
			(xy 186.864759 -60.460886) (xy 186.872879 -60.516062) (xy 186.873388 -60.543948) (xy 186.872879 -60.571834)
			(xy 186.864759 -60.62701) (xy 186.848691 -60.680417) (xy 186.825019 -60.730914) (xy 186.794246 -60.777427)
			(xy 186.757029 -60.818964) (xy 186.714161 -60.854639) (xy 186.666555 -60.883693) (xy 186.615226 -60.905505)
			(xy 186.561269 -60.919611) (xy 186.505832 -60.925711) (xy 186.450098 -60.923674) (xy 186.395255 -60.913544)
			(xy 186.342471 -60.895537) (xy 186.292871 -60.870036) (xy 186.247513 -60.837585) (xy 186.207364 -60.798876)
			(xy 186.173278 -60.754733) (xy 186.145982 -60.706098) (xy 186.126059 -60.654007) (xy 186.113933 -60.59957)
			(xy 186.109862 -60.543948) (xy 185.733182 -60.543948) (xy 187.246006 -62.056772) (xy 196.54393 -62.056772)
			(xy 200.603612 -66.116454) (xy 200.603612 -67.20332) (xy 210.356702 -67.20332) (xy 210.360773 -67.147698)
			(xy 210.372899 -67.093261) (xy 210.392822 -67.04117) (xy 210.420118 -66.992535) (xy 210.454204 -66.948392)
			(xy 210.494353 -66.909683) (xy 210.539711 -66.877232) (xy 210.589311 -66.851731) (xy 210.642095 -66.833724)
			(xy 210.696938 -66.823594) (xy 210.752672 -66.821557) (xy 210.808109 -66.827657) (xy 210.862066 -66.841763)
			(xy 210.913395 -66.863575) (xy 210.961001 -66.892629) (xy 211.003869 -66.928304) (xy 211.041086 -66.969841)
			(xy 211.071859 -67.016354) (xy 211.095531 -67.066851) (xy 211.111599 -67.120258) (xy 211.119719 -67.175434)
			(xy 211.120228 -67.20332) (xy 211.119719 -67.231206) (xy 211.111599 -67.286382) (xy 211.100137 -67.324478)
			(xy 216.490294 -67.324478) (xy 216.494365 -67.268856) (xy 216.506491 -67.214419) (xy 216.526414 -67.162328)
			(xy 216.55371 -67.113693) (xy 216.587796 -67.06955) (xy 216.627945 -67.030841) (xy 216.673303 -66.99839)
			(xy 216.722903 -66.972889) (xy 216.775687 -66.954882) (xy 216.83053 -66.944752) (xy 216.886264 -66.942715)
			(xy 216.941701 -66.948815) (xy 216.995658 -66.962921) (xy 217.046987 -66.984733) (xy 217.094593 -67.013787)
			(xy 217.137461 -67.049462) (xy 217.174678 -67.090999) (xy 217.205451 -67.137512) (xy 217.229123 -67.188009)
			(xy 217.245191 -67.241416) (xy 217.253311 -67.296592) (xy 217.25382 -67.324478) (xy 217.253311 -67.352364)
			(xy 217.245191 -67.40754) (xy 217.229123 -67.460947) (xy 217.205451 -67.511444) (xy 217.174678 -67.557957)
			(xy 217.137461 -67.599494) (xy 217.094593 -67.635169) (xy 217.046987 -67.664223) (xy 216.995658 -67.686035)
			(xy 216.941701 -67.700141) (xy 216.886264 -67.706241) (xy 216.83053 -67.704204) (xy 216.775687 -67.694074)
			(xy 216.722903 -67.676067) (xy 216.673303 -67.650566) (xy 216.627945 -67.618115) (xy 216.587796 -67.579406)
			(xy 216.55371 -67.535263) (xy 216.526414 -67.486628) (xy 216.506491 -67.434537) (xy 216.494365 -67.3801)
			(xy 216.490294 -67.324478) (xy 211.100137 -67.324478) (xy 211.095531 -67.339789) (xy 211.071859 -67.390286)
			(xy 211.041086 -67.436799) (xy 211.003869 -67.478336) (xy 210.961001 -67.514011) (xy 210.913395 -67.543065)
			(xy 210.862066 -67.564877) (xy 210.808109 -67.578983) (xy 210.752672 -67.585083) (xy 210.696938 -67.583046)
			(xy 210.642095 -67.572916) (xy 210.589311 -67.554909) (xy 210.539711 -67.529408) (xy 210.494353 -67.496957)
			(xy 210.454204 -67.458248) (xy 210.420118 -67.414105) (xy 210.392822 -67.36547) (xy 210.372899 -67.313379)
			(xy 210.360773 -67.258942) (xy 210.356702 -67.20332) (xy 200.603612 -67.20332) (xy 200.603612 -68.503292)
			(xy 206.348582 -68.503292) (xy 206.352653 -68.44767) (xy 206.364779 -68.393233) (xy 206.384702 -68.341142)
			(xy 206.411998 -68.292507) (xy 206.446084 -68.248364) (xy 206.486233 -68.209655) (xy 206.531591 -68.177204)
			(xy 206.581191 -68.151703) (xy 206.633975 -68.133696) (xy 206.688818 -68.123566) (xy 206.744552 -68.121529)
			(xy 206.799989 -68.127629) (xy 206.853946 -68.141735) (xy 206.905275 -68.163547) (xy 206.952881 -68.192601)
			(xy 206.995749 -68.228276) (xy 207.032966 -68.269813) (xy 207.063739 -68.316326) (xy 207.087411 -68.366823)
			(xy 207.103479 -68.42023) (xy 207.111599 -68.475406) (xy 207.112108 -68.503292) (xy 207.111599 -68.531178)
			(xy 207.103479 -68.586354) (xy 207.087411 -68.639761) (xy 207.063739 -68.690258) (xy 207.032966 -68.736771)
			(xy 206.995749 -68.778308) (xy 206.952881 -68.813983) (xy 206.905275 -68.843037) (xy 206.853946 -68.864849)
			(xy 206.799989 -68.878955) (xy 206.744552 -68.885055) (xy 206.688818 -68.883018) (xy 206.633975 -68.872888)
			(xy 206.581191 -68.854881) (xy 206.531591 -68.82938) (xy 206.486233 -68.796929) (xy 206.446084 -68.75822)
			(xy 206.411998 -68.714077) (xy 206.384702 -68.665442) (xy 206.364779 -68.613351) (xy 206.352653 -68.558914)
			(xy 206.348582 -68.503292) (xy 200.603612 -68.503292) (xy 200.603612 -68.953126) (xy 202.168504 -68.953126)
			(xy 202.172575 -68.897504) (xy 202.184701 -68.843067) (xy 202.204624 -68.790976) (xy 202.23192 -68.742341)
			(xy 202.266006 -68.698198) (xy 202.306155 -68.659489) (xy 202.351513 -68.627038) (xy 202.401113 -68.601537)
			(xy 202.453897 -68.58353) (xy 202.50874 -68.5734) (xy 202.564474 -68.571363) (xy 202.619911 -68.577463)
			(xy 202.673868 -68.591569) (xy 202.725197 -68.613381) (xy 202.772803 -68.642435) (xy 202.815671 -68.67811)
			(xy 202.852888 -68.719647) (xy 202.883661 -68.76616) (xy 202.907333 -68.816657) (xy 202.923401 -68.870064)
			(xy 202.931521 -68.92524) (xy 202.93203 -68.953126) (xy 202.931599 -68.976748) (xy 210.387182 -68.976748)
			(xy 210.391253 -68.921126) (xy 210.403379 -68.866689) (xy 210.423302 -68.814598) (xy 210.450598 -68.765963)
			(xy 210.484684 -68.72182) (xy 210.524833 -68.683111) (xy 210.570191 -68.65066) (xy 210.619791 -68.625159)
			(xy 210.672575 -68.607152) (xy 210.727418 -68.597022) (xy 210.783152 -68.594985) (xy 210.838589 -68.601085)
			(xy 210.892546 -68.615191) (xy 210.943875 -68.637003) (xy 210.991481 -68.666057) (xy 211.034349 -68.701732)
			(xy 211.071566 -68.743269) (xy 211.102339 -68.789782) (xy 211.126011 -68.840279) (xy 211.142079 -68.893686)
			(xy 211.150199 -68.948862) (xy 211.150708 -68.976748) (xy 211.150199 -69.004634) (xy 211.142079 -69.05981)
			(xy 211.126011 -69.113217) (xy 211.102339 -69.163714) (xy 211.071566 -69.210227) (xy 211.053801 -69.230054)
			(xy 212.016263 -69.230054) (xy 212.016263 -69.175546) (xy 212.024021 -69.121593) (xy 212.039379 -69.069293)
			(xy 212.062024 -69.019711) (xy 212.091495 -68.973857) (xy 212.127192 -68.932664) (xy 212.168389 -68.896971)
			(xy 212.214246 -68.867505) (xy 212.26383 -68.844865) (xy 212.316132 -68.829513) (xy 212.370086 -68.821761)
			(xy 212.39734 -68.8213) (xy 212.42328 -68.821773) (xy 212.474682 -68.828796) (xy 212.524659 -68.842721)
			(xy 212.572287 -68.863291) (xy 212.616687 -68.890127) (xy 212.657041 -68.922732) (xy 212.692603 -68.960506)
			(xy 212.722718 -69.002751) (xy 212.73516 -69.025516) (xy 212.742583 -69.038398) (xy 212.763401 -69.0596)
			(xy 212.78944 -69.073914) (xy 212.818496 -69.080127) (xy 212.848112 -69.077715) (xy 212.87578 -69.066881)
			(xy 212.899159 -69.048542) (xy 212.908134 -69.036692) (xy 212.923525 -69.015583) (xy 212.95913 -68.977355)
			(xy 212.999616 -68.94434) (xy 213.044228 -68.917156) (xy 213.092129 -68.89631) (xy 213.142427 -68.882193)
			(xy 213.19418 -68.875068) (xy 213.2203 -68.87464) (xy 213.247555 -68.87503) (xy 213.301509 -68.882787)
			(xy 213.353811 -68.898144) (xy 213.403394 -68.920788) (xy 213.44925 -68.950258) (xy 213.490446 -68.985954)
			(xy 213.526142 -69.02715) (xy 213.555612 -69.073006) (xy 213.578256 -69.122589) (xy 213.593613 -69.174891)
			(xy 213.60137 -69.228845) (xy 213.60137 -69.283355) (xy 213.593613 -69.337309) (xy 213.578256 -69.389611)
			(xy 213.555612 -69.439194) (xy 213.526142 -69.48505) (xy 213.490446 -69.526246) (xy 213.44925 -69.561942)
			(xy 213.403394 -69.591412) (xy 213.353811 -69.614056) (xy 213.301509 -69.629413) (xy 213.247555 -69.63717)
			(xy 213.2203 -69.637656) (xy 213.194357 -69.637256) (xy 213.142951 -69.630224) (xy 213.092972 -69.616289)
			(xy 213.045342 -69.595709) (xy 213.000942 -69.568864) (xy 212.960589 -69.536248) (xy 212.92503 -69.498464)
			(xy 212.894919 -69.45621) (xy 212.88248 -69.43344) (xy 212.875139 -69.420504) (xy 212.854309 -69.399286)
			(xy 212.828252 -69.384965) (xy 212.799176 -69.378754) (xy 212.769542 -69.381178) (xy 212.741861 -69.392033)
			(xy 212.718478 -69.410399) (xy 212.709506 -69.422264) (xy 212.694139 -69.443392) (xy 212.658531 -69.481621)
			(xy 212.618041 -69.514636) (xy 212.573426 -69.541819) (xy 212.52552 -69.562661) (xy 212.475218 -69.576773)
			(xy 212.423462 -69.583892) (xy 212.39734 -69.584316) (xy 212.370086 -69.583839) (xy 212.316132 -69.576087)
			(xy 212.26383 -69.560735) (xy 212.214246 -69.538095) (xy 212.168389 -69.508629) (xy 212.127192 -69.472936)
			(xy 212.091495 -69.431743) (xy 212.062024 -69.385889) (xy 212.039379 -69.336307) (xy 212.024021 -69.284007)
			(xy 212.016263 -69.230054) (xy 211.053801 -69.230054) (xy 211.034349 -69.251764) (xy 210.991481 -69.287439)
			(xy 210.943875 -69.316493) (xy 210.892546 -69.338305) (xy 210.838589 -69.352411) (xy 210.783152 -69.358511)
			(xy 210.727418 -69.356474) (xy 210.672575 -69.346344) (xy 210.619791 -69.328337) (xy 210.570191 -69.302836)
			(xy 210.524833 -69.270385) (xy 210.484684 -69.231676) (xy 210.450598 -69.187533) (xy 210.423302 -69.138898)
			(xy 210.403379 -69.086807) (xy 210.391253 -69.03237) (xy 210.387182 -68.976748) (xy 202.931599 -68.976748)
			(xy 202.931521 -68.981012) (xy 202.923401 -69.036188) (xy 202.907333 -69.089595) (xy 202.883661 -69.140092)
			(xy 202.852888 -69.186605) (xy 202.815671 -69.228142) (xy 202.772803 -69.263817) (xy 202.725197 -69.292871)
			(xy 202.673868 -69.314683) (xy 202.619911 -69.328789) (xy 202.564474 -69.334889) (xy 202.50874 -69.332852)
			(xy 202.453897 -69.322722) (xy 202.401113 -69.304715) (xy 202.351513 -69.279214) (xy 202.306155 -69.246763)
			(xy 202.266006 -69.208054) (xy 202.23192 -69.163911) (xy 202.204624 -69.115276) (xy 202.184701 -69.063185)
			(xy 202.172575 -69.008748) (xy 202.168504 -68.953126) (xy 200.603612 -68.953126) (xy 200.603612 -69.484748)
			(xy 205.281782 -69.484748) (xy 205.285853 -69.429126) (xy 205.297979 -69.374689) (xy 205.317902 -69.322598)
			(xy 205.345198 -69.273963) (xy 205.379284 -69.22982) (xy 205.419433 -69.191111) (xy 205.464791 -69.15866)
			(xy 205.514391 -69.133159) (xy 205.567175 -69.115152) (xy 205.622018 -69.105022) (xy 205.677752 -69.102985)
			(xy 205.733189 -69.109085) (xy 205.787146 -69.123191) (xy 205.838475 -69.145003) (xy 205.886081 -69.174057)
			(xy 205.928949 -69.209732) (xy 205.966166 -69.251269) (xy 205.996939 -69.297782) (xy 206.020611 -69.348279)
			(xy 206.036679 -69.401686) (xy 206.044799 -69.456862) (xy 206.045308 -69.484748) (xy 206.044799 -69.512634)
			(xy 206.037689 -69.560948) (xy 206.244442 -69.560948) (xy 206.248513 -69.505326) (xy 206.260639 -69.450889)
			(xy 206.280562 -69.398798) (xy 206.307858 -69.350163) (xy 206.341944 -69.30602) (xy 206.382093 -69.267311)
			(xy 206.427451 -69.23486) (xy 206.477051 -69.209359) (xy 206.529835 -69.191352) (xy 206.584678 -69.181222)
			(xy 206.640412 -69.179185) (xy 206.695849 -69.185285) (xy 206.749806 -69.199391) (xy 206.801135 -69.221203)
			(xy 206.848741 -69.250257) (xy 206.891609 -69.285932) (xy 206.928826 -69.327469) (xy 206.959599 -69.373982)
			(xy 206.983271 -69.424479) (xy 206.999339 -69.477886) (xy 207.007459 -69.533062) (xy 207.007968 -69.560948)
			(xy 207.007459 -69.588834) (xy 206.999339 -69.64401) (xy 206.983271 -69.697417) (xy 206.959599 -69.747914)
			(xy 206.928826 -69.794427) (xy 206.891609 -69.835964) (xy 206.848741 -69.871639) (xy 206.801135 -69.900693)
			(xy 206.749806 -69.922505) (xy 206.695849 -69.936611) (xy 206.640412 -69.942711) (xy 206.584678 -69.940674)
			(xy 206.529835 -69.930544) (xy 206.477051 -69.912537) (xy 206.427451 -69.887036) (xy 206.382093 -69.854585)
			(xy 206.341944 -69.815876) (xy 206.307858 -69.771733) (xy 206.280562 -69.723098) (xy 206.260639 -69.671007)
			(xy 206.248513 -69.61657) (xy 206.244442 -69.560948) (xy 206.037689 -69.560948) (xy 206.036679 -69.56781)
			(xy 206.020611 -69.621217) (xy 205.996939 -69.671714) (xy 205.966166 -69.718227) (xy 205.928949 -69.759764)
			(xy 205.886081 -69.795439) (xy 205.838475 -69.824493) (xy 205.787146 -69.846305) (xy 205.733189 -69.860411)
			(xy 205.677752 -69.866511) (xy 205.622018 -69.864474) (xy 205.567175 -69.854344) (xy 205.514391 -69.836337)
			(xy 205.464791 -69.810836) (xy 205.419433 -69.778385) (xy 205.379284 -69.739676) (xy 205.345198 -69.695533)
			(xy 205.317902 -69.646898) (xy 205.297979 -69.594807) (xy 205.285853 -69.54037) (xy 205.281782 -69.484748)
			(xy 200.603612 -69.484748) (xy 200.603612 -70.532498) (xy 200.974198 -70.903084) (xy 202.361798 -70.903084)
			(xy 202.365869 -70.847462) (xy 202.377995 -70.793025) (xy 202.397918 -70.740934) (xy 202.425214 -70.692299)
			(xy 202.4593 -70.648156) (xy 202.499449 -70.609447) (xy 202.544807 -70.576996) (xy 202.594407 -70.551495)
			(xy 202.647191 -70.533488) (xy 202.702034 -70.523358) (xy 202.757768 -70.521321) (xy 202.813205 -70.527421)
			(xy 202.867162 -70.541527) (xy 202.918491 -70.563339) (xy 202.966097 -70.592393) (xy 203.008965 -70.628068)
			(xy 203.046182 -70.669605) (xy 203.076955 -70.716118) (xy 203.100627 -70.766615) (xy 203.116695 -70.820022)
			(xy 203.124815 -70.875198) (xy 203.125324 -70.903084) (xy 203.124815 -70.93097) (xy 203.116695 -70.986146)
			(xy 203.102253 -71.034148) (xy 204.418182 -71.034148) (xy 204.422253 -70.978526) (xy 204.434379 -70.924089)
			(xy 204.454302 -70.871998) (xy 204.481598 -70.823363) (xy 204.515684 -70.77922) (xy 204.555833 -70.740511)
			(xy 204.601191 -70.70806) (xy 204.650791 -70.682559) (xy 204.703575 -70.664552) (xy 204.758418 -70.654422)
			(xy 204.814152 -70.652385) (xy 204.869589 -70.658485) (xy 204.923546 -70.672591) (xy 204.974875 -70.694403)
			(xy 205.022481 -70.723457) (xy 205.065349 -70.759132) (xy 205.102566 -70.800669) (xy 205.133339 -70.847182)
			(xy 205.157011 -70.897679) (xy 205.173079 -70.951086) (xy 205.181199 -71.006262) (xy 205.181708 -71.034148)
			(xy 205.181199 -71.062034) (xy 205.173079 -71.11721) (xy 205.167502 -71.135748) (xy 205.592172 -71.135748)
			(xy 205.5927 -71.108497) (xy 205.60045 -71.05455) (xy 205.615799 -71.002254) (xy 205.638434 -70.952676)
			(xy 205.667895 -70.906823) (xy 205.703582 -70.86563) (xy 205.744769 -70.829936) (xy 205.790616 -70.800467)
			(xy 205.84019 -70.777823) (xy 205.892483 -70.762464) (xy 205.946429 -70.754705) (xy 205.97368 -70.75424)
			(xy 206.00174 -70.754795) (xy 206.057252 -70.763026) (xy 206.11096 -70.779298) (xy 206.161706 -70.803261)
			(xy 206.208396 -70.834397) (xy 206.250021 -70.872036) (xy 206.285686 -70.915365) (xy 206.300578 -70.939152)
			(xy 206.30388 -70.944486) (xy 206.478886 -71.119492) (xy 206.488916 -71.128972) (xy 206.512943 -71.142538)
			(xy 206.539724 -71.149179) (xy 206.567306 -71.148412) (xy 206.593676 -71.140292) (xy 206.616912 -71.125412)
			(xy 206.635319 -71.104857) (xy 206.647555 -71.080126) (xy 206.65059 -71.06666) (xy 206.656268 -71.039607)
			(xy 206.674323 -70.987365) (xy 206.699736 -70.93828) (xy 206.731974 -70.893381) (xy 206.77036 -70.85361)
			(xy 206.81409 -70.819803) (xy 206.862245 -70.792668) (xy 206.913815 -70.772775) (xy 206.940658 -70.766178)
			(xy 206.954233 -70.762574) (xy 206.978852 -70.749077) (xy 206.998866 -70.729388) (xy 207.012765 -70.704994)
			(xy 207.019498 -70.677738) (xy 207.018557 -70.649678) (xy 207.010013 -70.622934) (xy 207.002634 -70.610984)
			(xy 206.987459 -70.587342) (xy 206.963437 -70.53656) (xy 206.947124 -70.482804) (xy 206.938875 -70.427236)
			(xy 206.938372 -70.399148) (xy 206.938858 -70.371897) (xy 206.946614 -70.317949) (xy 206.961969 -70.265654)
			(xy 206.984611 -70.216077) (xy 207.014077 -70.170227) (xy 207.049768 -70.129036) (xy 207.090959 -70.093345)
			(xy 207.136809 -70.063879) (xy 207.186386 -70.041237) (xy 207.238681 -70.025882) (xy 207.292629 -70.018126)
			(xy 207.347131 -70.018126) (xy 207.401079 -70.025882) (xy 207.453374 -70.041237) (xy 207.502951 -70.063879)
			(xy 207.548801 -70.093345) (xy 207.589992 -70.129036) (xy 207.625683 -70.170227) (xy 207.655149 -70.216077)
			(xy 207.677791 -70.265654) (xy 207.693146 -70.317949) (xy 207.700902 -70.371897) (xy 207.701388 -70.399148)
			(xy 207.700929 -70.427726) (xy 207.692423 -70.484246) (xy 207.67558 -70.538863) (xy 207.650775 -70.590356)
			(xy 207.618565 -70.637572) (xy 207.579671 -70.679453) (xy 207.534963 -70.715062) (xy 207.485442 -70.743602)
			(xy 207.432218 -70.764433) (xy 207.404462 -70.771258) (xy 207.390873 -70.774821) (xy 207.366246 -70.78832)
			(xy 207.346227 -70.808016) (xy 207.332326 -70.832419) (xy 207.325596 -70.859684) (xy 207.326545 -70.887752)
			(xy 207.335101 -70.914501) (xy 207.342486 -70.926452) (xy 207.357678 -70.950084) (xy 207.381696 -71.000869)
			(xy 207.398003 -71.054628) (xy 207.406247 -71.110199) (xy 207.406748 -71.138288) (xy 207.406541 -71.155336)
			(xy 207.403493 -71.189295) (xy 207.400652 -71.206106) (xy 207.39855 -71.220823) (xy 207.401846 -71.25035)
			(xy 207.413519 -71.277672) (xy 207.432575 -71.300466) (xy 207.457396 -71.316795) (xy 207.485871 -71.325272)
			(xy 207.500728 -71.32574) (xy 209.427826 -71.32574) (xy 209.806794 -70.947026) (xy 209.827658 -70.92693)
			(xy 209.874519 -70.892879) (xy 209.926131 -70.866579) (xy 209.981222 -70.848677) (xy 210.038435 -70.839615)
			(xy 210.067398 -70.839076) (xy 210.327748 -70.839076) (xy 210.342882 -70.838512) (xy 210.371811 -70.8296)
			(xy 210.396859 -70.812602) (xy 210.415825 -70.78901) (xy 210.427047 -70.760896) (xy 210.429537 -70.730728)
			(xy 210.423078 -70.701155) (xy 210.41614 -70.687692) (xy 210.404516 -70.666208) (xy 210.386265 -70.620896)
			(xy 210.373941 -70.573627) (xy 210.367744 -70.525173) (xy 210.367372 -70.500748) (xy 210.367917 -70.471594)
			(xy 210.37679 -70.413966) (xy 210.39432 -70.358357) (xy 210.420102 -70.306059) (xy 210.453535 -70.258289)
			(xy 210.47329 -70.236842) (xy 210.483088 -70.225829) (xy 210.49657 -70.199636) (xy 210.501993 -70.17068)
			(xy 210.498904 -70.141383) (xy 210.487562 -70.114195) (xy 210.478624 -70.102476) (xy 210.462451 -70.081979)
			(xy 210.435279 -70.037397) (xy 210.414441 -69.989525) (xy 210.400327 -69.939258) (xy 210.393202 -69.887535)
			(xy 210.392772 -69.86143) (xy 210.393283 -69.834179) (xy 210.401036 -69.780231) (xy 210.416387 -69.727935)
			(xy 210.439024 -69.678356) (xy 210.468487 -69.632504) (xy 210.504176 -69.591311) (xy 210.545364 -69.555617)
			(xy 210.591212 -69.526148) (xy 210.640788 -69.503504) (xy 210.693082 -69.488146) (xy 210.747029 -69.480387)
			(xy 210.77428 -69.479922) (xy 210.802339 -69.480485) (xy 210.857851 -69.488716) (xy 210.911559 -69.504987)
			(xy 210.962304 -69.528949) (xy 211.008994 -69.560084) (xy 211.05062 -69.597721) (xy 211.086285 -69.641048)
			(xy 211.101178 -69.664834) (xy 211.10448 -69.670168) (xy 211.567822 -70.133718) (xy 216.618564 -70.133718)
			(xy 216.622635 -70.078096) (xy 216.634761 -70.023659) (xy 216.654684 -69.971568) (xy 216.68198 -69.922933)
			(xy 216.716066 -69.87879) (xy 216.756215 -69.840081) (xy 216.801573 -69.80763) (xy 216.851173 -69.782129)
			(xy 216.903957 -69.764122) (xy 216.9588 -69.753992) (xy 217.014534 -69.751955) (xy 217.069971 -69.758055)
			(xy 217.123928 -69.772161) (xy 217.175257 -69.793973) (xy 217.222863 -69.823027) (xy 217.265731 -69.858702)
			(xy 217.302948 -69.900239) (xy 217.333721 -69.946752) (xy 217.357393 -69.997249) (xy 217.373461 -70.050656)
			(xy 217.381581 -70.105832) (xy 217.38209 -70.133718) (xy 217.381581 -70.161604) (xy 217.373461 -70.21678)
			(xy 217.357393 -70.270187) (xy 217.338018 -70.311518) (xy 218.270074 -70.311518) (xy 218.270587 -70.282911)
			(xy 218.279155 -70.226341) (xy 218.296072 -70.171683) (xy 218.320959 -70.120164) (xy 218.353257 -70.072937)
			(xy 218.392244 -70.031061) (xy 218.437045 -69.995474) (xy 218.486657 -69.966973) (xy 218.539967 -69.946198)
			(xy 218.567762 -69.939408) (xy 218.58225 -69.935611) (xy 218.608338 -69.920934) (xy 218.629044 -69.899319)
			(xy 218.642588 -69.872626) (xy 218.647804 -69.843151) (xy 218.644242 -69.81343) (xy 218.632211 -69.786022)
			(xy 218.62288 -69.774308) (xy 218.605857 -69.753521) (xy 218.577169 -69.708093) (xy 218.555139 -69.65909)
			(xy 218.540205 -69.607479) (xy 218.532662 -69.554284) (xy 218.532202 -69.52742) (xy 218.532688 -69.500169)
			(xy 218.540444 -69.446221) (xy 218.555799 -69.393926) (xy 218.578441 -69.344349) (xy 218.607907 -69.298499)
			(xy 218.643598 -69.257308) (xy 218.684789 -69.221617) (xy 218.730639 -69.192151) (xy 218.780216 -69.169509)
			(xy 218.832511 -69.154154) (xy 218.886459 -69.146398) (xy 218.940961 -69.146398) (xy 218.994909 -69.154154)
			(xy 219.047204 -69.169509) (xy 219.096781 -69.192151) (xy 219.142631 -69.221617) (xy 219.183822 -69.257308)
			(xy 219.219513 -69.298499) (xy 219.248979 -69.344349) (xy 219.271621 -69.393926) (xy 219.280613 -69.42455)
			(xy 219.89618 -69.42455) (xy 219.900251 -69.368928) (xy 219.912377 -69.314491) (xy 219.9323 -69.2624)
			(xy 219.959596 -69.213765) (xy 219.993682 -69.169622) (xy 220.033831 -69.130913) (xy 220.079189 -69.098462)
			(xy 220.128789 -69.072961) (xy 220.181573 -69.054954) (xy 220.236416 -69.044824) (xy 220.29215 -69.042787)
			(xy 220.347587 -69.048887) (xy 220.401544 -69.062993) (xy 220.452873 -69.084805) (xy 220.500479 -69.113859)
			(xy 220.543347 -69.149534) (xy 220.580564 -69.191071) (xy 220.611337 -69.237584) (xy 220.635009 -69.288081)
			(xy 220.651077 -69.341488) (xy 220.659197 -69.396664) (xy 220.659706 -69.42455) (xy 220.659197 -69.452436)
			(xy 220.651077 -69.507612) (xy 220.635009 -69.561019) (xy 220.611337 -69.611516) (xy 220.580564 -69.658029)
			(xy 220.543347 -69.699566) (xy 220.500479 -69.735241) (xy 220.452873 -69.764295) (xy 220.401544 -69.786107)
			(xy 220.347587 -69.800213) (xy 220.29215 -69.806313) (xy 220.236416 -69.804276) (xy 220.181573 -69.794146)
			(xy 220.128789 -69.776139) (xy 220.079189 -69.750638) (xy 220.033831 -69.718187) (xy 219.993682 -69.679478)
			(xy 219.959596 -69.635335) (xy 219.9323 -69.5867) (xy 219.912377 -69.534609) (xy 219.900251 -69.480172)
			(xy 219.89618 -69.42455) (xy 219.280613 -69.42455) (xy 219.286976 -69.446221) (xy 219.294732 -69.500169)
			(xy 219.295218 -69.52742) (xy 219.294655 -69.556026) (xy 219.286096 -69.612594) (xy 219.269187 -69.667251)
			(xy 219.244308 -69.71877) (xy 219.212015 -69.765998) (xy 219.173034 -69.807875) (xy 219.128238 -69.843463)
			(xy 219.07863 -69.871964) (xy 219.025323 -69.89274) (xy 218.99753 -69.89953) (xy 218.983023 -69.903266)
			(xy 218.956929 -69.917952) (xy 218.93622 -69.939578) (xy 218.922676 -69.966284) (xy 218.917465 -69.99577)
			(xy 218.921034 -70.025499) (xy 218.933076 -70.052914) (xy 218.942412 -70.06463) (xy 218.949669 -70.073289)
			(xy 218.963269 -70.091333) (xy 218.96959 -70.100698) (xy 218.977647 -70.111995) (xy 218.998596 -70.130169)
			(xy 219.023668 -70.142024) (xy 219.051007 -70.146682) (xy 219.07859 -70.143799) (xy 219.104375 -70.133588)
			(xy 219.126454 -70.116805) (xy 219.135198 -70.106032) (xy 219.153328 -70.083012) (xy 219.195511 -70.042342)
			(xy 219.243415 -70.008599) (xy 219.295915 -69.982575) (xy 219.351775 -69.964883) (xy 219.409684 -69.955938)
			(xy 219.438982 -69.95541) (xy 219.466237 -69.955836) (xy 219.520192 -69.963591) (xy 219.572495 -69.978946)
			(xy 219.62208 -70.001589) (xy 219.667937 -70.031058) (xy 219.709134 -70.066753) (xy 219.744832 -70.107948)
			(xy 219.774303 -70.153804) (xy 219.796948 -70.203388) (xy 219.812305 -70.25569) (xy 219.820063 -70.309645)
			(xy 219.820063 -70.364155) (xy 219.812305 -70.41811) (xy 219.796948 -70.470412) (xy 219.774303 -70.519996)
			(xy 219.744832 -70.565852) (xy 219.709134 -70.607047) (xy 219.667937 -70.642742) (xy 219.62208 -70.672211)
			(xy 219.572495 -70.694854) (xy 219.520192 -70.710209) (xy 219.466237 -70.717964) (xy 219.438982 -70.718426)
			(xy 219.412116 -70.717975) (xy 219.358914 -70.710445) (xy 219.307295 -70.695524) (xy 219.258281 -70.673506)
			(xy 219.212843 -70.644827) (xy 219.171879 -70.610055) (xy 219.1362 -70.569878) (xy 219.120974 -70.547738)
			(xy 219.112962 -70.536405) (xy 219.092006 -70.518223) (xy 219.066923 -70.506366) (xy 219.039573 -70.50171)
			(xy 219.01198 -70.504601) (xy 218.986188 -70.514824) (xy 218.964108 -70.531623) (xy 218.955366 -70.542404)
			(xy 218.937183 -70.56538) (xy 218.895013 -70.606055) (xy 218.84712 -70.639805) (xy 218.794631 -70.665837)
			(xy 218.738779 -70.683538) (xy 218.680877 -70.692493) (xy 218.651582 -70.693026) (xy 218.624331 -70.692539)
			(xy 218.570384 -70.684781) (xy 218.518091 -70.669424) (xy 218.468515 -70.646782) (xy 218.422665 -70.617316)
			(xy 218.381476 -70.581624) (xy 218.345784 -70.540435) (xy 218.316318 -70.494585) (xy 218.293676 -70.445009)
			(xy 218.278319 -70.392716) (xy 218.270561 -70.338769) (xy 218.270074 -70.311518) (xy 217.338018 -70.311518)
			(xy 217.333721 -70.320684) (xy 217.302948 -70.367197) (xy 217.265731 -70.408734) (xy 217.222863 -70.444409)
			(xy 217.175257 -70.473463) (xy 217.123928 -70.495275) (xy 217.069971 -70.509381) (xy 217.014534 -70.515481)
			(xy 216.9588 -70.513444) (xy 216.903957 -70.503314) (xy 216.851173 -70.485307) (xy 216.801573 -70.459806)
			(xy 216.756215 -70.427355) (xy 216.716066 -70.388646) (xy 216.68198 -70.344503) (xy 216.654684 -70.295868)
			(xy 216.634761 -70.243777) (xy 216.622635 -70.18934) (xy 216.618564 -70.133718) (xy 211.567822 -70.133718)
			(xy 211.669884 -70.235826) (xy 211.689994 -70.25669) (xy 211.724104 -70.303534) (xy 211.750461 -70.355138)
			(xy 211.768416 -70.410232) (xy 211.777527 -70.467457) (xy 211.778088 -70.49643) (xy 211.778088 -70.852792)
			(xy 213.193882 -70.852792) (xy 213.197953 -70.79717) (xy 213.210079 -70.742733) (xy 213.230002 -70.690642)
			(xy 213.257298 -70.642007) (xy 213.291384 -70.597864) (xy 213.331533 -70.559155) (xy 213.376891 -70.526704)
			(xy 213.426491 -70.501203) (xy 213.479275 -70.483196) (xy 213.534118 -70.473066) (xy 213.589852 -70.471029)
			(xy 213.645289 -70.477129) (xy 213.699246 -70.491235) (xy 213.750575 -70.513047) (xy 213.798181 -70.542101)
			(xy 213.841049 -70.577776) (xy 213.878266 -70.619313) (xy 213.909039 -70.665826) (xy 213.932711 -70.716323)
			(xy 213.948779 -70.76973) (xy 213.956899 -70.824906) (xy 213.957408 -70.852792) (xy 213.956899 -70.880678)
			(xy 213.948779 -70.935854) (xy 213.932711 -70.989261) (xy 213.909039 -71.039758) (xy 213.878266 -71.086271)
			(xy 213.8419 -71.126858) (xy 216.619834 -71.126858) (xy 216.623905 -71.071236) (xy 216.636031 -71.016799)
			(xy 216.655954 -70.964708) (xy 216.68325 -70.916073) (xy 216.717336 -70.87193) (xy 216.757485 -70.833221)
			(xy 216.802843 -70.80077) (xy 216.852443 -70.775269) (xy 216.905227 -70.757262) (xy 216.96007 -70.747132)
			(xy 217.015804 -70.745095) (xy 217.071241 -70.751195) (xy 217.125198 -70.765301) (xy 217.176527 -70.787113)
			(xy 217.224133 -70.816167) (xy 217.267001 -70.851842) (xy 217.304218 -70.893379) (xy 217.334991 -70.939892)
			(xy 217.358663 -70.990389) (xy 217.374731 -71.043796) (xy 217.382851 -71.098972) (xy 217.38336 -71.126858)
			(xy 217.382851 -71.154744) (xy 217.374731 -71.20992) (xy 217.358663 -71.263327) (xy 217.334991 -71.313824)
			(xy 217.317025 -71.34098) (xy 219.00972 -71.34098) (xy 219.013791 -71.285358) (xy 219.025917 -71.230921)
			(xy 219.04584 -71.17883) (xy 219.073136 -71.130195) (xy 219.107222 -71.086052) (xy 219.147371 -71.047343)
			(xy 219.192729 -71.014892) (xy 219.242329 -70.989391) (xy 219.295113 -70.971384) (xy 219.349956 -70.961254)
			(xy 219.40569 -70.959217) (xy 219.461127 -70.965317) (xy 219.515084 -70.979423) (xy 219.566413 -71.001235)
			(xy 219.614019 -71.030289) (xy 219.656887 -71.065964) (xy 219.694104 -71.107501) (xy 219.724877 -71.154014)
			(xy 219.748549 -71.204511) (xy 219.764617 -71.257918) (xy 219.772737 -71.313094) (xy 219.773246 -71.34098)
			(xy 219.772737 -71.368866) (xy 219.764617 -71.424042) (xy 219.748549 -71.477449) (xy 219.724877 -71.527946)
			(xy 219.694104 -71.574459) (xy 219.656887 -71.615996) (xy 219.614019 -71.651671) (xy 219.566413 -71.680725)
			(xy 219.515084 -71.702537) (xy 219.461127 -71.716643) (xy 219.40569 -71.722743) (xy 219.349956 -71.720706)
			(xy 219.295113 -71.710576) (xy 219.242329 -71.692569) (xy 219.192729 -71.667068) (xy 219.147371 -71.634617)
			(xy 219.107222 -71.595908) (xy 219.073136 -71.551765) (xy 219.04584 -71.50313) (xy 219.025917 -71.451039)
			(xy 219.013791 -71.396602) (xy 219.00972 -71.34098) (xy 217.317025 -71.34098) (xy 217.304218 -71.360337)
			(xy 217.267001 -71.401874) (xy 217.224133 -71.437549) (xy 217.176527 -71.466603) (xy 217.125198 -71.488415)
			(xy 217.071241 -71.502521) (xy 217.015804 -71.508621) (xy 216.96007 -71.506584) (xy 216.905227 -71.496454)
			(xy 216.852443 -71.478447) (xy 216.802843 -71.452946) (xy 216.757485 -71.420495) (xy 216.717336 -71.381786)
			(xy 216.68325 -71.337643) (xy 216.655954 -71.289008) (xy 216.636031 -71.236917) (xy 216.623905 -71.18248)
			(xy 216.619834 -71.126858) (xy 213.8419 -71.126858) (xy 213.841049 -71.127808) (xy 213.798181 -71.163483)
			(xy 213.750575 -71.192537) (xy 213.699246 -71.214349) (xy 213.645289 -71.228455) (xy 213.589852 -71.234555)
			(xy 213.534118 -71.232518) (xy 213.479275 -71.222388) (xy 213.426491 -71.204381) (xy 213.376891 -71.17888)
			(xy 213.331533 -71.146429) (xy 213.291384 -71.10772) (xy 213.257298 -71.063577) (xy 213.230002 -71.014942)
			(xy 213.210079 -70.962851) (xy 213.197953 -70.908414) (xy 213.193882 -70.852792) (xy 211.778088 -70.852792)
			(xy 211.778088 -71.567548) (xy 211.777984 -71.578178) (xy 211.776715 -71.5994) (xy 211.775548 -71.609966)
			(xy 211.774296 -71.625325) (xy 211.779962 -71.6556) (xy 211.794403 -71.682805) (xy 211.816301 -71.704464)
			(xy 211.843664 -71.718603) (xy 211.873999 -71.723936) (xy 211.88934 -71.722488) (xy 211.901353 -71.721047)
			(xy 211.925501 -71.719524) (xy 211.9376 -71.71944) (xy 211.964855 -71.71983) (xy 212.018809 -71.727587)
			(xy 212.071111 -71.742944) (xy 212.120694 -71.765588) (xy 212.16655 -71.795058) (xy 212.207746 -71.830754)
			(xy 212.243442 -71.87195) (xy 212.272912 -71.917806) (xy 212.295556 -71.967389) (xy 212.310913 -72.019691)
			(xy 212.31867 -72.073645) (xy 212.31867 -72.128155) (xy 212.310913 -72.182109) (xy 212.295556 -72.234411)
			(xy 212.272912 -72.283994) (xy 212.243442 -72.32985) (xy 212.207746 -72.371046) (xy 212.179423 -72.395588)
			(xy 212.993984 -72.395588) (xy 212.998055 -72.339966) (xy 213.010181 -72.285529) (xy 213.030104 -72.233438)
			(xy 213.0574 -72.184803) (xy 213.091486 -72.14066) (xy 213.131635 -72.101951) (xy 213.176993 -72.0695)
			(xy 213.226593 -72.043999) (xy 213.279377 -72.025992) (xy 213.33422 -72.015862) (xy 213.389954 -72.013825)
			(xy 213.40843 -72.015858) (xy 216.619834 -72.015858) (xy 216.623905 -71.960236) (xy 216.636031 -71.905799)
			(xy 216.655954 -71.853708) (xy 216.68325 -71.805073) (xy 216.717336 -71.76093) (xy 216.757485 -71.722221)
			(xy 216.802843 -71.68977) (xy 216.852443 -71.664269) (xy 216.905227 -71.646262) (xy 216.96007 -71.636132)
			(xy 217.015804 -71.634095) (xy 217.071241 -71.640195) (xy 217.125198 -71.654301) (xy 217.176527 -71.676113)
			(xy 217.224133 -71.705167) (xy 217.267001 -71.740842) (xy 217.304218 -71.782379) (xy 217.334991 -71.828892)
			(xy 217.358663 -71.879389) (xy 217.374731 -71.932796) (xy 217.382851 -71.987972) (xy 217.38336 -72.015858)
			(xy 217.382851 -72.043744) (xy 217.374731 -72.09892) (xy 217.358663 -72.152327) (xy 217.334991 -72.202824)
			(xy 217.304218 -72.249337) (xy 217.267001 -72.290874) (xy 217.224133 -72.326549) (xy 217.176527 -72.355603)
			(xy 217.125198 -72.377415) (xy 217.071241 -72.391521) (xy 217.015804 -72.397621) (xy 216.96007 -72.395584)
			(xy 216.905227 -72.385454) (xy 216.852443 -72.367447) (xy 216.802843 -72.341946) (xy 216.757485 -72.309495)
			(xy 216.717336 -72.270786) (xy 216.68325 -72.226643) (xy 216.655954 -72.178008) (xy 216.636031 -72.125917)
			(xy 216.623905 -72.07148) (xy 216.619834 -72.015858) (xy 213.40843 -72.015858) (xy 213.445391 -72.019925)
			(xy 213.499348 -72.034031) (xy 213.550677 -72.055843) (xy 213.598283 -72.084897) (xy 213.641151 -72.120572)
			(xy 213.678368 -72.162109) (xy 213.709141 -72.208622) (xy 213.732813 -72.259119) (xy 213.748881 -72.312526)
			(xy 213.757001 -72.367702) (xy 213.75751 -72.395588) (xy 213.757001 -72.423474) (xy 213.748881 -72.47865)
			(xy 213.732813 -72.532057) (xy 213.709141 -72.582554) (xy 213.678368 -72.629067) (xy 213.641151 -72.670604)
			(xy 213.598283 -72.706279) (xy 213.550677 -72.735333) (xy 213.499348 -72.757145) (xy 213.445391 -72.771251)
			(xy 213.389954 -72.777351) (xy 213.33422 -72.775314) (xy 213.279377 -72.765184) (xy 213.226593 -72.747177)
			(xy 213.176993 -72.721676) (xy 213.131635 -72.689225) (xy 213.091486 -72.650516) (xy 213.0574 -72.606373)
			(xy 213.030104 -72.557738) (xy 213.010181 -72.505647) (xy 212.998055 -72.45121) (xy 212.993984 -72.395588)
			(xy 212.179423 -72.395588) (xy 212.16655 -72.406742) (xy 212.120694 -72.436212) (xy 212.071111 -72.458856)
			(xy 212.018809 -72.474213) (xy 211.964855 -72.48197) (xy 211.9376 -72.482456) (xy 211.910796 -72.481966)
			(xy 211.85772 -72.474436) (xy 211.806219 -72.459552) (xy 211.757308 -72.437607) (xy 211.71195 -72.409034)
			(xy 211.671037 -72.374394) (xy 211.635374 -72.334369) (xy 211.605663 -72.289748) (xy 211.582489 -72.241407)
			(xy 211.566308 -72.1903) (xy 211.561426 -72.16394) (xy 211.558683 -72.15026) (xy 211.546799 -72.125026)
			(xy 211.528539 -72.103942) (xy 211.505261 -72.088578) (xy 211.478697 -72.080075) (xy 211.450823 -72.079068)
			(xy 211.423714 -72.08563) (xy 211.399387 -72.099273) (xy 211.389214 -72.108822) (xy 211.060284 -72.437752)
			(xy 211.039426 -72.45787) (xy 210.99258 -72.491975) (xy 210.940973 -72.518329) (xy 210.885878 -72.536283)
			(xy 210.828653 -72.545395) (xy 210.79968 -72.545956) (xy 210.617816 -72.545956) (xy 210.604035 -72.546476)
			(xy 210.577476 -72.553848) (xy 210.553859 -72.568058) (xy 210.534905 -72.588069) (xy 210.521998 -72.612423)
			(xy 210.516078 -72.639342) (xy 210.517578 -72.666864) (xy 210.52155 -72.680068) (xy 210.531008 -72.709854)
			(xy 210.541221 -72.771505) (xy 210.54187 -72.80275) (xy 210.541385 -72.829954) (xy 215.542533 -72.829954)
			(xy 215.542533 -72.775442) (xy 215.550291 -72.721486) (xy 215.56565 -72.669184) (xy 215.588296 -72.619599)
			(xy 215.617768 -72.573742) (xy 215.653466 -72.532547) (xy 215.694665 -72.496851) (xy 215.740524 -72.467382)
			(xy 215.79011 -72.44474) (xy 215.842414 -72.429385) (xy 215.89637 -72.421631) (xy 215.950882 -72.421635)
			(xy 216.004837 -72.429397) (xy 216.057139 -72.444758) (xy 216.106722 -72.467407) (xy 216.152577 -72.496882)
			(xy 216.19377 -72.532583) (xy 216.229463 -72.573784) (xy 216.258929 -72.619645) (xy 216.281568 -72.669232)
			(xy 216.29692 -72.721537) (xy 216.302092 -72.757538) (xy 217.103704 -72.757538) (xy 217.107775 -72.701916)
			(xy 217.119901 -72.647479) (xy 217.139824 -72.595388) (xy 217.16712 -72.546753) (xy 217.201206 -72.50261)
			(xy 217.241355 -72.463901) (xy 217.286713 -72.43145) (xy 217.336313 -72.405949) (xy 217.389097 -72.387942)
			(xy 217.44394 -72.377812) (xy 217.499674 -72.375775) (xy 217.555111 -72.381875) (xy 217.609068 -72.395981)
			(xy 217.660397 -72.417793) (xy 217.708003 -72.446847) (xy 217.750871 -72.482522) (xy 217.788088 -72.524059)
			(xy 217.789635 -72.526398) (xy 220.23019 -72.526398) (xy 220.234261 -72.470776) (xy 220.246387 -72.416339)
			(xy 220.26631 -72.364248) (xy 220.293606 -72.315613) (xy 220.327692 -72.27147) (xy 220.367841 -72.232761)
			(xy 220.413199 -72.20031) (xy 220.462799 -72.174809) (xy 220.515583 -72.156802) (xy 220.570426 -72.146672)
			(xy 220.62616 -72.144635) (xy 220.681597 -72.150735) (xy 220.735554 -72.164841) (xy 220.786883 -72.186653)
			(xy 220.834489 -72.215707) (xy 220.877357 -72.251382) (xy 220.914574 -72.292919) (xy 220.945347 -72.339432)
			(xy 220.969019 -72.389929) (xy 220.985087 -72.443336) (xy 220.993207 -72.498512) (xy 220.993716 -72.526398)
			(xy 220.993207 -72.554284) (xy 220.985087 -72.60946) (xy 220.969019 -72.662867) (xy 220.945347 -72.713364)
			(xy 220.932926 -72.732138) (xy 223.378014 -72.732138) (xy 223.378554 -72.703222) (xy 223.387278 -72.646051)
			(xy 223.404531 -72.590853) (xy 223.429919 -72.538891) (xy 223.462859 -72.491356) (xy 223.502596 -72.449339)
			(xy 223.52508 -72.431148) (xy 223.536848 -72.421209) (xy 223.554367 -72.395898) (xy 223.563548 -72.366515)
			(xy 223.563555 -72.335732) (xy 223.554388 -72.306345) (xy 223.53688 -72.281025) (xy 223.52508 -72.271128)
			(xy 223.502606 -72.252926) (xy 223.462871 -72.210908) (xy 223.429931 -72.163375) (xy 223.404542 -72.111416)
			(xy 223.387283 -72.056221) (xy 223.378551 -71.999053) (xy 223.378014 -71.970138) (xy 223.378491 -71.942885)
			(xy 223.386243 -71.888933) (xy 223.401595 -71.836635) (xy 223.424235 -71.787053) (xy 223.453701 -71.741199)
			(xy 223.489394 -71.700005) (xy 223.530586 -71.664311) (xy 223.576439 -71.634843) (xy 223.62602 -71.612201)
			(xy 223.678318 -71.596846) (xy 223.732269 -71.589092) (xy 223.759522 -71.58863) (xy 223.787913 -71.589142)
			(xy 223.844067 -71.597556) (xy 223.898356 -71.614193) (xy 223.949582 -71.638687) (xy 223.97339 -71.654162)
			(xy 223.9848 -71.661359) (xy 224.010291 -71.67015) (xy 224.037195 -71.671952) (xy 224.063631 -71.66664)
			(xy 224.087751 -71.654585) (xy 224.107867 -71.636628) (xy 224.122574 -71.614028) (xy 224.130842 -71.588362)
			(xy 224.131886 -71.574914) (xy 224.133549 -71.548532) (xy 224.143298 -71.496578) (xy 224.160128 -71.446467)
			(xy 224.183718 -71.399161) (xy 224.213616 -71.355567) (xy 224.249248 -71.31652) (xy 224.289931 -71.282768)
			(xy 224.334886 -71.254958) (xy 224.383251 -71.233624) (xy 224.434099 -71.219173) (xy 224.486455 -71.211884)
			(xy 224.512886 -71.21144) (xy 224.540143 -71.211806) (xy 224.594102 -71.219562) (xy 224.646408 -71.234919)
			(xy 224.695997 -71.257564) (xy 224.741857 -71.287035) (xy 224.783057 -71.322733) (xy 224.818757 -71.363931)
			(xy 224.84823 -71.409791) (xy 224.870876 -71.459378) (xy 224.886235 -71.511684) (xy 224.893993 -71.565643)
			(xy 224.893993 -71.620157) (xy 224.886235 -71.674116) (xy 224.870876 -71.726422) (xy 224.84823 -71.776009)
			(xy 224.818757 -71.821869) (xy 224.783057 -71.863067) (xy 224.741857 -71.898765) (xy 224.695997 -71.928236)
			(xy 224.646408 -71.950881) (xy 224.594102 -71.966238) (xy 224.540143 -71.973994) (xy 224.512886 -71.974456)
			(xy 224.484496 -71.973942) (xy 224.428341 -71.965529) (xy 224.374052 -71.948893) (xy 224.322826 -71.924398)
			(xy 224.299018 -71.908924) (xy 224.287596 -71.901748) (xy 224.262109 -71.892958) (xy 224.235209 -71.891155)
			(xy 224.208776 -71.896465) (xy 224.18466 -71.908517) (xy 224.164545 -71.926469) (xy 224.149838 -71.949065)
			(xy 224.141568 -71.974726) (xy 224.140522 -71.988172) (xy 224.138746 -72.015528) (xy 224.128382 -72.069357)
			(xy 224.110411 -72.121145) (xy 224.085203 -72.169823) (xy 224.053279 -72.214386) (xy 224.015298 -72.253914)
			(xy 223.993964 -72.271128) (xy 223.982116 -72.280981) (xy 223.96459 -72.306315) (xy 223.955414 -72.335721)
			(xy 223.955421 -72.366526) (xy 223.964611 -72.395928) (xy 223.982148 -72.421253) (xy 223.993964 -72.431148)
			(xy 224.016415 -72.449377) (xy 224.056154 -72.491388) (xy 224.089098 -72.538915) (xy 224.114492 -72.590869)
			(xy 224.131755 -72.64606) (xy 224.140491 -72.703224) (xy 224.14103 -72.732138) (xy 224.140544 -72.759389)
			(xy 224.132788 -72.813337) (xy 224.117433 -72.865632) (xy 224.094791 -72.915209) (xy 224.065325 -72.961059)
			(xy 224.029634 -73.00225) (xy 223.988443 -73.037941) (xy 223.942593 -73.067407) (xy 223.893016 -73.090049)
			(xy 223.840721 -73.105404) (xy 223.786773 -73.11316) (xy 223.732271 -73.11316) (xy 223.678323 -73.105404)
			(xy 223.626028 -73.090049) (xy 223.576451 -73.067407) (xy 223.530601 -73.037941) (xy 223.48941 -73.00225)
			(xy 223.453719 -72.961059) (xy 223.424253 -72.915209) (xy 223.401611 -72.865632) (xy 223.386256 -72.813337)
			(xy 223.3785 -72.759389) (xy 223.378014 -72.732138) (xy 220.932926 -72.732138) (xy 220.914574 -72.759877)
			(xy 220.877357 -72.801414) (xy 220.834489 -72.837089) (xy 220.786883 -72.866143) (xy 220.735554 -72.887955)
			(xy 220.681597 -72.902061) (xy 220.62616 -72.908161) (xy 220.570426 -72.906124) (xy 220.515583 -72.895994)
			(xy 220.462799 -72.877987) (xy 220.413199 -72.852486) (xy 220.367841 -72.820035) (xy 220.327692 -72.781326)
			(xy 220.293606 -72.737183) (xy 220.26631 -72.688548) (xy 220.246387 -72.636457) (xy 220.234261 -72.58202)
			(xy 220.23019 -72.526398) (xy 217.789635 -72.526398) (xy 217.818861 -72.570572) (xy 217.842533 -72.621069)
			(xy 217.858601 -72.674476) (xy 217.866721 -72.729652) (xy 217.86723 -72.757538) (xy 217.866721 -72.785424)
			(xy 217.858601 -72.8406) (xy 217.842533 -72.894007) (xy 217.818861 -72.944504) (xy 217.788088 -72.991017)
			(xy 217.750871 -73.032554) (xy 217.708003 -73.068229) (xy 217.660397 -73.097283) (xy 217.609068 -73.119095)
			(xy 217.555111 -73.133201) (xy 217.499674 -73.139301) (xy 217.44394 -73.137264) (xy 217.389097 -73.127134)
			(xy 217.336313 -73.109127) (xy 217.286713 -73.083626) (xy 217.241355 -73.051175) (xy 217.201206 -73.012466)
			(xy 217.16712 -72.968323) (xy 217.139824 -72.919688) (xy 217.119901 -72.867597) (xy 217.107775 -72.81316)
			(xy 217.103704 -72.757538) (xy 216.302092 -72.757538) (xy 216.304671 -72.775494) (xy 216.30513 -72.80275)
			(xy 216.305055 -72.813824) (xy 216.303786 -72.835936) (xy 216.30259 -72.846946) (xy 216.301419 -72.860452)
			(xy 216.305481 -72.887248) (xy 216.316456 -72.912029) (xy 216.333571 -72.933044) (xy 216.355615 -72.94881)
			(xy 216.381034 -72.958213) (xy 216.408031 -72.960591) (xy 216.434702 -72.955774) (xy 216.447116 -72.950324)
			(xy 216.472871 -72.938624) (xy 216.526971 -72.922104) (xy 216.582917 -72.913753) (xy 216.6112 -72.91324)
			(xy 216.638451 -72.913678) (xy 216.692397 -72.921434) (xy 216.74469 -72.936788) (xy 216.794266 -72.959428)
			(xy 216.840116 -72.988893) (xy 216.881306 -73.024583) (xy 216.916997 -73.065771) (xy 216.946464 -73.111619)
			(xy 216.969106 -73.161195) (xy 216.984463 -73.213487) (xy 216.992221 -73.267433) (xy 216.992223 -73.321935)
			(xy 216.98447 -73.375881) (xy 216.969117 -73.428175) (xy 216.94648 -73.477752) (xy 216.917017 -73.523603)
			(xy 216.881329 -73.564795) (xy 216.840142 -73.600488) (xy 216.794295 -73.629957) (xy 216.74472 -73.652601)
			(xy 216.692428 -73.667959) (xy 216.66477 -73.671938) (xy 218.576904 -73.671938) (xy 218.580975 -73.616316)
			(xy 218.593101 -73.561879) (xy 218.613024 -73.509788) (xy 218.64032 -73.461153) (xy 218.674406 -73.41701)
			(xy 218.714555 -73.378301) (xy 218.759913 -73.34585) (xy 218.809513 -73.320349) (xy 218.862297 -73.302342)
			(xy 218.91714 -73.292212) (xy 218.972874 -73.290175) (xy 219.028311 -73.296275) (xy 219.082268 -73.310381)
			(xy 219.133597 -73.332193) (xy 219.181203 -73.361247) (xy 219.224071 -73.396922) (xy 219.261288 -73.438459)
			(xy 219.292061 -73.484972) (xy 219.315733 -73.535469) (xy 219.331801 -73.588876) (xy 219.339921 -73.644052)
			(xy 219.34043 -73.671938) (xy 219.339921 -73.699824) (xy 219.331801 -73.755) (xy 219.315733 -73.808407)
			(xy 219.292061 -73.858904) (xy 219.261288 -73.905417) (xy 219.224071 -73.946954) (xy 219.181203 -73.982629)
			(xy 219.133597 -74.011683) (xy 219.082268 -74.033495) (xy 219.028311 -74.047601) (xy 218.972874 -74.053701)
			(xy 218.91714 -74.051664) (xy 218.862297 -74.041534) (xy 218.809513 -74.023527) (xy 218.759913 -73.998026)
			(xy 218.714555 -73.965575) (xy 218.674406 -73.926866) (xy 218.64032 -73.882723) (xy 218.613024 -73.834088)
			(xy 218.593101 -73.781997) (xy 218.580975 -73.72756) (xy 218.576904 -73.671938) (xy 216.66477 -73.671938)
			(xy 216.638482 -73.67572) (xy 216.583981 -73.675725) (xy 216.530034 -73.667973) (xy 216.47774 -73.652623)
			(xy 216.428162 -73.629987) (xy 216.38231 -73.600526) (xy 216.341117 -73.56484) (xy 216.305422 -73.523655)
			(xy 216.275951 -73.477809) (xy 216.253305 -73.428235) (xy 216.237944 -73.375944) (xy 216.230181 -73.321998)
			(xy 216.229692 -73.294748) (xy 216.229767 -73.283674) (xy 216.231036 -73.261562) (xy 216.232232 -73.250552)
			(xy 216.233373 -73.237045) (xy 216.229312 -73.210254) (xy 216.218339 -73.185478) (xy 216.201229 -73.164466)
			(xy 216.17919 -73.148702) (xy 216.153777 -73.139297) (xy 216.126785 -73.136916) (xy 216.100119 -73.141728)
			(xy 216.087706 -73.147174) (xy 216.061948 -73.158867) (xy 216.00785 -73.175389) (xy 215.951905 -73.183743)
			(xy 215.923622 -73.184258) (xy 215.896366 -73.183769) (xy 215.84241 -73.176014) (xy 215.790106 -73.160659)
			(xy 215.74052 -73.138016) (xy 215.694661 -73.108546) (xy 215.653464 -73.072851) (xy 215.617766 -73.031655)
			(xy 215.588294 -72.985797) (xy 215.565648 -72.936213) (xy 215.550291 -72.88391) (xy 215.542533 -72.829954)
			(xy 210.541385 -72.829954) (xy 210.541384 -72.830001) (xy 210.533628 -72.883949) (xy 210.518273 -72.936244)
			(xy 210.495631 -72.985821) (xy 210.466165 -73.031671) (xy 210.430474 -73.072862) (xy 210.389283 -73.108553)
			(xy 210.343433 -73.138019) (xy 210.293856 -73.160661) (xy 210.241561 -73.176016) (xy 210.187613 -73.183772)
			(xy 210.133111 -73.183772) (xy 210.079163 -73.176016) (xy 210.026868 -73.160661) (xy 209.977291 -73.138019)
			(xy 209.931441 -73.108553) (xy 209.89025 -73.072862) (xy 209.854559 -73.031671) (xy 209.825093 -72.985821)
			(xy 209.802451 -72.936244) (xy 209.787096 -72.883949) (xy 209.77934 -72.830001) (xy 209.778854 -72.80275)
			(xy 209.779494 -72.771504) (xy 209.789699 -72.70985) (xy 209.799174 -72.680068) (xy 209.803187 -72.666871)
			(xy 209.804687 -72.639336) (xy 209.798765 -72.612403) (xy 209.785853 -72.588037) (xy 209.766892 -72.568014)
			(xy 209.743266 -72.553794) (xy 209.716696 -72.546414) (xy 209.702908 -72.545956) (xy 207.773778 -72.545956)
			(xy 207.760089 -72.546467) (xy 207.733698 -72.553751) (xy 207.710193 -72.567788) (xy 207.691265 -72.587569)
			(xy 207.678276 -72.61167) (xy 207.672162 -72.638356) (xy 207.673362 -72.665708) (xy 207.681789 -72.691756)
			(xy 207.688942 -72.703436) (xy 207.703862 -72.726968) (xy 207.727508 -72.777416) (xy 207.74356 -72.830769)
			(xy 207.751677 -72.88589) (xy 207.752188 -72.913748) (xy 207.751767 -72.941001) (xy 207.744003 -72.994952)
			(xy 207.728641 -73.04725) (xy 207.705993 -73.096828) (xy 207.67652 -73.142679) (xy 207.640821 -73.18387)
			(xy 207.599625 -73.21956) (xy 207.553769 -73.249025) (xy 207.504186 -73.271665) (xy 207.451886 -73.287018)
			(xy 207.397933 -73.294772) (xy 207.37068 -73.295256) (xy 207.344365 -73.294797) (xy 207.292232 -73.287572)
			(xy 207.241589 -73.273248) (xy 207.193395 -73.252097) (xy 207.148567 -73.224522) (xy 207.107956 -73.191045)
			(xy 207.072333 -73.152302) (xy 207.05699 -73.130918) (xy 207.048647 -73.119635) (xy 207.027014 -73.10178)
			(xy 207.001334 -73.090496) (xy 206.973551 -73.086638) (xy 206.945768 -73.090496) (xy 206.920088 -73.10178)
			(xy 206.898455 -73.119635) (xy 206.890112 -73.130918) (xy 206.874754 -73.152291) (xy 206.839131 -73.191032)
			(xy 206.798522 -73.22451) (xy 206.753697 -73.252088) (xy 206.705507 -73.273245) (xy 206.654866 -73.287577)
			(xy 206.602737 -73.294813) (xy 206.576422 -73.295256) (xy 206.549174 -73.294701) (xy 206.495231 -73.286949)
			(xy 206.44294 -73.271599) (xy 206.393366 -73.248964) (xy 206.347518 -73.219505) (xy 206.306329 -73.18382)
			(xy 206.270637 -73.142638) (xy 206.241169 -73.096795) (xy 206.218525 -73.047225) (xy 206.203166 -72.994938)
			(xy 206.195404 -72.940996) (xy 206.194914 -72.913748) (xy 206.19529 -72.890456) (xy 206.201022 -72.844225)
			(xy 206.206344 -72.821546) (xy 206.207868 -72.81545) (xy 206.207868 -72.565006) (xy 206.208408 -72.536043)
			(xy 206.217469 -72.478829) (xy 206.23537 -72.423738) (xy 206.261669 -72.372125) (xy 206.295718 -72.325262)
			(xy 206.315818 -72.304402) (xy 206.42072 -72.199246) (xy 206.430449 -72.188878) (xy 206.444189 -72.163997)
			(xy 206.450547 -72.136294) (xy 206.449032 -72.107911) (xy 206.43976 -72.081043) (xy 206.423449 -72.057766)
			(xy 206.401359 -72.03988) (xy 206.388462 -72.033892) (xy 206.366896 -72.024301) (xy 206.326172 -72.000439)
			(xy 206.288823 -71.97158) (xy 206.271876 -71.955152) (xy 205.782418 -71.465948) (xy 205.777084 -71.462646)
			(xy 205.753284 -71.447767) (xy 205.709932 -71.412117) (xy 205.672275 -71.370496) (xy 205.641125 -71.323805)
			(xy 205.617156 -71.273053) (xy 205.600886 -71.219335) (xy 205.592666 -71.163812) (xy 205.592172 -71.135748)
			(xy 205.167502 -71.135748) (xy 205.157011 -71.170617) (xy 205.133339 -71.221114) (xy 205.102566 -71.267627)
			(xy 205.065349 -71.309164) (xy 205.022481 -71.344839) (xy 204.974875 -71.373893) (xy 204.923546 -71.395705)
			(xy 204.869589 -71.409811) (xy 204.814152 -71.415911) (xy 204.758418 -71.413874) (xy 204.703575 -71.403744)
			(xy 204.650791 -71.385737) (xy 204.601191 -71.360236) (xy 204.555833 -71.327785) (xy 204.515684 -71.289076)
			(xy 204.481598 -71.244933) (xy 204.454302 -71.196298) (xy 204.434379 -71.144207) (xy 204.422253 -71.08977)
			(xy 204.418182 -71.034148) (xy 203.102253 -71.034148) (xy 203.100627 -71.039553) (xy 203.076955 -71.09005)
			(xy 203.046182 -71.136563) (xy 203.008965 -71.1781) (xy 202.966097 -71.213775) (xy 202.918491 -71.242829)
			(xy 202.867162 -71.264641) (xy 202.813205 -71.278747) (xy 202.757768 -71.284847) (xy 202.702034 -71.28281)
			(xy 202.647191 -71.27268) (xy 202.594407 -71.254673) (xy 202.544807 -71.229172) (xy 202.499449 -71.196721)
			(xy 202.4593 -71.158012) (xy 202.425214 -71.113869) (xy 202.397918 -71.065234) (xy 202.377995 -71.013143)
			(xy 202.365869 -70.958706) (xy 202.361798 -70.903084) (xy 200.974198 -70.903084) (xy 204.85481 -74.783696)
			(xy 210.387438 -74.783696) (xy 210.402046 -74.783227) (xy 210.43007 -74.774968) (xy 210.454606 -74.759108)
			(xy 210.473644 -74.736947) (xy 210.485625 -74.710301) (xy 210.489565 -74.681352) (xy 210.485144 -74.652473)
			(xy 210.472723 -74.626029) (xy 210.463384 -74.614786) (xy 210.445388 -74.593725) (xy 210.415033 -74.547386)
			(xy 210.391693 -74.497147) (xy 210.375858 -74.444062) (xy 210.367861 -74.389246) (xy 210.367372 -74.361548)
			(xy 210.367858 -74.334297) (xy 210.375614 -74.280349) (xy 210.390969 -74.228054) (xy 210.413611 -74.178477)
			(xy 210.443077 -74.132627) (xy 210.478768 -74.091436) (xy 210.519959 -74.055745) (xy 210.565809 -74.026279)
			(xy 210.615386 -74.003637) (xy 210.667681 -73.988282) (xy 210.721629 -73.980526) (xy 210.776131 -73.980526)
			(xy 210.830079 -73.988282) (xy 210.882374 -74.003637) (xy 210.931951 -74.026279) (xy 210.977801 -74.055745)
			(xy 211.018992 -74.091436) (xy 211.054683 -74.132627) (xy 211.084149 -74.178477) (xy 211.106791 -74.228054)
			(xy 211.122146 -74.280349) (xy 211.129902 -74.334297) (xy 211.130388 -74.361548) (xy 211.129916 -74.389249)
			(xy 211.121945 -74.444074) (xy 211.106119 -74.497167) (xy 211.082771 -74.547409) (xy 211.052395 -74.593741)
			(xy 211.034376 -74.614786) (xy 211.025056 -74.626028) (xy 211.012679 -74.652465) (xy 211.008287 -74.681324)
			(xy 211.01224 -74.710246) (xy 211.024213 -74.736868) (xy 211.04323 -74.759014) (xy 211.067735 -74.774876)
			(xy 211.095727 -74.783156) (xy 211.110322 -74.783696) (xy 211.355178 -74.783696) (xy 211.69503 -74.443844)
			(xy 211.698586 -74.431398) (xy 211.706737 -74.40545) (xy 211.729368 -74.355995) (xy 211.758791 -74.310253)
			(xy 211.794411 -74.269153) (xy 211.835506 -74.233527) (xy 211.881242 -74.204097) (xy 211.930694 -74.181458)
			(xy 211.95665 -74.173334) (xy 211.969096 -74.169778) (xy 212.233002 -73.905872) (xy 216.045542 -73.905872)
			(xy 217.336624 -75.196954) (xy 222.45777 -75.196954) (xy 222.461841 -75.141332) (xy 222.473967 -75.086895)
			(xy 222.49389 -75.034804) (xy 222.521186 -74.986169) (xy 222.555272 -74.942026) (xy 222.595421 -74.903317)
			(xy 222.640779 -74.870866) (xy 222.690379 -74.845365) (xy 222.743163 -74.827358) (xy 222.798006 -74.817228)
			(xy 222.85374 -74.815191) (xy 222.909177 -74.821291) (xy 222.963134 -74.835397) (xy 223.014463 -74.857209)
			(xy 223.062069 -74.886263) (xy 223.104937 -74.921938) (xy 223.142154 -74.963475) (xy 223.172927 -75.009988)
			(xy 223.196599 -75.060485) (xy 223.212667 -75.113892) (xy 223.220787 -75.169068) (xy 223.221296 -75.196954)
			(xy 223.220787 -75.22484) (xy 223.212667 -75.280016) (xy 223.196599 -75.333423) (xy 223.172927 -75.38392)
			(xy 223.142154 -75.430433) (xy 223.104937 -75.47197) (xy 223.062069 -75.507645) (xy 223.014463 -75.536699)
			(xy 222.963134 -75.558511) (xy 222.909177 -75.572617) (xy 222.85374 -75.578717) (xy 222.798006 -75.57668)
			(xy 222.743163 -75.56655) (xy 222.690379 -75.548543) (xy 222.640779 -75.523042) (xy 222.595421 -75.490591)
			(xy 222.555272 -75.451882) (xy 222.521186 -75.407739) (xy 222.49389 -75.359104) (xy 222.473967 -75.307013)
			(xy 222.461841 -75.252576) (xy 222.45777 -75.196954) (xy 217.336624 -75.196954) (xy 219.391738 -77.252068)
			(xy 219.391738 -77.937868) (xy 223.09455 -77.937868)
		)
		(stroke
			(width 0)
			(type solid)
		)
		(fill yes)
		(layer "In4.Cu")
		(net "P3V3_AUX")
	)
	(gr_poly
		(pts
			(xy 446.290954 -335.06537) (xy 446.304469 -335.064955) (xy 446.330552 -335.057871) (xy 446.353861 -335.044187)
			(xy 446.372761 -335.024865) (xy 446.385924 -335.001258) (xy 446.392428 -334.975024) (xy 446.391817 -334.948002)
			(xy 446.384133 -334.922088) (xy 446.369916 -334.899101) (xy 446.360296 -334.889602) (xy 446.341654 -334.871498)
			(xy 446.308948 -334.831117) (xy 446.282024 -334.786672) (xy 446.26138 -334.738984) (xy 446.247398 -334.688936)
			(xy 446.240336 -334.637454) (xy 446.2399 -334.611472) (xy 446.240386 -334.584221) (xy 446.248142 -334.530273)
			(xy 446.263497 -334.477978) (xy 446.286139 -334.428401) (xy 446.315605 -334.382551) (xy 446.351296 -334.34136)
			(xy 446.392487 -334.305669) (xy 446.438337 -334.276203) (xy 446.487914 -334.253561) (xy 446.540209 -334.238206)
			(xy 446.594157 -334.23045) (xy 446.648659 -334.23045) (xy 446.702607 -334.238206) (xy 446.754902 -334.253561)
			(xy 446.804479 -334.276203) (xy 446.850329 -334.305669) (xy 446.89152 -334.34136) (xy 446.927211 -334.382551)
			(xy 446.956677 -334.428401) (xy 446.979319 -334.477978) (xy 446.994674 -334.530273) (xy 447.00243 -334.584221)
			(xy 447.002916 -334.611472) (xy 447.002478 -334.637455) (xy 446.995427 -334.68894) (xy 446.98145 -334.738991)
			(xy 446.960808 -334.786681) (xy 446.933881 -334.831127) (xy 446.90117 -334.871506) (xy 446.88252 -334.889602)
			(xy 446.872941 -334.899135) (xy 446.85874 -334.922118) (xy 446.851068 -334.948021) (xy 446.85046 -334.97503)
			(xy 446.85696 -335.001252) (xy 446.870113 -335.02485) (xy 446.888997 -335.04417) (xy 446.912288 -335.057859)
			(xy 446.938354 -335.064957) (xy 446.951862 -335.06537) (xy 455.601578 -335.06537) (xy 455.985118 -334.68183)
			(xy 455.985118 -323.867018) (xy 455.984679 -323.853444) (xy 455.97751 -323.827258) (xy 455.963698 -323.803885)
			(xy 455.94422 -323.784972) (xy 455.920449 -323.771856) (xy 455.894064 -323.765462) (xy 455.866925 -323.766241)
			(xy 455.8538 -323.769736) (xy 455.828261 -323.777073) (xy 455.775719 -323.784981) (xy 455.749152 -323.785484)
			(xy 455.722507 -323.784983) (xy 455.669813 -323.777034) (xy 455.618892 -323.76132) (xy 455.570881 -323.738194)
			(xy 455.526853 -323.708171) (xy 455.487791 -323.671921) (xy 455.454567 -323.630255) (xy 455.427924 -323.584103)
			(xy 455.408456 -323.534496) (xy 455.396599 -323.482541) (xy 455.392617 -323.4294) (xy 455.396599 -323.376259)
			(xy 455.408456 -323.324304) (xy 455.427924 -323.274697) (xy 455.454567 -323.228545) (xy 455.487791 -323.186879)
			(xy 455.526853 -323.150629) (xy 455.570881 -323.120606) (xy 455.618892 -323.09748) (xy 455.669813 -323.081766)
			(xy 455.722507 -323.073817) (xy 455.749152 -323.073268) (xy 455.77572 -323.07376) (xy 455.828262 -323.081672)
			(xy 455.8538 -323.089016) (xy 455.866915 -323.092576) (xy 455.894068 -323.093385) (xy 455.920472 -323.086999)
			(xy 455.944255 -323.073873) (xy 455.963732 -323.054936) (xy 455.977522 -323.031532) (xy 455.984647 -323.005317)
			(xy 455.985118 -322.991734) (xy 455.985118 -320.74993) (xy 455.477372 -320.242184) (xy 450.840856 -320.242184)
			(xy 450.825717 -320.242701) (xy 450.796751 -320.251507) (xy 450.771641 -320.268421) (xy 450.752595 -320.291956)
			(xy 450.74129 -320.320041) (xy 450.738718 -320.350207) (xy 450.745106 -320.3798) (xy 450.751956 -320.393314)
			(xy 450.766176 -320.419993) (xy 450.786325 -320.476988) (xy 450.796547 -320.53657) (xy 450.797168 -320.566796)
			(xy 450.79667 -320.593445) (xy 450.788727 -320.646149) (xy 450.773017 -320.697079) (xy 450.749891 -320.7451)
			(xy 450.719867 -320.789137) (xy 450.683615 -320.828208) (xy 450.641944 -320.861439) (xy 450.595786 -320.888088)
			(xy 450.546172 -320.90756) (xy 450.49421 -320.91942) (xy 450.44106 -320.923404) (xy 450.38791 -320.91942)
			(xy 450.335948 -320.90756) (xy 450.286334 -320.888088) (xy 450.240176 -320.861439) (xy 450.198505 -320.828208)
			(xy 450.162253 -320.789137) (xy 450.132229 -320.7451) (xy 450.109103 -320.697079) (xy 450.093393 -320.646149)
			(xy 450.08545 -320.593445) (xy 450.084952 -320.566796) (xy 450.085613 -320.536574) (xy 450.09585 -320.477003)
			(xy 450.11598 -320.420008) (xy 450.130164 -320.393314) (xy 450.137059 -320.37983) (xy 450.143423 -320.350237)
			(xy 450.140833 -320.320078) (xy 450.129517 -320.292004) (xy 450.110468 -320.26848) (xy 450.085361 -320.251572)
			(xy 450.0564 -320.242767) (xy 450.041264 -320.242184) (xy 443.302136 -320.242184) (xy 443.286988 -320.24269)
			(xy 443.258 -320.251483) (xy 443.232868 -320.268395) (xy 443.213805 -320.291938) (xy 443.20249 -320.320037)
			(xy 443.199918 -320.35022) (xy 443.206317 -320.379829) (xy 443.213236 -320.393314) (xy 443.227456 -320.419993)
			(xy 443.247607 -320.476988) (xy 443.25783 -320.53657) (xy 443.258448 -320.566796) (xy 443.25795 -320.593445)
			(xy 443.250007 -320.646149) (xy 443.234297 -320.697079) (xy 443.211171 -320.7451) (xy 443.181147 -320.789137)
			(xy 443.144895 -320.828208) (xy 443.103224 -320.861439) (xy 443.057066 -320.888088) (xy 443.007452 -320.90756)
			(xy 442.95549 -320.91942) (xy 442.90234 -320.923404) (xy 442.84919 -320.91942) (xy 442.797228 -320.90756)
			(xy 442.747614 -320.888088) (xy 442.701456 -320.861439) (xy 442.659785 -320.828208) (xy 442.623533 -320.789137)
			(xy 442.593509 -320.7451) (xy 442.570383 -320.697079) (xy 442.554673 -320.646149) (xy 442.54673 -320.593445)
			(xy 442.546232 -320.566796) (xy 442.546893 -320.536574) (xy 442.557132 -320.477004) (xy 442.577266 -320.420011)
			(xy 442.591444 -320.393314) (xy 442.598336 -320.379826) (xy 442.604694 -320.350228) (xy 442.602102 -320.320065)
			(xy 442.590788 -320.291986) (xy 442.571743 -320.268453) (xy 442.54664 -320.251532) (xy 442.517682 -320.242708)
			(xy 442.502544 -320.242184) (xy 435.738016 -320.242184) (xy 435.72287 -320.242693) (xy 435.693888 -320.251489)
			(xy 435.668761 -320.268402) (xy 435.649703 -320.291942) (xy 435.63839 -320.320038) (xy 435.635818 -320.350217)
			(xy 435.642214 -320.379822) (xy 435.649116 -320.393314) (xy 435.663337 -320.419993) (xy 435.683489 -320.476988)
			(xy 435.693712 -320.53657) (xy 435.694328 -320.566796) (xy 435.69383 -320.593445) (xy 435.685887 -320.646149)
			(xy 435.670177 -320.697079) (xy 435.647051 -320.7451) (xy 435.617027 -320.789137) (xy 435.580775 -320.828208)
			(xy 435.539104 -320.861439) (xy 435.492946 -320.888088) (xy 435.443332 -320.90756) (xy 435.39137 -320.91942)
			(xy 435.33822 -320.923404) (xy 435.28507 -320.91942) (xy 435.233108 -320.90756) (xy 435.183494 -320.888088)
			(xy 435.137336 -320.861439) (xy 435.095665 -320.828208) (xy 435.059413 -320.789137) (xy 435.029389 -320.7451)
			(xy 435.006263 -320.697079) (xy 434.990553 -320.646149) (xy 434.98261 -320.593445) (xy 434.982112 -320.566796)
			(xy 434.982773 -320.536574) (xy 434.993012 -320.477003) (xy 435.013144 -320.420011) (xy 435.027324 -320.393314)
			(xy 435.034217 -320.379827) (xy 435.040577 -320.35023) (xy 435.037985 -320.320069) (xy 435.02667 -320.29199)
			(xy 435.007625 -320.26846) (xy 434.98252 -320.251542) (xy 434.953561 -320.242722) (xy 434.938424 -320.242184)
			(xy 421.006524 -320.242184) (xy 420.993316 -320.272664) (xy 420.981735 -320.297713) (xy 420.951995 -320.344197)
			(xy 420.915442 -320.385537) (xy 420.87295 -320.420745) (xy 420.825535 -320.448977) (xy 420.774334 -320.469559)
			(xy 420.72057 -320.481996) (xy 420.693088 -320.4845) (xy 420.679847 -320.485941) (xy 420.654722 -320.494754)
			(xy 420.63273 -320.50976) (xy 420.615363 -320.529942) (xy 420.603803 -320.553926) (xy 420.598834 -320.580083)
			(xy 420.600796 -320.606636) (xy 420.604696 -320.619374) (xy 420.613941 -320.64776) (xy 420.623895 -320.70662)
			(xy 420.624508 -320.736468) (xy 420.624005 -320.763549) (xy 420.615808 -320.817086) (xy 420.599598 -320.868765)
			(xy 420.57575 -320.917393) (xy 420.544813 -320.96185) (xy 420.5075 -321.001108) (xy 420.464673 -321.034264)
			(xy 420.417319 -321.060552) (xy 420.36653 -321.079366) (xy 420.313478 -321.090272) (xy 420.259387 -321.093018)
			(xy 420.205503 -321.087542) (xy 420.15307 -321.073969) (xy 420.103297 -321.052613) (xy 420.057331 -321.023966)
			(xy 420.016234 -320.988688) (xy 419.980953 -320.947594) (xy 419.952302 -320.901632) (xy 419.930941 -320.851861)
			(xy 419.917364 -320.799429) (xy 419.911883 -320.745545) (xy 419.914624 -320.691453) (xy 419.925526 -320.6384)
			(xy 419.944335 -320.58761) (xy 419.970619 -320.540254) (xy 420.00377 -320.497424) (xy 420.043026 -320.460108)
			(xy 420.087479 -320.429166) (xy 420.136105 -320.405314) (xy 420.187783 -320.389099) (xy 420.241319 -320.380898)
			(xy 420.2684 -320.38036) (xy 420.278455 -320.380441) (xy 420.298533 -320.381587) (xy 420.308532 -320.382646)
			(xy 420.317895 -320.383325) (xy 420.336065 -320.378668) (xy 420.351333 -320.367774) (xy 420.361646 -320.352107)
			(xy 420.365616 -320.333776) (xy 420.36271 -320.315246) (xy 420.358316 -320.306954) (xy 420.353592 -320.298592)
			(xy 420.344952 -320.281437) (xy 420.341044 -320.272664) (xy 420.327836 -320.242184) (xy 413.048196 -320.242184)
			(xy 413.033053 -320.242696) (xy 413.004075 -320.251495) (xy 412.978954 -320.268408) (xy 412.9599 -320.291947)
			(xy 412.94859 -320.320039) (xy 412.946018 -320.350214) (xy 412.952411 -320.379815) (xy 412.959296 -320.393314)
			(xy 412.973514 -320.419994) (xy 412.993661 -320.476989) (xy 413.003883 -320.53657) (xy 413.004508 -320.566796)
			(xy 413.00401 -320.593445) (xy 412.996067 -320.646149) (xy 412.980357 -320.697079) (xy 412.957231 -320.7451)
			(xy 412.927207 -320.789137) (xy 412.890955 -320.828208) (xy 412.849284 -320.861439) (xy 412.803126 -320.888088)
			(xy 412.753512 -320.90756) (xy 412.70155 -320.91942) (xy 412.6484 -320.923404) (xy 412.59525 -320.91942)
			(xy 412.543288 -320.90756) (xy 412.493674 -320.888088) (xy 412.447516 -320.861439) (xy 412.405845 -320.828208)
			(xy 412.369593 -320.789137) (xy 412.339569 -320.7451) (xy 412.316443 -320.697079) (xy 412.300733 -320.646149)
			(xy 412.29279 -320.593445) (xy 412.292292 -320.566796) (xy 412.292953 -320.536574) (xy 412.303191 -320.477003)
			(xy 412.323323 -320.42001) (xy 412.337504 -320.393314) (xy 412.344397 -320.379828) (xy 412.350758 -320.350232)
			(xy 412.348167 -320.320072) (xy 412.336852 -320.291995) (xy 412.317805 -320.268466) (xy 412.2927 -320.251552)
			(xy 412.263741 -320.242737) (xy 412.248604 -320.242184) (xy 408.874214 -320.242184) (xy 408.860908 -320.242627)
			(xy 408.835205 -320.249522) (xy 408.812155 -320.262822) (xy 408.793322 -320.281625) (xy 408.779985 -320.304654)
			(xy 408.773048 -320.330346) (xy 408.772983 -320.356958) (xy 408.775916 -320.369946) (xy 408.78162 -320.392568)
			(xy 408.787737 -320.438821) (xy 408.788108 -320.462148) (xy 408.787555 -320.490129) (xy 408.778794 -320.5454)
			(xy 408.761496 -320.598621) (xy 408.736085 -320.64848) (xy 408.703188 -320.693751) (xy 408.663615 -320.733319)
			(xy 408.618339 -320.76621) (xy 408.568476 -320.791614) (xy 408.515253 -320.808906) (xy 408.459981 -320.817659)
			(xy 408.432 -320.818256) (xy 408.406097 -320.81779) (xy 408.354838 -320.81028) (xy 408.305209 -320.795418)
			(xy 408.258259 -320.77352) (xy 408.214979 -320.745046) (xy 408.176284 -320.7106) (xy 408.142991 -320.670908)
			(xy 408.115803 -320.626809) (xy 408.095295 -320.579235) (xy 408.088084 -320.55435) (xy 408.083594 -320.539799)
			(xy 408.067401 -320.514029) (xy 408.044339 -320.494168) (xy 408.016453 -320.481976) (xy 407.986213 -320.478534)
			(xy 407.9563 -320.484147) (xy 407.929364 -320.498317) (xy 407.918158 -320.50863) (xy 407.768298 -320.65849)
			(xy 407.768298 -321.161897) (xy 427.25339 -321.161897) (xy 427.25339 -321.108599) (xy 427.261333 -321.055895)
			(xy 427.277043 -321.004965) (xy 427.300169 -320.956944) (xy 427.330193 -320.912907) (xy 427.366445 -320.873836)
			(xy 427.408116 -320.840605) (xy 427.454274 -320.813956) (xy 427.503888 -320.794484) (xy 427.55585 -320.782624)
			(xy 427.609 -320.778641) (xy 427.66215 -320.782624) (xy 427.714112 -320.794484) (xy 427.763726 -320.813956)
			(xy 427.809884 -320.840605) (xy 427.851555 -320.873836) (xy 427.887807 -320.912907) (xy 427.917831 -320.956944)
			(xy 427.940957 -321.004965) (xy 427.956667 -321.055895) (xy 427.95733 -321.060297) (xy 431.19801 -321.060297)
			(xy 431.19801 -321.006999) (xy 431.205953 -320.954295) (xy 431.221663 -320.903365) (xy 431.244789 -320.855344)
			(xy 431.274813 -320.811307) (xy 431.311065 -320.772236) (xy 431.352736 -320.739005) (xy 431.398894 -320.712356)
			(xy 431.448508 -320.692884) (xy 431.50047 -320.681024) (xy 431.55362 -320.677041) (xy 431.60677 -320.681024)
			(xy 431.658732 -320.692884) (xy 431.708346 -320.712356) (xy 431.754504 -320.739005) (xy 431.796175 -320.772236)
			(xy 431.832427 -320.811307) (xy 431.862451 -320.855344) (xy 431.885577 -320.903365) (xy 431.901287 -320.954295)
			(xy 431.90923 -321.006999) (xy 431.909728 -321.033648) (xy 431.90923 -321.060297) (xy 431.901287 -321.113001)
			(xy 431.885577 -321.163931) (xy 431.862451 -321.211952) (xy 431.860211 -321.215237) (xy 453.88783 -321.215237)
			(xy 453.88783 -321.161939) (xy 453.895773 -321.109235) (xy 453.911483 -321.058305) (xy 453.934609 -321.010284)
			(xy 453.964633 -320.966247) (xy 454.000885 -320.927176) (xy 454.042556 -320.893945) (xy 454.088714 -320.867296)
			(xy 454.138328 -320.847824) (xy 454.19029 -320.835964) (xy 454.24344 -320.831981) (xy 454.29659 -320.835964)
			(xy 454.348552 -320.847824) (xy 454.398166 -320.867296) (xy 454.444324 -320.893945) (xy 454.485995 -320.927176)
			(xy 454.522247 -320.966247) (xy 454.552271 -321.010284) (xy 454.575397 -321.058305) (xy 454.591107 -321.109235)
			(xy 454.59905 -321.161939) (xy 454.599548 -321.188588) (xy 454.59905 -321.215237) (xy 454.591107 -321.267941)
			(xy 454.575397 -321.318871) (xy 454.552271 -321.366892) (xy 454.522247 -321.410929) (xy 454.485995 -321.45)
			(xy 454.444324 -321.483231) (xy 454.398166 -321.50988) (xy 454.348552 -321.529352) (xy 454.29659 -321.541212)
			(xy 454.24344 -321.545196) (xy 454.19029 -321.541212) (xy 454.138328 -321.529352) (xy 454.088714 -321.50988)
			(xy 454.042556 -321.483231) (xy 454.000885 -321.45) (xy 453.964633 -321.410929) (xy 453.934609 -321.366892)
			(xy 453.911483 -321.318871) (xy 453.895773 -321.267941) (xy 453.88783 -321.215237) (xy 431.860211 -321.215237)
			(xy 431.832427 -321.255989) (xy 431.796175 -321.29506) (xy 431.754504 -321.328291) (xy 431.708346 -321.35494)
			(xy 431.658732 -321.374412) (xy 431.60677 -321.386272) (xy 431.55362 -321.390256) (xy 431.50047 -321.386272)
			(xy 431.448508 -321.374412) (xy 431.398894 -321.35494) (xy 431.352736 -321.328291) (xy 431.311065 -321.29506)
			(xy 431.274813 -321.255989) (xy 431.244789 -321.211952) (xy 431.221663 -321.163931) (xy 431.205953 -321.113001)
			(xy 431.19801 -321.060297) (xy 427.95733 -321.060297) (xy 427.96461 -321.108599) (xy 427.965108 -321.135248)
			(xy 427.96461 -321.161897) (xy 427.956667 -321.214601) (xy 427.940957 -321.265531) (xy 427.917831 -321.313552)
			(xy 427.887807 -321.357589) (xy 427.851555 -321.39666) (xy 427.809884 -321.429891) (xy 427.763726 -321.45654)
			(xy 427.714112 -321.476012) (xy 427.66215 -321.487872) (xy 427.609 -321.491856) (xy 427.55585 -321.487872)
			(xy 427.503888 -321.476012) (xy 427.454274 -321.45654) (xy 427.408116 -321.429891) (xy 427.366445 -321.39666)
			(xy 427.330193 -321.357589) (xy 427.300169 -321.313552) (xy 427.277043 -321.265531) (xy 427.261333 -321.214601)
			(xy 427.25339 -321.161897) (xy 407.768298 -321.161897) (xy 407.768298 -321.56273) (xy 407.990781 -321.785213)
			(xy 412.579556 -321.785213) (xy 412.579556 -321.731915) (xy 412.587499 -321.679211) (xy 412.603209 -321.628281)
			(xy 412.626335 -321.58026) (xy 412.656359 -321.536223) (xy 412.692611 -321.497152) (xy 412.734282 -321.463921)
			(xy 412.78044 -321.437272) (xy 412.830054 -321.4178) (xy 412.882016 -321.40594) (xy 412.935166 -321.401957)
			(xy 412.988316 -321.40594) (xy 413.040278 -321.4178) (xy 413.089892 -321.437272) (xy 413.13605 -321.463921)
			(xy 413.177721 -321.497152) (xy 413.213973 -321.536223) (xy 413.243997 -321.58026) (xy 413.267123 -321.628281)
			(xy 413.282833 -321.679211) (xy 413.290776 -321.731915) (xy 413.291274 -321.758564) (xy 413.290776 -321.785213)
			(xy 413.282833 -321.837917) (xy 413.267123 -321.888847) (xy 413.243997 -321.936868) (xy 413.213973 -321.980905)
			(xy 413.177721 -322.019976) (xy 413.13605 -322.053207) (xy 413.089892 -322.079856) (xy 413.040278 -322.099328)
			(xy 412.988316 -322.111188) (xy 412.935166 -322.115172) (xy 412.882016 -322.111188) (xy 412.830054 -322.099328)
			(xy 412.78044 -322.079856) (xy 412.734282 -322.053207) (xy 412.692611 -322.019976) (xy 412.656359 -321.980905)
			(xy 412.626335 -321.936868) (xy 412.603209 -321.888847) (xy 412.587499 -321.837917) (xy 412.579556 -321.785213)
			(xy 407.990781 -321.785213) (xy 408.575317 -322.369749) (xy 415.741388 -322.369749) (xy 415.741388 -322.315251)
			(xy 415.749143 -322.261309) (xy 415.764496 -322.209019) (xy 415.787133 -322.159446) (xy 415.816595 -322.113599)
			(xy 415.852281 -322.072411) (xy 415.893465 -322.03672) (xy 415.939309 -322.007254) (xy 415.988879 -321.984611)
			(xy 416.041168 -321.969252) (xy 416.095109 -321.961491) (xy 416.122358 -321.961002) (xy 416.149857 -321.961476)
			(xy 416.204285 -321.969388) (xy 416.257014 -321.985025) (xy 416.306955 -322.008064) (xy 416.353075 -322.038029)
			(xy 416.394419 -322.0743) (xy 416.430133 -322.116126) (xy 416.459478 -322.162642) (xy 416.4711 -322.18757)
			(xy 416.476995 -322.199647) (xy 416.493947 -322.220485) (xy 416.515741 -322.236189) (xy 416.540873 -322.245674)
			(xy 416.567608 -322.248287) (xy 416.594101 -322.243847) (xy 416.606482 -322.238624) (xy 416.63165 -322.227563)
			(xy 416.684358 -322.211948) (xy 416.738762 -322.204055) (xy 416.766248 -322.203572) (xy 416.793496 -322.204102)
			(xy 416.847435 -322.211863) (xy 416.899721 -322.227222) (xy 416.94929 -322.249864) (xy 416.995132 -322.27933)
			(xy 417.036314 -322.31502) (xy 417.071999 -322.356207) (xy 417.101459 -322.402052) (xy 417.124095 -322.451624)
			(xy 417.139447 -322.503912) (xy 417.147202 -322.557852) (xy 417.147202 -322.612348) (xy 417.139447 -322.666288)
			(xy 417.124095 -322.718576) (xy 417.101459 -322.768148) (xy 417.071999 -322.813993) (xy 417.036314 -322.85518)
			(xy 416.995132 -322.89087) (xy 416.94929 -322.920336) (xy 416.899721 -322.942978) (xy 416.847435 -322.958337)
			(xy 416.793496 -322.966098) (xy 416.766248 -322.966588) (xy 416.738748 -322.966115) (xy 416.684321 -322.958204)
			(xy 416.631591 -322.942567) (xy 416.58165 -322.919527) (xy 416.53553 -322.889562) (xy 416.494186 -322.853292)
			(xy 416.458472 -322.811465) (xy 416.429128 -322.764948) (xy 416.417506 -322.74002) (xy 416.411719 -322.727884)
			(xy 416.394745 -322.707041) (xy 416.372927 -322.691339) (xy 416.347772 -322.681863) (xy 416.321017 -322.679267)
			(xy 416.294509 -322.68373) (xy 416.282124 -322.688966) (xy 416.256955 -322.700024) (xy 416.204247 -322.715641)
			(xy 416.149844 -322.723535) (xy 416.122358 -322.724018) (xy 416.095109 -322.723509) (xy 416.041168 -322.715748)
			(xy 415.988879 -322.700389) (xy 415.939309 -322.677746) (xy 415.893465 -322.64828) (xy 415.852281 -322.612589)
			(xy 415.816595 -322.571401) (xy 415.787133 -322.525554) (xy 415.764496 -322.475981) (xy 415.749143 -322.423691)
			(xy 415.741388 -322.369749) (xy 408.575317 -322.369749) (xy 409.634968 -323.4294) (xy 410.129768 -323.4294)
			(xy 410.133751 -323.376251) (xy 410.14561 -323.32429) (xy 410.16508 -323.274676) (xy 410.191727 -323.228517)
			(xy 410.224955 -323.186846) (xy 410.264022 -323.150591) (xy 410.308056 -323.120564) (xy 410.356074 -323.097434)
			(xy 410.407002 -323.081719) (xy 410.459703 -323.073769) (xy 410.486352 -323.073268) (xy 410.512759 -323.07379)
			(xy 410.564995 -323.081584) (xy 410.615507 -323.097008) (xy 410.663187 -323.119723) (xy 410.706988 -323.149232)
			(xy 410.745951 -323.184887) (xy 410.762958 -323.205094) (xy 410.772895 -323.216487) (xy 410.797948 -323.233378)
			(xy 410.826844 -323.242209) (xy 410.85706 -323.242209) (xy 410.885956 -323.233378) (xy 410.911009 -323.216487)
			(xy 410.920946 -323.205094) (xy 410.937972 -323.184902) (xy 410.976929 -323.149239) (xy 411.020725 -323.119721)
			(xy 411.0684 -323.096994) (xy 411.11891 -323.081558) (xy 411.171144 -323.073751) (xy 411.197552 -323.073268)
			(xy 411.224204 -323.073786) (xy 411.276913 -323.081724) (xy 411.327849 -323.09743) (xy 411.375876 -323.120552)
			(xy 411.41992 -323.150576) (xy 411.458997 -323.186828) (xy 411.492233 -323.2285) (xy 411.518887 -323.274661)
			(xy 411.538362 -323.324279) (xy 411.550224 -323.376246) (xy 411.554208 -323.4294) (xy 413.609568 -323.4294)
			(xy 413.613551 -323.376251) (xy 413.62541 -323.32429) (xy 413.64488 -323.274676) (xy 413.671527 -323.228517)
			(xy 413.704755 -323.186846) (xy 413.743822 -323.150591) (xy 413.787856 -323.120564) (xy 413.835874 -323.097434)
			(xy 413.886802 -323.081719) (xy 413.939503 -323.073769) (xy 413.966152 -323.073268) (xy 413.992559 -323.07379)
			(xy 414.044795 -323.081584) (xy 414.095307 -323.097008) (xy 414.142987 -323.119723) (xy 414.186788 -323.149232)
			(xy 414.225751 -323.184887) (xy 414.242758 -323.205094) (xy 414.252695 -323.216487) (xy 414.277748 -323.233378)
			(xy 414.306644 -323.242209) (xy 414.33686 -323.242209) (xy 414.365756 -323.233378) (xy 414.390809 -323.216487)
			(xy 414.400746 -323.205094) (xy 414.417772 -323.184902) (xy 414.456729 -323.149239) (xy 414.500525 -323.119721)
			(xy 414.5482 -323.096994) (xy 414.59871 -323.081558) (xy 414.650944 -323.073751) (xy 414.677352 -323.073268)
			(xy 414.704004 -323.073786) (xy 414.756713 -323.081724) (xy 414.807649 -323.09743) (xy 414.855676 -323.120552)
			(xy 414.89972 -323.150576) (xy 414.938797 -323.186828) (xy 414.972033 -323.2285) (xy 414.998687 -323.274661)
			(xy 415.018162 -323.324279) (xy 415.030024 -323.376246) (xy 415.034008 -323.4294) (xy 417.673568 -323.4294)
			(xy 417.677551 -323.376251) (xy 417.68941 -323.32429) (xy 417.70888 -323.274676) (xy 417.735527 -323.228517)
			(xy 417.768755 -323.186846) (xy 417.807822 -323.150591) (xy 417.851856 -323.120564) (xy 417.899874 -323.097434)
			(xy 417.950802 -323.081719) (xy 418.003503 -323.073769) (xy 418.030152 -323.073268) (xy 418.056559 -323.07379)
			(xy 418.108795 -323.081584) (xy 418.159307 -323.097008) (xy 418.206987 -323.119723) (xy 418.250788 -323.149232)
			(xy 418.289751 -323.184887) (xy 418.306758 -323.205094) (xy 418.316695 -323.216487) (xy 418.341748 -323.233378)
			(xy 418.370644 -323.242209) (xy 418.40086 -323.242209) (xy 418.429756 -323.233378) (xy 418.454809 -323.216487)
			(xy 418.464746 -323.205094) (xy 418.481772 -323.184902) (xy 418.520729 -323.149239) (xy 418.564525 -323.119721)
			(xy 418.6122 -323.096994) (xy 418.66271 -323.081558) (xy 418.714944 -323.073751) (xy 418.741352 -323.073268)
			(xy 418.768004 -323.073786) (xy 418.820713 -323.081724) (xy 418.871649 -323.09743) (xy 418.919676 -323.120552)
			(xy 418.96372 -323.150576) (xy 419.002797 -323.186828) (xy 419.036033 -323.2285) (xy 419.062687 -323.274661)
			(xy 419.082162 -323.324279) (xy 419.094024 -323.376246) (xy 419.098008 -323.4294) (xy 421.153368 -323.4294)
			(xy 421.157351 -323.376251) (xy 421.16921 -323.32429) (xy 421.18868 -323.274676) (xy 421.215327 -323.228517)
			(xy 421.248555 -323.186846) (xy 421.287622 -323.150591) (xy 421.331656 -323.120564) (xy 421.379674 -323.097434)
			(xy 421.430602 -323.081719) (xy 421.483303 -323.073769) (xy 421.509952 -323.073268) (xy 421.536359 -323.07379)
			(xy 421.588595 -323.081584) (xy 421.639107 -323.097008) (xy 421.686787 -323.119723) (xy 421.730588 -323.149232)
			(xy 421.769551 -323.184887) (xy 421.786558 -323.205094) (xy 421.796495 -323.216487) (xy 421.821548 -323.233378)
			(xy 421.850444 -323.242209) (xy 421.88066 -323.242209) (xy 421.909556 -323.233378) (xy 421.934609 -323.216487)
			(xy 421.944546 -323.205094) (xy 421.961572 -323.184902) (xy 422.000529 -323.149239) (xy 422.044325 -323.119721)
			(xy 422.092 -323.096994) (xy 422.14251 -323.081558) (xy 422.194744 -323.073751) (xy 422.221152 -323.073268)
			(xy 422.247804 -323.073786) (xy 422.300513 -323.081724) (xy 422.351449 -323.09743) (xy 422.399476 -323.120552)
			(xy 422.44352 -323.150576) (xy 422.482597 -323.186828) (xy 422.515833 -323.2285) (xy 422.542487 -323.274661)
			(xy 422.561962 -323.324279) (xy 422.573824 -323.376246) (xy 422.577808 -323.4294) (xy 425.217368 -323.4294)
			(xy 425.221351 -323.376251) (xy 425.23321 -323.32429) (xy 425.25268 -323.274676) (xy 425.279327 -323.228517)
			(xy 425.312555 -323.186846) (xy 425.351622 -323.150591) (xy 425.395656 -323.120564) (xy 425.443674 -323.097434)
			(xy 425.494602 -323.081719) (xy 425.547303 -323.073769) (xy 425.573952 -323.073268) (xy 425.600359 -323.07379)
			(xy 425.652595 -323.081584) (xy 425.703107 -323.097008) (xy 425.750787 -323.119723) (xy 425.794588 -323.149232)
			(xy 425.833551 -323.184887) (xy 425.850558 -323.205094) (xy 425.860495 -323.216487) (xy 425.885548 -323.233378)
			(xy 425.914444 -323.242209) (xy 425.94466 -323.242209) (xy 425.973556 -323.233378) (xy 425.998609 -323.216487)
			(xy 426.008546 -323.205094) (xy 426.025572 -323.184902) (xy 426.064529 -323.149239) (xy 426.108325 -323.119721)
			(xy 426.156 -323.096994) (xy 426.20651 -323.081558) (xy 426.258744 -323.073751) (xy 426.285152 -323.073268)
			(xy 426.311804 -323.073786) (xy 426.364513 -323.081724) (xy 426.415449 -323.09743) (xy 426.463476 -323.120552)
			(xy 426.50752 -323.150576) (xy 426.546597 -323.186828) (xy 426.579833 -323.2285) (xy 426.606487 -323.274661)
			(xy 426.625962 -323.324279) (xy 426.637824 -323.376246) (xy 426.641808 -323.4294) (xy 428.697168 -323.4294)
			(xy 428.701151 -323.376251) (xy 428.71301 -323.32429) (xy 428.73248 -323.274676) (xy 428.759127 -323.228517)
			(xy 428.792355 -323.186846) (xy 428.831422 -323.150591) (xy 428.875456 -323.120564) (xy 428.923474 -323.097434)
			(xy 428.974402 -323.081719) (xy 429.027103 -323.073769) (xy 429.053752 -323.073268) (xy 429.080159 -323.07379)
			(xy 429.132395 -323.081584) (xy 429.182907 -323.097008) (xy 429.230587 -323.119723) (xy 429.274388 -323.149232)
			(xy 429.313351 -323.184887) (xy 429.330358 -323.205094) (xy 429.340295 -323.216487) (xy 429.365348 -323.233378)
			(xy 429.394244 -323.242209) (xy 429.42446 -323.242209) (xy 429.453356 -323.233378) (xy 429.478409 -323.216487)
			(xy 429.488346 -323.205094) (xy 429.505372 -323.184902) (xy 429.544329 -323.149239) (xy 429.588125 -323.119721)
			(xy 429.6358 -323.096994) (xy 429.68631 -323.081558) (xy 429.738544 -323.073751) (xy 429.764952 -323.073268)
			(xy 429.791604 -323.073786) (xy 429.844313 -323.081724) (xy 429.895249 -323.09743) (xy 429.943276 -323.120552)
			(xy 429.98732 -323.150576) (xy 430.026397 -323.186828) (xy 430.059633 -323.2285) (xy 430.086287 -323.274661)
			(xy 430.105762 -323.324279) (xy 430.117624 -323.376246) (xy 430.121608 -323.4294) (xy 432.761168 -323.4294)
			(xy 432.765151 -323.376251) (xy 432.77701 -323.32429) (xy 432.79648 -323.274676) (xy 432.823127 -323.228517)
			(xy 432.856355 -323.186846) (xy 432.895422 -323.150591) (xy 432.939456 -323.120564) (xy 432.987474 -323.097434)
			(xy 433.038402 -323.081719) (xy 433.091103 -323.073769) (xy 433.117752 -323.073268) (xy 433.144314 -323.073727)
			(xy 433.196845 -323.081638) (xy 433.24762 -323.097261) (xy 433.295512 -323.12025) (xy 433.339459 -323.150096)
			(xy 433.359306 -323.167756) (xy 433.370108 -323.177123) (xy 433.395674 -323.189907) (xy 433.423782 -323.195102)
			(xy 433.452228 -323.192301) (xy 433.478783 -323.181724) (xy 433.49037 -323.173344) (xy 433.513938 -323.155803)
			(xy 433.565646 -323.127918) (xy 433.62123 -323.1089) (xy 433.679182 -323.099265) (xy 433.708556 -323.098668)
			(xy 433.735208 -323.099186) (xy 433.787916 -323.107125) (xy 433.838852 -323.122831) (xy 433.886879 -323.145954)
			(xy 433.930922 -323.175977) (xy 433.969998 -323.21223) (xy 434.003234 -323.253902) (xy 434.029887 -323.300062)
			(xy 434.049362 -323.34968) (xy 434.061224 -323.401646) (xy 434.063304 -323.4294) (xy 436.240968 -323.4294)
			(xy 436.244951 -323.376251) (xy 436.25681 -323.32429) (xy 436.27628 -323.274676) (xy 436.302927 -323.228517)
			(xy 436.336155 -323.186846) (xy 436.375222 -323.150591) (xy 436.419256 -323.120564) (xy 436.467274 -323.097434)
			(xy 436.518202 -323.081719) (xy 436.570903 -323.073769) (xy 436.597552 -323.073268) (xy 436.623959 -323.07379)
			(xy 436.676195 -323.081584) (xy 436.726707 -323.097008) (xy 436.774387 -323.119723) (xy 436.818188 -323.149232)
			(xy 436.857151 -323.184887) (xy 436.874158 -323.205094) (xy 436.884095 -323.216487) (xy 436.909148 -323.233378)
			(xy 436.938044 -323.242209) (xy 436.96826 -323.242209) (xy 436.997156 -323.233378) (xy 437.022209 -323.216487)
			(xy 437.032146 -323.205094) (xy 437.049172 -323.184902) (xy 437.088129 -323.149239) (xy 437.131925 -323.119721)
			(xy 437.1796 -323.096994) (xy 437.23011 -323.081558) (xy 437.282344 -323.073751) (xy 437.308752 -323.073268)
			(xy 437.335404 -323.073786) (xy 437.388113 -323.081724) (xy 437.439049 -323.09743) (xy 437.487076 -323.120552)
			(xy 437.53112 -323.150576) (xy 437.570197 -323.186828) (xy 437.603433 -323.2285) (xy 437.630087 -323.274661)
			(xy 437.649562 -323.324279) (xy 437.661424 -323.376246) (xy 437.665408 -323.4294) (xy 440.304968 -323.4294)
			(xy 440.308951 -323.376251) (xy 440.32081 -323.32429) (xy 440.34028 -323.274676) (xy 440.366927 -323.228517)
			(xy 440.400155 -323.186846) (xy 440.439222 -323.150591) (xy 440.483256 -323.120564) (xy 440.531274 -323.097434)
			(xy 440.582202 -323.081719) (xy 440.634903 -323.073769) (xy 440.661552 -323.073268) (xy 440.687959 -323.07379)
			(xy 440.740195 -323.081584) (xy 440.790707 -323.097008) (xy 440.838387 -323.119723) (xy 440.882188 -323.149232)
			(xy 440.921151 -323.184887) (xy 440.938158 -323.205094) (xy 440.948095 -323.216487) (xy 440.973148 -323.233378)
			(xy 441.002044 -323.242209) (xy 441.03226 -323.242209) (xy 441.061156 -323.233378) (xy 441.086209 -323.216487)
			(xy 441.096146 -323.205094) (xy 441.113172 -323.184902) (xy 441.152129 -323.149239) (xy 441.195925 -323.119721)
			(xy 441.2436 -323.096994) (xy 441.29411 -323.081558) (xy 441.346344 -323.073751) (xy 441.372752 -323.073268)
			(xy 441.399404 -323.073786) (xy 441.452113 -323.081724) (xy 441.503049 -323.09743) (xy 441.551076 -323.120552)
			(xy 441.59512 -323.150576) (xy 441.634197 -323.186828) (xy 441.667433 -323.2285) (xy 441.694087 -323.274661)
			(xy 441.713562 -323.324279) (xy 441.725424 -323.376246) (xy 441.729408 -323.4294) (xy 443.784768 -323.4294)
			(xy 443.788751 -323.376251) (xy 443.80061 -323.32429) (xy 443.82008 -323.274676) (xy 443.846727 -323.228517)
			(xy 443.879955 -323.186846) (xy 443.919022 -323.150591) (xy 443.963056 -323.120564) (xy 444.011074 -323.097434)
			(xy 444.062002 -323.081719) (xy 444.114703 -323.073769) (xy 444.141352 -323.073268) (xy 444.167759 -323.07379)
			(xy 444.219995 -323.081584) (xy 444.270507 -323.097008) (xy 444.318187 -323.119723) (xy 444.361988 -323.149232)
			(xy 444.400951 -323.184887) (xy 444.417958 -323.205094) (xy 444.427895 -323.216487) (xy 444.452948 -323.233378)
			(xy 444.481844 -323.242209) (xy 444.51206 -323.242209) (xy 444.540956 -323.233378) (xy 444.566009 -323.216487)
			(xy 444.575946 -323.205094) (xy 444.592972 -323.184902) (xy 444.631929 -323.149239) (xy 444.675725 -323.119721)
			(xy 444.7234 -323.096994) (xy 444.77391 -323.081558) (xy 444.826144 -323.073751) (xy 444.852552 -323.073268)
			(xy 444.879204 -323.073786) (xy 444.931913 -323.081724) (xy 444.982849 -323.09743) (xy 445.030876 -323.120552)
			(xy 445.07492 -323.150576) (xy 445.113997 -323.186828) (xy 445.147233 -323.2285) (xy 445.173887 -323.274661)
			(xy 445.193362 -323.324279) (xy 445.205224 -323.376246) (xy 445.209208 -323.4294) (xy 447.848768 -323.4294)
			(xy 447.852751 -323.376251) (xy 447.86461 -323.32429) (xy 447.88408 -323.274676) (xy 447.910727 -323.228517)
			(xy 447.943955 -323.186846) (xy 447.983022 -323.150591) (xy 448.027056 -323.120564) (xy 448.075074 -323.097434)
			(xy 448.126002 -323.081719) (xy 448.178703 -323.073769) (xy 448.205352 -323.073268) (xy 448.231759 -323.07379)
			(xy 448.283995 -323.081584) (xy 448.334507 -323.097008) (xy 448.382187 -323.119723) (xy 448.425988 -323.149232)
			(xy 448.464951 -323.184887) (xy 448.481958 -323.205094) (xy 448.491895 -323.216487) (xy 448.516948 -323.233378)
			(xy 448.545844 -323.242209) (xy 448.57606 -323.242209) (xy 448.604956 -323.233378) (xy 448.630009 -323.216487)
			(xy 448.639946 -323.205094) (xy 448.656972 -323.184902) (xy 448.695929 -323.149239) (xy 448.739725 -323.119721)
			(xy 448.7874 -323.096994) (xy 448.83791 -323.081558) (xy 448.890144 -323.073751) (xy 448.916552 -323.073268)
			(xy 448.943204 -323.073786) (xy 448.995913 -323.081724) (xy 449.046849 -323.09743) (xy 449.094876 -323.120552)
			(xy 449.13892 -323.150576) (xy 449.177997 -323.186828) (xy 449.211233 -323.2285) (xy 449.237887 -323.274661)
			(xy 449.257362 -323.324279) (xy 449.269224 -323.376246) (xy 449.273208 -323.4294) (xy 451.328568 -323.4294)
			(xy 451.332551 -323.376251) (xy 451.34441 -323.32429) (xy 451.36388 -323.274676) (xy 451.390527 -323.228517)
			(xy 451.423755 -323.186846) (xy 451.462822 -323.150591) (xy 451.506856 -323.120564) (xy 451.554874 -323.097434)
			(xy 451.605802 -323.081719) (xy 451.658503 -323.073769) (xy 451.685152 -323.073268) (xy 451.711559 -323.07379)
			(xy 451.763795 -323.081584) (xy 451.814307 -323.097008) (xy 451.861987 -323.119723) (xy 451.905788 -323.149232)
			(xy 451.944751 -323.184887) (xy 451.961758 -323.205094) (xy 451.971695 -323.216487) (xy 451.996748 -323.233378)
			(xy 452.025644 -323.242209) (xy 452.05586 -323.242209) (xy 452.084756 -323.233378) (xy 452.109809 -323.216487)
			(xy 452.119746 -323.205094) (xy 452.136772 -323.184902) (xy 452.175729 -323.149239) (xy 452.219525 -323.119721)
			(xy 452.2672 -323.096994) (xy 452.31771 -323.081558) (xy 452.369944 -323.073751) (xy 452.396352 -323.073268)
			(xy 452.423004 -323.073786) (xy 452.475713 -323.081724) (xy 452.526649 -323.09743) (xy 452.574676 -323.120552)
			(xy 452.61872 -323.150576) (xy 452.657797 -323.186828) (xy 452.691033 -323.2285) (xy 452.717687 -323.274661)
			(xy 452.737162 -323.324279) (xy 452.749024 -323.376246) (xy 452.753008 -323.4294) (xy 452.749024 -323.482554)
			(xy 452.737162 -323.534521) (xy 452.717687 -323.584139) (xy 452.691033 -323.6303) (xy 452.657797 -323.671972)
			(xy 452.61872 -323.708224) (xy 452.574676 -323.738248) (xy 452.526649 -323.76137) (xy 452.475713 -323.777076)
			(xy 452.423004 -323.785014) (xy 452.396352 -323.785484) (xy 452.369944 -323.784977) (xy 452.317707 -323.777182)
			(xy 452.267194 -323.761757) (xy 452.219514 -323.739038) (xy 452.175713 -323.709526) (xy 452.136752 -323.673867)
			(xy 452.119746 -323.653658) (xy 452.109809 -323.642265) (xy 452.084756 -323.625374) (xy 452.05586 -323.616543)
			(xy 452.025644 -323.616543) (xy 451.996748 -323.625374) (xy 451.971695 -323.642265) (xy 451.961758 -323.653658)
			(xy 451.944718 -323.673838) (xy 451.905766 -323.709504) (xy 451.861973 -323.739025) (xy 451.8143 -323.761754)
			(xy 451.763792 -323.777192) (xy 451.711559 -323.785) (xy 451.685152 -323.785484) (xy 451.658503 -323.785031)
			(xy 451.605802 -323.777081) (xy 451.554874 -323.761366) (xy 451.506856 -323.738236) (xy 451.462822 -323.708209)
			(xy 451.423755 -323.671954) (xy 451.390527 -323.630283) (xy 451.36388 -323.584124) (xy 451.34441 -323.53451)
			(xy 451.332551 -323.482549) (xy 451.328568 -323.4294) (xy 449.273208 -323.4294) (xy 449.269224 -323.482554)
			(xy 449.257362 -323.534521) (xy 449.237887 -323.584139) (xy 449.211233 -323.6303) (xy 449.177997 -323.671972)
			(xy 449.13892 -323.708224) (xy 449.094876 -323.738248) (xy 449.046849 -323.76137) (xy 448.995913 -323.777076)
			(xy 448.943204 -323.785014) (xy 448.916552 -323.785484) (xy 448.890144 -323.784977) (xy 448.837907 -323.777182)
			(xy 448.787394 -323.761757) (xy 448.739714 -323.739038) (xy 448.695913 -323.709526) (xy 448.656952 -323.673867)
			(xy 448.639946 -323.653658) (xy 448.630009 -323.642265) (xy 448.604956 -323.625374) (xy 448.57606 -323.616543)
			(xy 448.545844 -323.616543) (xy 448.516948 -323.625374) (xy 448.491895 -323.642265) (xy 448.481958 -323.653658)
			(xy 448.464918 -323.673838) (xy 448.425966 -323.709504) (xy 448.382173 -323.739025) (xy 448.3345 -323.761754)
			(xy 448.283992 -323.777192) (xy 448.231759 -323.785) (xy 448.205352 -323.785484) (xy 448.178703 -323.785031)
			(xy 448.126002 -323.777081) (xy 448.075074 -323.761366) (xy 448.027056 -323.738236) (xy 447.983022 -323.708209)
			(xy 447.943955 -323.671954) (xy 447.910727 -323.630283) (xy 447.88408 -323.584124) (xy 447.86461 -323.53451)
			(xy 447.852751 -323.482549) (xy 447.848768 -323.4294) (xy 445.209208 -323.4294) (xy 445.205224 -323.482554)
			(xy 445.193362 -323.534521) (xy 445.173887 -323.584139) (xy 445.147233 -323.6303) (xy 445.113997 -323.671972)
			(xy 445.07492 -323.708224) (xy 445.030876 -323.738248) (xy 444.982849 -323.76137) (xy 444.931913 -323.777076)
			(xy 444.879204 -323.785014) (xy 444.852552 -323.785484) (xy 444.826144 -323.784977) (xy 444.773907 -323.777182)
			(xy 444.723394 -323.761757) (xy 444.675714 -323.739038) (xy 444.631913 -323.709526) (xy 444.592952 -323.673867)
			(xy 444.575946 -323.653658) (xy 444.566009 -323.642265) (xy 444.540956 -323.625374) (xy 444.51206 -323.616543)
			(xy 444.481844 -323.616543) (xy 444.452948 -323.625374) (xy 444.427895 -323.642265) (xy 444.417958 -323.653658)
			(xy 444.400918 -323.673838) (xy 444.361966 -323.709504) (xy 444.318173 -323.739025) (xy 444.2705 -323.761754)
			(xy 444.219992 -323.777192) (xy 444.167759 -323.785) (xy 444.141352 -323.785484) (xy 444.114703 -323.785031)
			(xy 444.062002 -323.777081) (xy 444.011074 -323.761366) (xy 443.963056 -323.738236) (xy 443.919022 -323.708209)
			(xy 443.879955 -323.671954) (xy 443.846727 -323.630283) (xy 443.82008 -323.584124) (xy 443.80061 -323.53451)
			(xy 443.788751 -323.482549) (xy 443.784768 -323.4294) (xy 441.729408 -323.4294) (xy 441.725424 -323.482554)
			(xy 441.713562 -323.534521) (xy 441.694087 -323.584139) (xy 441.667433 -323.6303) (xy 441.634197 -323.671972)
			(xy 441.59512 -323.708224) (xy 441.551076 -323.738248) (xy 441.503049 -323.76137) (xy 441.452113 -323.777076)
			(xy 441.399404 -323.785014) (xy 441.372752 -323.785484) (xy 441.346344 -323.784977) (xy 441.294107 -323.777182)
			(xy 441.243594 -323.761757) (xy 441.195914 -323.739038) (xy 441.152113 -323.709526) (xy 441.113152 -323.673867)
			(xy 441.096146 -323.653658) (xy 441.086209 -323.642265) (xy 441.061156 -323.625374) (xy 441.03226 -323.616543)
			(xy 441.002044 -323.616543) (xy 440.973148 -323.625374) (xy 440.948095 -323.642265) (xy 440.938158 -323.653658)
			(xy 440.921118 -323.673838) (xy 440.882166 -323.709504) (xy 440.838373 -323.739025) (xy 440.7907 -323.761754)
			(xy 440.740192 -323.777192) (xy 440.687959 -323.785) (xy 440.661552 -323.785484) (xy 440.634903 -323.785031)
			(xy 440.582202 -323.777081) (xy 440.531274 -323.761366) (xy 440.483256 -323.738236) (xy 440.439222 -323.708209)
			(xy 440.400155 -323.671954) (xy 440.366927 -323.630283) (xy 440.34028 -323.584124) (xy 440.32081 -323.53451)
			(xy 440.308951 -323.482549) (xy 440.304968 -323.4294) (xy 437.665408 -323.4294) (xy 437.661424 -323.482554)
			(xy 437.649562 -323.534521) (xy 437.630087 -323.584139) (xy 437.603433 -323.6303) (xy 437.570197 -323.671972)
			(xy 437.53112 -323.708224) (xy 437.487076 -323.738248) (xy 437.439049 -323.76137) (xy 437.388113 -323.777076)
			(xy 437.335404 -323.785014) (xy 437.308752 -323.785484) (xy 437.282344 -323.784977) (xy 437.230107 -323.777182)
			(xy 437.179594 -323.761757) (xy 437.131914 -323.739038) (xy 437.088113 -323.709526) (xy 437.049152 -323.673867)
			(xy 437.032146 -323.653658) (xy 437.022209 -323.642265) (xy 436.997156 -323.625374) (xy 436.96826 -323.616543)
			(xy 436.938044 -323.616543) (xy 436.909148 -323.625374) (xy 436.884095 -323.642265) (xy 436.874158 -323.653658)
			(xy 436.857118 -323.673838) (xy 436.818166 -323.709504) (xy 436.774373 -323.739025) (xy 436.7267 -323.761754)
			(xy 436.676192 -323.777192) (xy 436.623959 -323.785) (xy 436.597552 -323.785484) (xy 436.570903 -323.785031)
			(xy 436.518202 -323.777081) (xy 436.467274 -323.761366) (xy 436.419256 -323.738236) (xy 436.375222 -323.708209)
			(xy 436.336155 -323.671954) (xy 436.302927 -323.630283) (xy 436.27628 -323.584124) (xy 436.25681 -323.53451)
			(xy 436.244951 -323.482549) (xy 436.240968 -323.4294) (xy 434.063304 -323.4294) (xy 434.065208 -323.4548)
			(xy 434.061224 -323.507954) (xy 434.049362 -323.55992) (xy 434.029887 -323.609538) (xy 434.003234 -323.655698)
			(xy 433.969998 -323.69737) (xy 433.930922 -323.733623) (xy 433.886879 -323.763646) (xy 433.838852 -323.786769)
			(xy 433.787916 -323.802475) (xy 433.735208 -323.810414) (xy 433.708556 -323.810884) (xy 433.681995 -323.810406)
			(xy 433.629465 -323.802498) (xy 433.578691 -323.786878) (xy 433.530799 -323.763894) (xy 433.48685 -323.734053)
			(xy 433.467002 -323.716396) (xy 433.456194 -323.707037) (xy 433.430629 -323.694259) (xy 433.402524 -323.689065)
			(xy 433.374081 -323.691863) (xy 433.347526 -323.702432) (xy 433.335938 -323.710808) (xy 433.312372 -323.728352)
			(xy 433.260663 -323.756235) (xy 433.205078 -323.775251) (xy 433.147126 -323.784886) (xy 433.117752 -323.785484)
			(xy 433.091103 -323.785031) (xy 433.038402 -323.777081) (xy 432.987474 -323.761366) (xy 432.939456 -323.738236)
			(xy 432.895422 -323.708209) (xy 432.856355 -323.671954) (xy 432.823127 -323.630283) (xy 432.79648 -323.584124)
			(xy 432.77701 -323.53451) (xy 432.765151 -323.482549) (xy 432.761168 -323.4294) (xy 430.121608 -323.4294)
			(xy 430.117624 -323.482554) (xy 430.105762 -323.534521) (xy 430.086287 -323.584139) (xy 430.059633 -323.6303)
			(xy 430.026397 -323.671972) (xy 429.98732 -323.708224) (xy 429.943276 -323.738248) (xy 429.895249 -323.76137)
			(xy 429.844313 -323.777076) (xy 429.791604 -323.785014) (xy 429.764952 -323.785484) (xy 429.738544 -323.784977)
			(xy 429.686307 -323.777182) (xy 429.635794 -323.761757) (xy 429.588114 -323.739038) (xy 429.544313 -323.709526)
			(xy 429.505352 -323.673867) (xy 429.488346 -323.653658) (xy 429.478409 -323.642265) (xy 429.453356 -323.625374)
			(xy 429.42446 -323.616543) (xy 429.394244 -323.616543) (xy 429.365348 -323.625374) (xy 429.340295 -323.642265)
			(xy 429.330358 -323.653658) (xy 429.313318 -323.673838) (xy 429.274366 -323.709504) (xy 429.230573 -323.739025)
			(xy 429.1829 -323.761754) (xy 429.132392 -323.777192) (xy 429.080159 -323.785) (xy 429.053752 -323.785484)
			(xy 429.027103 -323.785031) (xy 428.974402 -323.777081) (xy 428.923474 -323.761366) (xy 428.875456 -323.738236)
			(xy 428.831422 -323.708209) (xy 428.792355 -323.671954) (xy 428.759127 -323.630283) (xy 428.73248 -323.584124)
			(xy 428.71301 -323.53451) (xy 428.701151 -323.482549) (xy 428.697168 -323.4294) (xy 426.641808 -323.4294)
			(xy 426.637824 -323.482554) (xy 426.625962 -323.534521) (xy 426.606487 -323.584139) (xy 426.579833 -323.6303)
			(xy 426.546597 -323.671972) (xy 426.50752 -323.708224) (xy 426.463476 -323.738248) (xy 426.415449 -323.76137)
			(xy 426.364513 -323.777076) (xy 426.311804 -323.785014) (xy 426.285152 -323.785484) (xy 426.258744 -323.784977)
			(xy 426.206507 -323.777182) (xy 426.155994 -323.761757) (xy 426.108314 -323.739038) (xy 426.064513 -323.709526)
			(xy 426.025552 -323.673867) (xy 426.008546 -323.653658) (xy 425.998609 -323.642265) (xy 425.973556 -323.625374)
			(xy 425.94466 -323.616543) (xy 425.914444 -323.616543) (xy 425.885548 -323.625374) (xy 425.860495 -323.642265)
			(xy 425.850558 -323.653658) (xy 425.833518 -323.673838) (xy 425.794566 -323.709504) (xy 425.750773 -323.739025)
			(xy 425.7031 -323.761754) (xy 425.652592 -323.777192) (xy 425.600359 -323.785) (xy 425.573952 -323.785484)
			(xy 425.547303 -323.785031) (xy 425.494602 -323.777081) (xy 425.443674 -323.761366) (xy 425.395656 -323.738236)
			(xy 425.351622 -323.708209) (xy 425.312555 -323.671954) (xy 425.279327 -323.630283) (xy 425.25268 -323.584124)
			(xy 425.23321 -323.53451) (xy 425.221351 -323.482549) (xy 425.217368 -323.4294) (xy 422.577808 -323.4294)
			(xy 422.573824 -323.482554) (xy 422.561962 -323.534521) (xy 422.542487 -323.584139) (xy 422.515833 -323.6303)
			(xy 422.482597 -323.671972) (xy 422.44352 -323.708224) (xy 422.399476 -323.738248) (xy 422.351449 -323.76137)
			(xy 422.300513 -323.777076) (xy 422.247804 -323.785014) (xy 422.221152 -323.785484) (xy 422.194744 -323.784977)
			(xy 422.142507 -323.777182) (xy 422.091994 -323.761757) (xy 422.044314 -323.739038) (xy 422.000513 -323.709526)
			(xy 421.961552 -323.673867) (xy 421.944546 -323.653658) (xy 421.934609 -323.642265) (xy 421.909556 -323.625374)
			(xy 421.88066 -323.616543) (xy 421.850444 -323.616543) (xy 421.821548 -323.625374) (xy 421.796495 -323.642265)
			(xy 421.786558 -323.653658) (xy 421.769518 -323.673838) (xy 421.730566 -323.709504) (xy 421.686773 -323.739025)
			(xy 421.6391 -323.761754) (xy 421.588592 -323.777192) (xy 421.536359 -323.785) (xy 421.509952 -323.785484)
			(xy 421.483303 -323.785031) (xy 421.430602 -323.777081) (xy 421.379674 -323.761366) (xy 421.331656 -323.738236)
			(xy 421.287622 -323.708209) (xy 421.248555 -323.671954) (xy 421.215327 -323.630283) (xy 421.18868 -323.584124)
			(xy 421.16921 -323.53451) (xy 421.157351 -323.482549) (xy 421.153368 -323.4294) (xy 419.098008 -323.4294)
			(xy 419.094024 -323.482554) (xy 419.082162 -323.534521) (xy 419.062687 -323.584139) (xy 419.036033 -323.6303)
			(xy 419.002797 -323.671972) (xy 418.96372 -323.708224) (xy 418.919676 -323.738248) (xy 418.871649 -323.76137)
			(xy 418.820713 -323.777076) (xy 418.768004 -323.785014) (xy 418.741352 -323.785484) (xy 418.714944 -323.784977)
			(xy 418.662707 -323.777182) (xy 418.612194 -323.761757) (xy 418.564514 -323.739038) (xy 418.520713 -323.709526)
			(xy 418.481752 -323.673867) (xy 418.464746 -323.653658) (xy 418.454809 -323.642265) (xy 418.429756 -323.625374)
			(xy 418.40086 -323.616543) (xy 418.370644 -323.616543) (xy 418.341748 -323.625374) (xy 418.316695 -323.642265)
			(xy 418.306758 -323.653658) (xy 418.289718 -323.673838) (xy 418.250766 -323.709504) (xy 418.206973 -323.739025)
			(xy 418.1593 -323.761754) (xy 418.108792 -323.777192) (xy 418.056559 -323.785) (xy 418.030152 -323.785484)
			(xy 418.003503 -323.785031) (xy 417.950802 -323.777081) (xy 417.899874 -323.761366) (xy 417.851856 -323.738236)
			(xy 417.807822 -323.708209) (xy 417.768755 -323.671954) (xy 417.735527 -323.630283) (xy 417.70888 -323.584124)
			(xy 417.68941 -323.53451) (xy 417.677551 -323.482549) (xy 417.673568 -323.4294) (xy 415.034008 -323.4294)
			(xy 415.030024 -323.482554) (xy 415.018162 -323.534521) (xy 414.998687 -323.584139) (xy 414.972033 -323.6303)
			(xy 414.938797 -323.671972) (xy 414.89972 -323.708224) (xy 414.855676 -323.738248) (xy 414.807649 -323.76137)
			(xy 414.756713 -323.777076) (xy 414.704004 -323.785014) (xy 414.677352 -323.785484) (xy 414.650944 -323.784977)
			(xy 414.598707 -323.777182) (xy 414.548194 -323.761757) (xy 414.500514 -323.739038) (xy 414.456713 -323.709526)
			(xy 414.417752 -323.673867) (xy 414.400746 -323.653658) (xy 414.390809 -323.642265) (xy 414.365756 -323.625374)
			(xy 414.33686 -323.616543) (xy 414.306644 -323.616543) (xy 414.277748 -323.625374) (xy 414.252695 -323.642265)
			(xy 414.242758 -323.653658) (xy 414.225718 -323.673838) (xy 414.186766 -323.709504) (xy 414.142973 -323.739025)
			(xy 414.0953 -323.761754) (xy 414.044792 -323.777192) (xy 413.992559 -323.785) (xy 413.966152 -323.785484)
			(xy 413.939503 -323.785031) (xy 413.886802 -323.777081) (xy 413.835874 -323.761366) (xy 413.787856 -323.738236)
			(xy 413.743822 -323.708209) (xy 413.704755 -323.671954) (xy 413.671527 -323.630283) (xy 413.64488 -323.584124)
			(xy 413.62541 -323.53451) (xy 413.613551 -323.482549) (xy 413.609568 -323.4294) (xy 411.554208 -323.4294)
			(xy 411.550224 -323.482554) (xy 411.538362 -323.534521) (xy 411.518887 -323.584139) (xy 411.492233 -323.6303)
			(xy 411.458997 -323.671972) (xy 411.41992 -323.708224) (xy 411.375876 -323.738248) (xy 411.327849 -323.76137)
			(xy 411.276913 -323.777076) (xy 411.224204 -323.785014) (xy 411.197552 -323.785484) (xy 411.171144 -323.784977)
			(xy 411.118907 -323.777182) (xy 411.068394 -323.761757) (xy 411.020714 -323.739038) (xy 410.976913 -323.709526)
			(xy 410.937952 -323.673867) (xy 410.920946 -323.653658) (xy 410.911009 -323.642265) (xy 410.885956 -323.625374)
			(xy 410.85706 -323.616543) (xy 410.826844 -323.616543) (xy 410.797948 -323.625374) (xy 410.772895 -323.642265)
			(xy 410.762958 -323.653658) (xy 410.745918 -323.673838) (xy 410.706966 -323.709504) (xy 410.663173 -323.739025)
			(xy 410.6155 -323.761754) (xy 410.564992 -323.777192) (xy 410.512759 -323.785) (xy 410.486352 -323.785484)
			(xy 410.459703 -323.785031) (xy 410.407002 -323.777081) (xy 410.356074 -323.761366) (xy 410.308056 -323.738236)
			(xy 410.264022 -323.708209) (xy 410.224955 -323.671954) (xy 410.191727 -323.630283) (xy 410.16508 -323.584124)
			(xy 410.14561 -323.53451) (xy 410.133751 -323.482549) (xy 410.129768 -323.4294) (xy 409.634968 -323.4294)
			(xy 410.280358 -324.07479) (xy 411.004258 -324.07479) (xy 412.970218 -326.04075) (xy 412.970218 -327.10898)
			(xy 414.810321 -327.10898) (xy 414.810321 -327.02442) (xy 414.818124 -326.94022) (xy 414.833662 -326.857099)
			(xy 414.856804 -326.775767) (xy 414.887352 -326.696917) (xy 414.925045 -326.621222) (xy 414.969562 -326.549328)
			(xy 415.020523 -326.481848) (xy 415.077492 -326.419358) (xy 415.139985 -326.362392) (xy 415.207467 -326.311435)
			(xy 415.279364 -326.266922) (xy 415.355061 -326.229233) (xy 415.433912 -326.198689) (xy 415.515246 -326.175551)
			(xy 415.598367 -326.160017) (xy 415.682568 -326.152219) (xy 415.724848 -326.151748) (xy 416.969448 -326.151748)
			(xy 417.011721 -326.152326) (xy 417.095905 -326.160131) (xy 417.17901 -326.17567) (xy 417.260327 -326.198811)
			(xy 417.339162 -326.229355) (xy 417.414843 -326.267043) (xy 417.486723 -326.311553) (xy 417.554191 -326.362505)
			(xy 417.616669 -326.419465) (xy 417.673625 -326.481946) (xy 417.724574 -326.549416) (xy 417.76908 -326.621299)
			(xy 417.806764 -326.696982) (xy 417.837304 -326.775818) (xy 417.860441 -326.857136) (xy 417.875975 -326.940242)
			(xy 417.883776 -327.024427) (xy 417.883776 -327.108973) (xy 417.883775 -327.10898) (xy 422.354121 -327.10898)
			(xy 422.354121 -327.02442) (xy 422.361924 -326.94022) (xy 422.377462 -326.857099) (xy 422.400604 -326.775767)
			(xy 422.431152 -326.696917) (xy 422.468845 -326.621222) (xy 422.513362 -326.549328) (xy 422.564323 -326.481848)
			(xy 422.621292 -326.419358) (xy 422.683785 -326.362392) (xy 422.751267 -326.311435) (xy 422.823164 -326.266922)
			(xy 422.898861 -326.229233) (xy 422.977712 -326.198689) (xy 423.059046 -326.175551) (xy 423.142167 -326.160017)
			(xy 423.226368 -326.152219) (xy 423.268648 -326.151748) (xy 424.513248 -326.151748) (xy 424.555521 -326.152326)
			(xy 424.639705 -326.160131) (xy 424.72281 -326.17567) (xy 424.804127 -326.198811) (xy 424.882962 -326.229355)
			(xy 424.958643 -326.267043) (xy 425.030523 -326.311553) (xy 425.097991 -326.362505) (xy 425.160469 -326.419465)
			(xy 425.217425 -326.481946) (xy 425.268374 -326.549416) (xy 425.31288 -326.621299) (xy 425.350564 -326.696982)
			(xy 425.381104 -326.775818) (xy 425.404241 -326.857136) (xy 425.419775 -326.940242) (xy 425.427576 -327.024427)
			(xy 425.427576 -327.108973) (xy 425.427575 -327.10898) (xy 429.897921 -327.10898) (xy 429.897921 -327.02442)
			(xy 429.905724 -326.94022) (xy 429.921262 -326.857099) (xy 429.944404 -326.775767) (xy 429.974952 -326.696917)
			(xy 430.012645 -326.621222) (xy 430.057162 -326.549328) (xy 430.108123 -326.481848) (xy 430.165092 -326.419358)
			(xy 430.227585 -326.362392) (xy 430.295067 -326.311435) (xy 430.366964 -326.266922) (xy 430.442661 -326.229233)
			(xy 430.521512 -326.198689) (xy 430.602846 -326.175551) (xy 430.685967 -326.160017) (xy 430.770168 -326.152219)
			(xy 430.812448 -326.151748) (xy 432.057048 -326.151748) (xy 432.099321 -326.152326) (xy 432.183505 -326.160131)
			(xy 432.26661 -326.17567) (xy 432.347927 -326.198811) (xy 432.426762 -326.229355) (xy 432.502443 -326.267043)
			(xy 432.574323 -326.311553) (xy 432.641791 -326.362505) (xy 432.704269 -326.419465) (xy 432.761225 -326.481946)
			(xy 432.812174 -326.549416) (xy 432.85668 -326.621299) (xy 432.894364 -326.696982) (xy 432.924904 -326.775818)
			(xy 432.948041 -326.857136) (xy 432.963575 -326.940242) (xy 432.971376 -327.024427) (xy 432.971376 -327.108973)
			(xy 432.971375 -327.10898) (xy 437.441721 -327.10898) (xy 437.441721 -327.02442) (xy 437.449524 -326.94022)
			(xy 437.465062 -326.857099) (xy 437.488204 -326.775767) (xy 437.518752 -326.696917) (xy 437.556445 -326.621222)
			(xy 437.600962 -326.549328) (xy 437.651923 -326.481848) (xy 437.708892 -326.419358) (xy 437.771385 -326.362392)
			(xy 437.838867 -326.311435) (xy 437.910764 -326.266922) (xy 437.986461 -326.229233) (xy 438.065312 -326.198689)
			(xy 438.146646 -326.175551) (xy 438.229767 -326.160017) (xy 438.313968 -326.152219) (xy 438.356248 -326.151748)
			(xy 439.600848 -326.151748) (xy 439.643121 -326.152326) (xy 439.727305 -326.160131) (xy 439.81041 -326.17567)
			(xy 439.891727 -326.198811) (xy 439.970562 -326.229355) (xy 440.046243 -326.267043) (xy 440.118123 -326.311553)
			(xy 440.185591 -326.362505) (xy 440.248069 -326.419465) (xy 440.305025 -326.481946) (xy 440.355974 -326.549416)
			(xy 440.40048 -326.621299) (xy 440.438164 -326.696982) (xy 440.468704 -326.775818) (xy 440.491841 -326.857136)
			(xy 440.507375 -326.940242) (xy 440.515176 -327.024427) (xy 440.515176 -327.108973) (xy 440.515175 -327.10898)
			(xy 444.985521 -327.10898) (xy 444.985521 -327.02442) (xy 444.993324 -326.94022) (xy 445.008862 -326.857099)
			(xy 445.032004 -326.775767) (xy 445.062552 -326.696917) (xy 445.100245 -326.621222) (xy 445.144762 -326.549328)
			(xy 445.195723 -326.481848) (xy 445.252692 -326.419358) (xy 445.315185 -326.362392) (xy 445.382667 -326.311435)
			(xy 445.454564 -326.266922) (xy 445.530261 -326.229233) (xy 445.609112 -326.198689) (xy 445.690446 -326.175551)
			(xy 445.773567 -326.160017) (xy 445.857768 -326.152219) (xy 445.900048 -326.151748) (xy 447.144648 -326.151748)
			(xy 447.186921 -326.152326) (xy 447.271105 -326.160131) (xy 447.35421 -326.17567) (xy 447.435527 -326.198811)
			(xy 447.514362 -326.229355) (xy 447.590043 -326.267043) (xy 447.661923 -326.311553) (xy 447.729391 -326.362505)
			(xy 447.791869 -326.419465) (xy 447.848825 -326.481946) (xy 447.899774 -326.549416) (xy 447.94428 -326.621299)
			(xy 447.981964 -326.696982) (xy 448.012504 -326.775818) (xy 448.035641 -326.857136) (xy 448.051175 -326.940242)
			(xy 448.058976 -327.024427) (xy 448.058976 -327.108973) (xy 448.058975 -327.10898) (xy 452.529321 -327.10898)
			(xy 452.529321 -327.02442) (xy 452.537124 -326.94022) (xy 452.552662 -326.857099) (xy 452.575804 -326.775767)
			(xy 452.606352 -326.696917) (xy 452.644045 -326.621222) (xy 452.688562 -326.549328) (xy 452.739523 -326.481848)
			(xy 452.796492 -326.419358) (xy 452.858985 -326.362392) (xy 452.926467 -326.311435) (xy 452.998364 -326.266922)
			(xy 453.074061 -326.229233) (xy 453.152912 -326.198689) (xy 453.234246 -326.175551) (xy 453.317367 -326.160017)
			(xy 453.401568 -326.152219) (xy 453.443848 -326.151748) (xy 454.688448 -326.151748) (xy 454.730721 -326.152326)
			(xy 454.814905 -326.160131) (xy 454.89801 -326.17567) (xy 454.979327 -326.198811) (xy 455.058162 -326.229355)
			(xy 455.133843 -326.267043) (xy 455.205723 -326.311553) (xy 455.273191 -326.362505) (xy 455.335669 -326.419465)
			(xy 455.392625 -326.481946) (xy 455.443574 -326.549416) (xy 455.48808 -326.621299) (xy 455.525764 -326.696982)
			(xy 455.556304 -326.775818) (xy 455.579441 -326.857136) (xy 455.594975 -326.940242) (xy 455.602776 -327.024427)
			(xy 455.602776 -327.108973) (xy 455.594975 -327.193158) (xy 455.579441 -327.276264) (xy 455.556304 -327.357582)
			(xy 455.525764 -327.436418) (xy 455.48808 -327.512101) (xy 455.443574 -327.583984) (xy 455.392625 -327.651454)
			(xy 455.335669 -327.713935) (xy 455.273191 -327.770895) (xy 455.205724 -327.821847) (xy 455.133843 -327.866357)
			(xy 455.058162 -327.904045) (xy 454.979327 -327.934589) (xy 454.89801 -327.95773) (xy 454.814905 -327.973269)
			(xy 454.730721 -327.981074) (xy 454.688448 -327.981564) (xy 453.443848 -327.981564) (xy 453.401568 -327.981181)
			(xy 453.317367 -327.973383) (xy 453.234246 -327.957849) (xy 453.152912 -327.934711) (xy 453.074061 -327.904167)
			(xy 452.998364 -327.866478) (xy 452.926467 -327.821965) (xy 452.858985 -327.771008) (xy 452.796492 -327.714042)
			(xy 452.739523 -327.651552) (xy 452.688562 -327.584072) (xy 452.644045 -327.512178) (xy 452.606352 -327.436483)
			(xy 452.575804 -327.357633) (xy 452.552662 -327.276301) (xy 452.537124 -327.19318) (xy 452.529321 -327.10898)
			(xy 448.058975 -327.10898) (xy 448.051175 -327.193158) (xy 448.035641 -327.276264) (xy 448.012504 -327.357582)
			(xy 447.981964 -327.436418) (xy 447.94428 -327.512101) (xy 447.899774 -327.583984) (xy 447.848825 -327.651454)
			(xy 447.791869 -327.713935) (xy 447.729391 -327.770895) (xy 447.661924 -327.821847) (xy 447.590043 -327.866357)
			(xy 447.514362 -327.904045) (xy 447.435527 -327.934589) (xy 447.35421 -327.95773) (xy 447.271105 -327.973269)
			(xy 447.186921 -327.981074) (xy 447.144648 -327.981564) (xy 445.900048 -327.981564) (xy 445.857768 -327.981181)
			(xy 445.773567 -327.973383) (xy 445.690446 -327.957849) (xy 445.609112 -327.934711) (xy 445.530261 -327.904167)
			(xy 445.454564 -327.866478) (xy 445.382667 -327.821965) (xy 445.315185 -327.771008) (xy 445.252692 -327.714042)
			(xy 445.195723 -327.651552) (xy 445.144762 -327.584072) (xy 445.100245 -327.512178) (xy 445.062552 -327.436483)
			(xy 445.032004 -327.357633) (xy 445.008862 -327.276301) (xy 444.993324 -327.19318) (xy 444.985521 -327.10898)
			(xy 440.515175 -327.10898) (xy 440.507375 -327.193158) (xy 440.491841 -327.276264) (xy 440.468704 -327.357582)
			(xy 440.438164 -327.436418) (xy 440.40048 -327.512101) (xy 440.355974 -327.583984) (xy 440.305025 -327.651454)
			(xy 440.248069 -327.713935) (xy 440.185591 -327.770895) (xy 440.118124 -327.821847) (xy 440.046243 -327.866357)
			(xy 439.970562 -327.904045) (xy 439.891727 -327.934589) (xy 439.81041 -327.95773) (xy 439.727305 -327.973269)
			(xy 439.643121 -327.981074) (xy 439.600848 -327.981564) (xy 438.356248 -327.981564) (xy 438.313968 -327.981181)
			(xy 438.229767 -327.973383) (xy 438.146646 -327.957849) (xy 438.065312 -327.934711) (xy 437.986461 -327.904167)
			(xy 437.910764 -327.866478) (xy 437.838867 -327.821965) (xy 437.771385 -327.771008) (xy 437.708892 -327.714042)
			(xy 437.651923 -327.651552) (xy 437.600962 -327.584072) (xy 437.556445 -327.512178) (xy 437.518752 -327.436483)
			(xy 437.488204 -327.357633) (xy 437.465062 -327.276301) (xy 437.449524 -327.19318) (xy 437.441721 -327.10898)
			(xy 432.971375 -327.10898) (xy 432.963575 -327.193158) (xy 432.948041 -327.276264) (xy 432.924904 -327.357582)
			(xy 432.894364 -327.436418) (xy 432.85668 -327.512101) (xy 432.812174 -327.583984) (xy 432.761225 -327.651454)
			(xy 432.704269 -327.713935) (xy 432.641791 -327.770895) (xy 432.574324 -327.821847) (xy 432.502443 -327.866357)
			(xy 432.426762 -327.904045) (xy 432.347927 -327.934589) (xy 432.26661 -327.95773) (xy 432.183505 -327.973269)
			(xy 432.099321 -327.981074) (xy 432.057048 -327.981564) (xy 430.812448 -327.981564) (xy 430.770168 -327.981181)
			(xy 430.685967 -327.973383) (xy 430.602846 -327.957849) (xy 430.521512 -327.934711) (xy 430.442661 -327.904167)
			(xy 430.366964 -327.866478) (xy 430.295067 -327.821965) (xy 430.227585 -327.771008) (xy 430.165092 -327.714042)
			(xy 430.108123 -327.651552) (xy 430.057162 -327.584072) (xy 430.012645 -327.512178) (xy 429.974952 -327.436483)
			(xy 429.944404 -327.357633) (xy 429.921262 -327.276301) (xy 429.905724 -327.19318) (xy 429.897921 -327.10898)
			(xy 425.427575 -327.10898) (xy 425.419775 -327.193158) (xy 425.404241 -327.276264) (xy 425.381104 -327.357582)
			(xy 425.350564 -327.436418) (xy 425.31288 -327.512101) (xy 425.268374 -327.583984) (xy 425.217425 -327.651454)
			(xy 425.160469 -327.713935) (xy 425.097991 -327.770895) (xy 425.030524 -327.821847) (xy 424.958643 -327.866357)
			(xy 424.882962 -327.904045) (xy 424.804127 -327.934589) (xy 424.72281 -327.95773) (xy 424.639705 -327.973269)
			(xy 424.555521 -327.981074) (xy 424.513248 -327.981564) (xy 423.268648 -327.981564) (xy 423.226368 -327.981181)
			(xy 423.142167 -327.973383) (xy 423.059046 -327.957849) (xy 422.977712 -327.934711) (xy 422.898861 -327.904167)
			(xy 422.823164 -327.866478) (xy 422.751267 -327.821965) (xy 422.683785 -327.771008) (xy 422.621292 -327.714042)
			(xy 422.564323 -327.651552) (xy 422.513362 -327.584072) (xy 422.468845 -327.512178) (xy 422.431152 -327.436483)
			(xy 422.400604 -327.357633) (xy 422.377462 -327.276301) (xy 422.361924 -327.19318) (xy 422.354121 -327.10898)
			(xy 417.883775 -327.10898) (xy 417.875975 -327.193158) (xy 417.860441 -327.276264) (xy 417.837304 -327.357582)
			(xy 417.806764 -327.436418) (xy 417.76908 -327.512101) (xy 417.724574 -327.583984) (xy 417.673625 -327.651454)
			(xy 417.616669 -327.713935) (xy 417.554191 -327.770895) (xy 417.486724 -327.821847) (xy 417.414843 -327.866357)
			(xy 417.339162 -327.904045) (xy 417.260327 -327.934589) (xy 417.17901 -327.95773) (xy 417.095905 -327.973269)
			(xy 417.011721 -327.981074) (xy 416.969448 -327.981564) (xy 415.724848 -327.981564) (xy 415.682568 -327.981181)
			(xy 415.598367 -327.973383) (xy 415.515246 -327.957849) (xy 415.433912 -327.934711) (xy 415.355061 -327.904167)
			(xy 415.279364 -327.866478) (xy 415.207467 -327.821965) (xy 415.139985 -327.771008) (xy 415.077492 -327.714042)
			(xy 415.020523 -327.651552) (xy 414.969562 -327.584072) (xy 414.925045 -327.512178) (xy 414.887352 -327.436483)
			(xy 414.856804 -327.357633) (xy 414.833662 -327.276301) (xy 414.818124 -327.19318) (xy 414.810321 -327.10898)
			(xy 412.970218 -327.10898) (xy 412.970218 -331.01661) (xy 414.814008 -332.8604) (xy 443.200588 -332.8604)
			(xy 443.204571 -332.807254) (xy 443.216429 -332.755296) (xy 443.235898 -332.705684) (xy 443.262543 -332.659529)
			(xy 443.29577 -332.617859) (xy 443.334835 -332.581607) (xy 443.378866 -332.551581) (xy 443.426881 -332.528453)
			(xy 443.477806 -332.512739) (xy 443.530505 -332.504789) (xy 443.557152 -332.504288) (xy 443.58356 -332.504803)
			(xy 443.635796 -332.512597) (xy 443.686309 -332.528022) (xy 443.733988 -332.550739) (xy 443.77779 -332.580249)
			(xy 443.816751 -332.615906) (xy 443.833758 -332.636114) (xy 443.843695 -332.647507) (xy 443.868748 -332.664398)
			(xy 443.897644 -332.673229) (xy 443.92786 -332.673229) (xy 443.956756 -332.664398) (xy 443.981809 -332.647507)
			(xy 443.991746 -332.636114) (xy 444.008777 -332.615926) (xy 444.047732 -332.580262) (xy 444.091527 -332.550743)
			(xy 444.139202 -332.528015) (xy 444.18971 -332.512579) (xy 444.241945 -332.504771) (xy 444.268352 -332.504288)
			(xy 444.295005 -332.504766) (xy 444.347717 -332.512704) (xy 444.398657 -332.528411) (xy 444.446686 -332.551535)
			(xy 444.490732 -332.58156) (xy 444.529811 -332.617815) (xy 444.56305 -332.659489) (xy 444.589705 -332.705653)
			(xy 444.609181 -332.755273) (xy 444.621044 -332.807243) (xy 444.625028 -332.8604) (xy 444.621044 -332.913557)
			(xy 444.609181 -332.965527) (xy 444.589705 -333.015147) (xy 444.56305 -333.061311) (xy 444.529811 -333.102985)
			(xy 444.490732 -333.13924) (xy 444.446686 -333.169265) (xy 444.398657 -333.192389) (xy 444.347717 -333.208096)
			(xy 444.295005 -333.216034) (xy 444.268352 -333.216504) (xy 444.241944 -333.215989) (xy 444.189708 -333.208195)
			(xy 444.139195 -333.192771) (xy 444.091515 -333.170054) (xy 444.047714 -333.140543) (xy 444.008753 -333.104886)
			(xy 443.991746 -333.084678) (xy 443.981809 -333.073285) (xy 443.956756 -333.056394) (xy 443.92786 -333.047563)
			(xy 443.897644 -333.047563) (xy 443.868748 -333.056394) (xy 443.843695 -333.073285) (xy 443.833758 -333.084678)
			(xy 443.816723 -333.104863) (xy 443.777769 -333.140527) (xy 443.733975 -333.170047) (xy 443.686301 -333.192775)
			(xy 443.635793 -333.208212) (xy 443.583559 -333.216021) (xy 443.557152 -333.216504) (xy 443.530505 -333.216011)
			(xy 443.477806 -333.208061) (xy 443.426881 -333.192347) (xy 443.378866 -333.169219) (xy 443.334835 -333.139193)
			(xy 443.29577 -333.102941) (xy 443.262543 -333.061271) (xy 443.235898 -333.015116) (xy 443.216429 -332.965504)
			(xy 443.204571 -332.913546) (xy 443.200588 -332.8604) (xy 414.814008 -332.8604) (xy 417.018978 -335.06537)
		)
		(stroke
			(width 0)
			(type solid)
		)
		(fill yes)
		(layer "In4.Cu")
		(net "P12V_S3_AUX_CPU0_NVDIMM")
	)
	(gr_poly
		(pts
			(xy 63.621666 -34.927032) (xy 63.636654 -34.926491) (xy 63.665336 -34.917776) (xy 63.690255 -34.901114)
			(xy 63.709269 -34.877939) (xy 63.720741 -34.850244) (xy 63.723684 -34.820412) (xy 63.717846 -34.791009)
			(xy 63.703729 -34.764565) (xy 63.693548 -34.75355) (xy 61.91504 -32.975296) (xy 61.894261 -32.953682)
			(xy 61.859025 -32.905176) (xy 61.831808 -32.851757) (xy 61.81328 -32.794739) (xy 61.803897 -32.735524)
			(xy 61.80328 -32.705548) (xy 61.80328 -28.331922) (xy 61.803766 -28.304671) (xy 61.811522 -28.250723)
			(xy 61.826877 -28.198428) (xy 61.849519 -28.148851) (xy 61.878985 -28.103001) (xy 61.914676 -28.06181)
			(xy 61.955867 -28.026119) (xy 62.001717 -27.996653) (xy 62.051294 -27.974011) (xy 62.103589 -27.958656)
			(xy 62.157537 -27.9509) (xy 62.212039 -27.9509) (xy 62.265987 -27.958656) (xy 62.318282 -27.974011)
			(xy 62.367859 -27.996653) (xy 62.413709 -28.026119) (xy 62.4549 -28.06181) (xy 62.490591 -28.103001)
			(xy 62.520057 -28.148851) (xy 62.542699 -28.198428) (xy 62.558054 -28.250723) (xy 62.56581 -28.304671)
			(xy 62.566296 -28.331922) (xy 62.566296 -28.417051) (xy 64.103989 -28.417051) (xy 64.103989 -28.362549)
			(xy 64.111746 -28.308602) (xy 64.127101 -28.256308) (xy 64.149743 -28.206731) (xy 64.179209 -28.160882)
			(xy 64.214901 -28.119692) (xy 64.256091 -28.084002) (xy 64.301942 -28.054537) (xy 64.351519 -28.031897)
			(xy 64.403814 -28.016543) (xy 64.457761 -28.008788) (xy 64.485012 -28.008326) (xy 64.512988 -28.008794)
			(xy 64.568339 -28.016975) (xy 64.621899 -28.033159) (xy 64.672518 -28.056998) (xy 64.696086 -28.07208)
			(xy 65.27038 -28.07208) (xy 65.295355 -28.072546) (xy 65.344694 -28.080339) (xy 65.392207 -28.095752)
			(xy 65.436725 -28.118405) (xy 65.477153 -28.147741) (xy 65.49517 -28.165044) (xy 65.537588 -28.207462)
			(xy 66.166238 -28.207462) (xy 66.166725 -28.18014) (xy 66.17507 -28.126136) (xy 66.191558 -28.074039)
			(xy 66.215804 -28.025068) (xy 66.247239 -27.980371) (xy 66.265806 -27.96032) (xy 66.276244 -27.94873)
			(xy 66.290071 -27.920786) (xy 66.294822 -27.889972) (xy 66.290054 -27.859161) (xy 66.276212 -27.831225)
			(xy 66.265806 -27.819604) (xy 66.247204 -27.799581) (xy 66.215746 -27.754891) (xy 66.191495 -27.705914)
			(xy 66.175021 -27.653805) (xy 66.166712 -27.599788) (xy 66.166238 -27.572462) (xy 66.166736 -27.545813)
			(xy 66.174679 -27.493109) (xy 66.190389 -27.442179) (xy 66.213515 -27.394158) (xy 66.243539 -27.350121)
			(xy 66.279791 -27.31105) (xy 66.321462 -27.277819) (xy 66.36762 -27.25117) (xy 66.417234 -27.231698)
			(xy 66.469196 -27.219838) (xy 66.522346 -27.215855) (xy 66.575496 -27.219838) (xy 66.627458 -27.231698)
			(xy 66.677072 -27.25117) (xy 66.72323 -27.277819) (xy 66.764901 -27.31105) (xy 66.801153 -27.350121)
			(xy 66.831177 -27.394158) (xy 66.854303 -27.442179) (xy 66.870013 -27.493109) (xy 66.877956 -27.545813)
			(xy 66.878454 -27.572462) (xy 66.877922 -27.599782) (xy 66.869589 -27.653784) (xy 66.853111 -27.705881)
			(xy 66.828875 -27.754853) (xy 66.797449 -27.799552) (xy 66.778886 -27.819604) (xy 66.768524 -27.831256)
			(xy 66.75469 -27.859178) (xy 66.749926 -27.889972) (xy 66.754674 -27.92077) (xy 66.768492 -27.948699)
			(xy 66.778886 -27.96032) (xy 66.797498 -27.980334) (xy 66.828955 -28.025027) (xy 66.853205 -28.074005)
			(xy 66.869676 -28.126117) (xy 66.877982 -28.180135) (xy 66.878454 -28.207462) (xy 67.06616 -28.207462)
			(xy 67.066669 -28.180141) (xy 67.075011 -28.126139) (xy 67.091496 -28.074043) (xy 67.115736 -28.025072)
			(xy 67.147164 -27.980372) (xy 67.165728 -27.96032) (xy 67.176164 -27.948729) (xy 67.189988 -27.920785)
			(xy 67.194738 -27.889972) (xy 67.189971 -27.859162) (xy 67.176132 -27.831226) (xy 67.165728 -27.819604)
			(xy 67.14713 -27.799577) (xy 67.115671 -27.754889) (xy 67.091418 -27.705913) (xy 67.074943 -27.653804)
			(xy 67.066634 -27.599788) (xy 67.06616 -27.572462) (xy 67.066658 -27.545813) (xy 67.074601 -27.493109)
			(xy 67.090311 -27.442179) (xy 67.113437 -27.394158) (xy 67.143461 -27.350121) (xy 67.179713 -27.31105)
			(xy 67.221384 -27.277819) (xy 67.267542 -27.25117) (xy 67.317156 -27.231698) (xy 67.369118 -27.219838)
			(xy 67.422268 -27.215855) (xy 67.475418 -27.219838) (xy 67.52738 -27.231698) (xy 67.576994 -27.25117)
			(xy 67.623152 -27.277819) (xy 67.664823 -27.31105) (xy 67.701075 -27.350121) (xy 67.731099 -27.394158)
			(xy 67.754225 -27.442179) (xy 67.769935 -27.493109) (xy 67.777878 -27.545813) (xy 67.778376 -27.572462)
			(xy 67.777838 -27.599782) (xy 67.769505 -27.653783) (xy 67.753029 -27.70588) (xy 67.728794 -27.754852)
			(xy 67.69737 -27.799552) (xy 67.678808 -27.819604) (xy 67.668452 -27.831259) (xy 67.65463 -27.859181)
			(xy 67.649869 -27.889972) (xy 67.654613 -27.920766) (xy 67.668421 -27.948696) (xy 67.678808 -27.96032)
			(xy 67.697423 -27.980331) (xy 67.728879 -28.025025) (xy 67.753128 -28.074004) (xy 67.769599 -28.126116)
			(xy 67.777904 -28.180135) (xy 67.778376 -28.207462) (xy 67.966082 -28.207462) (xy 67.966585 -28.180141)
			(xy 67.974928 -28.126139) (xy 67.991414 -28.074042) (xy 68.015655 -28.025071) (xy 68.047085 -27.980372)
			(xy 68.06565 -27.96032) (xy 68.076084 -27.948728) (xy 68.089905 -27.920784) (xy 68.094654 -27.889972)
			(xy 68.089888 -27.859163) (xy 68.076052 -27.831226) (xy 68.06565 -27.819604) (xy 68.047056 -27.799574)
			(xy 68.015595 -27.754887) (xy 67.991341 -27.705912) (xy 67.974866 -27.653804) (xy 67.966556 -27.599788)
			(xy 67.966082 -27.572462) (xy 67.96658 -27.545813) (xy 67.974523 -27.493109) (xy 67.990233 -27.442179)
			(xy 68.013359 -27.394158) (xy 68.043383 -27.350121) (xy 68.079635 -27.31105) (xy 68.121306 -27.277819)
			(xy 68.167464 -27.25117) (xy 68.217078 -27.231698) (xy 68.26904 -27.219838) (xy 68.32219 -27.215855)
			(xy 68.37534 -27.219838) (xy 68.427302 -27.231698) (xy 68.476916 -27.25117) (xy 68.523074 -27.277819)
			(xy 68.564745 -27.31105) (xy 68.600997 -27.350121) (xy 68.631021 -27.394158) (xy 68.654147 -27.442179)
			(xy 68.669857 -27.493109) (xy 68.6778 -27.545813) (xy 68.678298 -27.572462) (xy 68.677754 -27.599782)
			(xy 68.669422 -27.653782) (xy 68.652946 -27.705879) (xy 68.628713 -27.754851) (xy 68.597291 -27.799551)
			(xy 68.57873 -27.819604) (xy 68.568372 -27.831258) (xy 68.554547 -27.85918) (xy 68.549785 -27.889972)
			(xy 68.55453 -27.920767) (xy 68.568341 -27.948697) (xy 68.57873 -27.96032) (xy 68.597349 -27.980328)
			(xy 68.628804 -28.025023) (xy 68.653051 -28.074003) (xy 68.669521 -28.126116) (xy 68.677826 -28.180135)
			(xy 68.678298 -28.207462) (xy 68.866258 -28.207462) (xy 68.86674 -28.18014) (xy 68.875085 -28.126136)
			(xy 68.891574 -28.074038) (xy 68.915821 -28.025067) (xy 68.947258 -27.98037) (xy 68.965826 -27.96032)
			(xy 68.976262 -27.948729) (xy 68.990086 -27.920785) (xy 68.994836 -27.889972) (xy 68.99007 -27.859162)
			(xy 68.976231 -27.831225) (xy 68.965826 -27.819604) (xy 68.947228 -27.799578) (xy 68.915768 -27.754889)
			(xy 68.891516 -27.705913) (xy 68.875041 -27.653804) (xy 68.866732 -27.599788) (xy 68.866258 -27.572462)
			(xy 68.866756 -27.545813) (xy 68.874699 -27.493109) (xy 68.890409 -27.442179) (xy 68.913535 -27.394158)
			(xy 68.943559 -27.350121) (xy 68.979811 -27.31105) (xy 69.021482 -27.277819) (xy 69.06764 -27.25117)
			(xy 69.117254 -27.231698) (xy 69.169216 -27.219838) (xy 69.222366 -27.215855) (xy 69.275516 -27.219838)
			(xy 69.327478 -27.231698) (xy 69.377092 -27.25117) (xy 69.42325 -27.277819) (xy 69.464921 -27.31105)
			(xy 69.501173 -27.350121) (xy 69.531197 -27.394158) (xy 69.554323 -27.442179) (xy 69.570033 -27.493109)
			(xy 69.577976 -27.545813) (xy 69.578474 -27.572462) (xy 69.577937 -27.599782) (xy 69.569604 -27.653783)
			(xy 69.553127 -27.70588) (xy 69.528893 -27.754852) (xy 69.497468 -27.799552) (xy 69.478906 -27.819604)
			(xy 69.468551 -27.831259) (xy 69.454728 -27.859181) (xy 69.449967 -27.889972) (xy 69.453879 -27.915362)
			(xy 70.95617 -27.915362) (xy 70.956679 -27.886623) (xy 70.965306 -27.829795) (xy 70.98236 -27.774904)
			(xy 71.007455 -27.723193) (xy 71.040022 -27.675831) (xy 71.059294 -27.654504) (xy 71.069401 -27.642999)
			(xy 71.082736 -27.615442) (xy 71.087312 -27.585172) (xy 71.082719 -27.554905) (xy 71.069369 -27.527355)
			(xy 71.059294 -27.51582) (xy 71.040015 -27.4945) (xy 71.007448 -27.447137) (xy 70.982356 -27.395424)
			(xy 70.965308 -27.340531) (xy 70.956689 -27.283702) (xy 70.95617 -27.254962) (xy 70.956656 -27.227711)
			(xy 70.964412 -27.173763) (xy 70.979767 -27.121468) (xy 71.002409 -27.071891) (xy 71.031875 -27.026041)
			(xy 71.067566 -26.98485) (xy 71.108757 -26.949159) (xy 71.154607 -26.919693) (xy 71.204184 -26.897051)
			(xy 71.256479 -26.881696) (xy 71.310427 -26.87394) (xy 71.364929 -26.87394) (xy 71.418877 -26.881696)
			(xy 71.471172 -26.897051) (xy 71.520749 -26.919693) (xy 71.566599 -26.949159) (xy 71.60779 -26.98485)
			(xy 71.643481 -27.026041) (xy 71.672947 -27.071891) (xy 71.695589 -27.121468) (xy 71.710944 -27.173763)
			(xy 71.7187 -27.227711) (xy 71.719186 -27.254962) (xy 71.718677 -27.283701) (xy 71.710047 -27.340528)
			(xy 71.692992 -27.395418) (xy 71.667898 -27.44713) (xy 71.635332 -27.494492) (xy 71.616062 -27.51582)
			(xy 71.606025 -27.527383) (xy 71.592674 -27.554918) (xy 71.588081 -27.585172) (xy 71.592658 -27.615429)
			(xy 71.605993 -27.642971) (xy 71.616062 -27.654504) (xy 71.635315 -27.675847) (xy 71.667883 -27.723204)
			(xy 71.692979 -27.774912) (xy 71.710034 -27.829799) (xy 71.718662 -27.886624) (xy 71.719186 -27.915362)
			(xy 71.7187 -27.942613) (xy 71.710944 -27.996561) (xy 71.695589 -28.048856) (xy 71.672947 -28.098433)
			(xy 71.643481 -28.144283) (xy 71.60779 -28.185474) (xy 71.566599 -28.221165) (xy 71.520749 -28.250631)
			(xy 71.471172 -28.273273) (xy 71.418877 -28.288628) (xy 71.364929 -28.296384) (xy 71.310427 -28.296384)
			(xy 71.256479 -28.288628) (xy 71.204184 -28.273273) (xy 71.154607 -28.250631) (xy 71.108757 -28.221165)
			(xy 71.067566 -28.185474) (xy 71.031875 -28.144283) (xy 71.002409 -28.098433) (xy 70.979767 -28.048856)
			(xy 70.964412 -27.996561) (xy 70.956656 -27.942613) (xy 70.95617 -27.915362) (xy 69.453879 -27.915362)
			(xy 69.454712 -27.920766) (xy 69.468519 -27.948696) (xy 69.478906 -27.96032) (xy 69.497521 -27.980331)
			(xy 69.528977 -28.025025) (xy 69.553226 -28.074004) (xy 69.569697 -28.126116) (xy 69.578002 -28.180135)
			(xy 69.578474 -28.207462) (xy 69.577976 -28.234111) (xy 69.570033 -28.286815) (xy 69.554323 -28.337745)
			(xy 69.531197 -28.385766) (xy 69.501173 -28.429803) (xy 69.464921 -28.468874) (xy 69.42325 -28.502105)
			(xy 69.377092 -28.528754) (xy 69.327478 -28.548226) (xy 69.275516 -28.560086) (xy 69.222366 -28.56407)
			(xy 69.169216 -28.560086) (xy 69.117254 -28.548226) (xy 69.06764 -28.528754) (xy 69.021482 -28.502105)
			(xy 68.979811 -28.468874) (xy 68.943559 -28.429803) (xy 68.913535 -28.385766) (xy 68.890409 -28.337745)
			(xy 68.874699 -28.286815) (xy 68.866756 -28.234111) (xy 68.866258 -28.207462) (xy 68.678298 -28.207462)
			(xy 68.6778 -28.234111) (xy 68.669857 -28.286815) (xy 68.654147 -28.337745) (xy 68.631021 -28.385766)
			(xy 68.600997 -28.429803) (xy 68.564745 -28.468874) (xy 68.523074 -28.502105) (xy 68.476916 -28.528754)
			(xy 68.427302 -28.548226) (xy 68.37534 -28.560086) (xy 68.32219 -28.56407) (xy 68.26904 -28.560086)
			(xy 68.217078 -28.548226) (xy 68.167464 -28.528754) (xy 68.121306 -28.502105) (xy 68.079635 -28.468874)
			(xy 68.043383 -28.429803) (xy 68.013359 -28.385766) (xy 67.990233 -28.337745) (xy 67.974523 -28.286815)
			(xy 67.96658 -28.234111) (xy 67.966082 -28.207462) (xy 67.778376 -28.207462) (xy 67.777878 -28.234111)
			(xy 67.769935 -28.286815) (xy 67.754225 -28.337745) (xy 67.731099 -28.385766) (xy 67.701075 -28.429803)
			(xy 67.664823 -28.468874) (xy 67.623152 -28.502105) (xy 67.576994 -28.528754) (xy 67.52738 -28.548226)
			(xy 67.475418 -28.560086) (xy 67.422268 -28.56407) (xy 67.369118 -28.560086) (xy 67.317156 -28.548226)
			(xy 67.267542 -28.528754) (xy 67.221384 -28.502105) (xy 67.179713 -28.468874) (xy 67.143461 -28.429803)
			(xy 67.113437 -28.385766) (xy 67.090311 -28.337745) (xy 67.074601 -28.286815) (xy 67.066658 -28.234111)
			(xy 67.06616 -28.207462) (xy 66.878454 -28.207462) (xy 66.877956 -28.234111) (xy 66.870013 -28.286815)
			(xy 66.854303 -28.337745) (xy 66.831177 -28.385766) (xy 66.801153 -28.429803) (xy 66.764901 -28.468874)
			(xy 66.72323 -28.502105) (xy 66.677072 -28.528754) (xy 66.627458 -28.548226) (xy 66.575496 -28.560086)
			(xy 66.522346 -28.56407) (xy 66.469196 -28.560086) (xy 66.417234 -28.548226) (xy 66.36762 -28.528754)
			(xy 66.321462 -28.502105) (xy 66.279791 -28.468874) (xy 66.243539 -28.429803) (xy 66.213515 -28.385766)
			(xy 66.190389 -28.337745) (xy 66.174679 -28.286815) (xy 66.166736 -28.234111) (xy 66.166238 -28.207462)
			(xy 65.537588 -28.207462) (xy 65.982088 -28.651962) (xy 76.118974 -28.651962) (xy 76.11943 -28.625646)
			(xy 76.126651 -28.573513) (xy 76.140964 -28.522865) (xy 76.162098 -28.474663) (xy 76.189652 -28.429821)
			(xy 76.223104 -28.389189) (xy 76.242164 -28.371038) (xy 76.252225 -28.361264) (xy 76.266926 -28.337381)
			(xy 76.274562 -28.310397) (xy 76.274555 -28.282352) (xy 76.266905 -28.255371) (xy 76.252193 -28.231497)
			(xy 76.242164 -28.221686) (xy 76.22309 -28.203546) (xy 76.189609 -28.162928) (xy 76.162036 -28.118089)
			(xy 76.140896 -28.069882) (xy 76.126591 -28.019225) (xy 76.119394 -27.967081) (xy 76.118974 -27.940762)
			(xy 76.119492 -27.913189) (xy 76.127435 -27.858619) (xy 76.14315 -27.805761) (xy 76.16631 -27.755715)
			(xy 76.196433 -27.709524) (xy 76.232891 -27.66815) (xy 76.253594 -27.649932) (xy 76.264529 -27.640072)
			(xy 76.280601 -27.615411) (xy 76.28898 -27.587193) (xy 76.288973 -27.557758) (xy 76.28058 -27.529544)
			(xy 76.264497 -27.504891) (xy 76.253594 -27.494992) (xy 76.232875 -27.47679) (xy 76.196405 -27.435419)
			(xy 76.166274 -27.389227) (xy 76.14311 -27.339177) (xy 76.127395 -27.286313) (xy 76.119458 -27.231737)
			(xy 76.118974 -27.204162) (xy 76.11946 -27.176911) (xy 76.127216 -27.122963) (xy 76.142571 -27.070668)
			(xy 76.165213 -27.021091) (xy 76.194679 -26.975241) (xy 76.23037 -26.93405) (xy 76.271561 -26.898359)
			(xy 76.317411 -26.868893) (xy 76.366988 -26.846251) (xy 76.419283 -26.830896) (xy 76.473231 -26.82314)
			(xy 76.527733 -26.82314) (xy 76.581681 -26.830896) (xy 76.633976 -26.846251) (xy 76.683553 -26.868893)
			(xy 76.729403 -26.898359) (xy 76.770594 -26.93405) (xy 76.806285 -26.975241) (xy 76.835751 -27.021091)
			(xy 76.858393 -27.070668) (xy 76.873748 -27.122963) (xy 76.881504 -27.176911) (xy 76.88199 -27.204162)
			(xy 76.881502 -27.231736) (xy 76.873554 -27.286308) (xy 76.857834 -27.339167) (xy 76.834668 -27.389213)
			(xy 76.804539 -27.435404) (xy 76.768076 -27.476776) (xy 76.74737 -27.494992) (xy 76.736514 -27.504931)
			(xy 76.720445 -27.529571) (xy 76.71206 -27.557767) (xy 76.712053 -27.587184) (xy 76.720425 -27.615384)
			(xy 76.736481 -27.640032) (xy 76.74737 -27.649932) (xy 76.768094 -27.66813) (xy 76.804564 -27.7095)
			(xy 76.834696 -27.755693) (xy 76.85786 -27.805744) (xy 76.873573 -27.858609) (xy 76.881508 -27.913186)
			(xy 76.88199 -27.940762) (xy 76.881561 -27.967079) (xy 76.874337 -28.019214) (xy 76.860019 -28.069863)
			(xy 76.83888 -28.118065) (xy 76.81132 -28.162906) (xy 76.777862 -28.203537) (xy 76.7588 -28.221686)
			(xy 76.748818 -28.231534) (xy 76.734119 -28.255397) (xy 76.726476 -28.282361) (xy 76.726469 -28.310388)
			(xy 76.734098 -28.337356) (xy 76.748785 -28.361226) (xy 76.7588 -28.371038) (xy 76.777898 -28.389154)
			(xy 76.811374 -28.429779) (xy 76.838942 -28.474623) (xy 76.860078 -28.522834) (xy 76.874378 -28.573495)
			(xy 76.881572 -28.625641) (xy 76.88199 -28.651962) (xy 78.62697 -28.651962) (xy 78.627428 -28.625646)
			(xy 78.634648 -28.573513) (xy 78.648961 -28.522865) (xy 78.670095 -28.474663) (xy 78.697649 -28.429821)
			(xy 78.731101 -28.389189) (xy 78.75016 -28.371038) (xy 78.760222 -28.361264) (xy 78.774923 -28.337381)
			(xy 78.782559 -28.310397) (xy 78.782552 -28.282352) (xy 78.774902 -28.255371) (xy 78.760189 -28.231496)
			(xy 78.75016 -28.221686) (xy 78.731085 -28.203546) (xy 78.697605 -28.162928) (xy 78.670032 -28.118089)
			(xy 78.648892 -28.069883) (xy 78.634587 -28.019225) (xy 78.62739 -27.967081) (xy 78.62697 -27.940762)
			(xy 78.627489 -27.913189) (xy 78.635432 -27.858619) (xy 78.651147 -27.805761) (xy 78.674307 -27.755715)
			(xy 78.70443 -27.709524) (xy 78.740888 -27.66815) (xy 78.76159 -27.649932) (xy 78.772526 -27.640072)
			(xy 78.788598 -27.615411) (xy 78.796978 -27.587193) (xy 78.796971 -27.557758) (xy 78.788577 -27.529544)
			(xy 78.772493 -27.504891) (xy 78.76159 -27.494992) (xy 78.74087 -27.476791) (xy 78.704401 -27.43542)
			(xy 78.67427 -27.389228) (xy 78.651106 -27.339178) (xy 78.635391 -27.286314) (xy 78.627454 -27.231737)
			(xy 78.62697 -27.204162) (xy 78.627456 -27.176911) (xy 78.635212 -27.122963) (xy 78.650567 -27.070668)
			(xy 78.673209 -27.021091) (xy 78.702675 -26.975241) (xy 78.738366 -26.93405) (xy 78.779557 -26.898359)
			(xy 78.825407 -26.868893) (xy 78.874984 -26.846251) (xy 78.927279 -26.830896) (xy 78.981227 -26.82314)
			(xy 79.035729 -26.82314) (xy 79.089677 -26.830896) (xy 79.141972 -26.846251) (xy 79.191549 -26.868893)
			(xy 79.237399 -26.898359) (xy 79.27859 -26.93405) (xy 79.314281 -26.975241) (xy 79.343747 -27.021091)
			(xy 79.366389 -27.070668) (xy 79.381744 -27.122963) (xy 79.3895 -27.176911) (xy 79.389986 -27.204162)
			(xy 79.389499 -27.231736) (xy 79.381552 -27.286308) (xy 79.365831 -27.339168) (xy 79.342665 -27.389214)
			(xy 79.312536 -27.435404) (xy 79.276072 -27.476776) (xy 79.255366 -27.494992) (xy 79.24451 -27.504931)
			(xy 79.228442 -27.529571) (xy 79.220058 -27.557767) (xy 79.22005 -27.587184) (xy 79.228422 -27.615384)
			(xy 79.244478 -27.640032) (xy 79.255366 -27.649932) (xy 79.276089 -27.66813) (xy 79.31256 -27.709501)
			(xy 79.342691 -27.755693) (xy 79.365855 -27.805744) (xy 79.381569 -27.858609) (xy 79.389504 -27.913186)
			(xy 79.389986 -27.940762) (xy 79.389559 -27.967079) (xy 79.382334 -28.019214) (xy 79.368016 -28.069863)
			(xy 79.346877 -28.118065) (xy 79.319317 -28.162906) (xy 79.285858 -28.203537) (xy 79.266796 -28.221686)
			(xy 79.256814 -28.231534) (xy 79.242116 -28.255397) (xy 79.234473 -28.282361) (xy 79.234466 -28.310388)
			(xy 79.242095 -28.337356) (xy 79.256782 -28.361226) (xy 79.266796 -28.371038) (xy 79.285893 -28.389155)
			(xy 79.31937 -28.429779) (xy 79.346938 -28.474623) (xy 79.368073 -28.522834) (xy 79.382374 -28.573495)
			(xy 79.389568 -28.625641) (xy 79.389986 -28.651962) (xy 79.3895 -28.679213) (xy 79.381744 -28.733161)
			(xy 79.366389 -28.785456) (xy 79.343747 -28.835033) (xy 79.314281 -28.880883) (xy 79.27859 -28.922074)
			(xy 79.237399 -28.957765) (xy 79.191549 -28.987231) (xy 79.141972 -29.009873) (xy 79.089677 -29.025228)
			(xy 79.035729 -29.032984) (xy 78.981227 -29.032984) (xy 78.927279 -29.025228) (xy 78.874984 -29.009873)
			(xy 78.825407 -28.987231) (xy 78.779557 -28.957765) (xy 78.738366 -28.922074) (xy 78.702675 -28.880883)
			(xy 78.673209 -28.835033) (xy 78.650567 -28.785456) (xy 78.635212 -28.733161) (xy 78.627456 -28.679213)
			(xy 78.62697 -28.651962) (xy 76.88199 -28.651962) (xy 76.881504 -28.679213) (xy 76.873748 -28.733161)
			(xy 76.858393 -28.785456) (xy 76.835751 -28.835033) (xy 76.806285 -28.880883) (xy 76.770594 -28.922074)
			(xy 76.729403 -28.957765) (xy 76.683553 -28.987231) (xy 76.633976 -29.009873) (xy 76.581681 -29.025228)
			(xy 76.527733 -29.032984) (xy 76.473231 -29.032984) (xy 76.419283 -29.025228) (xy 76.366988 -29.009873)
			(xy 76.317411 -28.987231) (xy 76.271561 -28.957765) (xy 76.23037 -28.922074) (xy 76.194679 -28.880883)
			(xy 76.165213 -28.835033) (xy 76.142571 -28.785456) (xy 76.127216 -28.733161) (xy 76.11946 -28.679213)
			(xy 76.118974 -28.651962) (xy 65.982088 -28.651962) (xy 66.08191 -28.751784) (xy 66.099244 -28.769782)
			(xy 66.128609 -28.810211) (xy 66.1513 -28.854729) (xy 66.166762 -28.902244) (xy 66.174615 -28.951591)
			(xy 66.175128 -28.976574) (xy 66.175128 -29.390453) (xy 71.46464 -29.390453) (xy 71.46464 -29.335947)
			(xy 71.472397 -29.281996) (xy 71.487752 -29.229698) (xy 71.510394 -29.180117) (xy 71.539861 -29.134263)
			(xy 71.575554 -29.093069) (xy 71.616745 -29.057374) (xy 71.662598 -29.027904) (xy 71.712177 -29.00526)
			(xy 71.764474 -28.989901) (xy 71.818425 -28.982141) (xy 71.845678 -28.981654) (xy 71.874595 -28.982168)
			(xy 71.931768 -28.990895) (xy 71.986967 -29.008152) (xy 72.03893 -29.033545) (xy 72.086463 -29.06649)
			(xy 72.128479 -29.106233) (xy 72.146668 -29.12872) (xy 72.156565 -29.140525) (xy 72.181889 -29.158044)
			(xy 72.211282 -29.16722) (xy 72.242074 -29.16722) (xy 72.271467 -29.158044) (xy 72.296791 -29.140525)
			(xy 72.306688 -29.12872) (xy 72.324891 -29.106246) (xy 72.366908 -29.06651) (xy 72.41444 -29.033569)
			(xy 72.466399 -29.008179) (xy 72.521595 -28.990921) (xy 72.578763 -28.98219) (xy 72.607678 -28.981654)
			(xy 72.634929 -28.982192) (xy 72.688877 -28.989945) (xy 72.741172 -29.005298) (xy 72.79075 -29.027937)
			(xy 72.836602 -29.057401) (xy 72.877793 -29.093092) (xy 72.913485 -29.134281) (xy 72.942952 -29.18013)
			(xy 72.965594 -29.229707) (xy 72.98095 -29.282001) (xy 72.988707 -29.335949) (xy 72.988707 -29.390451)
			(xy 72.98095 -29.444399) (xy 72.965594 -29.496693) (xy 72.942952 -29.54627) (xy 72.913485 -29.592119)
			(xy 72.877793 -29.633308) (xy 72.836602 -29.668999) (xy 72.79075 -29.698463) (xy 72.741172 -29.721102)
			(xy 72.688877 -29.736455) (xy 72.634929 -29.744208) (xy 72.607678 -29.74467) (xy 72.578763 -29.744107)
			(xy 72.521593 -29.735389) (xy 72.466395 -29.71814) (xy 72.414433 -29.692757) (xy 72.366898 -29.659821)
			(xy 72.324879 -29.620086) (xy 72.306688 -29.597604) (xy 72.296791 -29.585799) (xy 72.271467 -29.56828)
			(xy 72.242074 -29.559104) (xy 72.211282 -29.559104) (xy 72.181889 -29.56828) (xy 72.156565 -29.585799)
			(xy 72.146668 -29.597604) (xy 72.128496 -29.620104) (xy 72.086472 -29.659838) (xy 72.038933 -29.692775)
			(xy 71.986968 -29.71816) (xy 71.931767 -29.735413) (xy 71.874595 -29.744137) (xy 71.845678 -29.74467)
			(xy 71.818425 -29.744259) (xy 71.764474 -29.736499) (xy 71.712177 -29.72114) (xy 71.662598 -29.698496)
			(xy 71.616745 -29.669026) (xy 71.575554 -29.633331) (xy 71.539861 -29.592137) (xy 71.510394 -29.546283)
			(xy 71.487752 -29.496702) (xy 71.472397 -29.444404) (xy 71.46464 -29.390453) (xy 66.175128 -29.390453)
			(xy 66.175128 -30.714188) (xy 66.559682 -30.714188) (xy 66.563753 -30.658566) (xy 66.575879 -30.604129)
			(xy 66.595802 -30.552038) (xy 66.623098 -30.503403) (xy 66.657184 -30.45926) (xy 66.697333 -30.420551)
			(xy 66.742691 -30.3881) (xy 66.792291 -30.362599) (xy 66.845075 -30.344592) (xy 66.899918 -30.334462)
			(xy 66.955652 -30.332425) (xy 67.011089 -30.338525) (xy 67.065046 -30.352631) (xy 67.116375 -30.374443)
			(xy 67.163981 -30.403497) (xy 67.206849 -30.439172) (xy 67.244066 -30.480709) (xy 67.274839 -30.527222)
			(xy 67.298511 -30.577719) (xy 67.314579 -30.631126) (xy 67.322699 -30.686302) (xy 67.323208 -30.714188)
			(xy 67.322699 -30.742074) (xy 67.320448 -30.757368) (xy 67.992496 -30.757368) (xy 67.996567 -30.701746)
			(xy 68.008693 -30.647309) (xy 68.028616 -30.595218) (xy 68.055912 -30.546583) (xy 68.089998 -30.50244)
			(xy 68.130147 -30.463731) (xy 68.175505 -30.43128) (xy 68.225105 -30.405779) (xy 68.277889 -30.387772)
			(xy 68.332732 -30.377642) (xy 68.388466 -30.375605) (xy 68.443903 -30.381705) (xy 68.49786 -30.395811)
			(xy 68.549189 -30.417623) (xy 68.596795 -30.446677) (xy 68.639663 -30.482352) (xy 68.67688 -30.523889)
			(xy 68.689014 -30.54223) (xy 69.67042 -30.54223) (xy 69.674491 -30.486608) (xy 69.686617 -30.432171)
			(xy 69.70654 -30.38008) (xy 69.733836 -30.331445) (xy 69.767922 -30.287302) (xy 69.808071 -30.248593)
			(xy 69.853429 -30.216142) (xy 69.903029 -30.190641) (xy 69.955813 -30.172634) (xy 70.010656 -30.162504)
			(xy 70.06639 -30.160467) (xy 70.121827 -30.166567) (xy 70.175784 -30.180673) (xy 70.227113 -30.202485)
			(xy 70.274719 -30.231539) (xy 70.317587 -30.267214) (xy 70.354804 -30.308751) (xy 70.385577 -30.355264)
			(xy 70.409249 -30.405761) (xy 70.425317 -30.459168) (xy 70.433437 -30.514344) (xy 70.433946 -30.54223)
			(xy 70.433437 -30.570116) (xy 70.425317 -30.625292) (xy 70.409249 -30.678699) (xy 70.385577 -30.729196)
			(xy 70.354804 -30.775709) (xy 70.317587 -30.817246) (xy 70.274719 -30.852921) (xy 70.227113 -30.881975)
			(xy 70.175784 -30.903787) (xy 70.121827 -30.917893) (xy 70.06639 -30.923993) (xy 70.010656 -30.921956)
			(xy 69.955813 -30.911826) (xy 69.903029 -30.893819) (xy 69.853429 -30.868318) (xy 69.808071 -30.835867)
			(xy 69.767922 -30.797158) (xy 69.733836 -30.753015) (xy 69.70654 -30.70438) (xy 69.686617 -30.652289)
			(xy 69.674491 -30.597852) (xy 69.67042 -30.54223) (xy 68.689014 -30.54223) (xy 68.707653 -30.570402)
			(xy 68.731325 -30.620899) (xy 68.747393 -30.674306) (xy 68.755513 -30.729482) (xy 68.756022 -30.757368)
			(xy 68.755513 -30.785254) (xy 68.747393 -30.84043) (xy 68.731325 -30.893837) (xy 68.707653 -30.944334)
			(xy 68.67688 -30.990847) (xy 68.639663 -31.032384) (xy 68.596795 -31.068059) (xy 68.549189 -31.097113)
			(xy 68.49786 -31.118925) (xy 68.443903 -31.133031) (xy 68.388466 -31.139131) (xy 68.332732 -31.137094)
			(xy 68.277889 -31.126964) (xy 68.225105 -31.108957) (xy 68.175505 -31.083456) (xy 68.130147 -31.051005)
			(xy 68.089998 -31.012296) (xy 68.055912 -30.968153) (xy 68.028616 -30.919518) (xy 68.008693 -30.867427)
			(xy 67.996567 -30.81299) (xy 67.992496 -30.757368) (xy 67.320448 -30.757368) (xy 67.314579 -30.79725)
			(xy 67.298511 -30.850657) (xy 67.274839 -30.901154) (xy 67.244066 -30.947667) (xy 67.206849 -30.989204)
			(xy 67.163981 -31.024879) (xy 67.116375 -31.053933) (xy 67.065046 -31.075745) (xy 67.011089 -31.089851)
			(xy 66.955652 -31.095951) (xy 66.899918 -31.093914) (xy 66.845075 -31.083784) (xy 66.792291 -31.065777)
			(xy 66.742691 -31.040276) (xy 66.697333 -31.007825) (xy 66.657184 -30.969116) (xy 66.623098 -30.924973)
			(xy 66.595802 -30.876338) (xy 66.575879 -30.824247) (xy 66.563753 -30.76981) (xy 66.559682 -30.714188)
			(xy 66.175128 -30.714188) (xy 66.175128 -31.433516) (xy 66.61658 -31.874968) (xy 67.159122 -31.874968)
			(xy 67.163193 -31.819346) (xy 67.175319 -31.764909) (xy 67.195242 -31.712818) (xy 67.222538 -31.664183)
			(xy 67.256624 -31.62004) (xy 67.296773 -31.581331) (xy 67.342131 -31.54888) (xy 67.391731 -31.523379)
			(xy 67.444515 -31.505372) (xy 67.499358 -31.495242) (xy 67.555092 -31.493205) (xy 67.610529 -31.499305)
			(xy 67.664486 -31.513411) (xy 67.715815 -31.535223) (xy 67.763421 -31.564277) (xy 67.806289 -31.599952)
			(xy 67.843506 -31.641489) (xy 67.874279 -31.688002) (xy 67.897951 -31.738499) (xy 67.914019 -31.791906)
			(xy 67.922139 -31.847082) (xy 67.922648 -31.874968) (xy 67.922139 -31.902854) (xy 67.914019 -31.95803)
			(xy 67.897951 -32.011437) (xy 67.874279 -32.061934) (xy 67.843506 -32.108447) (xy 67.806289 -32.149984)
			(xy 67.763421 -32.185659) (xy 67.715815 -32.214713) (xy 67.664486 -32.236525) (xy 67.610529 -32.250631)
			(xy 67.555092 -32.256731) (xy 67.499358 -32.254694) (xy 67.444515 -32.244564) (xy 67.391731 -32.226557)
			(xy 67.342131 -32.201056) (xy 67.296773 -32.168605) (xy 67.256624 -32.129896) (xy 67.222538 -32.085753)
			(xy 67.195242 -32.037118) (xy 67.175319 -31.985027) (xy 67.163193 -31.93059) (xy 67.159122 -31.874968)
			(xy 66.61658 -31.874968) (xy 67.65798 -32.916368) (xy 69.67042 -32.916368) (xy 69.674491 -32.860746)
			(xy 69.686617 -32.806309) (xy 69.70654 -32.754218) (xy 69.733836 -32.705583) (xy 69.767922 -32.66144)
			(xy 69.808071 -32.622731) (xy 69.853429 -32.59028) (xy 69.903029 -32.564779) (xy 69.955813 -32.546772)
			(xy 70.010656 -32.536642) (xy 70.06639 -32.534605) (xy 70.121827 -32.540705) (xy 70.175784 -32.554811)
			(xy 70.227113 -32.576623) (xy 70.274719 -32.605677) (xy 70.317587 -32.641352) (xy 70.354804 -32.682889)
			(xy 70.385577 -32.729402) (xy 70.409249 -32.779899) (xy 70.425317 -32.833306) (xy 70.433437 -32.888482)
			(xy 70.433946 -32.916368) (xy 70.433437 -32.944254) (xy 70.425317 -32.99943) (xy 70.409249 -33.052837)
			(xy 70.385577 -33.103334) (xy 70.354804 -33.149847) (xy 70.317587 -33.191384) (xy 70.274719 -33.227059)
			(xy 70.227113 -33.256113) (xy 70.175784 -33.277925) (xy 70.121827 -33.292031) (xy 70.06639 -33.298131)
			(xy 70.010656 -33.296094) (xy 69.955813 -33.285964) (xy 69.903029 -33.267957) (xy 69.853429 -33.242456)
			(xy 69.808071 -33.210005) (xy 69.767922 -33.171296) (xy 69.733836 -33.127153) (xy 69.70654 -33.078518)
			(xy 69.686617 -33.026427) (xy 69.674491 -32.97199) (xy 69.67042 -32.916368) (xy 67.65798 -32.916368)
			(xy 68.15074 -33.409128) (xy 80.75803 -33.409128) (xy 82.729832 -31.437326) (xy 82.729832 -19.70024)
			(xy 82.613246 -19.583654) (xy 82.60346 -19.574358) (xy 82.580048 -19.560939) (xy 82.553938 -19.554118)
			(xy 82.526954 -19.554372) (xy 82.500977 -19.561684) (xy 82.477822 -19.575542) (xy 82.459103 -19.59498)
			(xy 82.446127 -19.618641) (xy 82.442558 -19.63166) (xy 82.435511 -19.659067) (xy 82.41427 -19.711518)
			(xy 82.385512 -19.760256) (xy 82.34987 -19.804211) (xy 82.308125 -19.842418) (xy 82.261194 -19.874038)
			(xy 82.210106 -19.898378) (xy 82.155983 -19.914903) (xy 82.100013 -19.923252) (xy 82.071718 -19.92376)
			(xy 82.040819 -19.923169) (xy 81.979833 -19.913181) (xy 81.921258 -19.893482) (xy 81.893664 -19.879564)
			(xy 81.88045 -19.873264) (xy 81.851758 -19.867541) (xy 81.82262 -19.870174) (xy 81.795419 -19.880946)
			(xy 81.772379 -19.898976) (xy 81.755384 -19.92279) (xy 81.750154 -19.93646) (xy 81.741218 -19.961196)
			(xy 81.71745 -20.008115) (xy 81.687464 -20.051325) (xy 81.651828 -20.090007) (xy 81.611218 -20.123429)
			(xy 81.566402 -20.150958) (xy 81.518231 -20.172071) (xy 81.467616 -20.18637) (xy 81.415518 -20.193581)
			(xy 81.38922 -20.194016) (xy 81.361967 -20.193538) (xy 81.308015 -20.185784) (xy 81.255716 -20.17043)
			(xy 81.206134 -20.147789) (xy 81.160279 -20.118322) (xy 81.119085 -20.082629) (xy 81.08339 -20.041437)
			(xy 81.053921 -19.995583) (xy 81.031277 -19.946003) (xy 81.015921 -19.893705) (xy 81.008163 -19.839753)
			(xy 81.008163 -19.785247) (xy 81.015921 -19.731295) (xy 81.031277 -19.678997) (xy 81.053921 -19.629417)
			(xy 81.08339 -19.583563) (xy 81.119085 -19.542371) (xy 81.160279 -19.506678) (xy 81.206134 -19.477211)
			(xy 81.255716 -19.45457) (xy 81.308015 -19.439216) (xy 81.361967 -19.431462) (xy 81.38922 -19.431)
			(xy 81.420118 -19.431619) (xy 81.481103 -19.441596) (xy 81.539679 -19.461284) (xy 81.567274 -19.475196)
			(xy 81.58046 -19.481564) (xy 81.609164 -19.487283) (xy 81.638314 -19.484641) (xy 81.665523 -19.473856)
			(xy 81.688566 -19.45581) (xy 81.705558 -19.431978) (xy 81.710784 -19.4183) (xy 81.720089 -19.392565)
			(xy 81.745086 -19.343884) (xy 81.776786 -19.299275) (xy 81.814536 -19.259657) (xy 81.857562 -19.225841)
			(xy 81.904979 -19.198523) (xy 81.955815 -19.178263) (xy 81.98231 -19.171412) (xy 81.995323 -19.167848)
			(xy 82.018965 -19.154864) (xy 82.038385 -19.136145) (xy 82.052228 -19.112995) (xy 82.05953 -19.087029)
			(xy 82.059781 -19.060058) (xy 82.052965 -19.033961) (xy 82.039555 -19.010557) (xy 82.030316 -19.000724)
			(xy 81.976976 -18.947384) (xy 81.963006 -18.943828) (xy 81.935615 -18.936689) (xy 81.883136 -18.915482)
			(xy 81.834367 -18.886752) (xy 81.790378 -18.851132) (xy 81.752137 -18.809402) (xy 81.720482 -18.762479)
			(xy 81.696108 -18.711394) (xy 81.679551 -18.657268) (xy 81.671173 -18.601289) (xy 81.670652 -18.572988)
			(xy 81.671166 -18.545738) (xy 81.678924 -18.491794) (xy 81.694278 -18.439502) (xy 81.716918 -18.389927)
			(xy 81.746382 -18.344079) (xy 81.78207 -18.30289) (xy 81.823256 -18.267198) (xy 81.869103 -18.237731)
			(xy 81.918676 -18.215088) (xy 81.970966 -18.19973) (xy 82.02491 -18.191968) (xy 82.05216 -18.19148)
			(xy 82.080466 -18.192017) (xy 82.136459 -18.200356) (xy 82.190603 -18.216888) (xy 82.241705 -18.241247)
			(xy 82.288642 -18.272898) (xy 82.330379 -18.311144) (xy 82.365999 -18.355145) (xy 82.394718 -18.40393)
			(xy 82.415904 -18.456427) (xy 82.423 -18.483834) (xy 82.426556 -18.497804) (xy 83.27263 -19.343878)
			(xy 83.289948 -19.361892) (xy 83.319317 -19.402315) (xy 83.342014 -19.446828) (xy 83.357479 -19.494341)
			(xy 83.365334 -19.543685) (xy 83.365848 -19.568668) (xy 83.365848 -31.568898) (xy 83.365379 -31.593886)
			(xy 83.357553 -31.643246) (xy 83.342095 -31.690771) (xy 83.319385 -31.73529) (xy 83.289984 -31.775703)
			(xy 83.27263 -31.793688) (xy 81.114392 -33.951926) (xy 81.096391 -33.969257) (xy 81.055965 -33.998625)
			(xy 81.011448 -34.021319) (xy 80.963932 -34.036782) (xy 80.914585 -34.044633) (xy 80.889602 -34.045144)
			(xy 68.019168 -34.045144) (xy 67.994179 -34.044698) (xy 67.944818 -34.036867) (xy 67.897292 -34.021403)
			(xy 67.852774 -33.998688) (xy 67.812362 -33.969282) (xy 67.794378 -33.951926) (xy 65.63233 -31.789878)
			(xy 65.615032 -31.771846) (xy 65.585661 -31.731427) (xy 65.562962 -31.686918) (xy 65.547492 -31.63941)
			(xy 65.53963 -31.590069) (xy 65.539112 -31.565088) (xy 65.539112 -29.108146) (xy 65.138808 -28.707588)
			(xy 64.696086 -28.707588) (xy 64.672517 -28.722666) (xy 64.621896 -28.746496) (xy 64.568336 -28.762673)
			(xy 64.512987 -28.77085) (xy 64.485012 -28.771342) (xy 64.457761 -28.770812) (xy 64.403814 -28.763057)
			(xy 64.351519 -28.747703) (xy 64.301942 -28.725063) (xy 64.256091 -28.695598) (xy 64.214901 -28.659908)
			(xy 64.179209 -28.618718) (xy 64.149743 -28.572869) (xy 64.127101 -28.523292) (xy 64.111746 -28.470998)
			(xy 64.103989 -28.417051) (xy 62.566296 -28.417051) (xy 62.566296 -29.393388) (xy 64.111122 -29.393388)
			(xy 64.115193 -29.337766) (xy 64.127319 -29.283329) (xy 64.147242 -29.231238) (xy 64.174538 -29.182603)
			(xy 64.208624 -29.13846) (xy 64.248773 -29.099751) (xy 64.294131 -29.0673) (xy 64.343731 -29.041799)
			(xy 64.396515 -29.023792) (xy 64.451358 -29.013662) (xy 64.507092 -29.011625) (xy 64.562529 -29.017725)
			(xy 64.616486 -29.031831) (xy 64.667815 -29.053643) (xy 64.715421 -29.082697) (xy 64.758289 -29.118372)
			(xy 64.795506 -29.159909) (xy 64.826279 -29.206422) (xy 64.849951 -29.256919) (xy 64.866019 -29.310326)
			(xy 64.874139 -29.365502) (xy 64.874648 -29.393388) (xy 64.874139 -29.421274) (xy 64.866019 -29.47645)
			(xy 64.849951 -29.529857) (xy 64.826279 -29.580354) (xy 64.795506 -29.626867) (xy 64.758289 -29.668404)
			(xy 64.715421 -29.704079) (xy 64.667815 -29.733133) (xy 64.616486 -29.754945) (xy 64.562529 -29.769051)
			(xy 64.507092 -29.775151) (xy 64.451358 -29.773114) (xy 64.396515 -29.762984) (xy 64.343731 -29.744977)
			(xy 64.294131 -29.719476) (xy 64.248773 -29.687025) (xy 64.208624 -29.648316) (xy 64.174538 -29.604173)
			(xy 64.147242 -29.555538) (xy 64.127319 -29.503447) (xy 64.115193 -29.44901) (xy 64.111122 -29.393388)
			(xy 62.566296 -29.393388) (xy 62.566296 -32.54756) (xy 64.613536 -34.5948) (xy 67.20078 -34.5948)
			(xy 67.23076 -34.595357) (xy 67.289983 -34.604739) (xy 67.347007 -34.623274) (xy 67.400427 -34.650505)
			(xy 67.448927 -34.685762) (xy 67.470528 -34.70656) (xy 67.690746 -34.927032) (xy 82.658712 -34.927032)
			(xy 82.681374 -34.913586) (xy 82.729615 -34.892383) (xy 82.780318 -34.878035) (xy 82.832516 -34.870818)
			(xy 82.858864 -34.87039) (xy 82.869427 -34.870448) (xy 82.890521 -34.871592) (xy 82.901028 -34.872676)
			(xy 82.925158 -34.87547) (xy 84.56168 -33.238948) (xy 84.56168 -16.841978) (xy 81.52384 -13.804138)
			(xy 74.689716 -13.804138) (xy 74.677778 -13.838174) (xy 74.668699 -13.862684) (xy 74.644782 -13.90916)
			(xy 74.614742 -13.951934) (xy 74.579143 -13.990205) (xy 74.538651 -14.023256) (xy 74.494025 -14.050468)
			(xy 74.4461 -14.071332) (xy 74.395776 -14.085455) (xy 74.343994 -14.092573) (xy 74.31786 -14.092936)
			(xy 74.288458 -14.092398) (xy 74.230348 -14.083385) (xy 74.17431 -14.065562) (xy 74.121669 -14.039353)
			(xy 74.073674 -14.005377) (xy 74.031459 -13.96444) (xy 74.013314 -13.941298) (xy 74.004199 -13.929984)
			(xy 73.980883 -13.912667) (xy 73.95363 -13.902631) (xy 73.924652 -13.90069) (xy 73.896303 -13.907002)
			(xy 73.870886 -13.921055) (xy 73.850466 -13.941707) (xy 73.843134 -13.954252) (xy 73.828695 -13.979744)
			(xy 73.793217 -14.026365) (xy 73.751032 -14.067018) (xy 73.703132 -14.100749) (xy 73.65064 -14.126765)
			(xy 73.59479 -14.144456) (xy 73.536893 -14.153407) (xy 73.5076 -14.153896) (xy 73.481293 -14.153461)
			(xy 73.429178 -14.146241) (xy 73.378551 -14.131924) (xy 73.330373 -14.110783) (xy 73.285559 -14.083218)
			(xy 73.24496 -14.049754) (xy 73.209348 -14.011026) (xy 73.179398 -13.967769) (xy 73.155681 -13.920806)
			(xy 73.138645 -13.871027) (xy 73.133204 -13.845286) (xy 73.125076 -13.804138) (xy 70.95871 -13.804138)
			(xy 70.69582 -14.067028) (xy 70.69582 -16.259302) (xy 77.27823 -16.259302) (xy 77.278687 -16.231727)
			(xy 77.286639 -16.177153) (xy 77.302366 -16.124293) (xy 77.325537 -16.074247) (xy 77.355672 -16.028057)
			(xy 77.392142 -15.986687) (xy 77.41285 -15.968472) (xy 77.423749 -15.958574) (xy 77.439829 -15.933925)
			(xy 77.448218 -15.905716) (xy 77.448218 -15.876286) (xy 77.439831 -15.848077) (xy 77.423751 -15.823428)
			(xy 77.41285 -15.813532) (xy 77.392141 -15.795319) (xy 77.355673 -15.753949) (xy 77.325542 -15.707759)
			(xy 77.302376 -15.657712) (xy 77.286658 -15.60485) (xy 77.278717 -15.550276) (xy 77.27823 -15.522702)
			(xy 77.278716 -15.495451) (xy 77.286472 -15.441503) (xy 77.301827 -15.389208) (xy 77.324469 -15.339631)
			(xy 77.353935 -15.293781) (xy 77.389626 -15.25259) (xy 77.430817 -15.216899) (xy 77.476667 -15.187433)
			(xy 77.526244 -15.164791) (xy 77.578539 -15.149436) (xy 77.632487 -15.14168) (xy 77.686989 -15.14168)
			(xy 77.740937 -15.149436) (xy 77.793232 -15.164791) (xy 77.842809 -15.187433) (xy 77.888659 -15.216899)
			(xy 77.92985 -15.25259) (xy 77.965541 -15.293781) (xy 77.995007 -15.339631) (xy 78.017649 -15.389208)
			(xy 78.033004 -15.441503) (xy 78.04076 -15.495451) (xy 78.041246 -15.522702) (xy 78.040801 -15.550277)
			(xy 78.032847 -15.604852) (xy 78.017119 -15.657713) (xy 77.993945 -15.707759) (xy 77.963808 -15.753948)
			(xy 77.927336 -15.795318) (xy 77.906626 -15.813532) (xy 77.895725 -15.823427) (xy 77.879649 -15.848078)
			(xy 77.871263 -15.876287) (xy 77.871264 -15.905716) (xy 77.87965 -15.933925) (xy 77.895727 -15.958574)
			(xy 77.906626 -15.968472) (xy 77.927332 -15.986689) (xy 77.963802 -16.028057) (xy 77.993934 -16.074246)
			(xy 78.0171 -16.124293) (xy 78.032818 -16.177154) (xy 78.04076 -16.231728) (xy 78.041246 -16.259302)
			(xy 78.04076 -16.286553) (xy 78.033004 -16.340501) (xy 78.017649 -16.392796) (xy 77.995007 -16.442373)
			(xy 77.965541 -16.488223) (xy 77.92985 -16.529414) (xy 77.888659 -16.565105) (xy 77.842809 -16.594571)
			(xy 77.793232 -16.617213) (xy 77.740937 -16.632568) (xy 77.686989 -16.640324) (xy 77.632487 -16.640324)
			(xy 77.578539 -16.632568) (xy 77.526244 -16.617213) (xy 77.476667 -16.594571) (xy 77.430817 -16.565105)
			(xy 77.389626 -16.529414) (xy 77.353935 -16.488223) (xy 77.324469 -16.442373) (xy 77.301827 -16.392796)
			(xy 77.286472 -16.340501) (xy 77.278716 -16.286553) (xy 77.27823 -16.259302) (xy 70.69582 -16.259302)
			(xy 70.69582 -18.160746) (xy 74.02525 -18.160746) (xy 74.029321 -18.105124) (xy 74.041447 -18.050687)
			(xy 74.06137 -17.998596) (xy 74.088666 -17.949961) (xy 74.122752 -17.905818) (xy 74.162901 -17.867109)
			(xy 74.208259 -17.834658) (xy 74.257859 -17.809157) (xy 74.310643 -17.79115) (xy 74.365486 -17.78102)
			(xy 74.42122 -17.778983) (xy 74.476657 -17.785083) (xy 74.530614 -17.799189) (xy 74.581943 -17.821001)
			(xy 74.629549 -17.850055) (xy 74.672417 -17.88573) (xy 74.709634 -17.927267) (xy 74.740407 -17.97378)
			(xy 74.764079 -18.024277) (xy 74.780147 -18.077684) (xy 74.788267 -18.13286) (xy 74.788776 -18.160746)
			(xy 74.788461 -18.178018) (xy 77.15072 -18.178018) (xy 77.154791 -18.122396) (xy 77.166917 -18.067959)
			(xy 77.18684 -18.015868) (xy 77.214136 -17.967233) (xy 77.248222 -17.92309) (xy 77.288371 -17.884381)
			(xy 77.333729 -17.85193) (xy 77.383329 -17.826429) (xy 77.436113 -17.808422) (xy 77.490956 -17.798292)
			(xy 77.54669 -17.796255) (xy 77.602127 -17.802355) (xy 77.656084 -17.816461) (xy 77.707413 -17.838273)
			(xy 77.755019 -17.867327) (xy 77.797887 -17.903002) (xy 77.835104 -17.944539) (xy 77.865877 -17.991052)
			(xy 77.889549 -18.041549) (xy 77.905617 -18.094956) (xy 77.913737 -18.150132) (xy 77.914246 -18.178018)
			(xy 77.913737 -18.205904) (xy 77.909019 -18.237962) (xy 79.54137 -18.237962) (xy 79.541889 -18.210389)
			(xy 79.549832 -18.155819) (xy 79.565547 -18.102961) (xy 79.588707 -18.052915) (xy 79.61883 -18.006724)
			(xy 79.655288 -17.96535) (xy 79.67599 -17.947132) (xy 79.686926 -17.937272) (xy 79.702998 -17.912611)
			(xy 79.711378 -17.884393) (xy 79.711371 -17.854958) (xy 79.702977 -17.826744) (xy 79.686893 -17.802091)
			(xy 79.67599 -17.792192) (xy 79.65527 -17.773991) (xy 79.618801 -17.73262) (xy 79.58867 -17.686428)
			(xy 79.565506 -17.636378) (xy 79.549791 -17.583514) (xy 79.541854 -17.528937) (xy 79.54137 -17.501362)
			(xy 79.541856 -17.474111) (xy 79.549612 -17.420163) (xy 79.564967 -17.367868) (xy 79.587609 -17.318291)
			(xy 79.617075 -17.272441) (xy 79.652766 -17.23125) (xy 79.693957 -17.195559) (xy 79.739807 -17.166093)
			(xy 79.789384 -17.143451) (xy 79.841679 -17.128096) (xy 79.895627 -17.12034) (xy 79.950129 -17.12034)
			(xy 80.004077 -17.128096) (xy 80.056372 -17.143451) (xy 80.105949 -17.166093) (xy 80.151799 -17.195559)
			(xy 80.19299 -17.23125) (xy 80.228681 -17.272441) (xy 80.258147 -17.318291) (xy 80.280789 -17.367868)
			(xy 80.296144 -17.420163) (xy 80.3039 -17.474111) (xy 80.304386 -17.501362) (xy 80.303899 -17.528936)
			(xy 80.295952 -17.583508) (xy 80.280231 -17.636368) (xy 80.257065 -17.686414) (xy 80.226936 -17.732604)
			(xy 80.190472 -17.773976) (xy 80.169766 -17.792192) (xy 80.15891 -17.802131) (xy 80.142842 -17.826771)
			(xy 80.134458 -17.854967) (xy 80.13445 -17.884384) (xy 80.142822 -17.912584) (xy 80.158878 -17.937232)
			(xy 80.169766 -17.947132) (xy 80.190489 -17.96533) (xy 80.22696 -18.006701) (xy 80.257091 -18.052893)
			(xy 80.280255 -18.102944) (xy 80.295969 -18.155809) (xy 80.303904 -18.210386) (xy 80.304386 -18.237962)
			(xy 80.3039 -18.265213) (xy 80.296144 -18.319161) (xy 80.280789 -18.371456) (xy 80.258147 -18.421033)
			(xy 80.228681 -18.466883) (xy 80.19299 -18.508074) (xy 80.151799 -18.543765) (xy 80.105949 -18.573231)
			(xy 80.056372 -18.595873) (xy 80.004077 -18.611228) (xy 79.950129 -18.618984) (xy 79.895627 -18.618984)
			(xy 79.841679 -18.611228) (xy 79.789384 -18.595873) (xy 79.739807 -18.573231) (xy 79.693957 -18.543765)
			(xy 79.652766 -18.508074) (xy 79.617075 -18.466883) (xy 79.587609 -18.421033) (xy 79.564967 -18.371456)
			(xy 79.549612 -18.319161) (xy 79.541856 -18.265213) (xy 79.54137 -18.237962) (xy 77.909019 -18.237962)
			(xy 77.905617 -18.26108) (xy 77.889549 -18.314487) (xy 77.865877 -18.364984) (xy 77.835104 -18.411497)
			(xy 77.797887 -18.453034) (xy 77.755019 -18.488709) (xy 77.707413 -18.517763) (xy 77.656084 -18.539575)
			(xy 77.602127 -18.553681) (xy 77.54669 -18.559781) (xy 77.490956 -18.557744) (xy 77.436113 -18.547614)
			(xy 77.383329 -18.529607) (xy 77.333729 -18.504106) (xy 77.288371 -18.471655) (xy 77.248222 -18.432946)
			(xy 77.214136 -18.388803) (xy 77.18684 -18.340168) (xy 77.166917 -18.288077) (xy 77.154791 -18.23364)
			(xy 77.15072 -18.178018) (xy 74.788461 -18.178018) (xy 74.788267 -18.188632) (xy 74.780147 -18.243808)
			(xy 74.764079 -18.297215) (xy 74.740407 -18.347712) (xy 74.709634 -18.394225) (xy 74.672417 -18.435762)
			(xy 74.629549 -18.471437) (xy 74.581943 -18.500491) (xy 74.530614 -18.522303) (xy 74.476657 -18.536409)
			(xy 74.42122 -18.542509) (xy 74.365486 -18.540472) (xy 74.310643 -18.530342) (xy 74.257859 -18.512335)
			(xy 74.208259 -18.486834) (xy 74.162901 -18.454383) (xy 74.122752 -18.415674) (xy 74.088666 -18.371531)
			(xy 74.06137 -18.322896) (xy 74.041447 -18.270805) (xy 74.029321 -18.216368) (xy 74.02525 -18.160746)
			(xy 70.69582 -18.160746) (xy 70.69582 -19.220942) (xy 76.404722 -19.220942) (xy 76.408793 -19.16532)
			(xy 76.420919 -19.110883) (xy 76.440842 -19.058792) (xy 76.468138 -19.010157) (xy 76.502224 -18.966014)
			(xy 76.542373 -18.927305) (xy 76.587731 -18.894854) (xy 76.637331 -18.869353) (xy 76.690115 -18.851346)
			(xy 76.744958 -18.841216) (xy 76.800692 -18.839179) (xy 76.856129 -18.845279) (xy 76.910086 -18.859385)
			(xy 76.961415 -18.881197) (xy 77.009021 -18.910251) (xy 77.051889 -18.945926) (xy 77.089106 -18.987463)
			(xy 77.119879 -19.033976) (xy 77.143551 -19.084473) (xy 77.159619 -19.13788) (xy 77.167739 -19.193056)
			(xy 77.168248 -19.220942) (xy 77.167739 -19.248828) (xy 77.163657 -19.276568) (xy 78.474568 -19.276568)
			(xy 78.478639 -19.220946) (xy 78.490765 -19.166509) (xy 78.510688 -19.114418) (xy 78.537984 -19.065783)
			(xy 78.57207 -19.02164) (xy 78.612219 -18.982931) (xy 78.657577 -18.95048) (xy 78.707177 -18.924979)
			(xy 78.759961 -18.906972) (xy 78.814804 -18.896842) (xy 78.870538 -18.894805) (xy 78.925975 -18.900905)
			(xy 78.979932 -18.915011) (xy 79.031261 -18.936823) (xy 79.078867 -18.965877) (xy 79.121735 -19.001552)
			(xy 79.158952 -19.043089) (xy 79.189725 -19.089602) (xy 79.213397 -19.140099) (xy 79.229465 -19.193506)
			(xy 79.237585 -19.248682) (xy 79.238094 -19.276568) (xy 79.237585 -19.304454) (xy 79.229465 -19.35963)
			(xy 79.213397 -19.413037) (xy 79.189725 -19.463534) (xy 79.158952 -19.510047) (xy 79.121735 -19.551584)
			(xy 79.078867 -19.587259) (xy 79.031261 -19.616313) (xy 78.979932 -19.638125) (xy 78.925975 -19.652231)
			(xy 78.870538 -19.658331) (xy 78.814804 -19.656294) (xy 78.759961 -19.646164) (xy 78.707177 -19.628157)
			(xy 78.657577 -19.602656) (xy 78.612219 -19.570205) (xy 78.57207 -19.531496) (xy 78.537984 -19.487353)
			(xy 78.510688 -19.438718) (xy 78.490765 -19.386627) (xy 78.478639 -19.33219) (xy 78.474568 -19.276568)
			(xy 77.163657 -19.276568) (xy 77.159619 -19.304004) (xy 77.143551 -19.357411) (xy 77.119879 -19.407908)
			(xy 77.089106 -19.454421) (xy 77.051889 -19.495958) (xy 77.009021 -19.531633) (xy 76.961415 -19.560687)
			(xy 76.910086 -19.582499) (xy 76.856129 -19.596605) (xy 76.800692 -19.602705) (xy 76.744958 -19.600668)
			(xy 76.690115 -19.590538) (xy 76.637331 -19.572531) (xy 76.587731 -19.54703) (xy 76.542373 -19.514579)
			(xy 76.502224 -19.47587) (xy 76.468138 -19.431727) (xy 76.440842 -19.383092) (xy 76.420919 -19.331001)
			(xy 76.408793 -19.276564) (xy 76.404722 -19.220942) (xy 70.69582 -19.220942) (xy 70.69582 -20.944078)
			(xy 76.224382 -20.944078) (xy 76.228453 -20.888456) (xy 76.240579 -20.834019) (xy 76.260502 -20.781928)
			(xy 76.287798 -20.733293) (xy 76.321884 -20.68915) (xy 76.362033 -20.650441) (xy 76.407391 -20.61799)
			(xy 76.456991 -20.592489) (xy 76.509775 -20.574482) (xy 76.564618 -20.564352) (xy 76.620352 -20.562315)
			(xy 76.675789 -20.568415) (xy 76.729746 -20.582521) (xy 76.781075 -20.604333) (xy 76.828681 -20.633387)
			(xy 76.871549 -20.669062) (xy 76.908766 -20.710599) (xy 76.939539 -20.757112) (xy 76.963211 -20.807609)
			(xy 76.979279 -20.861016) (xy 76.987399 -20.916192) (xy 76.987908 -20.944078) (xy 76.987399 -20.971964)
			(xy 76.979279 -21.02714) (xy 76.963211 -21.080547) (xy 76.939539 -21.131044) (xy 76.908766 -21.177557)
			(xy 76.871549 -21.219094) (xy 76.828681 -21.254769) (xy 76.781075 -21.283823) (xy 76.729746 -21.305635)
			(xy 76.675789 -21.319741) (xy 76.620352 -21.325841) (xy 76.564618 -21.323804) (xy 76.509775 -21.313674)
			(xy 76.456991 -21.295667) (xy 76.407391 -21.270166) (xy 76.362033 -21.237715) (xy 76.321884 -21.199006)
			(xy 76.287798 -21.154863) (xy 76.260502 -21.106228) (xy 76.240579 -21.054137) (xy 76.228453 -20.9997)
			(xy 76.224382 -20.944078) (xy 70.69582 -20.944078) (xy 70.69582 -21.416772) (xy 81.628742 -21.416772)
			(xy 81.62926 -21.387965) (xy 81.637934 -21.331007) (xy 81.655066 -21.275999) (xy 81.680266 -21.224189)
			(xy 81.712965 -21.176752) (xy 81.752418 -21.134766) (xy 81.79773 -21.099183) (xy 81.822544 -21.08454)
			(xy 81.834696 -21.07709) (xy 81.854691 -21.056799) (xy 81.86829 -21.031767) (xy 81.874431 -21.003949)
			(xy 81.872634 -20.975518) (xy 81.86304 -20.948695) (xy 81.846397 -20.925574) (xy 81.835498 -20.916392)
			(xy 81.813248 -20.898197) (xy 81.773976 -20.856231) (xy 81.741439 -20.808852) (xy 81.716371 -20.757131)
			(xy 81.699339 -20.702237) (xy 81.690727 -20.64541) (xy 81.69021 -20.616672) (xy 81.690696 -20.589421)
			(xy 81.698452 -20.535473) (xy 81.713807 -20.483178) (xy 81.736449 -20.433601) (xy 81.765915 -20.387751)
			(xy 81.801606 -20.34656) (xy 81.842797 -20.310869) (xy 81.888647 -20.281403) (xy 81.938224 -20.258761)
			(xy 81.990519 -20.243406) (xy 82.044467 -20.23565) (xy 82.098969 -20.23565) (xy 82.152917 -20.243406)
			(xy 82.205212 -20.258761) (xy 82.254789 -20.281403) (xy 82.300639 -20.310869) (xy 82.34183 -20.34656)
			(xy 82.377521 -20.387751) (xy 82.406987 -20.433601) (xy 82.429629 -20.483178) (xy 82.444984 -20.535473)
			(xy 82.45274 -20.589421) (xy 82.453226 -20.616672) (xy 82.452709 -20.645478) (xy 82.44403 -20.702435)
			(xy 82.426896 -20.757441) (xy 82.401694 -20.80925) (xy 82.368997 -20.856686) (xy 82.329546 -20.898674)
			(xy 82.284236 -20.934259) (xy 82.259424 -20.948904) (xy 82.247234 -20.956295) (xy 82.227242 -20.976601)
			(xy 82.213648 -21.001645) (xy 82.207513 -21.029473) (xy 82.209317 -21.057911) (xy 82.218918 -21.084741)
			(xy 82.235567 -21.107867) (xy 82.24647 -21.117052) (xy 82.268707 -21.135261) (xy 82.307977 -21.177227)
			(xy 82.340514 -21.224603) (xy 82.365583 -21.276321) (xy 82.382619 -21.331212) (xy 82.391237 -21.388035)
			(xy 82.391758 -21.416772) (xy 82.391272 -21.444023) (xy 82.383516 -21.497971) (xy 82.368161 -21.550266)
			(xy 82.345519 -21.599843) (xy 82.316053 -21.645693) (xy 82.280362 -21.686884) (xy 82.239171 -21.722575)
			(xy 82.193321 -21.752041) (xy 82.143744 -21.774683) (xy 82.091449 -21.790038) (xy 82.037501 -21.797794)
			(xy 81.982999 -21.797794) (xy 81.929051 -21.790038) (xy 81.876756 -21.774683) (xy 81.827179 -21.752041)
			(xy 81.781329 -21.722575) (xy 81.740138 -21.686884) (xy 81.704447 -21.645693) (xy 81.674981 -21.599843)
			(xy 81.652339 -21.550266) (xy 81.636984 -21.497971) (xy 81.629228 -21.444023) (xy 81.628742 -21.416772)
			(xy 70.69582 -21.416772) (xy 70.69582 -22.581362) (xy 74.63866 -22.581362) (xy 74.642731 -22.52574)
			(xy 74.654857 -22.471303) (xy 74.67478 -22.419212) (xy 74.702076 -22.370577) (xy 74.736162 -22.326434)
			(xy 74.776311 -22.287725) (xy 74.821669 -22.255274) (xy 74.871269 -22.229773) (xy 74.924053 -22.211766)
			(xy 74.978896 -22.201636) (xy 75.03463 -22.199599) (xy 75.090067 -22.205699) (xy 75.144024 -22.219805)
			(xy 75.195353 -22.241617) (xy 75.242959 -22.270671) (xy 75.285827 -22.306346) (xy 75.323044 -22.347883)
			(xy 75.353817 -22.394396) (xy 75.377489 -22.444893) (xy 75.393557 -22.4983) (xy 75.401677 -22.553476)
			(xy 75.402186 -22.581362) (xy 75.401677 -22.609248) (xy 75.393557 -22.664424) (xy 75.377489 -22.717831)
			(xy 75.357227 -22.761053) (xy 79.21164 -22.761053) (xy 79.21164 -22.706547) (xy 79.219397 -22.652596)
			(xy 79.234752 -22.600298) (xy 79.257394 -22.550717) (xy 79.286861 -22.504863) (xy 79.322554 -22.463669)
			(xy 79.363745 -22.427974) (xy 79.409598 -22.398504) (xy 79.459177 -22.37586) (xy 79.511474 -22.360501)
			(xy 79.565425 -22.352741) (xy 79.592678 -22.352254) (xy 79.618793 -22.352689) (xy 79.670533 -22.35983)
			(xy 79.720814 -22.373967) (xy 79.768694 -22.394835) (xy 79.813277 -22.422045) (xy 79.853729 -22.455085)
			(xy 79.871824 -22.47392) (xy 79.881243 -22.483397) (xy 79.903906 -22.497534) (xy 79.929458 -22.505316)
			(xy 79.956154 -22.506211) (xy 79.98217 -22.500157) (xy 80.005729 -22.487569) (xy 80.025221 -22.469307)
			(xy 80.032606 -22.458172) (xy 80.047649 -22.43498) (xy 80.083338 -22.392766) (xy 80.124745 -22.356144)
			(xy 80.171003 -22.325881) (xy 80.221144 -22.302609) (xy 80.274118 -22.286817) (xy 80.328817 -22.278834)
			(xy 80.356456 -22.27834) (xy 80.383714 -22.278704) (xy 80.437677 -22.286457) (xy 80.489987 -22.301811)
			(xy 80.539579 -22.324454) (xy 80.585443 -22.353924) (xy 80.626646 -22.389623) (xy 80.662349 -22.430822)
			(xy 80.691825 -22.476683) (xy 80.714474 -22.526272) (xy 80.729834 -22.57858) (xy 80.737593 -22.632542)
			(xy 80.737593 -22.687058) (xy 80.729834 -22.74102) (xy 80.714474 -22.793328) (xy 80.691825 -22.842917)
			(xy 80.662349 -22.888778) (xy 80.626646 -22.929977) (xy 80.585443 -22.965676) (xy 80.539579 -22.995146)
			(xy 80.489987 -23.017789) (xy 80.437677 -23.033143) (xy 80.383714 -23.040896) (xy 80.356456 -23.041356)
			(xy 80.33034 -23.040961) (xy 80.278598 -23.033812) (xy 80.228317 -23.019667) (xy 80.180437 -22.998791)
			(xy 80.135854 -22.971575) (xy 80.095404 -22.938528) (xy 80.07731 -22.91969) (xy 80.067857 -22.910248)
			(xy 80.045203 -22.896108) (xy 80.019659 -22.888321) (xy 79.992969 -22.887421) (xy 79.966958 -22.893469)
			(xy 79.943403 -22.90605) (xy 79.923913 -22.924307) (xy 79.916528 -22.935438) (xy 79.901532 -22.958663)
			(xy 79.865835 -23.000875) (xy 79.82442 -23.037495) (xy 79.778154 -23.067754) (xy 79.728005 -23.091021)
			(xy 79.675024 -23.106806) (xy 79.620319 -23.114781) (xy 79.592678 -23.11527) (xy 79.565425 -23.114859)
			(xy 79.511474 -23.107099) (xy 79.459177 -23.09174) (xy 79.409598 -23.069096) (xy 79.363745 -23.039626)
			(xy 79.322554 -23.003931) (xy 79.286861 -22.962737) (xy 79.257394 -22.916883) (xy 79.234752 -22.867302)
			(xy 79.219397 -22.815004) (xy 79.21164 -22.761053) (xy 75.357227 -22.761053) (xy 75.353817 -22.768328)
			(xy 75.323044 -22.814841) (xy 75.285827 -22.856378) (xy 75.242959 -22.892053) (xy 75.195353 -22.921107)
			(xy 75.144024 -22.942919) (xy 75.090067 -22.957025) (xy 75.03463 -22.963125) (xy 74.978896 -22.961088)
			(xy 74.924053 -22.950958) (xy 74.871269 -22.932951) (xy 74.821669 -22.90745) (xy 74.776311 -22.874999)
			(xy 74.736162 -22.83629) (xy 74.702076 -22.792147) (xy 74.67478 -22.743512) (xy 74.654857 -22.691421)
			(xy 74.642731 -22.636984) (xy 74.63866 -22.581362) (xy 70.69582 -22.581362) (xy 70.69582 -24.313896)
			(xy 77.804262 -24.313896) (xy 77.808333 -24.258274) (xy 77.820459 -24.203837) (xy 77.840382 -24.151746)
			(xy 77.867678 -24.103111) (xy 77.901764 -24.058968) (xy 77.941913 -24.020259) (xy 77.987271 -23.987808)
			(xy 78.036871 -23.962307) (xy 78.089655 -23.9443) (xy 78.144498 -23.93417) (xy 78.200232 -23.932133)
			(xy 78.255669 -23.938233) (xy 78.309626 -23.952339) (xy 78.360955 -23.974151) (xy 78.408561 -24.003205)
			(xy 78.451429 -24.03888) (xy 78.488646 -24.080417) (xy 78.519419 -24.12693) (xy 78.543091 -24.177427)
			(xy 78.559159 -24.230834) (xy 78.567279 -24.28601) (xy 78.567788 -24.313896) (xy 78.567279 -24.341782)
			(xy 78.559159 -24.396958) (xy 78.543091 -24.450365) (xy 78.519419 -24.500862) (xy 78.488646 -24.547375)
			(xy 78.45228 -24.587962) (xy 79.23606 -24.587962) (xy 79.240131 -24.53234) (xy 79.252257 -24.477903)
			(xy 79.27218 -24.425812) (xy 79.299476 -24.377177) (xy 79.333562 -24.333034) (xy 79.373711 -24.294325)
			(xy 79.419069 -24.261874) (xy 79.468669 -24.236373) (xy 79.521453 -24.218366) (xy 79.576296 -24.208236)
			(xy 79.63203 -24.206199) (xy 79.687467 -24.212299) (xy 79.741424 -24.226405) (xy 79.792753 -24.248217)
			(xy 79.840359 -24.277271) (xy 79.883227 -24.312946) (xy 79.920444 -24.354483) (xy 79.951217 -24.400996)
			(xy 79.974889 -24.451493) (xy 79.990957 -24.5049) (xy 79.999077 -24.560076) (xy 79.999586 -24.587962)
			(xy 79.999077 -24.615848) (xy 79.990957 -24.671024) (xy 79.974889 -24.724431) (xy 79.951217 -24.774928)
			(xy 79.920444 -24.821441) (xy 79.883227 -24.862978) (xy 79.840359 -24.898653) (xy 79.792753 -24.927707)
			(xy 79.741424 -24.949519) (xy 79.687467 -24.963625) (xy 79.63203 -24.969725) (xy 79.576296 -24.967688)
			(xy 79.521453 -24.957558) (xy 79.468669 -24.939551) (xy 79.419069 -24.91405) (xy 79.373711 -24.881599)
			(xy 79.333562 -24.84289) (xy 79.299476 -24.798747) (xy 79.27218 -24.750112) (xy 79.252257 -24.698021)
			(xy 79.240131 -24.643584) (xy 79.23606 -24.587962) (xy 78.45228 -24.587962) (xy 78.451429 -24.588912)
			(xy 78.408561 -24.624587) (xy 78.360955 -24.653641) (xy 78.309626 -24.675453) (xy 78.255669 -24.689559)
			(xy 78.200232 -24.695659) (xy 78.144498 -24.693622) (xy 78.089655 -24.683492) (xy 78.036871 -24.665485)
			(xy 77.987271 -24.639984) (xy 77.941913 -24.607533) (xy 77.901764 -24.568824) (xy 77.867678 -24.524681)
			(xy 77.840382 -24.476046) (xy 77.820459 -24.423955) (xy 77.808333 -24.369518) (xy 77.804262 -24.313896)
			(xy 70.69582 -24.313896) (xy 70.69582 -25.227788) (xy 69.88683 -26.036778) (xy 60.06465 -26.036778)
			(xy 59.403375 -26.698053) (xy 72.09964 -26.698053) (xy 72.09964 -26.643547) (xy 72.107397 -26.589596)
			(xy 72.122752 -26.537298) (xy 72.145394 -26.487717) (xy 72.174861 -26.441863) (xy 72.210554 -26.400669)
			(xy 72.251745 -26.364974) (xy 72.297598 -26.335504) (xy 72.347177 -26.31286) (xy 72.399474 -26.297501)
			(xy 72.453425 -26.289741) (xy 72.480678 -26.289254) (xy 72.507935 -26.289747) (xy 72.561894 -26.297511)
			(xy 72.6142 -26.312871) (xy 72.66379 -26.335513) (xy 72.709656 -26.364978) (xy 72.750865 -26.400666)
			(xy 72.786579 -26.441853) (xy 72.801734 -26.464514) (xy 72.810015 -26.476441) (xy 72.831951 -26.495445)
			(xy 72.858351 -26.5075) (xy 72.887078 -26.51163) (xy 72.915805 -26.5075) (xy 72.942205 -26.495445)
			(xy 72.964141 -26.476441) (xy 72.972422 -26.464514) (xy 72.987539 -26.441825) (xy 73.023252 -26.400629)
			(xy 73.064464 -26.364935) (xy 73.110336 -26.335469) (xy 73.159935 -26.312831) (xy 73.21225 -26.297482)
			(xy 73.266218 -26.289735) (xy 73.293478 -26.289254) (xy 73.320729 -26.289792) (xy 73.374677 -26.297545)
			(xy 73.426972 -26.312898) (xy 73.47655 -26.335537) (xy 73.522402 -26.365001) (xy 73.563593 -26.400692)
			(xy 73.599285 -26.441881) (xy 73.628752 -26.48773) (xy 73.651394 -26.537307) (xy 73.66675 -26.589601)
			(xy 73.674507 -26.643549) (xy 73.674507 -26.698051) (xy 73.66675 -26.751999) (xy 73.651394 -26.804293)
			(xy 73.628752 -26.85387) (xy 73.599285 -26.899719) (xy 73.563593 -26.940908) (xy 73.522402 -26.976599)
			(xy 73.47655 -27.006063) (xy 73.426972 -27.028702) (xy 73.374677 -27.044055) (xy 73.320729 -27.051808)
			(xy 73.293478 -27.05227) (xy 73.26622 -27.0518) (xy 73.212261 -27.044031) (xy 73.159954 -27.028666)
			(xy 73.110365 -27.00602) (xy 73.064499 -26.976552) (xy 73.023291 -26.940861) (xy 72.987577 -26.899672)
			(xy 72.972422 -26.87701) (xy 72.964141 -26.865083) (xy 72.942205 -26.846079) (xy 72.915805 -26.834024)
			(xy 72.887078 -26.829894) (xy 72.858351 -26.834024) (xy 72.831951 -26.846079) (xy 72.810015 -26.865083)
			(xy 72.801734 -26.87701) (xy 72.786588 -26.899679) (xy 72.750879 -26.940873) (xy 72.709671 -26.976568)
			(xy 72.663804 -27.006036) (xy 72.614211 -27.028677) (xy 72.5619 -27.044031) (xy 72.507937 -27.051786)
			(xy 72.480678 -27.05227) (xy 72.453425 -27.051859) (xy 72.399474 -27.044099) (xy 72.347177 -27.02874)
			(xy 72.297598 -27.006096) (xy 72.251745 -26.976626) (xy 72.210554 -26.940931) (xy 72.174861 -26.899737)
			(xy 72.145394 -26.853883) (xy 72.122752 -26.804302) (xy 72.107397 -26.752004) (xy 72.09964 -26.698053)
			(xy 59.403375 -26.698053) (xy 58.88228 -27.219148) (xy 58.88228 -32.944562) (xy 60.14542 -32.944562)
			(xy 60.149491 -32.88894) (xy 60.161617 -32.834503) (xy 60.18154 -32.782412) (xy 60.208836 -32.733777)
			(xy 60.242922 -32.689634) (xy 60.283071 -32.650925) (xy 60.328429 -32.618474) (xy 60.378029 -32.592973)
			(xy 60.430813 -32.574966) (xy 60.485656 -32.564836) (xy 60.54139 -32.562799) (xy 60.596827 -32.568899)
			(xy 60.650784 -32.583005) (xy 60.702113 -32.604817) (xy 60.749719 -32.633871) (xy 60.792587 -32.669546)
			(xy 60.829804 -32.711083) (xy 60.860577 -32.757596) (xy 60.884249 -32.808093) (xy 60.900317 -32.8615)
			(xy 60.908437 -32.916676) (xy 60.908946 -32.944562) (xy 60.908437 -32.972448) (xy 60.900317 -33.027624)
			(xy 60.884249 -33.081031) (xy 60.860577 -33.131528) (xy 60.829804 -33.178041) (xy 60.792587 -33.219578)
			(xy 60.749719 -33.255253) (xy 60.702113 -33.284307) (xy 60.650784 -33.306119) (xy 60.596827 -33.320225)
			(xy 60.54139 -33.326325) (xy 60.485656 -33.324288) (xy 60.430813 -33.314158) (xy 60.378029 -33.296151)
			(xy 60.328429 -33.27065) (xy 60.283071 -33.238199) (xy 60.242922 -33.19949) (xy 60.208836 -33.155347)
			(xy 60.18154 -33.106712) (xy 60.161617 -33.054621) (xy 60.149491 -33.000184) (xy 60.14542 -32.944562)
			(xy 58.88228 -32.944562) (xy 58.88228 -33.772348) (xy 60.036964 -34.927032)
		)
		(stroke
			(width 0)
			(type solid)
		)
		(fill yes)
		(layer "In4.Cu")
		(net "GND")
	)
	(gr_poly
		(pts
			(xy 13.789914 -335.56321) (xy 13.81179 -335.547802) (xy 13.858992 -335.522603) (xy 13.909251 -335.504242)
			(xy 13.961582 -335.49308) (xy 14.014958 -335.489334) (xy 14.068334 -335.49308) (xy 14.120665 -335.504242)
			(xy 14.170924 -335.522603) (xy 14.218126 -335.547802) (xy 14.240002 -335.56321) (xy 32.752538 -335.56321)
			(xy 35.0012 -333.314548) (xy 54.4068 -333.314548) (xy 55.2958 -332.425548) (xy 55.2958 -327.981564)
			(xy 54.83098 -327.981564) (xy 54.788704 -327.981076) (xy 54.704513 -327.973274) (xy 54.6214 -327.957738)
			(xy 54.540076 -327.934599) (xy 54.461234 -327.904055) (xy 54.385546 -327.866367) (xy 54.313658 -327.821857)
			(xy 54.246184 -327.770903) (xy 54.1837 -327.71394) (xy 54.126737 -327.651456) (xy 54.075783 -327.583982)
			(xy 54.031273 -327.512094) (xy 53.993585 -327.436406) (xy 53.963041 -327.357564) (xy 53.939902 -327.27624)
			(xy 53.924366 -327.193127) (xy 53.916564 -327.108936) (xy 53.916564 -327.024384) (xy 53.924366 -326.940193)
			(xy 53.939902 -326.85708) (xy 53.963041 -326.775756) (xy 53.993585 -326.696914) (xy 54.031273 -326.621226)
			(xy 54.075783 -326.549338) (xy 54.126737 -326.481864) (xy 54.1837 -326.41938) (xy 54.246184 -326.362417)
			(xy 54.313658 -326.311463) (xy 54.385546 -326.266953) (xy 54.461234 -326.229265) (xy 54.540076 -326.198721)
			(xy 54.6214 -326.175582) (xy 54.704513 -326.160046) (xy 54.788704 -326.152244) (xy 54.83098 -326.151748)
			(xy 55.5752 -326.151748) (xy 56.40959 -325.317358) (xy 56.412384 -325.313294) (xy 56.438495 -325.276222)
			(xy 56.496499 -325.206516) (xy 56.528208 -325.174102) (xy 57.793636 -323.90842) (xy 57.82818 -323.8754)
			(xy 57.83504 -323.868599) (xy 57.843515 -323.851259) (xy 57.844984 -323.832014) (xy 57.83924 -323.813589)
			(xy 57.827095 -323.798588) (xy 57.810267 -323.789136) (xy 57.800748 -323.787516) (xy 57.776748 -323.783928)
			(xy 57.72995 -323.771089) (xy 57.685331 -323.75201) (xy 57.643718 -323.727045) (xy 57.605883 -323.696657)
			(xy 57.588912 -323.679312) (xy 57.578343 -323.668903) (xy 57.552624 -323.654152) (xy 57.523751 -323.647408)
			(xy 57.494158 -323.649241) (xy 57.466337 -323.659495) (xy 57.442634 -323.677306) (xy 57.433464 -323.688964)
			(xy 57.416555 -323.711034) (xy 57.377041 -323.750143) (xy 57.331931 -323.782638) (xy 57.28232 -323.80773)
			(xy 57.229413 -323.82481) (xy 57.174496 -323.833462) (xy 57.146698 -323.833998) (xy 57.12005 -323.8335)
			(xy 57.067348 -323.825556) (xy 57.016419 -323.809847) (xy 56.9684 -323.786722) (xy 56.924364 -323.756698)
			(xy 56.885295 -323.720447) (xy 56.852065 -323.678778) (xy 56.825417 -323.632621) (xy 56.805945 -323.583009)
			(xy 56.794085 -323.531048) (xy 56.790102 -323.4779) (xy 56.794085 -323.424752) (xy 56.805945 -323.372791)
			(xy 56.825417 -323.323179) (xy 56.852065 -323.277022) (xy 56.885295 -323.235353) (xy 56.924364 -323.199102)
			(xy 56.9684 -323.169078) (xy 57.016419 -323.145953) (xy 57.067348 -323.130244) (xy 57.12005 -323.1223)
			(xy 57.146698 -323.121782) (xy 57.175654 -323.122349) (xy 57.232804 -323.13172) (xy 57.287685 -323.150214)
			(xy 57.338849 -323.177345) (xy 57.38495 -323.212397) (xy 57.40527 -323.233034) (xy 57.415841 -323.243442)
			(xy 57.441563 -323.258191) (xy 57.470438 -323.264936) (xy 57.500033 -323.263107) (xy 57.527857 -323.25286)
			(xy 57.551569 -323.235056) (xy 57.560718 -323.223382) (xy 57.577628 -323.201314) (xy 57.617144 -323.162208)
			(xy 57.662254 -323.129716) (xy 57.711865 -323.104625) (xy 57.76477 -323.087546) (xy 57.819687 -323.078892)
			(xy 57.847484 -323.078348) (xy 57.875758 -323.07889) (xy 57.931597 -323.087823) (xy 57.985323 -323.105468)
			(xy 58.035585 -323.13138) (xy 58.081121 -323.16491) (xy 58.120786 -323.205214) (xy 58.153584 -323.25128)
			(xy 58.178691 -323.301949) (xy 58.18759 -323.328792) (xy 58.192541 -323.342892) (xy 58.209308 -323.367613)
			(xy 58.232506 -323.38643) (xy 58.260154 -323.397737) (xy 58.28989 -323.400566) (xy 58.319174 -323.394678)
			(xy 58.345505 -323.380574) (xy 58.3565 -323.370448) (xy 60.6044 -321.122548) (xy 60.6044 -319.91427)
			(xy 60.3758 -319.68567) (xy 60.200286 -319.68567) (xy 60.197746 -319.73393) (xy 60.195923 -319.760985)
			(xy 60.18511 -319.814119) (xy 60.166365 -319.864998) (xy 60.140122 -319.912447) (xy 60.106987 -319.955368)
			(xy 60.067726 -319.992768) (xy 60.023249 -320.023782) (xy 59.974582 -320.047692) (xy 59.922853 -320.063947)
			(xy 59.869257 -320.072169) (xy 59.815035 -320.072169) (xy 59.761439 -320.063947) (xy 59.70971 -320.047692)
			(xy 59.661043 -320.023782) (xy 59.616566 -319.992768) (xy 59.577305 -319.955368) (xy 59.54417 -319.912447)
			(xy 59.517927 -319.864998) (xy 59.499182 -319.814119) (xy 59.488369 -319.760985) (xy 59.486546 -319.73393)
			(xy 59.484006 -319.68567) (xy 54.92369 -319.68567) (xy 54.920896 -319.733422) (xy 54.918826 -319.760295)
			(xy 54.907604 -319.813012) (xy 54.888569 -319.863435) (xy 54.862155 -319.910416) (xy 54.828964 -319.952881)
			(xy 54.789755 -319.989861) (xy 54.745422 -320.020512) (xy 54.696977 -320.044134) (xy 54.645527 -320.060188)
			(xy 54.592245 -320.068308) (xy 54.538347 -320.068308) (xy 54.485065 -320.060188) (xy 54.433615 -320.044134)
			(xy 54.38517 -320.020512) (xy 54.340837 -319.989861) (xy 54.301628 -319.952881) (xy 54.268437 -319.910416)
			(xy 54.242023 -319.863435) (xy 54.222988 -319.813012) (xy 54.211766 -319.760295) (xy 54.209696 -319.733422)
			(xy 54.206902 -319.68567) (xy 52.656486 -319.68567) (xy 52.653946 -319.73393) (xy 52.652123 -319.760985)
			(xy 52.64131 -319.814119) (xy 52.622565 -319.864998) (xy 52.596322 -319.912447) (xy 52.563187 -319.955368)
			(xy 52.523926 -319.992768) (xy 52.479449 -320.023782) (xy 52.430782 -320.047692) (xy 52.379053 -320.063947)
			(xy 52.325457 -320.072169) (xy 52.271235 -320.072169) (xy 52.217639 -320.063947) (xy 52.16591 -320.047692)
			(xy 52.117243 -320.023782) (xy 52.072766 -319.992768) (xy 52.033505 -319.955368) (xy 52.00037 -319.912447)
			(xy 51.974127 -319.864998) (xy 51.955382 -319.814119) (xy 51.944569 -319.760985) (xy 51.942746 -319.73393)
			(xy 51.940206 -319.68567) (xy 51.41087 -319.68567) (xy 51.397086 -319.708389) (xy 51.363839 -319.749843)
			(xy 51.324802 -319.785896) (xy 51.280841 -319.815749) (xy 51.232933 -319.838738) (xy 51.18214 -319.854354)
			(xy 51.129591 -319.862249) (xy 51.076453 -319.862249) (xy 51.023904 -319.854354) (xy 50.973111 -319.838738)
			(xy 50.925203 -319.815749) (xy 50.881242 -319.785896) (xy 50.842205 -319.749843) (xy 50.808958 -319.708389)
			(xy 50.795174 -319.68567) (xy 49.1871 -319.68567) (xy 49.18456 -319.73393) (xy 49.182781 -319.758969)
			(xy 49.172605 -319.808123) (xy 49.15511 -319.855172) (xy 49.1307 -319.899033) (xy 49.099935 -319.938697)
			(xy 49.063525 -319.973251) (xy 49.022307 -320.0019) (xy 48.97723 -320.023984) (xy 48.929331 -320.038995)
			(xy 48.879712 -320.046589) (xy 48.829516 -320.046589) (xy 48.779897 -320.038995) (xy 48.731998 -320.023984)
			(xy 48.686921 -320.0019) (xy 48.645703 -319.973251) (xy 48.609293 -319.938697) (xy 48.578528 -319.899033)
			(xy 48.554118 -319.855172) (xy 48.536623 -319.808123) (xy 48.526447 -319.758969) (xy 48.524668 -319.73393)
			(xy 48.522128 -319.68567) (xy 47.42688 -319.68567) (xy 47.411655 -319.686239) (xy 47.382557 -319.695216)
			(xy 47.357396 -319.712368) (xy 47.338405 -319.736171) (xy 47.327269 -319.764512) (xy 47.325534 -319.77965)
			(xy 47.323084 -319.8062) (xy 47.311245 -319.858185) (xy 47.291788 -319.907824) (xy 47.265148 -319.954008)
			(xy 47.231919 -319.995703) (xy 47.192845 -320.031978) (xy 47.148799 -320.062022) (xy 47.100767 -320.085163)
			(xy 47.049821 -320.100884) (xy 46.9971 -320.108833) (xy 46.943784 -320.108833) (xy 46.891063 -320.100884)
			(xy 46.840117 -320.085163) (xy 46.792085 -320.062022) (xy 46.748039 -320.031978) (xy 46.708965 -319.995703)
			(xy 46.675736 -319.954008) (xy 46.649096 -319.907824) (xy 46.629639 -319.858185) (xy 46.6178 -319.8062)
			(xy 46.61535 -319.77965) (xy 46.613708 -319.76449) (xy 46.602575 -319.736116) (xy 46.583568 -319.712288)
			(xy 46.558377 -319.695129) (xy 46.529245 -319.686165) (xy 46.514004 -319.68567) (xy 45.112686 -319.68567)
			(xy 45.110146 -319.73393) (xy 45.108323 -319.760985) (xy 45.09751 -319.814119) (xy 45.078765 -319.864998)
			(xy 45.052522 -319.912447) (xy 45.019387 -319.955368) (xy 44.980126 -319.992768) (xy 44.935649 -320.023782)
			(xy 44.886982 -320.047692) (xy 44.835253 -320.063947) (xy 44.781657 -320.072169) (xy 44.727435 -320.072169)
			(xy 44.673839 -320.063947) (xy 44.62211 -320.047692) (xy 44.573443 -320.023782) (xy 44.528966 -319.992768)
			(xy 44.489705 -319.955368) (xy 44.45657 -319.912447) (xy 44.430327 -319.864998) (xy 44.411582 -319.814119)
			(xy 44.400769 -319.760985) (xy 44.398946 -319.73393) (xy 44.396406 -319.68567) (xy 41.668954 -319.68567)
			(xy 41.666414 -319.73393) (xy 41.664591 -319.760985) (xy 41.653778 -319.814119) (xy 41.635033 -319.864998)
			(xy 41.60879 -319.912447) (xy 41.575655 -319.955368) (xy 41.536394 -319.992768) (xy 41.491917 -320.023782)
			(xy 41.44325 -320.047692) (xy 41.391521 -320.063947) (xy 41.337925 -320.072169) (xy 41.283703 -320.072169)
			(xy 41.230107 -320.063947) (xy 41.178378 -320.047692) (xy 41.129711 -320.023782) (xy 41.085234 -319.992768)
			(xy 41.045973 -319.955368) (xy 41.012838 -319.912447) (xy 40.986595 -319.864998) (xy 40.96785 -319.814119)
			(xy 40.957037 -319.760985) (xy 40.955214 -319.73393) (xy 40.952674 -319.68567) (xy 37.568886 -319.68567)
			(xy 37.566346 -319.73393) (xy 37.564523 -319.760985) (xy 37.55371 -319.814119) (xy 37.534965 -319.864998)
			(xy 37.508722 -319.912447) (xy 37.475587 -319.955368) (xy 37.436326 -319.992768) (xy 37.391849 -320.023782)
			(xy 37.343182 -320.047692) (xy 37.291453 -320.063947) (xy 37.237857 -320.072169) (xy 37.183635 -320.072169)
			(xy 37.130039 -320.063947) (xy 37.07831 -320.047692) (xy 37.029643 -320.023782) (xy 36.985166 -319.992768)
			(xy 36.945905 -319.955368) (xy 36.91277 -319.912447) (xy 36.886527 -319.864998) (xy 36.867782 -319.814119)
			(xy 36.856969 -319.760985) (xy 36.855146 -319.73393) (xy 36.852606 -319.68567) (xy 34.125154 -319.68567)
			(xy 34.122614 -319.73393) (xy 34.120791 -319.760985) (xy 34.109978 -319.814119) (xy 34.091233 -319.864998)
			(xy 34.06499 -319.912447) (xy 34.031855 -319.955368) (xy 33.992594 -319.992768) (xy 33.948117 -320.023782)
			(xy 33.89945 -320.047692) (xy 33.847721 -320.063947) (xy 33.794125 -320.072169) (xy 33.739903 -320.072169)
			(xy 33.686307 -320.063947) (xy 33.634578 -320.047692) (xy 33.585911 -320.023782) (xy 33.541434 -319.992768)
			(xy 33.502173 -319.955368) (xy 33.469038 -319.912447) (xy 33.442795 -319.864998) (xy 33.42405 -319.814119)
			(xy 33.413237 -319.760985) (xy 33.411414 -319.73393) (xy 33.408874 -319.68567) (xy 30.025086 -319.68567)
			(xy 30.022546 -319.73393) (xy 30.020723 -319.760985) (xy 30.00991 -319.814119) (xy 29.991165 -319.864998)
			(xy 29.964922 -319.912447) (xy 29.931787 -319.955368) (xy 29.892526 -319.992768) (xy 29.848049 -320.023782)
			(xy 29.799382 -320.047692) (xy 29.747653 -320.063947) (xy 29.694057 -320.072169) (xy 29.639835 -320.072169)
			(xy 29.586239 -320.063947) (xy 29.53451 -320.047692) (xy 29.485843 -320.023782) (xy 29.441366 -319.992768)
			(xy 29.402105 -319.955368) (xy 29.36897 -319.912447) (xy 29.342727 -319.864998) (xy 29.323982 -319.814119)
			(xy 29.313169 -319.760985) (xy 29.311346 -319.73393) (xy 29.308806 -319.68567) (xy 26.581354 -319.68567)
			(xy 26.578814 -319.73393) (xy 26.576991 -319.760985) (xy 26.566178 -319.814119) (xy 26.547433 -319.864998)
			(xy 26.52119 -319.912447) (xy 26.488055 -319.955368) (xy 26.448794 -319.992768) (xy 26.404317 -320.023782)
			(xy 26.35565 -320.047692) (xy 26.303921 -320.063947) (xy 26.250325 -320.072169) (xy 26.196103 -320.072169)
			(xy 26.142507 -320.063947) (xy 26.090778 -320.047692) (xy 26.042111 -320.023782) (xy 25.997634 -319.992768)
			(xy 25.958373 -319.955368) (xy 25.925238 -319.912447) (xy 25.898995 -319.864998) (xy 25.88025 -319.814119)
			(xy 25.869437 -319.760985) (xy 25.867614 -319.73393) (xy 25.865074 -319.68567) (xy 24.448008 -319.68567)
			(xy 24.441404 -319.687448) (xy 24.417941 -319.693589) (xy 24.369895 -319.700213) (xy 24.345646 -319.700656)
			(xy 24.321395 -319.700232) (xy 24.273347 -319.693609) (xy 24.249888 -319.687448) (xy 24.243284 -319.68567)
			(xy 22.481286 -319.68567) (xy 22.478746 -319.73393) (xy 22.476923 -319.760985) (xy 22.46611 -319.814119)
			(xy 22.447365 -319.864998) (xy 22.421122 -319.912447) (xy 22.387987 -319.955368) (xy 22.348726 -319.992768)
			(xy 22.304249 -320.023782) (xy 22.255582 -320.047692) (xy 22.203853 -320.063947) (xy 22.150257 -320.072169)
			(xy 22.096035 -320.072169) (xy 22.042439 -320.063947) (xy 21.99071 -320.047692) (xy 21.942043 -320.023782)
			(xy 21.897566 -319.992768) (xy 21.858305 -319.955368) (xy 21.82517 -319.912447) (xy 21.798927 -319.864998)
			(xy 21.780182 -319.814119) (xy 21.769369 -319.760985) (xy 21.767546 -319.73393) (xy 21.765006 -319.68567)
			(xy 19.037554 -319.68567) (xy 19.035014 -319.73393) (xy 19.033191 -319.760985) (xy 19.022378 -319.814119)
			(xy 19.003633 -319.864998) (xy 18.97739 -319.912447) (xy 18.944255 -319.955368) (xy 18.904994 -319.992768)
			(xy 18.860517 -320.023782) (xy 18.81185 -320.047692) (xy 18.760121 -320.063947) (xy 18.706525 -320.072169)
			(xy 18.652303 -320.072169) (xy 18.598707 -320.063947) (xy 18.546978 -320.047692) (xy 18.498311 -320.023782)
			(xy 18.453834 -319.992768) (xy 18.414573 -319.955368) (xy 18.381438 -319.912447) (xy 18.355195 -319.864998)
			(xy 18.33645 -319.814119) (xy 18.325637 -319.760985) (xy 18.323814 -319.73393) (xy 18.321274 -319.68567)
			(xy 17.027144 -319.68567) (xy 17.006414 -319.700837) (xy 16.961461 -319.725685) (xy 16.913402 -319.743811)
			(xy 16.863236 -319.75484) (xy 16.812006 -319.758542) (xy 16.760776 -319.75484) (xy 16.71061 -319.743811)
			(xy 16.662551 -319.725685) (xy 16.617598 -319.700837) (xy 16.596868 -319.68567) (xy 14.937486 -319.68567)
			(xy 14.934946 -319.73393) (xy 14.933123 -319.760985) (xy 14.92231 -319.814119) (xy 14.903565 -319.864998)
			(xy 14.877322 -319.912447) (xy 14.844187 -319.955368) (xy 14.804926 -319.992768) (xy 14.760449 -320.023782)
			(xy 14.711782 -320.047692) (xy 14.660053 -320.063947) (xy 14.606457 -320.072169) (xy 14.552235 -320.072169)
			(xy 14.498639 -320.063947) (xy 14.44691 -320.047692) (xy 14.398243 -320.023782) (xy 14.353766 -319.992768)
			(xy 14.314505 -319.955368) (xy 14.28137 -319.912447) (xy 14.255127 -319.864998) (xy 14.236382 -319.814119)
			(xy 14.225569 -319.760985) (xy 14.223746 -319.73393) (xy 14.221206 -319.68567) (xy 11.493754 -319.68567)
			(xy 11.491214 -319.73393) (xy 11.489391 -319.760985) (xy 11.478578 -319.814119) (xy 11.459833 -319.864998)
			(xy 11.43359 -319.912447) (xy 11.400455 -319.955368) (xy 11.361194 -319.992768) (xy 11.316717 -320.023782)
			(xy 11.26805 -320.047692) (xy 11.216321 -320.063947) (xy 11.162725 -320.072169) (xy 11.108503 -320.072169)
			(xy 11.054907 -320.063947) (xy 11.003178 -320.047692) (xy 10.954511 -320.023782) (xy 10.910034 -319.992768)
			(xy 10.870773 -319.955368) (xy 10.837638 -319.912447) (xy 10.811395 -319.864998) (xy 10.79265 -319.814119)
			(xy 10.781837 -319.760985) (xy 10.780014 -319.73393) (xy 10.777474 -319.68567) (xy 9.360408 -319.68567)
			(xy 9.353804 -319.687448) (xy 9.330341 -319.693589) (xy 9.282295 -319.700213) (xy 9.258046 -319.700656)
			(xy 9.233795 -319.700232) (xy 9.185747 -319.693609) (xy 9.162288 -319.687448) (xy 9.155684 -319.68567)
			(xy 7.393686 -319.68567) (xy 7.391146 -319.73393) (xy 7.389319 -319.760986) (xy 7.378501 -319.814122)
			(xy 7.359754 -319.865004) (xy 7.33351 -319.912456) (xy 7.300376 -319.955381) (xy 7.261119 -319.992788)
			(xy 7.216645 -320.023812) (xy 7.167982 -320.047736) (xy 7.116255 -320.064007) (xy 7.062659 -320.072249)
			(xy 7.035546 -320.072766) (xy 7.009088 -320.072287) (xy 6.956754 -320.064469) (xy 6.90615 -320.048998)
			(xy 6.858391 -320.026215) (xy 6.814525 -319.99662) (xy 6.775518 -319.960864) (xy 6.742227 -319.919733)
			(xy 6.715385 -319.874131) (xy 6.705092 -319.849754) (xy 6.699304 -319.83663) (xy 6.681653 -319.814035)
			(xy 6.658411 -319.797247) (xy 6.631415 -319.787589) (xy 6.602798 -319.785827) (xy 6.574821 -319.792099)
			(xy 6.549695 -319.80591) (xy 6.53923 -319.815718) (xy 6.1976 -320.157348) (xy 6.1976 -320.191617)
			(xy 55.43803 -320.191617) (xy 55.43803 -320.138319) (xy 55.445973 -320.085615) (xy 55.461683 -320.034685)
			(xy 55.484809 -319.986664) (xy 55.514833 -319.942627) (xy 55.551085 -319.903556) (xy 55.592756 -319.870325)
			(xy 55.638914 -319.843676) (xy 55.688528 -319.824204) (xy 55.74049 -319.812344) (xy 55.79364 -319.808361)
			(xy 55.84679 -319.812344) (xy 55.898752 -319.824204) (xy 55.948366 -319.843676) (xy 55.994524 -319.870325)
			(xy 56.036195 -319.903556) (xy 56.072447 -319.942627) (xy 56.102471 -319.986664) (xy 56.125597 -320.034685)
			(xy 56.141307 -320.085615) (xy 56.14925 -320.138319) (xy 56.149748 -320.164968) (xy 56.14925 -320.191617)
			(xy 56.141307 -320.244321) (xy 56.125597 -320.295251) (xy 56.102471 -320.343272) (xy 56.072447 -320.387309)
			(xy 56.036195 -320.42638) (xy 55.994524 -320.459611) (xy 55.948366 -320.48626) (xy 55.898752 -320.505732)
			(xy 55.84679 -320.517592) (xy 55.79364 -320.521576) (xy 55.74049 -320.517592) (xy 55.688528 -320.505732)
			(xy 55.638914 -320.48626) (xy 55.592756 -320.459611) (xy 55.551085 -320.42638) (xy 55.514833 -320.387309)
			(xy 55.484809 -320.343272) (xy 55.461683 -320.295251) (xy 55.445973 -320.244321) (xy 55.43803 -320.191617)
			(xy 6.1976 -320.191617) (xy 6.1976 -320.593445) (xy 6.679936 -320.593445) (xy 6.679936 -320.540147)
			(xy 6.687879 -320.487443) (xy 6.703589 -320.436513) (xy 6.726715 -320.388492) (xy 6.756739 -320.344455)
			(xy 6.792991 -320.305384) (xy 6.834662 -320.272153) (xy 6.88082 -320.245504) (xy 6.930434 -320.226032)
			(xy 6.982396 -320.214172) (xy 7.035546 -320.210189) (xy 7.088696 -320.214172) (xy 7.140658 -320.226032)
			(xy 7.190272 -320.245504) (xy 7.23643 -320.272153) (xy 7.278101 -320.305384) (xy 7.314353 -320.344455)
			(xy 7.344377 -320.388492) (xy 7.367503 -320.436513) (xy 7.383213 -320.487443) (xy 7.391156 -320.540147)
			(xy 7.391654 -320.566796) (xy 7.391156 -320.593445) (xy 14.223736 -320.593445) (xy 14.223736 -320.540147)
			(xy 14.231679 -320.487443) (xy 14.247389 -320.436513) (xy 14.270515 -320.388492) (xy 14.300539 -320.344455)
			(xy 14.336791 -320.305384) (xy 14.378462 -320.272153) (xy 14.42462 -320.245504) (xy 14.474234 -320.226032)
			(xy 14.526196 -320.214172) (xy 14.579346 -320.210189) (xy 14.632496 -320.214172) (xy 14.684458 -320.226032)
			(xy 14.734072 -320.245504) (xy 14.78023 -320.272153) (xy 14.821901 -320.305384) (xy 14.858153 -320.344455)
			(xy 14.888177 -320.388492) (xy 14.911303 -320.436513) (xy 14.927013 -320.487443) (xy 14.934956 -320.540147)
			(xy 14.935454 -320.566796) (xy 14.934956 -320.593445) (xy 21.767536 -320.593445) (xy 21.767536 -320.540147)
			(xy 21.775479 -320.487443) (xy 21.791189 -320.436513) (xy 21.814315 -320.388492) (xy 21.844339 -320.344455)
			(xy 21.880591 -320.305384) (xy 21.922262 -320.272153) (xy 21.96842 -320.245504) (xy 22.018034 -320.226032)
			(xy 22.069996 -320.214172) (xy 22.123146 -320.210189) (xy 22.176296 -320.214172) (xy 22.228258 -320.226032)
			(xy 22.277872 -320.245504) (xy 22.32403 -320.272153) (xy 22.365701 -320.305384) (xy 22.401953 -320.344455)
			(xy 22.431977 -320.388492) (xy 22.455103 -320.436513) (xy 22.470813 -320.487443) (xy 22.478756 -320.540147)
			(xy 22.479254 -320.566796) (xy 22.478756 -320.593445) (xy 29.311336 -320.593445) (xy 29.311336 -320.540147)
			(xy 29.319279 -320.487443) (xy 29.334989 -320.436513) (xy 29.358115 -320.388492) (xy 29.388139 -320.344455)
			(xy 29.424391 -320.305384) (xy 29.466062 -320.272153) (xy 29.51222 -320.245504) (xy 29.561834 -320.226032)
			(xy 29.613796 -320.214172) (xy 29.666946 -320.210189) (xy 29.720096 -320.214172) (xy 29.772058 -320.226032)
			(xy 29.821672 -320.245504) (xy 29.86783 -320.272153) (xy 29.909501 -320.305384) (xy 29.945753 -320.344455)
			(xy 29.975777 -320.388492) (xy 29.998903 -320.436513) (xy 30.014613 -320.487443) (xy 30.022556 -320.540147)
			(xy 30.023054 -320.566796) (xy 30.022556 -320.593445) (xy 36.855136 -320.593445) (xy 36.855136 -320.540147)
			(xy 36.863079 -320.487443) (xy 36.878789 -320.436513) (xy 36.901915 -320.388492) (xy 36.931939 -320.344455)
			(xy 36.968191 -320.305384) (xy 37.009862 -320.272153) (xy 37.05602 -320.245504) (xy 37.105634 -320.226032)
			(xy 37.157596 -320.214172) (xy 37.210746 -320.210189) (xy 37.263896 -320.214172) (xy 37.315858 -320.226032)
			(xy 37.365472 -320.245504) (xy 37.41163 -320.272153) (xy 37.453301 -320.305384) (xy 37.489553 -320.344455)
			(xy 37.519577 -320.388492) (xy 37.542703 -320.436513) (xy 37.558413 -320.487443) (xy 37.566356 -320.540147)
			(xy 37.566854 -320.566796) (xy 37.566356 -320.593445) (xy 44.398936 -320.593445) (xy 44.398936 -320.540147)
			(xy 44.406879 -320.487443) (xy 44.422589 -320.436513) (xy 44.445715 -320.388492) (xy 44.475739 -320.344455)
			(xy 44.511991 -320.305384) (xy 44.553662 -320.272153) (xy 44.59982 -320.245504) (xy 44.649434 -320.226032)
			(xy 44.701396 -320.214172) (xy 44.754546 -320.210189) (xy 44.807696 -320.214172) (xy 44.859658 -320.226032)
			(xy 44.909272 -320.245504) (xy 44.95543 -320.272153) (xy 44.997101 -320.305384) (xy 45.033353 -320.344455)
			(xy 45.063377 -320.388492) (xy 45.086503 -320.436513) (xy 45.102213 -320.487443) (xy 45.110156 -320.540147)
			(xy 45.110654 -320.566796) (xy 45.110156 -320.593445) (xy 51.942736 -320.593445) (xy 51.942736 -320.540147)
			(xy 51.950679 -320.487443) (xy 51.966389 -320.436513) (xy 51.989515 -320.388492) (xy 52.019539 -320.344455)
			(xy 52.055791 -320.305384) (xy 52.097462 -320.272153) (xy 52.14362 -320.245504) (xy 52.193234 -320.226032)
			(xy 52.245196 -320.214172) (xy 52.298346 -320.210189) (xy 52.351496 -320.214172) (xy 52.403458 -320.226032)
			(xy 52.453072 -320.245504) (xy 52.49923 -320.272153) (xy 52.540901 -320.305384) (xy 52.577153 -320.344455)
			(xy 52.607177 -320.388492) (xy 52.630303 -320.436513) (xy 52.646013 -320.487443) (xy 52.653956 -320.540147)
			(xy 52.654454 -320.566796) (xy 52.653956 -320.593445) (xy 59.486536 -320.593445) (xy 59.486536 -320.540147)
			(xy 59.494479 -320.487443) (xy 59.510189 -320.436513) (xy 59.533315 -320.388492) (xy 59.563339 -320.344455)
			(xy 59.599591 -320.305384) (xy 59.641262 -320.272153) (xy 59.68742 -320.245504) (xy 59.737034 -320.226032)
			(xy 59.788996 -320.214172) (xy 59.842146 -320.210189) (xy 59.895296 -320.214172) (xy 59.947258 -320.226032)
			(xy 59.996872 -320.245504) (xy 60.04303 -320.272153) (xy 60.084701 -320.305384) (xy 60.120953 -320.344455)
			(xy 60.150977 -320.388492) (xy 60.174103 -320.436513) (xy 60.189813 -320.487443) (xy 60.197756 -320.540147)
			(xy 60.198254 -320.566796) (xy 60.197756 -320.593445) (xy 60.189813 -320.646149) (xy 60.174103 -320.697079)
			(xy 60.150977 -320.7451) (xy 60.120953 -320.789137) (xy 60.084701 -320.828208) (xy 60.04303 -320.861439)
			(xy 59.996872 -320.888088) (xy 59.947258 -320.90756) (xy 59.895296 -320.91942) (xy 59.842146 -320.923404)
			(xy 59.788996 -320.91942) (xy 59.737034 -320.90756) (xy 59.68742 -320.888088) (xy 59.641262 -320.861439)
			(xy 59.599591 -320.828208) (xy 59.563339 -320.789137) (xy 59.533315 -320.7451) (xy 59.510189 -320.697079)
			(xy 59.494479 -320.646149) (xy 59.486536 -320.593445) (xy 52.653956 -320.593445) (xy 52.646013 -320.646149)
			(xy 52.630303 -320.697079) (xy 52.607177 -320.7451) (xy 52.577153 -320.789137) (xy 52.540901 -320.828208)
			(xy 52.49923 -320.861439) (xy 52.453072 -320.888088) (xy 52.403458 -320.90756) (xy 52.351496 -320.91942)
			(xy 52.298346 -320.923404) (xy 52.245196 -320.91942) (xy 52.193234 -320.90756) (xy 52.14362 -320.888088)
			(xy 52.097462 -320.861439) (xy 52.055791 -320.828208) (xy 52.019539 -320.789137) (xy 51.989515 -320.7451)
			(xy 51.966389 -320.697079) (xy 51.950679 -320.646149) (xy 51.942736 -320.593445) (xy 45.110156 -320.593445)
			(xy 45.102213 -320.646149) (xy 45.086503 -320.697079) (xy 45.063377 -320.7451) (xy 45.033353 -320.789137)
			(xy 44.997101 -320.828208) (xy 44.95543 -320.861439) (xy 44.909272 -320.888088) (xy 44.859658 -320.90756)
			(xy 44.807696 -320.91942) (xy 44.754546 -320.923404) (xy 44.701396 -320.91942) (xy 44.649434 -320.90756)
			(xy 44.59982 -320.888088) (xy 44.553662 -320.861439) (xy 44.511991 -320.828208) (xy 44.475739 -320.789137)
			(xy 44.445715 -320.7451) (xy 44.422589 -320.697079) (xy 44.406879 -320.646149) (xy 44.398936 -320.593445)
			(xy 37.566356 -320.593445) (xy 37.558413 -320.646149) (xy 37.542703 -320.697079) (xy 37.519577 -320.7451)
			(xy 37.489553 -320.789137) (xy 37.453301 -320.828208) (xy 37.41163 -320.861439) (xy 37.365472 -320.888088)
			(xy 37.315858 -320.90756) (xy 37.263896 -320.91942) (xy 37.210746 -320.923404) (xy 37.157596 -320.91942)
			(xy 37.105634 -320.90756) (xy 37.05602 -320.888088) (xy 37.009862 -320.861439) (xy 36.968191 -320.828208)
			(xy 36.931939 -320.789137) (xy 36.901915 -320.7451) (xy 36.878789 -320.697079) (xy 36.863079 -320.646149)
			(xy 36.855136 -320.593445) (xy 30.022556 -320.593445) (xy 30.014613 -320.646149) (xy 29.998903 -320.697079)
			(xy 29.975777 -320.7451) (xy 29.945753 -320.789137) (xy 29.909501 -320.828208) (xy 29.86783 -320.861439)
			(xy 29.821672 -320.888088) (xy 29.772058 -320.90756) (xy 29.720096 -320.91942) (xy 29.666946 -320.923404)
			(xy 29.613796 -320.91942) (xy 29.561834 -320.90756) (xy 29.51222 -320.888088) (xy 29.466062 -320.861439)
			(xy 29.424391 -320.828208) (xy 29.388139 -320.789137) (xy 29.358115 -320.7451) (xy 29.334989 -320.697079)
			(xy 29.319279 -320.646149) (xy 29.311336 -320.593445) (xy 22.478756 -320.593445) (xy 22.470813 -320.646149)
			(xy 22.455103 -320.697079) (xy 22.431977 -320.7451) (xy 22.401953 -320.789137) (xy 22.365701 -320.828208)
			(xy 22.32403 -320.861439) (xy 22.277872 -320.888088) (xy 22.228258 -320.90756) (xy 22.176296 -320.91942)
			(xy 22.123146 -320.923404) (xy 22.069996 -320.91942) (xy 22.018034 -320.90756) (xy 21.96842 -320.888088)
			(xy 21.922262 -320.861439) (xy 21.880591 -320.828208) (xy 21.844339 -320.789137) (xy 21.814315 -320.7451)
			(xy 21.791189 -320.697079) (xy 21.775479 -320.646149) (xy 21.767536 -320.593445) (xy 14.934956 -320.593445)
			(xy 14.927013 -320.646149) (xy 14.911303 -320.697079) (xy 14.888177 -320.7451) (xy 14.858153 -320.789137)
			(xy 14.821901 -320.828208) (xy 14.78023 -320.861439) (xy 14.734072 -320.888088) (xy 14.684458 -320.90756)
			(xy 14.632496 -320.91942) (xy 14.579346 -320.923404) (xy 14.526196 -320.91942) (xy 14.474234 -320.90756)
			(xy 14.42462 -320.888088) (xy 14.378462 -320.861439) (xy 14.336791 -320.828208) (xy 14.300539 -320.789137)
			(xy 14.270515 -320.7451) (xy 14.247389 -320.697079) (xy 14.231679 -320.646149) (xy 14.223736 -320.593445)
			(xy 7.391156 -320.593445) (xy 7.383213 -320.646149) (xy 7.367503 -320.697079) (xy 7.344377 -320.7451)
			(xy 7.314353 -320.789137) (xy 7.278101 -320.828208) (xy 7.23643 -320.861439) (xy 7.190272 -320.888088)
			(xy 7.140658 -320.90756) (xy 7.088696 -320.91942) (xy 7.035546 -320.923404) (xy 6.982396 -320.91942)
			(xy 6.930434 -320.90756) (xy 6.88082 -320.888088) (xy 6.834662 -320.861439) (xy 6.792991 -320.828208)
			(xy 6.756739 -320.789137) (xy 6.726715 -320.7451) (xy 6.703589 -320.697079) (xy 6.687879 -320.646149)
			(xy 6.679936 -320.593445) (xy 6.1976 -320.593445) (xy 6.1976 -322.900548) (xy 48.562768 -322.900548)
			(xy 48.563283 -322.873249) (xy 48.571616 -322.81929) (xy 48.588094 -322.767238) (xy 48.61233 -322.718314)
			(xy 48.643756 -322.673666) (xy 48.662336 -322.65366) (xy 48.672736 -322.6421) (xy 48.68654 -322.61425)
			(xy 48.691357 -322.583543) (xy 48.686745 -322.552804) (xy 48.673128 -322.524863) (xy 48.662844 -322.513198)
			(xy 48.644678 -322.493248) (xy 48.613962 -322.448891) (xy 48.590287 -322.400409) (xy 48.574197 -322.34891)
			(xy 48.566059 -322.295573) (xy 48.565562 -322.268596) (xy 48.56606 -322.241947) (xy 48.574003 -322.189243)
			(xy 48.589713 -322.138313) (xy 48.612839 -322.090292) (xy 48.642863 -322.046255) (xy 48.679115 -322.007184)
			(xy 48.720786 -321.973953) (xy 48.766944 -321.947304) (xy 48.816558 -321.927832) (xy 48.86852 -321.915972)
			(xy 48.92167 -321.911989) (xy 48.97482 -321.915972) (xy 49.026782 -321.927832) (xy 49.076396 -321.947304)
			(xy 49.122554 -321.973953) (xy 49.164225 -322.007184) (xy 49.200477 -322.046255) (xy 49.230501 -322.090292)
			(xy 49.253627 -322.138313) (xy 49.269337 -322.189243) (xy 49.27728 -322.241947) (xy 49.277778 -322.268596)
			(xy 49.277305 -322.295897) (xy 49.268964 -322.349858) (xy 49.252477 -322.401911) (xy 49.228231 -322.450835)
			(xy 49.196795 -322.49548) (xy 49.17821 -322.515484) (xy 49.167862 -322.527087) (xy 49.154046 -322.55492)
			(xy 49.149215 -322.585616) (xy 49.153815 -322.616347) (xy 49.167422 -322.644283) (xy 49.177702 -322.655946)
			(xy 49.195849 -322.675912) (xy 49.226566 -322.720266) (xy 49.250243 -322.768744) (xy 49.266338 -322.820239)
			(xy 49.274483 -322.873572) (xy 49.274984 -322.900548) (xy 49.274576 -322.922392) (xy 52.035964 -322.922392)
			(xy 52.036376 -322.897333) (xy 52.043387 -322.847707) (xy 52.057286 -322.799554) (xy 52.077796 -322.753824)
			(xy 52.104513 -322.71142) (xy 52.136909 -322.67318) (xy 52.155344 -322.6562) (xy 52.16539 -322.646655)
			(xy 52.180316 -322.623317) (xy 52.188429 -322.596829) (xy 52.189135 -322.569135) (xy 52.182382 -322.542268)
			(xy 52.168664 -322.518199) (xy 52.159154 -322.508118) (xy 52.139503 -322.487907) (xy 52.106178 -322.442445)
			(xy 52.080429 -322.392302) (xy 52.062898 -322.338729) (xy 52.054024 -322.283064) (xy 52.05349 -322.25488)
			(xy 52.053988 -322.228231) (xy 52.061931 -322.175527) (xy 52.077641 -322.124597) (xy 52.100767 -322.076576)
			(xy 52.130791 -322.032539) (xy 52.167043 -321.993468) (xy 52.208714 -321.960237) (xy 52.254872 -321.933588)
			(xy 52.304486 -321.914116) (xy 52.356448 -321.902256) (xy 52.409598 -321.898273) (xy 52.462748 -321.902256)
			(xy 52.51471 -321.914116) (xy 52.564324 -321.933588) (xy 52.610482 -321.960237) (xy 52.652153 -321.993468)
			(xy 52.688405 -322.032539) (xy 52.718429 -322.076576) (xy 52.741555 -322.124597) (xy 52.757265 -322.175527)
			(xy 52.765208 -322.228231) (xy 52.765706 -322.25488) (xy 52.765285 -322.279939) (xy 52.758277 -322.329565)
			(xy 52.744381 -322.377718) (xy 52.723873 -322.423448) (xy 52.697157 -322.465852) (xy 52.664761 -322.504093)
			(xy 52.646326 -322.521072) (xy 52.636309 -322.530644) (xy 52.621386 -322.553976) (xy 52.613272 -322.580456)
			(xy 52.612561 -322.608143) (xy 52.619306 -322.635005) (xy 52.633012 -322.659072) (xy 52.642516 -322.669154)
			(xy 52.662148 -322.689382) (xy 52.695477 -322.734839) (xy 52.72123 -322.784978) (xy 52.738765 -322.838547)
			(xy 52.747644 -322.894209) (xy 52.74818 -322.922392) (xy 52.747682 -322.949041) (xy 52.739739 -323.001745)
			(xy 52.724029 -323.052675) (xy 52.700903 -323.100696) (xy 52.670879 -323.144733) (xy 52.634627 -323.183804)
			(xy 52.592956 -323.217035) (xy 52.546798 -323.243684) (xy 52.497184 -323.263156) (xy 52.445222 -323.275016)
			(xy 52.392072 -323.279) (xy 52.338922 -323.275016) (xy 52.28696 -323.263156) (xy 52.237346 -323.243684)
			(xy 52.191188 -323.217035) (xy 52.149517 -323.183804) (xy 52.113265 -323.144733) (xy 52.083241 -323.100696)
			(xy 52.060115 -323.052675) (xy 52.044405 -323.001745) (xy 52.036462 -322.949041) (xy 52.035964 -322.922392)
			(xy 49.274576 -322.922392) (xy 49.274486 -322.927197) (xy 49.266543 -322.979901) (xy 49.250833 -323.030831)
			(xy 49.227707 -323.078852) (xy 49.197683 -323.122889) (xy 49.161431 -323.16196) (xy 49.11976 -323.195191)
			(xy 49.073602 -323.22184) (xy 49.023988 -323.241312) (xy 48.972026 -323.253172) (xy 48.918876 -323.257156)
			(xy 48.865726 -323.253172) (xy 48.813764 -323.241312) (xy 48.76415 -323.22184) (xy 48.717992 -323.195191)
			(xy 48.676321 -323.16196) (xy 48.640069 -323.122889) (xy 48.610045 -323.078852) (xy 48.586919 -323.030831)
			(xy 48.571209 -322.979901) (xy 48.563266 -322.927197) (xy 48.562768 -322.900548) (xy 6.1976 -322.900548)
			(xy 6.1976 -323.43446) (xy 7.452844 -323.43446) (xy 7.456827 -323.381306) (xy 7.468689 -323.329339)
			(xy 7.488163 -323.27972) (xy 7.514814 -323.233559) (xy 7.548049 -323.191885) (xy 7.587123 -323.155629)
			(xy 7.631164 -323.125603) (xy 7.679189 -323.102476) (xy 7.730124 -323.086765) (xy 7.782832 -323.078821)
			(xy 7.809484 -323.078348) (xy 7.835892 -323.078855) (xy 7.888128 -323.086653) (xy 7.93864 -323.10208)
			(xy 7.986319 -323.124798) (xy 8.030121 -323.15431) (xy 8.069083 -323.189966) (xy 8.08609 -323.210174)
			(xy 8.096027 -323.221567) (xy 8.12108 -323.238458) (xy 8.149976 -323.247289) (xy 8.180192 -323.247289)
			(xy 8.209088 -323.238458) (xy 8.234141 -323.221567) (xy 8.244078 -323.210174) (xy 8.261082 -323.189962)
			(xy 8.300044 -323.154302) (xy 8.343845 -323.124786) (xy 8.391525 -323.102064) (xy 8.442037 -323.086632)
			(xy 8.494275 -323.078829) (xy 8.520684 -323.078348) (xy 8.547333 -323.078854) (xy 8.600035 -323.086798)
			(xy 8.650965 -323.102508) (xy 8.698984 -323.125634) (xy 8.74302 -323.155658) (xy 8.78209 -323.191909)
			(xy 8.81532 -323.233579) (xy 8.841969 -323.279737) (xy 8.861441 -323.32935) (xy 8.873301 -323.381311)
			(xy 8.877284 -323.43446) (xy 11.516844 -323.43446) (xy 11.520827 -323.381306) (xy 11.532689 -323.329339)
			(xy 11.552163 -323.27972) (xy 11.578814 -323.233559) (xy 11.612049 -323.191885) (xy 11.651123 -323.155629)
			(xy 11.695164 -323.125603) (xy 11.743189 -323.102476) (xy 11.794124 -323.086765) (xy 11.846832 -323.078821)
			(xy 11.873484 -323.078348) (xy 11.899892 -323.078855) (xy 11.952128 -323.086653) (xy 12.00264 -323.10208)
			(xy 12.050319 -323.124798) (xy 12.094121 -323.15431) (xy 12.133083 -323.189966) (xy 12.15009 -323.210174)
			(xy 12.160027 -323.221567) (xy 12.18508 -323.238458) (xy 12.213976 -323.247289) (xy 12.244192 -323.247289)
			(xy 12.273088 -323.238458) (xy 12.298141 -323.221567) (xy 12.308078 -323.210174) (xy 12.325082 -323.189962)
			(xy 12.364044 -323.154302) (xy 12.407845 -323.124786) (xy 12.455525 -323.102064) (xy 12.506037 -323.086632)
			(xy 12.558275 -323.078829) (xy 12.584684 -323.078348) (xy 12.611333 -323.078854) (xy 12.664035 -323.086798)
			(xy 12.714965 -323.102508) (xy 12.762984 -323.125634) (xy 12.80702 -323.155658) (xy 12.84609 -323.191909)
			(xy 12.87932 -323.233579) (xy 12.905969 -323.279737) (xy 12.925441 -323.32935) (xy 12.937301 -323.381311)
			(xy 12.941284 -323.43446) (xy 14.996644 -323.43446) (xy 15.000627 -323.381306) (xy 15.012489 -323.329339)
			(xy 15.031963 -323.27972) (xy 15.058614 -323.233559) (xy 15.091849 -323.191885) (xy 15.130923 -323.155629)
			(xy 15.174964 -323.125603) (xy 15.222989 -323.102476) (xy 15.273924 -323.086765) (xy 15.326632 -323.078821)
			(xy 15.353284 -323.078348) (xy 15.379692 -323.078855) (xy 15.431928 -323.086653) (xy 15.48244 -323.10208)
			(xy 15.530119 -323.124798) (xy 15.573921 -323.15431) (xy 15.612883 -323.189966) (xy 15.62989 -323.210174)
			(xy 15.639827 -323.221567) (xy 15.66488 -323.238458) (xy 15.693776 -323.247289) (xy 15.723992 -323.247289)
			(xy 15.752888 -323.238458) (xy 15.777941 -323.221567) (xy 15.787878 -323.210174) (xy 15.804882 -323.189962)
			(xy 15.843844 -323.154302) (xy 15.887645 -323.124786) (xy 15.935325 -323.102064) (xy 15.985837 -323.086632)
			(xy 16.038075 -323.078829) (xy 16.064484 -323.078348) (xy 16.091133 -323.078854) (xy 16.143835 -323.086798)
			(xy 16.194765 -323.102508) (xy 16.242784 -323.125634) (xy 16.28682 -323.155658) (xy 16.32589 -323.191909)
			(xy 16.35912 -323.233579) (xy 16.385769 -323.279737) (xy 16.405241 -323.32935) (xy 16.417101 -323.381311)
			(xy 16.421084 -323.43446) (xy 19.060644 -323.43446) (xy 19.064627 -323.381306) (xy 19.076489 -323.329339)
			(xy 19.095963 -323.27972) (xy 19.122614 -323.233559) (xy 19.155849 -323.191885) (xy 19.194923 -323.155629)
			(xy 19.238964 -323.125603) (xy 19.286989 -323.102476) (xy 19.337924 -323.086765) (xy 19.390632 -323.078821)
			(xy 19.417284 -323.078348) (xy 19.443692 -323.078855) (xy 19.495928 -323.086653) (xy 19.54644 -323.10208)
			(xy 19.594119 -323.124798) (xy 19.637921 -323.15431) (xy 19.676883 -323.189966) (xy 19.69389 -323.210174)
			(xy 19.703827 -323.221567) (xy 19.72888 -323.238458) (xy 19.757776 -323.247289) (xy 19.787992 -323.247289)
			(xy 19.816888 -323.238458) (xy 19.841941 -323.221567) (xy 19.851878 -323.210174) (xy 19.868882 -323.189962)
			(xy 19.907844 -323.154302) (xy 19.951645 -323.124786) (xy 19.999325 -323.102064) (xy 20.049837 -323.086632)
			(xy 20.102075 -323.078829) (xy 20.128484 -323.078348) (xy 20.155133 -323.078854) (xy 20.207835 -323.086798)
			(xy 20.258765 -323.102508) (xy 20.306784 -323.125634) (xy 20.35082 -323.155658) (xy 20.38989 -323.191909)
			(xy 20.42312 -323.233579) (xy 20.449769 -323.279737) (xy 20.469241 -323.32935) (xy 20.481101 -323.381311)
			(xy 20.485084 -323.43446) (xy 20.485081 -323.4345) (xy 22.540448 -323.4345) (xy 22.544432 -323.381345)
			(xy 22.556293 -323.329378) (xy 22.575766 -323.279759) (xy 22.602417 -323.233596) (xy 22.635651 -323.191921)
			(xy 22.674724 -323.155664) (xy 22.718765 -323.125636) (xy 22.766789 -323.102507) (xy 22.817724 -323.086794)
			(xy 22.870432 -323.078847) (xy 22.897084 -323.078348) (xy 22.923492 -323.078855) (xy 22.975728 -323.086653)
			(xy 23.02624 -323.10208) (xy 23.073919 -323.124798) (xy 23.117721 -323.15431) (xy 23.156683 -323.189966)
			(xy 23.17369 -323.210174) (xy 23.183627 -323.221567) (xy 23.20868 -323.238458) (xy 23.237576 -323.247289)
			(xy 23.267792 -323.247289) (xy 23.296688 -323.238458) (xy 23.321741 -323.221567) (xy 23.331678 -323.210174)
			(xy 23.348682 -323.189962) (xy 23.387644 -323.154302) (xy 23.431445 -323.124786) (xy 23.479125 -323.102064)
			(xy 23.529637 -323.086632) (xy 23.581875 -323.078829) (xy 23.608284 -323.078348) (xy 23.634933 -323.078908)
			(xy 23.687635 -323.086849) (xy 23.738565 -323.102557) (xy 23.786585 -323.12568) (xy 23.830622 -323.155703)
			(xy 23.869692 -323.191953) (xy 23.902923 -323.233622) (xy 23.929573 -323.279778) (xy 23.949045 -323.329391)
			(xy 23.960905 -323.381352) (xy 23.964888 -323.4345) (xy 26.604448 -323.4345) (xy 26.608432 -323.381345)
			(xy 26.620293 -323.329378) (xy 26.639766 -323.279759) (xy 26.666417 -323.233596) (xy 26.699651 -323.191921)
			(xy 26.738724 -323.155664) (xy 26.782765 -323.125636) (xy 26.830789 -323.102507) (xy 26.881724 -323.086794)
			(xy 26.934432 -323.078847) (xy 26.961084 -323.078348) (xy 26.987492 -323.078855) (xy 27.039728 -323.086653)
			(xy 27.09024 -323.10208) (xy 27.137919 -323.124798) (xy 27.181721 -323.15431) (xy 27.220683 -323.189966)
			(xy 27.23769 -323.210174) (xy 27.247627 -323.221567) (xy 27.27268 -323.238458) (xy 27.301576 -323.247289)
			(xy 27.331792 -323.247289) (xy 27.360688 -323.238458) (xy 27.385741 -323.221567) (xy 27.395678 -323.210174)
			(xy 27.412682 -323.189962) (xy 27.451644 -323.154302) (xy 27.495445 -323.124786) (xy 27.543125 -323.102064)
			(xy 27.593637 -323.086632) (xy 27.645875 -323.078829) (xy 27.672284 -323.078348) (xy 27.698933 -323.078908)
			(xy 27.751635 -323.086849) (xy 27.802565 -323.102557) (xy 27.850585 -323.12568) (xy 27.894622 -323.155703)
			(xy 27.933692 -323.191953) (xy 27.966923 -323.233622) (xy 27.993573 -323.279778) (xy 28.013045 -323.329391)
			(xy 28.024905 -323.381352) (xy 28.028888 -323.4345) (xy 30.084248 -323.4345) (xy 30.088232 -323.381345)
			(xy 30.100093 -323.329378) (xy 30.119566 -323.279759) (xy 30.146217 -323.233596) (xy 30.179451 -323.191921)
			(xy 30.218524 -323.155664) (xy 30.262565 -323.125636) (xy 30.310589 -323.102507) (xy 30.361524 -323.086794)
			(xy 30.414232 -323.078847) (xy 30.440884 -323.078348) (xy 30.467292 -323.078855) (xy 30.519528 -323.086653)
			(xy 30.57004 -323.10208) (xy 30.617719 -323.124798) (xy 30.661521 -323.15431) (xy 30.700483 -323.189966)
			(xy 30.71749 -323.210174) (xy 30.727427 -323.221567) (xy 30.75248 -323.238458) (xy 30.781376 -323.247289)
			(xy 30.811592 -323.247289) (xy 30.840488 -323.238458) (xy 30.865541 -323.221567) (xy 30.875478 -323.210174)
			(xy 30.892482 -323.189962) (xy 30.931444 -323.154302) (xy 30.975245 -323.124786) (xy 31.022925 -323.102064)
			(xy 31.073437 -323.086632) (xy 31.125675 -323.078829) (xy 31.152084 -323.078348) (xy 31.178733 -323.078908)
			(xy 31.231435 -323.086849) (xy 31.282365 -323.102557) (xy 31.330385 -323.12568) (xy 31.374422 -323.155703)
			(xy 31.413492 -323.191953) (xy 31.446723 -323.233622) (xy 31.473373 -323.279778) (xy 31.492845 -323.329391)
			(xy 31.504705 -323.381352) (xy 31.508688 -323.4345) (xy 34.148248 -323.4345) (xy 34.152232 -323.381345)
			(xy 34.164093 -323.329378) (xy 34.183566 -323.279759) (xy 34.210217 -323.233596) (xy 34.243451 -323.191921)
			(xy 34.282524 -323.155664) (xy 34.326565 -323.125636) (xy 34.374589 -323.102507) (xy 34.425524 -323.086794)
			(xy 34.478232 -323.078847) (xy 34.504884 -323.078348) (xy 34.531292 -323.078855) (xy 34.583528 -323.086653)
			(xy 34.63404 -323.10208) (xy 34.681719 -323.124798) (xy 34.725521 -323.15431) (xy 34.764483 -323.189966)
			(xy 34.78149 -323.210174) (xy 34.791427 -323.221567) (xy 34.81648 -323.238458) (xy 34.845376 -323.247289)
			(xy 34.875592 -323.247289) (xy 34.904488 -323.238458) (xy 34.929541 -323.221567) (xy 34.939478 -323.210174)
			(xy 34.956482 -323.189962) (xy 34.995444 -323.154302) (xy 35.039245 -323.124786) (xy 35.086925 -323.102064)
			(xy 35.137437 -323.086632) (xy 35.189675 -323.078829) (xy 35.216084 -323.078348) (xy 35.242733 -323.078908)
			(xy 35.295435 -323.086849) (xy 35.346365 -323.102557) (xy 35.394385 -323.12568) (xy 35.438422 -323.155703)
			(xy 35.477492 -323.191953) (xy 35.510723 -323.233622) (xy 35.537373 -323.279778) (xy 35.556845 -323.329391)
			(xy 35.568705 -323.381352) (xy 35.572688 -323.4345) (xy 37.628048 -323.4345) (xy 37.632032 -323.381345)
			(xy 37.643893 -323.329378) (xy 37.663366 -323.279759) (xy 37.690017 -323.233596) (xy 37.723251 -323.191921)
			(xy 37.762324 -323.155664) (xy 37.806365 -323.125636) (xy 37.854389 -323.102507) (xy 37.905324 -323.086794)
			(xy 37.958032 -323.078847) (xy 37.984684 -323.078348) (xy 38.011092 -323.078855) (xy 38.063328 -323.086653)
			(xy 38.11384 -323.10208) (xy 38.161519 -323.124798) (xy 38.205321 -323.15431) (xy 38.244283 -323.189966)
			(xy 38.26129 -323.210174) (xy 38.271227 -323.221567) (xy 38.29628 -323.238458) (xy 38.325176 -323.247289)
			(xy 38.355392 -323.247289) (xy 38.384288 -323.238458) (xy 38.409341 -323.221567) (xy 38.419278 -323.210174)
			(xy 38.436282 -323.189962) (xy 38.475244 -323.154302) (xy 38.519045 -323.124786) (xy 38.566725 -323.102064)
			(xy 38.617237 -323.086632) (xy 38.669475 -323.078829) (xy 38.695884 -323.078348) (xy 38.722533 -323.078908)
			(xy 38.775235 -323.086849) (xy 38.826165 -323.102557) (xy 38.874185 -323.12568) (xy 38.918222 -323.155703)
			(xy 38.957292 -323.191953) (xy 38.990523 -323.233622) (xy 39.017173 -323.279778) (xy 39.036645 -323.329391)
			(xy 39.048505 -323.381352) (xy 39.052488 -323.4345) (xy 41.692048 -323.4345) (xy 41.696032 -323.381345)
			(xy 41.707893 -323.329378) (xy 41.727366 -323.279759) (xy 41.754017 -323.233596) (xy 41.787251 -323.191921)
			(xy 41.826324 -323.155664) (xy 41.870365 -323.125636) (xy 41.918389 -323.102507) (xy 41.969324 -323.086794)
			(xy 42.022032 -323.078847) (xy 42.048684 -323.078348) (xy 42.075092 -323.078855) (xy 42.127328 -323.086653)
			(xy 42.17784 -323.10208) (xy 42.225519 -323.124798) (xy 42.269321 -323.15431) (xy 42.308283 -323.189966)
			(xy 42.32529 -323.210174) (xy 42.335227 -323.221567) (xy 42.36028 -323.238458) (xy 42.389176 -323.247289)
			(xy 42.419392 -323.247289) (xy 42.448288 -323.238458) (xy 42.473341 -323.221567) (xy 42.483278 -323.210174)
			(xy 42.500282 -323.189962) (xy 42.539244 -323.154302) (xy 42.583045 -323.124786) (xy 42.630725 -323.102064)
			(xy 42.681237 -323.086632) (xy 42.733475 -323.078829) (xy 42.759884 -323.078348) (xy 42.786533 -323.078908)
			(xy 42.839235 -323.086849) (xy 42.890165 -323.102557) (xy 42.938185 -323.12568) (xy 42.982222 -323.155703)
			(xy 43.021292 -323.191953) (xy 43.054523 -323.233622) (xy 43.081173 -323.279778) (xy 43.100645 -323.329391)
			(xy 43.112505 -323.381352) (xy 43.116488 -323.4345) (xy 45.171848 -323.4345) (xy 45.175832 -323.381345)
			(xy 45.187693 -323.329378) (xy 45.207166 -323.279759) (xy 45.233817 -323.233596) (xy 45.267051 -323.191921)
			(xy 45.306124 -323.155664) (xy 45.350165 -323.125636) (xy 45.398189 -323.102507) (xy 45.449124 -323.086794)
			(xy 45.501832 -323.078847) (xy 45.528484 -323.078348) (xy 45.554892 -323.078855) (xy 45.607128 -323.086653)
			(xy 45.65764 -323.10208) (xy 45.705319 -323.124798) (xy 45.749121 -323.15431) (xy 45.788083 -323.189966)
			(xy 45.80509 -323.210174) (xy 45.815027 -323.221567) (xy 45.84008 -323.238458) (xy 45.868976 -323.247289)
			(xy 45.899192 -323.247289) (xy 45.928088 -323.238458) (xy 45.953141 -323.221567) (xy 45.963078 -323.210174)
			(xy 45.980082 -323.189962) (xy 46.019044 -323.154302) (xy 46.062845 -323.124786) (xy 46.110525 -323.102064)
			(xy 46.161037 -323.086632) (xy 46.213275 -323.078829) (xy 46.239684 -323.078348) (xy 46.266333 -323.078908)
			(xy 46.319035 -323.086849) (xy 46.369965 -323.102557) (xy 46.417985 -323.12568) (xy 46.462022 -323.155703)
			(xy 46.501092 -323.191953) (xy 46.534323 -323.233622) (xy 46.560973 -323.279778) (xy 46.580445 -323.329391)
			(xy 46.592305 -323.381352) (xy 46.596288 -323.4345) (xy 46.592305 -323.487648) (xy 46.580445 -323.539609)
			(xy 46.560973 -323.589222) (xy 46.534323 -323.635378) (xy 46.501092 -323.677047) (xy 46.462022 -323.713297)
			(xy 46.417985 -323.74332) (xy 46.369965 -323.766443) (xy 46.319035 -323.782151) (xy 46.266333 -323.790092)
			(xy 46.239684 -323.790564) (xy 46.213274 -323.790112) (xy 46.161034 -323.782307) (xy 46.110519 -323.766871)
			(xy 46.062839 -323.744143) (xy 46.01904 -323.71462) (xy 45.980082 -323.678952) (xy 45.963078 -323.658738)
			(xy 45.953141 -323.647345) (xy 45.928088 -323.630454) (xy 45.899192 -323.621623) (xy 45.868976 -323.621623)
			(xy 45.84008 -323.630454) (xy 45.815027 -323.647345) (xy 45.80509 -323.658738) (xy 45.788106 -323.678968)
			(xy 45.74914 -323.714626) (xy 45.705335 -323.744139) (xy 45.657651 -323.766859) (xy 45.607135 -323.782287)
			(xy 45.554894 -323.790086) (xy 45.528484 -323.790564) (xy 45.501832 -323.790153) (xy 45.449124 -323.782206)
			(xy 45.398189 -323.766493) (xy 45.350165 -323.743364) (xy 45.306124 -323.713336) (xy 45.267051 -323.677079)
			(xy 45.233817 -323.635404) (xy 45.207166 -323.589241) (xy 45.187693 -323.539622) (xy 45.175832 -323.487655)
			(xy 45.171848 -323.4345) (xy 43.116488 -323.4345) (xy 43.112505 -323.487648) (xy 43.100645 -323.539609)
			(xy 43.081173 -323.589222) (xy 43.054523 -323.635378) (xy 43.021292 -323.677047) (xy 42.982222 -323.713297)
			(xy 42.938185 -323.74332) (xy 42.890165 -323.766443) (xy 42.839235 -323.782151) (xy 42.786533 -323.790092)
			(xy 42.759884 -323.790564) (xy 42.733474 -323.790112) (xy 42.681234 -323.782307) (xy 42.630719 -323.766871)
			(xy 42.583039 -323.744143) (xy 42.53924 -323.71462) (xy 42.500282 -323.678952) (xy 42.483278 -323.658738)
			(xy 42.473341 -323.647345) (xy 42.448288 -323.630454) (xy 42.419392 -323.621623) (xy 42.389176 -323.621623)
			(xy 42.36028 -323.630454) (xy 42.335227 -323.647345) (xy 42.32529 -323.658738) (xy 42.308306 -323.678968)
			(xy 42.26934 -323.714626) (xy 42.225535 -323.744139) (xy 42.177851 -323.766859) (xy 42.127335 -323.782287)
			(xy 42.075094 -323.790086) (xy 42.048684 -323.790564) (xy 42.022032 -323.790153) (xy 41.969324 -323.782206)
			(xy 41.918389 -323.766493) (xy 41.870365 -323.743364) (xy 41.826324 -323.713336) (xy 41.787251 -323.677079)
			(xy 41.754017 -323.635404) (xy 41.727366 -323.589241) (xy 41.707893 -323.539622) (xy 41.696032 -323.487655)
			(xy 41.692048 -323.4345) (xy 39.052488 -323.4345) (xy 39.048505 -323.487648) (xy 39.036645 -323.539609)
			(xy 39.017173 -323.589222) (xy 38.990523 -323.635378) (xy 38.957292 -323.677047) (xy 38.918222 -323.713297)
			(xy 38.874185 -323.74332) (xy 38.826165 -323.766443) (xy 38.775235 -323.782151) (xy 38.722533 -323.790092)
			(xy 38.695884 -323.790564) (xy 38.669474 -323.790112) (xy 38.617234 -323.782307) (xy 38.566719 -323.766871)
			(xy 38.519039 -323.744143) (xy 38.47524 -323.71462) (xy 38.436282 -323.678952) (xy 38.419278 -323.658738)
			(xy 38.409341 -323.647345) (xy 38.384288 -323.630454) (xy 38.355392 -323.621623) (xy 38.325176 -323.621623)
			(xy 38.29628 -323.630454) (xy 38.271227 -323.647345) (xy 38.26129 -323.658738) (xy 38.244306 -323.678968)
			(xy 38.20534 -323.714626) (xy 38.161535 -323.744139) (xy 38.113851 -323.766859) (xy 38.063335 -323.782287)
			(xy 38.011094 -323.790086) (xy 37.984684 -323.790564) (xy 37.958032 -323.790153) (xy 37.905324 -323.782206)
			(xy 37.854389 -323.766493) (xy 37.806365 -323.743364) (xy 37.762324 -323.713336) (xy 37.723251 -323.677079)
			(xy 37.690017 -323.635404) (xy 37.663366 -323.589241) (xy 37.643893 -323.539622) (xy 37.632032 -323.487655)
			(xy 37.628048 -323.4345) (xy 35.572688 -323.4345) (xy 35.568705 -323.487648) (xy 35.556845 -323.539609)
			(xy 35.537373 -323.589222) (xy 35.510723 -323.635378) (xy 35.477492 -323.677047) (xy 35.438422 -323.713297)
			(xy 35.394385 -323.74332) (xy 35.346365 -323.766443) (xy 35.295435 -323.782151) (xy 35.242733 -323.790092)
			(xy 35.216084 -323.790564) (xy 35.189674 -323.790112) (xy 35.137434 -323.782307) (xy 35.086919 -323.766871)
			(xy 35.039239 -323.744143) (xy 34.99544 -323.71462) (xy 34.956482 -323.678952) (xy 34.939478 -323.658738)
			(xy 34.929541 -323.647345) (xy 34.904488 -323.630454) (xy 34.875592 -323.621623) (xy 34.845376 -323.621623)
			(xy 34.81648 -323.630454) (xy 34.791427 -323.647345) (xy 34.78149 -323.658738) (xy 34.764506 -323.678968)
			(xy 34.72554 -323.714626) (xy 34.681735 -323.744139) (xy 34.634051 -323.766859) (xy 34.583535 -323.782287)
			(xy 34.531294 -323.790086) (xy 34.504884 -323.790564) (xy 34.478232 -323.790153) (xy 34.425524 -323.782206)
			(xy 34.374589 -323.766493) (xy 34.326565 -323.743364) (xy 34.282524 -323.713336) (xy 34.243451 -323.677079)
			(xy 34.210217 -323.635404) (xy 34.183566 -323.589241) (xy 34.164093 -323.539622) (xy 34.152232 -323.487655)
			(xy 34.148248 -323.4345) (xy 31.508688 -323.4345) (xy 31.504705 -323.487648) (xy 31.492845 -323.539609)
			(xy 31.473373 -323.589222) (xy 31.446723 -323.635378) (xy 31.413492 -323.677047) (xy 31.374422 -323.713297)
			(xy 31.330385 -323.74332) (xy 31.282365 -323.766443) (xy 31.231435 -323.782151) (xy 31.178733 -323.790092)
			(xy 31.152084 -323.790564) (xy 31.125674 -323.790112) (xy 31.073434 -323.782307) (xy 31.022919 -323.766871)
			(xy 30.975239 -323.744143) (xy 30.93144 -323.71462) (xy 30.892482 -323.678952) (xy 30.875478 -323.658738)
			(xy 30.865541 -323.647345) (xy 30.840488 -323.630454) (xy 30.811592 -323.621623) (xy 30.781376 -323.621623)
			(xy 30.75248 -323.630454) (xy 30.727427 -323.647345) (xy 30.71749 -323.658738) (xy 30.700506 -323.678968)
			(xy 30.66154 -323.714626) (xy 30.617735 -323.744139) (xy 30.570051 -323.766859) (xy 30.519535 -323.782287)
			(xy 30.467294 -323.790086) (xy 30.440884 -323.790564) (xy 30.414232 -323.790153) (xy 30.361524 -323.782206)
			(xy 30.310589 -323.766493) (xy 30.262565 -323.743364) (xy 30.218524 -323.713336) (xy 30.179451 -323.677079)
			(xy 30.146217 -323.635404) (xy 30.119566 -323.589241) (xy 30.100093 -323.539622) (xy 30.088232 -323.487655)
			(xy 30.084248 -323.4345) (xy 28.028888 -323.4345) (xy 28.024905 -323.487648) (xy 28.013045 -323.539609)
			(xy 27.993573 -323.589222) (xy 27.966923 -323.635378) (xy 27.933692 -323.677047) (xy 27.894622 -323.713297)
			(xy 27.850585 -323.74332) (xy 27.802565 -323.766443) (xy 27.751635 -323.782151) (xy 27.698933 -323.790092)
			(xy 27.672284 -323.790564) (xy 27.645874 -323.790112) (xy 27.593634 -323.782307) (xy 27.543119 -323.766871)
			(xy 27.495439 -323.744143) (xy 27.45164 -323.71462) (xy 27.412682 -323.678952) (xy 27.395678 -323.658738)
			(xy 27.385741 -323.647345) (xy 27.360688 -323.630454) (xy 27.331792 -323.621623) (xy 27.301576 -323.621623)
			(xy 27.27268 -323.630454) (xy 27.247627 -323.647345) (xy 27.23769 -323.658738) (xy 27.220706 -323.678968)
			(xy 27.18174 -323.714626) (xy 27.137935 -323.744139) (xy 27.090251 -323.766859) (xy 27.039735 -323.782287)
			(xy 26.987494 -323.790086) (xy 26.961084 -323.790564) (xy 26.934432 -323.790153) (xy 26.881724 -323.782206)
			(xy 26.830789 -323.766493) (xy 26.782765 -323.743364) (xy 26.738724 -323.713336) (xy 26.699651 -323.677079)
			(xy 26.666417 -323.635404) (xy 26.639766 -323.589241) (xy 26.620293 -323.539622) (xy 26.608432 -323.487655)
			(xy 26.604448 -323.4345) (xy 23.964888 -323.4345) (xy 23.960905 -323.487648) (xy 23.949045 -323.539609)
			(xy 23.929573 -323.589222) (xy 23.902923 -323.635378) (xy 23.869692 -323.677047) (xy 23.830622 -323.713297)
			(xy 23.786585 -323.74332) (xy 23.738565 -323.766443) (xy 23.687635 -323.782151) (xy 23.634933 -323.790092)
			(xy 23.608284 -323.790564) (xy 23.581874 -323.790112) (xy 23.529634 -323.782307) (xy 23.479119 -323.766871)
			(xy 23.431439 -323.744143) (xy 23.38764 -323.71462) (xy 23.348682 -323.678952) (xy 23.331678 -323.658738)
			(xy 23.321741 -323.647345) (xy 23.296688 -323.630454) (xy 23.267792 -323.621623) (xy 23.237576 -323.621623)
			(xy 23.20868 -323.630454) (xy 23.183627 -323.647345) (xy 23.17369 -323.658738) (xy 23.156706 -323.678968)
			(xy 23.11774 -323.714626) (xy 23.073935 -323.744139) (xy 23.026251 -323.766859) (xy 22.975735 -323.782287)
			(xy 22.923494 -323.790086) (xy 22.897084 -323.790564) (xy 22.870432 -323.790153) (xy 22.817724 -323.782206)
			(xy 22.766789 -323.766493) (xy 22.718765 -323.743364) (xy 22.674724 -323.713336) (xy 22.635651 -323.677079)
			(xy 22.602417 -323.635404) (xy 22.575766 -323.589241) (xy 22.556293 -323.539622) (xy 22.544432 -323.487655)
			(xy 22.540448 -323.4345) (xy 20.485081 -323.4345) (xy 20.481101 -323.487609) (xy 20.469241 -323.53957)
			(xy 20.449769 -323.589183) (xy 20.42312 -323.635341) (xy 20.38989 -323.677011) (xy 20.35082 -323.713262)
			(xy 20.306784 -323.743286) (xy 20.258765 -323.766412) (xy 20.207835 -323.782122) (xy 20.155133 -323.790066)
			(xy 20.128484 -323.790564) (xy 20.102074 -323.790112) (xy 20.049834 -323.782307) (xy 19.999319 -323.766871)
			(xy 19.951639 -323.744143) (xy 19.90784 -323.71462) (xy 19.868882 -323.678952) (xy 19.851878 -323.658738)
			(xy 19.841941 -323.647345) (xy 19.816888 -323.630454) (xy 19.787992 -323.621623) (xy 19.757776 -323.621623)
			(xy 19.72888 -323.630454) (xy 19.703827 -323.647345) (xy 19.69389 -323.658738) (xy 19.676906 -323.678968)
			(xy 19.63794 -323.714626) (xy 19.594135 -323.744139) (xy 19.546451 -323.766859) (xy 19.495935 -323.782287)
			(xy 19.443694 -323.790086) (xy 19.417284 -323.790564) (xy 19.390632 -323.790099) (xy 19.337924 -323.782155)
			(xy 19.286989 -323.766444) (xy 19.238964 -323.743317) (xy 19.194923 -323.713291) (xy 19.155849 -323.677035)
			(xy 19.122614 -323.635361) (xy 19.095963 -323.5892) (xy 19.076489 -323.539581) (xy 19.064627 -323.487614)
			(xy 19.060644 -323.43446) (xy 16.421084 -323.43446) (xy 16.417101 -323.487609) (xy 16.405241 -323.53957)
			(xy 16.385769 -323.589183) (xy 16.35912 -323.635341) (xy 16.32589 -323.677011) (xy 16.28682 -323.713262)
			(xy 16.242784 -323.743286) (xy 16.194765 -323.766412) (xy 16.143835 -323.782122) (xy 16.091133 -323.790066)
			(xy 16.064484 -323.790564) (xy 16.038074 -323.790112) (xy 15.985834 -323.782307) (xy 15.935319 -323.766871)
			(xy 15.887639 -323.744143) (xy 15.84384 -323.71462) (xy 15.804882 -323.678952) (xy 15.787878 -323.658738)
			(xy 15.777941 -323.647345) (xy 15.752888 -323.630454) (xy 15.723992 -323.621623) (xy 15.693776 -323.621623)
			(xy 15.66488 -323.630454) (xy 15.639827 -323.647345) (xy 15.62989 -323.658738) (xy 15.612906 -323.678968)
			(xy 15.57394 -323.714626) (xy 15.530135 -323.744139) (xy 15.482451 -323.766859) (xy 15.431935 -323.782287)
			(xy 15.379694 -323.790086) (xy 15.353284 -323.790564) (xy 15.326632 -323.790099) (xy 15.273924 -323.782155)
			(xy 15.222989 -323.766444) (xy 15.174964 -323.743317) (xy 15.130923 -323.713291) (xy 15.091849 -323.677035)
			(xy 15.058614 -323.635361) (xy 15.031963 -323.5892) (xy 15.012489 -323.539581) (xy 15.000627 -323.487614)
			(xy 14.996644 -323.43446) (xy 12.941284 -323.43446) (xy 12.937301 -323.487609) (xy 12.925441 -323.53957)
			(xy 12.905969 -323.589183) (xy 12.87932 -323.635341) (xy 12.84609 -323.677011) (xy 12.80702 -323.713262)
			(xy 12.762984 -323.743286) (xy 12.714965 -323.766412) (xy 12.664035 -323.782122) (xy 12.611333 -323.790066)
			(xy 12.584684 -323.790564) (xy 12.558274 -323.790112) (xy 12.506034 -323.782307) (xy 12.455519 -323.766871)
			(xy 12.407839 -323.744143) (xy 12.36404 -323.71462) (xy 12.325082 -323.678952) (xy 12.308078 -323.658738)
			(xy 12.298141 -323.647345) (xy 12.273088 -323.630454) (xy 12.244192 -323.621623) (xy 12.213976 -323.621623)
			(xy 12.18508 -323.630454) (xy 12.160027 -323.647345) (xy 12.15009 -323.658738) (xy 12.133106 -323.678968)
			(xy 12.09414 -323.714626) (xy 12.050335 -323.744139) (xy 12.002651 -323.766859) (xy 11.952135 -323.782287)
			(xy 11.899894 -323.790086) (xy 11.873484 -323.790564) (xy 11.846832 -323.790099) (xy 11.794124 -323.782155)
			(xy 11.743189 -323.766444) (xy 11.695164 -323.743317) (xy 11.651123 -323.713291) (xy 11.612049 -323.677035)
			(xy 11.578814 -323.635361) (xy 11.552163 -323.5892) (xy 11.532689 -323.539581) (xy 11.520827 -323.487614)
			(xy 11.516844 -323.43446) (xy 8.877284 -323.43446) (xy 8.873301 -323.487609) (xy 8.861441 -323.53957)
			(xy 8.841969 -323.589183) (xy 8.81532 -323.635341) (xy 8.78209 -323.677011) (xy 8.74302 -323.713262)
			(xy 8.698984 -323.743286) (xy 8.650965 -323.766412) (xy 8.600035 -323.782122) (xy 8.547333 -323.790066)
			(xy 8.520684 -323.790564) (xy 8.494274 -323.790112) (xy 8.442034 -323.782307) (xy 8.391519 -323.766871)
			(xy 8.343839 -323.744143) (xy 8.30004 -323.71462) (xy 8.261082 -323.678952) (xy 8.244078 -323.658738)
			(xy 8.234141 -323.647345) (xy 8.209088 -323.630454) (xy 8.180192 -323.621623) (xy 8.149976 -323.621623)
			(xy 8.12108 -323.630454) (xy 8.096027 -323.647345) (xy 8.08609 -323.658738) (xy 8.069106 -323.678968)
			(xy 8.03014 -323.714626) (xy 7.986335 -323.744139) (xy 7.938651 -323.766859) (xy 7.888135 -323.782287)
			(xy 7.835894 -323.790086) (xy 7.809484 -323.790564) (xy 7.782832 -323.790099) (xy 7.730124 -323.782155)
			(xy 7.679189 -323.766444) (xy 7.631164 -323.743317) (xy 7.587123 -323.713291) (xy 7.548049 -323.677035)
			(xy 7.514814 -323.635361) (xy 7.488163 -323.5892) (xy 7.468689 -323.539581) (xy 7.456827 -323.487614)
			(xy 7.452844 -323.43446) (xy 6.1976 -323.43446) (xy 6.1976 -327.108936) (xy 8.653756 -327.108936)
			(xy 8.653756 -327.024384) (xy 8.661558 -326.940192) (xy 8.677094 -326.857079) (xy 8.700233 -326.775754)
			(xy 8.730777 -326.696911) (xy 8.768466 -326.621222) (xy 8.812977 -326.549334) (xy 8.863931 -326.481859)
			(xy 8.920894 -326.419374) (xy 8.983379 -326.362411) (xy 9.050854 -326.311457) (xy 9.122742 -326.266946)
			(xy 9.198431 -326.229257) (xy 9.277274 -326.198713) (xy 9.358599 -326.175574) (xy 9.441712 -326.160038)
			(xy 9.525904 -326.152236) (xy 9.56818 -326.151748) (xy 10.81278 -326.151748) (xy 10.855056 -326.152244)
			(xy 10.939247 -326.160046) (xy 11.02236 -326.175582) (xy 11.103684 -326.198721) (xy 11.182526 -326.229265)
			(xy 11.258214 -326.266953) (xy 11.330102 -326.311463) (xy 11.397576 -326.362417) (xy 11.46006 -326.41938)
			(xy 11.517023 -326.481864) (xy 11.567977 -326.549338) (xy 11.612487 -326.621226) (xy 11.650175 -326.696914)
			(xy 11.680719 -326.775756) (xy 11.703858 -326.85708) (xy 11.719394 -326.940193) (xy 11.727196 -327.024384)
			(xy 11.727196 -327.108936) (xy 16.197556 -327.108936) (xy 16.197556 -327.024384) (xy 16.205358 -326.940192)
			(xy 16.220894 -326.857079) (xy 16.244033 -326.775754) (xy 16.274577 -326.696911) (xy 16.312266 -326.621222)
			(xy 16.356777 -326.549334) (xy 16.407731 -326.481859) (xy 16.464694 -326.419374) (xy 16.527179 -326.362411)
			(xy 16.594654 -326.311457) (xy 16.666542 -326.266946) (xy 16.742231 -326.229257) (xy 16.821074 -326.198713)
			(xy 16.902399 -326.175574) (xy 16.985512 -326.160038) (xy 17.069704 -326.152236) (xy 17.11198 -326.151748)
			(xy 18.35658 -326.151748) (xy 18.398856 -326.152244) (xy 18.483047 -326.160046) (xy 18.56616 -326.175582)
			(xy 18.647484 -326.198721) (xy 18.726326 -326.229265) (xy 18.802014 -326.266953) (xy 18.873902 -326.311463)
			(xy 18.941376 -326.362417) (xy 19.00386 -326.41938) (xy 19.060823 -326.481864) (xy 19.111777 -326.549338)
			(xy 19.156287 -326.621226) (xy 19.193975 -326.696914) (xy 19.224519 -326.775756) (xy 19.247658 -326.85708)
			(xy 19.263194 -326.940193) (xy 19.270996 -327.024384) (xy 19.270996 -327.108936) (xy 23.741356 -327.108936)
			(xy 23.741356 -327.024384) (xy 23.749158 -326.940192) (xy 23.764694 -326.857079) (xy 23.787833 -326.775754)
			(xy 23.818377 -326.696911) (xy 23.856066 -326.621222) (xy 23.900577 -326.549334) (xy 23.951531 -326.481859)
			(xy 24.008494 -326.419374) (xy 24.070979 -326.362411) (xy 24.138454 -326.311457) (xy 24.210342 -326.266946)
			(xy 24.286031 -326.229257) (xy 24.364874 -326.198713) (xy 24.446199 -326.175574) (xy 24.529312 -326.160038)
			(xy 24.613504 -326.152236) (xy 24.65578 -326.151748) (xy 25.90038 -326.151748) (xy 25.942656 -326.152244)
			(xy 26.026847 -326.160046) (xy 26.10996 -326.175582) (xy 26.191284 -326.198721) (xy 26.270126 -326.229265)
			(xy 26.345814 -326.266953) (xy 26.417702 -326.311463) (xy 26.485176 -326.362417) (xy 26.54766 -326.41938)
			(xy 26.604623 -326.481864) (xy 26.655577 -326.549338) (xy 26.700087 -326.621226) (xy 26.737775 -326.696914)
			(xy 26.768319 -326.775756) (xy 26.791458 -326.85708) (xy 26.806994 -326.940193) (xy 26.814796 -327.024384)
			(xy 26.814796 -327.108936) (xy 31.285156 -327.108936) (xy 31.285156 -327.024384) (xy 31.292958 -326.940192)
			(xy 31.308494 -326.857079) (xy 31.331633 -326.775754) (xy 31.362177 -326.696911) (xy 31.399866 -326.621222)
			(xy 31.444377 -326.549334) (xy 31.495331 -326.481859) (xy 31.552294 -326.419374) (xy 31.614779 -326.362411)
			(xy 31.682254 -326.311457) (xy 31.754142 -326.266946) (xy 31.829831 -326.229257) (xy 31.908674 -326.198713)
			(xy 31.989999 -326.175574) (xy 32.073112 -326.160038) (xy 32.157304 -326.152236) (xy 32.19958 -326.151748)
			(xy 33.44418 -326.151748) (xy 33.486456 -326.152244) (xy 33.570647 -326.160046) (xy 33.65376 -326.175582)
			(xy 33.735084 -326.198721) (xy 33.813926 -326.229265) (xy 33.889614 -326.266953) (xy 33.961502 -326.311463)
			(xy 34.028976 -326.362417) (xy 34.09146 -326.41938) (xy 34.148423 -326.481864) (xy 34.199377 -326.549338)
			(xy 34.243887 -326.621226) (xy 34.281575 -326.696914) (xy 34.312119 -326.775756) (xy 34.335258 -326.85708)
			(xy 34.350794 -326.940193) (xy 34.358596 -327.024384) (xy 34.358596 -327.108936) (xy 38.828956 -327.108936)
			(xy 38.828956 -327.024384) (xy 38.836758 -326.940192) (xy 38.852294 -326.857079) (xy 38.875433 -326.775754)
			(xy 38.905977 -326.696911) (xy 38.943666 -326.621222) (xy 38.988177 -326.549334) (xy 39.039131 -326.481859)
			(xy 39.096094 -326.419374) (xy 39.158579 -326.362411) (xy 39.226054 -326.311457) (xy 39.297942 -326.266946)
			(xy 39.373631 -326.229257) (xy 39.452474 -326.198713) (xy 39.533799 -326.175574) (xy 39.616912 -326.160038)
			(xy 39.701104 -326.152236) (xy 39.74338 -326.151748) (xy 40.98798 -326.151748) (xy 41.030256 -326.152244)
			(xy 41.114447 -326.160046) (xy 41.19756 -326.175582) (xy 41.278884 -326.198721) (xy 41.357726 -326.229265)
			(xy 41.433414 -326.266953) (xy 41.505302 -326.311463) (xy 41.572776 -326.362417) (xy 41.63526 -326.41938)
			(xy 41.692223 -326.481864) (xy 41.743177 -326.549338) (xy 41.787687 -326.621226) (xy 41.825375 -326.696914)
			(xy 41.855919 -326.775756) (xy 41.879058 -326.85708) (xy 41.894594 -326.940193) (xy 41.902396 -327.024384)
			(xy 41.902396 -327.108936) (xy 46.372756 -327.108936) (xy 46.372756 -327.024384) (xy 46.380558 -326.940192)
			(xy 46.396094 -326.857079) (xy 46.419233 -326.775754) (xy 46.449777 -326.696911) (xy 46.487466 -326.621222)
			(xy 46.531977 -326.549334) (xy 46.582931 -326.481859) (xy 46.639894 -326.419374) (xy 46.702379 -326.362411)
			(xy 46.769854 -326.311457) (xy 46.841742 -326.266946) (xy 46.917431 -326.229257) (xy 46.996274 -326.198713)
			(xy 47.077599 -326.175574) (xy 47.160712 -326.160038) (xy 47.244904 -326.152236) (xy 47.28718 -326.151748)
			(xy 48.53178 -326.151748) (xy 48.574056 -326.152244) (xy 48.658247 -326.160046) (xy 48.74136 -326.175582)
			(xy 48.822684 -326.198721) (xy 48.901526 -326.229265) (xy 48.977214 -326.266953) (xy 49.049102 -326.311463)
			(xy 49.116576 -326.362417) (xy 49.17906 -326.41938) (xy 49.236023 -326.481864) (xy 49.286977 -326.549338)
			(xy 49.331487 -326.621226) (xy 49.369175 -326.696914) (xy 49.399719 -326.775756) (xy 49.422858 -326.85708)
			(xy 49.438394 -326.940193) (xy 49.446196 -327.024384) (xy 49.446196 -327.108936) (xy 49.438394 -327.193127)
			(xy 49.422858 -327.27624) (xy 49.399719 -327.357564) (xy 49.369175 -327.436406) (xy 49.331487 -327.512094)
			(xy 49.286977 -327.583982) (xy 49.236023 -327.651456) (xy 49.17906 -327.71394) (xy 49.116576 -327.770903)
			(xy 49.049102 -327.821857) (xy 48.977214 -327.866367) (xy 48.901526 -327.904055) (xy 48.822684 -327.934599)
			(xy 48.74136 -327.957738) (xy 48.658247 -327.973274) (xy 48.574056 -327.981076) (xy 48.53178 -327.981564)
			(xy 47.28718 -327.981564) (xy 47.244904 -327.981084) (xy 47.160712 -327.973282) (xy 47.077599 -327.957746)
			(xy 46.996274 -327.934607) (xy 46.917431 -327.904063) (xy 46.841742 -327.866374) (xy 46.769854 -327.821863)
			(xy 46.702379 -327.770909) (xy 46.639894 -327.713946) (xy 46.582931 -327.651461) (xy 46.531977 -327.583986)
			(xy 46.487466 -327.512098) (xy 46.449777 -327.436409) (xy 46.419233 -327.357566) (xy 46.396094 -327.276241)
			(xy 46.380558 -327.193128) (xy 46.372756 -327.108936) (xy 41.902396 -327.108936) (xy 41.894594 -327.193127)
			(xy 41.879058 -327.27624) (xy 41.855919 -327.357564) (xy 41.825375 -327.436406) (xy 41.787687 -327.512094)
			(xy 41.743177 -327.583982) (xy 41.692223 -327.651456) (xy 41.63526 -327.71394) (xy 41.572776 -327.770903)
			(xy 41.505302 -327.821857) (xy 41.433414 -327.866367) (xy 41.357726 -327.904055) (xy 41.278884 -327.934599)
			(xy 41.19756 -327.957738) (xy 41.114447 -327.973274) (xy 41.030256 -327.981076) (xy 40.98798 -327.981564)
			(xy 39.74338 -327.981564) (xy 39.701104 -327.981084) (xy 39.616912 -327.973282) (xy 39.533799 -327.957746)
			(xy 39.452474 -327.934607) (xy 39.373631 -327.904063) (xy 39.297942 -327.866374) (xy 39.226054 -327.821863)
			(xy 39.158579 -327.770909) (xy 39.096094 -327.713946) (xy 39.039131 -327.651461) (xy 38.988177 -327.583986)
			(xy 38.943666 -327.512098) (xy 38.905977 -327.436409) (xy 38.875433 -327.357566) (xy 38.852294 -327.276241)
			(xy 38.836758 -327.193128) (xy 38.828956 -327.108936) (xy 34.358596 -327.108936) (xy 34.350794 -327.193127)
			(xy 34.335258 -327.27624) (xy 34.312119 -327.357564) (xy 34.281575 -327.436406) (xy 34.243887 -327.512094)
			(xy 34.199377 -327.583982) (xy 34.148423 -327.651456) (xy 34.09146 -327.71394) (xy 34.028976 -327.770903)
			(xy 33.961502 -327.821857) (xy 33.889614 -327.866367) (xy 33.813926 -327.904055) (xy 33.735084 -327.934599)
			(xy 33.65376 -327.957738) (xy 33.570647 -327.973274) (xy 33.486456 -327.981076) (xy 33.44418 -327.981564)
			(xy 32.19958 -327.981564) (xy 32.157304 -327.981084) (xy 32.073112 -327.973282) (xy 31.989999 -327.957746)
			(xy 31.908674 -327.934607) (xy 31.829831 -327.904063) (xy 31.754142 -327.866374) (xy 31.682254 -327.821863)
			(xy 31.614779 -327.770909) (xy 31.552294 -327.713946) (xy 31.495331 -327.651461) (xy 31.444377 -327.583986)
			(xy 31.399866 -327.512098) (xy 31.362177 -327.436409) (xy 31.331633 -327.357566) (xy 31.308494 -327.276241)
			(xy 31.292958 -327.193128) (xy 31.285156 -327.108936) (xy 26.814796 -327.108936) (xy 26.806994 -327.193127)
			(xy 26.791458 -327.27624) (xy 26.768319 -327.357564) (xy 26.737775 -327.436406) (xy 26.700087 -327.512094)
			(xy 26.655577 -327.583982) (xy 26.604623 -327.651456) (xy 26.54766 -327.71394) (xy 26.485176 -327.770903)
			(xy 26.417702 -327.821857) (xy 26.345814 -327.866367) (xy 26.270126 -327.904055) (xy 26.191284 -327.934599)
			(xy 26.10996 -327.957738) (xy 26.026847 -327.973274) (xy 25.942656 -327.981076) (xy 25.90038 -327.981564)
			(xy 24.65578 -327.981564) (xy 24.613504 -327.981084) (xy 24.529312 -327.973282) (xy 24.446199 -327.957746)
			(xy 24.364874 -327.934607) (xy 24.286031 -327.904063) (xy 24.210342 -327.866374) (xy 24.138454 -327.821863)
			(xy 24.070979 -327.770909) (xy 24.008494 -327.713946) (xy 23.951531 -327.651461) (xy 23.900577 -327.583986)
			(xy 23.856066 -327.512098) (xy 23.818377 -327.436409) (xy 23.787833 -327.357566) (xy 23.764694 -327.276241)
			(xy 23.749158 -327.193128) (xy 23.741356 -327.108936) (xy 19.270996 -327.108936) (xy 19.263194 -327.193127)
			(xy 19.247658 -327.27624) (xy 19.224519 -327.357564) (xy 19.193975 -327.436406) (xy 19.156287 -327.512094)
			(xy 19.111777 -327.583982) (xy 19.060823 -327.651456) (xy 19.00386 -327.71394) (xy 18.941376 -327.770903)
			(xy 18.873902 -327.821857) (xy 18.802014 -327.866367) (xy 18.726326 -327.904055) (xy 18.647484 -327.934599)
			(xy 18.56616 -327.957738) (xy 18.483047 -327.973274) (xy 18.398856 -327.981076) (xy 18.35658 -327.981564)
			(xy 17.11198 -327.981564) (xy 17.069704 -327.981084) (xy 16.985512 -327.973282) (xy 16.902399 -327.957746)
			(xy 16.821074 -327.934607) (xy 16.742231 -327.904063) (xy 16.666542 -327.866374) (xy 16.594654 -327.821863)
			(xy 16.527179 -327.770909) (xy 16.464694 -327.713946) (xy 16.407731 -327.651461) (xy 16.356777 -327.583986)
			(xy 16.312266 -327.512098) (xy 16.274577 -327.436409) (xy 16.244033 -327.357566) (xy 16.220894 -327.276241)
			(xy 16.205358 -327.193128) (xy 16.197556 -327.108936) (xy 11.727196 -327.108936) (xy 11.719394 -327.193127)
			(xy 11.703858 -327.27624) (xy 11.680719 -327.357564) (xy 11.650175 -327.436406) (xy 11.612487 -327.512094)
			(xy 11.567977 -327.583982) (xy 11.517023 -327.651456) (xy 11.46006 -327.71394) (xy 11.397576 -327.770903)
			(xy 11.330102 -327.821857) (xy 11.258214 -327.866367) (xy 11.182526 -327.904055) (xy 11.103684 -327.934599)
			(xy 11.02236 -327.957738) (xy 10.939247 -327.973274) (xy 10.855056 -327.981076) (xy 10.81278 -327.981564)
			(xy 9.56818 -327.981564) (xy 9.525904 -327.981084) (xy 9.441712 -327.973282) (xy 9.358599 -327.957746)
			(xy 9.277274 -327.934607) (xy 9.198431 -327.904063) (xy 9.122742 -327.866374) (xy 9.050854 -327.821863)
			(xy 8.983379 -327.770909) (xy 8.920894 -327.713946) (xy 8.863931 -327.651461) (xy 8.812977 -327.583986)
			(xy 8.768466 -327.512098) (xy 8.730777 -327.436409) (xy 8.700233 -327.357566) (xy 8.677094 -327.276241)
			(xy 8.661558 -327.193128) (xy 8.653756 -327.108936) (xy 6.1976 -327.108936) (xy 6.1976 -333.79791)
			(xy 13.658344 -333.79791) (xy 13.662388 -333.719456) (xy 13.674477 -333.641834) (xy 13.694484 -333.565866)
			(xy 13.722195 -333.492358) (xy 13.757318 -333.422089) (xy 13.79948 -333.355804) (xy 13.848234 -333.294205)
			(xy 13.903063 -333.237945) (xy 13.963386 -333.187621) (xy 14.028564 -333.143767) (xy 14.097905 -333.106846)
			(xy 14.170676 -333.077251) (xy 14.246103 -333.055296) (xy 14.323388 -333.041212) (xy 14.401712 -333.035149)
			(xy 14.480244 -333.037172) (xy 14.558152 -333.047258) (xy 14.634609 -333.065302) (xy 14.708807 -333.091112)
			(xy 14.779957 -333.124414) (xy 14.847306 -333.164855) (xy 14.91014 -333.212006) (xy 14.967792 -333.265369)
			(xy 15.019652 -333.324376) (xy 15.065171 -333.388403) (xy 15.103864 -333.456771) (xy 15.135323 -333.528755)
			(xy 15.159214 -333.603592) (xy 15.175283 -333.680489) (xy 15.18336 -333.758631) (xy 15.183866 -333.79791)
			(xy 15.18336 -333.837189) (xy 15.175283 -333.915331) (xy 15.159214 -333.992228) (xy 15.135323 -334.067065)
			(xy 15.103864 -334.139049) (xy 15.065171 -334.207417) (xy 15.019652 -334.271444) (xy 14.967792 -334.330451)
			(xy 14.91014 -334.383814) (xy 14.847306 -334.430965) (xy 14.779957 -334.471406) (xy 14.708807 -334.504708)
			(xy 14.634609 -334.530518) (xy 14.558152 -334.548562) (xy 14.480244 -334.558648) (xy 14.401712 -334.560671)
			(xy 14.323388 -334.554608) (xy 14.246103 -334.540524) (xy 14.170676 -334.518569) (xy 14.097905 -334.488974)
			(xy 14.028564 -334.452053) (xy 13.963386 -334.408199) (xy 13.903063 -334.357875) (xy 13.848234 -334.301615)
			(xy 13.79948 -334.240016) (xy 13.757318 -334.173731) (xy 13.722195 -334.103462) (xy 13.694484 -334.029954)
			(xy 13.674477 -333.953986) (xy 13.662388 -333.876364) (xy 13.658344 -333.79791) (xy 6.1976 -333.79791)
			(xy 6.1976 -334.67421) (xy 6.444742 -334.921352) (xy 16.280382 -334.921352) (xy 16.284453 -334.86573)
			(xy 16.296579 -334.811293) (xy 16.316502 -334.759202) (xy 16.343798 -334.710567) (xy 16.377884 -334.666424)
			(xy 16.418033 -334.627715) (xy 16.463391 -334.595264) (xy 16.512991 -334.569763) (xy 16.565775 -334.551756)
			(xy 16.620618 -334.541626) (xy 16.676352 -334.539589) (xy 16.731789 -334.545689) (xy 16.785746 -334.559795)
			(xy 16.837075 -334.581607) (xy 16.884681 -334.610661) (xy 16.927549 -334.646336) (xy 16.964766 -334.687873)
			(xy 16.995539 -334.734386) (xy 17.019211 -334.784883) (xy 17.035279 -334.83829) (xy 17.043399 -334.893466)
			(xy 17.043908 -334.921352) (xy 17.043399 -334.949238) (xy 17.035279 -335.004414) (xy 17.019211 -335.057821)
			(xy 16.995539 -335.108318) (xy 16.964766 -335.154831) (xy 16.927549 -335.196368) (xy 16.884681 -335.232043)
			(xy 16.837075 -335.261097) (xy 16.785746 -335.282909) (xy 16.731789 -335.297015) (xy 16.676352 -335.303115)
			(xy 16.620618 -335.301078) (xy 16.565775 -335.290948) (xy 16.512991 -335.272941) (xy 16.463391 -335.24744)
			(xy 16.418033 -335.214989) (xy 16.377884 -335.17628) (xy 16.343798 -335.132137) (xy 16.316502 -335.083502)
			(xy 16.296579 -335.031411) (xy 16.284453 -334.976974) (xy 16.280382 -334.921352) (xy 6.444742 -334.921352)
			(xy 7.0866 -335.56321)
		)
		(stroke
			(width 0)
			(type solid)
		)
		(fill yes)
		(layer "In4.Cu")
		(net "P12V_S3_AUX_CPU1_NVDIMM")
	)
	(gr_poly
		(pts
			(xy 178.70297 -121.545858) (xy 178.720954 -121.528503) (xy 178.761366 -121.499102) (xy 178.805885 -121.476393)
			(xy 178.853411 -121.460939) (xy 178.902772 -121.45312) (xy 178.92776 -121.45264) (xy 179.026058 -121.45264)
			(xy 179.026058 -121.400316) (xy 179.025804 -121.398538) (xy 179.025042 -121.375424) (xy 179.025552 -121.349437)
			(xy 179.033682 -121.298102) (xy 179.049743 -121.248672) (xy 179.073339 -121.202362) (xy 179.103889 -121.160314)
			(xy 179.14064 -121.123563) (xy 179.182688 -121.093013) (xy 179.228998 -121.069417) (xy 179.278428 -121.053356)
			(xy 179.329763 -121.045226) (xy 179.381737 -121.045226) (xy 179.433072 -121.053356) (xy 179.482502 -121.069417)
			(xy 179.528812 -121.093013) (xy 179.57086 -121.123563) (xy 179.607611 -121.160314) (xy 179.638161 -121.202362)
			(xy 179.661757 -121.248672) (xy 179.677818 -121.298102) (xy 179.685948 -121.349437) (xy 179.686458 -121.375424)
			(xy 179.685696 -121.398538) (xy 179.685442 -121.400316) (xy 179.685442 -121.45264) (xy 179.825904 -121.45264)
			(xy 179.825904 -121.400316) (xy 179.82565 -121.398538) (xy 179.824888 -121.375424) (xy 179.825398 -121.349437)
			(xy 179.833528 -121.298102) (xy 179.849589 -121.248672) (xy 179.873185 -121.202362) (xy 179.903735 -121.160314)
			(xy 179.940486 -121.123563) (xy 179.982534 -121.093013) (xy 180.028844 -121.069417) (xy 180.078274 -121.053356)
			(xy 180.129609 -121.045226) (xy 180.181583 -121.045226) (xy 180.232918 -121.053356) (xy 180.282348 -121.069417)
			(xy 180.328658 -121.093013) (xy 180.370706 -121.123563) (xy 180.407457 -121.160314) (xy 180.438007 -121.202362)
			(xy 180.461603 -121.248672) (xy 180.477664 -121.298102) (xy 180.485794 -121.349437) (xy 180.486304 -121.375424)
			(xy 180.485833 -121.400661) (xy 180.485718 -121.401411) (xy 182.225444 -121.401411) (xy 182.225444 -121.349437)
			(xy 182.233574 -121.298102) (xy 182.249635 -121.248672) (xy 182.273231 -121.202362) (xy 182.303781 -121.160314)
			(xy 182.340532 -121.123563) (xy 182.38258 -121.093013) (xy 182.42889 -121.069417) (xy 182.47832 -121.053356)
			(xy 182.529655 -121.045226) (xy 182.581629 -121.045226) (xy 182.632964 -121.053356) (xy 182.682394 -121.069417)
			(xy 182.728704 -121.093013) (xy 182.770752 -121.123563) (xy 182.807503 -121.160314) (xy 182.838053 -121.202362)
			(xy 182.861649 -121.248672) (xy 182.87771 -121.298102) (xy 182.88584 -121.349437) (xy 182.88635 -121.375424)
			(xy 182.88584 -121.401411) (xy 183.025544 -121.401411) (xy 183.025544 -121.349437) (xy 183.033674 -121.298102)
			(xy 183.049735 -121.248672) (xy 183.073331 -121.202362) (xy 183.103881 -121.160314) (xy 183.140632 -121.123563)
			(xy 183.18268 -121.093013) (xy 183.22899 -121.069417) (xy 183.27842 -121.053356) (xy 183.329755 -121.045226)
			(xy 183.381729 -121.045226) (xy 183.433064 -121.053356) (xy 183.482494 -121.069417) (xy 183.528804 -121.093013)
			(xy 183.570852 -121.123563) (xy 183.607603 -121.160314) (xy 183.638153 -121.202362) (xy 183.661749 -121.248672)
			(xy 183.67781 -121.298102) (xy 183.68594 -121.349437) (xy 183.68645 -121.375424) (xy 183.68594 -121.401411)
			(xy 183.67781 -121.452746) (xy 183.661749 -121.502176) (xy 183.638153 -121.548486) (xy 183.607603 -121.590534)
			(xy 183.570852 -121.627285) (xy 183.528804 -121.657835) (xy 183.482494 -121.681431) (xy 183.433064 -121.697492)
			(xy 183.381729 -121.705622) (xy 183.329755 -121.705622) (xy 183.27842 -121.697492) (xy 183.22899 -121.681431)
			(xy 183.18268 -121.657835) (xy 183.140632 -121.627285) (xy 183.103881 -121.590534) (xy 183.073331 -121.548486)
			(xy 183.049735 -121.502176) (xy 183.033674 -121.452746) (xy 183.025544 -121.401411) (xy 182.88584 -121.401411)
			(xy 182.87771 -121.452746) (xy 182.861649 -121.502176) (xy 182.838053 -121.548486) (xy 182.807503 -121.590534)
			(xy 182.770752 -121.627285) (xy 182.728704 -121.657835) (xy 182.682394 -121.681431) (xy 182.632964 -121.697492)
			(xy 182.581629 -121.705622) (xy 182.529655 -121.705622) (xy 182.47832 -121.697492) (xy 182.42889 -121.681431)
			(xy 182.38258 -121.657835) (xy 182.340532 -121.627285) (xy 182.303781 -121.590534) (xy 182.273231 -121.548486)
			(xy 182.249635 -121.502176) (xy 182.233574 -121.452746) (xy 182.225444 -121.401411) (xy 180.485718 -121.401411)
			(xy 180.47817 -121.450548) (xy 180.463011 -121.498691) (xy 180.440708 -121.543969) (xy 180.426614 -121.564908)
			(xy 180.419112 -121.576542) (xy 180.410031 -121.60268) (xy 180.408304 -121.630296) (xy 180.414058 -121.657361)
			(xy 180.426869 -121.681887) (xy 180.445797 -121.70207) (xy 180.469451 -121.716429) (xy 180.496092 -121.723906)
			(xy 180.509926 -121.72442) (xy 182.16118 -121.72442) (xy 182.186161 -121.724937) (xy 182.235503 -121.732798)
			(xy 182.283011 -121.748268) (xy 182.327521 -121.770967) (xy 182.367941 -121.800338) (xy 182.38597 -121.817638)
			(xy 182.70728 -122.138948) (xy 183.857138 -122.138948) (xy 183.868314 -122.103388) (xy 183.876688 -122.078631)
			(xy 183.900134 -122.031924) (xy 183.930634 -121.989486) (xy 183.967429 -121.952374) (xy 184.009605 -121.921511)
			(xy 184.05611 -121.897667) (xy 184.105786 -121.881435) (xy 184.157397 -121.873219) (xy 184.183528 -121.872756)
			(xy 184.208298 -121.873192) (xy 184.257286 -121.880575) (xy 184.304623 -121.895185) (xy 184.349249 -121.916697)
			(xy 184.390166 -121.944627) (xy 184.426456 -121.978351) (xy 184.457307 -122.017113) (xy 184.47004 -122.038364)
			(xy 184.473342 -122.044206) (xy 184.513982 -122.084846) (xy 184.58688 -122.011948) (xy 184.58688 -121.655078)
			(xy 184.58642 -121.641301) (xy 184.579043 -121.614753) (xy 184.564833 -121.591145) (xy 184.544826 -121.5722)
			(xy 184.520479 -121.559297) (xy 184.493568 -121.553378) (xy 184.466055 -121.554873) (xy 184.439944 -121.563675)
			(xy 184.41714 -121.57914) (xy 184.40781 -121.589292) (xy 184.392018 -121.607259) (xy 184.356146 -121.638904)
			(xy 184.31609 -121.665053) (xy 184.272687 -121.68516) (xy 184.22684 -121.698807) (xy 184.179505 -121.705708)
			(xy 184.155588 -121.706132) (xy 184.1296 -121.705621) (xy 184.078263 -121.697489) (xy 184.02883 -121.681426)
			(xy 183.982519 -121.657827) (xy 183.94047 -121.627275) (xy 183.903717 -121.590521) (xy 183.873166 -121.548471)
			(xy 183.84957 -121.502159) (xy 183.833508 -121.452726) (xy 183.825378 -121.401388) (xy 183.825378 -121.349412)
			(xy 183.833508 -121.298074) (xy 183.84957 -121.248641) (xy 183.873166 -121.202329) (xy 183.903717 -121.160279)
			(xy 183.94047 -121.123525) (xy 183.982519 -121.092973) (xy 184.02883 -121.069374) (xy 184.078263 -121.053311)
			(xy 184.1296 -121.045179) (xy 184.155588 -121.044716) (xy 184.179506 -121.045138) (xy 184.226842 -121.052031)
			(xy 184.272691 -121.065675) (xy 184.316095 -121.085784) (xy 184.356147 -121.111939) (xy 184.392011 -121.143593)
			(xy 184.40781 -121.161556) (xy 184.417081 -121.171773) (xy 184.4399 -121.187259) (xy 184.466032 -121.196072)
			(xy 184.493568 -121.197572) (xy 184.520502 -121.191647) (xy 184.544868 -121.178731) (xy 184.564889 -121.159765)
			(xy 184.579103 -121.136133) (xy 184.586476 -121.109559) (xy 184.58688 -121.09577) (xy 184.58688 -119.928132)
			(xy 184.50814 -119.849392) (xy 184.465214 -119.892318) (xy 184.46115 -119.901716) (xy 184.451454 -119.92409)
			(xy 184.426446 -119.96595) (xy 184.395557 -120.00368) (xy 184.359458 -120.036459) (xy 184.318933 -120.063577)
			(xy 184.274862 -120.084444) (xy 184.228203 -120.098606) (xy 184.179969 -120.105757) (xy 184.155588 -120.106186)
			(xy 184.1296 -120.105702) (xy 184.078264 -120.097569) (xy 184.028833 -120.081506) (xy 183.982523 -120.057907)
			(xy 183.940475 -120.027354) (xy 183.903724 -119.990599) (xy 183.873175 -119.948548) (xy 183.849581 -119.902236)
			(xy 183.833523 -119.852803) (xy 183.825395 -119.801466) (xy 183.82488 -119.775478) (xy 183.825382 -119.748817)
			(xy 183.833924 -119.696185) (xy 183.850799 -119.645604) (xy 183.87557 -119.598386) (xy 183.907595 -119.555754)
			(xy 183.946046 -119.518811) (xy 183.989924 -119.488516) (xy 184.038095 -119.465653) (xy 184.08931 -119.450814)
			(xy 184.11571 -119.447056) (xy 184.133236 -119.445024) (xy 184.181496 -119.396764) (xy 184.082944 -119.298212)
			(xy 184.06999 -119.29491) (xy 184.046189 -119.288077) (xy 184.000803 -119.268275) (xy 183.958876 -119.241928)
			(xy 183.921344 -119.209626) (xy 183.889047 -119.172091) (xy 183.862706 -119.13016) (xy 183.842909 -119.084772)
			(xy 183.836056 -119.060976) (xy 183.832754 -119.048022) (xy 183.734456 -118.949724) (xy 183.686196 -118.997984)
			(xy 183.68391 -119.01551) (xy 183.680142 -119.041879) (xy 183.665279 -119.093027) (xy 183.642411 -119.141132)
			(xy 183.61213 -119.18495) (xy 183.575218 -119.223349) (xy 183.53263 -119.255338) (xy 183.485466 -119.280087)
			(xy 183.434945 -119.29696) (xy 183.382374 -119.305518) (xy 183.355742 -119.306086) (xy 183.329751 -119.305606)
			(xy 183.278409 -119.29748) (xy 183.22897 -119.281421) (xy 183.182653 -119.257825) (xy 183.140597 -119.227273)
			(xy 183.10384 -119.190518) (xy 183.073285 -119.148464) (xy 183.049687 -119.102148) (xy 183.033625 -119.052711)
			(xy 183.025496 -119.001369) (xy 183.025034 -118.975378) (xy 183.025564 -118.948739) (xy 183.034096 -118.89615)
			(xy 183.050953 -118.845609) (xy 183.075698 -118.798427) (xy 183.107689 -118.755824) (xy 183.1461 -118.718903)
			(xy 183.189935 -118.688622) (xy 183.238059 -118.665762) (xy 183.289226 -118.650917) (xy 183.31561 -118.64721)
			(xy 183.333136 -118.644924) (xy 183.381396 -118.596664) (xy 183.283098 -118.498366) (xy 183.270144 -118.495064)
			(xy 183.246338 -118.488235) (xy 183.200943 -118.46844) (xy 183.159006 -118.442099) (xy 183.121464 -118.409801)
			(xy 183.089155 -118.372267) (xy 183.062803 -118.330337) (xy 183.042995 -118.284947) (xy 183.03621 -118.26113)
			(xy 183.032908 -118.248176) (xy 182.934356 -118.149624) (xy 182.886096 -118.197884) (xy 182.884064 -118.21541)
			(xy 182.880296 -118.241801) (xy 182.865424 -118.292993) (xy 182.842541 -118.341139) (xy 182.812237 -118.384995)
			(xy 182.775297 -118.423428) (xy 182.732675 -118.455445) (xy 182.685472 -118.480217) (xy 182.63491 -118.497104)
			(xy 182.582296 -118.505669) (xy 182.555642 -118.50624) (xy 182.52965 -118.50576) (xy 182.478304 -118.497634)
			(xy 182.428862 -118.481576) (xy 182.382541 -118.457981) (xy 182.340481 -118.42743) (xy 182.303718 -118.390676)
			(xy 182.273158 -118.348623) (xy 182.249552 -118.302307) (xy 182.233483 -118.252868) (xy 182.225346 -118.201524)
			(xy 182.224934 -118.175532) (xy 182.224993 -118.165091) (xy 182.226267 -118.144247) (xy 182.227474 -118.133876)
			(xy 182.210245 -118.128156) (xy 182.176908 -118.113782) (xy 182.160926 -118.105174) (xy 182.151087 -118.100315)
			(xy 182.129232 -118.098629) (xy 182.108664 -118.10621) (xy 182.09313 -118.121676) (xy 182.08546 -118.142211)
			(xy 182.085742 -118.15318) (xy 182.086504 -118.175532) (xy 182.085992 -118.201518) (xy 182.077857 -118.25285)
			(xy 182.061792 -118.302278) (xy 182.038193 -118.348583) (xy 182.007641 -118.390628) (xy 181.970888 -118.427375)
			(xy 181.928839 -118.45792) (xy 181.882529 -118.481512) (xy 181.833099 -118.497569) (xy 181.781766 -118.505696)
			(xy 181.729794 -118.505693) (xy 181.678462 -118.49756) (xy 181.629034 -118.481497) (xy 181.582727 -118.457899)
			(xy 181.540682 -118.427349) (xy 181.503933 -118.390597) (xy 181.473386 -118.348549) (xy 181.449793 -118.302241)
			(xy 181.433734 -118.252811) (xy 181.425605 -118.201478) (xy 181.425606 -118.149506) (xy 181.433737 -118.098173)
			(xy 181.449799 -118.048745) (xy 181.473394 -118.002437) (xy 181.503943 -117.960391) (xy 181.540694 -117.923641)
			(xy 181.582741 -117.893092) (xy 181.629048 -117.869497) (xy 181.678477 -117.853437) (xy 181.72981 -117.845306)
			(xy 181.755796 -117.844824) (xy 181.779164 -117.845586) (xy 181.790124 -117.845887) (xy 181.81067 -117.838297)
			(xy 181.826188 -117.82284) (xy 181.833859 -117.802325) (xy 181.832289 -117.780478) (xy 181.827424 -117.770656)
			(xy 181.818861 -117.754478) (xy 181.804609 -117.720762) (xy 181.798976 -117.703346) (xy 181.78823 -117.704667)
			(xy 181.766623 -117.706068) (xy 181.755796 -117.70614) (xy 181.729808 -117.70563) (xy 181.678472 -117.697499)
			(xy 181.62904 -117.681438) (xy 181.582729 -117.657843) (xy 181.540679 -117.627294) (xy 181.503925 -117.590543)
			(xy 181.473372 -117.548495) (xy 181.449772 -117.502186) (xy 181.433707 -117.452755) (xy 181.425572 -117.40142)
			(xy 181.425088 -117.375432) (xy 181.425318 -117.358999) (xy 181.428628 -117.3263) (xy 181.431692 -117.310154)
			(xy 181.413304 -117.301824) (xy 181.378301 -117.281711) (xy 181.361842 -117.270022) (xy 181.353448 -117.264346)
			(xy 181.333786 -117.259511) (xy 181.313784 -117.262655) (xy 181.296553 -117.273289) (xy 181.284775 -117.289759)
			(xy 181.280281 -117.309501) (xy 181.281578 -117.319552) (xy 181.283828 -117.333412) (xy 181.286241 -117.361391)
			(xy 181.286404 -117.375432) (xy 181.285894 -117.401419) (xy 181.277764 -117.452754) (xy 181.261703 -117.502184)
			(xy 181.238107 -117.548494) (xy 181.207557 -117.590542) (xy 181.170806 -117.627293) (xy 181.128758 -117.657843)
			(xy 181.082448 -117.681439) (xy 181.033018 -117.6975) (xy 180.981683 -117.70563) (xy 180.929709 -117.70563)
			(xy 180.878374 -117.6975) (xy 180.828944 -117.681439) (xy 180.782634 -117.657843) (xy 180.740586 -117.627293)
			(xy 180.703835 -117.590542) (xy 180.673285 -117.548494) (xy 180.649689 -117.502184) (xy 180.633628 -117.452754)
			(xy 180.625498 -117.401419) (xy 180.624988 -117.375432) (xy 180.625439 -117.350504) (xy 180.632923 -117.301212)
			(xy 180.647725 -117.253604) (xy 180.669509 -117.208759) (xy 180.697783 -117.167694) (xy 180.731903 -117.131342)
			(xy 180.771096 -117.100527) (xy 180.814473 -117.075948) (xy 180.861049 -117.058163) (xy 180.909768 -117.047576)
			(xy 180.934614 -117.045486) (xy 180.948611 -117.044122) (xy 180.975103 -117.034713) (xy 180.998025 -117.018436)
			(xy 181.01564 -116.996526) (xy 181.026614 -116.970643) (xy 181.030115 -116.942749) (xy 181.025878 -116.914957)
			(xy 181.020466 -116.901976) (xy 181.009968 -116.877865) (xy 180.995149 -116.827411) (xy 180.987658 -116.775361)
			(xy 180.987192 -116.749068) (xy 180.987192 -116.568982) (xy 180.962046 -116.543836) (xy 175.75911 -116.543836)
			(xy 175.683672 -116.61902) (xy 175.680878 -116.634768) (xy 175.675943 -116.659325) (xy 175.659654 -116.706688)
			(xy 175.636408 -116.751054) (xy 175.606739 -116.791407) (xy 175.571323 -116.826825) (xy 175.530972 -116.856497)
			(xy 175.486608 -116.879746) (xy 175.439245 -116.896038) (xy 175.414686 -116.90096) (xy 175.398938 -116.903754)
			(xy 175.308006 -116.994686) (xy 175.357536 -117.044216) (xy 175.376586 -117.045486) (xy 175.401431 -117.047534)
			(xy 175.450136 -117.058155) (xy 175.496697 -117.075965) (xy 175.540058 -117.100559) (xy 175.579237 -117.131381)
			(xy 175.613348 -117.167733) (xy 175.641619 -117.208791) (xy 175.663408 -117.253627) (xy 175.678223 -117.301225)
			(xy 175.685728 -117.350507) (xy 175.686212 -117.375432) (xy 175.6857 -117.401418) (xy 175.6857 -117.401419)
			(xy 175.825406 -117.401419) (xy 175.825406 -117.349445) (xy 175.833536 -117.29811) (xy 175.849597 -117.24868)
			(xy 175.873193 -117.20237) (xy 175.903743 -117.160322) (xy 175.940494 -117.123571) (xy 175.982542 -117.093021)
			(xy 176.028852 -117.069425) (xy 176.078282 -117.053364) (xy 176.129617 -117.045234) (xy 176.181591 -117.045234)
			(xy 176.232926 -117.053364) (xy 176.282356 -117.069425) (xy 176.328666 -117.093021) (xy 176.370714 -117.123571)
			(xy 176.407465 -117.160322) (xy 176.438015 -117.20237) (xy 176.461611 -117.24868) (xy 176.477672 -117.29811)
			(xy 176.485802 -117.349445) (xy 176.486312 -117.375432) (xy 176.485802 -117.401419) (xy 176.625506 -117.401419)
			(xy 176.625506 -117.349445) (xy 176.633636 -117.29811) (xy 176.649697 -117.24868) (xy 176.673293 -117.20237)
			(xy 176.703843 -117.160322) (xy 176.740594 -117.123571) (xy 176.782642 -117.093021) (xy 176.828952 -117.069425)
			(xy 176.878382 -117.053364) (xy 176.929717 -117.045234) (xy 176.981691 -117.045234) (xy 177.033026 -117.053364)
			(xy 177.082456 -117.069425) (xy 177.128766 -117.093021) (xy 177.170814 -117.123571) (xy 177.207565 -117.160322)
			(xy 177.238115 -117.20237) (xy 177.261711 -117.24868) (xy 177.277772 -117.29811) (xy 177.285902 -117.349445)
			(xy 177.286412 -117.375432) (xy 177.285902 -117.401419) (xy 177.425352 -117.401419) (xy 177.425352 -117.349445)
			(xy 177.433482 -117.29811) (xy 177.449543 -117.24868) (xy 177.473139 -117.20237) (xy 177.503689 -117.160322)
			(xy 177.54044 -117.123571) (xy 177.582488 -117.093021) (xy 177.628798 -117.069425) (xy 177.678228 -117.053364)
			(xy 177.729563 -117.045234) (xy 177.781537 -117.045234) (xy 177.832872 -117.053364) (xy 177.882302 -117.069425)
			(xy 177.928612 -117.093021) (xy 177.97066 -117.123571) (xy 178.007411 -117.160322) (xy 178.037961 -117.20237)
			(xy 178.061557 -117.24868) (xy 178.077618 -117.29811) (xy 178.085748 -117.349445) (xy 178.086258 -117.375432)
			(xy 178.085748 -117.401419) (xy 179.025552 -117.401419) (xy 179.025552 -117.349445) (xy 179.033682 -117.29811)
			(xy 179.049743 -117.24868) (xy 179.073339 -117.20237) (xy 179.103889 -117.160322) (xy 179.14064 -117.123571)
			(xy 179.182688 -117.093021) (xy 179.228998 -117.069425) (xy 179.278428 -117.053364) (xy 179.329763 -117.045234)
			(xy 179.381737 -117.045234) (xy 179.433072 -117.053364) (xy 179.482502 -117.069425) (xy 179.528812 -117.093021)
			(xy 179.57086 -117.123571) (xy 179.607611 -117.160322) (xy 179.638161 -117.20237) (xy 179.661757 -117.24868)
			(xy 179.677818 -117.29811) (xy 179.685948 -117.349445) (xy 179.686458 -117.375432) (xy 179.685948 -117.401419)
			(xy 179.825398 -117.401419) (xy 179.825398 -117.349445) (xy 179.833528 -117.29811) (xy 179.849589 -117.24868)
			(xy 179.873185 -117.20237) (xy 179.903735 -117.160322) (xy 179.940486 -117.123571) (xy 179.982534 -117.093021)
			(xy 180.028844 -117.069425) (xy 180.078274 -117.053364) (xy 180.129609 -117.045234) (xy 180.181583 -117.045234)
			(xy 180.232918 -117.053364) (xy 180.282348 -117.069425) (xy 180.328658 -117.093021) (xy 180.370706 -117.123571)
			(xy 180.407457 -117.160322) (xy 180.438007 -117.20237) (xy 180.461603 -117.24868) (xy 180.477664 -117.29811)
			(xy 180.485794 -117.349445) (xy 180.486304 -117.375432) (xy 180.485794 -117.401419) (xy 180.477664 -117.452754)
			(xy 180.461603 -117.502184) (xy 180.438007 -117.548494) (xy 180.407457 -117.590542) (xy 180.370706 -117.627293)
			(xy 180.328658 -117.657843) (xy 180.282348 -117.681439) (xy 180.232918 -117.6975) (xy 180.181583 -117.70563)
			(xy 180.129609 -117.70563) (xy 180.078274 -117.6975) (xy 180.028844 -117.681439) (xy 179.982534 -117.657843)
			(xy 179.940486 -117.627293) (xy 179.903735 -117.590542) (xy 179.873185 -117.548494) (xy 179.849589 -117.502184)
			(xy 179.833528 -117.452754) (xy 179.825398 -117.401419) (xy 179.685948 -117.401419) (xy 179.677818 -117.452754)
			(xy 179.661757 -117.502184) (xy 179.638161 -117.548494) (xy 179.607611 -117.590542) (xy 179.57086 -117.627293)
			(xy 179.528812 -117.657843) (xy 179.482502 -117.681439) (xy 179.433072 -117.6975) (xy 179.381737 -117.70563)
			(xy 179.329763 -117.70563) (xy 179.278428 -117.6975) (xy 179.228998 -117.681439) (xy 179.182688 -117.657843)
			(xy 179.14064 -117.627293) (xy 179.103889 -117.590542) (xy 179.073339 -117.548494) (xy 179.049743 -117.502184)
			(xy 179.033682 -117.452754) (xy 179.025552 -117.401419) (xy 178.085748 -117.401419) (xy 178.077618 -117.452754)
			(xy 178.061557 -117.502184) (xy 178.037961 -117.548494) (xy 178.007411 -117.590542) (xy 177.97066 -117.627293)
			(xy 177.928612 -117.657843) (xy 177.882302 -117.681439) (xy 177.832872 -117.6975) (xy 177.781537 -117.70563)
			(xy 177.729563 -117.70563) (xy 177.678228 -117.6975) (xy 177.628798 -117.681439) (xy 177.582488 -117.657843)
			(xy 177.54044 -117.627293) (xy 177.503689 -117.590542) (xy 177.473139 -117.548494) (xy 177.449543 -117.502184)
			(xy 177.433482 -117.452754) (xy 177.425352 -117.401419) (xy 177.285902 -117.401419) (xy 177.277772 -117.452754)
			(xy 177.261711 -117.502184) (xy 177.238115 -117.548494) (xy 177.207565 -117.590542) (xy 177.170814 -117.627293)
			(xy 177.128766 -117.657843) (xy 177.082456 -117.681439) (xy 177.033026 -117.6975) (xy 176.981691 -117.70563)
			(xy 176.929717 -117.70563) (xy 176.878382 -117.6975) (xy 176.828952 -117.681439) (xy 176.782642 -117.657843)
			(xy 176.740594 -117.627293) (xy 176.703843 -117.590542) (xy 176.673293 -117.548494) (xy 176.649697 -117.502184)
			(xy 176.633636 -117.452754) (xy 176.625506 -117.401419) (xy 176.485802 -117.401419) (xy 176.477672 -117.452754)
			(xy 176.461611 -117.502184) (xy 176.438015 -117.548494) (xy 176.407465 -117.590542) (xy 176.370714 -117.627293)
			(xy 176.328666 -117.657843) (xy 176.282356 -117.681439) (xy 176.232926 -117.6975) (xy 176.181591 -117.70563)
			(xy 176.129617 -117.70563) (xy 176.078282 -117.6975) (xy 176.028852 -117.681439) (xy 175.982542 -117.657843)
			(xy 175.940494 -117.627293) (xy 175.903743 -117.590542) (xy 175.873193 -117.548494) (xy 175.849597 -117.502184)
			(xy 175.833536 -117.452754) (xy 175.825406 -117.401419) (xy 175.6857 -117.401419) (xy 175.677566 -117.452748)
			(xy 175.661502 -117.502175) (xy 175.637904 -117.54848) (xy 175.607354 -117.590524) (xy 175.570603 -117.627272)
			(xy 175.528556 -117.657819) (xy 175.482249 -117.681413) (xy 175.432821 -117.697472) (xy 175.38149 -117.705602)
			(xy 175.355504 -117.70614) (xy 175.330572 -117.705694) (xy 175.28127 -117.69822) (xy 175.233651 -117.683424)
			(xy 175.188795 -117.661644) (xy 175.147719 -117.633373) (xy 175.111355 -117.599253) (xy 175.08053 -117.560058)
			(xy 175.055941 -117.516678) (xy 175.038148 -117.470096) (xy 175.027553 -117.42137) (xy 175.025558 -117.396514)
			(xy 175.024288 -117.377464) (xy 174.974758 -117.327934) (xy 174.883826 -117.418866) (xy 174.881032 -117.434614)
			(xy 174.876094 -117.459167) (xy 174.859799 -117.506523) (xy 174.836549 -117.55088) (xy 174.806876 -117.591224)
			(xy 174.771459 -117.626632) (xy 174.731107 -117.656294) (xy 174.686744 -117.679533) (xy 174.639384 -117.695816)
			(xy 174.61484 -117.700806) (xy 174.599092 -117.7036) (xy 174.507906 -117.794786) (xy 174.557436 -117.844316)
			(xy 174.576486 -117.845586) (xy 174.601346 -117.847613) (xy 174.650087 -117.858201) (xy 174.696685 -117.875986)
			(xy 174.740085 -117.900566) (xy 174.779303 -117.931383) (xy 174.813449 -117.96774) (xy 174.841749 -118.00881)
			(xy 174.863563 -118.053665) (xy 174.878394 -118.101286) (xy 174.885908 -118.150594) (xy 174.886366 -118.175532)
			(xy 174.88588 -118.201518) (xy 174.88588 -118.201519) (xy 175.025306 -118.201519) (xy 175.025306 -118.149545)
			(xy 175.033436 -118.09821) (xy 175.049497 -118.04878) (xy 175.073093 -118.00247) (xy 175.103643 -117.960422)
			(xy 175.140394 -117.923671) (xy 175.182442 -117.893121) (xy 175.228752 -117.869525) (xy 175.278182 -117.853464)
			(xy 175.329517 -117.845334) (xy 175.381491 -117.845334) (xy 175.432826 -117.853464) (xy 175.482256 -117.869525)
			(xy 175.528566 -117.893121) (xy 175.570614 -117.923671) (xy 175.607365 -117.960422) (xy 175.637915 -118.00247)
			(xy 175.661511 -118.04878) (xy 175.677572 -118.09821) (xy 175.685702 -118.149545) (xy 175.686212 -118.175532)
			(xy 175.685702 -118.201519) (xy 175.825406 -118.201519) (xy 175.825406 -118.149545) (xy 175.833536 -118.09821)
			(xy 175.849597 -118.04878) (xy 175.873193 -118.00247) (xy 175.903743 -117.960422) (xy 175.940494 -117.923671)
			(xy 175.982542 -117.893121) (xy 176.028852 -117.869525) (xy 176.078282 -117.853464) (xy 176.129617 -117.845334)
			(xy 176.181591 -117.845334) (xy 176.232926 -117.853464) (xy 176.282356 -117.869525) (xy 176.328666 -117.893121)
			(xy 176.370714 -117.923671) (xy 176.407465 -117.960422) (xy 176.438015 -118.00247) (xy 176.461611 -118.04878)
			(xy 176.477672 -118.09821) (xy 176.485802 -118.149545) (xy 176.486312 -118.175532) (xy 176.485802 -118.201519)
			(xy 176.625506 -118.201519) (xy 176.625506 -118.149545) (xy 176.633636 -118.09821) (xy 176.649697 -118.04878)
			(xy 176.673293 -118.00247) (xy 176.703843 -117.960422) (xy 176.740594 -117.923671) (xy 176.782642 -117.893121)
			(xy 176.828952 -117.869525) (xy 176.878382 -117.853464) (xy 176.929717 -117.845334) (xy 176.981691 -117.845334)
			(xy 177.033026 -117.853464) (xy 177.082456 -117.869525) (xy 177.128766 -117.893121) (xy 177.170814 -117.923671)
			(xy 177.207565 -117.960422) (xy 177.238115 -118.00247) (xy 177.261711 -118.04878) (xy 177.277772 -118.09821)
			(xy 177.285902 -118.149545) (xy 177.286412 -118.175532) (xy 177.285902 -118.201519) (xy 177.425352 -118.201519)
			(xy 177.425352 -118.149545) (xy 177.433482 -118.09821) (xy 177.449543 -118.04878) (xy 177.473139 -118.00247)
			(xy 177.503689 -117.960422) (xy 177.54044 -117.923671) (xy 177.582488 -117.893121) (xy 177.628798 -117.869525)
			(xy 177.678228 -117.853464) (xy 177.729563 -117.845334) (xy 177.781537 -117.845334) (xy 177.832872 -117.853464)
			(xy 177.882302 -117.869525) (xy 177.928612 -117.893121) (xy 177.97066 -117.923671) (xy 178.007411 -117.960422)
			(xy 178.037961 -118.00247) (xy 178.061557 -118.04878) (xy 178.077618 -118.09821) (xy 178.085748 -118.149545)
			(xy 178.086258 -118.175532) (xy 178.085748 -118.201519) (xy 179.825398 -118.201519) (xy 179.825398 -118.149545)
			(xy 179.833528 -118.09821) (xy 179.849589 -118.04878) (xy 179.873185 -118.00247) (xy 179.903735 -117.960422)
			(xy 179.940486 -117.923671) (xy 179.982534 -117.893121) (xy 180.028844 -117.869525) (xy 180.078274 -117.853464)
			(xy 180.129609 -117.845334) (xy 180.181583 -117.845334) (xy 180.232918 -117.853464) (xy 180.282348 -117.869525)
			(xy 180.328658 -117.893121) (xy 180.370706 -117.923671) (xy 180.407457 -117.960422) (xy 180.438007 -118.00247)
			(xy 180.461603 -118.04878) (xy 180.477664 -118.09821) (xy 180.485794 -118.149545) (xy 180.486304 -118.175532)
			(xy 180.485794 -118.201519) (xy 180.625498 -118.201519) (xy 180.625498 -118.149545) (xy 180.633628 -118.09821)
			(xy 180.649689 -118.04878) (xy 180.673285 -118.00247) (xy 180.703835 -117.960422) (xy 180.740586 -117.923671)
			(xy 180.782634 -117.893121) (xy 180.828944 -117.869525) (xy 180.878374 -117.853464) (xy 180.929709 -117.845334)
			(xy 180.981683 -117.845334) (xy 181.033018 -117.853464) (xy 181.082448 -117.869525) (xy 181.128758 -117.893121)
			(xy 181.170806 -117.923671) (xy 181.207557 -117.960422) (xy 181.238107 -118.00247) (xy 181.261703 -118.04878)
			(xy 181.277764 -118.09821) (xy 181.285894 -118.149545) (xy 181.286404 -118.175532) (xy 181.285894 -118.201519)
			(xy 181.277764 -118.252854) (xy 181.261703 -118.302284) (xy 181.238107 -118.348594) (xy 181.207557 -118.390642)
			(xy 181.170806 -118.427393) (xy 181.128758 -118.457943) (xy 181.082448 -118.481539) (xy 181.033018 -118.4976)
			(xy 180.981683 -118.50573) (xy 180.929709 -118.50573) (xy 180.878374 -118.4976) (xy 180.828944 -118.481539)
			(xy 180.782634 -118.457943) (xy 180.740586 -118.427393) (xy 180.703835 -118.390642) (xy 180.673285 -118.348594)
			(xy 180.649689 -118.302284) (xy 180.633628 -118.252854) (xy 180.625498 -118.201519) (xy 180.485794 -118.201519)
			(xy 180.477664 -118.252854) (xy 180.461603 -118.302284) (xy 180.438007 -118.348594) (xy 180.407457 -118.390642)
			(xy 180.370706 -118.427393) (xy 180.328658 -118.457943) (xy 180.282348 -118.481539) (xy 180.232918 -118.4976)
			(xy 180.181583 -118.50573) (xy 180.129609 -118.50573) (xy 180.078274 -118.4976) (xy 180.028844 -118.481539)
			(xy 179.982534 -118.457943) (xy 179.940486 -118.427393) (xy 179.903735 -118.390642) (xy 179.873185 -118.348594)
			(xy 179.849589 -118.302284) (xy 179.833528 -118.252854) (xy 179.825398 -118.201519) (xy 178.085748 -118.201519)
			(xy 178.077618 -118.252854) (xy 178.061557 -118.302284) (xy 178.037961 -118.348594) (xy 178.007411 -118.390642)
			(xy 177.97066 -118.427393) (xy 177.928612 -118.457943) (xy 177.882302 -118.481539) (xy 177.832872 -118.4976)
			(xy 177.781537 -118.50573) (xy 177.729563 -118.50573) (xy 177.678228 -118.4976) (xy 177.628798 -118.481539)
			(xy 177.582488 -118.457943) (xy 177.54044 -118.427393) (xy 177.503689 -118.390642) (xy 177.473139 -118.348594)
			(xy 177.449543 -118.302284) (xy 177.433482 -118.252854) (xy 177.425352 -118.201519) (xy 177.285902 -118.201519)
			(xy 177.277772 -118.252854) (xy 177.261711 -118.302284) (xy 177.238115 -118.348594) (xy 177.207565 -118.390642)
			(xy 177.170814 -118.427393) (xy 177.128766 -118.457943) (xy 177.082456 -118.481539) (xy 177.033026 -118.4976)
			(xy 176.981691 -118.50573) (xy 176.929717 -118.50573) (xy 176.878382 -118.4976) (xy 176.828952 -118.481539)
			(xy 176.782642 -118.457943) (xy 176.740594 -118.427393) (xy 176.703843 -118.390642) (xy 176.673293 -118.348594)
			(xy 176.649697 -118.302284) (xy 176.633636 -118.252854) (xy 176.625506 -118.201519) (xy 176.485802 -118.201519)
			(xy 176.477672 -118.252854) (xy 176.461611 -118.302284) (xy 176.438015 -118.348594) (xy 176.407465 -118.390642)
			(xy 176.370714 -118.427393) (xy 176.328666 -118.457943) (xy 176.282356 -118.481539) (xy 176.232926 -118.4976)
			(xy 176.181591 -118.50573) (xy 176.129617 -118.50573) (xy 176.078282 -118.4976) (xy 176.028852 -118.481539)
			(xy 175.982542 -118.457943) (xy 175.940494 -118.427393) (xy 175.903743 -118.390642) (xy 175.873193 -118.348594)
			(xy 175.849597 -118.302284) (xy 175.833536 -118.252854) (xy 175.825406 -118.201519) (xy 175.685702 -118.201519)
			(xy 175.677572 -118.252854) (xy 175.661511 -118.302284) (xy 175.637915 -118.348594) (xy 175.607365 -118.390642)
			(xy 175.570614 -118.427393) (xy 175.528566 -118.457943) (xy 175.482256 -118.481539) (xy 175.432826 -118.4976)
			(xy 175.381491 -118.50573) (xy 175.329517 -118.50573) (xy 175.278182 -118.4976) (xy 175.228752 -118.481539)
			(xy 175.182442 -118.457943) (xy 175.140394 -118.427393) (xy 175.103643 -118.390642) (xy 175.073093 -118.348594)
			(xy 175.049497 -118.302284) (xy 175.033436 -118.252854) (xy 175.025306 -118.201519) (xy 174.88588 -118.201519)
			(xy 174.877745 -118.252851) (xy 174.861679 -118.302278) (xy 174.838079 -118.348584) (xy 174.807526 -118.390628)
			(xy 174.770771 -118.427374) (xy 174.728721 -118.457918) (xy 174.68241 -118.481508) (xy 174.632979 -118.497562)
			(xy 174.581645 -118.505686) (xy 174.555658 -118.50624) (xy 174.530715 -118.50579) (xy 174.481395 -118.498302)
			(xy 174.433759 -118.483488) (xy 174.388891 -118.461684) (xy 174.347809 -118.433385) (xy 174.311446 -118.399234)
			(xy 174.280628 -118.360006) (xy 174.256054 -118.316593) (xy 174.238283 -118.26998) (xy 174.227719 -118.221226)
			(xy 174.225712 -118.19636) (xy 174.224442 -118.17731) (xy 174.174912 -118.12778) (xy 174.12589 -118.177056)
			(xy 174.096172 -118.177056) (xy 174.086012 -118.187216) (xy 174.084541 -118.213766) (xy 174.074183 -118.265917)
			(xy 174.055617 -118.315741) (xy 174.029322 -118.361953) (xy 173.995973 -118.403365) (xy 173.95643 -118.43891)
			(xy 173.911711 -118.467672) (xy 173.862968 -118.488912) (xy 173.811455 -118.502082) (xy 173.785022 -118.50497)
			(xy 173.766734 -118.506494) (xy 173.679358 -118.59387) (xy 173.730412 -118.644924) (xy 173.751748 -118.64467)
			(xy 173.755558 -118.64467) (xy 173.78155 -118.64515) (xy 173.832895 -118.653276) (xy 173.882337 -118.669334)
			(xy 173.928658 -118.69293) (xy 173.970717 -118.723481) (xy 174.007478 -118.760236) (xy 174.038038 -118.802289)
			(xy 174.061642 -118.848605) (xy 174.077709 -118.898044) (xy 174.085845 -118.949387) (xy 174.085848 -119.001365)
			(xy 174.22546 -119.001365) (xy 174.22546 -118.949391) (xy 174.23359 -118.898056) (xy 174.249651 -118.848626)
			(xy 174.273247 -118.802316) (xy 174.303797 -118.760268) (xy 174.340548 -118.723517) (xy 174.382596 -118.692967)
			(xy 174.428906 -118.669371) (xy 174.478336 -118.65331) (xy 174.529671 -118.64518) (xy 174.581645 -118.64518)
			(xy 174.63298 -118.65331) (xy 174.68241 -118.669371) (xy 174.72872 -118.692967) (xy 174.770768 -118.723517)
			(xy 174.807519 -118.760268) (xy 174.838069 -118.802316) (xy 174.861665 -118.848626) (xy 174.877726 -118.898056)
			(xy 174.885856 -118.949391) (xy 174.886366 -118.975378) (xy 174.885856 -119.001365) (xy 175.025306 -119.001365)
			(xy 175.025306 -118.949391) (xy 175.033436 -118.898056) (xy 175.049497 -118.848626) (xy 175.073093 -118.802316)
			(xy 175.103643 -118.760268) (xy 175.140394 -118.723517) (xy 175.182442 -118.692967) (xy 175.228752 -118.669371)
			(xy 175.278182 -118.65331) (xy 175.329517 -118.64518) (xy 175.381491 -118.64518) (xy 175.432826 -118.65331)
			(xy 175.482256 -118.669371) (xy 175.528566 -118.692967) (xy 175.570614 -118.723517) (xy 175.607365 -118.760268)
			(xy 175.637915 -118.802316) (xy 175.661511 -118.848626) (xy 175.677572 -118.898056) (xy 175.685702 -118.949391)
			(xy 175.686212 -118.975378) (xy 175.685702 -119.001365) (xy 175.825406 -119.001365) (xy 175.825406 -118.949391)
			(xy 175.833536 -118.898056) (xy 175.849597 -118.848626) (xy 175.873193 -118.802316) (xy 175.903743 -118.760268)
			(xy 175.940494 -118.723517) (xy 175.982542 -118.692967) (xy 176.028852 -118.669371) (xy 176.078282 -118.65331)
			(xy 176.129617 -118.64518) (xy 176.181591 -118.64518) (xy 176.232926 -118.65331) (xy 176.282356 -118.669371)
			(xy 176.328666 -118.692967) (xy 176.370714 -118.723517) (xy 176.407465 -118.760268) (xy 176.438015 -118.802316)
			(xy 176.461611 -118.848626) (xy 176.477672 -118.898056) (xy 176.485802 -118.949391) (xy 176.486312 -118.975378)
			(xy 176.485802 -119.001365) (xy 176.625506 -119.001365) (xy 176.625506 -118.949391) (xy 176.633636 -118.898056)
			(xy 176.649697 -118.848626) (xy 176.673293 -118.802316) (xy 176.703843 -118.760268) (xy 176.740594 -118.723517)
			(xy 176.782642 -118.692967) (xy 176.828952 -118.669371) (xy 176.878382 -118.65331) (xy 176.929717 -118.64518)
			(xy 176.981691 -118.64518) (xy 177.033026 -118.65331) (xy 177.082456 -118.669371) (xy 177.128766 -118.692967)
			(xy 177.170814 -118.723517) (xy 177.207565 -118.760268) (xy 177.238115 -118.802316) (xy 177.261711 -118.848626)
			(xy 177.277772 -118.898056) (xy 177.285902 -118.949391) (xy 177.286412 -118.975378) (xy 177.285902 -119.001365)
			(xy 177.425352 -119.001365) (xy 177.425352 -118.949391) (xy 177.433482 -118.898056) (xy 177.449543 -118.848626)
			(xy 177.473139 -118.802316) (xy 177.503689 -118.760268) (xy 177.54044 -118.723517) (xy 177.582488 -118.692967)
			(xy 177.628798 -118.669371) (xy 177.678228 -118.65331) (xy 177.729563 -118.64518) (xy 177.781537 -118.64518)
			(xy 177.832872 -118.65331) (xy 177.882302 -118.669371) (xy 177.928612 -118.692967) (xy 177.97066 -118.723517)
			(xy 178.007411 -118.760268) (xy 178.037961 -118.802316) (xy 178.061557 -118.848626) (xy 178.077618 -118.898056)
			(xy 178.085748 -118.949391) (xy 178.086258 -118.975378) (xy 178.085748 -119.001365) (xy 179.825398 -119.001365)
			(xy 179.825398 -118.949391) (xy 179.833528 -118.898056) (xy 179.849589 -118.848626) (xy 179.873185 -118.802316)
			(xy 179.903735 -118.760268) (xy 179.940486 -118.723517) (xy 179.982534 -118.692967) (xy 180.028844 -118.669371)
			(xy 180.078274 -118.65331) (xy 180.129609 -118.64518) (xy 180.181583 -118.64518) (xy 180.232918 -118.65331)
			(xy 180.282348 -118.669371) (xy 180.328658 -118.692967) (xy 180.370706 -118.723517) (xy 180.407457 -118.760268)
			(xy 180.438007 -118.802316) (xy 180.461603 -118.848626) (xy 180.477664 -118.898056) (xy 180.485794 -118.949391)
			(xy 180.486304 -118.975378) (xy 180.485794 -119.001365) (xy 180.625498 -119.001365) (xy 180.625498 -118.949391)
			(xy 180.633628 -118.898056) (xy 180.649689 -118.848626) (xy 180.673285 -118.802316) (xy 180.703835 -118.760268)
			(xy 180.740586 -118.723517) (xy 180.782634 -118.692967) (xy 180.828944 -118.669371) (xy 180.878374 -118.65331)
			(xy 180.929709 -118.64518) (xy 180.981683 -118.64518) (xy 181.033018 -118.65331) (xy 181.082448 -118.669371)
			(xy 181.128758 -118.692967) (xy 181.170806 -118.723517) (xy 181.207557 -118.760268) (xy 181.238107 -118.802316)
			(xy 181.261703 -118.848626) (xy 181.277764 -118.898056) (xy 181.285894 -118.949391) (xy 181.286404 -118.975378)
			(xy 181.285894 -119.001365) (xy 181.425598 -119.001365) (xy 181.425598 -118.949391) (xy 181.433728 -118.898056)
			(xy 181.449789 -118.848626) (xy 181.473385 -118.802316) (xy 181.503935 -118.760268) (xy 181.540686 -118.723517)
			(xy 181.582734 -118.692967) (xy 181.629044 -118.669371) (xy 181.678474 -118.65331) (xy 181.729809 -118.64518)
			(xy 181.781783 -118.64518) (xy 181.833118 -118.65331) (xy 181.882548 -118.669371) (xy 181.928858 -118.692967)
			(xy 181.970906 -118.723517) (xy 182.007657 -118.760268) (xy 182.038207 -118.802316) (xy 182.061803 -118.848626)
			(xy 182.077864 -118.898056) (xy 182.085994 -118.949391) (xy 182.086504 -118.975378) (xy 182.085994 -119.001365)
			(xy 182.225444 -119.001365) (xy 182.225444 -118.949391) (xy 182.233574 -118.898056) (xy 182.249635 -118.848626)
			(xy 182.273231 -118.802316) (xy 182.303781 -118.760268) (xy 182.340532 -118.723517) (xy 182.38258 -118.692967)
			(xy 182.42889 -118.669371) (xy 182.47832 -118.65331) (xy 182.529655 -118.64518) (xy 182.581629 -118.64518)
			(xy 182.632964 -118.65331) (xy 182.682394 -118.669371) (xy 182.728704 -118.692967) (xy 182.770752 -118.723517)
			(xy 182.807503 -118.760268) (xy 182.838053 -118.802316) (xy 182.861649 -118.848626) (xy 182.87771 -118.898056)
			(xy 182.88584 -118.949391) (xy 182.88635 -118.975378) (xy 182.88584 -119.001365) (xy 182.87771 -119.0527)
			(xy 182.861649 -119.10213) (xy 182.838053 -119.14844) (xy 182.807503 -119.190488) (xy 182.770752 -119.227239)
			(xy 182.728704 -119.257789) (xy 182.682394 -119.281385) (xy 182.632964 -119.297446) (xy 182.581629 -119.305576)
			(xy 182.529655 -119.305576) (xy 182.47832 -119.297446) (xy 182.42889 -119.281385) (xy 182.38258 -119.257789)
			(xy 182.340532 -119.227239) (xy 182.303781 -119.190488) (xy 182.273231 -119.14844) (xy 182.249635 -119.10213)
			(xy 182.233574 -119.0527) (xy 182.225444 -119.001365) (xy 182.085994 -119.001365) (xy 182.077864 -119.0527)
			(xy 182.061803 -119.10213) (xy 182.038207 -119.14844) (xy 182.007657 -119.190488) (xy 181.970906 -119.227239)
			(xy 181.928858 -119.257789) (xy 181.882548 -119.281385) (xy 181.833118 -119.297446) (xy 181.781783 -119.305576)
			(xy 181.729809 -119.305576) (xy 181.678474 -119.297446) (xy 181.629044 -119.281385) (xy 181.582734 -119.257789)
			(xy 181.540686 -119.227239) (xy 181.503935 -119.190488) (xy 181.473385 -119.14844) (xy 181.449789 -119.10213)
			(xy 181.433728 -119.0527) (xy 181.425598 -119.001365) (xy 181.285894 -119.001365) (xy 181.277764 -119.0527)
			(xy 181.261703 -119.10213) (xy 181.238107 -119.14844) (xy 181.207557 -119.190488) (xy 181.170806 -119.227239)
			(xy 181.128758 -119.257789) (xy 181.082448 -119.281385) (xy 181.033018 -119.297446) (xy 180.981683 -119.305576)
			(xy 180.929709 -119.305576) (xy 180.878374 -119.297446) (xy 180.828944 -119.281385) (xy 180.782634 -119.257789)
			(xy 180.740586 -119.227239) (xy 180.703835 -119.190488) (xy 180.673285 -119.14844) (xy 180.649689 -119.10213)
			(xy 180.633628 -119.0527) (xy 180.625498 -119.001365) (xy 180.485794 -119.001365) (xy 180.477664 -119.0527)
			(xy 180.461603 -119.10213) (xy 180.438007 -119.14844) (xy 180.407457 -119.190488) (xy 180.370706 -119.227239)
			(xy 180.328658 -119.257789) (xy 180.282348 -119.281385) (xy 180.232918 -119.297446) (xy 180.181583 -119.305576)
			(xy 180.129609 -119.305576) (xy 180.078274 -119.297446) (xy 180.028844 -119.281385) (xy 179.982534 -119.257789)
			(xy 179.940486 -119.227239) (xy 179.903735 -119.190488) (xy 179.873185 -119.14844) (xy 179.849589 -119.10213)
			(xy 179.833528 -119.0527) (xy 179.825398 -119.001365) (xy 178.085748 -119.001365) (xy 178.077618 -119.0527)
			(xy 178.061557 -119.10213) (xy 178.037961 -119.14844) (xy 178.007411 -119.190488) (xy 177.97066 -119.227239)
			(xy 177.928612 -119.257789) (xy 177.882302 -119.281385) (xy 177.832872 -119.297446) (xy 177.781537 -119.305576)
			(xy 177.729563 -119.305576) (xy 177.678228 -119.297446) (xy 177.628798 -119.281385) (xy 177.582488 -119.257789)
			(xy 177.54044 -119.227239) (xy 177.503689 -119.190488) (xy 177.473139 -119.14844) (xy 177.449543 -119.10213)
			(xy 177.433482 -119.0527) (xy 177.425352 -119.001365) (xy 177.285902 -119.001365) (xy 177.277772 -119.0527)
			(xy 177.261711 -119.10213) (xy 177.238115 -119.14844) (xy 177.207565 -119.190488) (xy 177.170814 -119.227239)
			(xy 177.128766 -119.257789) (xy 177.082456 -119.281385) (xy 177.033026 -119.297446) (xy 176.981691 -119.305576)
			(xy 176.929717 -119.305576) (xy 176.878382 -119.297446) (xy 176.828952 -119.281385) (xy 176.782642 -119.257789)
			(xy 176.740594 -119.227239) (xy 176.703843 -119.190488) (xy 176.673293 -119.14844) (xy 176.649697 -119.10213)
			(xy 176.633636 -119.0527) (xy 176.625506 -119.001365) (xy 176.485802 -119.001365) (xy 176.477672 -119.0527)
			(xy 176.461611 -119.10213) (xy 176.438015 -119.14844) (xy 176.407465 -119.190488) (xy 176.370714 -119.227239)
			(xy 176.328666 -119.257789) (xy 176.282356 -119.281385) (xy 176.232926 -119.297446) (xy 176.181591 -119.305576)
			(xy 176.129617 -119.305576) (xy 176.078282 -119.297446) (xy 176.028852 -119.281385) (xy 175.982542 -119.257789)
			(xy 175.940494 -119.227239) (xy 175.903743 -119.190488) (xy 175.873193 -119.14844) (xy 175.849597 -119.10213)
			(xy 175.833536 -119.0527) (xy 175.825406 -119.001365) (xy 175.685702 -119.001365) (xy 175.677572 -119.0527)
			(xy 175.661511 -119.10213) (xy 175.637915 -119.14844) (xy 175.607365 -119.190488) (xy 175.570614 -119.227239)
			(xy 175.528566 -119.257789) (xy 175.482256 -119.281385) (xy 175.432826 -119.297446) (xy 175.381491 -119.305576)
			(xy 175.329517 -119.305576) (xy 175.278182 -119.297446) (xy 175.228752 -119.281385) (xy 175.182442 -119.257789)
			(xy 175.140394 -119.227239) (xy 175.103643 -119.190488) (xy 175.073093 -119.14844) (xy 175.049497 -119.10213)
			(xy 175.033436 -119.0527) (xy 175.025306 -119.001365) (xy 174.885856 -119.001365) (xy 174.877726 -119.0527)
			(xy 174.861665 -119.10213) (xy 174.838069 -119.14844) (xy 174.807519 -119.190488) (xy 174.770768 -119.227239)
			(xy 174.72872 -119.257789) (xy 174.68241 -119.281385) (xy 174.63298 -119.297446) (xy 174.581645 -119.305576)
			(xy 174.529671 -119.305576) (xy 174.478336 -119.297446) (xy 174.428906 -119.281385) (xy 174.382596 -119.257789)
			(xy 174.340548 -119.227239) (xy 174.303797 -119.190488) (xy 174.273247 -119.14844) (xy 174.249651 -119.10213)
			(xy 174.23359 -119.0527) (xy 174.22546 -119.001365) (xy 174.085848 -119.001365) (xy 174.085848 -119.001371)
			(xy 174.077719 -119.052716) (xy 174.061658 -119.102157) (xy 174.038059 -119.148476) (xy 174.007505 -119.190533)
			(xy 173.970748 -119.227292) (xy 173.928693 -119.257849) (xy 173.882375 -119.28145) (xy 173.832935 -119.297514)
			(xy 173.781591 -119.305647) (xy 173.729607 -119.305647) (xy 173.678263 -119.297514) (xy 173.628824 -119.281449)
			(xy 173.582506 -119.257848) (xy 173.540451 -119.227291) (xy 173.503694 -119.190532) (xy 173.47314 -119.148475)
			(xy 173.449542 -119.102155) (xy 173.433481 -119.052715) (xy 173.425352 -119.00137) (xy 173.42485 -118.975378)
			(xy 173.42485 -118.971568) (xy 173.425104 -118.950232) (xy 173.37405 -118.899178) (xy 173.286674 -118.986554)
			(xy 173.28515 -119.004842) (xy 173.282526 -119.02917) (xy 173.271043 -119.076734) (xy 173.26229 -119.099584)
			(xy 173.25848 -119.108728) (xy 173.25848 -119.642128) (xy 173.26229 -119.651272) (xy 173.273551 -119.68108)
			(xy 173.285705 -119.743622) (xy 173.28642 -119.775478) (xy 173.285843 -119.801465) (xy 173.42536 -119.801465)
			(xy 173.42536 -119.749491) (xy 173.43349 -119.698156) (xy 173.449551 -119.648726) (xy 173.473147 -119.602416)
			(xy 173.503697 -119.560368) (xy 173.540448 -119.523617) (xy 173.582496 -119.493067) (xy 173.628806 -119.469471)
			(xy 173.678236 -119.45341) (xy 173.729571 -119.44528) (xy 173.781545 -119.44528) (xy 173.83288 -119.45341)
			(xy 173.88231 -119.469471) (xy 173.92862 -119.493067) (xy 173.970668 -119.523617) (xy 174.007419 -119.560368)
			(xy 174.037969 -119.602416) (xy 174.061565 -119.648726) (xy 174.077626 -119.698156) (xy 174.085756 -119.749491)
			(xy 174.086266 -119.775478) (xy 174.085756 -119.801465) (xy 174.22546 -119.801465) (xy 174.22546 -119.749491)
			(xy 174.23359 -119.698156) (xy 174.249651 -119.648726) (xy 174.273247 -119.602416) (xy 174.303797 -119.560368)
			(xy 174.340548 -119.523617) (xy 174.382596 -119.493067) (xy 174.428906 -119.469471) (xy 174.478336 -119.45341)
			(xy 174.529671 -119.44528) (xy 174.581645 -119.44528) (xy 174.63298 -119.45341) (xy 174.68241 -119.469471)
			(xy 174.72872 -119.493067) (xy 174.770768 -119.523617) (xy 174.807519 -119.560368) (xy 174.838069 -119.602416)
			(xy 174.861665 -119.648726) (xy 174.877726 -119.698156) (xy 174.885856 -119.749491) (xy 174.886366 -119.775478)
			(xy 174.885856 -119.801465) (xy 175.025306 -119.801465) (xy 175.025306 -119.749491) (xy 175.033436 -119.698156)
			(xy 175.049497 -119.648726) (xy 175.073093 -119.602416) (xy 175.103643 -119.560368) (xy 175.140394 -119.523617)
			(xy 175.182442 -119.493067) (xy 175.228752 -119.469471) (xy 175.278182 -119.45341) (xy 175.329517 -119.44528)
			(xy 175.381491 -119.44528) (xy 175.432826 -119.45341) (xy 175.482256 -119.469471) (xy 175.528566 -119.493067)
			(xy 175.570614 -119.523617) (xy 175.607365 -119.560368) (xy 175.637915 -119.602416) (xy 175.661511 -119.648726)
			(xy 175.677572 -119.698156) (xy 175.685702 -119.749491) (xy 175.686212 -119.775478) (xy 175.685702 -119.801465)
			(xy 175.825406 -119.801465) (xy 175.825406 -119.749491) (xy 175.833536 -119.698156) (xy 175.849597 -119.648726)
			(xy 175.873193 -119.602416) (xy 175.903743 -119.560368) (xy 175.940494 -119.523617) (xy 175.982542 -119.493067)
			(xy 176.028852 -119.469471) (xy 176.078282 -119.45341) (xy 176.129617 -119.44528) (xy 176.181591 -119.44528)
			(xy 176.232926 -119.45341) (xy 176.282356 -119.469471) (xy 176.328666 -119.493067) (xy 176.370714 -119.523617)
			(xy 176.407465 -119.560368) (xy 176.438015 -119.602416) (xy 176.461611 -119.648726) (xy 176.477672 -119.698156)
			(xy 176.485802 -119.749491) (xy 176.486312 -119.775478) (xy 176.485802 -119.801465) (xy 176.625506 -119.801465)
			(xy 176.625506 -119.749491) (xy 176.633636 -119.698156) (xy 176.649697 -119.648726) (xy 176.673293 -119.602416)
			(xy 176.703843 -119.560368) (xy 176.740594 -119.523617) (xy 176.782642 -119.493067) (xy 176.828952 -119.469471)
			(xy 176.878382 -119.45341) (xy 176.929717 -119.44528) (xy 176.981691 -119.44528) (xy 177.033026 -119.45341)
			(xy 177.082456 -119.469471) (xy 177.128766 -119.493067) (xy 177.170814 -119.523617) (xy 177.207565 -119.560368)
			(xy 177.238115 -119.602416) (xy 177.261711 -119.648726) (xy 177.277772 -119.698156) (xy 177.285902 -119.749491)
			(xy 177.286412 -119.775478) (xy 177.285902 -119.801465) (xy 177.425352 -119.801465) (xy 177.425352 -119.749491)
			(xy 177.433482 -119.698156) (xy 177.449543 -119.648726) (xy 177.473139 -119.602416) (xy 177.503689 -119.560368)
			(xy 177.54044 -119.523617) (xy 177.582488 -119.493067) (xy 177.628798 -119.469471) (xy 177.678228 -119.45341)
			(xy 177.729563 -119.44528) (xy 177.781537 -119.44528) (xy 177.832872 -119.45341) (xy 177.882302 -119.469471)
			(xy 177.928612 -119.493067) (xy 177.97066 -119.523617) (xy 178.007411 -119.560368) (xy 178.037961 -119.602416)
			(xy 178.061557 -119.648726) (xy 178.077618 -119.698156) (xy 178.085748 -119.749491) (xy 178.086258 -119.775478)
			(xy 178.085748 -119.801465) (xy 179.025552 -119.801465) (xy 179.025552 -119.749491) (xy 179.033682 -119.698156)
			(xy 179.049743 -119.648726) (xy 179.073339 -119.602416) (xy 179.103889 -119.560368) (xy 179.14064 -119.523617)
			(xy 179.182688 -119.493067) (xy 179.228998 -119.469471) (xy 179.278428 -119.45341) (xy 179.329763 -119.44528)
			(xy 179.381737 -119.44528) (xy 179.433072 -119.45341) (xy 179.482502 -119.469471) (xy 179.528812 -119.493067)
			(xy 179.57086 -119.523617) (xy 179.607611 -119.560368) (xy 179.638161 -119.602416) (xy 179.661757 -119.648726)
			(xy 179.677818 -119.698156) (xy 179.685948 -119.749491) (xy 179.686458 -119.775478) (xy 179.685948 -119.801465)
			(xy 179.825398 -119.801465) (xy 179.825398 -119.749491) (xy 179.833528 -119.698156) (xy 179.849589 -119.648726)
			(xy 179.873185 -119.602416) (xy 179.903735 -119.560368) (xy 179.940486 -119.523617) (xy 179.982534 -119.493067)
			(xy 180.028844 -119.469471) (xy 180.078274 -119.45341) (xy 180.129609 -119.44528) (xy 180.181583 -119.44528)
			(xy 180.232918 -119.45341) (xy 180.282348 -119.469471) (xy 180.328658 -119.493067) (xy 180.370706 -119.523617)
			(xy 180.407457 -119.560368) (xy 180.438007 -119.602416) (xy 180.461603 -119.648726) (xy 180.477664 -119.698156)
			(xy 180.485794 -119.749491) (xy 180.486304 -119.775478) (xy 180.485794 -119.801465) (xy 180.625498 -119.801465)
			(xy 180.625498 -119.749491) (xy 180.633628 -119.698156) (xy 180.649689 -119.648726) (xy 180.673285 -119.602416)
			(xy 180.703835 -119.560368) (xy 180.740586 -119.523617) (xy 180.782634 -119.493067) (xy 180.828944 -119.469471)
			(xy 180.878374 -119.45341) (xy 180.929709 -119.44528) (xy 180.981683 -119.44528) (xy 181.033018 -119.45341)
			(xy 181.082448 -119.469471) (xy 181.128758 -119.493067) (xy 181.170806 -119.523617) (xy 181.207557 -119.560368)
			(xy 181.238107 -119.602416) (xy 181.261703 -119.648726) (xy 181.277764 -119.698156) (xy 181.285894 -119.749491)
			(xy 181.286404 -119.775478) (xy 181.285894 -119.801465) (xy 181.425598 -119.801465) (xy 181.425598 -119.749491)
			(xy 181.433728 -119.698156) (xy 181.449789 -119.648726) (xy 181.473385 -119.602416) (xy 181.503935 -119.560368)
			(xy 181.540686 -119.523617) (xy 181.582734 -119.493067) (xy 181.629044 -119.469471) (xy 181.678474 -119.45341)
			(xy 181.729809 -119.44528) (xy 181.781783 -119.44528) (xy 181.833118 -119.45341) (xy 181.882548 -119.469471)
			(xy 181.928858 -119.493067) (xy 181.970906 -119.523617) (xy 182.007657 -119.560368) (xy 182.038207 -119.602416)
			(xy 182.061803 -119.648726) (xy 182.077864 -119.698156) (xy 182.085994 -119.749491) (xy 182.086504 -119.775478)
			(xy 182.085994 -119.801465) (xy 182.225444 -119.801465) (xy 182.225444 -119.749491) (xy 182.233574 -119.698156)
			(xy 182.249635 -119.648726) (xy 182.273231 -119.602416) (xy 182.303781 -119.560368) (xy 182.340532 -119.523617)
			(xy 182.38258 -119.493067) (xy 182.42889 -119.469471) (xy 182.47832 -119.45341) (xy 182.529655 -119.44528)
			(xy 182.581629 -119.44528) (xy 182.632964 -119.45341) (xy 182.682394 -119.469471) (xy 182.728704 -119.493067)
			(xy 182.770752 -119.523617) (xy 182.807503 -119.560368) (xy 182.838053 -119.602416) (xy 182.861649 -119.648726)
			(xy 182.87771 -119.698156) (xy 182.88584 -119.749491) (xy 182.88635 -119.775478) (xy 182.88584 -119.801465)
			(xy 183.025544 -119.801465) (xy 183.025544 -119.749491) (xy 183.033674 -119.698156) (xy 183.049735 -119.648726)
			(xy 183.073331 -119.602416) (xy 183.103881 -119.560368) (xy 183.140632 -119.523617) (xy 183.18268 -119.493067)
			(xy 183.22899 -119.469471) (xy 183.27842 -119.45341) (xy 183.329755 -119.44528) (xy 183.381729 -119.44528)
			(xy 183.433064 -119.45341) (xy 183.482494 -119.469471) (xy 183.528804 -119.493067) (xy 183.570852 -119.523617)
			(xy 183.607603 -119.560368) (xy 183.638153 -119.602416) (xy 183.661749 -119.648726) (xy 183.67781 -119.698156)
			(xy 183.68594 -119.749491) (xy 183.68645 -119.775478) (xy 183.68594 -119.801465) (xy 183.67781 -119.8528)
			(xy 183.661749 -119.90223) (xy 183.638153 -119.94854) (xy 183.607603 -119.990588) (xy 183.570852 -120.027339)
			(xy 183.528804 -120.057889) (xy 183.482494 -120.081485) (xy 183.433064 -120.097546) (xy 183.381729 -120.105676)
			(xy 183.329755 -120.105676) (xy 183.27842 -120.097546) (xy 183.22899 -120.081485) (xy 183.18268 -120.057889)
			(xy 183.140632 -120.027339) (xy 183.103881 -119.990588) (xy 183.073331 -119.94854) (xy 183.049735 -119.90223)
			(xy 183.033674 -119.8528) (xy 183.025544 -119.801465) (xy 182.88584 -119.801465) (xy 182.87771 -119.8528)
			(xy 182.861649 -119.90223) (xy 182.838053 -119.94854) (xy 182.807503 -119.990588) (xy 182.770752 -120.027339)
			(xy 182.728704 -120.057889) (xy 182.682394 -120.081485) (xy 182.632964 -120.097546) (xy 182.581629 -120.105676)
			(xy 182.529655 -120.105676) (xy 182.47832 -120.097546) (xy 182.42889 -120.081485) (xy 182.38258 -120.057889)
			(xy 182.340532 -120.027339) (xy 182.303781 -119.990588) (xy 182.273231 -119.94854) (xy 182.249635 -119.90223)
			(xy 182.233574 -119.8528) (xy 182.225444 -119.801465) (xy 182.085994 -119.801465) (xy 182.077864 -119.8528)
			(xy 182.061803 -119.90223) (xy 182.038207 -119.94854) (xy 182.007657 -119.990588) (xy 181.970906 -120.027339)
			(xy 181.928858 -120.057889) (xy 181.882548 -120.081485) (xy 181.833118 -120.097546) (xy 181.781783 -120.105676)
			(xy 181.729809 -120.105676) (xy 181.678474 -120.097546) (xy 181.629044 -120.081485) (xy 181.582734 -120.057889)
			(xy 181.540686 -120.027339) (xy 181.503935 -119.990588) (xy 181.473385 -119.94854) (xy 181.449789 -119.90223)
			(xy 181.433728 -119.8528) (xy 181.425598 -119.801465) (xy 181.285894 -119.801465) (xy 181.277764 -119.8528)
			(xy 181.261703 -119.90223) (xy 181.238107 -119.94854) (xy 181.207557 -119.990588) (xy 181.170806 -120.027339)
			(xy 181.128758 -120.057889) (xy 181.082448 -120.081485) (xy 181.033018 -120.097546) (xy 180.981683 -120.105676)
			(xy 180.929709 -120.105676) (xy 180.878374 -120.097546) (xy 180.828944 -120.081485) (xy 180.782634 -120.057889)
			(xy 180.740586 -120.027339) (xy 180.703835 -119.990588) (xy 180.673285 -119.94854) (xy 180.649689 -119.90223)
			(xy 180.633628 -119.8528) (xy 180.625498 -119.801465) (xy 180.485794 -119.801465) (xy 180.477664 -119.8528)
			(xy 180.461603 -119.90223) (xy 180.438007 -119.94854) (xy 180.407457 -119.990588) (xy 180.370706 -120.027339)
			(xy 180.328658 -120.057889) (xy 180.282348 -120.081485) (xy 180.232918 -120.097546) (xy 180.181583 -120.105676)
			(xy 180.129609 -120.105676) (xy 180.078274 -120.097546) (xy 180.028844 -120.081485) (xy 179.982534 -120.057889)
			(xy 179.940486 -120.027339) (xy 179.903735 -119.990588) (xy 179.873185 -119.94854) (xy 179.849589 -119.90223)
			(xy 179.833528 -119.8528) (xy 179.825398 -119.801465) (xy 179.685948 -119.801465) (xy 179.677818 -119.8528)
			(xy 179.661757 -119.90223) (xy 179.638161 -119.94854) (xy 179.607611 -119.990588) (xy 179.57086 -120.027339)
			(xy 179.528812 -120.057889) (xy 179.482502 -120.081485) (xy 179.433072 -120.097546) (xy 179.381737 -120.105676)
			(xy 179.329763 -120.105676) (xy 179.278428 -120.097546) (xy 179.228998 -120.081485) (xy 179.182688 -120.057889)
			(xy 179.14064 -120.027339) (xy 179.103889 -119.990588) (xy 179.073339 -119.94854) (xy 179.049743 -119.90223)
			(xy 179.033682 -119.8528) (xy 179.025552 -119.801465) (xy 178.085748 -119.801465) (xy 178.077618 -119.8528)
			(xy 178.061557 -119.90223) (xy 178.037961 -119.94854) (xy 178.007411 -119.990588) (xy 177.97066 -120.027339)
			(xy 177.928612 -120.057889) (xy 177.882302 -120.081485) (xy 177.832872 -120.097546) (xy 177.781537 -120.105676)
			(xy 177.729563 -120.105676) (xy 177.678228 -120.097546) (xy 177.628798 -120.081485) (xy 177.582488 -120.057889)
			(xy 177.54044 -120.027339) (xy 177.503689 -119.990588) (xy 177.473139 -119.94854) (xy 177.449543 -119.90223)
			(xy 177.433482 -119.8528) (xy 177.425352 -119.801465) (xy 177.285902 -119.801465) (xy 177.277772 -119.8528)
			(xy 177.261711 -119.90223) (xy 177.238115 -119.94854) (xy 177.207565 -119.990588) (xy 177.170814 -120.027339)
			(xy 177.128766 -120.057889) (xy 177.082456 -120.081485) (xy 177.033026 -120.097546) (xy 176.981691 -120.105676)
			(xy 176.929717 -120.105676) (xy 176.878382 -120.097546) (xy 176.828952 -120.081485) (xy 176.782642 -120.057889)
			(xy 176.740594 -120.027339) (xy 176.703843 -119.990588) (xy 176.673293 -119.94854) (xy 176.649697 -119.90223)
			(xy 176.633636 -119.8528) (xy 176.625506 -119.801465) (xy 176.485802 -119.801465) (xy 176.477672 -119.8528)
			(xy 176.461611 -119.90223) (xy 176.438015 -119.94854) (xy 176.407465 -119.990588) (xy 176.370714 -120.027339)
			(xy 176.328666 -120.057889) (xy 176.282356 -120.081485) (xy 176.232926 -120.097546) (xy 176.181591 -120.105676)
			(xy 176.129617 -120.105676) (xy 176.078282 -120.097546) (xy 176.028852 -120.081485) (xy 175.982542 -120.057889)
			(xy 175.940494 -120.027339) (xy 175.903743 -119.990588) (xy 175.873193 -119.94854) (xy 175.849597 -119.90223)
			(xy 175.833536 -119.8528) (xy 175.825406 -119.801465) (xy 175.685702 -119.801465) (xy 175.677572 -119.8528)
			(xy 175.661511 -119.90223) (xy 175.637915 -119.94854) (xy 175.607365 -119.990588) (xy 175.570614 -120.027339)
			(xy 175.528566 -120.057889) (xy 175.482256 -120.081485) (xy 175.432826 -120.097546) (xy 175.381491 -120.105676)
			(xy 175.329517 -120.105676) (xy 175.278182 -120.097546) (xy 175.228752 -120.081485) (xy 175.182442 -120.057889)
			(xy 175.140394 -120.027339) (xy 175.103643 -119.990588) (xy 175.073093 -119.94854) (xy 175.049497 -119.90223)
			(xy 175.033436 -119.8528) (xy 175.025306 -119.801465) (xy 174.885856 -119.801465) (xy 174.877726 -119.8528)
			(xy 174.861665 -119.90223) (xy 174.838069 -119.94854) (xy 174.807519 -119.990588) (xy 174.770768 -120.027339)
			(xy 174.72872 -120.057889) (xy 174.68241 -120.081485) (xy 174.63298 -120.097546) (xy 174.581645 -120.105676)
			(xy 174.529671 -120.105676) (xy 174.478336 -120.097546) (xy 174.428906 -120.081485) (xy 174.382596 -120.057889)
			(xy 174.340548 -120.027339) (xy 174.303797 -119.990588) (xy 174.273247 -119.94854) (xy 174.249651 -119.90223)
			(xy 174.23359 -119.8528) (xy 174.22546 -119.801465) (xy 174.085756 -119.801465) (xy 174.077626 -119.8528)
			(xy 174.061565 -119.90223) (xy 174.037969 -119.94854) (xy 174.007419 -119.990588) (xy 173.970668 -120.027339)
			(xy 173.92862 -120.057889) (xy 173.88231 -120.081485) (xy 173.83288 -120.097546) (xy 173.781545 -120.105676)
			(xy 173.729571 -120.105676) (xy 173.678236 -120.097546) (xy 173.628806 -120.081485) (xy 173.582496 -120.057889)
			(xy 173.540448 -120.027339) (xy 173.503697 -119.990588) (xy 173.473147 -119.94854) (xy 173.449551 -119.90223)
			(xy 173.43349 -119.8528) (xy 173.42536 -119.801465) (xy 173.285843 -119.801465) (xy 173.285713 -119.807335)
			(xy 173.273564 -119.86988) (xy 173.26229 -119.899684) (xy 173.25848 -119.908828) (xy 173.25848 -120.442228)
			(xy 173.26229 -120.451372) (xy 173.273551 -120.48118) (xy 173.285705 -120.543722) (xy 173.28642 -120.575578)
			(xy 173.285843 -120.601565) (xy 174.22546 -120.601565) (xy 174.22546 -120.549591) (xy 174.23359 -120.498256)
			(xy 174.249651 -120.448826) (xy 174.273247 -120.402516) (xy 174.303797 -120.360468) (xy 174.340548 -120.323717)
			(xy 174.382596 -120.293167) (xy 174.428906 -120.269571) (xy 174.478336 -120.25351) (xy 174.529671 -120.24538)
			(xy 174.581645 -120.24538) (xy 174.63298 -120.25351) (xy 174.68241 -120.269571) (xy 174.72872 -120.293167)
			(xy 174.770768 -120.323717) (xy 174.807519 -120.360468) (xy 174.838069 -120.402516) (xy 174.861665 -120.448826)
			(xy 174.877726 -120.498256) (xy 174.885856 -120.549591) (xy 174.886366 -120.575578) (xy 174.885856 -120.601565)
			(xy 175.025306 -120.601565) (xy 175.025306 -120.549591) (xy 175.033436 -120.498256) (xy 175.049497 -120.448826)
			(xy 175.073093 -120.402516) (xy 175.103643 -120.360468) (xy 175.140394 -120.323717) (xy 175.182442 -120.293167)
			(xy 175.228752 -120.269571) (xy 175.278182 -120.25351) (xy 175.329517 -120.24538) (xy 175.381491 -120.24538)
			(xy 175.432826 -120.25351) (xy 175.482256 -120.269571) (xy 175.528566 -120.293167) (xy 175.570614 -120.323717)
			(xy 175.607365 -120.360468) (xy 175.637915 -120.402516) (xy 175.661511 -120.448826) (xy 175.677572 -120.498256)
			(xy 175.685702 -120.549591) (xy 175.686212 -120.575578) (xy 175.685702 -120.601565) (xy 175.825406 -120.601565)
			(xy 175.825406 -120.549591) (xy 175.833536 -120.498256) (xy 175.849597 -120.448826) (xy 175.873193 -120.402516)
			(xy 175.903743 -120.360468) (xy 175.940494 -120.323717) (xy 175.982542 -120.293167) (xy 176.028852 -120.269571)
			(xy 176.078282 -120.25351) (xy 176.129617 -120.24538) (xy 176.181591 -120.24538) (xy 176.232926 -120.25351)
			(xy 176.282356 -120.269571) (xy 176.328666 -120.293167) (xy 176.370714 -120.323717) (xy 176.407465 -120.360468)
			(xy 176.438015 -120.402516) (xy 176.461611 -120.448826) (xy 176.477672 -120.498256) (xy 176.485802 -120.549591)
			(xy 176.486312 -120.575578) (xy 176.485802 -120.601565) (xy 176.625506 -120.601565) (xy 176.625506 -120.549591)
			(xy 176.633636 -120.498256) (xy 176.649697 -120.448826) (xy 176.673293 -120.402516) (xy 176.703843 -120.360468)
			(xy 176.740594 -120.323717) (xy 176.782642 -120.293167) (xy 176.828952 -120.269571) (xy 176.878382 -120.25351)
			(xy 176.929717 -120.24538) (xy 176.981691 -120.24538) (xy 177.033026 -120.25351) (xy 177.082456 -120.269571)
			(xy 177.128766 -120.293167) (xy 177.170814 -120.323717) (xy 177.207565 -120.360468) (xy 177.238115 -120.402516)
			(xy 177.261711 -120.448826) (xy 177.277772 -120.498256) (xy 177.285902 -120.549591) (xy 177.286412 -120.575578)
			(xy 177.285902 -120.601565) (xy 177.425352 -120.601565) (xy 177.425352 -120.549591) (xy 177.433482 -120.498256)
			(xy 177.449543 -120.448826) (xy 177.473139 -120.402516) (xy 177.503689 -120.360468) (xy 177.54044 -120.323717)
			(xy 177.582488 -120.293167) (xy 177.628798 -120.269571) (xy 177.678228 -120.25351) (xy 177.729563 -120.24538)
			(xy 177.781537 -120.24538) (xy 177.832872 -120.25351) (xy 177.882302 -120.269571) (xy 177.928612 -120.293167)
			(xy 177.97066 -120.323717) (xy 178.007411 -120.360468) (xy 178.037961 -120.402516) (xy 178.061557 -120.448826)
			(xy 178.077618 -120.498256) (xy 178.085748 -120.549591) (xy 178.086258 -120.575578) (xy 178.085748 -120.601565)
			(xy 179.825398 -120.601565) (xy 179.825398 -120.549591) (xy 179.833528 -120.498256) (xy 179.849589 -120.448826)
			(xy 179.873185 -120.402516) (xy 179.903735 -120.360468) (xy 179.940486 -120.323717) (xy 179.982534 -120.293167)
			(xy 180.028844 -120.269571) (xy 180.078274 -120.25351) (xy 180.129609 -120.24538) (xy 180.181583 -120.24538)
			(xy 180.232918 -120.25351) (xy 180.282348 -120.269571) (xy 180.328658 -120.293167) (xy 180.370706 -120.323717)
			(xy 180.407457 -120.360468) (xy 180.438007 -120.402516) (xy 180.461603 -120.448826) (xy 180.477664 -120.498256)
			(xy 180.485794 -120.549591) (xy 180.486304 -120.575578) (xy 180.485794 -120.601565) (xy 180.625498 -120.601565)
			(xy 180.625498 -120.549591) (xy 180.633628 -120.498256) (xy 180.649689 -120.448826) (xy 180.673285 -120.402516)
			(xy 180.703835 -120.360468) (xy 180.740586 -120.323717) (xy 180.782634 -120.293167) (xy 180.828944 -120.269571)
			(xy 180.878374 -120.25351) (xy 180.929709 -120.24538) (xy 180.981683 -120.24538) (xy 181.033018 -120.25351)
			(xy 181.082448 -120.269571) (xy 181.128758 -120.293167) (xy 181.170806 -120.323717) (xy 181.207557 -120.360468)
			(xy 181.238107 -120.402516) (xy 181.261703 -120.448826) (xy 181.277764 -120.498256) (xy 181.285894 -120.549591)
			(xy 181.286404 -120.575578) (xy 181.285894 -120.601565) (xy 181.425598 -120.601565) (xy 181.425598 -120.549591)
			(xy 181.433728 -120.498256) (xy 181.449789 -120.448826) (xy 181.473385 -120.402516) (xy 181.503935 -120.360468)
			(xy 181.540686 -120.323717) (xy 181.582734 -120.293167) (xy 181.629044 -120.269571) (xy 181.678474 -120.25351)
			(xy 181.729809 -120.24538) (xy 181.781783 -120.24538) (xy 181.833118 -120.25351) (xy 181.882548 -120.269571)
			(xy 181.928858 -120.293167) (xy 181.970906 -120.323717) (xy 182.007657 -120.360468) (xy 182.038207 -120.402516)
			(xy 182.061803 -120.448826) (xy 182.077864 -120.498256) (xy 182.085994 -120.549591) (xy 182.086504 -120.575578)
			(xy 182.085994 -120.601565) (xy 182.225444 -120.601565) (xy 182.225444 -120.549591) (xy 182.233574 -120.498256)
			(xy 182.249635 -120.448826) (xy 182.273231 -120.402516) (xy 182.303781 -120.360468) (xy 182.340532 -120.323717)
			(xy 182.38258 -120.293167) (xy 182.42889 -120.269571) (xy 182.47832 -120.25351) (xy 182.529655 -120.24538)
			(xy 182.581629 -120.24538) (xy 182.632964 -120.25351) (xy 182.682394 -120.269571) (xy 182.728704 -120.293167)
			(xy 182.770752 -120.323717) (xy 182.807503 -120.360468) (xy 182.838053 -120.402516) (xy 182.861649 -120.448826)
			(xy 182.87771 -120.498256) (xy 182.88584 -120.549591) (xy 182.88635 -120.575578) (xy 182.88584 -120.601565)
			(xy 183.025544 -120.601565) (xy 183.025544 -120.549591) (xy 183.033674 -120.498256) (xy 183.049735 -120.448826)
			(xy 183.073331 -120.402516) (xy 183.103881 -120.360468) (xy 183.140632 -120.323717) (xy 183.18268 -120.293167)
			(xy 183.22899 -120.269571) (xy 183.27842 -120.25351) (xy 183.329755 -120.24538) (xy 183.381729 -120.24538)
			(xy 183.433064 -120.25351) (xy 183.482494 -120.269571) (xy 183.528804 -120.293167) (xy 183.570852 -120.323717)
			(xy 183.607603 -120.360468) (xy 183.638153 -120.402516) (xy 183.661749 -120.448826) (xy 183.67781 -120.498256)
			(xy 183.68594 -120.549591) (xy 183.68645 -120.575578) (xy 183.68594 -120.601565) (xy 183.67781 -120.6529)
			(xy 183.661749 -120.70233) (xy 183.638153 -120.74864) (xy 183.607603 -120.790688) (xy 183.570852 -120.827439)
			(xy 183.528804 -120.857989) (xy 183.482494 -120.881585) (xy 183.433064 -120.897646) (xy 183.381729 -120.905776)
			(xy 183.329755 -120.905776) (xy 183.27842 -120.897646) (xy 183.22899 -120.881585) (xy 183.18268 -120.857989)
			(xy 183.140632 -120.827439) (xy 183.103881 -120.790688) (xy 183.073331 -120.74864) (xy 183.049735 -120.70233)
			(xy 183.033674 -120.6529) (xy 183.025544 -120.601565) (xy 182.88584 -120.601565) (xy 182.87771 -120.6529)
			(xy 182.861649 -120.70233) (xy 182.838053 -120.74864) (xy 182.807503 -120.790688) (xy 182.770752 -120.827439)
			(xy 182.728704 -120.857989) (xy 182.682394 -120.881585) (xy 182.632964 -120.897646) (xy 182.581629 -120.905776)
			(xy 182.529655 -120.905776) (xy 182.47832 -120.897646) (xy 182.42889 -120.881585) (xy 182.38258 -120.857989)
			(xy 182.340532 -120.827439) (xy 182.303781 -120.790688) (xy 182.273231 -120.74864) (xy 182.249635 -120.70233)
			(xy 182.233574 -120.6529) (xy 182.225444 -120.601565) (xy 182.085994 -120.601565) (xy 182.077864 -120.6529)
			(xy 182.061803 -120.70233) (xy 182.038207 -120.74864) (xy 182.007657 -120.790688) (xy 181.970906 -120.827439)
			(xy 181.928858 -120.857989) (xy 181.882548 -120.881585) (xy 181.833118 -120.897646) (xy 181.781783 -120.905776)
			(xy 181.729809 -120.905776) (xy 181.678474 -120.897646) (xy 181.629044 -120.881585) (xy 181.582734 -120.857989)
			(xy 181.540686 -120.827439) (xy 181.503935 -120.790688) (xy 181.473385 -120.74864) (xy 181.449789 -120.70233)
			(xy 181.433728 -120.6529) (xy 181.425598 -120.601565) (xy 181.285894 -120.601565) (xy 181.277764 -120.6529)
			(xy 181.261703 -120.70233) (xy 181.238107 -120.74864) (xy 181.207557 -120.790688) (xy 181.170806 -120.827439)
			(xy 181.128758 -120.857989) (xy 181.082448 -120.881585) (xy 181.033018 -120.897646) (xy 180.981683 -120.905776)
			(xy 180.929709 -120.905776) (xy 180.878374 -120.897646) (xy 180.828944 -120.881585) (xy 180.782634 -120.857989)
			(xy 180.740586 -120.827439) (xy 180.703835 -120.790688) (xy 180.673285 -120.74864) (xy 180.649689 -120.70233)
			(xy 180.633628 -120.6529) (xy 180.625498 -120.601565) (xy 180.485794 -120.601565) (xy 180.477664 -120.6529)
			(xy 180.461603 -120.70233) (xy 180.438007 -120.74864) (xy 180.407457 -120.790688) (xy 180.370706 -120.827439)
			(xy 180.328658 -120.857989) (xy 180.282348 -120.881585) (xy 180.232918 -120.897646) (xy 180.181583 -120.905776)
			(xy 180.129609 -120.905776) (xy 180.078274 -120.897646) (xy 180.028844 -120.881585) (xy 179.982534 -120.857989)
			(xy 179.940486 -120.827439) (xy 179.903735 -120.790688) (xy 179.873185 -120.74864) (xy 179.849589 -120.70233)
			(xy 179.833528 -120.6529) (xy 179.825398 -120.601565) (xy 178.085748 -120.601565) (xy 178.077618 -120.6529)
			(xy 178.061557 -120.70233) (xy 178.037961 -120.74864) (xy 178.007411 -120.790688) (xy 177.97066 -120.827439)
			(xy 177.928612 -120.857989) (xy 177.882302 -120.881585) (xy 177.832872 -120.897646) (xy 177.781537 -120.905776)
			(xy 177.729563 -120.905776) (xy 177.678228 -120.897646) (xy 177.628798 -120.881585) (xy 177.582488 -120.857989)
			(xy 177.54044 -120.827439) (xy 177.503689 -120.790688) (xy 177.473139 -120.74864) (xy 177.449543 -120.70233)
			(xy 177.433482 -120.6529) (xy 177.425352 -120.601565) (xy 177.285902 -120.601565) (xy 177.277772 -120.6529)
			(xy 177.261711 -120.70233) (xy 177.238115 -120.74864) (xy 177.207565 -120.790688) (xy 177.170814 -120.827439)
			(xy 177.128766 -120.857989) (xy 177.082456 -120.881585) (xy 177.033026 -120.897646) (xy 176.981691 -120.905776)
			(xy 176.929717 -120.905776) (xy 176.878382 -120.897646) (xy 176.828952 -120.881585) (xy 176.782642 -120.857989)
			(xy 176.740594 -120.827439) (xy 176.703843 -120.790688) (xy 176.673293 -120.74864) (xy 176.649697 -120.70233)
			(xy 176.633636 -120.6529) (xy 176.625506 -120.601565) (xy 176.485802 -120.601565) (xy 176.477672 -120.6529)
			(xy 176.461611 -120.70233) (xy 176.438015 -120.74864) (xy 176.407465 -120.790688) (xy 176.370714 -120.827439)
			(xy 176.328666 -120.857989) (xy 176.282356 -120.881585) (xy 176.232926 -120.897646) (xy 176.181591 -120.905776)
			(xy 176.129617 -120.905776) (xy 176.078282 -120.897646) (xy 176.028852 -120.881585) (xy 175.982542 -120.857989)
			(xy 175.940494 -120.827439) (xy 175.903743 -120.790688) (xy 175.873193 -120.74864) (xy 175.849597 -120.70233)
			(xy 175.833536 -120.6529) (xy 175.825406 -120.601565) (xy 175.685702 -120.601565) (xy 175.677572 -120.6529)
			(xy 175.661511 -120.70233) (xy 175.637915 -120.74864) (xy 175.607365 -120.790688) (xy 175.570614 -120.827439)
			(xy 175.528566 -120.857989) (xy 175.482256 -120.881585) (xy 175.432826 -120.897646) (xy 175.381491 -120.905776)
			(xy 175.329517 -120.905776) (xy 175.278182 -120.897646) (xy 175.228752 -120.881585) (xy 175.182442 -120.857989)
			(xy 175.140394 -120.827439) (xy 175.103643 -120.790688) (xy 175.073093 -120.74864) (xy 175.049497 -120.70233)
			(xy 175.033436 -120.6529) (xy 175.025306 -120.601565) (xy 174.885856 -120.601565) (xy 174.877726 -120.6529)
			(xy 174.861665 -120.70233) (xy 174.838069 -120.74864) (xy 174.807519 -120.790688) (xy 174.770768 -120.827439)
			(xy 174.72872 -120.857989) (xy 174.68241 -120.881585) (xy 174.63298 -120.897646) (xy 174.581645 -120.905776)
			(xy 174.529671 -120.905776) (xy 174.478336 -120.897646) (xy 174.428906 -120.881585) (xy 174.382596 -120.857989)
			(xy 174.340548 -120.827439) (xy 174.303797 -120.790688) (xy 174.273247 -120.74864) (xy 174.249651 -120.70233)
			(xy 174.23359 -120.6529) (xy 174.22546 -120.601565) (xy 173.285843 -120.601565) (xy 173.285713 -120.607435)
			(xy 173.273564 -120.66998) (xy 173.26229 -120.699784) (xy 173.25848 -120.708928) (xy 173.25848 -121.242074)
			(xy 173.26229 -121.251218) (xy 173.273547 -121.281027) (xy 173.285693 -121.343569) (xy 173.28642 -121.375424)
			(xy 173.285839 -121.401411) (xy 173.42536 -121.401411) (xy 173.42536 -121.349437) (xy 173.43349 -121.298102)
			(xy 173.449551 -121.248672) (xy 173.473147 -121.202362) (xy 173.503697 -121.160314) (xy 173.540448 -121.123563)
			(xy 173.582496 -121.093013) (xy 173.628806 -121.069417) (xy 173.678236 -121.053356) (xy 173.729571 -121.045226)
			(xy 173.781545 -121.045226) (xy 173.83288 -121.053356) (xy 173.88231 -121.069417) (xy 173.92862 -121.093013)
			(xy 173.970668 -121.123563) (xy 174.007419 -121.160314) (xy 174.037969 -121.202362) (xy 174.061565 -121.248672)
			(xy 174.077626 -121.298102) (xy 174.085756 -121.349437) (xy 174.086266 -121.375424) (xy 174.085756 -121.401411)
			(xy 174.22546 -121.401411) (xy 174.22546 -121.349437) (xy 174.23359 -121.298102) (xy 174.249651 -121.248672)
			(xy 174.273247 -121.202362) (xy 174.303797 -121.160314) (xy 174.340548 -121.123563) (xy 174.382596 -121.093013)
			(xy 174.428906 -121.069417) (xy 174.478336 -121.053356) (xy 174.529671 -121.045226) (xy 174.581645 -121.045226)
			(xy 174.63298 -121.053356) (xy 174.68241 -121.069417) (xy 174.72872 -121.093013) (xy 174.770768 -121.123563)
			(xy 174.807519 -121.160314) (xy 174.838069 -121.202362) (xy 174.861665 -121.248672) (xy 174.877726 -121.298102)
			(xy 174.885856 -121.349437) (xy 174.886366 -121.375424) (xy 174.885856 -121.401411) (xy 175.025306 -121.401411)
			(xy 175.025306 -121.349437) (xy 175.033436 -121.298102) (xy 175.049497 -121.248672) (xy 175.073093 -121.202362)
			(xy 175.103643 -121.160314) (xy 175.140394 -121.123563) (xy 175.182442 -121.093013) (xy 175.228752 -121.069417)
			(xy 175.278182 -121.053356) (xy 175.329517 -121.045226) (xy 175.381491 -121.045226) (xy 175.432826 -121.053356)
			(xy 175.482256 -121.069417) (xy 175.528566 -121.093013) (xy 175.570614 -121.123563) (xy 175.607365 -121.160314)
			(xy 175.637915 -121.202362) (xy 175.661511 -121.248672) (xy 175.677572 -121.298102) (xy 175.685702 -121.349437)
			(xy 175.686212 -121.375424) (xy 175.685702 -121.401411) (xy 175.825406 -121.401411) (xy 175.825406 -121.349437)
			(xy 175.833536 -121.298102) (xy 175.849597 -121.248672) (xy 175.873193 -121.202362) (xy 175.903743 -121.160314)
			(xy 175.940494 -121.123563) (xy 175.982542 -121.093013) (xy 176.028852 -121.069417) (xy 176.078282 -121.053356)
			(xy 176.129617 -121.045226) (xy 176.181591 -121.045226) (xy 176.232926 -121.053356) (xy 176.282356 -121.069417)
			(xy 176.328666 -121.093013) (xy 176.370714 -121.123563) (xy 176.407465 -121.160314) (xy 176.438015 -121.202362)
			(xy 176.461611 -121.248672) (xy 176.477672 -121.298102) (xy 176.485802 -121.349437) (xy 176.486312 -121.375424)
			(xy 176.485802 -121.401411) (xy 176.625506 -121.401411) (xy 176.625506 -121.349437) (xy 176.633636 -121.298102)
			(xy 176.649697 -121.248672) (xy 176.673293 -121.202362) (xy 176.703843 -121.160314) (xy 176.740594 -121.123563)
			(xy 176.782642 -121.093013) (xy 176.828952 -121.069417) (xy 176.878382 -121.053356) (xy 176.929717 -121.045226)
			(xy 176.981691 -121.045226) (xy 177.033026 -121.053356) (xy 177.082456 -121.069417) (xy 177.128766 -121.093013)
			(xy 177.170814 -121.123563) (xy 177.207565 -121.160314) (xy 177.238115 -121.202362) (xy 177.261711 -121.248672)
			(xy 177.277772 -121.298102) (xy 177.285902 -121.349437) (xy 177.286412 -121.375424) (xy 177.285902 -121.401411)
			(xy 177.277772 -121.452746) (xy 177.261711 -121.502176) (xy 177.238115 -121.548486) (xy 177.207565 -121.590534)
			(xy 177.170814 -121.627285) (xy 177.128766 -121.657835) (xy 177.082456 -121.681431) (xy 177.033026 -121.697492)
			(xy 176.981691 -121.705622) (xy 176.929717 -121.705622) (xy 176.878382 -121.697492) (xy 176.828952 -121.681431)
			(xy 176.782642 -121.657835) (xy 176.740594 -121.627285) (xy 176.703843 -121.590534) (xy 176.673293 -121.548486)
			(xy 176.649697 -121.502176) (xy 176.633636 -121.452746) (xy 176.625506 -121.401411) (xy 176.485802 -121.401411)
			(xy 176.477672 -121.452746) (xy 176.461611 -121.502176) (xy 176.438015 -121.548486) (xy 176.407465 -121.590534)
			(xy 176.370714 -121.627285) (xy 176.328666 -121.657835) (xy 176.282356 -121.681431) (xy 176.232926 -121.697492)
			(xy 176.181591 -121.705622) (xy 176.129617 -121.705622) (xy 176.078282 -121.697492) (xy 176.028852 -121.681431)
			(xy 175.982542 -121.657835) (xy 175.940494 -121.627285) (xy 175.903743 -121.590534) (xy 175.873193 -121.548486)
			(xy 175.849597 -121.502176) (xy 175.833536 -121.452746) (xy 175.825406 -121.401411) (xy 175.685702 -121.401411)
			(xy 175.677572 -121.452746) (xy 175.661511 -121.502176) (xy 175.637915 -121.548486) (xy 175.607365 -121.590534)
			(xy 175.570614 -121.627285) (xy 175.528566 -121.657835) (xy 175.482256 -121.681431) (xy 175.432826 -121.697492)
			(xy 175.381491 -121.705622) (xy 175.329517 -121.705622) (xy 175.278182 -121.697492) (xy 175.228752 -121.681431)
			(xy 175.182442 -121.657835) (xy 175.140394 -121.627285) (xy 175.103643 -121.590534) (xy 175.073093 -121.548486)
			(xy 175.049497 -121.502176) (xy 175.033436 -121.452746) (xy 175.025306 -121.401411) (xy 174.885856 -121.401411)
			(xy 174.877726 -121.452746) (xy 174.861665 -121.502176) (xy 174.838069 -121.548486) (xy 174.807519 -121.590534)
			(xy 174.770768 -121.627285) (xy 174.72872 -121.657835) (xy 174.68241 -121.681431) (xy 174.63298 -121.697492)
			(xy 174.581645 -121.705622) (xy 174.529671 -121.705622) (xy 174.478336 -121.697492) (xy 174.428906 -121.681431)
			(xy 174.382596 -121.657835) (xy 174.340548 -121.627285) (xy 174.303797 -121.590534) (xy 174.273247 -121.548486)
			(xy 174.249651 -121.502176) (xy 174.23359 -121.452746) (xy 174.22546 -121.401411) (xy 174.085756 -121.401411)
			(xy 174.077626 -121.452746) (xy 174.061565 -121.502176) (xy 174.037969 -121.548486) (xy 174.007419 -121.590534)
			(xy 173.970668 -121.627285) (xy 173.92862 -121.657835) (xy 173.88231 -121.681431) (xy 173.83288 -121.697492)
			(xy 173.781545 -121.705622) (xy 173.729571 -121.705622) (xy 173.678236 -121.697492) (xy 173.628806 -121.681431)
			(xy 173.582496 -121.657835) (xy 173.540448 -121.627285) (xy 173.503697 -121.590534) (xy 173.473147 -121.548486)
			(xy 173.449551 -121.502176) (xy 173.43349 -121.452746) (xy 173.42536 -121.401411) (xy 173.285839 -121.401411)
			(xy 173.285708 -121.40728) (xy 173.273551 -121.469821) (xy 173.26229 -121.49963) (xy 173.25848 -121.508774)
			(xy 173.25848 -122.076718) (xy 173.985936 -122.80392) (xy 177.444908 -122.80392)
		)
		(stroke
			(width 0)
			(type solid)
		)
		(fill yes)
		(layer "In4.Cu")
		(net "P3V3_AUX_FPGA_VCCIO1")
	)
	(gr_poly
		(pts
			(xy 437.623458 -35.016948) (xy 437.637782 -35.016466) (xy 437.665305 -35.008516) (xy 437.689535 -34.993231)
			(xy 437.708563 -34.971815) (xy 437.72089 -34.945954) (xy 437.725544 -34.917687) (xy 437.724296 -34.90341)
			(xy 437.723092 -34.892337) (xy 437.721822 -34.870098) (xy 437.721756 -34.85896) (xy 437.721756 -34.671508)
			(xy 437.721314 -34.657495) (xy 437.713702 -34.630522) (xy 437.699047 -34.606632) (xy 437.678453 -34.587623)
			(xy 437.653468 -34.574924) (xy 437.625974 -34.56949) (xy 437.598037 -34.571732) (xy 437.57176 -34.581479)
			(xy 437.54912 -34.598) (xy 437.540146 -34.60877) (xy 437.52195 -34.631072) (xy 437.479987 -34.670466)
			(xy 437.432584 -34.70311) (xy 437.380814 -34.728262) (xy 437.325854 -34.745354) (xy 437.26895 -34.753995)
			(xy 437.240172 -34.754566) (xy 437.212925 -34.754078) (xy 437.158986 -34.746319) (xy 437.106701 -34.730963)
			(xy 437.057133 -34.708323) (xy 437.011291 -34.678859) (xy 436.970109 -34.643172) (xy 436.934424 -34.601987)
			(xy 436.904964 -34.556143) (xy 436.882327 -34.506573) (xy 436.866975 -34.454286) (xy 436.85922 -34.400347)
			(xy 436.85922 -34.345853) (xy 436.866975 -34.291914) (xy 436.882327 -34.239627) (xy 436.904964 -34.190057)
			(xy 436.934424 -34.144213) (xy 436.970109 -34.103028) (xy 437.011291 -34.067341) (xy 437.057133 -34.037877)
			(xy 437.106701 -34.015237) (xy 437.158986 -33.999881) (xy 437.212925 -33.992122) (xy 437.240172 -33.99155)
			(xy 437.268953 -33.992072) (xy 437.325861 -34.000717) (xy 437.380825 -34.017814) (xy 437.432596 -34.042975)
			(xy 437.479999 -34.075629) (xy 437.521957 -34.115035) (xy 437.540146 -34.137346) (xy 437.549136 -34.1481)
			(xy 437.571763 -34.164628) (xy 437.598031 -34.174382) (xy 437.625961 -34.176627) (xy 437.65345 -34.171195)
			(xy 437.678426 -34.158494) (xy 437.69901 -34.139482) (xy 437.713649 -34.11559) (xy 437.721242 -34.088619)
			(xy 437.721756 -34.074608) (xy 437.721756 -33.346644) (xy 436.595774 -32.220916) (xy 436.574985 -32.19932)
			(xy 436.539777 -32.150806) (xy 436.512601 -32.097378) (xy 436.494125 -32.040354) (xy 436.484806 -31.98114)
			(xy 436.484268 -31.951168) (xy 436.484268 -28.617418) (xy 436.484754 -28.590185) (xy 436.492505 -28.536273)
			(xy 436.50785 -28.484013) (xy 436.530476 -28.434469) (xy 436.559923 -28.388649) (xy 436.59559 -28.347486)
			(xy 436.636753 -28.311819) (xy 436.682573 -28.282372) (xy 436.732117 -28.259746) (xy 436.784377 -28.244401)
			(xy 436.838289 -28.23665) (xy 436.892755 -28.23665) (xy 436.946667 -28.244401) (xy 436.998927 -28.259746)
			(xy 437.048471 -28.282372) (xy 437.094291 -28.311819) (xy 437.135454 -28.347486) (xy 437.171121 -28.388649)
			(xy 437.200568 -28.434469) (xy 437.223194 -28.484013) (xy 437.238539 -28.536273) (xy 437.24629 -28.590185)
			(xy 437.246776 -28.617418) (xy 437.246776 -30.005528) (xy 438.804302 -30.005528) (xy 438.808373 -29.949906)
			(xy 438.820499 -29.895469) (xy 438.840422 -29.843378) (xy 438.867718 -29.794743) (xy 438.901804 -29.7506)
			(xy 438.941953 -29.711891) (xy 438.987311 -29.67944) (xy 439.036911 -29.653939) (xy 439.089695 -29.635932)
			(xy 439.144538 -29.625802) (xy 439.200272 -29.623765) (xy 439.255709 -29.629865) (xy 439.309666 -29.643971)
			(xy 439.360995 -29.665783) (xy 439.377664 -29.675956) (xy 446.145313 -29.675956) (xy 446.145313 -29.621444)
			(xy 446.153071 -29.567486) (xy 446.168429 -29.515181) (xy 446.191075 -29.465595) (xy 446.220548 -29.419736)
			(xy 446.256247 -29.378538) (xy 446.297445 -29.342841) (xy 446.343305 -29.31337) (xy 446.392892 -29.290725)
			(xy 446.445197 -29.275369) (xy 446.499156 -29.267612) (xy 446.526412 -29.26715) (xy 446.555327 -29.267713)
			(xy 446.612497 -29.27643) (xy 446.667696 -29.293678) (xy 446.719659 -29.319061) (xy 446.767193 -29.351998)
			(xy 446.809211 -29.391733) (xy 446.827402 -29.414216) (xy 446.837299 -29.426021) (xy 446.862623 -29.44354)
			(xy 446.892016 -29.452716) (xy 446.922808 -29.452716) (xy 446.952201 -29.44354) (xy 446.977525 -29.426021)
			(xy 446.987422 -29.414216) (xy 447.005605 -29.391725) (xy 447.047626 -29.35199) (xy 447.095162 -29.319051)
			(xy 447.147125 -29.293664) (xy 447.202324 -29.27641) (xy 447.259495 -29.267683) (xy 447.288412 -29.26715)
			(xy 447.31566 -29.267721) (xy 447.3696 -29.275478) (xy 447.421888 -29.290832) (xy 447.471458 -29.313472)
			(xy 447.517302 -29.342935) (xy 447.558486 -29.378623) (xy 447.594172 -29.419808) (xy 447.623634 -29.465653)
			(xy 447.646272 -29.515224) (xy 447.661625 -29.567512) (xy 447.66938 -29.621452) (xy 447.66938 -29.675948)
			(xy 447.661625 -29.729888) (xy 447.646272 -29.782176) (xy 447.623634 -29.831747) (xy 447.594172 -29.877592)
			(xy 447.558486 -29.918777) (xy 447.517302 -29.954465) (xy 447.471458 -29.983928) (xy 447.421888 -30.006568)
			(xy 447.3696 -30.021922) (xy 447.31566 -30.029679) (xy 447.288412 -30.030166) (xy 447.259495 -30.029652)
			(xy 447.202323 -30.020924) (xy 447.147123 -30.003666) (xy 447.095161 -29.978273) (xy 447.047628 -29.945329)
			(xy 447.005612 -29.905586) (xy 446.987422 -29.8831) (xy 446.977525 -29.871295) (xy 446.952201 -29.853776)
			(xy 446.922808 -29.8446) (xy 446.892016 -29.8446) (xy 446.862623 -29.853776) (xy 446.837299 -29.871295)
			(xy 446.827402 -29.8831) (xy 446.80921 -29.905583) (xy 446.76719 -29.945318) (xy 446.719656 -29.978257)
			(xy 446.667695 -30.003645) (xy 446.612497 -30.020902) (xy 446.555328 -30.029631) (xy 446.526412 -30.030166)
			(xy 446.499156 -30.029788) (xy 446.445197 -30.022031) (xy 446.392892 -30.006675) (xy 446.343305 -29.98403)
			(xy 446.297445 -29.954559) (xy 446.256247 -29.918862) (xy 446.220548 -29.877664) (xy 446.191075 -29.831805)
			(xy 446.168429 -29.782219) (xy 446.153071 -29.729914) (xy 446.145313 -29.675956) (xy 439.377664 -29.675956)
			(xy 439.408601 -29.694837) (xy 439.451469 -29.730512) (xy 439.488686 -29.772049) (xy 439.519459 -29.818562)
			(xy 439.543131 -29.869059) (xy 439.559199 -29.922466) (xy 439.567319 -29.977642) (xy 439.567828 -30.005528)
			(xy 439.567319 -30.033414) (xy 439.559199 -30.08859) (xy 439.543131 -30.141997) (xy 439.519459 -30.192494)
			(xy 439.488686 -30.239007) (xy 439.451469 -30.280544) (xy 439.408601 -30.316219) (xy 439.360995 -30.345273)
			(xy 439.309666 -30.367085) (xy 439.255709 -30.381191) (xy 439.200272 -30.387291) (xy 439.144538 -30.385254)
			(xy 439.089695 -30.375124) (xy 439.036911 -30.357117) (xy 438.987311 -30.331616) (xy 438.941953 -30.299165)
			(xy 438.901804 -30.260456) (xy 438.867718 -30.216313) (xy 438.840422 -30.167678) (xy 438.820499 -30.115587)
			(xy 438.808373 -30.06115) (xy 438.804302 -30.005528) (xy 437.246776 -30.005528) (xy 437.246776 -30.706568)
			(xy 441.506862 -30.706568) (xy 441.510933 -30.650946) (xy 441.523059 -30.596509) (xy 441.542982 -30.544418)
			(xy 441.570278 -30.495783) (xy 441.604364 -30.45164) (xy 441.644513 -30.412931) (xy 441.689871 -30.38048)
			(xy 441.739471 -30.354979) (xy 441.792255 -30.336972) (xy 441.847098 -30.326842) (xy 441.902832 -30.324805)
			(xy 441.958269 -30.330905) (xy 442.012226 -30.345011) (xy 442.063555 -30.366823) (xy 442.111161 -30.395877)
			(xy 442.154029 -30.431552) (xy 442.191066 -30.472888) (xy 444.326262 -30.472888) (xy 444.330333 -30.417266)
			(xy 444.342459 -30.362829) (xy 444.362382 -30.310738) (xy 444.389678 -30.262103) (xy 444.423764 -30.21796)
			(xy 444.463913 -30.179251) (xy 444.509271 -30.1468) (xy 444.558871 -30.121299) (xy 444.611655 -30.103292)
			(xy 444.666498 -30.093162) (xy 444.722232 -30.091125) (xy 444.777669 -30.097225) (xy 444.831626 -30.111331)
			(xy 444.882955 -30.133143) (xy 444.930561 -30.162197) (xy 444.973429 -30.197872) (xy 445.010646 -30.239409)
			(xy 445.041419 -30.285922) (xy 445.065091 -30.336419) (xy 445.081159 -30.389826) (xy 445.089279 -30.445002)
			(xy 445.089788 -30.472888) (xy 445.089279 -30.500774) (xy 445.081159 -30.55595) (xy 445.065091 -30.609357)
			(xy 445.041419 -30.659854) (xy 445.010646 -30.706367) (xy 444.973429 -30.747904) (xy 444.930561 -30.783579)
			(xy 444.882955 -30.812633) (xy 444.831626 -30.834445) (xy 444.777669 -30.848551) (xy 444.722232 -30.854651)
			(xy 444.666498 -30.852614) (xy 444.611655 -30.842484) (xy 444.558871 -30.824477) (xy 444.509271 -30.798976)
			(xy 444.463913 -30.766525) (xy 444.423764 -30.727816) (xy 444.389678 -30.683673) (xy 444.362382 -30.635038)
			(xy 444.342459 -30.582947) (xy 444.330333 -30.52851) (xy 444.326262 -30.472888) (xy 442.191066 -30.472888)
			(xy 442.191246 -30.473089) (xy 442.222019 -30.519602) (xy 442.245691 -30.570099) (xy 442.261759 -30.623506)
			(xy 442.269879 -30.678682) (xy 442.270388 -30.706568) (xy 442.269879 -30.734454) (xy 442.261759 -30.78963)
			(xy 442.245691 -30.843037) (xy 442.222019 -30.893534) (xy 442.191246 -30.940047) (xy 442.154029 -30.981584)
			(xy 442.111161 -31.017259) (xy 442.063555 -31.046313) (xy 442.012226 -31.068125) (xy 441.958269 -31.082231)
			(xy 441.902832 -31.088331) (xy 441.847098 -31.086294) (xy 441.792255 -31.076164) (xy 441.739471 -31.058157)
			(xy 441.689871 -31.032656) (xy 441.644513 -31.000205) (xy 441.604364 -30.961496) (xy 441.570278 -30.917353)
			(xy 441.542982 -30.868718) (xy 441.523059 -30.816627) (xy 441.510933 -30.76219) (xy 441.506862 -30.706568)
			(xy 437.246776 -30.706568) (xy 437.246776 -31.229808) (xy 442.850522 -31.229808) (xy 442.854593 -31.174186)
			(xy 442.866719 -31.119749) (xy 442.886642 -31.067658) (xy 442.913938 -31.019023) (xy 442.948024 -30.97488)
			(xy 442.988173 -30.936171) (xy 443.033531 -30.90372) (xy 443.083131 -30.878219) (xy 443.135915 -30.860212)
			(xy 443.190758 -30.850082) (xy 443.246492 -30.848045) (xy 443.301929 -30.854145) (xy 443.355886 -30.868251)
			(xy 443.407215 -30.890063) (xy 443.454821 -30.919117) (xy 443.497689 -30.954792) (xy 443.534906 -30.996329)
			(xy 443.565679 -31.042842) (xy 443.589351 -31.093339) (xy 443.605419 -31.146746) (xy 443.613539 -31.201922)
			(xy 443.614048 -31.229808) (xy 443.613539 -31.257694) (xy 443.605419 -31.31287) (xy 443.589351 -31.366277)
			(xy 443.565679 -31.416774) (xy 443.534906 -31.463287) (xy 443.497689 -31.504824) (xy 443.454821 -31.540499)
			(xy 443.407215 -31.569553) (xy 443.355886 -31.591365) (xy 443.301929 -31.605471) (xy 443.246492 -31.611571)
			(xy 443.190758 -31.609534) (xy 443.135915 -31.599404) (xy 443.083131 -31.581397) (xy 443.033531 -31.555896)
			(xy 442.988173 -31.523445) (xy 442.948024 -31.484736) (xy 442.913938 -31.440593) (xy 442.886642 -31.391958)
			(xy 442.866719 -31.339867) (xy 442.854593 -31.28543) (xy 442.850522 -31.229808) (xy 437.246776 -31.229808)
			(xy 437.246776 -31.79318) (xy 438.02724 -32.573468) (xy 446.226182 -32.573468) (xy 446.230253 -32.517846)
			(xy 446.242379 -32.463409) (xy 446.262302 -32.411318) (xy 446.289598 -32.362683) (xy 446.323684 -32.31854)
			(xy 446.363833 -32.279831) (xy 446.409191 -32.24738) (xy 446.458791 -32.221879) (xy 446.511575 -32.203872)
			(xy 446.566418 -32.193742) (xy 446.622152 -32.191705) (xy 446.677589 -32.197805) (xy 446.731546 -32.211911)
			(xy 446.782875 -32.233723) (xy 446.830481 -32.262777) (xy 446.873349 -32.298452) (xy 446.910566 -32.339989)
			(xy 446.941339 -32.386502) (xy 446.965011 -32.436999) (xy 446.981079 -32.490406) (xy 446.989199 -32.545582)
			(xy 446.989708 -32.573468) (xy 446.989199 -32.601354) (xy 446.981079 -32.65653) (xy 446.965011 -32.709937)
			(xy 446.941339 -32.760434) (xy 446.910566 -32.806947) (xy 446.873349 -32.848484) (xy 446.830481 -32.884159)
			(xy 446.782875 -32.913213) (xy 446.731546 -32.935025) (xy 446.677589 -32.949131) (xy 446.622152 -32.955231)
			(xy 446.566418 -32.953194) (xy 446.511575 -32.943064) (xy 446.458791 -32.925057) (xy 446.409191 -32.899556)
			(xy 446.363833 -32.867105) (xy 446.323684 -32.828396) (xy 446.289598 -32.784253) (xy 446.262302 -32.735618)
			(xy 446.242379 -32.683527) (xy 446.230253 -32.62909) (xy 446.226182 -32.573468) (xy 438.02724 -32.573468)
			(xy 438.372758 -32.918908) (xy 438.393549 -32.940503) (xy 438.428759 -32.989016) (xy 438.455938 -33.042444)
			(xy 438.474413 -33.099469) (xy 438.48373 -33.158684) (xy 438.484264 -33.188656) (xy 438.484264 -34.700972)
			(xy 438.80024 -35.016948) (xy 456.87488 -35.016948) (xy 459.54188 -32.349948) (xy 459.54188 -22.669246)
			(xy 459.535746 -22.57704) (xy 459.52914 -22.392339) (xy 459.528672 -22.29993) (xy 459.529138 -22.207521)
			(xy 459.535743 -22.02282) (xy 459.54188 -21.930614) (xy 459.54188 -15.204948) (xy 459.004162 -14.66723)
			(xy 458.993748 -14.66342) (xy 458.96991 -14.654124) (xy 458.924963 -14.629678) (xy 458.883977 -14.599053)
			(xy 458.847795 -14.562877) (xy 458.817161 -14.521897) (xy 458.792706 -14.476955) (xy 458.783436 -14.453108)
			(xy 458.779626 -14.442694) (xy 458.52588 -14.188948) (xy 452.709026 -14.188948) (xy 452.700644 -14.191996)
			(xy 452.675527 -14.200622) (xy 452.623574 -14.211632) (xy 452.570596 -14.215326) (xy 452.517618 -14.211632)
			(xy 452.465665 -14.200622) (xy 452.440548 -14.191996) (xy 452.432166 -14.188948) (xy 446.46088 -14.188948)
			(xy 444.869316 -15.780512) (xy 444.859126 -15.791493) (xy 444.845056 -15.817924) (xy 444.839252 -15.847299)
			(xy 444.842214 -15.877096) (xy 444.853687 -15.904753) (xy 444.872686 -15.927897) (xy 444.897579 -15.944538)
			(xy 444.926227 -15.953248) (xy 444.941198 -15.95374) (xy 449.96608 -15.95374) (xy 449.991061 -15.954257)
			(xy 450.040402 -15.962119) (xy 450.08791 -15.977589) (xy 450.132419 -16.000289) (xy 450.172837 -16.029661)
			(xy 450.19087 -16.046958) (xy 450.248274 -16.104362) (xy 450.300852 -16.052038) (xy 450.299074 -16.02867)
			(xy 450.297804 -15.998698) (xy 450.298291 -15.971124) (xy 450.306234 -15.916552) (xy 450.321953 -15.863692)
			(xy 450.345122 -15.813648) (xy 450.375257 -15.767462) (xy 450.41173 -15.726098) (xy 450.432424 -15.707868)
			(xy 450.443318 -15.697968) (xy 450.459386 -15.673317) (xy 450.467767 -15.645111) (xy 450.467766 -15.615686)
			(xy 450.459385 -15.58748) (xy 450.443317 -15.56283) (xy 450.432424 -15.552928) (xy 450.411717 -15.534712)
			(xy 450.37525 -15.493341) (xy 450.345117 -15.447151) (xy 450.321947 -15.397105) (xy 450.306222 -15.344245)
			(xy 450.29827 -15.289673) (xy 450.297804 -15.262098) (xy 450.29829 -15.234847) (xy 450.306046 -15.180899)
			(xy 450.321401 -15.128604) (xy 450.344043 -15.079027) (xy 450.373509 -15.033177) (xy 450.4092 -14.991986)
			(xy 450.450391 -14.956295) (xy 450.496241 -14.926829) (xy 450.545818 -14.904187) (xy 450.598113 -14.888832)
			(xy 450.652061 -14.881076) (xy 450.706563 -14.881076) (xy 450.760511 -14.888832) (xy 450.812806 -14.904187)
			(xy 450.862383 -14.926829) (xy 450.908233 -14.956295) (xy 450.949424 -14.991986) (xy 450.985115 -15.033177)
			(xy 451.014581 -15.079027) (xy 451.037223 -15.128604) (xy 451.052578 -15.180899) (xy 451.060334 -15.234847)
			(xy 451.06082 -15.262098) (xy 451.060333 -15.289672) (xy 451.052392 -15.344245) (xy 451.036673 -15.397106)
			(xy 451.013505 -15.447152) (xy 450.983372 -15.493339) (xy 450.946901 -15.534706) (xy 450.9262 -15.552928)
			(xy 450.915303 -15.562827) (xy 450.89923 -15.587477) (xy 450.890846 -15.615685) (xy 450.890846 -15.645112)
			(xy 450.899229 -15.67332) (xy 450.915301 -15.697971) (xy 450.9262 -15.707868) (xy 450.946906 -15.726084)
			(xy 450.983372 -15.767456) (xy 451.013503 -15.813646) (xy 451.036672 -15.863692) (xy 451.052396 -15.916551)
			(xy 451.060349 -15.971124) (xy 451.06082 -15.998698) (xy 451.060368 -16.025382) (xy 451.052921 -16.078228)
			(xy 451.038185 -16.129521) (xy 451.016449 -16.178262) (xy 450.988135 -16.2235) (xy 450.953796 -16.264353)
			(xy 450.914101 -16.300025) (xy 450.869825 -16.32982) (xy 450.82183 -16.353157) (xy 450.771052 -16.369582)
			(xy 450.744844 -16.374618) (xy 450.731232 -16.377455) (xy 450.70614 -16.389405) (xy 450.685197 -16.407676)
			(xy 450.669954 -16.430916) (xy 450.66154 -16.457404) (xy 450.660576 -16.48518) (xy 450.667135 -16.512187)
			(xy 450.680731 -16.536427) (xy 450.690234 -16.546576) (xy 450.859652 -16.71574) (xy 452.218552 -16.71574)
			(xy 452.243534 -16.716255) (xy 452.292877 -16.724113) (xy 452.340388 -16.73958) (xy 452.3849 -16.762277)
			(xy 452.425322 -16.791648) (xy 452.443342 -16.808958) (xy 454.287636 -18.653252) (xy 454.301606 -18.656808)
			(xy 454.329014 -18.663905) (xy 454.381513 -18.685093) (xy 454.430301 -18.713812) (xy 454.474305 -18.749432)
			(xy 454.512557 -18.791168) (xy 454.544214 -18.838103) (xy 454.568582 -18.889204) (xy 454.585124 -18.943347)
			(xy 454.593476 -18.999341) (xy 454.59396 -19.027648) (xy 454.593496 -19.054249) (xy 454.5861 -19.106936)
			(xy 454.571457 -19.158084) (xy 454.549853 -19.206704) (xy 454.521706 -19.251851) (xy 454.48756 -19.292651)
			(xy 454.448079 -19.328313) (xy 454.42632 -19.343624) (xy 454.414838 -19.351957) (xy 454.39663 -19.3737)
			(xy 454.38511 -19.399615) (xy 454.381169 -19.427699) (xy 454.38511 -19.455783) (xy 454.396629 -19.481698)
			(xy 454.414836 -19.503441) (xy 454.42632 -19.511772) (xy 454.448094 -19.527065) (xy 454.487586 -19.56272)
			(xy 454.521738 -19.603519) (xy 454.549887 -19.64867) (xy 454.571487 -19.697295) (xy 454.586116 -19.748451)
			(xy 454.593492 -19.801144) (xy 454.59396 -19.827748) (xy 454.593474 -19.854999) (xy 454.585718 -19.908947)
			(xy 454.570363 -19.961242) (xy 454.547721 -20.010819) (xy 454.518255 -20.056669) (xy 454.482564 -20.09786)
			(xy 454.441373 -20.133551) (xy 454.395523 -20.163017) (xy 454.345946 -20.185659) (xy 454.293651 -20.201014)
			(xy 454.239703 -20.20877) (xy 454.185201 -20.20877) (xy 454.131253 -20.201014) (xy 454.078958 -20.185659)
			(xy 454.029381 -20.163017) (xy 453.983531 -20.133551) (xy 453.94234 -20.09786) (xy 453.906649 -20.056669)
			(xy 453.877183 -20.010819) (xy 453.854541 -19.961242) (xy 453.839186 -19.908947) (xy 453.83143 -19.854999)
			(xy 453.830944 -19.827748) (xy 453.831409 -19.801147) (xy 453.838805 -19.748461) (xy 453.853448 -19.697313)
			(xy 453.875053 -19.648694) (xy 453.903201 -19.603547) (xy 453.937346 -19.562748) (xy 453.976828 -19.527086)
			(xy 453.998584 -19.511772) (xy 454.010065 -19.503439) (xy 454.028271 -19.481696) (xy 454.039789 -19.455782)
			(xy 454.04373 -19.427699) (xy 454.039789 -19.399616) (xy 454.02827 -19.373702) (xy 454.010064 -19.35196)
			(xy 453.998584 -19.343624) (xy 453.990377 -19.338022) (xy 453.974493 -19.326079) (xy 453.966834 -19.319748)
			(xy 453.954827 -19.310416) (xy 453.926824 -19.298599) (xy 453.896585 -19.295533) (xy 453.866781 -19.301488)
			(xy 453.840041 -19.315938) (xy 453.818729 -19.337607) (xy 453.804725 -19.364582) (xy 453.80148 -19.379438)
			(xy 453.796355 -19.405534) (xy 453.779826 -19.45608) (xy 453.75643 -19.503837) (xy 453.726622 -19.547878)
			(xy 453.69098 -19.587346) (xy 453.650196 -19.621476) (xy 453.605064 -19.649604) (xy 453.556459 -19.671184)
			(xy 453.505326 -19.685797) (xy 453.452658 -19.693159) (xy 453.426068 -19.693636) (xy 453.398818 -19.693148)
			(xy 453.344872 -19.685388) (xy 453.292579 -19.67003) (xy 453.243004 -19.647388) (xy 453.197156 -19.617921)
			(xy 453.155967 -19.58223) (xy 453.120277 -19.541041) (xy 453.09081 -19.495192) (xy 453.068168 -19.445617)
			(xy 453.052811 -19.393324) (xy 453.045052 -19.339378) (xy 453.04456 -19.312128) (xy 453.04503 -19.285071)
			(xy 453.052672 -19.231498) (xy 453.067807 -19.179543) (xy 453.090131 -19.130248) (xy 453.119197 -19.084602)
			(xy 453.15442 -19.04352) (xy 453.195095 -19.007828) (xy 453.240405 -18.97824) (xy 453.289441 -18.955352)
			(xy 453.341218 -18.939622) (xy 453.394699 -18.931365) (xy 453.42175 -18.93062) (xy 453.436684 -18.929955)
			(xy 453.465201 -18.921038) (xy 453.489916 -18.904247) (xy 453.508711 -18.88102) (xy 453.519977 -18.853347)
			(xy 453.52275 -18.823597) (xy 453.516791 -18.794318) (xy 453.502611 -18.768018) (xy 453.492362 -18.757138)
			(xy 452.595996 -17.860772) (xy 452.585099 -17.850601) (xy 452.558851 -17.836503) (xy 452.52965 -17.830586)
			(xy 452.499984 -17.833355) (xy 452.472382 -17.844573) (xy 452.449196 -17.863285) (xy 452.432403 -17.887896)
			(xy 452.42734 -17.90192) (xy 452.418847 -17.927284) (xy 452.395755 -17.97553) (xy 452.366149 -18.020078)
			(xy 452.330611 -18.060054) (xy 452.3105 -18.077688) (xy 452.299597 -18.087587) (xy 452.283514 -18.112241)
			(xy 452.27512 -18.140455) (xy 452.275112 -18.169891) (xy 452.283491 -18.19811) (xy 452.299561 -18.222772)
			(xy 452.3105 -18.232628) (xy 452.331203 -18.250846) (xy 452.367662 -18.292219) (xy 452.397786 -18.33841)
			(xy 452.420947 -18.388456) (xy 452.436663 -18.441315) (xy 452.444607 -18.495885) (xy 452.44512 -18.523458)
			(xy 452.444634 -18.550709) (xy 452.436878 -18.604657) (xy 452.421523 -18.656952) (xy 452.398881 -18.706529)
			(xy 452.369415 -18.752379) (xy 452.333724 -18.79357) (xy 452.292533 -18.829261) (xy 452.246683 -18.858727)
			(xy 452.197106 -18.881369) (xy 452.144811 -18.896724) (xy 452.090863 -18.90448) (xy 452.036361 -18.90448)
			(xy 451.982413 -18.896724) (xy 451.930118 -18.881369) (xy 451.880541 -18.858727) (xy 451.834691 -18.829261)
			(xy 451.7935 -18.79357) (xy 451.757809 -18.752379) (xy 451.728343 -18.706529) (xy 451.705701 -18.656952)
			(xy 451.690346 -18.604657) (xy 451.68259 -18.550709) (xy 451.682104 -18.523458) (xy 451.682587 -18.495882)
			(xy 451.690522 -18.441305) (xy 451.706235 -18.38844) (xy 451.729399 -18.33839) (xy 451.759531 -18.292197)
			(xy 451.796001 -18.250826) (xy 451.816724 -18.232628) (xy 451.827613 -18.222728) (xy 451.843669 -18.198081)
			(xy 451.85204 -18.169881) (xy 451.852032 -18.140465) (xy 451.843646 -18.11227) (xy 451.827576 -18.087631)
			(xy 451.816724 -18.077688) (xy 451.796019 -18.059471) (xy 451.759556 -18.018099) (xy 451.729428 -17.971909)
			(xy 451.706263 -17.921863) (xy 451.690544 -17.869003) (xy 451.682597 -17.814432) (xy 451.682104 -17.786858)
			(xy 451.682676 -17.757767) (xy 451.691551 -17.700264) (xy 451.709044 -17.644772) (xy 451.73475 -17.592574)
			(xy 451.768074 -17.544879) (xy 451.787768 -17.52346) (xy 451.797658 -17.512362) (xy 451.811127 -17.485877)
			(xy 451.816406 -17.456636) (xy 451.813048 -17.427114) (xy 451.801336 -17.399806) (xy 451.782261 -17.377024)
			(xy 451.757438 -17.360694) (xy 451.728965 -17.352197) (xy 451.714108 -17.351756) (xy 450.72808 -17.351756)
			(xy 450.703097 -17.351243) (xy 450.653751 -17.34339) (xy 450.606237 -17.327926) (xy 450.561722 -17.305231)
			(xy 450.521297 -17.275863) (xy 450.50329 -17.258538) (xy 449.834508 -16.589756) (xy 444.060326 -16.589756)
			(xy 442.494416 -18.155412) (xy 442.512704 -18.188686) (xy 442.527408 -18.216947) (xy 442.548239 -18.277148)
			(xy 442.5588 -18.339969) (xy 442.55944 -18.37182) (xy 442.558967 -18.399189) (xy 442.552168 -18.446242)
			(xy 446.165984 -18.446242) (xy 446.170055 -18.39062) (xy 446.182181 -18.336183) (xy 446.202104 -18.284092)
			(xy 446.2294 -18.235457) (xy 446.263486 -18.191314) (xy 446.303635 -18.152605) (xy 446.348993 -18.120154)
			(xy 446.398593 -18.094653) (xy 446.451377 -18.076646) (xy 446.50622 -18.066516) (xy 446.561954 -18.064479)
			(xy 446.617391 -18.070579) (xy 446.671348 -18.084685) (xy 446.722677 -18.106497) (xy 446.770283 -18.135551)
			(xy 446.813151 -18.171226) (xy 446.850368 -18.212763) (xy 446.881141 -18.259276) (xy 446.904813 -18.309773)
			(xy 446.920881 -18.36318) (xy 446.929001 -18.418356) (xy 446.92951 -18.446242) (xy 446.929195 -18.463514)
			(xy 449.291454 -18.463514) (xy 449.295525 -18.407892) (xy 449.307651 -18.353455) (xy 449.327574 -18.301364)
			(xy 449.35487 -18.252729) (xy 449.388956 -18.208586) (xy 449.429105 -18.169877) (xy 449.474463 -18.137426)
			(xy 449.524063 -18.111925) (xy 449.576847 -18.093918) (xy 449.63169 -18.083788) (xy 449.687424 -18.081751)
			(xy 449.742861 -18.087851) (xy 449.796818 -18.101957) (xy 449.848147 -18.123769) (xy 449.895753 -18.152823)
			(xy 449.938621 -18.188498) (xy 449.975838 -18.230035) (xy 450.006611 -18.276548) (xy 450.030283 -18.327045)
			(xy 450.046351 -18.380452) (xy 450.054471 -18.435628) (xy 450.05498 -18.463514) (xy 450.054471 -18.4914)
			(xy 450.046351 -18.546576) (xy 450.030283 -18.599983) (xy 450.018171 -18.62582) (xy 450.615302 -18.62582)
			(xy 450.619373 -18.570198) (xy 450.631499 -18.515761) (xy 450.651422 -18.46367) (xy 450.678718 -18.415035)
			(xy 450.712804 -18.370892) (xy 450.752953 -18.332183) (xy 450.798311 -18.299732) (xy 450.847911 -18.274231)
			(xy 450.900695 -18.256224) (xy 450.955538 -18.246094) (xy 451.011272 -18.244057) (xy 451.066709 -18.250157)
			(xy 451.120666 -18.264263) (xy 451.171995 -18.286075) (xy 451.219601 -18.315129) (xy 451.262469 -18.350804)
			(xy 451.299686 -18.392341) (xy 451.330459 -18.438854) (xy 451.354131 -18.489351) (xy 451.370199 -18.542758)
			(xy 451.378319 -18.597934) (xy 451.378828 -18.62582) (xy 451.378319 -18.653706) (xy 451.370199 -18.708882)
			(xy 451.354131 -18.762289) (xy 451.330459 -18.812786) (xy 451.299686 -18.859299) (xy 451.262469 -18.900836)
			(xy 451.219601 -18.936511) (xy 451.171995 -18.965565) (xy 451.120666 -18.987377) (xy 451.066709 -19.001483)
			(xy 451.011272 -19.007583) (xy 450.955538 -19.005546) (xy 450.900695 -18.995416) (xy 450.847911 -18.977409)
			(xy 450.798311 -18.951908) (xy 450.752953 -18.919457) (xy 450.712804 -18.880748) (xy 450.678718 -18.836605)
			(xy 450.651422 -18.78797) (xy 450.631499 -18.735879) (xy 450.619373 -18.681442) (xy 450.615302 -18.62582)
			(xy 450.018171 -18.62582) (xy 450.006611 -18.65048) (xy 449.975838 -18.696993) (xy 449.938621 -18.73853)
			(xy 449.895753 -18.774205) (xy 449.848147 -18.803259) (xy 449.796818 -18.825071) (xy 449.742861 -18.839177)
			(xy 449.687424 -18.845277) (xy 449.63169 -18.84324) (xy 449.576847 -18.83311) (xy 449.524063 -18.815103)
			(xy 449.474463 -18.789602) (xy 449.429105 -18.757151) (xy 449.388956 -18.718442) (xy 449.35487 -18.674299)
			(xy 449.327574 -18.625664) (xy 449.307651 -18.573573) (xy 449.295525 -18.519136) (xy 449.291454 -18.463514)
			(xy 446.929195 -18.463514) (xy 446.929001 -18.474128) (xy 446.920881 -18.529304) (xy 446.904813 -18.582711)
			(xy 446.881141 -18.633208) (xy 446.850368 -18.679721) (xy 446.813151 -18.721258) (xy 446.770283 -18.756933)
			(xy 446.722677 -18.785987) (xy 446.671348 -18.807799) (xy 446.617391 -18.821905) (xy 446.561954 -18.828005)
			(xy 446.50622 -18.825968) (xy 446.451377 -18.815838) (xy 446.398593 -18.797831) (xy 446.348993 -18.77233)
			(xy 446.303635 -18.739879) (xy 446.263486 -18.70117) (xy 446.2294 -18.657027) (xy 446.202104 -18.608392)
			(xy 446.182181 -18.556301) (xy 446.170055 -18.501864) (xy 446.165984 -18.446242) (xy 442.552168 -18.446242)
			(xy 442.551139 -18.453365) (xy 442.535648 -18.505866) (xy 442.512811 -18.555613) (xy 442.483098 -18.601585)
			(xy 442.46546 -18.622518) (xy 442.456229 -18.633846) (xy 442.444062 -18.660403) (xy 442.439896 -18.689315)
			(xy 442.444071 -18.718226) (xy 442.456246 -18.744779) (xy 442.46546 -18.756122) (xy 442.483102 -18.777053)
			(xy 442.512829 -18.823019) (xy 442.535672 -18.872766) (xy 442.551161 -18.92527) (xy 442.558977 -18.979449)
			(xy 442.55944 -19.00682) (xy 442.558953 -19.034071) (xy 442.551194 -19.088018) (xy 442.535838 -19.140313)
			(xy 442.513196 -19.189889) (xy 442.48373 -19.23574) (xy 442.448038 -19.27693) (xy 442.406849 -19.312622)
			(xy 442.361 -19.34209) (xy 442.311424 -19.364733) (xy 442.25913 -19.380092) (xy 442.205183 -19.387852)
			(xy 442.177932 -19.388328) (xy 442.1513 -19.387867) (xy 442.098554 -19.380462) (xy 442.04735 -19.365793)
			(xy 441.998685 -19.344144) (xy 441.953504 -19.315937) (xy 441.912685 -19.281719) (xy 441.877023 -19.242156)
			(xy 441.847211 -19.198018) (xy 441.823828 -19.150161) (xy 441.807329 -19.099517) (xy 441.802266 -19.073368)
			(xy 441.799389 -19.059776) (xy 441.787366 -19.034742) (xy 441.769036 -19.01388) (xy 441.745758 -18.998736)
			(xy 441.719258 -18.990434) (xy 441.6915 -18.989587) (xy 441.664543 -18.996261) (xy 441.640385 -19.009958)
			(xy 441.630308 -19.01952) (xy 441.143532 -19.506438) (xy 448.687442 -19.506438) (xy 448.691513 -19.450816)
			(xy 448.703639 -19.396379) (xy 448.723562 -19.344288) (xy 448.750858 -19.295653) (xy 448.784944 -19.25151)
			(xy 448.825093 -19.212801) (xy 448.870451 -19.18035) (xy 448.920051 -19.154849) (xy 448.972835 -19.136842)
			(xy 449.027678 -19.126712) (xy 449.083412 -19.124675) (xy 449.138849 -19.130775) (xy 449.192806 -19.144881)
			(xy 449.244135 -19.166693) (xy 449.291741 -19.195747) (xy 449.334609 -19.231422) (xy 449.371826 -19.272959)
			(xy 449.402599 -19.319472) (xy 449.426271 -19.369969) (xy 449.442339 -19.423376) (xy 449.450459 -19.478552)
			(xy 449.450968 -19.506438) (xy 449.450459 -19.534324) (xy 449.442339 -19.5895) (xy 449.426271 -19.642907)
			(xy 449.402599 -19.693404) (xy 449.371826 -19.739917) (xy 449.334609 -19.781454) (xy 449.291741 -19.817129)
			(xy 449.244135 -19.846183) (xy 449.192806 -19.867995) (xy 449.138849 -19.882101) (xy 449.083412 -19.888201)
			(xy 449.027678 -19.886164) (xy 448.972835 -19.876034) (xy 448.920051 -19.858027) (xy 448.870451 -19.832526)
			(xy 448.825093 -19.800075) (xy 448.784944 -19.761366) (xy 448.750858 -19.717223) (xy 448.723562 -19.668588)
			(xy 448.703639 -19.616497) (xy 448.691513 -19.56206) (xy 448.687442 -19.506438) (xy 441.143532 -19.506438)
			(xy 440.759088 -19.890994) (xy 440.759088 -20.91182) (xy 441.796424 -20.91182) (xy 441.796896 -20.88445)
			(xy 441.804711 -20.830271) (xy 441.820199 -20.777768) (xy 441.843039 -20.728021) (xy 441.872763 -20.682054)
			(xy 441.890404 -20.661122) (xy 441.899621 -20.64978) (xy 441.911801 -20.623228) (xy 441.915977 -20.594315)
			(xy 441.911809 -20.565401) (xy 441.899638 -20.538845) (xy 441.890404 -20.527518) (xy 441.872761 -20.506589)
			(xy 441.843049 -20.460616) (xy 441.820214 -20.410867) (xy 441.804724 -20.358366) (xy 441.796897 -20.304189)
			(xy 441.796424 -20.27682) (xy 441.79691 -20.249569) (xy 441.804666 -20.195621) (xy 441.820021 -20.143326)
			(xy 441.842663 -20.093749) (xy 441.872129 -20.047899) (xy 441.90782 -20.006708) (xy 441.949011 -19.971017)
			(xy 441.994861 -19.941551) (xy 442.044438 -19.918909) (xy 442.096733 -19.903554) (xy 442.150681 -19.895798)
			(xy 442.205183 -19.895798) (xy 442.259131 -19.903554) (xy 442.311426 -19.918909) (xy 442.361003 -19.941551)
			(xy 442.406853 -19.971017) (xy 442.448044 -20.006708) (xy 442.483735 -20.047899) (xy 442.513201 -20.093749)
			(xy 442.535843 -20.143326) (xy 442.551198 -20.195621) (xy 442.558954 -20.249569) (xy 442.55944 -20.27682)
			(xy 442.559 -20.304191) (xy 442.551178 -20.358372) (xy 442.535684 -20.410876) (xy 442.512836 -20.460623)
			(xy 442.483105 -20.506588) (xy 442.46546 -20.527518) (xy 442.456207 -20.538832) (xy 442.444037 -20.565395)
			(xy 442.43987 -20.594315) (xy 442.444046 -20.623234) (xy 442.456224 -20.649793) (xy 442.46546 -20.661122)
			(xy 442.48307 -20.682078) (xy 442.512787 -20.728043) (xy 442.53563 -20.777785) (xy 442.551127 -20.830281)
			(xy 442.558963 -20.884452) (xy 442.55944 -20.91182) (xy 442.558954 -20.939071) (xy 442.551198 -20.993019)
			(xy 442.535843 -21.045314) (xy 442.513201 -21.094891) (xy 442.483735 -21.140741) (xy 442.448044 -21.181932)
			(xy 442.406853 -21.217623) (xy 442.377981 -21.236178) (xy 448.479162 -21.236178) (xy 448.483233 -21.180556)
			(xy 448.495359 -21.126119) (xy 448.515282 -21.074028) (xy 448.542578 -21.025393) (xy 448.576664 -20.98125)
			(xy 448.616813 -20.942541) (xy 448.662171 -20.91009) (xy 448.711771 -20.884589) (xy 448.764555 -20.866582)
			(xy 448.819398 -20.856452) (xy 448.875132 -20.854415) (xy 448.930569 -20.860515) (xy 448.984526 -20.874621)
			(xy 449.035855 -20.896433) (xy 449.083461 -20.925487) (xy 449.126329 -20.961162) (xy 449.163546 -21.002699)
			(xy 449.194319 -21.049212) (xy 449.217991 -21.099709) (xy 449.234059 -21.153116) (xy 449.242179 -21.208292)
			(xy 449.242688 -21.236178) (xy 449.242179 -21.264064) (xy 449.234059 -21.31924) (xy 449.217991 -21.372647)
			(xy 449.194319 -21.423144) (xy 449.163546 -21.469657) (xy 449.126329 -21.511194) (xy 449.083461 -21.546869)
			(xy 449.035855 -21.575923) (xy 448.984526 -21.597735) (xy 448.930569 -21.611841) (xy 448.875132 -21.617941)
			(xy 448.819398 -21.615904) (xy 448.764555 -21.605774) (xy 448.711771 -21.587767) (xy 448.662171 -21.562266)
			(xy 448.616813 -21.529815) (xy 448.576664 -21.491106) (xy 448.542578 -21.446963) (xy 448.515282 -21.398328)
			(xy 448.495359 -21.346237) (xy 448.483233 -21.2918) (xy 448.479162 -21.236178) (xy 442.377981 -21.236178)
			(xy 442.361003 -21.247089) (xy 442.311426 -21.269731) (xy 442.259131 -21.285086) (xy 442.205183 -21.292842)
			(xy 442.150681 -21.292842) (xy 442.096733 -21.285086) (xy 442.044438 -21.269731) (xy 441.994861 -21.247089)
			(xy 441.949011 -21.217623) (xy 441.90782 -21.181932) (xy 441.872129 -21.140741) (xy 441.842663 -21.094891)
			(xy 441.820021 -21.045314) (xy 441.804666 -20.993019) (xy 441.79691 -20.939071) (xy 441.796424 -20.91182)
			(xy 440.759088 -20.91182) (xy 440.759088 -21.623528) (xy 453.717152 -21.623528) (xy 453.717637 -21.595899)
			(xy 453.725599 -21.541219) (xy 453.741363 -21.488258) (xy 453.764597 -21.438123) (xy 453.794816 -21.391861)
			(xy 453.83139 -21.35044) (xy 453.873553 -21.314725) (xy 453.89673 -21.299678) (xy 453.908805 -21.291585)
			(xy 453.928135 -21.269892) (xy 453.940583 -21.243638) (xy 453.945145 -21.214942) (xy 453.941451 -21.186121)
			(xy 453.9298 -21.159504) (xy 453.92086 -21.14804) (xy 453.90395 -21.127324) (xy 453.875493 -21.082051)
			(xy 453.85365 -21.033242) (xy 453.838851 -20.981856) (xy 453.831387 -20.928905) (xy 453.830944 -20.902168)
			(xy 453.83143 -20.874917) (xy 453.839186 -20.820969) (xy 453.854541 -20.768674) (xy 453.877183 -20.719097)
			(xy 453.906649 -20.673247) (xy 453.94234 -20.632056) (xy 453.983531 -20.596365) (xy 454.029381 -20.566899)
			(xy 454.078958 -20.544257) (xy 454.131253 -20.528902) (xy 454.185201 -20.521146) (xy 454.239703 -20.521146)
			(xy 454.293651 -20.528902) (xy 454.345946 -20.544257) (xy 454.395523 -20.566899) (xy 454.441373 -20.596365)
			(xy 454.482564 -20.632056) (xy 454.518255 -20.673247) (xy 454.547721 -20.719097) (xy 454.570363 -20.768674)
			(xy 454.585718 -20.820969) (xy 454.593474 -20.874917) (xy 454.59396 -20.902168) (xy 454.593513 -20.929798)
			(xy 454.585549 -20.984482) (xy 454.569782 -21.037446) (xy 454.546543 -21.087583) (xy 454.516317 -21.133844)
			(xy 454.479735 -21.175263) (xy 454.437563 -21.210974) (xy 454.414382 -21.226018) (xy 454.402311 -21.234117)
			(xy 454.382979 -21.255808) (xy 454.370529 -21.282061) (xy 454.365967 -21.310756) (xy 454.369661 -21.339576)
			(xy 454.381312 -21.366193) (xy 454.390252 -21.377656) (xy 454.407162 -21.398372) (xy 454.435619 -21.443645)
			(xy 454.457462 -21.492455) (xy 454.472261 -21.54384) (xy 454.479725 -21.596791) (xy 454.480168 -21.623528)
			(xy 454.479682 -21.650779) (xy 454.471926 -21.704727) (xy 454.456571 -21.757022) (xy 454.433929 -21.806599)
			(xy 454.404463 -21.852449) (xy 454.368772 -21.89364) (xy 454.327581 -21.929331) (xy 454.281731 -21.958797)
			(xy 454.232154 -21.981439) (xy 454.179859 -21.996794) (xy 454.125911 -22.00455) (xy 454.071409 -22.00455)
			(xy 454.017461 -21.996794) (xy 453.965166 -21.981439) (xy 453.915589 -21.958797) (xy 453.869739 -21.929331)
			(xy 453.828548 -21.89364) (xy 453.792857 -21.852449) (xy 453.763391 -21.806599) (xy 453.740749 -21.757022)
			(xy 453.725394 -21.704727) (xy 453.717638 -21.650779) (xy 453.717152 -21.623528) (xy 440.759088 -21.623528)
			(xy 440.759088 -22.426422) (xy 450.115176 -22.426422) (xy 450.119247 -22.3708) (xy 450.131373 -22.316363)
			(xy 450.151296 -22.264272) (xy 450.178592 -22.215637) (xy 450.212678 -22.171494) (xy 450.252827 -22.132785)
			(xy 450.298185 -22.100334) (xy 450.347785 -22.074833) (xy 450.400569 -22.056826) (xy 450.455412 -22.046696)
			(xy 450.511146 -22.044659) (xy 450.566583 -22.050759) (xy 450.62054 -22.064865) (xy 450.671869 -22.086677)
			(xy 450.719475 -22.115731) (xy 450.762343 -22.151406) (xy 450.79956 -22.192943) (xy 450.830333 -22.239456)
			(xy 450.854005 -22.289953) (xy 450.870073 -22.34336) (xy 450.878193 -22.398536) (xy 450.878234 -22.400768)
			(xy 452.115172 -22.400768) (xy 452.119243 -22.345146) (xy 452.131369 -22.290709) (xy 452.151292 -22.238618)
			(xy 452.178588 -22.189983) (xy 452.212674 -22.14584) (xy 452.252823 -22.107131) (xy 452.298181 -22.07468)
			(xy 452.347781 -22.049179) (xy 452.400565 -22.031172) (xy 452.455408 -22.021042) (xy 452.511142 -22.019005)
			(xy 452.566579 -22.025105) (xy 452.620536 -22.039211) (xy 452.671865 -22.061023) (xy 452.719471 -22.090077)
			(xy 452.762339 -22.125752) (xy 452.799556 -22.167289) (xy 452.830329 -22.213802) (xy 452.854001 -22.264299)
			(xy 452.870069 -22.317706) (xy 452.878189 -22.372882) (xy 452.878698 -22.400768) (xy 452.878189 -22.428654)
			(xy 452.870069 -22.48383) (xy 452.854001 -22.537237) (xy 452.830329 -22.587734) (xy 452.799556 -22.634247)
			(xy 452.762339 -22.675784) (xy 452.719471 -22.711459) (xy 452.671865 -22.740513) (xy 452.620536 -22.762325)
			(xy 452.566579 -22.776431) (xy 452.511142 -22.782531) (xy 452.455408 -22.780494) (xy 452.400565 -22.770364)
			(xy 452.347781 -22.752357) (xy 452.298181 -22.726856) (xy 452.252823 -22.694405) (xy 452.212674 -22.655696)
			(xy 452.178588 -22.611553) (xy 452.151292 -22.562918) (xy 452.131369 -22.510827) (xy 452.119243 -22.45639)
			(xy 452.115172 -22.400768) (xy 450.878234 -22.400768) (xy 450.878702 -22.426422) (xy 450.878193 -22.454308)
			(xy 450.870073 -22.509484) (xy 450.854005 -22.562891) (xy 450.830333 -22.613388) (xy 450.79956 -22.659901)
			(xy 450.762343 -22.701438) (xy 450.719475 -22.737113) (xy 450.671869 -22.766167) (xy 450.62054 -22.787979)
			(xy 450.566583 -22.802085) (xy 450.511146 -22.808185) (xy 450.455412 -22.806148) (xy 450.400569 -22.796018)
			(xy 450.347785 -22.778011) (xy 450.298185 -22.75251) (xy 450.252827 -22.720059) (xy 450.212678 -22.68135)
			(xy 450.178592 -22.637207) (xy 450.151296 -22.588572) (xy 450.131373 -22.536481) (xy 450.119247 -22.482044)
			(xy 450.115176 -22.426422) (xy 440.759088 -22.426422) (xy 440.759088 -22.866858) (xy 446.779394 -22.866858)
			(xy 446.783465 -22.811236) (xy 446.795591 -22.756799) (xy 446.815514 -22.704708) (xy 446.84281 -22.656073)
			(xy 446.876896 -22.61193) (xy 446.917045 -22.573221) (xy 446.962403 -22.54077) (xy 447.012003 -22.515269)
			(xy 447.064787 -22.497262) (xy 447.11963 -22.487132) (xy 447.175364 -22.485095) (xy 447.230801 -22.491195)
			(xy 447.284758 -22.505301) (xy 447.336087 -22.527113) (xy 447.383693 -22.556167) (xy 447.426561 -22.591842)
			(xy 447.463778 -22.633379) (xy 447.494551 -22.679892) (xy 447.518223 -22.730389) (xy 447.534291 -22.783796)
			(xy 447.542411 -22.838972) (xy 447.54292 -22.866858) (xy 447.542411 -22.894744) (xy 447.534291 -22.94992)
			(xy 447.518223 -23.003327) (xy 447.510755 -23.019258) (xy 451.351394 -23.019258) (xy 451.355465 -22.963636)
			(xy 451.367591 -22.909199) (xy 451.387514 -22.857108) (xy 451.41481 -22.808473) (xy 451.448896 -22.76433)
			(xy 451.489045 -22.725621) (xy 451.534403 -22.69317) (xy 451.584003 -22.667669) (xy 451.636787 -22.649662)
			(xy 451.69163 -22.639532) (xy 451.747364 -22.637495) (xy 451.802801 -22.643595) (xy 451.856758 -22.657701)
			(xy 451.908087 -22.679513) (xy 451.955693 -22.708567) (xy 451.998561 -22.744242) (xy 452.035778 -22.785779)
			(xy 452.066551 -22.832292) (xy 452.090223 -22.882789) (xy 452.106291 -22.936196) (xy 452.114411 -22.991372)
			(xy 452.11492 -23.019258) (xy 452.114411 -23.047144) (xy 452.106291 -23.10232) (xy 452.090223 -23.155727)
			(xy 452.066551 -23.206224) (xy 452.035778 -23.252737) (xy 451.998561 -23.294274) (xy 451.955693 -23.329949)
			(xy 451.908087 -23.359003) (xy 451.856758 -23.380815) (xy 451.802801 -23.394921) (xy 451.747364 -23.401021)
			(xy 451.69163 -23.398984) (xy 451.636787 -23.388854) (xy 451.584003 -23.370847) (xy 451.534403 -23.345346)
			(xy 451.489045 -23.312895) (xy 451.448896 -23.274186) (xy 451.41481 -23.230043) (xy 451.387514 -23.181408)
			(xy 451.367591 -23.129317) (xy 451.355465 -23.07488) (xy 451.351394 -23.019258) (xy 447.510755 -23.019258)
			(xy 447.494551 -23.053824) (xy 447.463778 -23.100337) (xy 447.426561 -23.141874) (xy 447.383693 -23.177549)
			(xy 447.336087 -23.206603) (xy 447.284758 -23.228415) (xy 447.230801 -23.242521) (xy 447.175364 -23.248621)
			(xy 447.11963 -23.246584) (xy 447.064787 -23.236454) (xy 447.012003 -23.218447) (xy 446.962403 -23.192946)
			(xy 446.917045 -23.160495) (xy 446.876896 -23.121786) (xy 446.84281 -23.077643) (xy 446.815514 -23.029008)
			(xy 446.795591 -22.976917) (xy 446.783465 -22.92248) (xy 446.779394 -22.866858) (xy 440.759088 -22.866858)
			(xy 440.759088 -25.46985) (xy 440.759527 -25.483552) (xy 440.766804 -25.509972) (xy 440.780846 -25.533505)
			(xy 440.800641 -25.552454) (xy 440.824764 -25.565456) (xy 440.851476 -25.571572) (xy 440.878853 -25.570363)
			(xy 440.904922 -25.561915) (xy 440.916568 -25.554686) (xy 440.93897 -25.540426) (xy 440.986909 -25.51758)
			(xy 441.037559 -25.501624) (xy 441.089936 -25.492867) (xy 441.116466 -25.491694) (xy 441.130163 -25.490833)
			(xy 441.156373 -25.482736) (xy 441.179482 -25.467954) (xy 441.197823 -25.447554) (xy 441.210071 -25.423007)
			(xy 441.215343 -25.396086) (xy 441.213258 -25.368733) (xy 441.203967 -25.342922) (xy 441.196476 -25.33142)
			(xy 441.17994 -25.307108) (xy 441.153744 -25.254473) (xy 441.135925 -25.198443) (xy 441.126906 -25.140345)
			(xy 441.126372 -25.110948) (xy 441.126858 -25.083697) (xy 441.134614 -25.029749) (xy 441.149969 -24.977454)
			(xy 441.172611 -24.927877) (xy 441.202077 -24.882027) (xy 441.237768 -24.840836) (xy 441.278959 -24.805145)
			(xy 441.324809 -24.775679) (xy 441.374386 -24.753037) (xy 441.426681 -24.737682) (xy 441.480629 -24.729926)
			(xy 441.535131 -24.729926) (xy 441.589079 -24.737682) (xy 441.641374 -24.753037) (xy 441.690951 -24.775679)
			(xy 441.736801 -24.805145) (xy 441.777992 -24.840836) (xy 441.813683 -24.882027) (xy 441.843149 -24.927877)
			(xy 441.865791 -24.977454) (xy 441.881146 -25.029749) (xy 441.888902 -25.083697) (xy 441.889388 -25.110948)
			(xy 441.888939 -25.137723) (xy 441.881453 -25.190748) (xy 441.866622 -25.242203) (xy 441.844737 -25.291077)
			(xy 441.816229 -25.336408) (xy 441.781658 -25.377304) (xy 441.741706 -25.412961) (xy 441.697157 -25.442677)
			(xy 441.648889 -25.465867) (xy 441.59785 -25.482076) (xy 441.545046 -25.490983) (xy 441.518294 -25.492202)
			(xy 441.504601 -25.493068) (xy 441.4784 -25.501171) (xy 441.4553 -25.515954) (xy 441.436967 -25.536352)
			(xy 441.424723 -25.560893) (xy 441.419452 -25.587808) (xy 441.421534 -25.615154) (xy 441.430818 -25.640961)
			(xy 441.438284 -25.652476) (xy 441.454822 -25.676787) (xy 441.481021 -25.729422) (xy 441.498842 -25.785451)
			(xy 441.507863 -25.84355) (xy 441.508388 -25.872948) (xy 441.634372 -25.872948) (xy 441.634911 -25.846179)
			(xy 441.642416 -25.793169) (xy 441.657258 -25.74173) (xy 441.679146 -25.69287) (xy 441.707649 -25.647549)
			(xy 441.742207 -25.606658) (xy 441.782142 -25.571) (xy 441.826671 -25.541275) (xy 441.874917 -25.518066)
			(xy 441.925934 -25.501829) (xy 441.97872 -25.492884) (xy 442.005466 -25.491694) (xy 442.019171 -25.490836)
			(xy 442.045404 -25.482755) (xy 442.068535 -25.467978) (xy 442.086895 -25.447573) (xy 442.099156 -25.423014)
			(xy 442.104431 -25.396077) (xy 442.10234 -25.368708) (xy 442.093034 -25.342885) (xy 442.085476 -25.33142)
			(xy 442.068919 -25.307123) (xy 442.042727 -25.254482) (xy 442.024917 -25.198448) (xy 442.01591 -25.140346)
			(xy 442.015372 -25.110948) (xy 442.015858 -25.083697) (xy 442.023614 -25.029749) (xy 442.038969 -24.977454)
			(xy 442.061611 -24.927877) (xy 442.091077 -24.882027) (xy 442.126768 -24.840836) (xy 442.167959 -24.805145)
			(xy 442.213809 -24.775679) (xy 442.263386 -24.753037) (xy 442.315681 -24.737682) (xy 442.369629 -24.729926)
			(xy 442.424131 -24.729926) (xy 442.478079 -24.737682) (xy 442.530374 -24.753037) (xy 442.579951 -24.775679)
			(xy 442.625801 -24.805145) (xy 442.666992 -24.840836) (xy 442.702683 -24.882027) (xy 442.732149 -24.927877)
			(xy 442.754791 -24.977454) (xy 442.770146 -25.029749) (xy 442.777902 -25.083697) (xy 442.778388 -25.110948)
			(xy 442.777884 -25.137719) (xy 442.770378 -25.190731) (xy 442.755535 -25.242174) (xy 442.733645 -25.291037)
			(xy 442.705139 -25.336359) (xy 442.670577 -25.377251) (xy 442.630637 -25.412909) (xy 442.586104 -25.442634)
			(xy 442.537854 -25.465841) (xy 442.486832 -25.482074) (xy 442.434042 -25.491014) (xy 442.407294 -25.492202)
			(xy 442.393588 -25.49304) (xy 442.367358 -25.501129) (xy 442.34423 -25.515911) (xy 442.325873 -25.536319)
			(xy 442.313614 -25.560878) (xy 442.308339 -25.587815) (xy 442.310427 -25.615185) (xy 442.319729 -25.64101)
			(xy 442.327284 -25.652476) (xy 442.343835 -25.676778) (xy 442.370029 -25.729416) (xy 442.387841 -25.785449)
			(xy 442.39685 -25.84355) (xy 442.397388 -25.872948) (xy 442.523372 -25.872948) (xy 442.523911 -25.846179)
			(xy 442.531416 -25.793169) (xy 442.546258 -25.74173) (xy 442.568146 -25.69287) (xy 442.596649 -25.647549)
			(xy 442.631207 -25.606658) (xy 442.671142 -25.571) (xy 442.715671 -25.541275) (xy 442.763917 -25.518066)
			(xy 442.814934 -25.501829) (xy 442.86772 -25.492884) (xy 442.894466 -25.491694) (xy 442.908171 -25.490836)
			(xy 442.934404 -25.482755) (xy 442.957535 -25.467978) (xy 442.975895 -25.447573) (xy 442.988156 -25.423014)
			(xy 442.993431 -25.396077) (xy 442.99134 -25.368708) (xy 442.982034 -25.342885) (xy 442.974476 -25.33142)
			(xy 442.957919 -25.307123) (xy 442.931727 -25.254482) (xy 442.913917 -25.198448) (xy 442.90491 -25.140346)
			(xy 442.904372 -25.110948) (xy 442.904858 -25.083697) (xy 442.912614 -25.029749) (xy 442.927969 -24.977454)
			(xy 442.950611 -24.927877) (xy 442.980077 -24.882027) (xy 443.015768 -24.840836) (xy 443.056959 -24.805145)
			(xy 443.102809 -24.775679) (xy 443.152386 -24.753037) (xy 443.204681 -24.737682) (xy 443.258629 -24.729926)
			(xy 443.313131 -24.729926) (xy 443.313284 -24.729948) (xy 443.792862 -24.729948) (xy 443.796933 -24.674326)
			(xy 443.809059 -24.619889) (xy 443.828982 -24.567798) (xy 443.856278 -24.519163) (xy 443.890364 -24.47502)
			(xy 443.930513 -24.436311) (xy 443.975871 -24.40386) (xy 444.025471 -24.378359) (xy 444.078255 -24.360352)
			(xy 444.133098 -24.350222) (xy 444.188832 -24.348185) (xy 444.244269 -24.354285) (xy 444.298226 -24.368391)
			(xy 444.349555 -24.390203) (xy 444.397161 -24.419257) (xy 444.440029 -24.454932) (xy 444.477246 -24.496469)
			(xy 444.508019 -24.542982) (xy 444.531691 -24.593479) (xy 444.547759 -24.646886) (xy 444.555879 -24.702062)
			(xy 444.556388 -24.729948) (xy 444.555879 -24.757834) (xy 444.547759 -24.81301) (xy 444.531691 -24.866417)
			(xy 444.52839 -24.873458) (xy 451.376794 -24.873458) (xy 451.380865 -24.817836) (xy 451.392991 -24.763399)
			(xy 451.412914 -24.711308) (xy 451.44021 -24.662673) (xy 451.474296 -24.61853) (xy 451.514445 -24.579821)
			(xy 451.559803 -24.54737) (xy 451.609403 -24.521869) (xy 451.662187 -24.503862) (xy 451.71703 -24.493732)
			(xy 451.772764 -24.491695) (xy 451.828201 -24.497795) (xy 451.882158 -24.511901) (xy 451.933487 -24.533713)
			(xy 451.981093 -24.562767) (xy 452.023961 -24.598442) (xy 452.061178 -24.639979) (xy 452.091951 -24.686492)
			(xy 452.115623 -24.736989) (xy 452.131691 -24.790396) (xy 452.139811 -24.845572) (xy 452.14032 -24.873458)
			(xy 452.139811 -24.901344) (xy 452.131691 -24.95652) (xy 452.115623 -25.009927) (xy 452.091951 -25.060424)
			(xy 452.061178 -25.106937) (xy 452.023961 -25.148474) (xy 451.981093 -25.184149) (xy 451.933487 -25.213203)
			(xy 451.882158 -25.235015) (xy 451.828201 -25.249121) (xy 451.772764 -25.255221) (xy 451.71703 -25.253184)
			(xy 451.662187 -25.243054) (xy 451.609403 -25.225047) (xy 451.559803 -25.199546) (xy 451.514445 -25.167095)
			(xy 451.474296 -25.128386) (xy 451.44021 -25.084243) (xy 451.412914 -25.035608) (xy 451.392991 -24.983517)
			(xy 451.380865 -24.92908) (xy 451.376794 -24.873458) (xy 444.52839 -24.873458) (xy 444.508019 -24.916914)
			(xy 444.477246 -24.963427) (xy 444.440029 -25.004964) (xy 444.397161 -25.040639) (xy 444.349555 -25.069693)
			(xy 444.298226 -25.091505) (xy 444.244269 -25.105611) (xy 444.188832 -25.111711) (xy 444.133098 -25.109674)
			(xy 444.078255 -25.099544) (xy 444.025471 -25.081537) (xy 443.975871 -25.056036) (xy 443.930513 -25.023585)
			(xy 443.890364 -24.984876) (xy 443.856278 -24.940733) (xy 443.828982 -24.892098) (xy 443.809059 -24.840007)
			(xy 443.796933 -24.78557) (xy 443.792862 -24.729948) (xy 443.313284 -24.729948) (xy 443.367079 -24.737682)
			(xy 443.419374 -24.753037) (xy 443.468951 -24.775679) (xy 443.514801 -24.805145) (xy 443.555992 -24.840836)
			(xy 443.591683 -24.882027) (xy 443.621149 -24.927877) (xy 443.643791 -24.977454) (xy 443.659146 -25.029749)
			(xy 443.666902 -25.083697) (xy 443.667388 -25.110948) (xy 443.666884 -25.137719) (xy 443.659378 -25.190731)
			(xy 443.644535 -25.242174) (xy 443.622645 -25.291037) (xy 443.594139 -25.336359) (xy 443.559577 -25.377251)
			(xy 443.519637 -25.412909) (xy 443.475104 -25.442634) (xy 443.426854 -25.465841) (xy 443.375832 -25.482074)
			(xy 443.323042 -25.491014) (xy 443.296294 -25.492202) (xy 443.282588 -25.49304) (xy 443.256358 -25.501129)
			(xy 443.23323 -25.515911) (xy 443.214873 -25.536319) (xy 443.202614 -25.560878) (xy 443.197339 -25.587815)
			(xy 443.199427 -25.615185) (xy 443.208729 -25.64101) (xy 443.216284 -25.652476) (xy 443.232835 -25.676778)
			(xy 443.259029 -25.729416) (xy 443.276841 -25.785449) (xy 443.28585 -25.84355) (xy 443.286388 -25.872948)
			(xy 443.285902 -25.900199) (xy 443.278146 -25.954147) (xy 443.262791 -26.006442) (xy 443.240149 -26.056019)
			(xy 443.210683 -26.101869) (xy 443.174992 -26.14306) (xy 443.133801 -26.178751) (xy 443.087951 -26.208217)
			(xy 443.038374 -26.230859) (xy 442.986079 -26.246214) (xy 442.932131 -26.25397) (xy 442.877629 -26.25397)
			(xy 442.823681 -26.246214) (xy 442.771386 -26.230859) (xy 442.721809 -26.208217) (xy 442.675959 -26.178751)
			(xy 442.634768 -26.14306) (xy 442.599077 -26.101869) (xy 442.569611 -26.056019) (xy 442.546969 -26.006442)
			(xy 442.531614 -25.954147) (xy 442.523858 -25.900199) (xy 442.523372 -25.872948) (xy 442.397388 -25.872948)
			(xy 442.396902 -25.900199) (xy 442.389146 -25.954147) (xy 442.373791 -26.006442) (xy 442.351149 -26.056019)
			(xy 442.321683 -26.101869) (xy 442.285992 -26.14306) (xy 442.244801 -26.178751) (xy 442.198951 -26.208217)
			(xy 442.149374 -26.230859) (xy 442.097079 -26.246214) (xy 442.043131 -26.25397) (xy 441.988629 -26.25397)
			(xy 441.934681 -26.246214) (xy 441.882386 -26.230859) (xy 441.832809 -26.208217) (xy 441.786959 -26.178751)
			(xy 441.745768 -26.14306) (xy 441.710077 -26.101869) (xy 441.680611 -26.056019) (xy 441.657969 -26.006442)
			(xy 441.642614 -25.954147) (xy 441.634858 -25.900199) (xy 441.634372 -25.872948) (xy 441.508388 -25.872948)
			(xy 441.507898 -25.900196) (xy 441.500136 -25.954138) (xy 441.484777 -26.006426) (xy 441.462133 -26.055995)
			(xy 441.432665 -26.101838) (xy 441.396973 -26.143021) (xy 441.355784 -26.178706) (xy 441.309936 -26.208165)
			(xy 441.260362 -26.230801) (xy 441.208071 -26.246151) (xy 441.154129 -26.253903) (xy 441.12688 -26.254456)
			(xy 441.099021 -26.253947) (xy 441.043898 -26.245836) (xy 440.990541 -26.22979) (xy 440.940087 -26.20615)
			(xy 440.916568 -26.19121) (xy 440.904885 -26.184054) (xy 440.878829 -26.17562) (xy 440.851468 -26.174416)
			(xy 440.824772 -26.180528) (xy 440.800661 -26.193516) (xy 440.780869 -26.212446) (xy 440.766821 -26.235955)
			(xy 440.759528 -26.262353) (xy 440.759088 -26.276046) (xy 440.759088 -26.983556) (xy 446.780313 -26.983556)
			(xy 446.780313 -26.929044) (xy 446.788071 -26.875086) (xy 446.803429 -26.822781) (xy 446.826075 -26.773195)
			(xy 446.855548 -26.727336) (xy 446.891247 -26.686138) (xy 446.932445 -26.650441) (xy 446.978305 -26.62097)
			(xy 447.027892 -26.598325) (xy 447.080197 -26.582969) (xy 447.134156 -26.575212) (xy 447.161412 -26.57475)
			(xy 447.18867 -26.575219) (xy 447.24263 -26.582987) (xy 447.294937 -26.598351) (xy 447.344526 -26.620998)
			(xy 447.390392 -26.650466) (xy 447.4316 -26.686158) (xy 447.467313 -26.727348) (xy 447.482468 -26.75001)
			(xy 447.490749 -26.761937) (xy 447.512685 -26.780941) (xy 447.539085 -26.792996) (xy 447.567812 -26.797126)
			(xy 447.596539 -26.792996) (xy 447.622939 -26.780941) (xy 447.644875 -26.761937) (xy 447.653156 -26.75001)
			(xy 447.668315 -26.727351) (xy 447.704021 -26.686155) (xy 447.745226 -26.650459) (xy 447.791091 -26.620989)
			(xy 447.840683 -26.598347) (xy 447.892992 -26.582991) (xy 447.946954 -26.575235) (xy 447.974212 -26.57475)
			(xy 448.00146 -26.575321) (xy 448.0554 -26.583078) (xy 448.107688 -26.598432) (xy 448.157258 -26.621072)
			(xy 448.203102 -26.650535) (xy 448.244286 -26.686223) (xy 448.279972 -26.727408) (xy 448.309434 -26.773253)
			(xy 448.332072 -26.822824) (xy 448.347425 -26.875112) (xy 448.35518 -26.929052) (xy 448.35518 -26.983548)
			(xy 448.347425 -27.037488) (xy 448.332072 -27.089776) (xy 448.309434 -27.139347) (xy 448.279972 -27.185192)
			(xy 448.244286 -27.226377) (xy 448.203102 -27.262065) (xy 448.157258 -27.291528) (xy 448.107688 -27.314168)
			(xy 448.0554 -27.329522) (xy 448.00146 -27.337279) (xy 447.974212 -27.337766) (xy 447.946955 -27.337272)
			(xy 447.892997 -27.329506) (xy 447.840691 -27.314147) (xy 447.791101 -27.291504) (xy 447.745236 -27.26204)
			(xy 447.704027 -27.226352) (xy 447.668312 -27.185166) (xy 447.653156 -27.162506) (xy 447.644875 -27.150579)
			(xy 447.622939 -27.131575) (xy 447.596539 -27.11952) (xy 447.567812 -27.11539) (xy 447.539085 -27.11952)
			(xy 447.512685 -27.131575) (xy 447.490749 -27.150579) (xy 447.482468 -27.162506) (xy 447.467298 -27.185158)
			(xy 447.431593 -27.226353) (xy 447.39039 -27.262049) (xy 447.344527 -27.291519) (xy 447.294937 -27.314163)
			(xy 447.24263 -27.329521) (xy 447.18867 -27.337279) (xy 447.161412 -27.337766) (xy 447.134156 -27.337388)
			(xy 447.080197 -27.329631) (xy 447.027892 -27.314275) (xy 446.978305 -27.29163) (xy 446.932445 -27.262159)
			(xy 446.891247 -27.226462) (xy 446.855548 -27.185264) (xy 446.826075 -27.139405) (xy 446.803429 -27.089819)
			(xy 446.788071 -27.037514) (xy 446.780313 -26.983556) (xy 440.759088 -26.983556) (xy 440.759088 -27.399996)
			(xy 440.75857 -27.424977) (xy 440.750707 -27.474317) (xy 440.735235 -27.521824) (xy 440.712535 -27.566333)
			(xy 440.683164 -27.606751) (xy 440.66587 -27.624786) (xy 439.797698 -28.492958) (xy 440.846972 -28.492958)
			(xy 440.847475 -28.465637) (xy 440.855819 -28.411635) (xy 440.872304 -28.359538) (xy 440.896546 -28.310567)
			(xy 440.927975 -28.265868) (xy 440.94654 -28.245816) (xy 440.956979 -28.234228) (xy 440.970801 -28.206283)
			(xy 440.975549 -28.17547) (xy 440.970782 -28.144659) (xy 440.956944 -28.116722) (xy 440.94654 -28.1051)
			(xy 440.927942 -28.085073) (xy 440.896482 -28.040385) (xy 440.872229 -27.991409) (xy 440.855754 -27.9393)
			(xy 440.847445 -27.885284) (xy 440.846972 -27.857958) (xy 440.84747 -27.831309) (xy 440.855413 -27.778605)
			(xy 440.871123 -27.727675) (xy 440.894249 -27.679654) (xy 440.924273 -27.635617) (xy 440.960525 -27.596546)
			(xy 441.002196 -27.563315) (xy 441.048354 -27.536666) (xy 441.097968 -27.517194) (xy 441.14993 -27.505334)
			(xy 441.20308 -27.501351) (xy 441.25623 -27.505334) (xy 441.308192 -27.517194) (xy 441.357806 -27.536666)
			(xy 441.403964 -27.563315) (xy 441.445635 -27.596546) (xy 441.481887 -27.635617) (xy 441.511911 -27.679654)
			(xy 441.535037 -27.727675) (xy 441.550747 -27.778605) (xy 441.55869 -27.831309) (xy 441.559188 -27.857958)
			(xy 441.558644 -27.885278) (xy 441.550312 -27.939278) (xy 441.533837 -27.991375) (xy 441.509604 -28.040347)
			(xy 441.478182 -28.085047) (xy 441.45962 -28.1051) (xy 441.449267 -28.116757) (xy 441.435442 -28.144679)
			(xy 441.43068 -28.17547) (xy 441.435424 -28.206263) (xy 441.449232 -28.234193) (xy 441.45962 -28.245816)
			(xy 441.478236 -28.265827) (xy 441.509691 -28.310521) (xy 441.533939 -28.3595) (xy 441.55041 -28.411612)
			(xy 441.558716 -28.465631) (xy 441.559188 -28.492958) (xy 441.746894 -28.492958) (xy 441.747391 -28.465636)
			(xy 441.755735 -28.411634) (xy 441.772222 -28.359537) (xy 441.796465 -28.310566) (xy 441.827896 -28.265868)
			(xy 441.846462 -28.245816) (xy 441.856899 -28.234227) (xy 441.870718 -28.206282) (xy 441.875465 -28.17547)
			(xy 441.8707 -28.14466) (xy 441.856864 -28.116723) (xy 441.846462 -28.1051) (xy 441.827868 -28.08507)
			(xy 441.796407 -28.040383) (xy 441.772153 -27.991408) (xy 441.755677 -27.9393) (xy 441.747368 -27.885284)
			(xy 441.746894 -27.857958) (xy 441.747392 -27.831309) (xy 441.755335 -27.778605) (xy 441.771045 -27.727675)
			(xy 441.794171 -27.679654) (xy 441.824195 -27.635617) (xy 441.860447 -27.596546) (xy 441.902118 -27.563315)
			(xy 441.948276 -27.536666) (xy 441.99789 -27.517194) (xy 442.049852 -27.505334) (xy 442.103002 -27.501351)
			(xy 442.156152 -27.505334) (xy 442.208114 -27.517194) (xy 442.257728 -27.536666) (xy 442.303886 -27.563315)
			(xy 442.345557 -27.596546) (xy 442.381809 -27.635617) (xy 442.411833 -27.679654) (xy 442.434959 -27.727675)
			(xy 442.450669 -27.778605) (xy 442.458612 -27.831309) (xy 442.45911 -27.857958) (xy 442.45856 -27.885278)
			(xy 442.450229 -27.939278) (xy 442.433754 -27.991374) (xy 442.409523 -28.040346) (xy 442.378102 -28.085047)
			(xy 442.359542 -28.1051) (xy 442.349187 -28.116756) (xy 442.335359 -28.144678) (xy 442.330596 -28.17547)
			(xy 442.335341 -28.206264) (xy 442.349152 -28.234194) (xy 442.359542 -28.245816) (xy 442.378144 -28.265839)
			(xy 442.409604 -28.310528) (xy 442.433857 -28.359504) (xy 442.450331 -28.411614) (xy 442.458638 -28.465631)
			(xy 442.45911 -28.492958) (xy 442.646816 -28.492958) (xy 442.647307 -28.465636) (xy 442.655652 -28.411633)
			(xy 442.672139 -28.359536) (xy 442.696384 -28.310565) (xy 442.727817 -28.265867) (xy 442.746384 -28.245816)
			(xy 442.756819 -28.234226) (xy 442.770635 -28.206281) (xy 442.775381 -28.17547) (xy 442.770617 -28.144661)
			(xy 442.756784 -28.116724) (xy 442.746384 -28.1051) (xy 442.727777 -28.085082) (xy 442.69632 -28.04039)
			(xy 442.67207 -27.991412) (xy 442.655597 -27.939302) (xy 442.647289 -27.885285) (xy 442.646816 -27.857958)
			(xy 442.647314 -27.831309) (xy 442.655257 -27.778605) (xy 442.670967 -27.727675) (xy 442.694093 -27.679654)
			(xy 442.724117 -27.635617) (xy 442.760369 -27.596546) (xy 442.80204 -27.563315) (xy 442.848198 -27.536666)
			(xy 442.897812 -27.517194) (xy 442.949774 -27.505334) (xy 443.002924 -27.501351) (xy 443.056074 -27.505334)
			(xy 443.108036 -27.517194) (xy 443.15765 -27.536666) (xy 443.203808 -27.563315) (xy 443.245479 -27.596546)
			(xy 443.281731 -27.635617) (xy 443.311755 -27.679654) (xy 443.334881 -27.727675) (xy 443.350591 -27.778605)
			(xy 443.358534 -27.831309) (xy 443.359032 -27.857958) (xy 443.358476 -27.885277) (xy 443.350145 -27.939277)
			(xy 443.333672 -27.991373) (xy 443.309442 -28.040345) (xy 443.278023 -28.085046) (xy 443.259464 -28.1051)
			(xy 443.249107 -28.116755) (xy 443.235276 -28.144677) (xy 443.230512 -28.17547) (xy 443.235258 -28.206265)
			(xy 443.249072 -28.234195) (xy 443.259464 -28.245816) (xy 443.27807 -28.265836) (xy 443.309529 -28.310526)
			(xy 443.33378 -28.359503) (xy 443.350253 -28.411614) (xy 443.35856 -28.465631) (xy 443.359032 -28.492958)
			(xy 443.546992 -28.492958) (xy 443.547489 -28.465636) (xy 443.555834 -28.411634) (xy 443.57232 -28.359537)
			(xy 443.596563 -28.310566) (xy 443.627995 -28.265868) (xy 443.64656 -28.245816) (xy 443.656998 -28.234228)
			(xy 443.670816 -28.206282) (xy 443.675564 -28.17547) (xy 443.670798 -28.14466) (xy 443.656963 -28.116723)
			(xy 443.64656 -28.1051) (xy 443.627966 -28.08507) (xy 443.596504 -28.040383) (xy 443.57225 -27.991408)
			(xy 443.555775 -27.9393) (xy 443.547466 -27.885284) (xy 443.546992 -27.857958) (xy 443.54749 -27.831309)
			(xy 443.555433 -27.778605) (xy 443.571143 -27.727675) (xy 443.594269 -27.679654) (xy 443.624293 -27.635617)
			(xy 443.660545 -27.596546) (xy 443.702216 -27.563315) (xy 443.748374 -27.536666) (xy 443.797988 -27.517194)
			(xy 443.84995 -27.505334) (xy 443.9031 -27.501351) (xy 443.95625 -27.505334) (xy 444.008212 -27.517194)
			(xy 444.057826 -27.536666) (xy 444.103984 -27.563315) (xy 444.145655 -27.596546) (xy 444.181907 -27.635617)
			(xy 444.211931 -27.679654) (xy 444.235057 -27.727675) (xy 444.250767 -27.778605) (xy 444.25871 -27.831309)
			(xy 444.259208 -27.857958) (xy 444.258659 -27.885278) (xy 444.250327 -27.939278) (xy 444.233853 -27.991374)
			(xy 444.209621 -28.040346) (xy 444.178201 -28.085047) (xy 444.15964 -28.1051) (xy 444.149285 -28.116756)
			(xy 444.135458 -28.144678) (xy 444.130695 -28.17547) (xy 444.134607 -28.200858) (xy 445.636904 -28.200858)
			(xy 445.637401 -28.172118) (xy 445.64603 -28.11529) (xy 445.663086 -28.060398) (xy 445.688184 -28.008687)
			(xy 445.720755 -27.961326) (xy 445.740028 -27.94) (xy 445.750145 -27.928501) (xy 445.763488 -27.900943)
			(xy 445.768067 -27.870669) (xy 445.76347 -27.840398) (xy 445.75011 -27.812849) (xy 445.740028 -27.801316)
			(xy 445.720736 -27.780008) (xy 445.688173 -27.73264) (xy 445.663085 -27.680924) (xy 445.646039 -27.626029)
			(xy 445.637422 -27.569198) (xy 445.636904 -27.540458) (xy 445.63739 -27.513207) (xy 445.645146 -27.459259)
			(xy 445.660501 -27.406964) (xy 445.683143 -27.357387) (xy 445.712609 -27.311537) (xy 445.7483 -27.270346)
			(xy 445.789491 -27.234655) (xy 445.835341 -27.205189) (xy 445.884918 -27.182547) (xy 445.937213 -27.167192)
			(xy 445.991161 -27.159436) (xy 446.045663 -27.159436) (xy 446.099611 -27.167192) (xy 446.151906 -27.182547)
			(xy 446.201483 -27.205189) (xy 446.247333 -27.234655) (xy 446.288524 -27.270346) (xy 446.324215 -27.311537)
			(xy 446.353681 -27.357387) (xy 446.376323 -27.406964) (xy 446.391678 -27.459259) (xy 446.399434 -27.513207)
			(xy 446.39992 -27.540458) (xy 446.399426 -27.569198) (xy 446.390795 -27.626026) (xy 446.373738 -27.680917)
			(xy 446.34864 -27.732628) (xy 446.316069 -27.77999) (xy 446.296796 -27.801316) (xy 446.286768 -27.812884)
			(xy 446.273426 -27.840419) (xy 446.268835 -27.870669) (xy 446.273408 -27.900922) (xy 446.286733 -27.928465)
			(xy 446.296796 -27.94) (xy 446.316083 -27.961313) (xy 446.348649 -28.008678) (xy 446.37374 -28.060393)
			(xy 446.390786 -28.115287) (xy 446.399403 -28.172118) (xy 446.39992 -28.200858) (xy 446.399434 -28.228109)
			(xy 446.391678 -28.282057) (xy 446.376323 -28.334352) (xy 446.353681 -28.383929) (xy 446.324215 -28.429779)
			(xy 446.288524 -28.47097) (xy 446.247333 -28.506661) (xy 446.201483 -28.536127) (xy 446.151906 -28.558769)
			(xy 446.099611 -28.574124) (xy 446.045663 -28.58188) (xy 445.991161 -28.58188) (xy 445.937213 -28.574124)
			(xy 445.884918 -28.558769) (xy 445.835341 -28.536127) (xy 445.789491 -28.506661) (xy 445.7483 -28.47097)
			(xy 445.712609 -28.429779) (xy 445.683143 -28.383929) (xy 445.660501 -28.334352) (xy 445.645146 -28.282057)
			(xy 445.63739 -28.228109) (xy 445.636904 -28.200858) (xy 444.134607 -28.200858) (xy 444.13544 -28.206264)
			(xy 444.14925 -28.234194) (xy 444.15964 -28.245816) (xy 444.178242 -28.265839) (xy 444.209702 -28.310528)
			(xy 444.233955 -28.359504) (xy 444.250428 -28.411614) (xy 444.258736 -28.465631) (xy 444.259208 -28.492958)
			(xy 444.25871 -28.519607) (xy 444.250767 -28.572311) (xy 444.235057 -28.623241) (xy 444.211931 -28.671262)
			(xy 444.181907 -28.715299) (xy 444.145655 -28.75437) (xy 444.103984 -28.787601) (xy 444.057826 -28.81425)
			(xy 444.008212 -28.833722) (xy 443.95625 -28.845582) (xy 443.9031 -28.849566) (xy 443.84995 -28.845582)
			(xy 443.797988 -28.833722) (xy 443.748374 -28.81425) (xy 443.702216 -28.787601) (xy 443.660545 -28.75437)
			(xy 443.624293 -28.715299) (xy 443.594269 -28.671262) (xy 443.571143 -28.623241) (xy 443.555433 -28.572311)
			(xy 443.54749 -28.519607) (xy 443.546992 -28.492958) (xy 443.359032 -28.492958) (xy 443.358534 -28.519607)
			(xy 443.350591 -28.572311) (xy 443.334881 -28.623241) (xy 443.311755 -28.671262) (xy 443.281731 -28.715299)
			(xy 443.245479 -28.75437) (xy 443.203808 -28.787601) (xy 443.15765 -28.81425) (xy 443.108036 -28.833722)
			(xy 443.056074 -28.845582) (xy 443.002924 -28.849566) (xy 442.949774 -28.845582) (xy 442.897812 -28.833722)
			(xy 442.848198 -28.81425) (xy 442.80204 -28.787601) (xy 442.760369 -28.75437) (xy 442.724117 -28.715299)
			(xy 442.694093 -28.671262) (xy 442.670967 -28.623241) (xy 442.655257 -28.572311) (xy 442.647314 -28.519607)
			(xy 442.646816 -28.492958) (xy 442.45911 -28.492958) (xy 442.458612 -28.519607) (xy 442.450669 -28.572311)
			(xy 442.434959 -28.623241) (xy 442.411833 -28.671262) (xy 442.381809 -28.715299) (xy 442.345557 -28.75437)
			(xy 442.303886 -28.787601) (xy 442.257728 -28.81425) (xy 442.208114 -28.833722) (xy 442.156152 -28.845582)
			(xy 442.103002 -28.849566) (xy 442.049852 -28.845582) (xy 441.99789 -28.833722) (xy 441.948276 -28.81425)
			(xy 441.902118 -28.787601) (xy 441.860447 -28.75437) (xy 441.824195 -28.715299) (xy 441.794171 -28.671262)
			(xy 441.771045 -28.623241) (xy 441.755335 -28.572311) (xy 441.747392 -28.519607) (xy 441.746894 -28.492958)
			(xy 441.559188 -28.492958) (xy 441.55869 -28.519607) (xy 441.550747 -28.572311) (xy 441.535037 -28.623241)
			(xy 441.511911 -28.671262) (xy 441.481887 -28.715299) (xy 441.445635 -28.75437) (xy 441.403964 -28.787601)
			(xy 441.357806 -28.81425) (xy 441.308192 -28.833722) (xy 441.25623 -28.845582) (xy 441.20308 -28.849566)
			(xy 441.14993 -28.845582) (xy 441.097968 -28.833722) (xy 441.048354 -28.81425) (xy 441.002196 -28.787601)
			(xy 440.960525 -28.75437) (xy 440.924273 -28.715299) (xy 440.894249 -28.671262) (xy 440.871123 -28.623241)
			(xy 440.855413 -28.572311) (xy 440.84747 -28.519607) (xy 440.846972 -28.492958) (xy 439.797698 -28.492958)
			(xy 439.540142 -28.750514) (xy 439.536586 -28.764484) (xy 439.52949 -28.791892) (xy 439.508304 -28.844394)
			(xy 439.483427 -28.886658) (xy 449.015104 -28.886658) (xy 449.015548 -28.860342) (xy 449.02277 -28.808207)
			(xy 449.037085 -28.757559) (xy 449.058221 -28.709357) (xy 449.085778 -28.664515) (xy 449.119233 -28.623884)
			(xy 449.138294 -28.605734) (xy 449.148357 -28.595962) (xy 449.163053 -28.572078) (xy 449.170686 -28.545093)
			(xy 449.170678 -28.51705) (xy 449.16303 -28.49007) (xy 449.148321 -28.466194) (xy 449.138294 -28.456382)
			(xy 449.119205 -28.438257) (xy 449.085728 -28.397635) (xy 449.058159 -28.352792) (xy 449.037022 -28.304583)
			(xy 449.02272 -28.253923) (xy 449.015523 -28.201778) (xy 449.015104 -28.175458) (xy 449.015608 -28.147885)
			(xy 449.023553 -28.093314) (xy 449.03927 -28.040454) (xy 449.062433 -27.990408) (xy 449.092559 -27.944218)
			(xy 449.12902 -27.902845) (xy 449.149724 -27.884628) (xy 449.160661 -27.874771) (xy 449.176728 -27.850108)
			(xy 449.185104 -27.82189) (xy 449.185096 -27.792456) (xy 449.176705 -27.764242) (xy 449.160625 -27.739588)
			(xy 449.149724 -27.729688) (xy 449.129009 -27.711481) (xy 449.092538 -27.670112) (xy 449.062405 -27.623922)
			(xy 449.03924 -27.573873) (xy 449.023525 -27.521009) (xy 449.015588 -27.466433) (xy 449.015104 -27.438858)
			(xy 449.01559 -27.411607) (xy 449.023346 -27.357659) (xy 449.038701 -27.305364) (xy 449.061343 -27.255787)
			(xy 449.090809 -27.209937) (xy 449.1265 -27.168746) (xy 449.167691 -27.133055) (xy 449.213541 -27.103589)
			(xy 449.263118 -27.080947) (xy 449.315413 -27.065592) (xy 449.369361 -27.057836) (xy 449.423863 -27.057836)
			(xy 449.477811 -27.065592) (xy 449.530106 -27.080947) (xy 449.579683 -27.103589) (xy 449.625533 -27.133055)
			(xy 449.666724 -27.168746) (xy 449.702415 -27.209937) (xy 449.731881 -27.255787) (xy 449.754523 -27.305364)
			(xy 449.769878 -27.357659) (xy 449.777634 -27.411607) (xy 449.77812 -27.438858) (xy 449.777618 -27.466431)
			(xy 449.769672 -27.521002) (xy 449.753954 -27.573861) (xy 449.73079 -27.623907) (xy 449.700665 -27.670098)
			(xy 449.664204 -27.711471) (xy 449.6435 -27.729688) (xy 449.632645 -27.739629) (xy 449.616572 -27.764268)
			(xy 449.608183 -27.792464) (xy 449.608176 -27.821882) (xy 449.616549 -27.850083) (xy 449.632609 -27.874729)
			(xy 449.6435 -27.884628) (xy 449.664228 -27.902821) (xy 449.700697 -27.944194) (xy 449.730827 -27.990387)
			(xy 449.75399 -28.040439) (xy 449.769703 -28.093305) (xy 449.777637 -28.147882) (xy 449.77812 -28.175458)
			(xy 449.777679 -28.201774) (xy 449.770455 -28.253909) (xy 449.75614 -28.304557) (xy 449.735003 -28.352759)
			(xy 449.707446 -28.3976) (xy 449.673991 -28.438232) (xy 449.65493 -28.456382) (xy 449.64495 -28.466233)
			(xy 449.630245 -28.490093) (xy 449.6226 -28.517058) (xy 449.622592 -28.545085) (xy 449.630222 -28.572054)
			(xy 449.644913 -28.595923) (xy 449.65493 -28.605734) (xy 449.674013 -28.623866) (xy 449.707493 -28.664485)
			(xy 449.735065 -28.709326) (xy 449.756203 -28.757534) (xy 449.770506 -28.808193) (xy 449.777701 -28.860338)
			(xy 449.77812 -28.886658) (xy 449.777634 -28.913909) (xy 449.774248 -28.937458) (xy 452.799704 -28.937458)
			(xy 452.800148 -28.911142) (xy 452.80737 -28.859007) (xy 452.821685 -28.808359) (xy 452.842821 -28.760157)
			(xy 452.870378 -28.715315) (xy 452.903833 -28.674684) (xy 452.922894 -28.656534) (xy 452.932957 -28.646762)
			(xy 452.947653 -28.622878) (xy 452.955286 -28.595893) (xy 452.955278 -28.56785) (xy 452.94763 -28.54087)
			(xy 452.932921 -28.516994) (xy 452.922894 -28.507182) (xy 452.903805 -28.489057) (xy 452.870328 -28.448435)
			(xy 452.842759 -28.403592) (xy 452.821622 -28.355383) (xy 452.80732 -28.304723) (xy 452.800123 -28.252578)
			(xy 452.799704 -28.226258) (xy 452.800208 -28.198685) (xy 452.808153 -28.144114) (xy 452.82387 -28.091254)
			(xy 452.847033 -28.041208) (xy 452.877159 -27.995018) (xy 452.91362 -27.953645) (xy 452.934324 -27.935428)
			(xy 452.945261 -27.925571) (xy 452.961328 -27.900908) (xy 452.969704 -27.87269) (xy 452.969696 -27.843256)
			(xy 452.961305 -27.815042) (xy 452.945225 -27.790388) (xy 452.934324 -27.780488) (xy 452.913609 -27.762281)
			(xy 452.877138 -27.720912) (xy 452.847005 -27.674722) (xy 452.82384 -27.624673) (xy 452.808125 -27.571809)
			(xy 452.800188 -27.517233) (xy 452.799704 -27.489658) (xy 452.80019 -27.462407) (xy 452.807946 -27.408459)
			(xy 452.823301 -27.356164) (xy 452.845943 -27.306587) (xy 452.875409 -27.260737) (xy 452.9111 -27.219546)
			(xy 452.952291 -27.183855) (xy 452.998141 -27.154389) (xy 453.047718 -27.131747) (xy 453.100013 -27.116392)
			(xy 453.153961 -27.108636) (xy 453.208463 -27.108636) (xy 453.262411 -27.116392) (xy 453.314706 -27.131747)
			(xy 453.364283 -27.154389) (xy 453.410133 -27.183855) (xy 453.451324 -27.219546) (xy 453.487015 -27.260737)
			(xy 453.516481 -27.306587) (xy 453.539123 -27.356164) (xy 453.554478 -27.408459) (xy 453.562234 -27.462407)
			(xy 453.56272 -27.489658) (xy 453.562218 -27.517231) (xy 453.554272 -27.571802) (xy 453.538554 -27.624661)
			(xy 453.51539 -27.674707) (xy 453.485265 -27.720898) (xy 453.448804 -27.762271) (xy 453.4281 -27.780488)
			(xy 453.417245 -27.790429) (xy 453.401172 -27.815068) (xy 453.392783 -27.843264) (xy 453.392776 -27.872682)
			(xy 453.401149 -27.900883) (xy 453.417209 -27.925529) (xy 453.4281 -27.935428) (xy 453.448828 -27.953621)
			(xy 453.485297 -27.994994) (xy 453.515427 -28.041187) (xy 453.53859 -28.091239) (xy 453.554303 -28.144105)
			(xy 453.562237 -28.198682) (xy 453.56272 -28.226258) (xy 453.562279 -28.252574) (xy 453.555055 -28.304709)
			(xy 453.54074 -28.355357) (xy 453.519603 -28.403559) (xy 453.492046 -28.4484) (xy 453.458591 -28.489032)
			(xy 453.43953 -28.507182) (xy 453.42955 -28.517033) (xy 453.414845 -28.540893) (xy 453.4072 -28.567858)
			(xy 453.407192 -28.595885) (xy 453.414822 -28.622854) (xy 453.429513 -28.646723) (xy 453.43953 -28.656534)
			(xy 453.458613 -28.674666) (xy 453.492093 -28.715285) (xy 453.519665 -28.760126) (xy 453.540803 -28.808334)
			(xy 453.555106 -28.858993) (xy 453.562301 -28.911138) (xy 453.56272 -28.937458) (xy 453.562234 -28.964709)
			(xy 453.554478 -29.018657) (xy 453.539123 -29.070952) (xy 453.516481 -29.120529) (xy 453.487015 -29.166379)
			(xy 453.451324 -29.20757) (xy 453.410133 -29.243261) (xy 453.364283 -29.272727) (xy 453.314706 -29.295369)
			(xy 453.262411 -29.310724) (xy 453.208463 -29.31848) (xy 453.153961 -29.31848) (xy 453.100013 -29.310724)
			(xy 453.047718 -29.295369) (xy 452.998141 -29.272727) (xy 452.952291 -29.243261) (xy 452.9111 -29.20757)
			(xy 452.875409 -29.166379) (xy 452.845943 -29.120529) (xy 452.823301 -29.070952) (xy 452.807946 -29.018657)
			(xy 452.80019 -28.964709) (xy 452.799704 -28.937458) (xy 449.774248 -28.937458) (xy 449.769878 -28.967857)
			(xy 449.754523 -29.020152) (xy 449.731881 -29.069729) (xy 449.702415 -29.115579) (xy 449.666724 -29.15677)
			(xy 449.625533 -29.192461) (xy 449.579683 -29.221927) (xy 449.530106 -29.244569) (xy 449.477811 -29.259924)
			(xy 449.423863 -29.26768) (xy 449.369361 -29.26768) (xy 449.315413 -29.259924) (xy 449.263118 -29.244569)
			(xy 449.213541 -29.221927) (xy 449.167691 -29.192461) (xy 449.1265 -29.15677) (xy 449.090809 -29.115579)
			(xy 449.061343 -29.069729) (xy 449.038701 -29.020152) (xy 449.023346 -28.967857) (xy 449.01559 -28.913909)
			(xy 449.015104 -28.886658) (xy 439.483427 -28.886658) (xy 439.479586 -28.893184) (xy 439.443967 -28.93719)
			(xy 439.402231 -28.975444) (xy 439.355295 -29.007103) (xy 439.304193 -29.031472) (xy 439.250049 -29.048014)
			(xy 439.194054 -29.056365) (xy 439.165746 -29.056838) (xy 439.13849 -29.056378) (xy 439.084533 -29.048627)
			(xy 439.032227 -29.033275) (xy 438.98264 -29.010636) (xy 438.936778 -28.981169) (xy 438.895578 -28.945476)
			(xy 438.859876 -28.904282) (xy 438.830401 -28.858427) (xy 438.807752 -28.808844) (xy 438.792389 -28.756542)
			(xy 438.784627 -28.702586) (xy 438.784238 -28.67533) (xy 438.784758 -28.647028) (xy 438.793133 -28.591047)
			(xy 438.809688 -28.536918) (xy 438.834061 -28.485829) (xy 438.865715 -28.438904) (xy 438.903956 -28.39717)
			(xy 438.947944 -28.361546) (xy 438.996714 -28.332814) (xy 439.049194 -28.311603) (xy 439.076592 -28.30449)
			(xy 439.090562 -28.300934) (xy 440.123072 -27.268424) (xy 440.123072 -20.771866) (xy 440.12255 -20.756891)
			(xy 440.113874 -20.728226) (xy 440.09725 -20.703314) (xy 440.07411 -20.684302) (xy 440.046446 -20.672826)
			(xy 440.016643 -20.669875) (xy 439.987266 -20.675704) (xy 439.960847 -20.68981) (xy 439.949844 -20.699984)
			(xy 436.96001 -23.689818) (xy 437.315354 -23.689818) (xy 437.319425 -23.634196) (xy 437.331551 -23.579759)
			(xy 437.351474 -23.527668) (xy 437.37877 -23.479033) (xy 437.412856 -23.43489) (xy 437.453005 -23.396181)
			(xy 437.498363 -23.36373) (xy 437.547963 -23.338229) (xy 437.600747 -23.320222) (xy 437.65559 -23.310092)
			(xy 437.711324 -23.308055) (xy 437.766761 -23.314155) (xy 437.820718 -23.328261) (xy 437.872047 -23.350073)
			(xy 437.919653 -23.379127) (xy 437.962521 -23.414802) (xy 437.999738 -23.456339) (xy 438.030511 -23.502852)
			(xy 438.054183 -23.553349) (xy 438.070251 -23.606756) (xy 438.078371 -23.661932) (xy 438.07888 -23.689818)
			(xy 438.078371 -23.717704) (xy 438.070251 -23.77288) (xy 438.054183 -23.826287) (xy 438.030511 -23.876784)
			(xy 437.999738 -23.923297) (xy 437.962521 -23.964834) (xy 437.919653 -24.000509) (xy 437.872047 -24.029563)
			(xy 437.820718 -24.051375) (xy 437.766761 -24.065481) (xy 437.711324 -24.071581) (xy 437.65559 -24.069544)
			(xy 437.600747 -24.059414) (xy 437.547963 -24.041407) (xy 437.498363 -24.015906) (xy 437.453005 -23.983455)
			(xy 437.412856 -23.944746) (xy 437.37877 -23.900603) (xy 437.351474 -23.851968) (xy 437.331551 -23.799877)
			(xy 437.319425 -23.74544) (xy 437.315354 -23.689818) (xy 436.96001 -23.689818) (xy 436.396384 -24.253444)
			(xy 435.746089 -25.823418) (xy 437.264554 -25.823418) (xy 437.268625 -25.767796) (xy 437.280751 -25.713359)
			(xy 437.300674 -25.661268) (xy 437.32797 -25.612633) (xy 437.362056 -25.56849) (xy 437.402205 -25.529781)
			(xy 437.447563 -25.49733) (xy 437.497163 -25.471829) (xy 437.549947 -25.453822) (xy 437.60479 -25.443692)
			(xy 437.660524 -25.441655) (xy 437.715961 -25.447755) (xy 437.769918 -25.461861) (xy 437.821247 -25.483673)
			(xy 437.868853 -25.512727) (xy 437.911721 -25.548402) (xy 437.948938 -25.589939) (xy 437.979711 -25.636452)
			(xy 438.003383 -25.686949) (xy 438.019451 -25.740356) (xy 438.027571 -25.795532) (xy 438.02808 -25.823418)
			(xy 438.027571 -25.851304) (xy 438.019451 -25.90648) (xy 438.003383 -25.959887) (xy 437.979711 -26.010384)
			(xy 437.948938 -26.056897) (xy 437.911721 -26.098434) (xy 437.868853 -26.134109) (xy 437.821247 -26.163163)
			(xy 437.769918 -26.184975) (xy 437.715961 -26.199081) (xy 437.660524 -26.205181) (xy 437.60479 -26.203144)
			(xy 437.549947 -26.193014) (xy 437.497163 -26.175007) (xy 437.447563 -26.149506) (xy 437.402205 -26.117055)
			(xy 437.362056 -26.078346) (xy 437.32797 -26.034203) (xy 437.300674 -25.985568) (xy 437.280751 -25.933477)
			(xy 437.268625 -25.87904) (xy 437.264554 -25.823418) (xy 435.746089 -25.823418) (xy 435.03088 -27.55011)
			(xy 435.03088 -28.0289) (xy 435.075584 -28.03398) (xy 435.103075 -28.037723) (xy 435.156651 -28.052132)
			(xy 435.207576 -28.074149) (xy 435.254775 -28.103309) (xy 435.297253 -28.138997) (xy 435.334115 -28.180462)
			(xy 435.364582 -28.226827) (xy 435.388013 -28.277117) (xy 435.403914 -28.33027) (xy 435.411948 -28.385165)
			(xy 435.411947 -28.440646) (xy 435.403911 -28.495541) (xy 435.388009 -28.548693) (xy 435.364577 -28.598982)
			(xy 435.334108 -28.645347) (xy 435.297245 -28.686811) (xy 435.254766 -28.722498) (xy 435.207566 -28.751656)
			(xy 435.156641 -28.773672) (xy 435.103064 -28.788079) (xy 435.075584 -28.791916) (xy 435.03088 -28.796996)
			(xy 435.03088 -29.55671) (xy 435.069742 -29.566108) (xy 435.097107 -29.573251) (xy 435.149513 -29.594511)
			(xy 435.198206 -29.623275) (xy 435.242119 -29.658913) (xy 435.280289 -29.700643) (xy 435.31188 -29.747552)
			(xy 435.336199 -29.79861) (xy 435.352714 -29.852699) (xy 435.361062 -29.908634) (xy 435.36106 -29.965188)
			(xy 435.352709 -30.021123) (xy 435.336191 -30.075211) (xy 435.311869 -30.126268) (xy 435.280275 -30.173175)
			(xy 435.242103 -30.214903) (xy 435.198188 -30.250538) (xy 435.149493 -30.279299) (xy 435.097085 -30.300555)
			(xy 435.069742 -30.307788) (xy 435.03088 -30.317186) (xy 435.03088 -32.761936) (xy 435.031369 -32.776604)
			(xy 435.039713 -32.804728) (xy 435.055704 -32.829324) (xy 435.078022 -32.848363) (xy 435.10483 -32.860277)
			(xy 435.133919 -32.864084) (xy 435.148482 -32.862266) (xy 435.163304 -32.860035) (xy 435.193184 -32.857615)
			(xy 435.208172 -32.85744) (xy 435.235425 -32.857901) (xy 435.289376 -32.865655) (xy 435.341675 -32.88101)
			(xy 435.391255 -32.903651) (xy 435.437109 -32.933119) (xy 435.478301 -32.968814) (xy 435.513993 -33.010007)
			(xy 435.543458 -33.055862) (xy 435.566097 -33.105444) (xy 435.581449 -33.157743) (xy 435.5892 -33.211695)
			(xy 435.58968 -33.238948) (xy 435.589227 -33.265488) (xy 435.581879 -33.318058) (xy 435.567317 -33.369102)
			(xy 435.545823 -33.417636) (xy 435.517812 -33.462724) (xy 435.483822 -33.503495) (xy 435.464458 -33.52165)
			(xy 435.45455 -33.531182) (xy 435.439786 -33.554361) (xy 435.431754 -33.580643) (xy 435.431041 -33.608115)
			(xy 435.437697 -33.634779) (xy 435.451238 -33.658693) (xy 435.460648 -33.668716) (xy 435.924198 -34.132266)
			(xy 435.960012 -34.097722) (xy 435.981469 -34.077926) (xy 436.029273 -34.044422) (xy 436.081619 -34.018585)
			(xy 436.137289 -34.001016) (xy 436.194984 -33.992126) (xy 436.224172 -33.99155) (xy 436.251426 -33.992034)
			(xy 436.305379 -33.999787) (xy 436.357679 -34.015139) (xy 436.407263 -34.037778) (xy 436.45312 -34.067243)
			(xy 436.494317 -34.102934) (xy 436.530015 -34.144124) (xy 436.559488 -34.189976) (xy 436.582136 -34.239555)
			(xy 436.597498 -34.291853) (xy 436.605261 -34.345804) (xy 436.60568 -34.373058) (xy 436.605129 -34.402248)
			(xy 436.596244 -34.459949) (xy 436.578677 -34.515624) (xy 436.552836 -34.567973) (xy 436.519324 -34.615778)
			(xy 436.499508 -34.637218) (xy 436.464964 -34.673032) (xy 436.80888 -35.016948)
		)
		(stroke
			(width 0)
			(type solid)
		)
		(fill yes)
		(layer "In4.Cu")
		(net "GND")
	)
	(gr_poly
		(pts
			(xy 185.438034 -117.770148) (xy 185.452771 -117.769662) (xy 185.481022 -117.761263) (xy 185.505698 -117.745146)
			(xy 185.524744 -117.722652) (xy 185.536572 -117.695657) (xy 185.540198 -117.666407) (xy 185.53532 -117.63734)
			(xy 185.522343 -117.610877) (xy 185.51271 -117.599714) (xy 185.496325 -117.581283) (xy 185.46864 -117.540473)
			(xy 185.447327 -117.496003) (xy 185.432858 -117.448859) (xy 185.425555 -117.400089) (xy 185.42508 -117.375432)
			(xy 185.42559 -117.349445) (xy 185.43372 -117.29811) (xy 185.449781 -117.24868) (xy 185.473377 -117.20237)
			(xy 185.503927 -117.160322) (xy 185.540678 -117.123571) (xy 185.582726 -117.093021) (xy 185.629036 -117.069425)
			(xy 185.678466 -117.053364) (xy 185.729801 -117.045234) (xy 185.781775 -117.045234) (xy 185.83311 -117.053364)
			(xy 185.88254 -117.069425) (xy 185.92885 -117.093021) (xy 185.970898 -117.123571) (xy 186.007649 -117.160322)
			(xy 186.038199 -117.20237) (xy 186.061795 -117.24868) (xy 186.077856 -117.29811) (xy 186.085986 -117.349445)
			(xy 186.086496 -117.375432) (xy 186.086039 -117.400089) (xy 186.078716 -117.448855) (xy 186.064236 -117.495995)
			(xy 186.042921 -117.540463) (xy 186.015243 -117.581276) (xy 185.998866 -117.599714) (xy 185.989241 -117.610885)
			(xy 185.97628 -117.637356) (xy 185.97141 -117.666424) (xy 185.975038 -117.695674) (xy 185.986861 -117.722673)
			(xy 186.005897 -117.745175) (xy 186.030562 -117.76131) (xy 186.058805 -117.769736) (xy 186.073542 -117.770148)
			(xy 187.33008 -117.770148) (xy 187.66028 -117.439948) (xy 187.66028 -116.957348) (xy 187.659756 -116.942363)
			(xy 187.651072 -116.91368) (xy 187.634439 -116.888751) (xy 187.611287 -116.869722) (xy 187.583609 -116.85823)
			(xy 187.553787 -116.855265) (xy 187.524388 -116.861081) (xy 187.510928 -116.867686) (xy 187.486892 -116.87986)
			(xy 187.435843 -116.897086) (xy 187.382673 -116.905784) (xy 187.355734 -116.906294) (xy 187.329744 -116.905813)
			(xy 187.278404 -116.897687) (xy 187.228967 -116.881628) (xy 187.182651 -116.858033) (xy 187.140596 -116.827483)
			(xy 187.103839 -116.79073) (xy 187.073285 -116.748678) (xy 187.049685 -116.702365) (xy 187.033621 -116.65293)
			(xy 187.025489 -116.60159) (xy 187.025489 -116.54961) (xy 187.033621 -116.49827) (xy 187.049685 -116.448835)
			(xy 187.073285 -116.402522) (xy 187.103839 -116.36047) (xy 187.140596 -116.323717) (xy 187.182651 -116.293167)
			(xy 187.228967 -116.269572) (xy 187.278404 -116.253513) (xy 187.329744 -116.245387) (xy 187.355734 -116.244878)
			(xy 187.382669 -116.245414) (xy 187.435829 -116.25414) (xy 187.48688 -116.271342) (xy 187.510928 -116.283486)
			(xy 187.524401 -116.290062) (xy 187.553796 -116.295872) (xy 187.583614 -116.292906) (xy 187.611289 -116.281419)
			(xy 187.634442 -116.262399) (xy 187.651084 -116.23748) (xy 187.659782 -116.208806) (xy 187.66028 -116.193824)
			(xy 187.66028 -112.957102) (xy 187.65975 -112.942122) (xy 187.651059 -112.913451) (xy 187.634424 -112.888535)
			(xy 187.611276 -112.869515) (xy 187.583606 -112.858029) (xy 187.553794 -112.855064) (xy 187.524404 -112.860876)
			(xy 187.510928 -112.86744) (xy 187.486892 -112.879616) (xy 187.435843 -112.896843) (xy 187.382673 -112.905543)
			(xy 187.355734 -112.906048) (xy 187.32974 -112.905567) (xy 187.278391 -112.897439) (xy 187.228946 -112.881378)
			(xy 187.182622 -112.857779) (xy 187.140561 -112.827224) (xy 187.103798 -112.790465) (xy 187.073238 -112.748407)
			(xy 187.049635 -112.702086) (xy 187.033569 -112.652642) (xy 187.025435 -112.601294) (xy 187.025435 -112.549306)
			(xy 187.033569 -112.497958) (xy 187.049635 -112.448514) (xy 187.073238 -112.402193) (xy 187.103798 -112.360135)
			(xy 187.140561 -112.323376) (xy 187.182622 -112.292821) (xy 187.228946 -112.269222) (xy 187.278391 -112.253161)
			(xy 187.32974 -112.245033) (xy 187.355734 -112.244632) (xy 187.382669 -112.245168) (xy 187.435829 -112.253893)
			(xy 187.486881 -112.271092) (xy 187.510928 -112.28324) (xy 187.524398 -112.289817) (xy 187.553791 -112.295631)
			(xy 187.583606 -112.292666) (xy 187.611278 -112.281178) (xy 187.634427 -112.262155) (xy 187.65106 -112.237234)
			(xy 187.659747 -112.208559) (xy 187.66028 -112.193578) (xy 187.66028 -108.157264) (xy 187.659745 -108.142289)
			(xy 187.651048 -108.113628) (xy 187.634412 -108.088721) (xy 187.611267 -108.06971) (xy 187.583604 -108.058229)
			(xy 187.5538 -108.055264) (xy 187.524417 -108.061071) (xy 187.510928 -108.067602) (xy 187.486893 -108.079779)
			(xy 187.435844 -108.097009) (xy 187.382673 -108.105709) (xy 187.355734 -108.10621) (xy 187.329743 -108.105729)
			(xy 187.2784 -108.097602) (xy 187.22896 -108.081543) (xy 187.182642 -108.057947) (xy 187.140586 -108.027395)
			(xy 187.103827 -107.99064) (xy 187.073271 -107.948587) (xy 187.04967 -107.902271) (xy 187.033606 -107.852833)
			(xy 187.025473 -107.801491) (xy 187.025473 -107.749509) (xy 187.033606 -107.698167) (xy 187.04967 -107.648729)
			(xy 187.073271 -107.602413) (xy 187.103827 -107.56036) (xy 187.140586 -107.523605) (xy 187.182642 -107.493053)
			(xy 187.22896 -107.469457) (xy 187.2784 -107.453398) (xy 187.329743 -107.445271) (xy 187.355734 -107.444794)
			(xy 187.382669 -107.44533) (xy 187.435829 -107.454057) (xy 187.486879 -107.471259) (xy 187.510928 -107.483402)
			(xy 187.524401 -107.489977) (xy 187.553798 -107.495786) (xy 187.583616 -107.49282) (xy 187.611292 -107.481334)
			(xy 187.634448 -107.462314) (xy 187.651092 -107.437396) (xy 187.659794 -107.408722) (xy 187.66028 -107.39374)
			(xy 187.66028 -104.957118) (xy 187.659752 -104.942137) (xy 187.651063 -104.913461) (xy 187.634429 -104.88854)
			(xy 187.61128 -104.869517) (xy 187.583607 -104.858029) (xy 187.553791 -104.855064) (xy 187.524398 -104.860878)
			(xy 187.510928 -104.867456) (xy 187.486892 -104.879631) (xy 187.435843 -104.896858) (xy 187.382673 -104.905557)
			(xy 187.355734 -104.906064) (xy 187.328832 -104.90554) (xy 187.275736 -104.896837) (xy 187.224749 -104.879655)
			(xy 187.177215 -104.854447) (xy 187.134387 -104.821879) (xy 187.097396 -104.782807) (xy 187.067216 -104.738264)
			(xy 187.055506 -104.71404) (xy 187.049271 -104.701672) (xy 187.031321 -104.680593) (xy 187.008367 -104.665114)
			(xy 186.982097 -104.656372) (xy 186.954444 -104.655011) (xy 186.927443 -104.661131) (xy 186.915044 -104.667304)
			(xy 186.888906 -104.680769) (xy 186.83328 -104.699808) (xy 186.775278 -104.709424) (xy 186.74588 -104.709976)
			(xy 186.719234 -104.709477) (xy 186.666538 -104.701531) (xy 186.615614 -104.685821) (xy 186.567601 -104.662696)
			(xy 186.52357 -104.632674) (xy 186.484506 -104.596426) (xy 186.45128 -104.55476) (xy 186.424635 -104.508607)
			(xy 186.405166 -104.458999) (xy 186.393307 -104.407043) (xy 186.389325 -104.3539) (xy 186.393307 -104.300757)
			(xy 186.405166 -104.248801) (xy 186.424635 -104.199193) (xy 186.45128 -104.15304) (xy 186.484506 -104.111374)
			(xy 186.52357 -104.075126) (xy 186.567601 -104.045104) (xy 186.615614 -104.021979) (xy 186.666538 -104.006269)
			(xy 186.719234 -103.998323) (xy 186.74588 -103.99776) (xy 186.772407 -103.998255) (xy 186.824871 -104.00614)
			(xy 186.875585 -104.021722) (xy 186.923425 -104.044657) (xy 186.967332 -104.074437) (xy 187.006334 -104.110403)
			(xy 187.039568 -104.151759) (xy 187.066296 -104.197588) (xy 187.076588 -104.222042) (xy 187.082143 -104.234759)
			(xy 187.09894 -104.256835) (xy 187.121056 -104.273578) (xy 187.14686 -104.283756) (xy 187.174451 -104.286618)
			(xy 187.201795 -104.281953) (xy 187.21451 -104.276398) (xy 187.23669 -104.266381) (xy 187.28326 -104.252246)
			(xy 187.3314 -104.245104) (xy 187.355734 -104.244648) (xy 187.382669 -104.245184) (xy 187.435829 -104.253909)
			(xy 187.486881 -104.27111) (xy 187.510928 -104.283256) (xy 187.524399 -104.289832) (xy 187.553793 -104.295645)
			(xy 187.583609 -104.29268) (xy 187.611282 -104.281192) (xy 187.634432 -104.26217) (xy 187.651068 -104.23725)
			(xy 187.659759 -104.208575) (xy 187.66028 -104.193594) (xy 187.66028 -101.209348) (xy 187.518294 -101.067616)
			(xy 186.23534 -101.067616) (xy 186.209517 -101.067165) (xy 186.158382 -101.059921) (xy 186.108757 -101.045613)
			(xy 186.061615 -101.02452) (xy 186.017878 -100.997055) (xy 185.99785 -100.980748) (xy 185.17108 -100.980748)
			(xy 184.96788 -101.183948) (xy 184.96788 -105.401443) (xy 185.42559 -105.401443) (xy 185.42559 -105.349469)
			(xy 185.43372 -105.298134) (xy 185.449781 -105.248704) (xy 185.473377 -105.202394) (xy 185.503927 -105.160346)
			(xy 185.540678 -105.123595) (xy 185.582726 -105.093045) (xy 185.629036 -105.069449) (xy 185.678466 -105.053388)
			(xy 185.729801 -105.045258) (xy 185.781775 -105.045258) (xy 185.83311 -105.053388) (xy 185.88254 -105.069449)
			(xy 185.92885 -105.093045) (xy 185.970898 -105.123595) (xy 186.007649 -105.160346) (xy 186.038199 -105.202394)
			(xy 186.061795 -105.248704) (xy 186.077856 -105.298134) (xy 186.085986 -105.349469) (xy 186.086496 -105.375456)
			(xy 186.085986 -105.401443) (xy 186.077856 -105.452778) (xy 186.061795 -105.502208) (xy 186.038199 -105.548518)
			(xy 186.007649 -105.590566) (xy 185.970898 -105.627317) (xy 185.92885 -105.657867) (xy 185.88254 -105.681463)
			(xy 185.83311 -105.697524) (xy 185.781775 -105.705654) (xy 185.729801 -105.705654) (xy 185.678466 -105.697524)
			(xy 185.629036 -105.681463) (xy 185.582726 -105.657867) (xy 185.540678 -105.627317) (xy 185.503927 -105.590566)
			(xy 185.473377 -105.548518) (xy 185.449781 -105.502208) (xy 185.43372 -105.452778) (xy 185.42559 -105.401443)
			(xy 184.96788 -105.401443) (xy 184.96788 -105.842054) (xy 185.010298 -105.849166) (xy 185.035685 -105.85392)
			(xy 185.084677 -105.870263) (xy 185.130533 -105.894024) (xy 185.172137 -105.924625) (xy 185.208478 -105.961322)
			(xy 185.238671 -106.003223) (xy 185.261983 -106.049309) (xy 185.277846 -106.098459) (xy 185.285876 -106.149477)
			(xy 185.285876 -106.201123) (xy 185.28585 -106.201289) (xy 185.42559 -106.201289) (xy 185.42559 -106.149315)
			(xy 185.43372 -106.09798) (xy 185.449781 -106.04855) (xy 185.473377 -106.00224) (xy 185.503927 -105.960192)
			(xy 185.540678 -105.923441) (xy 185.582726 -105.892891) (xy 185.629036 -105.869295) (xy 185.678466 -105.853234)
			(xy 185.729801 -105.845104) (xy 185.781775 -105.845104) (xy 185.83311 -105.853234) (xy 185.88254 -105.869295)
			(xy 185.92885 -105.892891) (xy 185.970898 -105.923441) (xy 186.007649 -105.960192) (xy 186.038199 -106.00224)
			(xy 186.061795 -106.04855) (xy 186.077856 -106.09798) (xy 186.085986 -106.149315) (xy 186.086496 -106.175302)
			(xy 186.085986 -106.201289) (xy 186.225436 -106.201289) (xy 186.225436 -106.149315) (xy 186.233566 -106.09798)
			(xy 186.249627 -106.04855) (xy 186.273223 -106.00224) (xy 186.303773 -105.960192) (xy 186.340524 -105.923441)
			(xy 186.382572 -105.892891) (xy 186.428882 -105.869295) (xy 186.478312 -105.853234) (xy 186.529647 -105.845104)
			(xy 186.581621 -105.845104) (xy 186.632956 -105.853234) (xy 186.682386 -105.869295) (xy 186.728696 -105.892891)
			(xy 186.770744 -105.923441) (xy 186.807495 -105.960192) (xy 186.838045 -106.00224) (xy 186.861641 -106.04855)
			(xy 186.877702 -106.09798) (xy 186.885832 -106.149315) (xy 186.886342 -106.175302) (xy 186.885832 -106.201289)
			(xy 186.877702 -106.252624) (xy 186.861641 -106.302054) (xy 186.838045 -106.348364) (xy 186.807495 -106.390412)
			(xy 186.770744 -106.427163) (xy 186.728696 -106.457713) (xy 186.682386 -106.481309) (xy 186.632956 -106.49737)
			(xy 186.581621 -106.5055) (xy 186.529647 -106.5055) (xy 186.478312 -106.49737) (xy 186.428882 -106.481309)
			(xy 186.382572 -106.457713) (xy 186.340524 -106.427163) (xy 186.303773 -106.390412) (xy 186.273223 -106.348364)
			(xy 186.249627 -106.302054) (xy 186.233566 -106.252624) (xy 186.225436 -106.201289) (xy 186.085986 -106.201289)
			(xy 186.077856 -106.252624) (xy 186.061795 -106.302054) (xy 186.038199 -106.348364) (xy 186.007649 -106.390412)
			(xy 185.970898 -106.427163) (xy 185.92885 -106.457713) (xy 185.88254 -106.481309) (xy 185.83311 -106.49737)
			(xy 185.781775 -106.5055) (xy 185.729801 -106.5055) (xy 185.678466 -106.49737) (xy 185.629036 -106.481309)
			(xy 185.582726 -106.457713) (xy 185.540678 -106.427163) (xy 185.503927 -106.390412) (xy 185.473377 -106.348364)
			(xy 185.449781 -106.302054) (xy 185.43372 -106.252624) (xy 185.42559 -106.201289) (xy 185.28585 -106.201289)
			(xy 185.277846 -106.252142) (xy 185.261983 -106.301291) (xy 185.238671 -106.347377) (xy 185.208477 -106.389278)
			(xy 185.172136 -106.425975) (xy 185.130532 -106.456577) (xy 185.084676 -106.480338) (xy 185.035684 -106.49668)
			(xy 185.010298 -106.501438) (xy 184.96788 -106.50855) (xy 184.96788 -106.642154) (xy 185.010298 -106.649266)
			(xy 185.035688 -106.654019) (xy 185.084688 -106.67036) (xy 185.130551 -106.694119) (xy 185.172165 -106.724719)
			(xy 185.208516 -106.761415) (xy 185.238721 -106.803315) (xy 185.262045 -106.849402) (xy 185.277923 -106.898553)
			(xy 185.285967 -106.949576) (xy 185.286396 -106.975402) (xy 185.285913 -107.001389) (xy 185.42559 -107.001389)
			(xy 185.42559 -106.949415) (xy 185.43372 -106.89808) (xy 185.449781 -106.84865) (xy 185.473377 -106.80234)
			(xy 185.503927 -106.760292) (xy 185.540678 -106.723541) (xy 185.582726 -106.692991) (xy 185.629036 -106.669395)
			(xy 185.678466 -106.653334) (xy 185.729801 -106.645204) (xy 185.781775 -106.645204) (xy 185.83311 -106.653334)
			(xy 185.88254 -106.669395) (xy 185.92885 -106.692991) (xy 185.970898 -106.723541) (xy 186.007649 -106.760292)
			(xy 186.038199 -106.80234) (xy 186.061795 -106.84865) (xy 186.077856 -106.89808) (xy 186.085986 -106.949415)
			(xy 186.086496 -106.975402) (xy 186.085986 -107.001389) (xy 186.225436 -107.001389) (xy 186.225436 -106.949415)
			(xy 186.233566 -106.89808) (xy 186.249627 -106.84865) (xy 186.273223 -106.80234) (xy 186.303773 -106.760292)
			(xy 186.340524 -106.723541) (xy 186.382572 -106.692991) (xy 186.428882 -106.669395) (xy 186.478312 -106.653334)
			(xy 186.529647 -106.645204) (xy 186.581621 -106.645204) (xy 186.632956 -106.653334) (xy 186.682386 -106.669395)
			(xy 186.728696 -106.692991) (xy 186.770744 -106.723541) (xy 186.807495 -106.760292) (xy 186.838045 -106.80234)
			(xy 186.861641 -106.84865) (xy 186.877702 -106.89808) (xy 186.885832 -106.949415) (xy 186.886342 -106.975402)
			(xy 186.885832 -107.001389) (xy 186.877702 -107.052724) (xy 186.861641 -107.102154) (xy 186.838045 -107.148464)
			(xy 186.807495 -107.190512) (xy 186.770744 -107.227263) (xy 186.728696 -107.257813) (xy 186.682386 -107.281409)
			(xy 186.632956 -107.29747) (xy 186.581621 -107.3056) (xy 186.529647 -107.3056) (xy 186.478312 -107.29747)
			(xy 186.428882 -107.281409) (xy 186.382572 -107.257813) (xy 186.340524 -107.227263) (xy 186.303773 -107.190512)
			(xy 186.273223 -107.148464) (xy 186.249627 -107.102154) (xy 186.233566 -107.052724) (xy 186.225436 -107.001389)
			(xy 186.085986 -107.001389) (xy 186.077856 -107.052724) (xy 186.061795 -107.102154) (xy 186.038199 -107.148464)
			(xy 186.007649 -107.190512) (xy 185.970898 -107.227263) (xy 185.92885 -107.257813) (xy 185.88254 -107.281409)
			(xy 185.83311 -107.29747) (xy 185.781775 -107.3056) (xy 185.729801 -107.3056) (xy 185.678466 -107.29747)
			(xy 185.629036 -107.281409) (xy 185.582726 -107.257813) (xy 185.540678 -107.227263) (xy 185.503927 -107.190512)
			(xy 185.473377 -107.148464) (xy 185.449781 -107.102154) (xy 185.43372 -107.052724) (xy 185.42559 -107.001389)
			(xy 185.285913 -107.001389) (xy 185.285913 -107.001391) (xy 185.277781 -107.052728) (xy 185.261719 -107.102162)
			(xy 185.238121 -107.148474) (xy 185.207568 -107.190524) (xy 185.170814 -107.227277) (xy 185.128762 -107.257828)
			(xy 185.082449 -107.281424) (xy 185.033015 -107.297484) (xy 184.981677 -107.305614) (xy 184.955688 -107.30611)
			(xy 184.940194 -107.305856) (xy 184.917842 -107.304586) (xy 184.823608 -107.39882) (xy 184.877964 -107.452922)
			(xy 184.903618 -107.448858) (xy 184.916549 -107.446933) (xy 184.942615 -107.444902) (xy 184.955688 -107.444794)
			(xy 184.981677 -107.445276) (xy 185.033016 -107.453406) (xy 185.082451 -107.469466) (xy 185.128765 -107.493062)
			(xy 185.170818 -107.523613) (xy 185.207573 -107.560366) (xy 185.238127 -107.602417) (xy 185.261726 -107.64873)
			(xy 185.27779 -107.698164) (xy 185.285922 -107.749502) (xy 185.285924 -107.801481) (xy 185.285923 -107.801489)
			(xy 185.42559 -107.801489) (xy 185.42559 -107.749515) (xy 185.43372 -107.69818) (xy 185.449781 -107.64875)
			(xy 185.473377 -107.60244) (xy 185.503927 -107.560392) (xy 185.540678 -107.523641) (xy 185.582726 -107.493091)
			(xy 185.629036 -107.469495) (xy 185.678466 -107.453434) (xy 185.729801 -107.445304) (xy 185.781775 -107.445304)
			(xy 185.83311 -107.453434) (xy 185.88254 -107.469495) (xy 185.92885 -107.493091) (xy 185.970898 -107.523641)
			(xy 186.007649 -107.560392) (xy 186.038199 -107.60244) (xy 186.061795 -107.64875) (xy 186.077856 -107.69818)
			(xy 186.085986 -107.749515) (xy 186.086496 -107.775502) (xy 186.085986 -107.801489) (xy 186.225436 -107.801489)
			(xy 186.225436 -107.749515) (xy 186.233566 -107.69818) (xy 186.249627 -107.64875) (xy 186.273223 -107.60244)
			(xy 186.303773 -107.560392) (xy 186.340524 -107.523641) (xy 186.382572 -107.493091) (xy 186.428882 -107.469495)
			(xy 186.478312 -107.453434) (xy 186.529647 -107.445304) (xy 186.581621 -107.445304) (xy 186.632956 -107.453434)
			(xy 186.682386 -107.469495) (xy 186.728696 -107.493091) (xy 186.770744 -107.523641) (xy 186.807495 -107.560392)
			(xy 186.838045 -107.60244) (xy 186.861641 -107.64875) (xy 186.877702 -107.69818) (xy 186.885832 -107.749515)
			(xy 186.886342 -107.775502) (xy 186.885832 -107.801489) (xy 186.877702 -107.852824) (xy 186.861641 -107.902254)
			(xy 186.838045 -107.948564) (xy 186.807495 -107.990612) (xy 186.770744 -108.027363) (xy 186.728696 -108.057913)
			(xy 186.682386 -108.081509) (xy 186.632956 -108.09757) (xy 186.581621 -108.1057) (xy 186.529647 -108.1057)
			(xy 186.478312 -108.09757) (xy 186.428882 -108.081509) (xy 186.382572 -108.057913) (xy 186.340524 -108.027363)
			(xy 186.303773 -107.990612) (xy 186.273223 -107.948564) (xy 186.249627 -107.902254) (xy 186.233566 -107.852824)
			(xy 186.225436 -107.801489) (xy 186.085986 -107.801489) (xy 186.077856 -107.852824) (xy 186.061795 -107.902254)
			(xy 186.038199 -107.948564) (xy 186.007649 -107.990612) (xy 185.970898 -108.027363) (xy 185.92885 -108.057913)
			(xy 185.88254 -108.081509) (xy 185.83311 -108.09757) (xy 185.781775 -108.1057) (xy 185.729801 -108.1057)
			(xy 185.678466 -108.09757) (xy 185.629036 -108.081509) (xy 185.582726 -108.057913) (xy 185.540678 -108.027363)
			(xy 185.503927 -107.990612) (xy 185.473377 -107.948564) (xy 185.449781 -107.902254) (xy 185.43372 -107.852824)
			(xy 185.42559 -107.801489) (xy 185.285923 -107.801489) (xy 185.277794 -107.852819) (xy 185.261733 -107.902254)
			(xy 185.238136 -107.948568) (xy 185.207585 -107.99062) (xy 185.170831 -108.027375) (xy 185.12878 -108.057929)
			(xy 185.082467 -108.081527) (xy 185.033033 -108.09759) (xy 184.981695 -108.105722) (xy 184.929716 -108.105723)
			(xy 184.878377 -108.097593) (xy 184.828943 -108.081531) (xy 184.782629 -108.057934) (xy 184.740577 -108.027382)
			(xy 184.703822 -107.990628) (xy 184.67327 -107.948577) (xy 184.649672 -107.902264) (xy 184.633609 -107.85283)
			(xy 184.625477 -107.801491) (xy 184.62498 -107.775502) (xy 184.625103 -107.76243) (xy 184.627138 -107.736365)
			(xy 184.629044 -107.723432) (xy 184.633108 -107.697778) (xy 184.579006 -107.643422) (xy 184.484772 -107.737656)
			(xy 184.486042 -107.760008) (xy 184.486296 -107.775502) (xy 184.485813 -107.801491) (xy 184.477681 -107.852828)
			(xy 184.461619 -107.902262) (xy 184.438021 -107.948574) (xy 184.407468 -107.990624) (xy 184.370714 -108.027377)
			(xy 184.328662 -108.057928) (xy 184.282349 -108.081524) (xy 184.232915 -108.097584) (xy 184.181577 -108.105714)
			(xy 184.155588 -108.10621) (xy 184.140094 -108.105956) (xy 184.117742 -108.104686) (xy 184.023762 -108.198666)
			(xy 184.078118 -108.252768) (xy 184.103772 -108.248704) (xy 184.116642 -108.246803) (xy 184.142579 -108.244769)
			(xy 184.155588 -108.24464) (xy 184.181571 -108.245149) (xy 184.232897 -108.253276) (xy 184.28232 -108.269332)
			(xy 184.328623 -108.292922) (xy 184.370665 -108.323464) (xy 184.407412 -108.360207) (xy 184.437959 -108.402247)
			(xy 184.461554 -108.448547) (xy 184.477616 -108.497968) (xy 184.485748 -108.549293) (xy 184.485752 -108.601259)
			(xy 184.48574 -108.601335) (xy 184.62549 -108.601335) (xy 184.62549 -108.549361) (xy 184.63362 -108.498026)
			(xy 184.649681 -108.448596) (xy 184.673277 -108.402286) (xy 184.703827 -108.360238) (xy 184.740578 -108.323487)
			(xy 184.782626 -108.292937) (xy 184.828936 -108.269341) (xy 184.878366 -108.25328) (xy 184.929701 -108.24515)
			(xy 184.981675 -108.24515) (xy 185.03301 -108.25328) (xy 185.08244 -108.269341) (xy 185.12875 -108.292937)
			(xy 185.170798 -108.323487) (xy 185.207549 -108.360238) (xy 185.238099 -108.402286) (xy 185.261695 -108.448596)
			(xy 185.277756 -108.498026) (xy 185.285886 -108.549361) (xy 185.286396 -108.575348) (xy 185.285886 -108.601335)
			(xy 185.42559 -108.601335) (xy 185.42559 -108.549361) (xy 185.43372 -108.498026) (xy 185.449781 -108.448596)
			(xy 185.473377 -108.402286) (xy 185.503927 -108.360238) (xy 185.540678 -108.323487) (xy 185.582726 -108.292937)
			(xy 185.629036 -108.269341) (xy 185.678466 -108.25328) (xy 185.729801 -108.24515) (xy 185.781775 -108.24515)
			(xy 185.83311 -108.25328) (xy 185.88254 -108.269341) (xy 185.92885 -108.292937) (xy 185.970898 -108.323487)
			(xy 186.007649 -108.360238) (xy 186.038199 -108.402286) (xy 186.061795 -108.448596) (xy 186.077856 -108.498026)
			(xy 186.085986 -108.549361) (xy 186.086496 -108.575348) (xy 186.085986 -108.601335) (xy 186.077856 -108.65267)
			(xy 186.061795 -108.7021) (xy 186.038199 -108.74841) (xy 186.007649 -108.790458) (xy 185.970898 -108.827209)
			(xy 185.92885 -108.857759) (xy 185.88254 -108.881355) (xy 185.83311 -108.897416) (xy 185.781775 -108.905546)
			(xy 185.729801 -108.905546) (xy 185.678466 -108.897416) (xy 185.629036 -108.881355) (xy 185.582726 -108.857759)
			(xy 185.540678 -108.827209) (xy 185.503927 -108.790458) (xy 185.473377 -108.74841) (xy 185.449781 -108.7021)
			(xy 185.43372 -108.65267) (xy 185.42559 -108.601335) (xy 185.285886 -108.601335) (xy 185.277756 -108.65267)
			(xy 185.261695 -108.7021) (xy 185.238099 -108.74841) (xy 185.207549 -108.790458) (xy 185.170798 -108.827209)
			(xy 185.12875 -108.857759) (xy 185.08244 -108.881355) (xy 185.03301 -108.897416) (xy 184.981675 -108.905546)
			(xy 184.929701 -108.905546) (xy 184.878366 -108.897416) (xy 184.828936 -108.881355) (xy 184.782626 -108.857759)
			(xy 184.740578 -108.827209) (xy 184.703827 -108.790458) (xy 184.673277 -108.74841) (xy 184.649681 -108.7021)
			(xy 184.63362 -108.65267) (xy 184.62549 -108.601335) (xy 184.48574 -108.601335) (xy 184.477627 -108.652585)
			(xy 184.461572 -108.702009) (xy 184.437984 -108.748312) (xy 184.407444 -108.790356) (xy 184.370702 -108.827105)
			(xy 184.328664 -108.857653) (xy 184.282364 -108.881249) (xy 184.232944 -108.897313) (xy 184.181619 -108.905447)
			(xy 184.129653 -108.905453) (xy 184.078326 -108.89733) (xy 184.028902 -108.881277) (xy 183.982598 -108.857691)
			(xy 183.940553 -108.827151) (xy 183.903803 -108.790411) (xy 183.873253 -108.748374) (xy 183.849655 -108.702075)
			(xy 183.83359 -108.652655) (xy 183.825454 -108.601331) (xy 183.82488 -108.575348) (xy 183.824995 -108.562339)
			(xy 183.827031 -108.5364) (xy 183.828944 -108.523532) (xy 183.833008 -108.497878) (xy 183.778906 -108.443522)
			(xy 183.684926 -108.537502) (xy 183.686196 -108.559854) (xy 183.68645 -108.575348) (xy 183.685937 -108.601334)
			(xy 183.677801 -108.652665) (xy 183.661736 -108.702092) (xy 183.638138 -108.748398) (xy 183.607588 -108.790443)
			(xy 183.570838 -108.827192) (xy 183.528793 -108.857741) (xy 183.482486 -108.881338) (xy 183.433059 -108.897402)
			(xy 183.381728 -108.905537) (xy 183.355742 -108.906056) (xy 183.340248 -108.905802) (xy 183.317896 -108.904532)
			(xy 183.223662 -108.998766) (xy 183.278018 -109.052868) (xy 183.303672 -109.048804) (xy 183.316603 -109.046877)
			(xy 183.342669 -109.044842) (xy 183.355742 -109.04474) (xy 183.381724 -109.045253) (xy 183.433047 -109.053388)
			(xy 183.482466 -109.069451) (xy 183.528763 -109.093047) (xy 183.5708 -109.123594) (xy 183.607541 -109.160341)
			(xy 183.638081 -109.202383) (xy 183.66167 -109.248684) (xy 183.677725 -109.298106) (xy 183.685851 -109.34943)
			(xy 183.685849 -109.401394) (xy 183.685843 -109.401435) (xy 183.82539 -109.401435) (xy 183.82539 -109.349461)
			(xy 183.83352 -109.298126) (xy 183.849581 -109.248696) (xy 183.873177 -109.202386) (xy 183.903727 -109.160338)
			(xy 183.940478 -109.123587) (xy 183.982526 -109.093037) (xy 184.028836 -109.069441) (xy 184.078266 -109.05338)
			(xy 184.129601 -109.04525) (xy 184.181575 -109.04525) (xy 184.23291 -109.05338) (xy 184.28234 -109.069441)
			(xy 184.32865 -109.093037) (xy 184.370698 -109.123587) (xy 184.407449 -109.160338) (xy 184.437999 -109.202386)
			(xy 184.461595 -109.248696) (xy 184.477656 -109.298126) (xy 184.485786 -109.349461) (xy 184.486296 -109.375448)
			(xy 184.485786 -109.401435) (xy 185.42559 -109.401435) (xy 185.42559 -109.349461) (xy 185.43372 -109.298126)
			(xy 185.449781 -109.248696) (xy 185.473377 -109.202386) (xy 185.503927 -109.160338) (xy 185.540678 -109.123587)
			(xy 185.582726 -109.093037) (xy 185.629036 -109.069441) (xy 185.678466 -109.05338) (xy 185.729801 -109.04525)
			(xy 185.781775 -109.04525) (xy 185.83311 -109.05338) (xy 185.88254 -109.069441) (xy 185.92885 -109.093037)
			(xy 185.970898 -109.123587) (xy 186.007649 -109.160338) (xy 186.038199 -109.202386) (xy 186.061795 -109.248696)
			(xy 186.077856 -109.298126) (xy 186.085986 -109.349461) (xy 186.086496 -109.375448) (xy 186.085986 -109.401435)
			(xy 186.077856 -109.45277) (xy 186.061795 -109.5022) (xy 186.038199 -109.54851) (xy 186.007649 -109.590558)
			(xy 185.970898 -109.627309) (xy 185.92885 -109.657859) (xy 185.88254 -109.681455) (xy 185.83311 -109.697516)
			(xy 185.781775 -109.705646) (xy 185.729801 -109.705646) (xy 185.678466 -109.697516) (xy 185.629036 -109.681455)
			(xy 185.582726 -109.657859) (xy 185.540678 -109.627309) (xy 185.503927 -109.590558) (xy 185.473377 -109.54851)
			(xy 185.449781 -109.5022) (xy 185.43372 -109.45277) (xy 185.42559 -109.401435) (xy 184.485786 -109.401435)
			(xy 184.477656 -109.45277) (xy 184.461595 -109.5022) (xy 184.437999 -109.54851) (xy 184.407449 -109.590558)
			(xy 184.370698 -109.627309) (xy 184.32865 -109.657859) (xy 184.28234 -109.681455) (xy 184.23291 -109.697516)
			(xy 184.181575 -109.705646) (xy 184.129601 -109.705646) (xy 184.078266 -109.697516) (xy 184.028836 -109.681455)
			(xy 183.982526 -109.657859) (xy 183.940478 -109.627309) (xy 183.903727 -109.590558) (xy 183.873177 -109.54851)
			(xy 183.849581 -109.5022) (xy 183.83352 -109.45277) (xy 183.82539 -109.401435) (xy 183.685843 -109.401435)
			(xy 183.677719 -109.452718) (xy 183.66166 -109.502138) (xy 183.638069 -109.548438) (xy 183.607525 -109.590477)
			(xy 183.570782 -109.627221) (xy 183.528743 -109.657766) (xy 183.482443 -109.681358) (xy 183.433023 -109.697418)
			(xy 183.3817 -109.705549) (xy 183.329736 -109.705552) (xy 183.278412 -109.697426) (xy 183.22899 -109.681372)
			(xy 183.182688 -109.657785) (xy 183.140646 -109.627245) (xy 183.103898 -109.590505) (xy 183.07335 -109.548468)
			(xy 183.049753 -109.502171) (xy 183.033689 -109.452753) (xy 183.025554 -109.40143) (xy 183.025034 -109.375448)
			(xy 183.025155 -109.362376) (xy 183.027186 -109.33631) (xy 183.029098 -109.323378) (xy 183.033162 -109.297724)
			(xy 182.97906 -109.243368) (xy 182.884826 -109.337602) (xy 182.886096 -109.359954) (xy 182.88635 -109.375448)
			(xy 182.885837 -109.401434) (xy 182.877701 -109.452765) (xy 182.861636 -109.502192) (xy 182.838038 -109.548498)
			(xy 182.807488 -109.590543) (xy 182.770738 -109.627292) (xy 182.728693 -109.657841) (xy 182.682386 -109.681438)
			(xy 182.632959 -109.697502) (xy 182.581628 -109.705637) (xy 182.555642 -109.706156) (xy 182.540148 -109.705902)
			(xy 182.517796 -109.704632) (xy 182.423816 -109.798612) (xy 182.478172 -109.852714) (xy 182.503826 -109.84865)
			(xy 182.516696 -109.846748) (xy 182.542633 -109.84471) (xy 182.555642 -109.844586) (xy 182.581629 -109.845099)
			(xy 182.632962 -109.853236) (xy 182.682391 -109.869302) (xy 182.728697 -109.892904) (xy 182.770742 -109.923458)
			(xy 182.807489 -109.960213) (xy 182.838034 -110.002264) (xy 182.861625 -110.048576) (xy 182.877681 -110.098008)
			(xy 182.885807 -110.149343) (xy 182.885802 -110.201281) (xy 183.025544 -110.201281) (xy 183.025544 -110.149307)
			(xy 183.033674 -110.097972) (xy 183.049735 -110.048542) (xy 183.073331 -110.002232) (xy 183.103881 -109.960184)
			(xy 183.140632 -109.923433) (xy 183.18268 -109.892883) (xy 183.22899 -109.869287) (xy 183.27842 -109.853226)
			(xy 183.329755 -109.845096) (xy 183.381729 -109.845096) (xy 183.433064 -109.853226) (xy 183.482494 -109.869287)
			(xy 183.528804 -109.892883) (xy 183.570852 -109.923433) (xy 183.607603 -109.960184) (xy 183.638153 -110.002232)
			(xy 183.661749 -110.048542) (xy 183.67781 -110.097972) (xy 183.68594 -110.149307) (xy 183.68645 -110.175294)
			(xy 183.68594 -110.201281) (xy 183.82539 -110.201281) (xy 183.82539 -110.149307) (xy 183.83352 -110.097972)
			(xy 183.849581 -110.048542) (xy 183.873177 -110.002232) (xy 183.903727 -109.960184) (xy 183.940478 -109.923433)
			(xy 183.982526 -109.892883) (xy 184.028836 -109.869287) (xy 184.078266 -109.853226) (xy 184.129601 -109.845096)
			(xy 184.181575 -109.845096) (xy 184.23291 -109.853226) (xy 184.28234 -109.869287) (xy 184.32865 -109.892883)
			(xy 184.370698 -109.923433) (xy 184.407449 -109.960184) (xy 184.437999 -110.002232) (xy 184.461595 -110.048542)
			(xy 184.477656 -110.097972) (xy 184.485786 -110.149307) (xy 184.486296 -110.175294) (xy 184.485786 -110.201281)
			(xy 184.62549 -110.201281) (xy 184.62549 -110.149307) (xy 184.63362 -110.097972) (xy 184.649681 -110.048542)
			(xy 184.673277 -110.002232) (xy 184.703827 -109.960184) (xy 184.740578 -109.923433) (xy 184.782626 -109.892883)
			(xy 184.828936 -109.869287) (xy 184.878366 -109.853226) (xy 184.929701 -109.845096) (xy 184.981675 -109.845096)
			(xy 185.03301 -109.853226) (xy 185.08244 -109.869287) (xy 185.12875 -109.892883) (xy 185.170798 -109.923433)
			(xy 185.207549 -109.960184) (xy 185.238099 -110.002232) (xy 185.261695 -110.048542) (xy 185.277756 -110.097972)
			(xy 185.285886 -110.149307) (xy 185.286396 -110.175294) (xy 185.285886 -110.201281) (xy 185.42559 -110.201281)
			(xy 185.42559 -110.149307) (xy 185.43372 -110.097972) (xy 185.449781 -110.048542) (xy 185.473377 -110.002232)
			(xy 185.503927 -109.960184) (xy 185.540678 -109.923433) (xy 185.582726 -109.892883) (xy 185.629036 -109.869287)
			(xy 185.678466 -109.853226) (xy 185.729801 -109.845096) (xy 185.781775 -109.845096) (xy 185.83311 -109.853226)
			(xy 185.88254 -109.869287) (xy 185.92885 -109.892883) (xy 185.970898 -109.923433) (xy 186.007649 -109.960184)
			(xy 186.038199 -110.002232) (xy 186.061795 -110.048542) (xy 186.077856 -110.097972) (xy 186.085986 -110.149307)
			(xy 186.086496 -110.175294) (xy 186.085986 -110.201281) (xy 186.077856 -110.252616) (xy 186.061795 -110.302046)
			(xy 186.038199 -110.348356) (xy 186.007649 -110.390404) (xy 185.970898 -110.427155) (xy 185.92885 -110.457705)
			(xy 185.88254 -110.481301) (xy 185.83311 -110.497362) (xy 185.781775 -110.505492) (xy 185.729801 -110.505492)
			(xy 185.678466 -110.497362) (xy 185.629036 -110.481301) (xy 185.582726 -110.457705) (xy 185.540678 -110.427155)
			(xy 185.503927 -110.390404) (xy 185.473377 -110.348356) (xy 185.449781 -110.302046) (xy 185.43372 -110.252616)
			(xy 185.42559 -110.201281) (xy 185.285886 -110.201281) (xy 185.277756 -110.252616) (xy 185.261695 -110.302046)
			(xy 185.238099 -110.348356) (xy 185.207549 -110.390404) (xy 185.170798 -110.427155) (xy 185.12875 -110.457705)
			(xy 185.08244 -110.481301) (xy 185.03301 -110.497362) (xy 184.981675 -110.505492) (xy 184.929701 -110.505492)
			(xy 184.878366 -110.497362) (xy 184.828936 -110.481301) (xy 184.782626 -110.457705) (xy 184.740578 -110.427155)
			(xy 184.703827 -110.390404) (xy 184.673277 -110.348356) (xy 184.649681 -110.302046) (xy 184.63362 -110.252616)
			(xy 184.62549 -110.201281) (xy 184.485786 -110.201281) (xy 184.477656 -110.252616) (xy 184.461595 -110.302046)
			(xy 184.437999 -110.348356) (xy 184.407449 -110.390404) (xy 184.370698 -110.427155) (xy 184.32865 -110.457705)
			(xy 184.28234 -110.481301) (xy 184.23291 -110.497362) (xy 184.181575 -110.505492) (xy 184.129601 -110.505492)
			(xy 184.078266 -110.497362) (xy 184.028836 -110.481301) (xy 183.982526 -110.457705) (xy 183.940478 -110.427155)
			(xy 183.903727 -110.390404) (xy 183.873177 -110.348356) (xy 183.849581 -110.302046) (xy 183.83352 -110.252616)
			(xy 183.82539 -110.201281) (xy 183.68594 -110.201281) (xy 183.67781 -110.252616) (xy 183.661749 -110.302046)
			(xy 183.638153 -110.348356) (xy 183.607603 -110.390404) (xy 183.570852 -110.427155) (xy 183.528804 -110.457705)
			(xy 183.482494 -110.481301) (xy 183.433064 -110.497362) (xy 183.381729 -110.505492) (xy 183.329755 -110.505492)
			(xy 183.27842 -110.497362) (xy 183.22899 -110.481301) (xy 183.18268 -110.457705) (xy 183.140632 -110.427155)
			(xy 183.103881 -110.390404) (xy 183.073331 -110.348356) (xy 183.049735 -110.302046) (xy 183.033674 -110.252616)
			(xy 183.025544 -110.201281) (xy 182.885802 -110.201281) (xy 182.885802 -110.201317) (xy 182.877667 -110.252651)
			(xy 182.861602 -110.302079) (xy 182.838003 -110.348387) (xy 182.80745 -110.390432) (xy 182.770696 -110.427181)
			(xy 182.728646 -110.457728) (xy 182.682335 -110.481321) (xy 182.632904 -110.497378) (xy 182.581569 -110.505506)
			(xy 182.529595 -110.505503) (xy 182.478261 -110.49737) (xy 182.428832 -110.481307) (xy 182.382523 -110.457709)
			(xy 182.340477 -110.427158) (xy 182.303727 -110.390405) (xy 182.273178 -110.348356) (xy 182.249584 -110.302046)
			(xy 182.233524 -110.252615) (xy 182.225395 -110.201281) (xy 182.224934 -110.175294) (xy 182.225047 -110.162285)
			(xy 182.227079 -110.136346) (xy 182.228998 -110.123478) (xy 182.233062 -110.097824) (xy 182.17896 -110.043468)
			(xy 182.08498 -110.137448) (xy 182.08625 -110.1598) (xy 182.086504 -110.175294) (xy 182.086021 -110.201283)
			(xy 182.077891 -110.252623) (xy 182.061829 -110.302058) (xy 182.038232 -110.348371) (xy 182.007679 -110.390423)
			(xy 181.970925 -110.427178) (xy 181.928873 -110.45773) (xy 181.882559 -110.481328) (xy 181.833124 -110.49739)
			(xy 181.781785 -110.505521) (xy 181.755796 -110.506002) (xy 181.740302 -110.505748) (xy 181.71795 -110.504478)
			(xy 181.41188 -110.810548) (xy 181.41188 -111.001381) (xy 182.225444 -111.001381) (xy 182.225444 -110.949407)
			(xy 182.233574 -110.898072) (xy 182.249635 -110.848642) (xy 182.273231 -110.802332) (xy 182.303781 -110.760284)
			(xy 182.340532 -110.723533) (xy 182.38258 -110.692983) (xy 182.42889 -110.669387) (xy 182.47832 -110.653326)
			(xy 182.529655 -110.645196) (xy 182.581629 -110.645196) (xy 182.632964 -110.653326) (xy 182.682394 -110.669387)
			(xy 182.728704 -110.692983) (xy 182.770752 -110.723533) (xy 182.807503 -110.760284) (xy 182.838053 -110.802332)
			(xy 182.861649 -110.848642) (xy 182.87771 -110.898072) (xy 182.88584 -110.949407) (xy 182.88635 -110.975394)
			(xy 182.88584 -111.001381) (xy 183.025544 -111.001381) (xy 183.025544 -110.949407) (xy 183.033674 -110.898072)
			(xy 183.049735 -110.848642) (xy 183.073331 -110.802332) (xy 183.103881 -110.760284) (xy 183.140632 -110.723533)
			(xy 183.18268 -110.692983) (xy 183.22899 -110.669387) (xy 183.27842 -110.653326) (xy 183.329755 -110.645196)
			(xy 183.381729 -110.645196) (xy 183.433064 -110.653326) (xy 183.482494 -110.669387) (xy 183.528804 -110.692983)
			(xy 183.570852 -110.723533) (xy 183.607603 -110.760284) (xy 183.638153 -110.802332) (xy 183.661749 -110.848642)
			(xy 183.67781 -110.898072) (xy 183.68594 -110.949407) (xy 183.68645 -110.975394) (xy 183.68594 -111.001381)
			(xy 183.82539 -111.001381) (xy 183.82539 -110.949407) (xy 183.83352 -110.898072) (xy 183.849581 -110.848642)
			(xy 183.873177 -110.802332) (xy 183.903727 -110.760284) (xy 183.940478 -110.723533) (xy 183.982526 -110.692983)
			(xy 184.028836 -110.669387) (xy 184.078266 -110.653326) (xy 184.129601 -110.645196) (xy 184.181575 -110.645196)
			(xy 184.23291 -110.653326) (xy 184.28234 -110.669387) (xy 184.32865 -110.692983) (xy 184.370698 -110.723533)
			(xy 184.407449 -110.760284) (xy 184.437999 -110.802332) (xy 184.461595 -110.848642) (xy 184.477656 -110.898072)
			(xy 184.485786 -110.949407) (xy 184.486296 -110.975394) (xy 184.485786 -111.001381) (xy 184.62549 -111.001381)
			(xy 184.62549 -110.949407) (xy 184.63362 -110.898072) (xy 184.649681 -110.848642) (xy 184.673277 -110.802332)
			(xy 184.703827 -110.760284) (xy 184.740578 -110.723533) (xy 184.782626 -110.692983) (xy 184.828936 -110.669387)
			(xy 184.878366 -110.653326) (xy 184.929701 -110.645196) (xy 184.981675 -110.645196) (xy 185.03301 -110.653326)
			(xy 185.08244 -110.669387) (xy 185.12875 -110.692983) (xy 185.170798 -110.723533) (xy 185.207549 -110.760284)
			(xy 185.238099 -110.802332) (xy 185.261695 -110.848642) (xy 185.277756 -110.898072) (xy 185.285886 -110.949407)
			(xy 185.286396 -110.975394) (xy 185.285886 -111.001381) (xy 185.42559 -111.001381) (xy 185.42559 -110.949407)
			(xy 185.43372 -110.898072) (xy 185.449781 -110.848642) (xy 185.473377 -110.802332) (xy 185.503927 -110.760284)
			(xy 185.540678 -110.723533) (xy 185.582726 -110.692983) (xy 185.629036 -110.669387) (xy 185.678466 -110.653326)
			(xy 185.729801 -110.645196) (xy 185.781775 -110.645196) (xy 185.83311 -110.653326) (xy 185.88254 -110.669387)
			(xy 185.92885 -110.692983) (xy 185.970898 -110.723533) (xy 186.007649 -110.760284) (xy 186.038199 -110.802332)
			(xy 186.061795 -110.848642) (xy 186.077856 -110.898072) (xy 186.085986 -110.949407) (xy 186.086496 -110.975394)
			(xy 186.085986 -111.001381) (xy 186.225436 -111.001381) (xy 186.225436 -110.949407) (xy 186.233566 -110.898072)
			(xy 186.249627 -110.848642) (xy 186.273223 -110.802332) (xy 186.303773 -110.760284) (xy 186.340524 -110.723533)
			(xy 186.382572 -110.692983) (xy 186.428882 -110.669387) (xy 186.478312 -110.653326) (xy 186.529647 -110.645196)
			(xy 186.581621 -110.645196) (xy 186.632956 -110.653326) (xy 186.682386 -110.669387) (xy 186.728696 -110.692983)
			(xy 186.770744 -110.723533) (xy 186.807495 -110.760284) (xy 186.838045 -110.802332) (xy 186.861641 -110.848642)
			(xy 186.877702 -110.898072) (xy 186.885832 -110.949407) (xy 186.886342 -110.975394) (xy 186.885832 -111.001381)
			(xy 186.877702 -111.052716) (xy 186.861641 -111.102146) (xy 186.838045 -111.148456) (xy 186.807495 -111.190504)
			(xy 186.770744 -111.227255) (xy 186.728696 -111.257805) (xy 186.682386 -111.281401) (xy 186.632956 -111.297462)
			(xy 186.581621 -111.305592) (xy 186.529647 -111.305592) (xy 186.478312 -111.297462) (xy 186.428882 -111.281401)
			(xy 186.382572 -111.257805) (xy 186.340524 -111.227255) (xy 186.303773 -111.190504) (xy 186.273223 -111.148456)
			(xy 186.249627 -111.102146) (xy 186.233566 -111.052716) (xy 186.225436 -111.001381) (xy 186.085986 -111.001381)
			(xy 186.077856 -111.052716) (xy 186.061795 -111.102146) (xy 186.038199 -111.148456) (xy 186.007649 -111.190504)
			(xy 185.970898 -111.227255) (xy 185.92885 -111.257805) (xy 185.88254 -111.281401) (xy 185.83311 -111.297462)
			(xy 185.781775 -111.305592) (xy 185.729801 -111.305592) (xy 185.678466 -111.297462) (xy 185.629036 -111.281401)
			(xy 185.582726 -111.257805) (xy 185.540678 -111.227255) (xy 185.503927 -111.190504) (xy 185.473377 -111.148456)
			(xy 185.449781 -111.102146) (xy 185.43372 -111.052716) (xy 185.42559 -111.001381) (xy 185.285886 -111.001381)
			(xy 185.277756 -111.052716) (xy 185.261695 -111.102146) (xy 185.238099 -111.148456) (xy 185.207549 -111.190504)
			(xy 185.170798 -111.227255) (xy 185.12875 -111.257805) (xy 185.08244 -111.281401) (xy 185.03301 -111.297462)
			(xy 184.981675 -111.305592) (xy 184.929701 -111.305592) (xy 184.878366 -111.297462) (xy 184.828936 -111.281401)
			(xy 184.782626 -111.257805) (xy 184.740578 -111.227255) (xy 184.703827 -111.190504) (xy 184.673277 -111.148456)
			(xy 184.649681 -111.102146) (xy 184.63362 -111.052716) (xy 184.62549 -111.001381) (xy 184.485786 -111.001381)
			(xy 184.477656 -111.052716) (xy 184.461595 -111.102146) (xy 184.437999 -111.148456) (xy 184.407449 -111.190504)
			(xy 184.370698 -111.227255) (xy 184.32865 -111.257805) (xy 184.28234 -111.281401) (xy 184.23291 -111.297462)
			(xy 184.181575 -111.305592) (xy 184.129601 -111.305592) (xy 184.078266 -111.297462) (xy 184.028836 -111.281401)
			(xy 183.982526 -111.257805) (xy 183.940478 -111.227255) (xy 183.903727 -111.190504) (xy 183.873177 -111.148456)
			(xy 183.849581 -111.102146) (xy 183.83352 -111.052716) (xy 183.82539 -111.001381) (xy 183.68594 -111.001381)
			(xy 183.67781 -111.052716) (xy 183.661749 -111.102146) (xy 183.638153 -111.148456) (xy 183.607603 -111.190504)
			(xy 183.570852 -111.227255) (xy 183.528804 -111.257805) (xy 183.482494 -111.281401) (xy 183.433064 -111.297462)
			(xy 183.381729 -111.305592) (xy 183.329755 -111.305592) (xy 183.27842 -111.297462) (xy 183.22899 -111.281401)
			(xy 183.18268 -111.257805) (xy 183.140632 -111.227255) (xy 183.103881 -111.190504) (xy 183.073331 -111.148456)
			(xy 183.049735 -111.102146) (xy 183.033674 -111.052716) (xy 183.025544 -111.001381) (xy 182.88584 -111.001381)
			(xy 182.87771 -111.052716) (xy 182.861649 -111.102146) (xy 182.838053 -111.148456) (xy 182.807503 -111.190504)
			(xy 182.770752 -111.227255) (xy 182.728704 -111.257805) (xy 182.682394 -111.281401) (xy 182.632964 -111.297462)
			(xy 182.581629 -111.305592) (xy 182.529655 -111.305592) (xy 182.47832 -111.297462) (xy 182.42889 -111.281401)
			(xy 182.38258 -111.257805) (xy 182.340532 -111.227255) (xy 182.303781 -111.190504) (xy 182.273231 -111.148456)
			(xy 182.249635 -111.102146) (xy 182.233574 -111.052716) (xy 182.225444 -111.001381) (xy 181.41188 -111.001381)
			(xy 181.41188 -111.801481) (xy 182.225444 -111.801481) (xy 182.225444 -111.749507) (xy 182.233574 -111.698172)
			(xy 182.249635 -111.648742) (xy 182.273231 -111.602432) (xy 182.303781 -111.560384) (xy 182.340532 -111.523633)
			(xy 182.38258 -111.493083) (xy 182.42889 -111.469487) (xy 182.47832 -111.453426) (xy 182.529655 -111.445296)
			(xy 182.581629 -111.445296) (xy 182.632964 -111.453426) (xy 182.682394 -111.469487) (xy 182.728704 -111.493083)
			(xy 182.770752 -111.523633) (xy 182.807503 -111.560384) (xy 182.838053 -111.602432) (xy 182.861649 -111.648742)
			(xy 182.87771 -111.698172) (xy 182.88584 -111.749507) (xy 182.88635 -111.775494) (xy 182.88584 -111.801481)
			(xy 183.025544 -111.801481) (xy 183.025544 -111.749507) (xy 183.033674 -111.698172) (xy 183.049735 -111.648742)
			(xy 183.073331 -111.602432) (xy 183.103881 -111.560384) (xy 183.140632 -111.523633) (xy 183.18268 -111.493083)
			(xy 183.22899 -111.469487) (xy 183.27842 -111.453426) (xy 183.329755 -111.445296) (xy 183.381729 -111.445296)
			(xy 183.433064 -111.453426) (xy 183.482494 -111.469487) (xy 183.528804 -111.493083) (xy 183.570852 -111.523633)
			(xy 183.607603 -111.560384) (xy 183.638153 -111.602432) (xy 183.661749 -111.648742) (xy 183.67781 -111.698172)
			(xy 183.68594 -111.749507) (xy 183.68645 -111.775494) (xy 183.68594 -111.801481) (xy 183.82539 -111.801481)
			(xy 183.82539 -111.749507) (xy 183.83352 -111.698172) (xy 183.849581 -111.648742) (xy 183.873177 -111.602432)
			(xy 183.903727 -111.560384) (xy 183.940478 -111.523633) (xy 183.982526 -111.493083) (xy 184.028836 -111.469487)
			(xy 184.078266 -111.453426) (xy 184.129601 -111.445296) (xy 184.181575 -111.445296) (xy 184.23291 -111.453426)
			(xy 184.28234 -111.469487) (xy 184.32865 -111.493083) (xy 184.370698 -111.523633) (xy 184.407449 -111.560384)
			(xy 184.437999 -111.602432) (xy 184.461595 -111.648742) (xy 184.477656 -111.698172) (xy 184.485786 -111.749507)
			(xy 184.486296 -111.775494) (xy 184.485786 -111.801481) (xy 184.62549 -111.801481) (xy 184.62549 -111.749507)
			(xy 184.63362 -111.698172) (xy 184.649681 -111.648742) (xy 184.673277 -111.602432) (xy 184.703827 -111.560384)
			(xy 184.740578 -111.523633) (xy 184.782626 -111.493083) (xy 184.828936 -111.469487) (xy 184.878366 -111.453426)
			(xy 184.929701 -111.445296) (xy 184.981675 -111.445296) (xy 185.03301 -111.453426) (xy 185.08244 -111.469487)
			(xy 185.12875 -111.493083) (xy 185.170798 -111.523633) (xy 185.207549 -111.560384) (xy 185.238099 -111.602432)
			(xy 185.261695 -111.648742) (xy 185.277756 -111.698172) (xy 185.285886 -111.749507) (xy 185.286396 -111.775494)
			(xy 185.285886 -111.801481) (xy 185.42559 -111.801481) (xy 185.42559 -111.749507) (xy 185.43372 -111.698172)
			(xy 185.449781 -111.648742) (xy 185.473377 -111.602432) (xy 185.503927 -111.560384) (xy 185.540678 -111.523633)
			(xy 185.582726 -111.493083) (xy 185.629036 -111.469487) (xy 185.678466 -111.453426) (xy 185.729801 -111.445296)
			(xy 185.781775 -111.445296) (xy 185.83311 -111.453426) (xy 185.88254 -111.469487) (xy 185.92885 -111.493083)
			(xy 185.970898 -111.523633) (xy 186.007649 -111.560384) (xy 186.038199 -111.602432) (xy 186.061795 -111.648742)
			(xy 186.077856 -111.698172) (xy 186.085986 -111.749507) (xy 186.086496 -111.775494) (xy 186.085986 -111.801481)
			(xy 186.077856 -111.852816) (xy 186.061795 -111.902246) (xy 186.038199 -111.948556) (xy 186.007649 -111.990604)
			(xy 185.970898 -112.027355) (xy 185.92885 -112.057905) (xy 185.88254 -112.081501) (xy 185.83311 -112.097562)
			(xy 185.781775 -112.105692) (xy 185.729801 -112.105692) (xy 185.678466 -112.097562) (xy 185.629036 -112.081501)
			(xy 185.582726 -112.057905) (xy 185.540678 -112.027355) (xy 185.503927 -111.990604) (xy 185.473377 -111.948556)
			(xy 185.449781 -111.902246) (xy 185.43372 -111.852816) (xy 185.42559 -111.801481) (xy 185.285886 -111.801481)
			(xy 185.277756 -111.852816) (xy 185.261695 -111.902246) (xy 185.238099 -111.948556) (xy 185.207549 -111.990604)
			(xy 185.170798 -112.027355) (xy 185.12875 -112.057905) (xy 185.08244 -112.081501) (xy 185.03301 -112.097562)
			(xy 184.981675 -112.105692) (xy 184.929701 -112.105692) (xy 184.878366 -112.097562) (xy 184.828936 -112.081501)
			(xy 184.782626 -112.057905) (xy 184.740578 -112.027355) (xy 184.703827 -111.990604) (xy 184.673277 -111.948556)
			(xy 184.649681 -111.902246) (xy 184.63362 -111.852816) (xy 184.62549 -111.801481) (xy 184.485786 -111.801481)
			(xy 184.477656 -111.852816) (xy 184.461595 -111.902246) (xy 184.437999 -111.948556) (xy 184.407449 -111.990604)
			(xy 184.370698 -112.027355) (xy 184.32865 -112.057905) (xy 184.28234 -112.081501) (xy 184.23291 -112.097562)
			(xy 184.181575 -112.105692) (xy 184.129601 -112.105692) (xy 184.078266 -112.097562) (xy 184.028836 -112.081501)
			(xy 183.982526 -112.057905) (xy 183.940478 -112.027355) (xy 183.903727 -111.990604) (xy 183.873177 -111.948556)
			(xy 183.849581 -111.902246) (xy 183.83352 -111.852816) (xy 183.82539 -111.801481) (xy 183.68594 -111.801481)
			(xy 183.67781 -111.852816) (xy 183.661749 -111.902246) (xy 183.638153 -111.948556) (xy 183.607603 -111.990604)
			(xy 183.570852 -112.027355) (xy 183.528804 -112.057905) (xy 183.482494 -112.081501) (xy 183.433064 -112.097562)
			(xy 183.381729 -112.105692) (xy 183.329755 -112.105692) (xy 183.27842 -112.097562) (xy 183.22899 -112.081501)
			(xy 183.18268 -112.057905) (xy 183.140632 -112.027355) (xy 183.103881 -111.990604) (xy 183.073331 -111.948556)
			(xy 183.049735 -111.902246) (xy 183.033674 -111.852816) (xy 183.025544 -111.801481) (xy 182.88584 -111.801481)
			(xy 182.87771 -111.852816) (xy 182.861649 -111.902246) (xy 182.838053 -111.948556) (xy 182.807503 -111.990604)
			(xy 182.770752 -112.027355) (xy 182.728704 -112.057905) (xy 182.682394 -112.081501) (xy 182.632964 -112.097562)
			(xy 182.581629 -112.105692) (xy 182.529655 -112.105692) (xy 182.47832 -112.097562) (xy 182.42889 -112.081501)
			(xy 182.38258 -112.057905) (xy 182.340532 -112.027355) (xy 182.303781 -111.990604) (xy 182.273231 -111.948556)
			(xy 182.249635 -111.902246) (xy 182.233574 -111.852816) (xy 182.225444 -111.801481) (xy 181.41188 -111.801481)
			(xy 181.41188 -112.601327) (xy 182.225444 -112.601327) (xy 182.225444 -112.549353) (xy 182.233574 -112.498018)
			(xy 182.249635 -112.448588) (xy 182.273231 -112.402278) (xy 182.303781 -112.36023) (xy 182.340532 -112.323479)
			(xy 182.38258 -112.292929) (xy 182.42889 -112.269333) (xy 182.47832 -112.253272) (xy 182.529655 -112.245142)
			(xy 182.581629 -112.245142) (xy 182.632964 -112.253272) (xy 182.682394 -112.269333) (xy 182.728704 -112.292929)
			(xy 182.770752 -112.323479) (xy 182.807503 -112.36023) (xy 182.838053 -112.402278) (xy 182.861649 -112.448588)
			(xy 182.87771 -112.498018) (xy 182.88584 -112.549353) (xy 182.88635 -112.57534) (xy 182.88584 -112.601327)
			(xy 183.025544 -112.601327) (xy 183.025544 -112.549353) (xy 183.033674 -112.498018) (xy 183.049735 -112.448588)
			(xy 183.073331 -112.402278) (xy 183.103881 -112.36023) (xy 183.140632 -112.323479) (xy 183.18268 -112.292929)
			(xy 183.22899 -112.269333) (xy 183.27842 -112.253272) (xy 183.329755 -112.245142) (xy 183.381729 -112.245142)
			(xy 183.433064 -112.253272) (xy 183.482494 -112.269333) (xy 183.528804 -112.292929) (xy 183.570852 -112.323479)
			(xy 183.607603 -112.36023) (xy 183.638153 -112.402278) (xy 183.661749 -112.448588) (xy 183.67781 -112.498018)
			(xy 183.68594 -112.549353) (xy 183.68645 -112.57534) (xy 183.68594 -112.601327) (xy 183.82539 -112.601327)
			(xy 183.82539 -112.549353) (xy 183.83352 -112.498018) (xy 183.849581 -112.448588) (xy 183.873177 -112.402278)
			(xy 183.903727 -112.36023) (xy 183.940478 -112.323479) (xy 183.982526 -112.292929) (xy 184.028836 -112.269333)
			(xy 184.078266 -112.253272) (xy 184.129601 -112.245142) (xy 184.181575 -112.245142) (xy 184.23291 -112.253272)
			(xy 184.28234 -112.269333) (xy 184.32865 -112.292929) (xy 184.370698 -112.323479) (xy 184.407449 -112.36023)
			(xy 184.437999 -112.402278) (xy 184.461595 -112.448588) (xy 184.477656 -112.498018) (xy 184.485786 -112.549353)
			(xy 184.486296 -112.57534) (xy 184.485786 -112.601327) (xy 185.42559 -112.601327) (xy 185.42559 -112.549353)
			(xy 185.43372 -112.498018) (xy 185.449781 -112.448588) (xy 185.473377 -112.402278) (xy 185.503927 -112.36023)
			(xy 185.540678 -112.323479) (xy 185.582726 -112.292929) (xy 185.629036 -112.269333) (xy 185.678466 -112.253272)
			(xy 185.729801 -112.245142) (xy 185.781775 -112.245142) (xy 185.83311 -112.253272) (xy 185.88254 -112.269333)
			(xy 185.92885 -112.292929) (xy 185.970898 -112.323479) (xy 186.007649 -112.36023) (xy 186.038199 -112.402278)
			(xy 186.061795 -112.448588) (xy 186.077856 -112.498018) (xy 186.085986 -112.549353) (xy 186.086496 -112.57534)
			(xy 186.085986 -112.601327) (xy 186.225436 -112.601327) (xy 186.225436 -112.549353) (xy 186.233566 -112.498018)
			(xy 186.249627 -112.448588) (xy 186.273223 -112.402278) (xy 186.303773 -112.36023) (xy 186.340524 -112.323479)
			(xy 186.382572 -112.292929) (xy 186.428882 -112.269333) (xy 186.478312 -112.253272) (xy 186.529647 -112.245142)
			(xy 186.581621 -112.245142) (xy 186.632956 -112.253272) (xy 186.682386 -112.269333) (xy 186.728696 -112.292929)
			(xy 186.770744 -112.323479) (xy 186.807495 -112.36023) (xy 186.838045 -112.402278) (xy 186.861641 -112.448588)
			(xy 186.877702 -112.498018) (xy 186.885832 -112.549353) (xy 186.886342 -112.57534) (xy 186.885832 -112.601327)
			(xy 186.877702 -112.652662) (xy 186.861641 -112.702092) (xy 186.838045 -112.748402) (xy 186.807495 -112.79045)
			(xy 186.770744 -112.827201) (xy 186.728696 -112.857751) (xy 186.682386 -112.881347) (xy 186.632956 -112.897408)
			(xy 186.581621 -112.905538) (xy 186.529647 -112.905538) (xy 186.478312 -112.897408) (xy 186.428882 -112.881347)
			(xy 186.382572 -112.857751) (xy 186.340524 -112.827201) (xy 186.303773 -112.79045) (xy 186.273223 -112.748402)
			(xy 186.249627 -112.702092) (xy 186.233566 -112.652662) (xy 186.225436 -112.601327) (xy 186.085986 -112.601327)
			(xy 186.077856 -112.652662) (xy 186.061795 -112.702092) (xy 186.038199 -112.748402) (xy 186.007649 -112.79045)
			(xy 185.970898 -112.827201) (xy 185.92885 -112.857751) (xy 185.88254 -112.881347) (xy 185.83311 -112.897408)
			(xy 185.781775 -112.905538) (xy 185.729801 -112.905538) (xy 185.678466 -112.897408) (xy 185.629036 -112.881347)
			(xy 185.582726 -112.857751) (xy 185.540678 -112.827201) (xy 185.503927 -112.79045) (xy 185.473377 -112.748402)
			(xy 185.449781 -112.702092) (xy 185.43372 -112.652662) (xy 185.42559 -112.601327) (xy 184.485786 -112.601327)
			(xy 184.477656 -112.652662) (xy 184.461595 -112.702092) (xy 184.437999 -112.748402) (xy 184.407449 -112.79045)
			(xy 184.370698 -112.827201) (xy 184.32865 -112.857751) (xy 184.28234 -112.881347) (xy 184.23291 -112.897408)
			(xy 184.181575 -112.905538) (xy 184.129601 -112.905538) (xy 184.078266 -112.897408) (xy 184.028836 -112.881347)
			(xy 183.982526 -112.857751) (xy 183.940478 -112.827201) (xy 183.903727 -112.79045) (xy 183.873177 -112.748402)
			(xy 183.849581 -112.702092) (xy 183.83352 -112.652662) (xy 183.82539 -112.601327) (xy 183.68594 -112.601327)
			(xy 183.67781 -112.652662) (xy 183.661749 -112.702092) (xy 183.638153 -112.748402) (xy 183.607603 -112.79045)
			(xy 183.570852 -112.827201) (xy 183.528804 -112.857751) (xy 183.482494 -112.881347) (xy 183.433064 -112.897408)
			(xy 183.381729 -112.905538) (xy 183.329755 -112.905538) (xy 183.27842 -112.897408) (xy 183.22899 -112.881347)
			(xy 183.18268 -112.857751) (xy 183.140632 -112.827201) (xy 183.103881 -112.79045) (xy 183.073331 -112.748402)
			(xy 183.049735 -112.702092) (xy 183.033674 -112.652662) (xy 183.025544 -112.601327) (xy 182.88584 -112.601327)
			(xy 182.87771 -112.652662) (xy 182.861649 -112.702092) (xy 182.838053 -112.748402) (xy 182.807503 -112.79045)
			(xy 182.770752 -112.827201) (xy 182.728704 -112.857751) (xy 182.682394 -112.881347) (xy 182.632964 -112.897408)
			(xy 182.581629 -112.905538) (xy 182.529655 -112.905538) (xy 182.47832 -112.897408) (xy 182.42889 -112.881347)
			(xy 182.38258 -112.857751) (xy 182.340532 -112.827201) (xy 182.303781 -112.79045) (xy 182.273231 -112.748402)
			(xy 182.249635 -112.702092) (xy 182.233574 -112.652662) (xy 182.225444 -112.601327) (xy 181.41188 -112.601327)
			(xy 181.41188 -114.201527) (xy 182.225444 -114.201527) (xy 182.225444 -114.149553) (xy 182.233574 -114.098218)
			(xy 182.249635 -114.048788) (xy 182.273231 -114.002478) (xy 182.303781 -113.96043) (xy 182.340532 -113.923679)
			(xy 182.38258 -113.893129) (xy 182.42889 -113.869533) (xy 182.47832 -113.853472) (xy 182.529655 -113.845342)
			(xy 182.581629 -113.845342) (xy 182.632964 -113.853472) (xy 182.682394 -113.869533) (xy 182.728704 -113.893129)
			(xy 182.770752 -113.923679) (xy 182.807503 -113.96043) (xy 182.838053 -114.002478) (xy 182.861649 -114.048788)
			(xy 182.87771 -114.098218) (xy 182.88584 -114.149553) (xy 182.88635 -114.17554) (xy 182.88584 -114.201527)
			(xy 183.025544 -114.201527) (xy 183.025544 -114.149553) (xy 183.033674 -114.098218) (xy 183.049735 -114.048788)
			(xy 183.073331 -114.002478) (xy 183.103881 -113.96043) (xy 183.140632 -113.923679) (xy 183.18268 -113.893129)
			(xy 183.22899 -113.869533) (xy 183.27842 -113.853472) (xy 183.329755 -113.845342) (xy 183.381729 -113.845342)
			(xy 183.433064 -113.853472) (xy 183.482494 -113.869533) (xy 183.528804 -113.893129) (xy 183.570852 -113.923679)
			(xy 183.607603 -113.96043) (xy 183.638153 -114.002478) (xy 183.661749 -114.048788) (xy 183.67781 -114.098218)
			(xy 183.68594 -114.149553) (xy 183.68645 -114.17554) (xy 183.68594 -114.201527) (xy 183.82539 -114.201527)
			(xy 183.82539 -114.149553) (xy 183.83352 -114.098218) (xy 183.849581 -114.048788) (xy 183.873177 -114.002478)
			(xy 183.903727 -113.96043) (xy 183.940478 -113.923679) (xy 183.982526 -113.893129) (xy 184.028836 -113.869533)
			(xy 184.078266 -113.853472) (xy 184.129601 -113.845342) (xy 184.181575 -113.845342) (xy 184.23291 -113.853472)
			(xy 184.28234 -113.869533) (xy 184.32865 -113.893129) (xy 184.370698 -113.923679) (xy 184.407449 -113.96043)
			(xy 184.437999 -114.002478) (xy 184.461595 -114.048788) (xy 184.477656 -114.098218) (xy 184.485786 -114.149553)
			(xy 184.486296 -114.17554) (xy 184.485786 -114.201527) (xy 184.62549 -114.201527) (xy 184.62549 -114.149553)
			(xy 184.63362 -114.098218) (xy 184.649681 -114.048788) (xy 184.673277 -114.002478) (xy 184.703827 -113.96043)
			(xy 184.740578 -113.923679) (xy 184.782626 -113.893129) (xy 184.828936 -113.869533) (xy 184.878366 -113.853472)
			(xy 184.929701 -113.845342) (xy 184.981675 -113.845342) (xy 185.03301 -113.853472) (xy 185.08244 -113.869533)
			(xy 185.12875 -113.893129) (xy 185.170798 -113.923679) (xy 185.207549 -113.96043) (xy 185.238099 -114.002478)
			(xy 185.261695 -114.048788) (xy 185.277756 -114.098218) (xy 185.285886 -114.149553) (xy 185.286396 -114.17554)
			(xy 185.285886 -114.201527) (xy 185.42559 -114.201527) (xy 185.42559 -114.149553) (xy 185.43372 -114.098218)
			(xy 185.449781 -114.048788) (xy 185.473377 -114.002478) (xy 185.503927 -113.96043) (xy 185.540678 -113.923679)
			(xy 185.582726 -113.893129) (xy 185.629036 -113.869533) (xy 185.678466 -113.853472) (xy 185.729801 -113.845342)
			(xy 185.781775 -113.845342) (xy 185.83311 -113.853472) (xy 185.88254 -113.869533) (xy 185.92885 -113.893129)
			(xy 185.970898 -113.923679) (xy 186.007649 -113.96043) (xy 186.038199 -114.002478) (xy 186.061795 -114.048788)
			(xy 186.077856 -114.098218) (xy 186.085986 -114.149553) (xy 186.086496 -114.17554) (xy 186.085986 -114.201527)
			(xy 186.077856 -114.252862) (xy 186.061795 -114.302292) (xy 186.038199 -114.348602) (xy 186.007649 -114.39065)
			(xy 185.970898 -114.427401) (xy 185.92885 -114.457951) (xy 185.88254 -114.481547) (xy 185.83311 -114.497608)
			(xy 185.781775 -114.505738) (xy 185.729801 -114.505738) (xy 185.678466 -114.497608) (xy 185.629036 -114.481547)
			(xy 185.582726 -114.457951) (xy 185.540678 -114.427401) (xy 185.503927 -114.39065) (xy 185.473377 -114.348602)
			(xy 185.449781 -114.302292) (xy 185.43372 -114.252862) (xy 185.42559 -114.201527) (xy 185.285886 -114.201527)
			(xy 185.277756 -114.252862) (xy 185.261695 -114.302292) (xy 185.238099 -114.348602) (xy 185.207549 -114.39065)
			(xy 185.170798 -114.427401) (xy 185.12875 -114.457951) (xy 185.08244 -114.481547) (xy 185.03301 -114.497608)
			(xy 184.981675 -114.505738) (xy 184.929701 -114.505738) (xy 184.878366 -114.497608) (xy 184.828936 -114.481547)
			(xy 184.782626 -114.457951) (xy 184.740578 -114.427401) (xy 184.703827 -114.39065) (xy 184.673277 -114.348602)
			(xy 184.649681 -114.302292) (xy 184.63362 -114.252862) (xy 184.62549 -114.201527) (xy 184.485786 -114.201527)
			(xy 184.477656 -114.252862) (xy 184.461595 -114.302292) (xy 184.437999 -114.348602) (xy 184.407449 -114.39065)
			(xy 184.370698 -114.427401) (xy 184.32865 -114.457951) (xy 184.28234 -114.481547) (xy 184.23291 -114.497608)
			(xy 184.181575 -114.505738) (xy 184.129601 -114.505738) (xy 184.078266 -114.497608) (xy 184.028836 -114.481547)
			(xy 183.982526 -114.457951) (xy 183.940478 -114.427401) (xy 183.903727 -114.39065) (xy 183.873177 -114.348602)
			(xy 183.849581 -114.302292) (xy 183.83352 -114.252862) (xy 183.82539 -114.201527) (xy 183.68594 -114.201527)
			(xy 183.67781 -114.252862) (xy 183.661749 -114.302292) (xy 183.638153 -114.348602) (xy 183.607603 -114.39065)
			(xy 183.570852 -114.427401) (xy 183.528804 -114.457951) (xy 183.482494 -114.481547) (xy 183.433064 -114.497608)
			(xy 183.381729 -114.505738) (xy 183.329755 -114.505738) (xy 183.27842 -114.497608) (xy 183.22899 -114.481547)
			(xy 183.18268 -114.457951) (xy 183.140632 -114.427401) (xy 183.103881 -114.39065) (xy 183.073331 -114.348602)
			(xy 183.049735 -114.302292) (xy 183.033674 -114.252862) (xy 183.025544 -114.201527) (xy 182.88584 -114.201527)
			(xy 182.87771 -114.252862) (xy 182.861649 -114.302292) (xy 182.838053 -114.348602) (xy 182.807503 -114.39065)
			(xy 182.770752 -114.427401) (xy 182.728704 -114.457951) (xy 182.682394 -114.481547) (xy 182.632964 -114.497608)
			(xy 182.581629 -114.505738) (xy 182.529655 -114.505738) (xy 182.47832 -114.497608) (xy 182.42889 -114.481547)
			(xy 182.38258 -114.457951) (xy 182.340532 -114.427401) (xy 182.303781 -114.39065) (xy 182.273231 -114.348602)
			(xy 182.249635 -114.302292) (xy 182.233574 -114.252862) (xy 182.225444 -114.201527) (xy 181.41188 -114.201527)
			(xy 181.41188 -115.001373) (xy 182.225444 -115.001373) (xy 182.225444 -114.949399) (xy 182.233574 -114.898064)
			(xy 182.249635 -114.848634) (xy 182.273231 -114.802324) (xy 182.303781 -114.760276) (xy 182.340532 -114.723525)
			(xy 182.38258 -114.692975) (xy 182.42889 -114.669379) (xy 182.47832 -114.653318) (xy 182.529655 -114.645188)
			(xy 182.581629 -114.645188) (xy 182.632964 -114.653318) (xy 182.682394 -114.669379) (xy 182.728704 -114.692975)
			(xy 182.770752 -114.723525) (xy 182.807503 -114.760276) (xy 182.838053 -114.802324) (xy 182.861649 -114.848634)
			(xy 182.87771 -114.898064) (xy 182.88584 -114.949399) (xy 182.88635 -114.975386) (xy 182.88584 -115.001373)
			(xy 183.025544 -115.001373) (xy 183.025544 -114.949399) (xy 183.033674 -114.898064) (xy 183.049735 -114.848634)
			(xy 183.073331 -114.802324) (xy 183.103881 -114.760276) (xy 183.140632 -114.723525) (xy 183.18268 -114.692975)
			(xy 183.22899 -114.669379) (xy 183.27842 -114.653318) (xy 183.329755 -114.645188) (xy 183.381729 -114.645188)
			(xy 183.433064 -114.653318) (xy 183.482494 -114.669379) (xy 183.528804 -114.692975) (xy 183.570852 -114.723525)
			(xy 183.607603 -114.760276) (xy 183.638153 -114.802324) (xy 183.661749 -114.848634) (xy 183.67781 -114.898064)
			(xy 183.68594 -114.949399) (xy 183.68645 -114.975386) (xy 183.68594 -115.001373) (xy 183.82539 -115.001373)
			(xy 183.82539 -114.949399) (xy 183.83352 -114.898064) (xy 183.849581 -114.848634) (xy 183.873177 -114.802324)
			(xy 183.903727 -114.760276) (xy 183.940478 -114.723525) (xy 183.982526 -114.692975) (xy 184.028836 -114.669379)
			(xy 184.078266 -114.653318) (xy 184.129601 -114.645188) (xy 184.181575 -114.645188) (xy 184.23291 -114.653318)
			(xy 184.28234 -114.669379) (xy 184.32865 -114.692975) (xy 184.370698 -114.723525) (xy 184.407449 -114.760276)
			(xy 184.437999 -114.802324) (xy 184.461595 -114.848634) (xy 184.477656 -114.898064) (xy 184.485786 -114.949399)
			(xy 184.486296 -114.975386) (xy 184.485786 -115.001373) (xy 184.62549 -115.001373) (xy 184.62549 -114.949399)
			(xy 184.63362 -114.898064) (xy 184.649681 -114.848634) (xy 184.673277 -114.802324) (xy 184.703827 -114.760276)
			(xy 184.740578 -114.723525) (xy 184.782626 -114.692975) (xy 184.828936 -114.669379) (xy 184.878366 -114.653318)
			(xy 184.929701 -114.645188) (xy 184.981675 -114.645188) (xy 185.03301 -114.653318) (xy 185.08244 -114.669379)
			(xy 185.12875 -114.692975) (xy 185.170798 -114.723525) (xy 185.207549 -114.760276) (xy 185.238099 -114.802324)
			(xy 185.261695 -114.848634) (xy 185.277756 -114.898064) (xy 185.285886 -114.949399) (xy 185.286396 -114.975386)
			(xy 185.285886 -115.001373) (xy 185.42559 -115.001373) (xy 185.42559 -114.949399) (xy 185.43372 -114.898064)
			(xy 185.449781 -114.848634) (xy 185.473377 -114.802324) (xy 185.503927 -114.760276) (xy 185.540678 -114.723525)
			(xy 185.582726 -114.692975) (xy 185.629036 -114.669379) (xy 185.678466 -114.653318) (xy 185.729801 -114.645188)
			(xy 185.781775 -114.645188) (xy 185.83311 -114.653318) (xy 185.88254 -114.669379) (xy 185.92885 -114.692975)
			(xy 185.970898 -114.723525) (xy 186.007649 -114.760276) (xy 186.038199 -114.802324) (xy 186.061795 -114.848634)
			(xy 186.077856 -114.898064) (xy 186.085986 -114.949399) (xy 186.086496 -114.975386) (xy 186.085986 -115.001373)
			(xy 186.225436 -115.001373) (xy 186.225436 -114.949399) (xy 186.233566 -114.898064) (xy 186.249627 -114.848634)
			(xy 186.273223 -114.802324) (xy 186.303773 -114.760276) (xy 186.340524 -114.723525) (xy 186.382572 -114.692975)
			(xy 186.428882 -114.669379) (xy 186.478312 -114.653318) (xy 186.529647 -114.645188) (xy 186.581621 -114.645188)
			(xy 186.632956 -114.653318) (xy 186.682386 -114.669379) (xy 186.728696 -114.692975) (xy 186.770744 -114.723525)
			(xy 186.807495 -114.760276) (xy 186.838045 -114.802324) (xy 186.861641 -114.848634) (xy 186.877702 -114.898064)
			(xy 186.885832 -114.949399) (xy 186.886342 -114.975386) (xy 186.885832 -115.001373) (xy 186.877702 -115.052708)
			(xy 186.861641 -115.102138) (xy 186.838045 -115.148448) (xy 186.807495 -115.190496) (xy 186.770744 -115.227247)
			(xy 186.728696 -115.257797) (xy 186.682386 -115.281393) (xy 186.632956 -115.297454) (xy 186.581621 -115.305584)
			(xy 186.529647 -115.305584) (xy 186.478312 -115.297454) (xy 186.428882 -115.281393) (xy 186.382572 -115.257797)
			(xy 186.340524 -115.227247) (xy 186.303773 -115.190496) (xy 186.273223 -115.148448) (xy 186.249627 -115.102138)
			(xy 186.233566 -115.052708) (xy 186.225436 -115.001373) (xy 186.085986 -115.001373) (xy 186.077856 -115.052708)
			(xy 186.061795 -115.102138) (xy 186.038199 -115.148448) (xy 186.007649 -115.190496) (xy 185.970898 -115.227247)
			(xy 185.92885 -115.257797) (xy 185.88254 -115.281393) (xy 185.83311 -115.297454) (xy 185.781775 -115.305584)
			(xy 185.729801 -115.305584) (xy 185.678466 -115.297454) (xy 185.629036 -115.281393) (xy 185.582726 -115.257797)
			(xy 185.540678 -115.227247) (xy 185.503927 -115.190496) (xy 185.473377 -115.148448) (xy 185.449781 -115.102138)
			(xy 185.43372 -115.052708) (xy 185.42559 -115.001373) (xy 185.285886 -115.001373) (xy 185.277756 -115.052708)
			(xy 185.261695 -115.102138) (xy 185.238099 -115.148448) (xy 185.207549 -115.190496) (xy 185.170798 -115.227247)
			(xy 185.12875 -115.257797) (xy 185.08244 -115.281393) (xy 185.03301 -115.297454) (xy 184.981675 -115.305584)
			(xy 184.929701 -115.305584) (xy 184.878366 -115.297454) (xy 184.828936 -115.281393) (xy 184.782626 -115.257797)
			(xy 184.740578 -115.227247) (xy 184.703827 -115.190496) (xy 184.673277 -115.148448) (xy 184.649681 -115.102138)
			(xy 184.63362 -115.052708) (xy 184.62549 -115.001373) (xy 184.485786 -115.001373) (xy 184.477656 -115.052708)
			(xy 184.461595 -115.102138) (xy 184.437999 -115.148448) (xy 184.407449 -115.190496) (xy 184.370698 -115.227247)
			(xy 184.32865 -115.257797) (xy 184.28234 -115.281393) (xy 184.23291 -115.297454) (xy 184.181575 -115.305584)
			(xy 184.129601 -115.305584) (xy 184.078266 -115.297454) (xy 184.028836 -115.281393) (xy 183.982526 -115.257797)
			(xy 183.940478 -115.227247) (xy 183.903727 -115.190496) (xy 183.873177 -115.148448) (xy 183.849581 -115.102138)
			(xy 183.83352 -115.052708) (xy 183.82539 -115.001373) (xy 183.68594 -115.001373) (xy 183.67781 -115.052708)
			(xy 183.661749 -115.102138) (xy 183.638153 -115.148448) (xy 183.607603 -115.190496) (xy 183.570852 -115.227247)
			(xy 183.528804 -115.257797) (xy 183.482494 -115.281393) (xy 183.433064 -115.297454) (xy 183.381729 -115.305584)
			(xy 183.329755 -115.305584) (xy 183.27842 -115.297454) (xy 183.22899 -115.281393) (xy 183.18268 -115.257797)
			(xy 183.140632 -115.227247) (xy 183.103881 -115.190496) (xy 183.073331 -115.148448) (xy 183.049735 -115.102138)
			(xy 183.033674 -115.052708) (xy 183.025544 -115.001373) (xy 182.88584 -115.001373) (xy 182.87771 -115.052708)
			(xy 182.861649 -115.102138) (xy 182.838053 -115.148448) (xy 182.807503 -115.190496) (xy 182.770752 -115.227247)
			(xy 182.728704 -115.257797) (xy 182.682394 -115.281393) (xy 182.632964 -115.297454) (xy 182.581629 -115.305584)
			(xy 182.529655 -115.305584) (xy 182.47832 -115.297454) (xy 182.42889 -115.281393) (xy 182.38258 -115.257797)
			(xy 182.340532 -115.227247) (xy 182.303781 -115.190496) (xy 182.273231 -115.148448) (xy 182.249635 -115.102138)
			(xy 182.233574 -115.052708) (xy 182.225444 -115.001373) (xy 181.41188 -115.001373) (xy 181.41188 -115.801473)
			(xy 182.225444 -115.801473) (xy 182.225444 -115.749499) (xy 182.233574 -115.698164) (xy 182.249635 -115.648734)
			(xy 182.273231 -115.602424) (xy 182.303781 -115.560376) (xy 182.340532 -115.523625) (xy 182.38258 -115.493075)
			(xy 182.42889 -115.469479) (xy 182.47832 -115.453418) (xy 182.529655 -115.445288) (xy 182.581629 -115.445288)
			(xy 182.632964 -115.453418) (xy 182.682394 -115.469479) (xy 182.728704 -115.493075) (xy 182.770752 -115.523625)
			(xy 182.807503 -115.560376) (xy 182.838053 -115.602424) (xy 182.861649 -115.648734) (xy 182.87771 -115.698164)
			(xy 182.88584 -115.749499) (xy 182.88635 -115.775486) (xy 182.88584 -115.801473) (xy 183.025544 -115.801473)
			(xy 183.025544 -115.749499) (xy 183.033674 -115.698164) (xy 183.049735 -115.648734) (xy 183.073331 -115.602424)
			(xy 183.103881 -115.560376) (xy 183.140632 -115.523625) (xy 183.18268 -115.493075) (xy 183.22899 -115.469479)
			(xy 183.27842 -115.453418) (xy 183.329755 -115.445288) (xy 183.381729 -115.445288) (xy 183.433064 -115.453418)
			(xy 183.482494 -115.469479) (xy 183.528804 -115.493075) (xy 183.570852 -115.523625) (xy 183.607603 -115.560376)
			(xy 183.638153 -115.602424) (xy 183.661749 -115.648734) (xy 183.67781 -115.698164) (xy 183.68594 -115.749499)
			(xy 183.68645 -115.775486) (xy 183.68594 -115.801473) (xy 184.62549 -115.801473) (xy 184.62549 -115.749499)
			(xy 184.63362 -115.698164) (xy 184.649681 -115.648734) (xy 184.673277 -115.602424) (xy 184.703827 -115.560376)
			(xy 184.740578 -115.523625) (xy 184.782626 -115.493075) (xy 184.828936 -115.469479) (xy 184.878366 -115.453418)
			(xy 184.929701 -115.445288) (xy 184.981675 -115.445288) (xy 185.03301 -115.453418) (xy 185.08244 -115.469479)
			(xy 185.12875 -115.493075) (xy 185.170798 -115.523625) (xy 185.207549 -115.560376) (xy 185.238099 -115.602424)
			(xy 185.261695 -115.648734) (xy 185.277756 -115.698164) (xy 185.285886 -115.749499) (xy 185.286396 -115.775486)
			(xy 185.285886 -115.801473) (xy 185.42559 -115.801473) (xy 185.42559 -115.749499) (xy 185.43372 -115.698164)
			(xy 185.449781 -115.648734) (xy 185.473377 -115.602424) (xy 185.503927 -115.560376) (xy 185.540678 -115.523625)
			(xy 185.582726 -115.493075) (xy 185.629036 -115.469479) (xy 185.678466 -115.453418) (xy 185.729801 -115.445288)
			(xy 185.781775 -115.445288) (xy 185.83311 -115.453418) (xy 185.88254 -115.469479) (xy 185.92885 -115.493075)
			(xy 185.970898 -115.523625) (xy 186.007649 -115.560376) (xy 186.038199 -115.602424) (xy 186.061795 -115.648734)
			(xy 186.077856 -115.698164) (xy 186.085986 -115.749499) (xy 186.086496 -115.775486) (xy 186.085986 -115.801473)
			(xy 186.077856 -115.852808) (xy 186.061795 -115.902238) (xy 186.038199 -115.948548) (xy 186.007649 -115.990596)
			(xy 185.970898 -116.027347) (xy 185.92885 -116.057897) (xy 185.88254 -116.081493) (xy 185.83311 -116.097554)
			(xy 185.781775 -116.105684) (xy 185.729801 -116.105684) (xy 185.678466 -116.097554) (xy 185.629036 -116.081493)
			(xy 185.582726 -116.057897) (xy 185.540678 -116.027347) (xy 185.503927 -115.990596) (xy 185.473377 -115.948548)
			(xy 185.449781 -115.902238) (xy 185.43372 -115.852808) (xy 185.42559 -115.801473) (xy 185.285886 -115.801473)
			(xy 185.277756 -115.852808) (xy 185.261695 -115.902238) (xy 185.238099 -115.948548) (xy 185.207549 -115.990596)
			(xy 185.170798 -116.027347) (xy 185.12875 -116.057897) (xy 185.08244 -116.081493) (xy 185.03301 -116.097554)
			(xy 184.981675 -116.105684) (xy 184.929701 -116.105684) (xy 184.878366 -116.097554) (xy 184.828936 -116.081493)
			(xy 184.782626 -116.057897) (xy 184.740578 -116.027347) (xy 184.703827 -115.990596) (xy 184.673277 -115.948548)
			(xy 184.649681 -115.902238) (xy 184.63362 -115.852808) (xy 184.62549 -115.801473) (xy 183.68594 -115.801473)
			(xy 183.67781 -115.852808) (xy 183.661749 -115.902238) (xy 183.638153 -115.948548) (xy 183.607603 -115.990596)
			(xy 183.570852 -116.027347) (xy 183.528804 -116.057897) (xy 183.482494 -116.081493) (xy 183.433064 -116.097554)
			(xy 183.381729 -116.105684) (xy 183.329755 -116.105684) (xy 183.27842 -116.097554) (xy 183.22899 -116.081493)
			(xy 183.18268 -116.057897) (xy 183.140632 -116.027347) (xy 183.103881 -115.990596) (xy 183.073331 -115.948548)
			(xy 183.049735 -115.902238) (xy 183.033674 -115.852808) (xy 183.025544 -115.801473) (xy 182.88584 -115.801473)
			(xy 182.87771 -115.852808) (xy 182.861649 -115.902238) (xy 182.838053 -115.948548) (xy 182.807503 -115.990596)
			(xy 182.770752 -116.027347) (xy 182.728704 -116.057897) (xy 182.682394 -116.081493) (xy 182.632964 -116.097554)
			(xy 182.581629 -116.105684) (xy 182.529655 -116.105684) (xy 182.47832 -116.097554) (xy 182.42889 -116.081493)
			(xy 182.38258 -116.057897) (xy 182.340532 -116.027347) (xy 182.303781 -115.990596) (xy 182.273231 -115.948548)
			(xy 182.249635 -115.902238) (xy 182.233574 -115.852808) (xy 182.225444 -115.801473) (xy 181.41188 -115.801473)
			(xy 181.41188 -115.950746) (xy 181.616604 -116.155724) (xy 181.637365 -116.177245) (xy 181.672335 -116.225749)
			(xy 181.6862 -116.252244) (xy 181.703392 -116.248796) (xy 181.738263 -116.245111) (xy 181.755796 -116.244878)
			(xy 181.781784 -116.245387) (xy 181.83312 -116.253517) (xy 181.882552 -116.269578) (xy 181.928863 -116.293173)
			(xy 181.970912 -116.323723) (xy 182.007666 -116.360474) (xy 182.038217 -116.402522) (xy 182.061815 -116.448832)
			(xy 182.077879 -116.498263) (xy 182.086011 -116.549598) (xy 182.086504 -116.575586) (xy 182.086419 -116.585197)
			(xy 182.085273 -116.604386) (xy 182.084218 -116.61394) (xy 182.101976 -116.618399) (xy 182.136583 -116.630361)
			(xy 182.153306 -116.637816) (xy 182.162983 -116.641679) (xy 182.183793 -116.642097) (xy 182.203067 -116.634238)
			(xy 182.217652 -116.619386) (xy 182.22516 -116.599972) (xy 182.225188 -116.589556) (xy 182.224934 -116.575586)
			(xy 182.225445 -116.549603) (xy 182.233576 -116.498277) (xy 182.249636 -116.448855) (xy 182.273229 -116.402554)
			(xy 182.303775 -116.360513) (xy 182.340521 -116.323769) (xy 182.382562 -116.293224) (xy 182.428864 -116.269632)
			(xy 182.478286 -116.253574) (xy 182.529612 -116.245444) (xy 182.581578 -116.245443) (xy 182.632904 -116.253572)
			(xy 182.682327 -116.269629) (xy 182.72863 -116.293219) (xy 182.770672 -116.323763) (xy 182.807419 -116.360506)
			(xy 182.837966 -116.402546) (xy 182.86156 -116.448847) (xy 182.877622 -116.498268) (xy 182.885754 -116.549594)
			(xy 182.885758 -116.60156) (xy 182.885756 -116.601573) (xy 183.025544 -116.601573) (xy 183.025544 -116.549599)
			(xy 183.033674 -116.498264) (xy 183.049735 -116.448834) (xy 183.073331 -116.402524) (xy 183.103881 -116.360476)
			(xy 183.140632 -116.323725) (xy 183.18268 -116.293175) (xy 183.22899 -116.269579) (xy 183.27842 -116.253518)
			(xy 183.329755 -116.245388) (xy 183.381729 -116.245388) (xy 183.433064 -116.253518) (xy 183.482494 -116.269579)
			(xy 183.528804 -116.293175) (xy 183.570852 -116.323725) (xy 183.607603 -116.360476) (xy 183.638153 -116.402524)
			(xy 183.661749 -116.448834) (xy 183.67781 -116.498264) (xy 183.68594 -116.549599) (xy 183.68645 -116.575586)
			(xy 183.68594 -116.601573) (xy 183.82539 -116.601573) (xy 183.82539 -116.549599) (xy 183.83352 -116.498264)
			(xy 183.849581 -116.448834) (xy 183.873177 -116.402524) (xy 183.903727 -116.360476) (xy 183.940478 -116.323725)
			(xy 183.982526 -116.293175) (xy 184.028836 -116.269579) (xy 184.078266 -116.253518) (xy 184.129601 -116.245388)
			(xy 184.181575 -116.245388) (xy 184.23291 -116.253518) (xy 184.28234 -116.269579) (xy 184.32865 -116.293175)
			(xy 184.370698 -116.323725) (xy 184.407449 -116.360476) (xy 184.437999 -116.402524) (xy 184.461595 -116.448834)
			(xy 184.477656 -116.498264) (xy 184.485786 -116.549599) (xy 184.486296 -116.575586) (xy 184.485786 -116.601573)
			(xy 184.62549 -116.601573) (xy 184.62549 -116.549599) (xy 184.63362 -116.498264) (xy 184.649681 -116.448834)
			(xy 184.673277 -116.402524) (xy 184.703827 -116.360476) (xy 184.740578 -116.323725) (xy 184.782626 -116.293175)
			(xy 184.828936 -116.269579) (xy 184.878366 -116.253518) (xy 184.929701 -116.245388) (xy 184.981675 -116.245388)
			(xy 185.03301 -116.253518) (xy 185.08244 -116.269579) (xy 185.12875 -116.293175) (xy 185.170798 -116.323725)
			(xy 185.207549 -116.360476) (xy 185.238099 -116.402524) (xy 185.261695 -116.448834) (xy 185.277756 -116.498264)
			(xy 185.285886 -116.549599) (xy 185.286396 -116.575586) (xy 185.285886 -116.601573) (xy 185.42559 -116.601573)
			(xy 185.42559 -116.549599) (xy 185.43372 -116.498264) (xy 185.449781 -116.448834) (xy 185.473377 -116.402524)
			(xy 185.503927 -116.360476) (xy 185.540678 -116.323725) (xy 185.582726 -116.293175) (xy 185.629036 -116.269579)
			(xy 185.678466 -116.253518) (xy 185.729801 -116.245388) (xy 185.781775 -116.245388) (xy 185.83311 -116.253518)
			(xy 185.88254 -116.269579) (xy 185.92885 -116.293175) (xy 185.970898 -116.323725) (xy 186.007649 -116.360476)
			(xy 186.038199 -116.402524) (xy 186.061795 -116.448834) (xy 186.077856 -116.498264) (xy 186.085986 -116.549599)
			(xy 186.086496 -116.575586) (xy 186.085986 -116.601573) (xy 186.225436 -116.601573) (xy 186.225436 -116.549599)
			(xy 186.233566 -116.498264) (xy 186.249627 -116.448834) (xy 186.273223 -116.402524) (xy 186.303773 -116.360476)
			(xy 186.340524 -116.323725) (xy 186.382572 -116.293175) (xy 186.428882 -116.269579) (xy 186.478312 -116.253518)
			(xy 186.529647 -116.245388) (xy 186.581621 -116.245388) (xy 186.632956 -116.253518) (xy 186.682386 -116.269579)
			(xy 186.728696 -116.293175) (xy 186.770744 -116.323725) (xy 186.807495 -116.360476) (xy 186.838045 -116.402524)
			(xy 186.861641 -116.448834) (xy 186.877702 -116.498264) (xy 186.885832 -116.549599) (xy 186.886342 -116.575586)
			(xy 186.885832 -116.601573) (xy 186.877702 -116.652908) (xy 186.861641 -116.702338) (xy 186.838045 -116.748648)
			(xy 186.807495 -116.790696) (xy 186.770744 -116.827447) (xy 186.728696 -116.857997) (xy 186.682386 -116.881593)
			(xy 186.632956 -116.897654) (xy 186.581621 -116.905784) (xy 186.529647 -116.905784) (xy 186.478312 -116.897654)
			(xy 186.428882 -116.881593) (xy 186.382572 -116.857997) (xy 186.340524 -116.827447) (xy 186.303773 -116.790696)
			(xy 186.273223 -116.748648) (xy 186.249627 -116.702338) (xy 186.233566 -116.652908) (xy 186.225436 -116.601573)
			(xy 186.085986 -116.601573) (xy 186.077856 -116.652908) (xy 186.061795 -116.702338) (xy 186.038199 -116.748648)
			(xy 186.007649 -116.790696) (xy 185.970898 -116.827447) (xy 185.92885 -116.857997) (xy 185.88254 -116.881593)
			(xy 185.83311 -116.897654) (xy 185.781775 -116.905784) (xy 185.729801 -116.905784) (xy 185.678466 -116.897654)
			(xy 185.629036 -116.881593) (xy 185.582726 -116.857997) (xy 185.540678 -116.827447) (xy 185.503927 -116.790696)
			(xy 185.473377 -116.748648) (xy 185.449781 -116.702338) (xy 185.43372 -116.652908) (xy 185.42559 -116.601573)
			(xy 185.285886 -116.601573) (xy 185.277756 -116.652908) (xy 185.261695 -116.702338) (xy 185.238099 -116.748648)
			(xy 185.207549 -116.790696) (xy 185.170798 -116.827447) (xy 185.12875 -116.857997) (xy 185.08244 -116.881593)
			(xy 185.03301 -116.897654) (xy 184.981675 -116.905784) (xy 184.929701 -116.905784) (xy 184.878366 -116.897654)
			(xy 184.828936 -116.881593) (xy 184.782626 -116.857997) (xy 184.740578 -116.827447) (xy 184.703827 -116.790696)
			(xy 184.673277 -116.748648) (xy 184.649681 -116.702338) (xy 184.63362 -116.652908) (xy 184.62549 -116.601573)
			(xy 184.485786 -116.601573) (xy 184.477656 -116.652908) (xy 184.461595 -116.702338) (xy 184.437999 -116.748648)
			(xy 184.407449 -116.790696) (xy 184.370698 -116.827447) (xy 184.32865 -116.857997) (xy 184.28234 -116.881593)
			(xy 184.23291 -116.897654) (xy 184.181575 -116.905784) (xy 184.129601 -116.905784) (xy 184.078266 -116.897654)
			(xy 184.028836 -116.881593) (xy 183.982526 -116.857997) (xy 183.940478 -116.827447) (xy 183.903727 -116.790696)
			(xy 183.873177 -116.748648) (xy 183.849581 -116.702338) (xy 183.83352 -116.652908) (xy 183.82539 -116.601573)
			(xy 183.68594 -116.601573) (xy 183.67781 -116.652908) (xy 183.661749 -116.702338) (xy 183.638153 -116.748648)
			(xy 183.607603 -116.790696) (xy 183.570852 -116.827447) (xy 183.528804 -116.857997) (xy 183.482494 -116.881593)
			(xy 183.433064 -116.897654) (xy 183.381729 -116.905784) (xy 183.329755 -116.905784) (xy 183.27842 -116.897654)
			(xy 183.22899 -116.881593) (xy 183.18268 -116.857997) (xy 183.140632 -116.827447) (xy 183.103881 -116.790696)
			(xy 183.073331 -116.748648) (xy 183.049735 -116.702338) (xy 183.033674 -116.652908) (xy 183.025544 -116.601573)
			(xy 182.885756 -116.601573) (xy 182.877633 -116.652886) (xy 182.861578 -116.70231) (xy 182.83799 -116.748614)
			(xy 182.80745 -116.790658) (xy 182.770708 -116.827407) (xy 182.72867 -116.857956) (xy 182.68237 -116.881553)
			(xy 182.63295 -116.897617) (xy 182.581625 -116.905753) (xy 182.555642 -116.906294) (xy 182.538116 -116.905786)
			(xy 182.527695 -116.905688) (xy 182.508148 -116.912854) (xy 182.493063 -116.927203) (xy 182.484927 -116.946367)
			(xy 182.485083 -116.967185) (xy 182.48884 -116.976906) (xy 182.496127 -116.994077) (xy 182.507584 -117.029578)
			(xy 182.5117 -117.047772) (xy 182.522632 -117.046375) (xy 182.544621 -117.04485) (xy 182.555642 -117.044724)
			(xy 182.581096 -117.045188) (xy 182.631402 -117.052984) (xy 182.679919 -117.068399) (xy 182.7255 -117.09107)
			(xy 182.767066 -117.120461) (xy 182.803635 -117.155876) (xy 182.834342 -117.196479) (xy 182.858462 -117.241309)
			(xy 182.875425 -117.289307) (xy 182.884828 -117.339338) (xy 182.886096 -117.364764) (xy 182.887874 -117.41404)
			(xy 183.02351 -117.41404) (xy 183.025288 -117.364764) (xy 183.026581 -117.339343) (xy 183.036006 -117.289325)
			(xy 183.052982 -117.24134) (xy 183.077107 -117.196523) (xy 183.107813 -117.155929) (xy 183.144375 -117.120519)
			(xy 183.18593 -117.091127) (xy 183.231496 -117.068447) (xy 183.279999 -117.053014) (xy 183.330293 -117.045193)
			(xy 183.355742 -117.044724) (xy 183.381726 -117.045237) (xy 183.433054 -117.053373) (xy 183.482477 -117.069438)
			(xy 183.528778 -117.093036) (xy 183.570818 -117.123587) (xy 183.607561 -117.160339) (xy 183.638102 -117.202385)
			(xy 183.661691 -117.248692) (xy 183.677745 -117.298118) (xy 183.685869 -117.349448) (xy 183.68645 -117.375432)
			(xy 183.686152 -117.39427) (xy 183.681822 -117.431699) (xy 183.677814 -117.450108) (xy 183.69725 -117.459741)
			(xy 183.733923 -117.482915) (xy 183.750966 -117.496336) (xy 183.759429 -117.50256) (xy 183.779646 -117.508186)
			(xy 183.800425 -117.505246) (xy 183.818287 -117.494231) (xy 183.830243 -117.476985) (xy 183.834293 -117.456394)
			(xy 183.8325 -117.446044) (xy 183.828931 -117.428609) (xy 183.825109 -117.393226) (xy 183.82488 -117.375432)
			(xy 183.82539 -117.349445) (xy 183.83352 -117.29811) (xy 183.849581 -117.24868) (xy 183.873177 -117.20237)
			(xy 183.903727 -117.160322) (xy 183.940478 -117.123571) (xy 183.982526 -117.093021) (xy 184.028836 -117.069425)
			(xy 184.078266 -117.053364) (xy 184.129601 -117.045234) (xy 184.181575 -117.045234) (xy 184.23291 -117.053364)
			(xy 184.28234 -117.069425) (xy 184.32865 -117.093021) (xy 184.370698 -117.123571) (xy 184.407449 -117.160322)
			(xy 184.437999 -117.20237) (xy 184.461595 -117.24868) (xy 184.477656 -117.29811) (xy 184.485786 -117.349445)
			(xy 184.486296 -117.375432) (xy 184.485839 -117.400089) (xy 184.478516 -117.448855) (xy 184.464036 -117.495995)
			(xy 184.442721 -117.540463) (xy 184.415043 -117.581276) (xy 184.398666 -117.599714) (xy 184.389041 -117.610885)
			(xy 184.37608 -117.637356) (xy 184.37121 -117.666424) (xy 184.374838 -117.695674) (xy 184.386661 -117.722673)
			(xy 184.405697 -117.745175) (xy 184.430362 -117.76131) (xy 184.458605 -117.769736) (xy 184.473342 -117.770148)
		)
		(stroke
			(width 0)
			(type solid)
		)
		(fill yes)
		(layer "In4.Cu")
		(net "P3V3_AUX_FPGA_VCCIO2")
	)
	(gr_poly
		(pts
			(xy 170.34256 -117.922548) (xy 170.362569 -117.906349) (xy 170.406615 -117.879701) (xy 170.454256 -117.860194)
			(xy 170.504342 -117.848298) (xy 170.555666 -117.8443) (xy 170.60699 -117.848298) (xy 170.657076 -117.860194)
			(xy 170.704717 -117.879701) (xy 170.748763 -117.906349) (xy 170.768772 -117.922548) (xy 171.142406 -117.922548)
			(xy 171.162415 -117.906349) (xy 171.206461 -117.879701) (xy 171.254102 -117.860194) (xy 171.304188 -117.848298)
			(xy 171.355512 -117.8443) (xy 171.406836 -117.848298) (xy 171.456922 -117.860194) (xy 171.504563 -117.879701)
			(xy 171.548609 -117.906349) (xy 171.568618 -117.922548) (xy 171.942506 -117.922548) (xy 171.962515 -117.906349)
			(xy 172.006561 -117.879701) (xy 172.054202 -117.860194) (xy 172.104288 -117.848298) (xy 172.155612 -117.8443)
			(xy 172.206936 -117.848298) (xy 172.257022 -117.860194) (xy 172.304663 -117.879701) (xy 172.348709 -117.906349)
			(xy 172.368718 -117.922548) (xy 172.917358 -117.922548) (xy 172.964856 -117.87505) (xy 172.974508 -117.864784)
			(xy 172.988261 -117.840203) (xy 172.994776 -117.8128) (xy 172.99356 -117.784659) (xy 172.984702 -117.757921)
			(xy 172.968879 -117.734618) (xy 172.947292 -117.716524) (xy 172.921584 -117.705014) (xy 172.907706 -117.702584)
			(xy 172.881863 -117.698282) (xy 172.831879 -117.682591) (xy 172.784994 -117.659218) (xy 172.742379 -117.628747)
			(xy 172.705099 -117.59194) (xy 172.674086 -117.549718) (xy 172.650117 -117.503135) (xy 172.633789 -117.453356)
			(xy 172.625511 -117.401626) (xy 172.625004 -117.375432) (xy 172.625485 -117.349441) (xy 172.633612 -117.2981)
			(xy 172.649672 -117.248662) (xy 172.673268 -117.202345) (xy 172.70382 -117.16029) (xy 172.740575 -117.123533)
			(xy 172.782628 -117.092978) (xy 172.828943 -117.069379) (xy 172.87838 -117.053317) (xy 172.929721 -117.045186)
			(xy 172.955712 -117.044724) (xy 172.981911 -117.045218) (xy 173.033655 -117.05347) (xy 173.08345 -117.069781)
			(xy 173.130047 -117.093744) (xy 173.172282 -117.124757) (xy 173.209094 -117.162044) (xy 173.239564 -117.204672)
			(xy 173.262928 -117.251573) (xy 173.278601 -117.301572) (xy 173.282864 -117.327426) (xy 173.285318 -117.341303)
			(xy 173.296797 -117.367027) (xy 173.314876 -117.388629) (xy 173.338175 -117.404462) (xy 173.364916 -117.413318)
			(xy 173.39306 -117.41452) (xy 173.420459 -117.407978) (xy 173.445023 -117.39419) (xy 173.45533 -117.384576)
			(xy 173.764702 -117.075204) (xy 173.774343 -117.064937) (xy 173.788077 -117.04036) (xy 173.79458 -117.012967)
			(xy 173.793356 -116.98484) (xy 173.784499 -116.958115) (xy 173.768683 -116.934823) (xy 173.747109 -116.916735)
			(xy 173.721416 -116.905223) (xy 173.707552 -116.902738) (xy 173.681708 -116.898439) (xy 173.631722 -116.882752)
			(xy 173.584834 -116.859381) (xy 173.542217 -116.828911) (xy 173.504936 -116.792104) (xy 173.473924 -116.749879)
			(xy 173.449956 -116.703294) (xy 173.433632 -116.653513) (xy 173.425359 -116.601781) (xy 173.42485 -116.575586)
			(xy 173.42536 -116.549599) (xy 173.43349 -116.498264) (xy 173.449551 -116.448834) (xy 173.473147 -116.402524)
			(xy 173.503697 -116.360476) (xy 173.540448 -116.323725) (xy 173.582496 -116.293175) (xy 173.628806 -116.269579)
			(xy 173.678236 -116.253518) (xy 173.729571 -116.245388) (xy 173.781545 -116.245388) (xy 173.83288 -116.253518)
			(xy 173.88231 -116.269579) (xy 173.92862 -116.293175) (xy 173.970668 -116.323725) (xy 174.007419 -116.360476)
			(xy 174.037969 -116.402524) (xy 174.061565 -116.448834) (xy 174.077626 -116.498264) (xy 174.085756 -116.549599)
			(xy 174.086266 -116.575586) (xy 174.086101 -116.58969) (xy 174.083683 -116.617794) (xy 174.08144 -116.63172)
			(xy 174.080107 -116.641936) (xy 174.084759 -116.661986) (xy 174.096916 -116.678595) (xy 174.114622 -116.68909)
			(xy 174.135028 -116.691782) (xy 174.15485 -116.686238) (xy 174.163228 -116.680234) (xy 174.179071 -116.667988)
			(xy 174.212925 -116.646601) (xy 174.230792 -116.637562) (xy 174.228049 -116.622215) (xy 174.225127 -116.591175)
			(xy 174.22495 -116.575586) (xy 174.225461 -116.549598) (xy 174.233593 -116.498263) (xy 174.249654 -116.448832)
			(xy 174.27325 -116.402521) (xy 174.303799 -116.360471) (xy 174.34055 -116.323718) (xy 174.382597 -116.293165)
			(xy 174.428906 -116.269565) (xy 174.478336 -116.253499) (xy 174.52967 -116.245363) (xy 174.555658 -116.244878)
			(xy 174.571443 -116.245092) (xy 174.602865 -116.248146) (xy 174.618396 -116.250974) (xy 174.627345 -116.232978)
			(xy 174.6486 -116.198863) (xy 174.660814 -116.182902) (xy 174.666808 -116.174574) (xy 174.672224 -116.1548)
			(xy 174.66947 -116.134485) (xy 174.658986 -116.116867) (xy 174.642443 -116.104757) (xy 174.622481 -116.100085)
			(xy 174.6123 -116.101368) (xy 174.598251 -116.103648) (xy 174.56989 -116.106062) (xy 174.555658 -116.106194)
			(xy 174.529674 -116.105681) (xy 174.478347 -116.097546) (xy 174.428924 -116.081482) (xy 174.382622 -116.057885)
			(xy 174.340582 -116.027336) (xy 174.303837 -115.990586) (xy 174.273293 -115.948542) (xy 174.249702 -115.902237)
			(xy 174.233644 -115.852812) (xy 174.225515 -115.801484) (xy 174.225515 -115.749516) (xy 174.233644 -115.698188)
			(xy 174.249702 -115.648763) (xy 174.273293 -115.602458) (xy 174.303837 -115.560414) (xy 174.340582 -115.523664)
			(xy 174.382622 -115.493115) (xy 174.428924 -115.469518) (xy 174.478347 -115.453454) (xy 174.529674 -115.445319)
			(xy 174.555658 -115.444778) (xy 174.580631 -115.445238) (xy 174.630009 -115.452752) (xy 174.677697 -115.467602)
			(xy 174.722612 -115.48945) (xy 174.763733 -115.5178) (xy 174.800127 -115.552007) (xy 174.830967 -115.591295)
			(xy 174.855552 -115.634772) (xy 174.873324 -115.681449) (xy 174.88388 -115.730268) (xy 174.885858 -115.755166)
			(xy 174.887168 -115.769258) (xy 174.896555 -115.795945) (xy 174.912915 -115.819024) (xy 174.934987 -115.836719)
			(xy 174.961073 -115.847667) (xy 174.989163 -115.851024) (xy 175.017094 -115.846533) (xy 175.03013 -115.841018)
			(xy 175.054695 -115.830045) (xy 175.106214 -115.814543) (xy 175.15944 -115.806705) (xy 175.18634 -115.80622)
			(xy 175.74768 -115.80622) (xy 175.74768 -115.295426) (xy 175.747195 -115.280735) (xy 175.738839 -115.252566)
			(xy 175.722811 -115.227941) (xy 175.700437 -115.208896) (xy 175.673567 -115.197008) (xy 175.644425 -115.19326)
			(xy 175.615422 -115.197962) (xy 175.588956 -115.210725) (xy 175.577754 -115.220242) (xy 175.559404 -115.236307)
			(xy 175.518868 -115.263423) (xy 175.474791 -115.284295) (xy 175.428127 -115.298472) (xy 175.379889 -115.305646)
			(xy 175.355504 -115.306094) (xy 175.329516 -115.305611) (xy 175.278179 -115.297481) (xy 175.228746 -115.28142)
			(xy 175.182434 -115.257823) (xy 175.140384 -115.227272) (xy 175.10363 -115.190519) (xy 175.073079 -115.148469)
			(xy 175.049482 -115.102158) (xy 175.03342 -115.052725) (xy 175.025289 -115.001388) (xy 175.025289 -114.949412)
			(xy 175.03342 -114.898075) (xy 175.049482 -114.848642) (xy 175.073079 -114.802331) (xy 175.10363 -114.760281)
			(xy 175.140384 -114.723528) (xy 175.182434 -114.692977) (xy 175.228746 -114.66938) (xy 175.278179 -114.653319)
			(xy 175.329516 -114.645189) (xy 175.355504 -114.644678) (xy 175.379889 -114.645114) (xy 175.42813 -114.652282)
			(xy 175.474794 -114.66646) (xy 175.518868 -114.687342) (xy 175.559395 -114.714474) (xy 175.577754 -114.73053)
			(xy 175.588956 -114.740049) (xy 175.615428 -114.752804) (xy 175.644435 -114.757501) (xy 175.673579 -114.753751)
			(xy 175.700453 -114.741865) (xy 175.722834 -114.722825) (xy 175.738874 -114.698205) (xy 175.747246 -114.670038)
			(xy 175.74768 -114.655346) (xy 175.74768 -112.095534) (xy 175.747196 -112.080842) (xy 175.738842 -112.052671)
			(xy 175.722814 -112.028044) (xy 175.700439 -112.008998) (xy 175.673568 -111.997109) (xy 175.644424 -111.99336)
			(xy 175.615419 -111.998063) (xy 175.588952 -112.010827) (xy 175.577754 -112.02035) (xy 175.559404 -112.036414)
			(xy 175.518868 -112.06353) (xy 175.47479 -112.084402) (xy 175.428127 -112.098578) (xy 175.379888 -112.105752)
			(xy 175.355504 -112.106202) (xy 175.329515 -112.105719) (xy 175.278177 -112.097589) (xy 175.228743 -112.081527)
			(xy 175.18243 -112.05793) (xy 175.140379 -112.027378) (xy 175.103624 -111.990625) (xy 175.073072 -111.948574)
			(xy 175.049475 -111.902261) (xy 175.033412 -111.852827) (xy 175.025281 -111.801489) (xy 175.025281 -111.749511)
			(xy 175.033412 -111.698173) (xy 175.049475 -111.648739) (xy 175.073072 -111.602426) (xy 175.103624 -111.560375)
			(xy 175.140379 -111.523622) (xy 175.18243 -111.49307) (xy 175.228743 -111.469473) (xy 175.278177 -111.453411)
			(xy 175.329515 -111.445281) (xy 175.355504 -111.444786) (xy 175.379889 -111.445222) (xy 175.42813 -111.45239)
			(xy 175.474794 -111.466569) (xy 175.518868 -111.487451) (xy 175.559394 -111.514583) (xy 175.577754 -111.530638)
			(xy 175.588957 -111.540156) (xy 175.615429 -111.55291) (xy 175.644436 -111.557607) (xy 175.67358 -111.553857)
			(xy 175.700454 -111.541971) (xy 175.722836 -111.522932) (xy 175.738877 -111.498312) (xy 175.747251 -111.470146)
			(xy 175.74768 -111.455454) (xy 175.74768 -110.886748) (xy 175.367442 -110.50651) (xy 175.347122 -110.506002)
			(xy 175.321985 -110.504896) (xy 175.272461 -110.49602) (xy 175.224852 -110.479746) (xy 175.180257 -110.456452)
			(xy 175.139703 -110.426672) (xy 175.104126 -110.391095) (xy 175.074347 -110.350541) (xy 175.051053 -110.305946)
			(xy 175.03478 -110.258337) (xy 175.025904 -110.208813) (xy 175.024796 -110.183676) (xy 175.024288 -110.163356)
			(xy 174.93615 -110.075218) (xy 174.883826 -110.127542) (xy 174.88535 -110.150656) (xy 174.886366 -110.175294)
			(xy 174.885857 -110.201277) (xy 174.877728 -110.252604) (xy 174.861671 -110.302028) (xy 174.83808 -110.348331)
			(xy 174.807536 -110.390374) (xy 174.770792 -110.427121) (xy 174.728751 -110.457668) (xy 174.68245 -110.481262)
			(xy 174.633028 -110.497323) (xy 174.581701 -110.505455) (xy 174.529735 -110.505458) (xy 174.478408 -110.497331)
			(xy 174.428983 -110.481276) (xy 174.382679 -110.457686) (xy 174.340636 -110.427144) (xy 174.303887 -110.390401)
			(xy 174.273339 -110.348362) (xy 174.249743 -110.302061) (xy 174.23368 -110.252639) (xy 174.225546 -110.201313)
			(xy 174.225542 -110.149347) (xy 174.233666 -110.098019) (xy 174.24972 -110.048595) (xy 174.273307 -110.00229)
			(xy 174.303848 -109.960245) (xy 174.34059 -109.923495) (xy 174.382628 -109.892945) (xy 174.428928 -109.869347)
			(xy 174.478349 -109.853283) (xy 174.529675 -109.845147) (xy 174.555658 -109.844586) (xy 174.580296 -109.845602)
			(xy 174.60341 -109.847126) (xy 174.655734 -109.794802) (xy 174.567596 -109.706664) (xy 174.547276 -109.706156)
			(xy 174.52214 -109.705046) (xy 174.472618 -109.696165) (xy 174.425012 -109.679889) (xy 174.380419 -109.656593)
			(xy 174.339866 -109.626814) (xy 174.30429 -109.591238) (xy 174.27451 -109.550687) (xy 174.251213 -109.506094)
			(xy 174.234936 -109.458488) (xy 174.226054 -109.408966) (xy 174.22495 -109.38383) (xy 174.224442 -109.36351)
			(xy 174.13605 -109.275118) (xy 174.083472 -109.327442) (xy 174.08525 -109.35081) (xy 174.086266 -109.375448)
			(xy 174.085752 -109.40143) (xy 174.077616 -109.452754) (xy 174.061552 -109.502173) (xy 174.037955 -109.548472)
			(xy 174.007407 -109.590509) (xy 173.970658 -109.627249) (xy 173.928615 -109.65779) (xy 173.882312 -109.681377)
			(xy 173.83289 -109.697432) (xy 173.781564 -109.705558) (xy 173.7296 -109.705555) (xy 173.678275 -109.697423)
			(xy 173.628854 -109.681364) (xy 173.582554 -109.657771) (xy 173.540514 -109.627226) (xy 173.50377 -109.590481)
			(xy 173.473226 -109.548441) (xy 173.449634 -109.50214) (xy 173.433575 -109.452719) (xy 173.425445 -109.401394)
			(xy 173.425443 -109.34943) (xy 173.43357 -109.298104) (xy 173.449625 -109.248682) (xy 173.473213 -109.20238)
			(xy 173.503754 -109.160337) (xy 173.540496 -109.12359) (xy 173.582534 -109.093042) (xy 173.628832 -109.069446)
			(xy 173.678252 -109.053382) (xy 173.729576 -109.045247) (xy 173.755558 -109.04474) (xy 173.780196 -109.045756)
			(xy 173.803564 -109.047534) (xy 173.855888 -108.994956) (xy 173.767496 -108.906564) (xy 173.747176 -108.906056)
			(xy 173.72204 -108.904946) (xy 173.672518 -108.896065) (xy 173.624912 -108.879789) (xy 173.580319 -108.856493)
			(xy 173.539766 -108.826714) (xy 173.50419 -108.791138) (xy 173.47441 -108.750587) (xy 173.451113 -108.705994)
			(xy 173.434836 -108.658388) (xy 173.425954 -108.608866) (xy 173.42485 -108.58373) (xy 173.424342 -108.56341)
			(xy 173.336204 -108.475272) (xy 173.28388 -108.527596) (xy 173.285404 -108.55071) (xy 173.28642 -108.575348)
			(xy 173.285907 -108.601335) (xy 173.277769 -108.652669) (xy 173.261701 -108.702098) (xy 173.238098 -108.748405)
			(xy 173.207543 -108.79045) (xy 173.170786 -108.827197) (xy 173.128734 -108.857742) (xy 173.082421 -108.881333)
			(xy 173.032988 -108.897388) (xy 172.981652 -108.905513) (xy 172.929677 -108.905508) (xy 172.878342 -108.897372)
			(xy 172.828913 -108.881305) (xy 172.782605 -108.857705) (xy 172.740559 -108.827151) (xy 172.70381 -108.790395)
			(xy 172.673264 -108.748344) (xy 172.649672 -108.702032) (xy 172.633614 -108.652599) (xy 172.625488 -108.601264)
			(xy 172.625491 -108.549289) (xy 172.633626 -108.497954) (xy 172.64969 -108.448524) (xy 172.673289 -108.402215)
			(xy 172.703842 -108.360168) (xy 172.740596 -108.323418) (xy 172.782646 -108.29287) (xy 172.828957 -108.269276)
			(xy 172.878389 -108.253217) (xy 172.929724 -108.245089) (xy 172.955712 -108.24464) (xy 172.98035 -108.245656)
			(xy 173.003464 -108.24718) (xy 173.055788 -108.194856) (xy 172.96765 -108.106718) (xy 172.94733 -108.10621)
			(xy 172.921773 -108.105092) (xy 172.871443 -108.095952) (xy 172.823122 -108.079168) (xy 172.777962 -108.055142)
			(xy 172.737041 -108.024447) (xy 172.701336 -107.987816) (xy 172.6717 -107.946123) (xy 172.648838 -107.900362)
			(xy 172.633298 -107.851627) (xy 172.62545 -107.801079) (xy 172.625004 -107.775502) (xy 172.625496 -107.750154)
			(xy 172.633249 -107.700055) (xy 172.648557 -107.651725) (xy 172.671062 -107.606298) (xy 172.700237 -107.564839)
			(xy 172.735397 -107.528317) (xy 172.77572 -107.497591) (xy 172.820261 -107.473378) (xy 172.843952 -107.464352)
			(xy 172.87748 -107.45216) (xy 172.87748 -107.298744) (xy 172.843952 -107.286552) (xy 172.820241 -107.277562)
			(xy 172.775681 -107.25336) (xy 172.73534 -107.222637) (xy 172.700165 -107.186114) (xy 172.67098 -107.144647)
			(xy 172.648469 -107.09921) (xy 172.633163 -107.050867) (xy 172.625419 -107.000755) (xy 172.625418 -106.950047)
			(xy 172.633163 -106.899934) (xy 172.648469 -106.851591) (xy 172.670979 -106.806154) (xy 172.700164 -106.764687)
			(xy 172.735339 -106.728163) (xy 172.77568 -106.697441) (xy 172.82024 -106.673239) (xy 172.843952 -106.664252)
			(xy 172.87748 -106.65206) (xy 172.87748 -106.498644) (xy 172.843952 -106.486452) (xy 172.820241 -106.477462)
			(xy 172.775681 -106.45326) (xy 172.73534 -106.422537) (xy 172.700165 -106.386014) (xy 172.67098 -106.344547)
			(xy 172.648469 -106.29911) (xy 172.633163 -106.250767) (xy 172.625419 -106.200655) (xy 172.625418 -106.149947)
			(xy 172.633163 -106.099834) (xy 172.648469 -106.051491) (xy 172.670979 -106.006054) (xy 172.700164 -105.964587)
			(xy 172.735339 -105.928063) (xy 172.77568 -105.897341) (xy 172.82024 -105.873139) (xy 172.843952 -105.864152)
			(xy 172.87748 -105.85196) (xy 172.87748 -105.698798) (xy 172.843952 -105.686606) (xy 172.820245 -105.677616)
			(xy 172.775692 -105.653415) (xy 172.735358 -105.622695) (xy 172.700188 -105.586175) (xy 172.671009 -105.544712)
			(xy 172.648504 -105.499279) (xy 172.633201 -105.450942) (xy 172.625461 -105.400836) (xy 172.625463 -105.350135)
			(xy 172.633208 -105.300029) (xy 172.648515 -105.251693) (xy 172.671024 -105.206263) (xy 172.700207 -105.164802)
			(xy 172.73538 -105.128285) (xy 172.775717 -105.097568) (xy 172.820272 -105.073372) (xy 172.843952 -105.064306)
			(xy 172.87748 -105.052114) (xy 172.87748 -101.310948) (xy 172.671994 -101.105716) (xy 171.849542 -101.105716)
			(xy 171.835947 -101.106142) (xy 171.809719 -101.11331) (xy 171.786315 -101.127149) (xy 171.767395 -101.146676)
			(xy 171.754302 -101.170505) (xy 171.747965 -101.196946) (xy 171.748834 -101.224121) (xy 171.756848 -101.250103)
			(xy 171.771437 -101.273047) (xy 171.781216 -101.2825) (xy 171.800557 -101.300651) (xy 171.834536 -101.341377)
			(xy 171.862546 -101.386418) (xy 171.884046 -101.434905) (xy 171.898621 -101.485903) (xy 171.90599 -101.538428)
			(xy 171.906438 -101.564948) (xy 171.905952 -101.592199) (xy 171.898196 -101.646147) (xy 171.882841 -101.698442)
			(xy 171.860199 -101.748019) (xy 171.830733 -101.793869) (xy 171.795042 -101.83506) (xy 171.753851 -101.870751)
			(xy 171.708001 -101.900217) (xy 171.658424 -101.922859) (xy 171.606129 -101.938214) (xy 171.552181 -101.94597)
			(xy 171.497679 -101.94597) (xy 171.443731 -101.938214) (xy 171.391436 -101.922859) (xy 171.341859 -101.900217)
			(xy 171.296009 -101.870751) (xy 171.254818 -101.83506) (xy 171.219127 -101.793869) (xy 171.189661 -101.748019)
			(xy 171.167019 -101.698442) (xy 171.151664 -101.646147) (xy 171.143908 -101.592199) (xy 171.143422 -101.564948)
			(xy 171.143876 -101.538427) (xy 171.151226 -101.485896) (xy 171.165789 -101.434892) (xy 171.187286 -101.3864)
			(xy 171.2153 -101.341359) (xy 171.249289 -101.300638) (xy 171.268644 -101.2825) (xy 171.278413 -101.273038)
			(xy 171.292993 -101.250092) (xy 171.301001 -101.224111) (xy 171.301867 -101.196938) (xy 171.295531 -101.1705)
			(xy 171.282443 -101.146672) (xy 171.26353 -101.127142) (xy 171.240133 -101.113297) (xy 171.213911 -101.106117)
			(xy 171.200318 -101.105716) (xy 169.374566 -101.105716) (xy 169.19448 -101.285548) (xy 169.19448 -102.707948)
			(xy 171.650912 -102.707948) (xy 171.654983 -102.652326) (xy 171.667109 -102.597889) (xy 171.687032 -102.545798)
			(xy 171.714328 -102.497163) (xy 171.748414 -102.45302) (xy 171.788563 -102.414311) (xy 171.833921 -102.38186)
			(xy 171.883521 -102.356359) (xy 171.936305 -102.338352) (xy 171.991148 -102.328222) (xy 172.046882 -102.326185)
			(xy 172.102319 -102.332285) (xy 172.156276 -102.346391) (xy 172.207605 -102.368203) (xy 172.255211 -102.397257)
			(xy 172.298079 -102.432932) (xy 172.335296 -102.474469) (xy 172.366069 -102.520982) (xy 172.389741 -102.571479)
			(xy 172.405809 -102.624886) (xy 172.413929 -102.680062) (xy 172.414438 -102.707948) (xy 172.413929 -102.735834)
			(xy 172.405809 -102.79101) (xy 172.389741 -102.844417) (xy 172.366069 -102.894914) (xy 172.335296 -102.941427)
			(xy 172.298079 -102.982964) (xy 172.255211 -103.018639) (xy 172.207605 -103.047693) (xy 172.156276 -103.069505)
			(xy 172.102319 -103.083611) (xy 172.046882 -103.089711) (xy 171.991148 -103.087674) (xy 171.936305 -103.077544)
			(xy 171.883521 -103.059537) (xy 171.833921 -103.034036) (xy 171.788563 -103.001585) (xy 171.748414 -102.962876)
			(xy 171.714328 -102.918733) (xy 171.687032 -102.870098) (xy 171.667109 -102.818007) (xy 171.654983 -102.76357)
			(xy 171.650912 -102.707948) (xy 169.19448 -102.707948) (xy 169.19448 -103.698548) (xy 171.625512 -103.698548)
			(xy 171.629583 -103.642926) (xy 171.641709 -103.588489) (xy 171.661632 -103.536398) (xy 171.688928 -103.487763)
			(xy 171.723014 -103.44362) (xy 171.763163 -103.404911) (xy 171.808521 -103.37246) (xy 171.858121 -103.346959)
			(xy 171.910905 -103.328952) (xy 171.965748 -103.318822) (xy 172.021482 -103.316785) (xy 172.076919 -103.322885)
			(xy 172.130876 -103.336991) (xy 172.182205 -103.358803) (xy 172.229811 -103.387857) (xy 172.272679 -103.423532)
			(xy 172.309896 -103.465069) (xy 172.340669 -103.511582) (xy 172.364341 -103.562079) (xy 172.380409 -103.615486)
			(xy 172.388529 -103.670662) (xy 172.389038 -103.698548) (xy 172.388529 -103.726434) (xy 172.380409 -103.78161)
			(xy 172.364341 -103.835017) (xy 172.340669 -103.885514) (xy 172.309896 -103.932027) (xy 172.272679 -103.973564)
			(xy 172.229811 -104.009239) (xy 172.182205 -104.038293) (xy 172.130876 -104.060105) (xy 172.076919 -104.074211)
			(xy 172.021482 -104.080311) (xy 171.965748 -104.078274) (xy 171.910905 -104.068144) (xy 171.858121 -104.050137)
			(xy 171.808521 -104.024636) (xy 171.763163 -103.992185) (xy 171.723014 -103.953476) (xy 171.688928 -103.909333)
			(xy 171.661632 -103.860698) (xy 171.641709 -103.808607) (xy 171.629583 -103.75417) (xy 171.625512 -103.698548)
			(xy 169.19448 -103.698548) (xy 169.19448 -104.601343) (xy 169.425368 -104.601343) (xy 169.425368 -104.549369)
			(xy 169.433498 -104.498034) (xy 169.449559 -104.448604) (xy 169.473155 -104.402294) (xy 169.503705 -104.360246)
			(xy 169.540456 -104.323495) (xy 169.582504 -104.292945) (xy 169.628814 -104.269349) (xy 169.678244 -104.253288)
			(xy 169.729579 -104.245158) (xy 169.781553 -104.245158) (xy 169.832888 -104.253288) (xy 169.882318 -104.269349)
			(xy 169.928628 -104.292945) (xy 169.970676 -104.323495) (xy 170.007427 -104.360246) (xy 170.037977 -104.402294)
			(xy 170.061573 -104.448604) (xy 170.077634 -104.498034) (xy 170.085764 -104.549369) (xy 170.086274 -104.575356)
			(xy 170.085764 -104.601343) (xy 170.077634 -104.652678) (xy 170.061573 -104.702108) (xy 170.037977 -104.748418)
			(xy 170.007427 -104.790466) (xy 169.970676 -104.827217) (xy 169.928628 -104.857767) (xy 169.882318 -104.881363)
			(xy 169.832888 -104.897424) (xy 169.781553 -104.905554) (xy 169.729579 -104.905554) (xy 169.678244 -104.897424)
			(xy 169.628814 -104.881363) (xy 169.582504 -104.857767) (xy 169.540456 -104.827217) (xy 169.503705 -104.790466)
			(xy 169.473155 -104.748418) (xy 169.449559 -104.702108) (xy 169.433498 -104.652678) (xy 169.425368 -104.601343)
			(xy 169.19448 -104.601343) (xy 169.19448 -105.401443) (xy 170.225468 -105.401443) (xy 170.225468 -105.349469)
			(xy 170.233598 -105.298134) (xy 170.249659 -105.248704) (xy 170.273255 -105.202394) (xy 170.303805 -105.160346)
			(xy 170.340556 -105.123595) (xy 170.382604 -105.093045) (xy 170.428914 -105.069449) (xy 170.478344 -105.053388)
			(xy 170.529679 -105.045258) (xy 170.581653 -105.045258) (xy 170.632988 -105.053388) (xy 170.682418 -105.069449)
			(xy 170.728728 -105.093045) (xy 170.770776 -105.123595) (xy 170.807527 -105.160346) (xy 170.838077 -105.202394)
			(xy 170.861673 -105.248704) (xy 170.877734 -105.298134) (xy 170.885864 -105.349469) (xy 170.886374 -105.375456)
			(xy 170.885864 -105.401443) (xy 171.025314 -105.401443) (xy 171.025314 -105.349469) (xy 171.033444 -105.298134)
			(xy 171.049505 -105.248704) (xy 171.073101 -105.202394) (xy 171.103651 -105.160346) (xy 171.140402 -105.123595)
			(xy 171.18245 -105.093045) (xy 171.22876 -105.069449) (xy 171.27819 -105.053388) (xy 171.329525 -105.045258)
			(xy 171.381499 -105.045258) (xy 171.432834 -105.053388) (xy 171.482264 -105.069449) (xy 171.528574 -105.093045)
			(xy 171.570622 -105.123595) (xy 171.607373 -105.160346) (xy 171.637923 -105.202394) (xy 171.661519 -105.248704)
			(xy 171.67758 -105.298134) (xy 171.68571 -105.349469) (xy 171.68622 -105.375456) (xy 171.68571 -105.401443)
			(xy 171.825414 -105.401443) (xy 171.825414 -105.349469) (xy 171.833544 -105.298134) (xy 171.849605 -105.248704)
			(xy 171.873201 -105.202394) (xy 171.903751 -105.160346) (xy 171.940502 -105.123595) (xy 171.98255 -105.093045)
			(xy 172.02886 -105.069449) (xy 172.07829 -105.053388) (xy 172.129625 -105.045258) (xy 172.181599 -105.045258)
			(xy 172.232934 -105.053388) (xy 172.282364 -105.069449) (xy 172.328674 -105.093045) (xy 172.370722 -105.123595)
			(xy 172.407473 -105.160346) (xy 172.438023 -105.202394) (xy 172.461619 -105.248704) (xy 172.47768 -105.298134)
			(xy 172.48581 -105.349469) (xy 172.48632 -105.375456) (xy 172.48581 -105.401443) (xy 172.47768 -105.452778)
			(xy 172.461619 -105.502208) (xy 172.438023 -105.548518) (xy 172.407473 -105.590566) (xy 172.370722 -105.627317)
			(xy 172.328674 -105.657867) (xy 172.282364 -105.681463) (xy 172.232934 -105.697524) (xy 172.181599 -105.705654)
			(xy 172.129625 -105.705654) (xy 172.07829 -105.697524) (xy 172.02886 -105.681463) (xy 171.98255 -105.657867)
			(xy 171.940502 -105.627317) (xy 171.903751 -105.590566) (xy 171.873201 -105.548518) (xy 171.849605 -105.502208)
			(xy 171.833544 -105.452778) (xy 171.825414 -105.401443) (xy 171.68571 -105.401443) (xy 171.67758 -105.452778)
			(xy 171.661519 -105.502208) (xy 171.637923 -105.548518) (xy 171.607373 -105.590566) (xy 171.570622 -105.627317)
			(xy 171.528574 -105.657867) (xy 171.482264 -105.681463) (xy 171.432834 -105.697524) (xy 171.381499 -105.705654)
			(xy 171.329525 -105.705654) (xy 171.27819 -105.697524) (xy 171.22876 -105.681463) (xy 171.18245 -105.657867)
			(xy 171.140402 -105.627317) (xy 171.103651 -105.590566) (xy 171.073101 -105.548518) (xy 171.049505 -105.502208)
			(xy 171.033444 -105.452778) (xy 171.025314 -105.401443) (xy 170.885864 -105.401443) (xy 170.877734 -105.452778)
			(xy 170.861673 -105.502208) (xy 170.838077 -105.548518) (xy 170.807527 -105.590566) (xy 170.770776 -105.627317)
			(xy 170.728728 -105.657867) (xy 170.682418 -105.681463) (xy 170.632988 -105.697524) (xy 170.581653 -105.705654)
			(xy 170.529679 -105.705654) (xy 170.478344 -105.697524) (xy 170.428914 -105.681463) (xy 170.382604 -105.657867)
			(xy 170.340556 -105.627317) (xy 170.303805 -105.590566) (xy 170.273255 -105.548518) (xy 170.249659 -105.502208)
			(xy 170.233598 -105.452778) (xy 170.225468 -105.401443) (xy 169.19448 -105.401443) (xy 169.19448 -106.201289)
			(xy 171.025314 -106.201289) (xy 171.025314 -106.149315) (xy 171.033444 -106.09798) (xy 171.049505 -106.04855)
			(xy 171.073101 -106.00224) (xy 171.103651 -105.960192) (xy 171.140402 -105.923441) (xy 171.18245 -105.892891)
			(xy 171.22876 -105.869295) (xy 171.27819 -105.853234) (xy 171.329525 -105.845104) (xy 171.381499 -105.845104)
			(xy 171.432834 -105.853234) (xy 171.482264 -105.869295) (xy 171.528574 -105.892891) (xy 171.570622 -105.923441)
			(xy 171.607373 -105.960192) (xy 171.637923 -106.00224) (xy 171.661519 -106.04855) (xy 171.67758 -106.09798)
			(xy 171.68571 -106.149315) (xy 171.68622 -106.175302) (xy 171.68571 -106.201289) (xy 171.825414 -106.201289)
			(xy 171.825414 -106.149315) (xy 171.833544 -106.09798) (xy 171.849605 -106.04855) (xy 171.873201 -106.00224)
			(xy 171.903751 -105.960192) (xy 171.940502 -105.923441) (xy 171.98255 -105.892891) (xy 172.02886 -105.869295)
			(xy 172.07829 -105.853234) (xy 172.129625 -105.845104) (xy 172.181599 -105.845104) (xy 172.232934 -105.853234)
			(xy 172.282364 -105.869295) (xy 172.328674 -105.892891) (xy 172.370722 -105.923441) (xy 172.407473 -105.960192)
			(xy 172.438023 -106.00224) (xy 172.461619 -106.04855) (xy 172.47768 -106.09798) (xy 172.48581 -106.149315)
			(xy 172.48632 -106.175302) (xy 172.48581 -106.201289) (xy 172.47768 -106.252624) (xy 172.461619 -106.302054)
			(xy 172.438023 -106.348364) (xy 172.407473 -106.390412) (xy 172.370722 -106.427163) (xy 172.328674 -106.457713)
			(xy 172.282364 -106.481309) (xy 172.232934 -106.49737) (xy 172.181599 -106.5055) (xy 172.129625 -106.5055)
			(xy 172.07829 -106.49737) (xy 172.02886 -106.481309) (xy 171.98255 -106.457713) (xy 171.940502 -106.427163)
			(xy 171.903751 -106.390412) (xy 171.873201 -106.348364) (xy 171.849605 -106.302054) (xy 171.833544 -106.252624)
			(xy 171.825414 -106.201289) (xy 171.68571 -106.201289) (xy 171.67758 -106.252624) (xy 171.661519 -106.302054)
			(xy 171.637923 -106.348364) (xy 171.607373 -106.390412) (xy 171.570622 -106.427163) (xy 171.528574 -106.457713)
			(xy 171.482264 -106.481309) (xy 171.432834 -106.49737) (xy 171.381499 -106.5055) (xy 171.329525 -106.5055)
			(xy 171.27819 -106.49737) (xy 171.22876 -106.481309) (xy 171.18245 -106.457713) (xy 171.140402 -106.427163)
			(xy 171.103651 -106.390412) (xy 171.073101 -106.348364) (xy 171.049505 -106.302054) (xy 171.033444 -106.252624)
			(xy 171.025314 -106.201289) (xy 169.19448 -106.201289) (xy 169.19448 -107.001389) (xy 169.425368 -107.001389)
			(xy 169.425368 -106.949415) (xy 169.433498 -106.89808) (xy 169.449559 -106.84865) (xy 169.473155 -106.80234)
			(xy 169.503705 -106.760292) (xy 169.540456 -106.723541) (xy 169.582504 -106.692991) (xy 169.628814 -106.669395)
			(xy 169.678244 -106.653334) (xy 169.729579 -106.645204) (xy 169.781553 -106.645204) (xy 169.832888 -106.653334)
			(xy 169.882318 -106.669395) (xy 169.928628 -106.692991) (xy 169.970676 -106.723541) (xy 170.007427 -106.760292)
			(xy 170.037977 -106.80234) (xy 170.061573 -106.84865) (xy 170.077634 -106.89808) (xy 170.085764 -106.949415)
			(xy 170.086274 -106.975402) (xy 170.085764 -107.001389) (xy 170.225468 -107.001389) (xy 170.225468 -106.949415)
			(xy 170.233598 -106.89808) (xy 170.249659 -106.84865) (xy 170.273255 -106.80234) (xy 170.303805 -106.760292)
			(xy 170.340556 -106.723541) (xy 170.382604 -106.692991) (xy 170.428914 -106.669395) (xy 170.478344 -106.653334)
			(xy 170.529679 -106.645204) (xy 170.581653 -106.645204) (xy 170.632988 -106.653334) (xy 170.682418 -106.669395)
			(xy 170.728728 -106.692991) (xy 170.770776 -106.723541) (xy 170.807527 -106.760292) (xy 170.838077 -106.80234)
			(xy 170.861673 -106.84865) (xy 170.877734 -106.89808) (xy 170.885864 -106.949415) (xy 170.886374 -106.975402)
			(xy 170.885864 -107.001389) (xy 171.025314 -107.001389) (xy 171.025314 -106.949415) (xy 171.033444 -106.89808)
			(xy 171.049505 -106.84865) (xy 171.073101 -106.80234) (xy 171.103651 -106.760292) (xy 171.140402 -106.723541)
			(xy 171.18245 -106.692991) (xy 171.22876 -106.669395) (xy 171.27819 -106.653334) (xy 171.329525 -106.645204)
			(xy 171.381499 -106.645204) (xy 171.432834 -106.653334) (xy 171.482264 -106.669395) (xy 171.528574 -106.692991)
			(xy 171.570622 -106.723541) (xy 171.607373 -106.760292) (xy 171.637923 -106.80234) (xy 171.661519 -106.84865)
			(xy 171.67758 -106.89808) (xy 171.68571 -106.949415) (xy 171.68622 -106.975402) (xy 171.68571 -107.001389)
			(xy 171.825414 -107.001389) (xy 171.825414 -106.949415) (xy 171.833544 -106.89808) (xy 171.849605 -106.84865)
			(xy 171.873201 -106.80234) (xy 171.903751 -106.760292) (xy 171.940502 -106.723541) (xy 171.98255 -106.692991)
			(xy 172.02886 -106.669395) (xy 172.07829 -106.653334) (xy 172.129625 -106.645204) (xy 172.181599 -106.645204)
			(xy 172.232934 -106.653334) (xy 172.282364 -106.669395) (xy 172.328674 -106.692991) (xy 172.370722 -106.723541)
			(xy 172.407473 -106.760292) (xy 172.438023 -106.80234) (xy 172.461619 -106.84865) (xy 172.47768 -106.89808)
			(xy 172.48581 -106.949415) (xy 172.48632 -106.975402) (xy 172.48581 -107.001389) (xy 172.47768 -107.052724)
			(xy 172.461619 -107.102154) (xy 172.438023 -107.148464) (xy 172.407473 -107.190512) (xy 172.370722 -107.227263)
			(xy 172.328674 -107.257813) (xy 172.282364 -107.281409) (xy 172.232934 -107.29747) (xy 172.181599 -107.3056)
			(xy 172.129625 -107.3056) (xy 172.07829 -107.29747) (xy 172.02886 -107.281409) (xy 171.98255 -107.257813)
			(xy 171.940502 -107.227263) (xy 171.903751 -107.190512) (xy 171.873201 -107.148464) (xy 171.849605 -107.102154)
			(xy 171.833544 -107.052724) (xy 171.825414 -107.001389) (xy 171.68571 -107.001389) (xy 171.67758 -107.052724)
			(xy 171.661519 -107.102154) (xy 171.637923 -107.148464) (xy 171.607373 -107.190512) (xy 171.570622 -107.227263)
			(xy 171.528574 -107.257813) (xy 171.482264 -107.281409) (xy 171.432834 -107.29747) (xy 171.381499 -107.3056)
			(xy 171.329525 -107.3056) (xy 171.27819 -107.29747) (xy 171.22876 -107.281409) (xy 171.18245 -107.257813)
			(xy 171.140402 -107.227263) (xy 171.103651 -107.190512) (xy 171.073101 -107.148464) (xy 171.049505 -107.102154)
			(xy 171.033444 -107.052724) (xy 171.025314 -107.001389) (xy 170.885864 -107.001389) (xy 170.877734 -107.052724)
			(xy 170.861673 -107.102154) (xy 170.838077 -107.148464) (xy 170.807527 -107.190512) (xy 170.770776 -107.227263)
			(xy 170.728728 -107.257813) (xy 170.682418 -107.281409) (xy 170.632988 -107.29747) (xy 170.581653 -107.3056)
			(xy 170.529679 -107.3056) (xy 170.478344 -107.29747) (xy 170.428914 -107.281409) (xy 170.382604 -107.257813)
			(xy 170.340556 -107.227263) (xy 170.303805 -107.190512) (xy 170.273255 -107.148464) (xy 170.249659 -107.102154)
			(xy 170.233598 -107.052724) (xy 170.225468 -107.001389) (xy 170.085764 -107.001389) (xy 170.077634 -107.052724)
			(xy 170.061573 -107.102154) (xy 170.037977 -107.148464) (xy 170.007427 -107.190512) (xy 169.970676 -107.227263)
			(xy 169.928628 -107.257813) (xy 169.882318 -107.281409) (xy 169.832888 -107.29747) (xy 169.781553 -107.3056)
			(xy 169.729579 -107.3056) (xy 169.678244 -107.29747) (xy 169.628814 -107.281409) (xy 169.582504 -107.257813)
			(xy 169.540456 -107.227263) (xy 169.503705 -107.190512) (xy 169.473155 -107.148464) (xy 169.449559 -107.102154)
			(xy 169.433498 -107.052724) (xy 169.425368 -107.001389) (xy 169.19448 -107.001389) (xy 169.19448 -107.801489)
			(xy 171.025314 -107.801489) (xy 171.025314 -107.749515) (xy 171.033444 -107.69818) (xy 171.049505 -107.64875)
			(xy 171.073101 -107.60244) (xy 171.103651 -107.560392) (xy 171.140402 -107.523641) (xy 171.18245 -107.493091)
			(xy 171.22876 -107.469495) (xy 171.27819 -107.453434) (xy 171.329525 -107.445304) (xy 171.381499 -107.445304)
			(xy 171.432834 -107.453434) (xy 171.482264 -107.469495) (xy 171.528574 -107.493091) (xy 171.570622 -107.523641)
			(xy 171.607373 -107.560392) (xy 171.637923 -107.60244) (xy 171.661519 -107.64875) (xy 171.67758 -107.69818)
			(xy 171.68571 -107.749515) (xy 171.68622 -107.775502) (xy 171.68571 -107.801489) (xy 171.825414 -107.801489)
			(xy 171.825414 -107.749515) (xy 171.833544 -107.69818) (xy 171.849605 -107.64875) (xy 171.873201 -107.60244)
			(xy 171.903751 -107.560392) (xy 171.940502 -107.523641) (xy 171.98255 -107.493091) (xy 172.02886 -107.469495)
			(xy 172.07829 -107.453434) (xy 172.129625 -107.445304) (xy 172.181599 -107.445304) (xy 172.232934 -107.453434)
			(xy 172.282364 -107.469495) (xy 172.328674 -107.493091) (xy 172.370722 -107.523641) (xy 172.407473 -107.560392)
			(xy 172.438023 -107.60244) (xy 172.461619 -107.64875) (xy 172.47768 -107.69818) (xy 172.48581 -107.749515)
			(xy 172.48632 -107.775502) (xy 172.48581 -107.801489) (xy 172.47768 -107.852824) (xy 172.461619 -107.902254)
			(xy 172.438023 -107.948564) (xy 172.407473 -107.990612) (xy 172.370722 -108.027363) (xy 172.328674 -108.057913)
			(xy 172.282364 -108.081509) (xy 172.232934 -108.09757) (xy 172.181599 -108.1057) (xy 172.129625 -108.1057)
			(xy 172.07829 -108.09757) (xy 172.02886 -108.081509) (xy 171.98255 -108.057913) (xy 171.940502 -108.027363)
			(xy 171.903751 -107.990612) (xy 171.873201 -107.948564) (xy 171.849605 -107.902254) (xy 171.833544 -107.852824)
			(xy 171.825414 -107.801489) (xy 171.68571 -107.801489) (xy 171.67758 -107.852824) (xy 171.661519 -107.902254)
			(xy 171.637923 -107.948564) (xy 171.607373 -107.990612) (xy 171.570622 -108.027363) (xy 171.528574 -108.057913)
			(xy 171.482264 -108.081509) (xy 171.432834 -108.09757) (xy 171.381499 -108.1057) (xy 171.329525 -108.1057)
			(xy 171.27819 -108.09757) (xy 171.22876 -108.081509) (xy 171.18245 -108.057913) (xy 171.140402 -108.027363)
			(xy 171.103651 -107.990612) (xy 171.073101 -107.948564) (xy 171.049505 -107.902254) (xy 171.033444 -107.852824)
			(xy 171.025314 -107.801489) (xy 169.19448 -107.801489) (xy 169.19448 -108.601335) (xy 171.025314 -108.601335)
			(xy 171.025314 -108.549361) (xy 171.033444 -108.498026) (xy 171.049505 -108.448596) (xy 171.073101 -108.402286)
			(xy 171.103651 -108.360238) (xy 171.140402 -108.323487) (xy 171.18245 -108.292937) (xy 171.22876 -108.269341)
			(xy 171.27819 -108.25328) (xy 171.329525 -108.24515) (xy 171.381499 -108.24515) (xy 171.432834 -108.25328)
			(xy 171.482264 -108.269341) (xy 171.528574 -108.292937) (xy 171.570622 -108.323487) (xy 171.607373 -108.360238)
			(xy 171.637923 -108.402286) (xy 171.661519 -108.448596) (xy 171.67758 -108.498026) (xy 171.68571 -108.549361)
			(xy 171.68622 -108.575348) (xy 171.68571 -108.601335) (xy 171.825414 -108.601335) (xy 171.825414 -108.549361)
			(xy 171.833544 -108.498026) (xy 171.849605 -108.448596) (xy 171.873201 -108.402286) (xy 171.903751 -108.360238)
			(xy 171.940502 -108.323487) (xy 171.98255 -108.292937) (xy 172.02886 -108.269341) (xy 172.07829 -108.25328)
			(xy 172.129625 -108.24515) (xy 172.181599 -108.24515) (xy 172.232934 -108.25328) (xy 172.282364 -108.269341)
			(xy 172.328674 -108.292937) (xy 172.370722 -108.323487) (xy 172.407473 -108.360238) (xy 172.438023 -108.402286)
			(xy 172.461619 -108.448596) (xy 172.47768 -108.498026) (xy 172.48581 -108.549361) (xy 172.48632 -108.575348)
			(xy 172.48581 -108.601335) (xy 172.47768 -108.65267) (xy 172.461619 -108.7021) (xy 172.438023 -108.74841)
			(xy 172.407473 -108.790458) (xy 172.370722 -108.827209) (xy 172.328674 -108.857759) (xy 172.282364 -108.881355)
			(xy 172.232934 -108.897416) (xy 172.181599 -108.905546) (xy 172.129625 -108.905546) (xy 172.07829 -108.897416)
			(xy 172.02886 -108.881355) (xy 171.98255 -108.857759) (xy 171.940502 -108.827209) (xy 171.903751 -108.790458)
			(xy 171.873201 -108.74841) (xy 171.849605 -108.7021) (xy 171.833544 -108.65267) (xy 171.825414 -108.601335)
			(xy 171.68571 -108.601335) (xy 171.67758 -108.65267) (xy 171.661519 -108.7021) (xy 171.637923 -108.74841)
			(xy 171.607373 -108.790458) (xy 171.570622 -108.827209) (xy 171.528574 -108.857759) (xy 171.482264 -108.881355)
			(xy 171.432834 -108.897416) (xy 171.381499 -108.905546) (xy 171.329525 -108.905546) (xy 171.27819 -108.897416)
			(xy 171.22876 -108.881355) (xy 171.18245 -108.857759) (xy 171.140402 -108.827209) (xy 171.103651 -108.790458)
			(xy 171.073101 -108.74841) (xy 171.049505 -108.7021) (xy 171.033444 -108.65267) (xy 171.025314 -108.601335)
			(xy 169.19448 -108.601335) (xy 169.19448 -108.654342) (xy 169.19497 -108.669007) (xy 169.203313 -108.697127)
			(xy 169.219299 -108.721719) (xy 169.241613 -108.740757) (xy 169.268414 -108.752672) (xy 169.297497 -108.756484)
			(xy 169.326464 -108.751879) (xy 169.35293 -108.739235) (xy 169.364152 -108.72978) (xy 169.382469 -108.713836)
			(xy 169.4229 -108.68694) (xy 169.466832 -108.666249) (xy 169.513319 -108.65221) (xy 169.56136 -108.645125)
			(xy 169.58564 -108.64469) (xy 169.611625 -108.645203) (xy 169.662955 -108.653338) (xy 169.712381 -108.669403)
			(xy 169.758685 -108.693001) (xy 169.800728 -108.723552) (xy 169.837475 -108.760303) (xy 169.86802 -108.802349)
			(xy 169.891613 -108.848656) (xy 169.907671 -108.898084) (xy 169.915801 -108.949415) (xy 169.915801 -109.001385)
			(xy 169.907671 -109.052716) (xy 169.891613 -109.102144) (xy 169.86802 -109.148451) (xy 169.837475 -109.190497)
			(xy 169.800728 -109.227248) (xy 169.758685 -109.257799) (xy 169.712381 -109.281397) (xy 169.662955 -109.297462)
			(xy 169.611625 -109.305597) (xy 169.58564 -109.306106) (xy 169.561361 -109.305675) (xy 169.513326 -109.29857)
			(xy 169.466845 -109.284521) (xy 169.422916 -109.26383) (xy 169.382483 -109.236942) (xy 169.364152 -109.221016)
			(xy 169.35294 -109.211548) (xy 169.326478 -109.198892) (xy 169.29751 -109.194279) (xy 169.268426 -109.19809)
			(xy 169.241625 -109.210011) (xy 169.219317 -109.229058) (xy 169.203343 -109.25366) (xy 169.19502 -109.281787)
			(xy 169.19448 -109.296454) (xy 169.19448 -109.401435) (xy 170.225468 -109.401435) (xy 170.225468 -109.349461)
			(xy 170.233598 -109.298126) (xy 170.249659 -109.248696) (xy 170.273255 -109.202386) (xy 170.303805 -109.160338)
			(xy 170.340556 -109.123587) (xy 170.382604 -109.093037) (xy 170.428914 -109.069441) (xy 170.478344 -109.05338)
			(xy 170.529679 -109.04525) (xy 170.581653 -109.04525) (xy 170.632988 -109.05338) (xy 170.682418 -109.069441)
			(xy 170.728728 -109.093037) (xy 170.770776 -109.123587) (xy 170.807527 -109.160338) (xy 170.838077 -109.202386)
			(xy 170.861673 -109.248696) (xy 170.877734 -109.298126) (xy 170.885864 -109.349461) (xy 170.886374 -109.375448)
			(xy 170.885864 -109.401435) (xy 171.825414 -109.401435) (xy 171.825414 -109.349461) (xy 171.833544 -109.298126)
			(xy 171.849605 -109.248696) (xy 171.873201 -109.202386) (xy 171.903751 -109.160338) (xy 171.940502 -109.123587)
			(xy 171.98255 -109.093037) (xy 172.02886 -109.069441) (xy 172.07829 -109.05338) (xy 172.129625 -109.04525)
			(xy 172.181599 -109.04525) (xy 172.232934 -109.05338) (xy 172.282364 -109.069441) (xy 172.328674 -109.093037)
			(xy 172.370722 -109.123587) (xy 172.407473 -109.160338) (xy 172.438023 -109.202386) (xy 172.461619 -109.248696)
			(xy 172.47768 -109.298126) (xy 172.48581 -109.349461) (xy 172.48632 -109.375448) (xy 172.48581 -109.401435)
			(xy 172.625514 -109.401435) (xy 172.625514 -109.349461) (xy 172.633644 -109.298126) (xy 172.649705 -109.248696)
			(xy 172.673301 -109.202386) (xy 172.703851 -109.160338) (xy 172.740602 -109.123587) (xy 172.78265 -109.093037)
			(xy 172.82896 -109.069441) (xy 172.87839 -109.05338) (xy 172.929725 -109.04525) (xy 172.981699 -109.04525)
			(xy 173.033034 -109.05338) (xy 173.082464 -109.069441) (xy 173.128774 -109.093037) (xy 173.170822 -109.123587)
			(xy 173.207573 -109.160338) (xy 173.238123 -109.202386) (xy 173.261719 -109.248696) (xy 173.27778 -109.298126)
			(xy 173.28591 -109.349461) (xy 173.28642 -109.375448) (xy 173.28591 -109.401435) (xy 173.27778 -109.45277)
			(xy 173.261719 -109.5022) (xy 173.238123 -109.54851) (xy 173.207573 -109.590558) (xy 173.170822 -109.627309)
			(xy 173.128774 -109.657859) (xy 173.082464 -109.681455) (xy 173.033034 -109.697516) (xy 172.981699 -109.705646)
			(xy 172.929725 -109.705646) (xy 172.87839 -109.697516) (xy 172.82896 -109.681455) (xy 172.78265 -109.657859)
			(xy 172.740602 -109.627309) (xy 172.703851 -109.590558) (xy 172.673301 -109.54851) (xy 172.649705 -109.5022)
			(xy 172.633644 -109.45277) (xy 172.625514 -109.401435) (xy 172.48581 -109.401435) (xy 172.47768 -109.45277)
			(xy 172.461619 -109.5022) (xy 172.438023 -109.54851) (xy 172.407473 -109.590558) (xy 172.370722 -109.627309)
			(xy 172.328674 -109.657859) (xy 172.282364 -109.681455) (xy 172.232934 -109.697516) (xy 172.181599 -109.705646)
			(xy 172.129625 -109.705646) (xy 172.07829 -109.697516) (xy 172.02886 -109.681455) (xy 171.98255 -109.657859)
			(xy 171.940502 -109.627309) (xy 171.903751 -109.590558) (xy 171.873201 -109.54851) (xy 171.849605 -109.5022)
			(xy 171.833544 -109.45277) (xy 171.825414 -109.401435) (xy 170.885864 -109.401435) (xy 170.877734 -109.45277)
			(xy 170.861673 -109.5022) (xy 170.838077 -109.54851) (xy 170.807527 -109.590558) (xy 170.770776 -109.627309)
			(xy 170.728728 -109.657859) (xy 170.682418 -109.681455) (xy 170.632988 -109.697516) (xy 170.581653 -109.705646)
			(xy 170.529679 -109.705646) (xy 170.478344 -109.697516) (xy 170.428914 -109.681455) (xy 170.382604 -109.657859)
			(xy 170.340556 -109.627309) (xy 170.303805 -109.590558) (xy 170.273255 -109.54851) (xy 170.249659 -109.5022)
			(xy 170.233598 -109.45277) (xy 170.225468 -109.401435) (xy 169.19448 -109.401435) (xy 169.19448 -109.868716)
			(xy 169.231056 -109.879384) (xy 169.25678 -109.88745) (xy 169.305631 -109.910252) (xy 169.350489 -109.940151)
			(xy 169.390332 -109.976467) (xy 169.424249 -110.01837) (xy 169.451468 -110.064904) (xy 169.471367 -110.115007)
			(xy 169.483491 -110.167535) (xy 169.486048 -110.201281) (xy 171.825414 -110.201281) (xy 171.825414 -110.149307)
			(xy 171.833544 -110.097972) (xy 171.849605 -110.048542) (xy 171.873201 -110.002232) (xy 171.903751 -109.960184)
			(xy 171.940502 -109.923433) (xy 171.98255 -109.892883) (xy 172.02886 -109.869287) (xy 172.07829 -109.853226)
			(xy 172.129625 -109.845096) (xy 172.181599 -109.845096) (xy 172.232934 -109.853226) (xy 172.282364 -109.869287)
			(xy 172.328674 -109.892883) (xy 172.370722 -109.923433) (xy 172.407473 -109.960184) (xy 172.438023 -110.002232)
			(xy 172.461619 -110.048542) (xy 172.47768 -110.097972) (xy 172.48581 -110.149307) (xy 172.48632 -110.175294)
			(xy 172.48581 -110.201281) (xy 172.625514 -110.201281) (xy 172.625514 -110.149307) (xy 172.633644 -110.097972)
			(xy 172.649705 -110.048542) (xy 172.673301 -110.002232) (xy 172.703851 -109.960184) (xy 172.740602 -109.923433)
			(xy 172.78265 -109.892883) (xy 172.82896 -109.869287) (xy 172.87839 -109.853226) (xy 172.929725 -109.845096)
			(xy 172.981699 -109.845096) (xy 173.033034 -109.853226) (xy 173.082464 -109.869287) (xy 173.128774 -109.892883)
			(xy 173.170822 -109.923433) (xy 173.207573 -109.960184) (xy 173.238123 -110.002232) (xy 173.261719 -110.048542)
			(xy 173.27778 -110.097972) (xy 173.28591 -110.149307) (xy 173.28642 -110.175294) (xy 173.28591 -110.201281)
			(xy 173.42536 -110.201281) (xy 173.42536 -110.149307) (xy 173.43349 -110.097972) (xy 173.449551 -110.048542)
			(xy 173.473147 -110.002232) (xy 173.503697 -109.960184) (xy 173.540448 -109.923433) (xy 173.582496 -109.892883)
			(xy 173.628806 -109.869287) (xy 173.678236 -109.853226) (xy 173.729571 -109.845096) (xy 173.781545 -109.845096)
			(xy 173.83288 -109.853226) (xy 173.88231 -109.869287) (xy 173.92862 -109.892883) (xy 173.970668 -109.923433)
			(xy 174.007419 -109.960184) (xy 174.037969 -110.002232) (xy 174.061565 -110.048542) (xy 174.077626 -110.097972)
			(xy 174.085756 -110.149307) (xy 174.086266 -110.175294) (xy 174.085756 -110.201281) (xy 174.077626 -110.252616)
			(xy 174.061565 -110.302046) (xy 174.037969 -110.348356) (xy 174.007419 -110.390404) (xy 173.970668 -110.427155)
			(xy 173.92862 -110.457705) (xy 173.88231 -110.481301) (xy 173.83288 -110.497362) (xy 173.781545 -110.505492)
			(xy 173.729571 -110.505492) (xy 173.678236 -110.497362) (xy 173.628806 -110.481301) (xy 173.582496 -110.457705)
			(xy 173.540448 -110.427155) (xy 173.503697 -110.390404) (xy 173.473147 -110.348356) (xy 173.449551 -110.302046)
			(xy 173.43349 -110.252616) (xy 173.42536 -110.201281) (xy 173.28591 -110.201281) (xy 173.27778 -110.252616)
			(xy 173.261719 -110.302046) (xy 173.238123 -110.348356) (xy 173.207573 -110.390404) (xy 173.170822 -110.427155)
			(xy 173.128774 -110.457705) (xy 173.082464 -110.481301) (xy 173.033034 -110.497362) (xy 172.981699 -110.505492)
			(xy 172.929725 -110.505492) (xy 172.87839 -110.497362) (xy 172.82896 -110.481301) (xy 172.78265 -110.457705)
			(xy 172.740602 -110.427155) (xy 172.703851 -110.390404) (xy 172.673301 -110.348356) (xy 172.649705 -110.302046)
			(xy 172.633644 -110.252616) (xy 172.625514 -110.201281) (xy 172.48581 -110.201281) (xy 172.47768 -110.252616)
			(xy 172.461619 -110.302046) (xy 172.438023 -110.348356) (xy 172.407473 -110.390404) (xy 172.370722 -110.427155)
			(xy 172.328674 -110.457705) (xy 172.282364 -110.481301) (xy 172.232934 -110.497362) (xy 172.181599 -110.505492)
			(xy 172.129625 -110.505492) (xy 172.07829 -110.497362) (xy 172.02886 -110.481301) (xy 171.98255 -110.457705)
			(xy 171.940502 -110.427155) (xy 171.903751 -110.390404) (xy 171.873201 -110.348356) (xy 171.849605 -110.302046)
			(xy 171.833544 -110.252616) (xy 171.825414 -110.201281) (xy 169.486048 -110.201281) (xy 169.487564 -110.221291)
			(xy 169.483493 -110.275047) (xy 169.471372 -110.327576) (xy 169.451476 -110.37768) (xy 169.42426 -110.424215)
			(xy 169.390344 -110.46612) (xy 169.350503 -110.502438) (xy 169.305647 -110.53234) (xy 169.256797 -110.555143)
			(xy 169.231056 -110.563152) (xy 169.19448 -110.57382) (xy 169.19448 -111.001381) (xy 169.425368 -111.001381)
			(xy 169.425368 -110.949407) (xy 169.433498 -110.898072) (xy 169.449559 -110.848642) (xy 169.473155 -110.802332)
			(xy 169.503705 -110.760284) (xy 169.540456 -110.723533) (xy 169.582504 -110.692983) (xy 169.628814 -110.669387)
			(xy 169.678244 -110.653326) (xy 169.729579 -110.645196) (xy 169.781553 -110.645196) (xy 169.832888 -110.653326)
			(xy 169.882318 -110.669387) (xy 169.928628 -110.692983) (xy 169.970676 -110.723533) (xy 170.007427 -110.760284)
			(xy 170.037977 -110.802332) (xy 170.061573 -110.848642) (xy 170.077634 -110.898072) (xy 170.085764 -110.949407)
			(xy 170.086274 -110.975394) (xy 170.085764 -111.001381) (xy 170.225468 -111.001381) (xy 170.225468 -110.949407)
			(xy 170.233598 -110.898072) (xy 170.249659 -110.848642) (xy 170.273255 -110.802332) (xy 170.303805 -110.760284)
			(xy 170.340556 -110.723533) (xy 170.382604 -110.692983) (xy 170.428914 -110.669387) (xy 170.478344 -110.653326)
			(xy 170.529679 -110.645196) (xy 170.581653 -110.645196) (xy 170.632988 -110.653326) (xy 170.682418 -110.669387)
			(xy 170.728728 -110.692983) (xy 170.770776 -110.723533) (xy 170.807527 -110.760284) (xy 170.838077 -110.802332)
			(xy 170.861673 -110.848642) (xy 170.877734 -110.898072) (xy 170.885864 -110.949407) (xy 170.886374 -110.975394)
			(xy 170.885864 -111.001381) (xy 171.025314 -111.001381) (xy 171.025314 -110.949407) (xy 171.033444 -110.898072)
			(xy 171.049505 -110.848642) (xy 171.073101 -110.802332) (xy 171.103651 -110.760284) (xy 171.140402 -110.723533)
			(xy 171.18245 -110.692983) (xy 171.22876 -110.669387) (xy 171.27819 -110.653326) (xy 171.329525 -110.645196)
			(xy 171.381499 -110.645196) (xy 171.432834 -110.653326) (xy 171.482264 -110.669387) (xy 171.528574 -110.692983)
			(xy 171.570622 -110.723533) (xy 171.607373 -110.760284) (xy 171.637923 -110.802332) (xy 171.661519 -110.848642)
			(xy 171.67758 -110.898072) (xy 171.68571 -110.949407) (xy 171.68622 -110.975394) (xy 171.68571 -111.001381)
			(xy 171.825414 -111.001381) (xy 171.825414 -110.949407) (xy 171.833544 -110.898072) (xy 171.849605 -110.848642)
			(xy 171.873201 -110.802332) (xy 171.903751 -110.760284) (xy 171.940502 -110.723533) (xy 171.98255 -110.692983)
			(xy 172.02886 -110.669387) (xy 172.07829 -110.653326) (xy 172.129625 -110.645196) (xy 172.181599 -110.645196)
			(xy 172.232934 -110.653326) (xy 172.282364 -110.669387) (xy 172.328674 -110.692983) (xy 172.370722 -110.723533)
			(xy 172.407473 -110.760284) (xy 172.438023 -110.802332) (xy 172.461619 -110.848642) (xy 172.47768 -110.898072)
			(xy 172.48581 -110.949407) (xy 172.48632 -110.975394) (xy 172.48581 -111.001381) (xy 172.625514 -111.001381)
			(xy 172.625514 -110.949407) (xy 172.633644 -110.898072) (xy 172.649705 -110.848642) (xy 172.673301 -110.802332)
			(xy 172.703851 -110.760284) (xy 172.740602 -110.723533) (xy 172.78265 -110.692983) (xy 172.82896 -110.669387)
			(xy 172.87839 -110.653326) (xy 172.929725 -110.645196) (xy 172.981699 -110.645196) (xy 173.033034 -110.653326)
			(xy 173.082464 -110.669387) (xy 173.128774 -110.692983) (xy 173.170822 -110.723533) (xy 173.207573 -110.760284)
			(xy 173.238123 -110.802332) (xy 173.261719 -110.848642) (xy 173.27778 -110.898072) (xy 173.28591 -110.949407)
			(xy 173.28642 -110.975394) (xy 173.28591 -111.001381) (xy 173.42536 -111.001381) (xy 173.42536 -110.949407)
			(xy 173.43349 -110.898072) (xy 173.449551 -110.848642) (xy 173.473147 -110.802332) (xy 173.503697 -110.760284)
			(xy 173.540448 -110.723533) (xy 173.582496 -110.692983) (xy 173.628806 -110.669387) (xy 173.678236 -110.653326)
			(xy 173.729571 -110.645196) (xy 173.781545 -110.645196) (xy 173.83288 -110.653326) (xy 173.88231 -110.669387)
			(xy 173.92862 -110.692983) (xy 173.970668 -110.723533) (xy 174.007419 -110.760284) (xy 174.037969 -110.802332)
			(xy 174.061565 -110.848642) (xy 174.077626 -110.898072) (xy 174.085756 -110.949407) (xy 174.086266 -110.975394)
			(xy 174.085756 -111.001381) (xy 174.22546 -111.001381) (xy 174.22546 -110.949407) (xy 174.23359 -110.898072)
			(xy 174.249651 -110.848642) (xy 174.273247 -110.802332) (xy 174.303797 -110.760284) (xy 174.340548 -110.723533)
			(xy 174.382596 -110.692983) (xy 174.428906 -110.669387) (xy 174.478336 -110.653326) (xy 174.529671 -110.645196)
			(xy 174.581645 -110.645196) (xy 174.63298 -110.653326) (xy 174.68241 -110.669387) (xy 174.72872 -110.692983)
			(xy 174.770768 -110.723533) (xy 174.807519 -110.760284) (xy 174.838069 -110.802332) (xy 174.861665 -110.848642)
			(xy 174.877726 -110.898072) (xy 174.885856 -110.949407) (xy 174.886366 -110.975394) (xy 174.885856 -111.001381)
			(xy 174.877726 -111.052716) (xy 174.861665 -111.102146) (xy 174.838069 -111.148456) (xy 174.807519 -111.190504)
			(xy 174.770768 -111.227255) (xy 174.72872 -111.257805) (xy 174.68241 -111.281401) (xy 174.63298 -111.297462)
			(xy 174.581645 -111.305592) (xy 174.529671 -111.305592) (xy 174.478336 -111.297462) (xy 174.428906 -111.281401)
			(xy 174.382596 -111.257805) (xy 174.340548 -111.227255) (xy 174.303797 -111.190504) (xy 174.273247 -111.148456)
			(xy 174.249651 -111.102146) (xy 174.23359 -111.052716) (xy 174.22546 -111.001381) (xy 174.085756 -111.001381)
			(xy 174.077626 -111.052716) (xy 174.061565 -111.102146) (xy 174.037969 -111.148456) (xy 174.007419 -111.190504)
			(xy 173.970668 -111.227255) (xy 173.92862 -111.257805) (xy 173.88231 -111.281401) (xy 173.83288 -111.297462)
			(xy 173.781545 -111.305592) (xy 173.729571 -111.305592) (xy 173.678236 -111.297462) (xy 173.628806 -111.281401)
			(xy 173.582496 -111.257805) (xy 173.540448 -111.227255) (xy 173.503697 -111.190504) (xy 173.473147 -111.148456)
			(xy 173.449551 -111.102146) (xy 173.43349 -111.052716) (xy 173.42536 -111.001381) (xy 173.28591 -111.001381)
			(xy 173.27778 -111.052716) (xy 173.261719 -111.102146) (xy 173.238123 -111.148456) (xy 173.207573 -111.190504)
			(xy 173.170822 -111.227255) (xy 173.128774 -111.257805) (xy 173.082464 -111.281401) (xy 173.033034 -111.297462)
			(xy 172.981699 -111.305592) (xy 172.929725 -111.305592) (xy 172.87839 -111.297462) (xy 172.82896 -111.281401)
			(xy 172.78265 -111.257805) (xy 172.740602 -111.227255) (xy 172.703851 -111.190504) (xy 172.673301 -111.148456)
			(xy 172.649705 -111.102146) (xy 172.633644 -111.052716) (xy 172.625514 -111.001381) (xy 172.48581 -111.001381)
			(xy 172.47768 -111.052716) (xy 172.461619 -111.102146) (xy 172.438023 -111.148456) (xy 172.407473 -111.190504)
			(xy 172.370722 -111.227255) (xy 172.328674 -111.257805) (xy 172.282364 -111.281401) (xy 172.232934 -111.297462)
			(xy 172.181599 -111.305592) (xy 172.129625 -111.305592) (xy 172.07829 -111.297462) (xy 172.02886 -111.281401)
			(xy 171.98255 -111.257805) (xy 171.940502 -111.227255) (xy 171.903751 -111.190504) (xy 171.873201 -111.148456)
			(xy 171.849605 -111.102146) (xy 171.833544 -111.052716) (xy 171.825414 -111.001381) (xy 171.68571 -111.001381)
			(xy 171.67758 -111.052716) (xy 171.661519 -111.102146) (xy 171.637923 -111.148456) (xy 171.607373 -111.190504)
			(xy 171.570622 -111.227255) (xy 171.528574 -111.257805) (xy 171.482264 -111.281401) (xy 171.432834 -111.297462)
			(xy 171.381499 -111.305592) (xy 171.329525 -111.305592) (xy 171.27819 -111.297462) (xy 171.22876 -111.281401)
			(xy 171.18245 -111.257805) (xy 171.140402 -111.227255) (xy 171.103651 -111.190504) (xy 171.073101 -111.148456)
			(xy 171.049505 -111.102146) (xy 171.033444 -111.052716) (xy 171.025314 -111.001381) (xy 170.885864 -111.001381)
			(xy 170.877734 -111.052716) (xy 170.861673 -111.102146) (xy 170.838077 -111.148456) (xy 170.807527 -111.190504)
			(xy 170.770776 -111.227255) (xy 170.728728 -111.257805) (xy 170.682418 -111.281401) (xy 170.632988 -111.297462)
			(xy 170.581653 -111.305592) (xy 170.529679 -111.305592) (xy 170.478344 -111.297462) (xy 170.428914 -111.281401)
			(xy 170.382604 -111.257805) (xy 170.340556 -111.227255) (xy 170.303805 -111.190504) (xy 170.273255 -111.148456)
			(xy 170.249659 -111.102146) (xy 170.233598 -111.052716) (xy 170.225468 -111.001381) (xy 170.085764 -111.001381)
			(xy 170.077634 -111.052716) (xy 170.061573 -111.102146) (xy 170.037977 -111.148456) (xy 170.007427 -111.190504)
			(xy 169.970676 -111.227255) (xy 169.928628 -111.257805) (xy 169.882318 -111.281401) (xy 169.832888 -111.297462)
			(xy 169.781553 -111.305592) (xy 169.729579 -111.305592) (xy 169.678244 -111.297462) (xy 169.628814 -111.281401)
			(xy 169.582504 -111.257805) (xy 169.540456 -111.227255) (xy 169.503705 -111.190504) (xy 169.473155 -111.148456)
			(xy 169.449559 -111.102146) (xy 169.433498 -111.052716) (xy 169.425368 -111.001381) (xy 169.19448 -111.001381)
			(xy 169.19448 -111.801481) (xy 171.025314 -111.801481) (xy 171.025314 -111.749507) (xy 171.033444 -111.698172)
			(xy 171.049505 -111.648742) (xy 171.073101 -111.602432) (xy 171.103651 -111.560384) (xy 171.140402 -111.523633)
			(xy 171.18245 -111.493083) (xy 171.22876 -111.469487) (xy 171.27819 -111.453426) (xy 171.329525 -111.445296)
			(xy 171.381499 -111.445296) (xy 171.432834 -111.453426) (xy 171.482264 -111.469487) (xy 171.528574 -111.493083)
			(xy 171.570622 -111.523633) (xy 171.607373 -111.560384) (xy 171.637923 -111.602432) (xy 171.661519 -111.648742)
			(xy 171.67758 -111.698172) (xy 171.68571 -111.749507) (xy 171.68622 -111.775494) (xy 171.68571 -111.801481)
			(xy 171.825414 -111.801481) (xy 171.825414 -111.749507) (xy 171.833544 -111.698172) (xy 171.849605 -111.648742)
			(xy 171.873201 -111.602432) (xy 171.903751 -111.560384) (xy 171.940502 -111.523633) (xy 171.98255 -111.493083)
			(xy 172.02886 -111.469487) (xy 172.07829 -111.453426) (xy 172.129625 -111.445296) (xy 172.181599 -111.445296)
			(xy 172.232934 -111.453426) (xy 172.282364 -111.469487) (xy 172.328674 -111.493083) (xy 172.370722 -111.523633)
			(xy 172.407473 -111.560384) (xy 172.438023 -111.602432) (xy 172.461619 -111.648742) (xy 172.47768 -111.698172)
			(xy 172.48581 -111.749507) (xy 172.48632 -111.775494) (xy 172.48581 -111.801481) (xy 172.625514 -111.801481)
			(xy 172.625514 -111.749507) (xy 172.633644 -111.698172) (xy 172.649705 -111.648742) (xy 172.673301 -111.602432)
			(xy 172.703851 -111.560384) (xy 172.740602 -111.523633) (xy 172.78265 -111.493083) (xy 172.82896 -111.469487)
			(xy 172.87839 -111.453426) (xy 172.929725 -111.445296) (xy 172.981699 -111.445296) (xy 173.033034 -111.453426)
			(xy 173.082464 -111.469487) (xy 173.128774 -111.493083) (xy 173.170822 -111.523633) (xy 173.207573 -111.560384)
			(xy 173.238123 -111.602432) (xy 173.261719 -111.648742) (xy 173.27778 -111.698172) (xy 173.28591 -111.749507)
			(xy 173.28642 -111.775494) (xy 173.28591 -111.801481) (xy 173.42536 -111.801481) (xy 173.42536 -111.749507)
			(xy 173.43349 -111.698172) (xy 173.449551 -111.648742) (xy 173.473147 -111.602432) (xy 173.503697 -111.560384)
			(xy 173.540448 -111.523633) (xy 173.582496 -111.493083) (xy 173.628806 -111.469487) (xy 173.678236 -111.453426)
			(xy 173.729571 -111.445296) (xy 173.781545 -111.445296) (xy 173.83288 -111.453426) (xy 173.88231 -111.469487)
			(xy 173.92862 -111.493083) (xy 173.970668 -111.523633) (xy 174.007419 -111.560384) (xy 174.037969 -111.602432)
			(xy 174.061565 -111.648742) (xy 174.077626 -111.698172) (xy 174.085756 -111.749507) (xy 174.086266 -111.775494)
			(xy 174.085756 -111.801481) (xy 174.077626 -111.852816) (xy 174.061565 -111.902246) (xy 174.037969 -111.948556)
			(xy 174.007419 -111.990604) (xy 173.970668 -112.027355) (xy 173.92862 -112.057905) (xy 173.88231 -112.081501)
			(xy 173.83288 -112.097562) (xy 173.781545 -112.105692) (xy 173.729571 -112.105692) (xy 173.678236 -112.097562)
			(xy 173.628806 -112.081501) (xy 173.582496 -112.057905) (xy 173.540448 -112.027355) (xy 173.503697 -111.990604)
			(xy 173.473147 -111.948556) (xy 173.449551 -111.902246) (xy 173.43349 -111.852816) (xy 173.42536 -111.801481)
			(xy 173.28591 -111.801481) (xy 173.27778 -111.852816) (xy 173.261719 -111.902246) (xy 173.238123 -111.948556)
			(xy 173.207573 -111.990604) (xy 173.170822 -112.027355) (xy 173.128774 -112.057905) (xy 173.082464 -112.081501)
			(xy 173.033034 -112.097562) (xy 172.981699 -112.105692) (xy 172.929725 -112.105692) (xy 172.87839 -112.097562)
			(xy 172.82896 -112.081501) (xy 172.78265 -112.057905) (xy 172.740602 -112.027355) (xy 172.703851 -111.990604)
			(xy 172.673301 -111.948556) (xy 172.649705 -111.902246) (xy 172.633644 -111.852816) (xy 172.625514 -111.801481)
			(xy 172.48581 -111.801481) (xy 172.47768 -111.852816) (xy 172.461619 -111.902246) (xy 172.438023 -111.948556)
			(xy 172.407473 -111.990604) (xy 172.370722 -112.027355) (xy 172.328674 -112.057905) (xy 172.282364 -112.081501)
			(xy 172.232934 -112.097562) (xy 172.181599 -112.105692) (xy 172.129625 -112.105692) (xy 172.07829 -112.097562)
			(xy 172.02886 -112.081501) (xy 171.98255 -112.057905) (xy 171.940502 -112.027355) (xy 171.903751 -111.990604)
			(xy 171.873201 -111.948556) (xy 171.849605 -111.902246) (xy 171.833544 -111.852816) (xy 171.825414 -111.801481)
			(xy 171.68571 -111.801481) (xy 171.67758 -111.852816) (xy 171.661519 -111.902246) (xy 171.637923 -111.948556)
			(xy 171.607373 -111.990604) (xy 171.570622 -112.027355) (xy 171.528574 -112.057905) (xy 171.482264 -112.081501)
			(xy 171.432834 -112.097562) (xy 171.381499 -112.105692) (xy 171.329525 -112.105692) (xy 171.27819 -112.097562)
			(xy 171.22876 -112.081501) (xy 171.18245 -112.057905) (xy 171.140402 -112.027355) (xy 171.103651 -111.990604)
			(xy 171.073101 -111.948556) (xy 171.049505 -111.902246) (xy 171.033444 -111.852816) (xy 171.025314 -111.801481)
			(xy 169.19448 -111.801481) (xy 169.19448 -111.858552) (xy 169.194971 -111.873307) (xy 169.203397 -111.901587)
			(xy 169.21956 -111.926276) (xy 169.242108 -111.945311) (xy 169.269159 -111.957102) (xy 169.298452 -111.960664)
			(xy 169.32754 -111.9557) (xy 169.353993 -111.942623) (xy 169.365168 -111.932974) (xy 169.383619 -111.916505)
			(xy 169.424496 -111.88867) (xy 169.469063 -111.867233) (xy 169.516326 -111.852673) (xy 169.565231 -111.845316)
			(xy 169.589958 -111.844836) (xy 169.615946 -111.845316) (xy 169.667283 -111.853441) (xy 169.716716 -111.869497)
			(xy 169.763029 -111.89309) (xy 169.805081 -111.923637) (xy 169.841836 -111.960387) (xy 169.872388 -112.002435)
			(xy 169.895987 -112.048745) (xy 169.912049 -112.098176) (xy 169.920181 -112.149512) (xy 169.920181 -112.201488)
			(xy 169.912049 -112.252824) (xy 169.895987 -112.302255) (xy 169.872388 -112.348565) (xy 169.841836 -112.390613)
			(xy 169.805081 -112.427363) (xy 169.763029 -112.45791) (xy 169.716716 -112.481503) (xy 169.667283 -112.497559)
			(xy 169.615946 -112.505684) (xy 169.589958 -112.506252) (xy 169.565231 -112.505788) (xy 169.516329 -112.498418)
			(xy 169.46907 -112.48385) (xy 169.424506 -112.462407) (xy 169.383632 -112.434568) (xy 169.365168 -112.418114)
			(xy 169.354017 -112.408451) (xy 169.327562 -112.395412) (xy 169.298485 -112.390474) (xy 169.269209 -112.394049)
			(xy 169.242174 -112.405839) (xy 169.219635 -112.424862) (xy 169.203469 -112.44953) (xy 169.195026 -112.47779)
			(xy 169.19448 -112.492536) (xy 169.19448 -112.601581) (xy 170.225468 -112.601581) (xy 170.225468 -112.549607)
			(xy 170.233598 -112.498272) (xy 170.249659 -112.448842) (xy 170.273255 -112.402532) (xy 170.303805 -112.360484)
			(xy 170.340556 -112.323733) (xy 170.382604 -112.293183) (xy 170.428914 -112.269587) (xy 170.478344 -112.253526)
			(xy 170.529679 -112.245396) (xy 170.581653 -112.245396) (xy 170.632988 -112.253526) (xy 170.682418 -112.269587)
			(xy 170.728728 -112.293183) (xy 170.770776 -112.323733) (xy 170.807527 -112.360484) (xy 170.838077 -112.402532)
			(xy 170.861673 -112.448842) (xy 170.877734 -112.498272) (xy 170.885864 -112.549607) (xy 170.886374 -112.575594)
			(xy 170.885869 -112.601327) (xy 171.025314 -112.601327) (xy 171.025314 -112.549353) (xy 171.033444 -112.498018)
			(xy 171.049505 -112.448588) (xy 171.073101 -112.402278) (xy 171.103651 -112.36023) (xy 171.140402 -112.323479)
			(xy 171.18245 -112.292929) (xy 171.22876 -112.269333) (xy 171.27819 -112.253272) (xy 171.329525 -112.245142)
			(xy 171.381499 -112.245142) (xy 171.432834 -112.253272) (xy 171.482264 -112.269333) (xy 171.528574 -112.292929)
			(xy 171.570622 -112.323479) (xy 171.607373 -112.36023) (xy 171.637923 -112.402278) (xy 171.661519 -112.448588)
			(xy 171.67758 -112.498018) (xy 171.68571 -112.549353) (xy 171.68622 -112.57534) (xy 171.68571 -112.601327)
			(xy 171.825414 -112.601327) (xy 171.825414 -112.549353) (xy 171.833544 -112.498018) (xy 171.849605 -112.448588)
			(xy 171.873201 -112.402278) (xy 171.903751 -112.36023) (xy 171.940502 -112.323479) (xy 171.98255 -112.292929)
			(xy 172.02886 -112.269333) (xy 172.07829 -112.253272) (xy 172.129625 -112.245142) (xy 172.181599 -112.245142)
			(xy 172.232934 -112.253272) (xy 172.282364 -112.269333) (xy 172.328674 -112.292929) (xy 172.370722 -112.323479)
			(xy 172.407473 -112.36023) (xy 172.438023 -112.402278) (xy 172.461619 -112.448588) (xy 172.47768 -112.498018)
			(xy 172.48581 -112.549353) (xy 172.48632 -112.57534) (xy 172.48581 -112.601327) (xy 172.625514 -112.601327)
			(xy 172.625514 -112.549353) (xy 172.633644 -112.498018) (xy 172.649705 -112.448588) (xy 172.673301 -112.402278)
			(xy 172.703851 -112.36023) (xy 172.740602 -112.323479) (xy 172.78265 -112.292929) (xy 172.82896 -112.269333)
			(xy 172.87839 -112.253272) (xy 172.929725 -112.245142) (xy 172.981699 -112.245142) (xy 173.033034 -112.253272)
			(xy 173.082464 -112.269333) (xy 173.128774 -112.292929) (xy 173.170822 -112.323479) (xy 173.207573 -112.36023)
			(xy 173.238123 -112.402278) (xy 173.261719 -112.448588) (xy 173.27778 -112.498018) (xy 173.28591 -112.549353)
			(xy 173.28642 -112.57534) (xy 173.28591 -112.601327) (xy 173.42536 -112.601327) (xy 173.42536 -112.549353)
			(xy 173.43349 -112.498018) (xy 173.449551 -112.448588) (xy 173.473147 -112.402278) (xy 173.503697 -112.36023)
			(xy 173.540448 -112.323479) (xy 173.582496 -112.292929) (xy 173.628806 -112.269333) (xy 173.678236 -112.253272)
			(xy 173.729571 -112.245142) (xy 173.781545 -112.245142) (xy 173.83288 -112.253272) (xy 173.88231 -112.269333)
			(xy 173.92862 -112.292929) (xy 173.970668 -112.323479) (xy 174.007419 -112.36023) (xy 174.037969 -112.402278)
			(xy 174.061565 -112.448588) (xy 174.077626 -112.498018) (xy 174.085756 -112.549353) (xy 174.086266 -112.57534)
			(xy 174.085756 -112.601327) (xy 174.22546 -112.601327) (xy 174.22546 -112.549353) (xy 174.23359 -112.498018)
			(xy 174.249651 -112.448588) (xy 174.273247 -112.402278) (xy 174.303797 -112.36023) (xy 174.340548 -112.323479)
			(xy 174.382596 -112.292929) (xy 174.428906 -112.269333) (xy 174.478336 -112.253272) (xy 174.529671 -112.245142)
			(xy 174.581645 -112.245142) (xy 174.63298 -112.253272) (xy 174.68241 -112.269333) (xy 174.72872 -112.292929)
			(xy 174.770768 -112.323479) (xy 174.807519 -112.36023) (xy 174.838069 -112.402278) (xy 174.861665 -112.448588)
			(xy 174.877726 -112.498018) (xy 174.885856 -112.549353) (xy 174.886366 -112.57534) (xy 174.885856 -112.601327)
			(xy 174.877726 -112.652662) (xy 174.861665 -112.702092) (xy 174.838069 -112.748402) (xy 174.807519 -112.79045)
			(xy 174.770768 -112.827201) (xy 174.72872 -112.857751) (xy 174.68241 -112.881347) (xy 174.63298 -112.897408)
			(xy 174.581645 -112.905538) (xy 174.529671 -112.905538) (xy 174.478336 -112.897408) (xy 174.428906 -112.881347)
			(xy 174.382596 -112.857751) (xy 174.340548 -112.827201) (xy 174.303797 -112.79045) (xy 174.273247 -112.748402)
			(xy 174.249651 -112.702092) (xy 174.23359 -112.652662) (xy 174.22546 -112.601327) (xy 174.085756 -112.601327)
			(xy 174.077626 -112.652662) (xy 174.061565 -112.702092) (xy 174.037969 -112.748402) (xy 174.007419 -112.79045)
			(xy 173.970668 -112.827201) (xy 173.92862 -112.857751) (xy 173.88231 -112.881347) (xy 173.83288 -112.897408)
			(xy 173.781545 -112.905538) (xy 173.729571 -112.905538) (xy 173.678236 -112.897408) (xy 173.628806 -112.881347)
			(xy 173.582496 -112.857751) (xy 173.540448 -112.827201) (xy 173.503697 -112.79045) (xy 173.473147 -112.748402)
			(xy 173.449551 -112.702092) (xy 173.43349 -112.652662) (xy 173.42536 -112.601327) (xy 173.28591 -112.601327)
			(xy 173.27778 -112.652662) (xy 173.261719 -112.702092) (xy 173.238123 -112.748402) (xy 173.207573 -112.79045)
			(xy 173.170822 -112.827201) (xy 173.128774 -112.857751) (xy 173.082464 -112.881347) (xy 173.033034 -112.897408)
			(xy 172.981699 -112.905538) (xy 172.929725 -112.905538) (xy 172.87839 -112.897408) (xy 172.82896 -112.881347)
			(xy 172.78265 -112.857751) (xy 172.740602 -112.827201) (xy 172.703851 -112.79045) (xy 172.673301 -112.748402)
			(xy 172.649705 -112.702092) (xy 172.633644 -112.652662) (xy 172.625514 -112.601327) (xy 172.48581 -112.601327)
			(xy 172.47768 -112.652662) (xy 172.461619 -112.702092) (xy 172.438023 -112.748402) (xy 172.407473 -112.79045)
			(xy 172.370722 -112.827201) (xy 172.328674 -112.857751) (xy 172.282364 -112.881347) (xy 172.232934 -112.897408)
			(xy 172.181599 -112.905538) (xy 172.129625 -112.905538) (xy 172.07829 -112.897408) (xy 172.02886 -112.881347)
			(xy 171.98255 -112.857751) (xy 171.940502 -112.827201) (xy 171.903751 -112.79045) (xy 171.873201 -112.748402)
			(xy 171.849605 -112.702092) (xy 171.833544 -112.652662) (xy 171.825414 -112.601327) (xy 171.68571 -112.601327)
			(xy 171.67758 -112.652662) (xy 171.661519 -112.702092) (xy 171.637923 -112.748402) (xy 171.607373 -112.79045)
			(xy 171.570622 -112.827201) (xy 171.528574 -112.857751) (xy 171.482264 -112.881347) (xy 171.432834 -112.897408)
			(xy 171.381499 -112.905538) (xy 171.329525 -112.905538) (xy 171.27819 -112.897408) (xy 171.22876 -112.881347)
			(xy 171.18245 -112.857751) (xy 171.140402 -112.827201) (xy 171.103651 -112.79045) (xy 171.073101 -112.748402)
			(xy 171.049505 -112.702092) (xy 171.033444 -112.652662) (xy 171.025314 -112.601327) (xy 170.885869 -112.601327)
			(xy 170.885864 -112.601581) (xy 170.877734 -112.652916) (xy 170.861673 -112.702346) (xy 170.838077 -112.748656)
			(xy 170.807527 -112.790704) (xy 170.770776 -112.827455) (xy 170.728728 -112.858005) (xy 170.682418 -112.881601)
			(xy 170.632988 -112.897662) (xy 170.581653 -112.905792) (xy 170.529679 -112.905792) (xy 170.478344 -112.897662)
			(xy 170.428914 -112.881601) (xy 170.382604 -112.858005) (xy 170.340556 -112.827455) (xy 170.303805 -112.790704)
			(xy 170.273255 -112.748656) (xy 170.249659 -112.702346) (xy 170.233598 -112.652916) (xy 170.225468 -112.601581)
			(xy 169.19448 -112.601581) (xy 169.19448 -113.159286) (xy 169.282364 -113.247424) (xy 169.302491 -113.268273)
			(xy 169.336595 -113.315122) (xy 169.362949 -113.366731) (xy 169.380902 -113.421827) (xy 169.390012 -113.479055)
			(xy 169.390568 -113.508028) (xy 169.390568 -114.201527) (xy 171.825414 -114.201527) (xy 171.825414 -114.149553)
			(xy 171.833544 -114.098218) (xy 171.849605 -114.048788) (xy 171.873201 -114.002478) (xy 171.903751 -113.96043)
			(xy 171.940502 -113.923679) (xy 171.98255 -113.893129) (xy 172.02886 -113.869533) (xy 172.07829 -113.853472)
			(xy 172.129625 -113.845342) (xy 172.181599 -113.845342) (xy 172.232934 -113.853472) (xy 172.282364 -113.869533)
			(xy 172.328674 -113.893129) (xy 172.370722 -113.923679) (xy 172.407473 -113.96043) (xy 172.438023 -114.002478)
			(xy 172.461619 -114.048788) (xy 172.47768 -114.098218) (xy 172.48581 -114.149553) (xy 172.48632 -114.17554)
			(xy 172.48581 -114.201527) (xy 172.625514 -114.201527) (xy 172.625514 -114.149553) (xy 172.633644 -114.098218)
			(xy 172.649705 -114.048788) (xy 172.673301 -114.002478) (xy 172.703851 -113.96043) (xy 172.740602 -113.923679)
			(xy 172.78265 -113.893129) (xy 172.82896 -113.869533) (xy 172.87839 -113.853472) (xy 172.929725 -113.845342)
			(xy 172.981699 -113.845342) (xy 173.033034 -113.853472) (xy 173.082464 -113.869533) (xy 173.128774 -113.893129)
			(xy 173.170822 -113.923679) (xy 173.207573 -113.96043) (xy 173.238123 -114.002478) (xy 173.261719 -114.048788)
			(xy 173.27778 -114.098218) (xy 173.28591 -114.149553) (xy 173.28642 -114.17554) (xy 173.28591 -114.201527)
			(xy 173.42536 -114.201527) (xy 173.42536 -114.149553) (xy 173.43349 -114.098218) (xy 173.449551 -114.048788)
			(xy 173.473147 -114.002478) (xy 173.503697 -113.96043) (xy 173.540448 -113.923679) (xy 173.582496 -113.893129)
			(xy 173.628806 -113.869533) (xy 173.678236 -113.853472) (xy 173.729571 -113.845342) (xy 173.781545 -113.845342)
			(xy 173.83288 -113.853472) (xy 173.88231 -113.869533) (xy 173.92862 -113.893129) (xy 173.970668 -113.923679)
			(xy 174.007419 -113.96043) (xy 174.037969 -114.002478) (xy 174.061565 -114.048788) (xy 174.077626 -114.098218)
			(xy 174.085756 -114.149553) (xy 174.086266 -114.17554) (xy 174.085756 -114.201527) (xy 174.22546 -114.201527)
			(xy 174.22546 -114.149553) (xy 174.23359 -114.098218) (xy 174.249651 -114.048788) (xy 174.273247 -114.002478)
			(xy 174.303797 -113.96043) (xy 174.340548 -113.923679) (xy 174.382596 -113.893129) (xy 174.428906 -113.869533)
			(xy 174.478336 -113.853472) (xy 174.529671 -113.845342) (xy 174.581645 -113.845342) (xy 174.63298 -113.853472)
			(xy 174.68241 -113.869533) (xy 174.72872 -113.893129) (xy 174.770768 -113.923679) (xy 174.807519 -113.96043)
			(xy 174.838069 -114.002478) (xy 174.861665 -114.048788) (xy 174.877726 -114.098218) (xy 174.885856 -114.149553)
			(xy 174.886366 -114.17554) (xy 174.885856 -114.201527) (xy 174.877726 -114.252862) (xy 174.861665 -114.302292)
			(xy 174.838069 -114.348602) (xy 174.807519 -114.39065) (xy 174.770768 -114.427401) (xy 174.72872 -114.457951)
			(xy 174.68241 -114.481547) (xy 174.63298 -114.497608) (xy 174.581645 -114.505738) (xy 174.529671 -114.505738)
			(xy 174.478336 -114.497608) (xy 174.428906 -114.481547) (xy 174.382596 -114.457951) (xy 174.340548 -114.427401)
			(xy 174.303797 -114.39065) (xy 174.273247 -114.348602) (xy 174.249651 -114.302292) (xy 174.23359 -114.252862)
			(xy 174.22546 -114.201527) (xy 174.085756 -114.201527) (xy 174.077626 -114.252862) (xy 174.061565 -114.302292)
			(xy 174.037969 -114.348602) (xy 174.007419 -114.39065) (xy 173.970668 -114.427401) (xy 173.92862 -114.457951)
			(xy 173.88231 -114.481547) (xy 173.83288 -114.497608) (xy 173.781545 -114.505738) (xy 173.729571 -114.505738)
			(xy 173.678236 -114.497608) (xy 173.628806 -114.481547) (xy 173.582496 -114.457951) (xy 173.540448 -114.427401)
			(xy 173.503697 -114.39065) (xy 173.473147 -114.348602) (xy 173.449551 -114.302292) (xy 173.43349 -114.252862)
			(xy 173.42536 -114.201527) (xy 173.28591 -114.201527) (xy 173.27778 -114.252862) (xy 173.261719 -114.302292)
			(xy 173.238123 -114.348602) (xy 173.207573 -114.39065) (xy 173.170822 -114.427401) (xy 173.128774 -114.457951)
			(xy 173.082464 -114.481547) (xy 173.033034 -114.497608) (xy 172.981699 -114.505738) (xy 172.929725 -114.505738)
			(xy 172.87839 -114.497608) (xy 172.82896 -114.481547) (xy 172.78265 -114.457951) (xy 172.740602 -114.427401)
			(xy 172.703851 -114.39065) (xy 172.673301 -114.348602) (xy 172.649705 -114.302292) (xy 172.633644 -114.252862)
			(xy 172.625514 -114.201527) (xy 172.48581 -114.201527) (xy 172.47768 -114.252862) (xy 172.461619 -114.302292)
			(xy 172.438023 -114.348602) (xy 172.407473 -114.39065) (xy 172.370722 -114.427401) (xy 172.328674 -114.457951)
			(xy 172.282364 -114.481547) (xy 172.232934 -114.497608) (xy 172.181599 -114.505738) (xy 172.129625 -114.505738)
			(xy 172.07829 -114.497608) (xy 172.02886 -114.481547) (xy 171.98255 -114.457951) (xy 171.940502 -114.427401)
			(xy 171.903751 -114.39065) (xy 171.873201 -114.348602) (xy 171.849605 -114.302292) (xy 171.833544 -114.252862)
			(xy 171.825414 -114.201527) (xy 169.390568 -114.201527) (xy 169.390568 -114.63274) (xy 169.391024 -114.646886)
			(xy 169.398782 -114.674092) (xy 169.413718 -114.698119) (xy 169.434682 -114.717116) (xy 169.460059 -114.729621)
			(xy 169.487895 -114.734671) (xy 169.516048 -114.731877) (xy 169.542348 -114.721454) (xy 169.55389 -114.713258)
			(xy 169.575721 -114.697145) (xy 169.623543 -114.671518) (xy 169.674909 -114.654046) (xy 169.728438 -114.645196)
			(xy 169.755566 -114.644678) (xy 169.781558 -114.645159) (xy 169.832903 -114.653286) (xy 169.882344 -114.669346)
			(xy 169.928664 -114.692943) (xy 169.970722 -114.723496) (xy 170.007482 -114.760252) (xy 170.038039 -114.802307)
			(xy 170.061641 -114.848624) (xy 170.077706 -114.898064) (xy 170.085839 -114.949408) (xy 170.085839 -115.001373)
			(xy 170.225468 -115.001373) (xy 170.225468 -114.949399) (xy 170.233598 -114.898064) (xy 170.249659 -114.848634)
			(xy 170.273255 -114.802324) (xy 170.303805 -114.760276) (xy 170.340556 -114.723525) (xy 170.382604 -114.692975)
			(xy 170.428914 -114.669379) (xy 170.478344 -114.653318) (xy 170.529679 -114.645188) (xy 170.581653 -114.645188)
			(xy 170.632988 -114.653318) (xy 170.682418 -114.669379) (xy 170.728728 -114.692975) (xy 170.770776 -114.723525)
			(xy 170.807527 -114.760276) (xy 170.838077 -114.802324) (xy 170.861673 -114.848634) (xy 170.877734 -114.898064)
			(xy 170.885864 -114.949399) (xy 170.886374 -114.975386) (xy 170.885864 -115.001373) (xy 171.025314 -115.001373)
			(xy 171.025314 -114.949399) (xy 171.033444 -114.898064) (xy 171.049505 -114.848634) (xy 171.073101 -114.802324)
			(xy 171.103651 -114.760276) (xy 171.140402 -114.723525) (xy 171.18245 -114.692975) (xy 171.22876 -114.669379)
			(xy 171.27819 -114.653318) (xy 171.329525 -114.645188) (xy 171.381499 -114.645188) (xy 171.432834 -114.653318)
			(xy 171.482264 -114.669379) (xy 171.528574 -114.692975) (xy 171.570622 -114.723525) (xy 171.607373 -114.760276)
			(xy 171.637923 -114.802324) (xy 171.661519 -114.848634) (xy 171.67758 -114.898064) (xy 171.68571 -114.949399)
			(xy 171.68622 -114.975386) (xy 171.68571 -115.001373) (xy 171.825414 -115.001373) (xy 171.825414 -114.949399)
			(xy 171.833544 -114.898064) (xy 171.849605 -114.848634) (xy 171.873201 -114.802324) (xy 171.903751 -114.760276)
			(xy 171.940502 -114.723525) (xy 171.98255 -114.692975) (xy 172.02886 -114.669379) (xy 172.07829 -114.653318)
			(xy 172.129625 -114.645188) (xy 172.181599 -114.645188) (xy 172.232934 -114.653318) (xy 172.282364 -114.669379)
			(xy 172.328674 -114.692975) (xy 172.370722 -114.723525) (xy 172.407473 -114.760276) (xy 172.438023 -114.802324)
			(xy 172.461619 -114.848634) (xy 172.47768 -114.898064) (xy 172.48581 -114.949399) (xy 172.48632 -114.975386)
			(xy 172.48581 -115.001373) (xy 172.625514 -115.001373) (xy 172.625514 -114.949399) (xy 172.633644 -114.898064)
			(xy 172.649705 -114.848634) (xy 172.673301 -114.802324) (xy 172.703851 -114.760276) (xy 172.740602 -114.723525)
			(xy 172.78265 -114.692975) (xy 172.82896 -114.669379) (xy 172.87839 -114.653318) (xy 172.929725 -114.645188)
			(xy 172.981699 -114.645188) (xy 173.033034 -114.653318) (xy 173.082464 -114.669379) (xy 173.128774 -114.692975)
			(xy 173.170822 -114.723525) (xy 173.207573 -114.760276) (xy 173.238123 -114.802324) (xy 173.261719 -114.848634)
			(xy 173.27778 -114.898064) (xy 173.28591 -114.949399) (xy 173.28642 -114.975386) (xy 173.28591 -115.001373)
			(xy 173.42536 -115.001373) (xy 173.42536 -114.949399) (xy 173.43349 -114.898064) (xy 173.449551 -114.848634)
			(xy 173.473147 -114.802324) (xy 173.503697 -114.760276) (xy 173.540448 -114.723525) (xy 173.582496 -114.692975)
			(xy 173.628806 -114.669379) (xy 173.678236 -114.653318) (xy 173.729571 -114.645188) (xy 173.781545 -114.645188)
			(xy 173.83288 -114.653318) (xy 173.88231 -114.669379) (xy 173.92862 -114.692975) (xy 173.970668 -114.723525)
			(xy 174.007419 -114.760276) (xy 174.037969 -114.802324) (xy 174.061565 -114.848634) (xy 174.077626 -114.898064)
			(xy 174.085756 -114.949399) (xy 174.086266 -114.975386) (xy 174.085756 -115.001373) (xy 174.077626 -115.052708)
			(xy 174.061565 -115.102138) (xy 174.037969 -115.148448) (xy 174.007419 -115.190496) (xy 173.970668 -115.227247)
			(xy 173.92862 -115.257797) (xy 173.88231 -115.281393) (xy 173.83288 -115.297454) (xy 173.781545 -115.305584)
			(xy 173.729571 -115.305584) (xy 173.678236 -115.297454) (xy 173.628806 -115.281393) (xy 173.582496 -115.257797)
			(xy 173.540448 -115.227247) (xy 173.503697 -115.190496) (xy 173.473147 -115.148448) (xy 173.449551 -115.102138)
			(xy 173.43349 -115.052708) (xy 173.42536 -115.001373) (xy 173.28591 -115.001373) (xy 173.27778 -115.052708)
			(xy 173.261719 -115.102138) (xy 173.238123 -115.148448) (xy 173.207573 -115.190496) (xy 173.170822 -115.227247)
			(xy 173.128774 -115.257797) (xy 173.082464 -115.281393) (xy 173.033034 -115.297454) (xy 172.981699 -115.305584)
			(xy 172.929725 -115.305584) (xy 172.87839 -115.297454) (xy 172.82896 -115.281393) (xy 172.78265 -115.257797)
			(xy 172.740602 -115.227247) (xy 172.703851 -115.190496) (xy 172.673301 -115.148448) (xy 172.649705 -115.102138)
			(xy 172.633644 -115.052708) (xy 172.625514 -115.001373) (xy 172.48581 -115.001373) (xy 172.47768 -115.052708)
			(xy 172.461619 -115.102138) (xy 172.438023 -115.148448) (xy 172.407473 -115.190496) (xy 172.370722 -115.227247)
			(xy 172.328674 -115.257797) (xy 172.282364 -115.281393) (xy 172.232934 -115.297454) (xy 172.181599 -115.305584)
			(xy 172.129625 -115.305584) (xy 172.07829 -115.297454) (xy 172.02886 -115.281393) (xy 171.98255 -115.257797)
			(xy 171.940502 -115.227247) (xy 171.903751 -115.190496) (xy 171.873201 -115.148448) (xy 171.849605 -115.102138)
			(xy 171.833544 -115.052708) (xy 171.825414 -115.001373) (xy 171.68571 -115.001373) (xy 171.67758 -115.052708)
			(xy 171.661519 -115.102138) (xy 171.637923 -115.148448) (xy 171.607373 -115.190496) (xy 171.570622 -115.227247)
			(xy 171.528574 -115.257797) (xy 171.482264 -115.281393) (xy 171.432834 -115.297454) (xy 171.381499 -115.305584)
			(xy 171.329525 -115.305584) (xy 171.27819 -115.297454) (xy 171.22876 -115.281393) (xy 171.18245 -115.257797)
			(xy 171.140402 -115.227247) (xy 171.103651 -115.190496) (xy 171.073101 -115.148448) (xy 171.049505 -115.102138)
			(xy 171.033444 -115.052708) (xy 171.025314 -115.001373) (xy 170.885864 -115.001373) (xy 170.877734 -115.052708)
			(xy 170.861673 -115.102138) (xy 170.838077 -115.148448) (xy 170.807527 -115.190496) (xy 170.770776 -115.227247)
			(xy 170.728728 -115.257797) (xy 170.682418 -115.281393) (xy 170.632988 -115.297454) (xy 170.581653 -115.305584)
			(xy 170.529679 -115.305584) (xy 170.478344 -115.297454) (xy 170.428914 -115.281393) (xy 170.382604 -115.257797)
			(xy 170.340556 -115.227247) (xy 170.303805 -115.190496) (xy 170.273255 -115.148448) (xy 170.249659 -115.102138)
			(xy 170.233598 -115.052708) (xy 170.225468 -115.001373) (xy 170.085839 -115.001373) (xy 170.085839 -115.001392)
			(xy 170.077706 -115.052736) (xy 170.061641 -115.102176) (xy 170.038039 -115.148493) (xy 170.007482 -115.190548)
			(xy 169.970722 -115.227304) (xy 169.928664 -115.257857) (xy 169.882344 -115.281454) (xy 169.832903 -115.297514)
			(xy 169.781558 -115.305641) (xy 169.755566 -115.306094) (xy 169.72844 -115.305546) (xy 169.674917 -115.296691)
			(xy 169.623555 -115.279224) (xy 169.57573 -115.253612) (xy 169.55389 -115.237514) (xy 169.542384 -115.229297)
			(xy 169.516085 -115.218944) (xy 169.487956 -115.216199) (xy 169.460152 -115.221272) (xy 169.434804 -115.233773)
			(xy 169.413855 -115.252745) (xy 169.398911 -115.276734) (xy 169.391117 -115.303901) (xy 169.390568 -115.318032)
			(xy 169.390568 -115.43284) (xy 169.391024 -115.446986) (xy 169.398782 -115.474192) (xy 169.413718 -115.498219)
			(xy 169.434682 -115.517216) (xy 169.460059 -115.529721) (xy 169.487895 -115.534771) (xy 169.516048 -115.531977)
			(xy 169.542348 -115.521554) (xy 169.55389 -115.513358) (xy 169.575721 -115.497245) (xy 169.623543 -115.471618)
			(xy 169.674909 -115.454146) (xy 169.728438 -115.445296) (xy 169.755566 -115.444778) (xy 169.781558 -115.445259)
			(xy 169.832903 -115.453386) (xy 169.882344 -115.469446) (xy 169.928664 -115.493043) (xy 169.970722 -115.523596)
			(xy 170.007482 -115.560352) (xy 170.038039 -115.602407) (xy 170.061641 -115.648724) (xy 170.077706 -115.698164)
			(xy 170.085839 -115.749508) (xy 170.085839 -115.801473) (xy 170.225468 -115.801473) (xy 170.225468 -115.749499)
			(xy 170.233598 -115.698164) (xy 170.249659 -115.648734) (xy 170.273255 -115.602424) (xy 170.303805 -115.560376)
			(xy 170.340556 -115.523625) (xy 170.382604 -115.493075) (xy 170.428914 -115.469479) (xy 170.478344 -115.453418)
			(xy 170.529679 -115.445288) (xy 170.581653 -115.445288) (xy 170.632988 -115.453418) (xy 170.682418 -115.469479)
			(xy 170.728728 -115.493075) (xy 170.770776 -115.523625) (xy 170.807527 -115.560376) (xy 170.838077 -115.602424)
			(xy 170.861673 -115.648734) (xy 170.877734 -115.698164) (xy 170.885864 -115.749499) (xy 170.886374 -115.775486)
			(xy 170.885864 -115.801473) (xy 171.025314 -115.801473) (xy 171.025314 -115.749499) (xy 171.033444 -115.698164)
			(xy 171.049505 -115.648734) (xy 171.073101 -115.602424) (xy 171.103651 -115.560376) (xy 171.140402 -115.523625)
			(xy 171.18245 -115.493075) (xy 171.22876 -115.469479) (xy 171.27819 -115.453418) (xy 171.329525 -115.445288)
			(xy 171.381499 -115.445288) (xy 171.432834 -115.453418) (xy 171.482264 -115.469479) (xy 171.528574 -115.493075)
			(xy 171.570622 -115.523625) (xy 171.607373 -115.560376) (xy 171.637923 -115.602424) (xy 171.661519 -115.648734)
			(xy 171.67758 -115.698164) (xy 171.68571 -115.749499) (xy 171.68622 -115.775486) (xy 171.68571 -115.801473)
			(xy 171.825414 -115.801473) (xy 171.825414 -115.749499) (xy 171.833544 -115.698164) (xy 171.849605 -115.648734)
			(xy 171.873201 -115.602424) (xy 171.903751 -115.560376) (xy 171.940502 -115.523625) (xy 171.98255 -115.493075)
			(xy 172.02886 -115.469479) (xy 172.07829 -115.453418) (xy 172.129625 -115.445288) (xy 172.181599 -115.445288)
			(xy 172.232934 -115.453418) (xy 172.282364 -115.469479) (xy 172.328674 -115.493075) (xy 172.370722 -115.523625)
			(xy 172.407473 -115.560376) (xy 172.438023 -115.602424) (xy 172.461619 -115.648734) (xy 172.47768 -115.698164)
			(xy 172.48581 -115.749499) (xy 172.48632 -115.775486) (xy 172.48581 -115.801473) (xy 172.625514 -115.801473)
			(xy 172.625514 -115.749499) (xy 172.633644 -115.698164) (xy 172.649705 -115.648734) (xy 172.673301 -115.602424)
			(xy 172.703851 -115.560376) (xy 172.740602 -115.523625) (xy 172.78265 -115.493075) (xy 172.82896 -115.469479)
			(xy 172.87839 -115.453418) (xy 172.929725 -115.445288) (xy 172.981699 -115.445288) (xy 173.033034 -115.453418)
			(xy 173.082464 -115.469479) (xy 173.128774 -115.493075) (xy 173.170822 -115.523625) (xy 173.207573 -115.560376)
			(xy 173.238123 -115.602424) (xy 173.261719 -115.648734) (xy 173.27778 -115.698164) (xy 173.28591 -115.749499)
			(xy 173.28642 -115.775486) (xy 173.28591 -115.801473) (xy 173.42536 -115.801473) (xy 173.42536 -115.749499)
			(xy 173.43349 -115.698164) (xy 173.449551 -115.648734) (xy 173.473147 -115.602424) (xy 173.503697 -115.560376)
			(xy 173.540448 -115.523625) (xy 173.582496 -115.493075) (xy 173.628806 -115.469479) (xy 173.678236 -115.453418)
			(xy 173.729571 -115.445288) (xy 173.781545 -115.445288) (xy 173.83288 -115.453418) (xy 173.88231 -115.469479)
			(xy 173.92862 -115.493075) (xy 173.970668 -115.523625) (xy 174.007419 -115.560376) (xy 174.037969 -115.602424)
			(xy 174.061565 -115.648734) (xy 174.077626 -115.698164) (xy 174.085756 -115.749499) (xy 174.086266 -115.775486)
			(xy 174.085756 -115.801473) (xy 174.077626 -115.852808) (xy 174.061565 -115.902238) (xy 174.037969 -115.948548)
			(xy 174.007419 -115.990596) (xy 173.970668 -116.027347) (xy 173.92862 -116.057897) (xy 173.88231 -116.081493)
			(xy 173.83288 -116.097554) (xy 173.781545 -116.105684) (xy 173.729571 -116.105684) (xy 173.678236 -116.097554)
			(xy 173.628806 -116.081493) (xy 173.582496 -116.057897) (xy 173.540448 -116.027347) (xy 173.503697 -115.990596)
			(xy 173.473147 -115.948548) (xy 173.449551 -115.902238) (xy 173.43349 -115.852808) (xy 173.42536 -115.801473)
			(xy 173.28591 -115.801473) (xy 173.27778 -115.852808) (xy 173.261719 -115.902238) (xy 173.238123 -115.948548)
			(xy 173.207573 -115.990596) (xy 173.170822 -116.027347) (xy 173.128774 -116.057897) (xy 173.082464 -116.081493)
			(xy 173.033034 -116.097554) (xy 172.981699 -116.105684) (xy 172.929725 -116.105684) (xy 172.87839 -116.097554)
			(xy 172.82896 -116.081493) (xy 172.78265 -116.057897) (xy 172.740602 -116.027347) (xy 172.703851 -115.990596)
			(xy 172.673301 -115.948548) (xy 172.649705 -115.902238) (xy 172.633644 -115.852808) (xy 172.625514 -115.801473)
			(xy 172.48581 -115.801473) (xy 172.47768 -115.852808) (xy 172.461619 -115.902238) (xy 172.438023 -115.948548)
			(xy 172.407473 -115.990596) (xy 172.370722 -116.027347) (xy 172.328674 -116.057897) (xy 172.282364 -116.081493)
			(xy 172.232934 -116.097554) (xy 172.181599 -116.105684) (xy 172.129625 -116.105684) (xy 172.07829 -116.097554)
			(xy 172.02886 -116.081493) (xy 171.98255 -116.057897) (xy 171.940502 -116.027347) (xy 171.903751 -115.990596)
			(xy 171.873201 -115.948548) (xy 171.849605 -115.902238) (xy 171.833544 -115.852808) (xy 171.825414 -115.801473)
			(xy 171.68571 -115.801473) (xy 171.67758 -115.852808) (xy 171.661519 -115.902238) (xy 171.637923 -115.948548)
			(xy 171.607373 -115.990596) (xy 171.570622 -116.027347) (xy 171.528574 -116.057897) (xy 171.482264 -116.081493)
			(xy 171.432834 -116.097554) (xy 171.381499 -116.105684) (xy 171.329525 -116.105684) (xy 171.27819 -116.097554)
			(xy 171.22876 -116.081493) (xy 171.18245 -116.057897) (xy 171.140402 -116.027347) (xy 171.103651 -115.990596)
			(xy 171.073101 -115.948548) (xy 171.049505 -115.902238) (xy 171.033444 -115.852808) (xy 171.025314 -115.801473)
			(xy 170.885864 -115.801473) (xy 170.877734 -115.852808) (xy 170.861673 -115.902238) (xy 170.838077 -115.948548)
			(xy 170.807527 -115.990596) (xy 170.770776 -116.027347) (xy 170.728728 -116.057897) (xy 170.682418 -116.081493)
			(xy 170.632988 -116.097554) (xy 170.581653 -116.105684) (xy 170.529679 -116.105684) (xy 170.478344 -116.097554)
			(xy 170.428914 -116.081493) (xy 170.382604 -116.057897) (xy 170.340556 -116.027347) (xy 170.303805 -115.990596)
			(xy 170.273255 -115.948548) (xy 170.249659 -115.902238) (xy 170.233598 -115.852808) (xy 170.225468 -115.801473)
			(xy 170.085839 -115.801473) (xy 170.085839 -115.801492) (xy 170.077706 -115.852836) (xy 170.061641 -115.902276)
			(xy 170.038039 -115.948593) (xy 170.007482 -115.990648) (xy 169.970722 -116.027404) (xy 169.928664 -116.057957)
			(xy 169.882344 -116.081554) (xy 169.832903 -116.097614) (xy 169.781558 -116.105741) (xy 169.755566 -116.106194)
			(xy 169.72844 -116.105646) (xy 169.674917 -116.096791) (xy 169.623555 -116.079324) (xy 169.57573 -116.053712)
			(xy 169.55389 -116.037614) (xy 169.542384 -116.029397) (xy 169.516085 -116.019044) (xy 169.487956 -116.016299)
			(xy 169.460152 -116.021372) (xy 169.434804 -116.033873) (xy 169.413855 -116.052845) (xy 169.398911 -116.076834)
			(xy 169.391117 -116.104001) (xy 169.390568 -116.118132) (xy 169.390568 -116.23294) (xy 169.391024 -116.247086)
			(xy 169.398782 -116.274292) (xy 169.413718 -116.298319) (xy 169.434682 -116.317316) (xy 169.460059 -116.329821)
			(xy 169.487895 -116.334871) (xy 169.516048 -116.332077) (xy 169.542348 -116.321654) (xy 169.55389 -116.313458)
			(xy 169.575721 -116.297345) (xy 169.623543 -116.271718) (xy 169.674909 -116.254246) (xy 169.728438 -116.245396)
			(xy 169.755566 -116.244878) (xy 169.781558 -116.245359) (xy 169.832903 -116.253486) (xy 169.882344 -116.269546)
			(xy 169.928664 -116.293143) (xy 169.970722 -116.323696) (xy 170.007482 -116.360452) (xy 170.038039 -116.402507)
			(xy 170.061641 -116.448824) (xy 170.077706 -116.498264) (xy 170.085839 -116.549608) (xy 170.085839 -116.601573)
			(xy 170.225468 -116.601573) (xy 170.225468 -116.549599) (xy 170.233598 -116.498264) (xy 170.249659 -116.448834)
			(xy 170.273255 -116.402524) (xy 170.303805 -116.360476) (xy 170.340556 -116.323725) (xy 170.382604 -116.293175)
			(xy 170.428914 -116.269579) (xy 170.478344 -116.253518) (xy 170.529679 -116.245388) (xy 170.581653 -116.245388)
			(xy 170.632988 -116.253518) (xy 170.682418 -116.269579) (xy 170.728728 -116.293175) (xy 170.770776 -116.323725)
			(xy 170.807527 -116.360476) (xy 170.838077 -116.402524) (xy 170.861673 -116.448834) (xy 170.877734 -116.498264)
			(xy 170.885864 -116.549599) (xy 170.886374 -116.575586) (xy 170.885864 -116.601573) (xy 171.025314 -116.601573)
			(xy 171.025314 -116.549599) (xy 171.033444 -116.498264) (xy 171.049505 -116.448834) (xy 171.073101 -116.402524)
			(xy 171.103651 -116.360476) (xy 171.140402 -116.323725) (xy 171.18245 -116.293175) (xy 171.22876 -116.269579)
			(xy 171.27819 -116.253518) (xy 171.329525 -116.245388) (xy 171.381499 -116.245388) (xy 171.432834 -116.253518)
			(xy 171.482264 -116.269579) (xy 171.528574 -116.293175) (xy 171.570622 -116.323725) (xy 171.607373 -116.360476)
			(xy 171.637923 -116.402524) (xy 171.661519 -116.448834) (xy 171.67758 -116.498264) (xy 171.68571 -116.549599)
			(xy 171.68622 -116.575586) (xy 171.68571 -116.601573) (xy 171.825414 -116.601573) (xy 171.825414 -116.549599)
			(xy 171.833544 -116.498264) (xy 171.849605 -116.448834) (xy 171.873201 -116.402524) (xy 171.903751 -116.360476)
			(xy 171.940502 -116.323725) (xy 171.98255 -116.293175) (xy 172.02886 -116.269579) (xy 172.07829 -116.253518)
			(xy 172.129625 -116.245388) (xy 172.181599 -116.245388) (xy 172.232934 -116.253518) (xy 172.282364 -116.269579)
			(xy 172.328674 -116.293175) (xy 172.370722 -116.323725) (xy 172.407473 -116.360476) (xy 172.438023 -116.402524)
			(xy 172.461619 -116.448834) (xy 172.47768 -116.498264) (xy 172.48581 -116.549599) (xy 172.48632 -116.575586)
			(xy 172.48581 -116.601573) (xy 172.625514 -116.601573) (xy 172.625514 -116.549599) (xy 172.633644 -116.498264)
			(xy 172.649705 -116.448834) (xy 172.673301 -116.402524) (xy 172.703851 -116.360476) (xy 172.740602 -116.323725)
			(xy 172.78265 -116.293175) (xy 172.82896 -116.269579) (xy 172.87839 -116.253518) (xy 172.929725 -116.245388)
			(xy 172.981699 -116.245388) (xy 173.033034 -116.253518) (xy 173.082464 -116.269579) (xy 173.128774 -116.293175)
			(xy 173.170822 -116.323725) (xy 173.207573 -116.360476) (xy 173.238123 -116.402524) (xy 173.261719 -116.448834)
			(xy 173.27778 -116.498264) (xy 173.28591 -116.549599) (xy 173.28642 -116.575586) (xy 173.28591 -116.601573)
			(xy 173.27778 -116.652908) (xy 173.261719 -116.702338) (xy 173.238123 -116.748648) (xy 173.207573 -116.790696)
			(xy 173.170822 -116.827447) (xy 173.128774 -116.857997) (xy 173.082464 -116.881593) (xy 173.033034 -116.897654)
			(xy 172.981699 -116.905784) (xy 172.929725 -116.905784) (xy 172.87839 -116.897654) (xy 172.82896 -116.881593)
			(xy 172.78265 -116.857997) (xy 172.740602 -116.827447) (xy 172.703851 -116.790696) (xy 172.673301 -116.748648)
			(xy 172.649705 -116.702338) (xy 172.633644 -116.652908) (xy 172.625514 -116.601573) (xy 172.48581 -116.601573)
			(xy 172.47768 -116.652908) (xy 172.461619 -116.702338) (xy 172.438023 -116.748648) (xy 172.407473 -116.790696)
			(xy 172.370722 -116.827447) (xy 172.328674 -116.857997) (xy 172.282364 -116.881593) (xy 172.232934 -116.897654)
			(xy 172.181599 -116.905784) (xy 172.129625 -116.905784) (xy 172.07829 -116.897654) (xy 172.02886 -116.881593)
			(xy 171.98255 -116.857997) (xy 171.940502 -116.827447) (xy 171.903751 -116.790696) (xy 171.873201 -116.748648)
			(xy 171.849605 -116.702338) (xy 171.833544 -116.652908) (xy 171.825414 -116.601573) (xy 171.68571 -116.601573)
			(xy 171.67758 -116.652908) (xy 171.661519 -116.702338) (xy 171.637923 -116.748648) (xy 171.607373 -116.790696)
			(xy 171.570622 -116.827447) (xy 171.528574 -116.857997) (xy 171.482264 -116.881593) (xy 171.432834 -116.897654)
			(xy 171.381499 -116.905784) (xy 171.329525 -116.905784) (xy 171.27819 -116.897654) (xy 171.22876 -116.881593)
			(xy 171.18245 -116.857997) (xy 171.140402 -116.827447) (xy 171.103651 -116.790696) (xy 171.073101 -116.748648)
			(xy 171.049505 -116.702338) (xy 171.033444 -116.652908) (xy 171.025314 -116.601573) (xy 170.885864 -116.601573)
			(xy 170.877734 -116.652908) (xy 170.861673 -116.702338) (xy 170.838077 -116.748648) (xy 170.807527 -116.790696)
			(xy 170.770776 -116.827447) (xy 170.728728 -116.857997) (xy 170.682418 -116.881593) (xy 170.632988 -116.897654)
			(xy 170.581653 -116.905784) (xy 170.529679 -116.905784) (xy 170.478344 -116.897654) (xy 170.428914 -116.881593)
			(xy 170.382604 -116.857997) (xy 170.340556 -116.827447) (xy 170.303805 -116.790696) (xy 170.273255 -116.748648)
			(xy 170.249659 -116.702338) (xy 170.233598 -116.652908) (xy 170.225468 -116.601573) (xy 170.085839 -116.601573)
			(xy 170.085839 -116.601592) (xy 170.077706 -116.652936) (xy 170.061641 -116.702376) (xy 170.038039 -116.748693)
			(xy 170.007482 -116.790748) (xy 169.970722 -116.827504) (xy 169.928664 -116.858057) (xy 169.882344 -116.881654)
			(xy 169.832903 -116.897714) (xy 169.781558 -116.905841) (xy 169.755566 -116.906294) (xy 169.72844 -116.905746)
			(xy 169.674917 -116.896891) (xy 169.623555 -116.879424) (xy 169.57573 -116.853812) (xy 169.55389 -116.837714)
			(xy 169.542384 -116.829497) (xy 169.516085 -116.819144) (xy 169.487956 -116.816399) (xy 169.460152 -116.821472)
			(xy 169.434804 -116.833973) (xy 169.413855 -116.852945) (xy 169.398911 -116.876934) (xy 169.391117 -116.904101)
			(xy 169.390568 -116.918232) (xy 169.390568 -116.98605) (xy 169.391074 -117.00091) (xy 169.399618 -117.029374)
			(xy 169.415997 -117.054173) (xy 169.438823 -117.073204) (xy 169.466163 -117.084856) (xy 169.4957 -117.088142)
			(xy 169.524932 -117.082783) (xy 169.538396 -117.076474) (xy 169.561835 -117.065025) (xy 169.611422 -117.048841)
			(xy 169.662937 -117.040649) (xy 169.689018 -117.040152) (xy 169.715007 -117.040663) (xy 169.766346 -117.048797)
			(xy 169.81578 -117.064861) (xy 169.862093 -117.088461) (xy 169.904143 -117.119015) (xy 169.940897 -117.15577)
			(xy 169.971448 -117.197823) (xy 169.995046 -117.244137) (xy 170.011107 -117.293572) (xy 170.019238 -117.344911)
			(xy 170.019238 -117.396889) (xy 170.018521 -117.401419) (xy 170.225468 -117.401419) (xy 170.225468 -117.349445)
			(xy 170.233598 -117.29811) (xy 170.249659 -117.24868) (xy 170.273255 -117.20237) (xy 170.303805 -117.160322)
			(xy 170.340556 -117.123571) (xy 170.382604 -117.093021) (xy 170.428914 -117.069425) (xy 170.478344 -117.053364)
			(xy 170.529679 -117.045234) (xy 170.581653 -117.045234) (xy 170.632988 -117.053364) (xy 170.682418 -117.069425)
			(xy 170.728728 -117.093021) (xy 170.770776 -117.123571) (xy 170.807527 -117.160322) (xy 170.838077 -117.20237)
			(xy 170.861673 -117.24868) (xy 170.877734 -117.29811) (xy 170.885864 -117.349445) (xy 170.886374 -117.375432)
			(xy 170.885864 -117.401419) (xy 171.825414 -117.401419) (xy 171.825414 -117.349445) (xy 171.833544 -117.29811)
			(xy 171.849605 -117.24868) (xy 171.873201 -117.20237) (xy 171.903751 -117.160322) (xy 171.940502 -117.123571)
			(xy 171.98255 -117.093021) (xy 172.02886 -117.069425) (xy 172.07829 -117.053364) (xy 172.129625 -117.045234)
			(xy 172.181599 -117.045234) (xy 172.232934 -117.053364) (xy 172.282364 -117.069425) (xy 172.328674 -117.093021)
			(xy 172.370722 -117.123571) (xy 172.407473 -117.160322) (xy 172.438023 -117.20237) (xy 172.461619 -117.24868)
			(xy 172.47768 -117.29811) (xy 172.48581 -117.349445) (xy 172.48632 -117.375432) (xy 172.48581 -117.401419)
			(xy 172.47768 -117.452754) (xy 172.461619 -117.502184) (xy 172.438023 -117.548494) (xy 172.407473 -117.590542)
			(xy 172.370722 -117.627293) (xy 172.328674 -117.657843) (xy 172.282364 -117.681439) (xy 172.232934 -117.6975)
			(xy 172.181599 -117.70563) (xy 172.129625 -117.70563) (xy 172.07829 -117.6975) (xy 172.02886 -117.681439)
			(xy 171.98255 -117.657843) (xy 171.940502 -117.627293) (xy 171.903751 -117.590542) (xy 171.873201 -117.548494)
			(xy 171.849605 -117.502184) (xy 171.833544 -117.452754) (xy 171.825414 -117.401419) (xy 170.885864 -117.401419)
			(xy 170.877734 -117.452754) (xy 170.861673 -117.502184) (xy 170.838077 -117.548494) (xy 170.807527 -117.590542)
			(xy 170.770776 -117.627293) (xy 170.728728 -117.657843) (xy 170.682418 -117.681439) (xy 170.632988 -117.6975)
			(xy 170.581653 -117.70563) (xy 170.529679 -117.70563) (xy 170.478344 -117.6975) (xy 170.428914 -117.681439)
			(xy 170.382604 -117.657843) (xy 170.340556 -117.627293) (xy 170.303805 -117.590542) (xy 170.273255 -117.548494)
			(xy 170.249659 -117.502184) (xy 170.233598 -117.452754) (xy 170.225468 -117.401419) (xy 170.018521 -117.401419)
			(xy 170.011107 -117.448228) (xy 169.995046 -117.497663) (xy 169.971448 -117.543977) (xy 169.940897 -117.58603)
			(xy 169.904143 -117.622785) (xy 169.862093 -117.653339) (xy 169.81578 -117.676939) (xy 169.766346 -117.693003)
			(xy 169.715007 -117.701137) (xy 169.689018 -117.701568) (xy 169.66562 -117.701165) (xy 169.619292 -117.694576)
			(xy 169.574353 -117.681527) (xy 169.5317 -117.662278) (xy 169.492183 -117.637214) (xy 169.474134 -117.62232)
			(xy 169.466501 -117.616404) (xy 169.448209 -117.610257) (xy 169.428941 -117.6113) (xy 169.411421 -117.619387)
			(xy 169.398126 -117.633373) (xy 169.390938 -117.651281) (xy 169.390568 -117.660928) (xy 169.390568 -117.737382)
			(xy 169.559478 -117.906546) (xy 169.593006 -117.887496) (xy 169.617978 -117.87408) (xy 169.671371 -117.855051)
			(xy 169.727225 -117.845392) (xy 169.755566 -117.844824) (xy 169.784527 -117.845427) (xy 169.841564 -117.855513)
			(xy 169.895978 -117.875366) (xy 169.946109 -117.90438) (xy 169.968672 -117.922548)
		)
		(stroke
			(width 0)
			(type solid)
		)
		(fill yes)
		(layer "In4.Cu")
		(net "P3V3_AUX_FPGA_VCCIO0")
	)
	(gr_poly
		(pts
			(xy 469.65108 -76.647548) (xy 469.65108 -55.926228) (xy 460.8322 -47.107348) (xy 441.005214 -47.107348)
			(xy 440.990736 -47.134272) (xy 440.977411 -47.158418) (xy 440.944869 -47.202943) (xy 440.906253 -47.242315)
			(xy 440.862367 -47.275714) (xy 440.814127 -47.302442) (xy 440.762541 -47.321942) (xy 440.708683 -47.333807)
			(xy 440.653678 -47.33779) (xy 440.598673 -47.333807) (xy 440.544815 -47.321942) (xy 440.493229 -47.302442)
			(xy 440.444989 -47.275714) (xy 440.401103 -47.242315) (xy 440.362487 -47.202943) (xy 440.329945 -47.158418)
			(xy 440.31662 -47.134272) (xy 440.302142 -47.107348) (xy 438.084976 -47.107348) (xy 438.07987 -47.133992)
			(xy 438.063196 -47.185614) (xy 438.039492 -47.234411) (xy 438.009221 -47.279429) (xy 437.972973 -47.319791)
			(xy 437.931456 -47.354709) (xy 437.885479 -47.383503) (xy 437.835938 -47.40561) (xy 437.783801 -47.4206)
			(xy 437.730084 -47.42818) (xy 437.70296 -47.428658) (xy 437.675832 -47.428208) (xy 437.622104 -47.420651)
			(xy 437.569954 -47.405675) (xy 437.520403 -47.383575) (xy 437.474417 -47.354781) (xy 437.432895 -47.319855)
			(xy 437.39665 -47.279481) (xy 437.366388 -47.234448) (xy 437.342701 -47.185635) (xy 437.326052 -47.133995)
			(xy 437.320944 -47.107348) (xy 435.4322 -47.107348) (xy 433.96154 -48.578008) (xy 436.577232 -48.578008)
			(xy 436.577787 -48.549327) (xy 436.586396 -48.492615) (xy 436.603391 -48.437828) (xy 436.62839 -48.3862)
			(xy 436.66083 -48.338892) (xy 436.699982 -48.296969) (xy 436.744964 -48.261374) (xy 436.794764 -48.232907)
			(xy 436.848262 -48.212211) (xy 436.904254 -48.199749) (xy 436.932832 -48.197262) (xy 436.947352 -48.195752)
			(xy 436.974693 -48.18556) (xy 436.998039 -48.168055) (xy 437.015484 -48.144666) (xy 437.025607 -48.117298)
			(xy 437.027066 -48.102774) (xy 437.029521 -48.074186) (xy 437.041948 -48.018171) (xy 437.062623 -47.964649)
			(xy 437.091079 -47.914826) (xy 437.126675 -47.869826) (xy 437.168609 -47.830663) (xy 437.215933 -47.798221)
			(xy 437.267582 -47.773231) (xy 437.322391 -47.756258) (xy 437.379123 -47.747683) (xy 437.407812 -47.747174)
			(xy 437.435063 -47.747667) (xy 437.489009 -47.755424) (xy 437.541303 -47.77078) (xy 437.590879 -47.793421)
			(xy 437.636728 -47.822887) (xy 437.677918 -47.858578) (xy 437.713609 -47.899767) (xy 437.743076 -47.945616)
			(xy 437.765718 -47.995192) (xy 437.781074 -48.047485) (xy 437.788833 -48.101431) (xy 437.78932 -48.128682)
			(xy 437.7888 -48.157365) (xy 437.780192 -48.214081) (xy 437.763195 -48.268871) (xy 437.738194 -48.320502)
			(xy 437.70575 -48.367812) (xy 437.666594 -48.409736) (xy 437.621606 -48.445331) (xy 437.574339 -48.472344)
			(xy 445.193418 -48.472344) (xy 445.197489 -48.416722) (xy 445.209615 -48.362285) (xy 445.229538 -48.310194)
			(xy 445.256834 -48.261559) (xy 445.29092 -48.217416) (xy 445.331069 -48.178707) (xy 445.376427 -48.146256)
			(xy 445.426027 -48.120755) (xy 445.478811 -48.102748) (xy 445.533654 -48.092618) (xy 445.589388 -48.090581)
			(xy 445.644825 -48.096681) (xy 445.698782 -48.110787) (xy 445.750111 -48.132599) (xy 445.797717 -48.161653)
			(xy 445.840585 -48.197328) (xy 445.877802 -48.238865) (xy 445.908575 -48.285378) (xy 445.932247 -48.335875)
			(xy 445.948315 -48.389282) (xy 445.956435 -48.444458) (xy 445.956944 -48.472344) (xy 445.956435 -48.50023)
			(xy 445.948315 -48.555406) (xy 445.932247 -48.608813) (xy 445.908575 -48.65931) (xy 445.877802 -48.705823)
			(xy 445.840585 -48.74736) (xy 445.797717 -48.783035) (xy 445.750111 -48.812089) (xy 445.698782 -48.833901)
			(xy 445.644825 -48.848007) (xy 445.589388 -48.854107) (xy 445.533654 -48.85207) (xy 445.478811 -48.84194)
			(xy 445.426027 -48.823933) (xy 445.376427 -48.798432) (xy 445.331069 -48.765981) (xy 445.29092 -48.727272)
			(xy 445.256834 -48.683129) (xy 445.229538 -48.634494) (xy 445.209615 -48.582403) (xy 445.197489 -48.527966)
			(xy 445.193418 -48.472344) (xy 437.574339 -48.472344) (xy 437.5718 -48.473795) (xy 437.518297 -48.494488)
			(xy 437.4623 -48.506944) (xy 437.43372 -48.509428) (xy 437.419197 -48.510909) (xy 437.391856 -48.521112)
			(xy 437.368513 -48.538625) (xy 437.351069 -48.56202) (xy 437.340946 -48.58939) (xy 437.339486 -48.603916)
			(xy 437.336971 -48.632497) (xy 437.324548 -48.688507) (xy 437.303878 -48.742026) (xy 437.275428 -48.791846)
			(xy 437.239838 -48.836845) (xy 437.197912 -48.876008) (xy 437.150595 -48.908451) (xy 437.098954 -48.933444)
			(xy 437.044152 -48.950422) (xy 436.987426 -48.959004) (xy 436.95874 -48.959516) (xy 436.931488 -48.959008)
			(xy 436.87754 -48.951256) (xy 436.825243 -48.935906) (xy 436.775664 -48.913268) (xy 436.729811 -48.883805)
			(xy 436.688618 -48.848116) (xy 436.652924 -48.806928) (xy 436.623455 -48.761079) (xy 436.600811 -48.711502)
			(xy 436.585454 -48.659207) (xy 436.577696 -48.605259) (xy 436.577232 -48.578008) (xy 433.96154 -48.578008)
			(xy 433.063142 -49.476406) (xy 448.662047 -49.476406) (xy 448.666083 -49.392959) (xy 448.678155 -49.310291)
			(xy 448.698148 -49.229174) (xy 448.725877 -49.150365) (xy 448.761083 -49.0746) (xy 448.803437 -49.002587)
			(xy 448.852543 -48.934998) (xy 448.907944 -48.872464) (xy 448.969121 -48.815569) (xy 449.035504 -48.764843)
			(xy 449.106472 -48.720762) (xy 449.181364 -48.683736) (xy 449.25948 -48.65411) (xy 449.34009 -48.632162)
			(xy 449.422442 -48.618097) (xy 449.505768 -48.612045) (xy 449.589288 -48.614064) (xy 449.672224 -48.624134)
			(xy 449.7538 -48.642162) (xy 449.833256 -48.667979) (xy 449.909849 -48.701344) (xy 449.982865 -48.741945)
			(xy 450.051621 -48.789404) (xy 450.115475 -48.843277) (xy 450.173832 -48.903062) (xy 450.226147 -48.968199)
			(xy 450.27193 -49.038082) (xy 450.310755 -49.112057) (xy 450.34226 -49.189434) (xy 450.366149 -49.269491)
			(xy 450.3822 -49.351479) (xy 450.390263 -49.434634) (xy 450.390768 -49.476406) (xy 456.170287 -49.476406)
			(xy 456.174323 -49.392959) (xy 456.186395 -49.310291) (xy 456.206388 -49.229174) (xy 456.234117 -49.150365)
			(xy 456.269323 -49.0746) (xy 456.311677 -49.002587) (xy 456.360783 -48.934998) (xy 456.416184 -48.872464)
			(xy 456.477361 -48.815569) (xy 456.543744 -48.764843) (xy 456.614712 -48.720762) (xy 456.689604 -48.683736)
			(xy 456.76772 -48.65411) (xy 456.84833 -48.632162) (xy 456.930682 -48.618097) (xy 457.014008 -48.612045)
			(xy 457.097528 -48.614064) (xy 457.180464 -48.624134) (xy 457.26204 -48.642162) (xy 457.341496 -48.667979)
			(xy 457.418089 -48.701344) (xy 457.491105 -48.741945) (xy 457.559861 -48.789404) (xy 457.623715 -48.843277)
			(xy 457.682072 -48.903062) (xy 457.734387 -48.968199) (xy 457.78017 -49.038082) (xy 457.818995 -49.112057)
			(xy 457.8505 -49.189434) (xy 457.874389 -49.269491) (xy 457.89044 -49.351479) (xy 457.898503 -49.434634)
			(xy 457.899008 -49.476406) (xy 457.898503 -49.518178) (xy 457.89044 -49.601333) (xy 457.874389 -49.683321)
			(xy 457.8505 -49.763378) (xy 457.818995 -49.840755) (xy 457.78017 -49.91473) (xy 457.734387 -49.984613)
			(xy 457.682072 -50.04975) (xy 457.623715 -50.109535) (xy 457.559861 -50.163408) (xy 457.491105 -50.210867)
			(xy 457.418089 -50.251468) (xy 457.341496 -50.284833) (xy 457.26204 -50.31065) (xy 457.180464 -50.328678)
			(xy 457.097528 -50.338748) (xy 457.014008 -50.340767) (xy 456.930682 -50.334715) (xy 456.84833 -50.32065)
			(xy 456.76772 -50.298702) (xy 456.689604 -50.269076) (xy 456.614712 -50.23205) (xy 456.543744 -50.187969)
			(xy 456.477361 -50.137243) (xy 456.416184 -50.080348) (xy 456.360783 -50.017814) (xy 456.311677 -49.950225)
			(xy 456.269323 -49.878212) (xy 456.234117 -49.802447) (xy 456.206388 -49.723638) (xy 456.186395 -49.642521)
			(xy 456.174323 -49.559853) (xy 456.170287 -49.476406) (xy 450.390768 -49.476406) (xy 450.390263 -49.518178)
			(xy 450.3822 -49.601333) (xy 450.366149 -49.683321) (xy 450.34226 -49.763378) (xy 450.310755 -49.840755)
			(xy 450.27193 -49.91473) (xy 450.226147 -49.984613) (xy 450.173832 -50.04975) (xy 450.115475 -50.109535)
			(xy 450.051621 -50.163408) (xy 449.982865 -50.210867) (xy 449.909849 -50.251468) (xy 449.833256 -50.284833)
			(xy 449.7538 -50.31065) (xy 449.672224 -50.328678) (xy 449.589288 -50.338748) (xy 449.505768 -50.340767)
			(xy 449.422442 -50.334715) (xy 449.34009 -50.32065) (xy 449.25948 -50.298702) (xy 449.181364 -50.269076)
			(xy 449.106472 -50.23205) (xy 449.035504 -50.187969) (xy 448.969121 -50.137243) (xy 448.907944 -50.080348)
			(xy 448.852543 -50.017814) (xy 448.803437 -49.950225) (xy 448.761083 -49.878212) (xy 448.725877 -49.802447)
			(xy 448.698148 -49.723638) (xy 448.678155 -49.642521) (xy 448.666083 -49.559853) (xy 448.662047 -49.476406)
			(xy 433.063142 -49.476406) (xy 430.525428 -52.01412) (xy 432.050442 -52.01412) (xy 432.054513 -51.958498)
			(xy 432.066639 -51.904061) (xy 432.086562 -51.85197) (xy 432.113858 -51.803335) (xy 432.147944 -51.759192)
			(xy 432.188093 -51.720483) (xy 432.233451 -51.688032) (xy 432.283051 -51.662531) (xy 432.335835 -51.644524)
			(xy 432.390678 -51.634394) (xy 432.446412 -51.632357) (xy 432.501849 -51.638457) (xy 432.555806 -51.652563)
			(xy 432.607135 -51.674375) (xy 432.654741 -51.703429) (xy 432.697609 -51.739104) (xy 432.734826 -51.780641)
			(xy 432.765599 -51.827154) (xy 432.789271 -51.877651) (xy 432.805339 -51.931058) (xy 432.813459 -51.986234)
			(xy 432.813968 -52.01412) (xy 432.813881 -52.018876) (xy 448.637656 -52.018876) (xy 448.637656 -51.93418)
			(xy 448.645707 -51.849866) (xy 448.661736 -51.7667) (xy 448.685597 -51.685433) (xy 448.717076 -51.606803)
			(xy 448.755887 -51.531522) (xy 448.801677 -51.46027) (xy 448.854033 -51.393694) (xy 448.912481 -51.332396)
			(xy 448.976491 -51.276931) (xy 449.045483 -51.227802) (xy 449.118833 -51.185453) (xy 449.195876 -51.150269)
			(xy 449.275915 -51.122567) (xy 449.358224 -51.102599) (xy 449.442059 -51.090546) (xy 449.52666 -51.086516)
			(xy 449.611261 -51.090546) (xy 449.695096 -51.102599) (xy 449.777405 -51.122567) (xy 449.857444 -51.150269)
			(xy 449.934487 -51.185453) (xy 450.007837 -51.227802) (xy 450.076829 -51.276931) (xy 450.140839 -51.332396)
			(xy 450.199287 -51.393694) (xy 450.251643 -51.46027) (xy 450.297433 -51.531522) (xy 450.336244 -51.606803)
			(xy 450.367723 -51.685433) (xy 450.391584 -51.7667) (xy 450.407613 -51.849866) (xy 450.415664 -51.93418)
			(xy 450.416168 -51.976528) (xy 450.415664 -52.018876) (xy 456.145896 -52.018876) (xy 456.145896 -51.93418)
			(xy 456.153947 -51.849866) (xy 456.169976 -51.7667) (xy 456.193837 -51.685433) (xy 456.225316 -51.606803)
			(xy 456.264127 -51.531522) (xy 456.309917 -51.46027) (xy 456.362273 -51.393694) (xy 456.420721 -51.332396)
			(xy 456.484731 -51.276931) (xy 456.553723 -51.227802) (xy 456.627073 -51.185453) (xy 456.704116 -51.150269)
			(xy 456.784155 -51.122567) (xy 456.866464 -51.102599) (xy 456.950299 -51.090546) (xy 457.0349 -51.086516)
			(xy 457.119501 -51.090546) (xy 457.203336 -51.102599) (xy 457.285645 -51.122567) (xy 457.365684 -51.150269)
			(xy 457.442727 -51.185453) (xy 457.516077 -51.227802) (xy 457.585069 -51.276931) (xy 457.649079 -51.332396)
			(xy 457.707527 -51.393694) (xy 457.759883 -51.46027) (xy 457.805673 -51.531522) (xy 457.844484 -51.606803)
			(xy 457.875963 -51.685433) (xy 457.899824 -51.7667) (xy 457.915853 -51.849866) (xy 457.923904 -51.93418)
			(xy 457.924408 -51.976528) (xy 457.923904 -52.018876) (xy 457.915853 -52.10319) (xy 457.899824 -52.186356)
			(xy 457.875963 -52.267623) (xy 457.844484 -52.346253) (xy 457.805673 -52.421534) (xy 457.759883 -52.492786)
			(xy 457.707527 -52.559362) (xy 457.649079 -52.62066) (xy 457.585069 -52.676125) (xy 457.516077 -52.725254)
			(xy 457.442727 -52.767603) (xy 457.365684 -52.802787) (xy 457.285645 -52.830489) (xy 457.203336 -52.850457)
			(xy 457.119501 -52.86251) (xy 457.0349 -52.866541) (xy 456.950299 -52.86251) (xy 456.866464 -52.850457)
			(xy 456.784155 -52.830489) (xy 456.704116 -52.802787) (xy 456.627073 -52.767603) (xy 456.553723 -52.725254)
			(xy 456.484731 -52.676125) (xy 456.420721 -52.62066) (xy 456.362273 -52.559362) (xy 456.309917 -52.492786)
			(xy 456.264127 -52.421534) (xy 456.225316 -52.346253) (xy 456.193837 -52.267623) (xy 456.169976 -52.186356)
			(xy 456.153947 -52.10319) (xy 456.145896 -52.018876) (xy 450.415664 -52.018876) (xy 450.407613 -52.10319)
			(xy 450.391584 -52.186356) (xy 450.367723 -52.267623) (xy 450.336244 -52.346253) (xy 450.297433 -52.421534)
			(xy 450.251643 -52.492786) (xy 450.199287 -52.559362) (xy 450.140839 -52.62066) (xy 450.076829 -52.676125)
			(xy 450.007837 -52.725254) (xy 449.934487 -52.767603) (xy 449.857444 -52.802787) (xy 449.777405 -52.830489)
			(xy 449.695096 -52.850457) (xy 449.611261 -52.86251) (xy 449.52666 -52.866541) (xy 449.442059 -52.86251)
			(xy 449.358224 -52.850457) (xy 449.275915 -52.830489) (xy 449.195876 -52.802787) (xy 449.118833 -52.767603)
			(xy 449.045483 -52.725254) (xy 448.976491 -52.676125) (xy 448.912481 -52.62066) (xy 448.854033 -52.559362)
			(xy 448.801677 -52.492786) (xy 448.755887 -52.421534) (xy 448.717076 -52.346253) (xy 448.685597 -52.267623)
			(xy 448.661736 -52.186356) (xy 448.645707 -52.10319) (xy 448.637656 -52.018876) (xy 432.813881 -52.018876)
			(xy 432.813459 -52.042006) (xy 432.805339 -52.097182) (xy 432.789271 -52.150589) (xy 432.765599 -52.201086)
			(xy 432.734826 -52.247599) (xy 432.697609 -52.289136) (xy 432.654741 -52.324811) (xy 432.607135 -52.353865)
			(xy 432.555806 -52.375677) (xy 432.501849 -52.389783) (xy 432.446412 -52.395883) (xy 432.390678 -52.393846)
			(xy 432.335835 -52.383716) (xy 432.283051 -52.365709) (xy 432.233451 -52.340208) (xy 432.188093 -52.307757)
			(xy 432.147944 -52.269048) (xy 432.113858 -52.224905) (xy 432.086562 -52.17627) (xy 432.066639 -52.124179)
			(xy 432.054513 -52.069742) (xy 432.050442 -52.01412) (xy 430.525428 -52.01412) (xy 430.022 -52.517548)
			(xy 444.575182 -52.517548) (xy 444.579253 -52.461926) (xy 444.591379 -52.407489) (xy 444.611302 -52.355398)
			(xy 444.638598 -52.306763) (xy 444.672684 -52.26262) (xy 444.712833 -52.223911) (xy 444.758191 -52.19146)
			(xy 444.807791 -52.165959) (xy 444.860575 -52.147952) (xy 444.915418 -52.137822) (xy 444.971152 -52.135785)
			(xy 445.026589 -52.141885) (xy 445.080546 -52.155991) (xy 445.131875 -52.177803) (xy 445.179481 -52.206857)
			(xy 445.222349 -52.242532) (xy 445.259566 -52.284069) (xy 445.290339 -52.330582) (xy 445.314011 -52.381079)
			(xy 445.330079 -52.434486) (xy 445.338199 -52.489662) (xy 445.338708 -52.517548) (xy 445.338199 -52.545434)
			(xy 445.330079 -52.60061) (xy 445.314011 -52.654017) (xy 445.290339 -52.704514) (xy 445.259566 -52.751027)
			(xy 445.222349 -52.792564) (xy 445.179481 -52.828239) (xy 445.131875 -52.857293) (xy 445.080546 -52.879105)
			(xy 445.026589 -52.893211) (xy 444.971152 -52.899311) (xy 444.915418 -52.897274) (xy 444.860575 -52.887144)
			(xy 444.807791 -52.869137) (xy 444.758191 -52.843636) (xy 444.712833 -52.811185) (xy 444.672684 -52.772476)
			(xy 444.638598 -52.728333) (xy 444.611302 -52.679698) (xy 444.591379 -52.627607) (xy 444.579253 -52.57317)
			(xy 444.575182 -52.517548) (xy 430.022 -52.517548) (xy 429.38446 -53.155088) (xy 429.38446 -54.534816)
			(xy 429.758856 -54.534816) (xy 429.759318 -54.507445) (xy 429.767135 -54.453266) (xy 429.782624 -54.400762)
			(xy 429.805467 -54.351015) (xy 429.835194 -54.305049) (xy 429.852836 -54.284118) (xy 429.862055 -54.272778)
			(xy 429.874229 -54.246224) (xy 429.878403 -54.217312) (xy 429.874236 -54.188399) (xy 429.862068 -54.161842)
			(xy 429.852836 -54.150514) (xy 429.835196 -54.129583) (xy 429.805483 -54.08361) (xy 429.782646 -54.033863)
			(xy 429.767156 -53.981362) (xy 429.759329 -53.927185) (xy 429.758856 -53.899816) (xy 429.759435 -53.869693)
			(xy 429.768914 -53.810197) (xy 429.787623 -53.752929) (xy 429.815097 -53.699312) (xy 429.850654 -53.650677)
			(xy 429.871632 -53.629052) (xy 429.880834 -53.619316) (xy 429.89428 -53.596158) (xy 429.901244 -53.570301)
			(xy 429.901247 -53.543522) (xy 429.894288 -53.517663) (xy 429.880847 -53.494502) (xy 429.871632 -53.48478)
			(xy 429.850671 -53.463138) (xy 429.815099 -53.414514) (xy 429.787614 -53.360902) (xy 429.768902 -53.303636)
			(xy 429.759426 -53.244139) (xy 429.758856 -53.214016) (xy 429.759393 -53.186767) (xy 429.767146 -53.132823)
			(xy 429.782498 -53.080531) (xy 429.805134 -53.030957) (xy 429.834596 -52.985108) (xy 429.870282 -52.943918)
			(xy 429.911466 -52.908227) (xy 429.957311 -52.878759) (xy 430.006883 -52.856116) (xy 430.059172 -52.840757)
			(xy 430.113115 -52.832997) (xy 430.140364 -52.832508) (xy 430.166824 -52.832931) (xy 430.219233 -52.840271)
			(xy 430.270124 -52.854787) (xy 430.318518 -52.876201) (xy 430.363487 -52.904102) (xy 430.404166 -52.937952)
			(xy 430.422304 -52.957222) (xy 430.433109 -52.968182) (xy 430.459663 -52.983704) (xy 430.489627 -52.990644)
			(xy 430.520301 -52.988377) (xy 430.54892 -52.977108) (xy 430.561242 -52.96789) (xy 430.581659 -52.951937)
			(xy 430.62602 -52.925161) (xy 430.673598 -52.904638) (xy 430.723516 -52.890745) (xy 430.774856 -52.883738)
			(xy 430.800764 -52.883308) (xy 430.828134 -52.883793) (xy 430.882312 -52.891606) (xy 430.934815 -52.907091)
			(xy 430.984562 -52.929928) (xy 431.03053 -52.959649) (xy 431.051462 -52.977288) (xy 431.06279 -52.986524)
			(xy 431.089347 -52.9987) (xy 431.118264 -53.002873) (xy 431.147181 -52.9987) (xy 431.173738 -52.986524)
			(xy 431.185066 -52.977288) (xy 431.205999 -52.95965) (xy 431.251971 -52.929938) (xy 431.301719 -52.907102)
			(xy 431.354219 -52.891611) (xy 431.408395 -52.883782) (xy 431.435764 -52.883308) (xy 431.465276 -52.883875)
			(xy 431.523597 -52.892961) (xy 431.579823 -52.910922) (xy 431.632611 -52.937328) (xy 431.680702 -52.97155)
			(xy 431.70221 -52.991766) (xy 431.713589 -53.002006) (xy 431.740854 -53.015882) (xy 431.771003 -53.021076)
			(xy 431.801339 -53.017123) (xy 431.82915 -53.004375) (xy 431.840894 -52.99456) (xy 431.861973 -52.976257)
			(xy 431.908518 -52.945435) (xy 431.959057 -52.921725) (xy 432.012513 -52.905634) (xy 432.067743 -52.897506)
			(xy 432.095656 -52.897024) (xy 432.124842 -52.897613) (xy 432.182533 -52.906505) (xy 432.238198 -52.924075)
			(xy 432.29054 -52.949912) (xy 432.338341 -52.983414) (xy 432.380485 -53.023801) (xy 432.398678 -53.04663)
			(xy 432.407273 -53.057141) (xy 432.428869 -53.073581) (xy 432.454033 -53.083755) (xy 432.480987 -53.086942)
			(xy 432.507829 -53.082919) (xy 432.532664 -53.071969) (xy 432.553739 -53.054866) (xy 432.562 -53.04409)
			(xy 432.577449 -53.023253) (xy 432.613004 -52.985486) (xy 432.653348 -52.952885) (xy 432.697737 -52.926051)
			(xy 432.745353 -52.905477) (xy 432.795316 -52.891545) (xy 432.846707 -52.884509) (xy 432.872642 -52.88407)
			(xy 432.900387 -52.884563) (xy 432.955291 -52.892607) (xy 433.008451 -52.90852) (xy 433.058744 -52.931966)
			(xy 433.105111 -52.96245) (xy 433.146573 -52.999329) (xy 433.182255 -53.041825) (xy 433.197254 -53.065172)
			(xy 433.205615 -53.077809) (xy 433.228365 -53.097807) (xy 433.255973 -53.110268) (xy 433.286019 -53.1141)
			(xy 433.315871 -53.108968) (xy 433.342913 -53.095322) (xy 433.354226 -53.085238) (xy 433.375661 -53.065403)
			(xy 433.423454 -53.031843) (xy 433.475799 -53.00595) (xy 433.531476 -52.988329) (xy 433.589187 -52.97939)
			(xy 433.618386 -52.978812) (xy 433.645641 -52.979234) (xy 433.699596 -52.98699) (xy 433.751899 -53.002345)
			(xy 433.801483 -53.024988) (xy 433.847341 -53.054457) (xy 433.888537 -53.090153) (xy 433.924234 -53.131348)
			(xy 433.953705 -53.177205) (xy 433.97635 -53.226788) (xy 433.991707 -53.27909) (xy 433.999465 -53.333045)
			(xy 433.999465 -53.387555) (xy 433.991707 -53.44151) (xy 433.97635 -53.493812) (xy 433.953705 -53.543395)
			(xy 433.924234 -53.589252) (xy 433.888537 -53.630447) (xy 433.847341 -53.666143) (xy 433.801483 -53.695612)
			(xy 433.751899 -53.718255) (xy 433.699596 -53.73361) (xy 433.645641 -53.741366) (xy 433.618386 -53.741828)
			(xy 433.590229 -53.741343) (xy 433.534526 -53.733076) (xy 433.480643 -53.716709) (xy 433.429753 -53.692597)
			(xy 433.38296 -53.661266) (xy 433.341282 -53.623395) (xy 433.305626 -53.579808) (xy 433.276765 -53.531453)
			(xy 433.26558 -53.505608) (xy 433.261051 -53.495825) (xy 433.245429 -53.480995) (xy 433.225106 -53.473859)
			(xy 433.203641 -53.475669) (xy 433.184799 -53.486106) (xy 433.17795 -53.494432) (xy 433.16017 -53.516276)
			(xy 433.150957 -53.52762) (xy 433.13878 -53.554172) (xy 433.134605 -53.583083) (xy 433.138771 -53.611996)
			(xy 433.150939 -53.638552) (xy 433.16017 -53.64988) (xy 433.177809 -53.670813) (xy 433.207521 -53.716785)
			(xy 433.230358 -53.766532) (xy 433.245849 -53.819033) (xy 433.253677 -53.873209) (xy 433.25415 -53.900578)
			(xy 433.253591 -53.930883) (xy 433.243998 -53.990728) (xy 433.225064 -54.048304) (xy 433.197268 -54.102163)
			(xy 433.161306 -54.150952) (xy 433.140104 -54.172612) (xy 433.130665 -54.182541) (xy 433.11702 -54.206286)
			(xy 433.110167 -54.232801) (xy 433.110597 -54.260184) (xy 433.11828 -54.28647) (xy 433.132664 -54.309775)
			(xy 433.14239 -54.319424) (xy 433.15353 -54.329979) (xy 433.174256 -54.352613) (xy 433.183792 -54.364636)
			(xy 433.193277 -54.375863) (xy 433.217199 -54.392905) (xy 433.244978 -54.402451) (xy 433.274324 -54.403712)
			(xy 433.302819 -54.396586) (xy 433.328116 -54.381659) (xy 433.338478 -54.37124) (xy 433.356615 -54.352319)
			(xy 433.397123 -54.319063) (xy 433.441807 -54.291672) (xy 433.489823 -54.270663) (xy 433.540265 -54.256433)
			(xy 433.592181 -54.249248) (xy 433.618386 -54.248812) (xy 433.645639 -54.249268) (xy 433.699592 -54.257024)
			(xy 433.751891 -54.272379) (xy 433.801472 -54.295022) (xy 433.847326 -54.32449) (xy 433.88852 -54.360185)
			(xy 433.924214 -54.401378) (xy 433.953681 -54.447233) (xy 433.976323 -54.496815) (xy 433.991677 -54.549114)
			(xy 433.999432 -54.603067) (xy 433.999894 -54.63032) (xy 433.999441 -54.657691) (xy 433.99162 -54.71187)
			(xy 433.976128 -54.764374) (xy 433.953284 -54.81412) (xy 433.923556 -54.860087) (xy 433.905914 -54.881018)
			(xy 433.896657 -54.89233) (xy 433.88448 -54.918893) (xy 433.880311 -54.947815) (xy 433.884489 -54.976736)
			(xy 433.896673 -55.003295) (xy 433.905914 -55.014622) (xy 433.923573 -55.03554) (xy 433.953293 -55.081511)
			(xy 433.976135 -55.13126) (xy 433.991628 -55.183764) (xy 433.999454 -55.237944) (xy 433.999452 -55.292686)
			(xy 433.991622 -55.346865) (xy 433.976125 -55.399368) (xy 433.953279 -55.449115) (xy 433.923554 -55.495084)
			(xy 433.905914 -55.516018) (xy 433.896657 -55.52733) (xy 433.88448 -55.553893) (xy 433.880311 -55.582815)
			(xy 433.884489 -55.611736) (xy 433.896673 -55.638295) (xy 433.905914 -55.649622) (xy 433.923573 -55.67054)
			(xy 433.953293 -55.716511) (xy 433.976135 -55.76626) (xy 433.991628 -55.818764) (xy 433.999454 -55.872944)
			(xy 433.999452 -55.927686) (xy 433.991622 -55.981865) (xy 433.976125 -56.034368) (xy 433.953279 -56.084115)
			(xy 433.923554 -56.130084) (xy 433.905914 -56.151018) (xy 433.896657 -56.16233) (xy 433.88448 -56.188893)
			(xy 433.880311 -56.217815) (xy 433.884489 -56.246736) (xy 433.896673 -56.273295) (xy 433.905914 -56.284622)
			(xy 433.923573 -56.30554) (xy 433.953293 -56.351511) (xy 433.976135 -56.40126) (xy 433.991628 -56.453764)
			(xy 433.999454 -56.507944) (xy 433.999452 -56.562686) (xy 433.991622 -56.616865) (xy 433.976125 -56.669368)
			(xy 433.953279 -56.719115) (xy 433.923554 -56.765084) (xy 433.905914 -56.786018) (xy 433.896657 -56.79733)
			(xy 433.88448 -56.823893) (xy 433.880311 -56.852815) (xy 433.884489 -56.881736) (xy 433.886597 -56.88633)
			(xy 440.94303 -56.88633) (xy 440.946755 -56.833083) (xy 440.957867 -56.780876) (xy 440.976147 -56.730727)
			(xy 441.00124 -56.683617) (xy 441.032655 -56.640464) (xy 441.069779 -56.602112) (xy 441.090558 -56.585358)
			(xy 441.102318 -56.57541) (xy 441.119841 -56.550102) (xy 441.129025 -56.520721) (xy 441.129034 -56.489938)
			(xy 441.119868 -56.460552) (xy 441.102359 -56.435234) (xy 441.090558 -56.425338) (xy 441.069823 -56.408528)
			(xy 441.032693 -56.370181) (xy 441.001272 -56.327033) (xy 440.976172 -56.279927) (xy 440.957883 -56.229781)
			(xy 440.946764 -56.177575) (xy 440.94303 -56.12433) (xy 440.946755 -56.071083) (xy 440.957867 -56.018876)
			(xy 440.976147 -55.968727) (xy 441.00124 -55.921617) (xy 441.032655 -55.878464) (xy 441.069779 -55.840112)
			(xy 441.090558 -55.823358) (xy 441.102318 -55.81341) (xy 441.119841 -55.788102) (xy 441.129025 -55.758721)
			(xy 441.129034 -55.727938) (xy 441.119868 -55.698552) (xy 441.102359 -55.673234) (xy 441.090558 -55.663338)
			(xy 441.069823 -55.646528) (xy 441.032693 -55.608181) (xy 441.001272 -55.565033) (xy 440.976172 -55.517927)
			(xy 440.957883 -55.467781) (xy 440.946764 -55.415575) (xy 440.94303 -55.36233) (xy 440.946755 -55.309083)
			(xy 440.957867 -55.256876) (xy 440.976147 -55.206727) (xy 441.00124 -55.159617) (xy 441.032655 -55.116464)
			(xy 441.069779 -55.078112) (xy 441.090558 -55.061358) (xy 441.102318 -55.05141) (xy 441.119841 -55.026102)
			(xy 441.129025 -54.996721) (xy 441.129034 -54.965938) (xy 441.119868 -54.936552) (xy 441.102359 -54.911234)
			(xy 441.090558 -54.901338) (xy 441.069823 -54.884528) (xy 441.032693 -54.846181) (xy 441.001272 -54.803033)
			(xy 440.976172 -54.755927) (xy 440.957883 -54.705781) (xy 440.946764 -54.653575) (xy 440.94303 -54.60033)
			(xy 440.946755 -54.547083) (xy 440.957867 -54.494876) (xy 440.976147 -54.444727) (xy 441.00124 -54.397617)
			(xy 441.032655 -54.354464) (xy 441.069779 -54.316112) (xy 441.090558 -54.299358) (xy 441.102318 -54.28941)
			(xy 441.119841 -54.264102) (xy 441.129025 -54.234721) (xy 441.129034 -54.203938) (xy 441.119868 -54.174552)
			(xy 441.102359 -54.149234) (xy 441.090558 -54.139338) (xy 441.069823 -54.122528) (xy 441.032693 -54.084181)
			(xy 441.001272 -54.041033) (xy 440.976172 -53.993927) (xy 440.957883 -53.943781) (xy 440.946764 -53.891575)
			(xy 440.94303 -53.83833) (xy 440.946755 -53.785083) (xy 440.957867 -53.732876) (xy 440.976147 -53.682727)
			(xy 441.00124 -53.635617) (xy 441.032655 -53.592464) (xy 441.069779 -53.554112) (xy 441.090558 -53.537358)
			(xy 441.102318 -53.52741) (xy 441.119841 -53.502102) (xy 441.129025 -53.472721) (xy 441.129034 -53.441938)
			(xy 441.119868 -53.412552) (xy 441.102359 -53.387234) (xy 441.090558 -53.377338) (xy 441.068084 -53.359136)
			(xy 441.02835 -53.317117) (xy 440.995411 -53.269584) (xy 440.970022 -53.217625) (xy 440.952763 -53.16243)
			(xy 440.94403 -53.105263) (xy 440.943492 -53.076348) (xy 440.944 -53.049096) (xy 440.95175 -52.995147)
			(xy 440.9671 -52.94285) (xy 440.989737 -52.89327) (xy 441.0192 -52.847417) (xy 441.054889 -52.806223)
			(xy 441.096078 -52.770529) (xy 441.141928 -52.74106) (xy 441.191505 -52.718417) (xy 441.2438 -52.703061)
			(xy 441.297748 -52.695303) (xy 441.325 -52.69484) (xy 441.353918 -52.695343) (xy 441.41109 -52.704073)
			(xy 441.46629 -52.721333) (xy 441.518252 -52.746728) (xy 441.565785 -52.779675) (xy 441.607801 -52.819419)
			(xy 441.62599 -52.841906) (xy 441.635887 -52.853711) (xy 441.661211 -52.87123) (xy 441.690604 -52.880406)
			(xy 441.721396 -52.880406) (xy 441.750789 -52.87123) (xy 441.776113 -52.853711) (xy 441.78601 -52.841906)
			(xy 441.804197 -52.819419) (xy 441.846217 -52.779684) (xy 441.893753 -52.746745) (xy 441.945715 -52.721357)
			(xy 442.000914 -52.704102) (xy 442.058084 -52.695374) (xy 442.087 -52.69484) (xy 442.114255 -52.695255)
			(xy 442.16821 -52.703014) (xy 442.220512 -52.718372) (xy 442.270095 -52.741018) (xy 442.315951 -52.770491)
			(xy 442.357145 -52.806189) (xy 442.392838 -52.847388) (xy 442.422305 -52.893247) (xy 442.444945 -52.942833)
			(xy 442.460297 -52.995137) (xy 442.468048 -53.049093) (xy 442.468508 -53.076348) (xy 442.467987 -53.105265)
			(xy 442.464373 -53.128948) (xy 442.747426 -53.128948) (xy 442.747426 -53.074452) (xy 442.755182 -53.020511)
			(xy 442.770535 -52.968223) (xy 442.793173 -52.918652) (xy 442.822636 -52.872808) (xy 442.858323 -52.831623)
			(xy 442.899508 -52.795936) (xy 442.945352 -52.766473) (xy 442.994923 -52.743835) (xy 443.047211 -52.728482)
			(xy 443.101152 -52.720726) (xy 443.1284 -52.72024) (xy 443.157318 -52.720743) (xy 443.21449 -52.729473)
			(xy 443.26969 -52.746733) (xy 443.321652 -52.772128) (xy 443.369185 -52.805075) (xy 443.411201 -52.844819)
			(xy 443.42939 -52.867306) (xy 443.439287 -52.879111) (xy 443.464611 -52.89663) (xy 443.494004 -52.905806)
			(xy 443.524796 -52.905806) (xy 443.554189 -52.89663) (xy 443.579513 -52.879111) (xy 443.58941 -52.867306)
			(xy 443.607597 -52.844819) (xy 443.649617 -52.805084) (xy 443.697153 -52.772145) (xy 443.749115 -52.746757)
			(xy 443.804314 -52.729502) (xy 443.861484 -52.720774) (xy 443.8904 -52.72024) (xy 443.917655 -52.72063)
			(xy 443.971609 -52.728387) (xy 444.023911 -52.743744) (xy 444.073494 -52.766388) (xy 444.11935 -52.795858)
			(xy 444.160546 -52.831554) (xy 444.196242 -52.87275) (xy 444.225712 -52.918606) (xy 444.248356 -52.968189)
			(xy 444.263713 -53.020491) (xy 444.27147 -53.074445) (xy 444.27147 -53.128955) (xy 444.263713 -53.182909)
			(xy 444.248356 -53.235211) (xy 444.225712 -53.284794) (xy 444.196242 -53.33065) (xy 444.160546 -53.371846)
			(xy 444.11935 -53.407542) (xy 444.073494 -53.437012) (xy 444.023911 -53.459656) (xy 443.971609 -53.475013)
			(xy 443.917655 -53.48277) (xy 443.8904 -53.483256) (xy 443.861482 -53.482754) (xy 443.80431 -53.474024)
			(xy 443.74911 -53.456764) (xy 443.697148 -53.431369) (xy 443.649614 -53.398422) (xy 443.607599 -53.358677)
			(xy 443.58941 -53.33619) (xy 443.579513 -53.324385) (xy 443.554189 -53.306866) (xy 443.524796 -53.29769)
			(xy 443.494004 -53.29769) (xy 443.464611 -53.306866) (xy 443.439287 -53.324385) (xy 443.42939 -53.33619)
			(xy 443.411202 -53.358676) (xy 443.369182 -53.398412) (xy 443.321647 -53.431351) (xy 443.269685 -53.456739)
			(xy 443.214486 -53.473994) (xy 443.157316 -53.482722) (xy 443.1284 -53.483256) (xy 443.101152 -53.482674)
			(xy 443.047211 -53.474918) (xy 442.994923 -53.459565) (xy 442.945352 -53.436927) (xy 442.899508 -53.407464)
			(xy 442.858323 -53.371777) (xy 442.822636 -53.330592) (xy 442.793173 -53.284748) (xy 442.770535 -53.235177)
			(xy 442.755182 -53.182889) (xy 442.747426 -53.128948) (xy 442.464373 -53.128948) (xy 442.459263 -53.162438)
			(xy 442.442008 -53.217638) (xy 442.416617 -53.269601) (xy 442.383672 -53.317134) (xy 442.343929 -53.359149)
			(xy 442.321442 -53.377338) (xy 442.309586 -53.387181) (xy 442.292064 -53.412518) (xy 442.282891 -53.441927)
			(xy 442.2829 -53.472732) (xy 442.29209 -53.502135) (xy 442.309627 -53.527462) (xy 442.321442 -53.537358)
			(xy 442.342272 -53.554055) (xy 442.379403 -53.592415) (xy 442.410824 -53.635576) (xy 442.435922 -53.682696)
			(xy 442.454206 -53.732855) (xy 442.46532 -53.785073) (xy 442.469046 -53.83833) (xy 442.465312 -53.891586)
			(xy 442.45419 -53.943802) (xy 442.435898 -53.993958) (xy 442.410793 -54.041074) (xy 442.379365 -54.08423)
			(xy 442.342228 -54.122585) (xy 442.321442 -54.139338) (xy 442.309586 -54.149181) (xy 442.292064 -54.174518)
			(xy 442.282891 -54.203927) (xy 442.2829 -54.234732) (xy 442.29209 -54.264135) (xy 442.309627 -54.289462)
			(xy 442.321442 -54.299358) (xy 442.342272 -54.316055) (xy 442.379403 -54.354415) (xy 442.392021 -54.371748)
			(xy 447.038982 -54.371748) (xy 447.043053 -54.316126) (xy 447.055179 -54.261689) (xy 447.075102 -54.209598)
			(xy 447.102398 -54.160963) (xy 447.136484 -54.11682) (xy 447.176633 -54.078111) (xy 447.221991 -54.04566)
			(xy 447.271591 -54.020159) (xy 447.324375 -54.002152) (xy 447.379218 -53.992022) (xy 447.434952 -53.989985)
			(xy 447.490389 -53.996085) (xy 447.544346 -54.010191) (xy 447.595675 -54.032003) (xy 447.643281 -54.061057)
			(xy 447.686149 -54.096732) (xy 447.723366 -54.138269) (xy 447.754139 -54.184782) (xy 447.777811 -54.235279)
			(xy 447.793879 -54.288686) (xy 447.801999 -54.343862) (xy 447.802508 -54.371748) (xy 447.927982 -54.371748)
			(xy 447.932053 -54.316126) (xy 447.944179 -54.261689) (xy 447.964102 -54.209598) (xy 447.991398 -54.160963)
			(xy 448.025484 -54.11682) (xy 448.065633 -54.078111) (xy 448.110991 -54.04566) (xy 448.160591 -54.020159)
			(xy 448.213375 -54.002152) (xy 448.268218 -53.992022) (xy 448.323952 -53.989985) (xy 448.379389 -53.996085)
			(xy 448.433346 -54.010191) (xy 448.484675 -54.032003) (xy 448.532281 -54.061057) (xy 448.575149 -54.096732)
			(xy 448.612366 -54.138269) (xy 448.643139 -54.184782) (xy 448.666811 -54.235279) (xy 448.682879 -54.288686)
			(xy 448.690999 -54.343862) (xy 448.691508 -54.371748) (xy 448.816982 -54.371748) (xy 448.821053 -54.316126)
			(xy 448.833179 -54.261689) (xy 448.853102 -54.209598) (xy 448.880398 -54.160963) (xy 448.914484 -54.11682)
			(xy 448.954633 -54.078111) (xy 448.999991 -54.04566) (xy 449.049591 -54.020159) (xy 449.102375 -54.002152)
			(xy 449.157218 -53.992022) (xy 449.212952 -53.989985) (xy 449.268389 -53.996085) (xy 449.322346 -54.010191)
			(xy 449.373675 -54.032003) (xy 449.421281 -54.061057) (xy 449.464149 -54.096732) (xy 449.501366 -54.138269)
			(xy 449.532139 -54.184782) (xy 449.555811 -54.235279) (xy 449.571879 -54.288686) (xy 449.579999 -54.343862)
			(xy 449.580508 -54.371748) (xy 449.705982 -54.371748) (xy 449.710053 -54.316126) (xy 449.722179 -54.261689)
			(xy 449.742102 -54.209598) (xy 449.769398 -54.160963) (xy 449.803484 -54.11682) (xy 449.843633 -54.078111)
			(xy 449.888991 -54.04566) (xy 449.938591 -54.020159) (xy 449.991375 -54.002152) (xy 450.046218 -53.992022)
			(xy 450.101952 -53.989985) (xy 450.157389 -53.996085) (xy 450.211346 -54.010191) (xy 450.262675 -54.032003)
			(xy 450.310281 -54.061057) (xy 450.353149 -54.096732) (xy 450.390366 -54.138269) (xy 450.421139 -54.184782)
			(xy 450.444811 -54.235279) (xy 450.460879 -54.288686) (xy 450.468999 -54.343862) (xy 450.469508 -54.371748)
			(xy 450.468999 -54.399634) (xy 450.460879 -54.45481) (xy 450.444811 -54.508217) (xy 450.421139 -54.558714)
			(xy 450.390366 -54.605227) (xy 450.353149 -54.646764) (xy 450.310281 -54.682439) (xy 450.262675 -54.711493)
			(xy 450.211346 -54.733305) (xy 450.157389 -54.747411) (xy 450.101952 -54.753511) (xy 450.046218 -54.751474)
			(xy 449.991375 -54.741344) (xy 449.938591 -54.723337) (xy 449.888991 -54.697836) (xy 449.843633 -54.665385)
			(xy 449.803484 -54.626676) (xy 449.769398 -54.582533) (xy 449.742102 -54.533898) (xy 449.722179 -54.481807)
			(xy 449.710053 -54.42737) (xy 449.705982 -54.371748) (xy 449.580508 -54.371748) (xy 449.579999 -54.399634)
			(xy 449.571879 -54.45481) (xy 449.555811 -54.508217) (xy 449.532139 -54.558714) (xy 449.501366 -54.605227)
			(xy 449.464149 -54.646764) (xy 449.421281 -54.682439) (xy 449.373675 -54.711493) (xy 449.322346 -54.733305)
			(xy 449.268389 -54.747411) (xy 449.212952 -54.753511) (xy 449.157218 -54.751474) (xy 449.102375 -54.741344)
			(xy 449.049591 -54.723337) (xy 448.999991 -54.697836) (xy 448.954633 -54.665385) (xy 448.914484 -54.626676)
			(xy 448.880398 -54.582533) (xy 448.853102 -54.533898) (xy 448.833179 -54.481807) (xy 448.821053 -54.42737)
			(xy 448.816982 -54.371748) (xy 448.691508 -54.371748) (xy 448.690999 -54.399634) (xy 448.682879 -54.45481)
			(xy 448.666811 -54.508217) (xy 448.643139 -54.558714) (xy 448.612366 -54.605227) (xy 448.575149 -54.646764)
			(xy 448.532281 -54.682439) (xy 448.484675 -54.711493) (xy 448.433346 -54.733305) (xy 448.379389 -54.747411)
			(xy 448.323952 -54.753511) (xy 448.268218 -54.751474) (xy 448.213375 -54.741344) (xy 448.160591 -54.723337)
			(xy 448.110991 -54.697836) (xy 448.065633 -54.665385) (xy 448.025484 -54.626676) (xy 447.991398 -54.582533)
			(xy 447.964102 -54.533898) (xy 447.944179 -54.481807) (xy 447.932053 -54.42737) (xy 447.927982 -54.371748)
			(xy 447.802508 -54.371748) (xy 447.801999 -54.399634) (xy 447.793879 -54.45481) (xy 447.777811 -54.508217)
			(xy 447.754139 -54.558714) (xy 447.723366 -54.605227) (xy 447.686149 -54.646764) (xy 447.643281 -54.682439)
			(xy 447.595675 -54.711493) (xy 447.544346 -54.733305) (xy 447.490389 -54.747411) (xy 447.434952 -54.753511)
			(xy 447.379218 -54.751474) (xy 447.324375 -54.741344) (xy 447.271591 -54.723337) (xy 447.221991 -54.697836)
			(xy 447.176633 -54.665385) (xy 447.136484 -54.626676) (xy 447.102398 -54.582533) (xy 447.075102 -54.533898)
			(xy 447.055179 -54.481807) (xy 447.043053 -54.42737) (xy 447.038982 -54.371748) (xy 442.392021 -54.371748)
			(xy 442.410824 -54.397576) (xy 442.435922 -54.444696) (xy 442.454206 -54.494855) (xy 442.46532 -54.547073)
			(xy 442.469046 -54.60033) (xy 442.465312 -54.653586) (xy 442.45419 -54.705802) (xy 442.435898 -54.755958)
			(xy 442.410793 -54.803074) (xy 442.379365 -54.84623) (xy 442.342228 -54.884585) (xy 442.321442 -54.901338)
			(xy 442.309586 -54.911181) (xy 442.292064 -54.936518) (xy 442.282891 -54.965927) (xy 442.2829 -54.996732)
			(xy 442.29209 -55.026135) (xy 442.309627 -55.051462) (xy 442.321442 -55.061358) (xy 442.342272 -55.078055)
			(xy 442.379403 -55.116415) (xy 442.410824 -55.159576) (xy 442.435922 -55.206696) (xy 442.454206 -55.256855)
			(xy 442.46532 -55.309073) (xy 442.469046 -55.36233) (xy 442.465312 -55.415586) (xy 442.45419 -55.467802)
			(xy 442.435898 -55.517958) (xy 442.410793 -55.565074) (xy 442.379365 -55.60823) (xy 442.342228 -55.646585)
			(xy 442.321442 -55.663338) (xy 442.309586 -55.673181) (xy 442.292064 -55.698518) (xy 442.282891 -55.727927)
			(xy 442.2829 -55.758732) (xy 442.29209 -55.788135) (xy 442.309627 -55.813462) (xy 442.321442 -55.823358)
			(xy 442.342272 -55.840055) (xy 442.379403 -55.878415) (xy 442.410824 -55.921576) (xy 442.435922 -55.968696)
			(xy 442.454206 -56.018855) (xy 442.46532 -56.071073) (xy 442.469046 -56.12433) (xy 442.465312 -56.177586)
			(xy 442.45419 -56.229802) (xy 442.435898 -56.279958) (xy 442.410793 -56.327074) (xy 442.379365 -56.37023)
			(xy 442.342228 -56.408585) (xy 442.321442 -56.425338) (xy 442.309586 -56.435181) (xy 442.292064 -56.460518)
			(xy 442.282891 -56.489927) (xy 442.2829 -56.520732) (xy 442.29209 -56.550135) (xy 442.309627 -56.575462)
			(xy 442.321442 -56.585358) (xy 442.342272 -56.602055) (xy 442.379403 -56.640415) (xy 442.410824 -56.683576)
			(xy 442.435922 -56.730696) (xy 442.454206 -56.780855) (xy 442.46532 -56.833073) (xy 442.469046 -56.88633)
			(xy 442.465312 -56.939586) (xy 442.45419 -56.991802) (xy 442.435898 -57.041958) (xy 442.410793 -57.089074)
			(xy 442.379365 -57.13223) (xy 442.342228 -57.170585) (xy 442.321442 -57.187338) (xy 442.309586 -57.197181)
			(xy 442.292064 -57.222518) (xy 442.282891 -57.251927) (xy 442.2829 -57.282732) (xy 442.29209 -57.312135)
			(xy 442.309627 -57.337462) (xy 442.321442 -57.347358) (xy 442.343914 -57.365562) (xy 442.383648 -57.40758)
			(xy 442.416587 -57.455113) (xy 442.441977 -57.507071) (xy 442.459237 -57.562266) (xy 442.463308 -57.588912)
			(xy 444.646304 -57.588912) (xy 444.646776 -57.561542) (xy 444.654592 -57.507363) (xy 444.67008 -57.45486)
			(xy 444.69292 -57.405113) (xy 444.722643 -57.359146) (xy 444.740284 -57.338214) (xy 444.749511 -57.326879)
			(xy 444.761691 -57.300324) (xy 444.765867 -57.271409) (xy 444.761696 -57.242493) (xy 444.74952 -57.215937)
			(xy 444.740284 -57.20461) (xy 444.722657 -57.183667) (xy 444.692935 -57.1377) (xy 444.670091 -57.087955)
			(xy 444.654596 -57.035455) (xy 444.646767 -56.981279) (xy 444.646766 -56.926539) (xy 444.654592 -56.872363)
			(xy 444.670085 -56.819862) (xy 444.692926 -56.770116) (xy 444.722646 -56.724148) (xy 444.740284 -56.703214)
			(xy 444.749511 -56.691879) (xy 444.761691 -56.665324) (xy 444.765867 -56.636409) (xy 444.761696 -56.607493)
			(xy 444.74952 -56.580937) (xy 444.740284 -56.56961) (xy 444.722657 -56.548667) (xy 444.692935 -56.5027)
			(xy 444.670091 -56.452955) (xy 444.654596 -56.400455) (xy 444.646767 -56.346279) (xy 444.646766 -56.291539)
			(xy 444.654592 -56.237363) (xy 444.670085 -56.184862) (xy 444.692926 -56.135116) (xy 444.722646 -56.089148)
			(xy 444.740284 -56.068214) (xy 444.749511 -56.056879) (xy 444.761691 -56.030324) (xy 444.765867 -56.001409)
			(xy 444.761696 -55.972493) (xy 444.74952 -55.945937) (xy 444.740284 -55.93461) (xy 444.722657 -55.913667)
			(xy 444.692935 -55.8677) (xy 444.670091 -55.817955) (xy 444.654596 -55.765455) (xy 444.646767 -55.711279)
			(xy 444.646766 -55.656539) (xy 444.654592 -55.602363) (xy 444.670085 -55.549862) (xy 444.692926 -55.500116)
			(xy 444.722646 -55.454148) (xy 444.740284 -55.433214) (xy 444.749511 -55.421879) (xy 444.761691 -55.395324)
			(xy 444.765867 -55.366409) (xy 444.761696 -55.337493) (xy 444.74952 -55.310937) (xy 444.740284 -55.29961)
			(xy 444.722634 -55.278687) (xy 444.692924 -55.232711) (xy 444.670091 -55.182962) (xy 444.654602 -55.130459)
			(xy 444.646777 -55.076282) (xy 444.646304 -55.048912) (xy 444.646767 -55.021659) (xy 444.654522 -54.967707)
			(xy 444.669877 -54.915409) (xy 444.692519 -54.865828) (xy 444.721987 -54.819974) (xy 444.757681 -54.778781)
			(xy 444.798874 -54.743087) (xy 444.844728 -54.713619) (xy 444.894309 -54.690977) (xy 444.946607 -54.675622)
			(xy 445.000559 -54.667867) (xy 445.027812 -54.667404) (xy 445.054483 -54.66783) (xy 445.107306 -54.67525)
			(xy 445.158579 -54.689958) (xy 445.207304 -54.711667) (xy 445.252528 -54.739952) (xy 445.29337 -54.774263)
			(xy 445.329032 -54.81393) (xy 445.344296 -54.835806) (xy 445.35343 -54.848302) (xy 445.377599 -54.867612)
			(xy 445.406436 -54.87881) (xy 445.437302 -54.88087) (xy 445.467372 -54.873605) (xy 445.493892 -54.857678)
			(xy 445.50457 -54.846474) (xy 445.522735 -54.826673) (xy 445.563685 -54.791879) (xy 445.609115 -54.76318)
			(xy 445.658124 -54.741143) (xy 445.709741 -54.726205) (xy 445.762944 -54.718663) (xy 445.789812 -54.718204)
			(xy 445.817064 -54.718667) (xy 445.871013 -54.726425) (xy 445.923309 -54.741782) (xy 445.972887 -54.764426)
			(xy 446.018738 -54.793894) (xy 446.059929 -54.829588) (xy 446.09562 -54.870781) (xy 446.125086 -54.916634)
			(xy 446.147726 -54.966213) (xy 446.16308 -55.01851) (xy 446.170835 -55.07246) (xy 446.17132 -55.099712)
			(xy 446.17088 -55.127083) (xy 446.163059 -55.181264) (xy 446.147565 -55.233769) (xy 446.124717 -55.283515)
			(xy 446.094985 -55.32948) (xy 446.07734 -55.35041) (xy 446.068088 -55.361727) (xy 446.055908 -55.388288)
			(xy 446.051735 -55.417209) (xy 446.055913 -55.44613) (xy 446.068098 -55.472688) (xy 446.07734 -55.484014)
			(xy 446.094994 -55.504937) (xy 446.124721 -55.550905) (xy 446.147567 -55.600653) (xy 446.163064 -55.653157)
			(xy 446.170892 -55.707337) (xy 446.170891 -55.762081) (xy 446.16306 -55.816261) (xy 446.147561 -55.868764)
			(xy 446.124712 -55.918511) (xy 446.094983 -55.964478) (xy 446.07734 -55.98541) (xy 446.068088 -55.996727)
			(xy 446.055908 -56.023288) (xy 446.051735 -56.052209) (xy 446.055913 -56.08113) (xy 446.068098 -56.107688)
			(xy 446.07734 -56.119014) (xy 446.094994 -56.139937) (xy 446.124721 -56.185905) (xy 446.147567 -56.235653)
			(xy 446.163064 -56.288157) (xy 446.170892 -56.342337) (xy 446.170891 -56.369712) (xy 451.428104 -56.369712)
			(xy 451.428576 -56.342342) (xy 451.436392 -56.288163) (xy 451.45188 -56.23566) (xy 451.47472 -56.185913)
			(xy 451.504443 -56.139946) (xy 451.522084 -56.119014) (xy 451.531311 -56.107679) (xy 451.543491 -56.081124)
			(xy 451.547667 -56.052209) (xy 451.543496 -56.023293) (xy 451.53132 -55.996737) (xy 451.522084 -55.98541)
			(xy 451.504457 -55.964467) (xy 451.474735 -55.9185) (xy 451.451891 -55.868755) (xy 451.436396 -55.816255)
			(xy 451.428567 -55.762079) (xy 451.428566 -55.707339) (xy 451.436392 -55.653163) (xy 451.451885 -55.600662)
			(xy 451.474726 -55.550916) (xy 451.504446 -55.504948) (xy 451.522084 -55.484014) (xy 451.531311 -55.472679)
			(xy 451.543491 -55.446124) (xy 451.547667 -55.417209) (xy 451.543496 -55.388293) (xy 451.53132 -55.361737)
			(xy 451.522084 -55.35041) (xy 451.504434 -55.329487) (xy 451.474724 -55.283511) (xy 451.451891 -55.233762)
			(xy 451.436402 -55.181259) (xy 451.428577 -55.127082) (xy 451.428104 -55.099712) (xy 451.42859 -55.072461)
			(xy 451.436346 -55.018513) (xy 451.451701 -54.966218) (xy 451.474343 -54.916641) (xy 451.503809 -54.870791)
			(xy 451.5395 -54.8296) (xy 451.580691 -54.793909) (xy 451.626541 -54.764443) (xy 451.676118 -54.741801)
			(xy 451.728413 -54.726446) (xy 451.782361 -54.71869) (xy 451.836863 -54.71869) (xy 451.890811 -54.726446)
			(xy 451.943106 -54.741801) (xy 451.992683 -54.764443) (xy 452.038533 -54.793909) (xy 452.079724 -54.8296)
			(xy 452.115415 -54.870791) (xy 452.144881 -54.916641) (xy 452.167523 -54.966218) (xy 452.182878 -55.018513)
			(xy 452.190634 -55.072461) (xy 452.19112 -55.099712) (xy 452.19068 -55.127083) (xy 452.182859 -55.181264)
			(xy 452.167365 -55.233769) (xy 452.144517 -55.283515) (xy 452.114785 -55.32948) (xy 452.09714 -55.35041)
			(xy 452.087888 -55.361727) (xy 452.075708 -55.388288) (xy 452.071535 -55.417209) (xy 452.075713 -55.44613)
			(xy 452.087898 -55.472688) (xy 452.09714 -55.484014) (xy 452.114794 -55.504937) (xy 452.144521 -55.550905)
			(xy 452.167367 -55.600653) (xy 452.182864 -55.653157) (xy 452.190692 -55.707337) (xy 452.190691 -55.762081)
			(xy 452.18286 -55.816261) (xy 452.167361 -55.868764) (xy 452.144512 -55.918511) (xy 452.114783 -55.964478)
			(xy 452.09714 -55.98541) (xy 452.087888 -55.996727) (xy 452.075708 -56.023288) (xy 452.071535 -56.052209)
			(xy 452.075713 -56.08113) (xy 452.087898 -56.107688) (xy 452.09714 -56.119014) (xy 452.114759 -56.139962)
			(xy 452.144472 -56.185931) (xy 452.167312 -56.235675) (xy 452.182808 -56.288172) (xy 452.190643 -56.342344)
			(xy 452.19112 -56.369712) (xy 452.190634 -56.396963) (xy 452.182878 -56.450911) (xy 452.167523 -56.503206)
			(xy 452.144881 -56.552783) (xy 452.115415 -56.598633) (xy 452.079724 -56.639824) (xy 452.038533 -56.675515)
			(xy 451.992683 -56.704981) (xy 451.943106 -56.727623) (xy 451.890811 -56.742978) (xy 451.836863 -56.750734)
			(xy 451.782361 -56.750734) (xy 451.728413 -56.742978) (xy 451.676118 -56.727623) (xy 451.626541 -56.704981)
			(xy 451.580691 -56.675515) (xy 451.5395 -56.639824) (xy 451.503809 -56.598633) (xy 451.474343 -56.552783)
			(xy 451.451701 -56.503206) (xy 451.436346 -56.450911) (xy 451.42859 -56.396963) (xy 451.428104 -56.369712)
			(xy 446.170891 -56.369712) (xy 446.170891 -56.397081) (xy 446.16306 -56.451261) (xy 446.147561 -56.503764)
			(xy 446.124712 -56.553511) (xy 446.094983 -56.599478) (xy 446.07734 -56.62041) (xy 446.068088 -56.631727)
			(xy 446.055908 -56.658288) (xy 446.051735 -56.687209) (xy 446.055913 -56.71613) (xy 446.068098 -56.742688)
			(xy 446.07734 -56.754014) (xy 446.094959 -56.774962) (xy 446.124672 -56.820931) (xy 446.147512 -56.870675)
			(xy 446.163008 -56.923172) (xy 446.170843 -56.977344) (xy 446.17132 -57.004712) (xy 446.170833 -57.031963)
			(xy 446.163076 -57.08591) (xy 446.14772 -57.138204) (xy 446.125078 -57.187781) (xy 446.095611 -57.23363)
			(xy 446.05992 -57.27482) (xy 446.01873 -57.310511) (xy 445.972881 -57.339978) (xy 445.923304 -57.36262)
			(xy 445.87101 -57.377976) (xy 445.817063 -57.385733) (xy 445.789812 -57.38622) (xy 445.762381 -57.385755)
			(xy 445.708084 -57.377911) (xy 445.65547 -57.362369) (xy 445.605626 -57.339449) (xy 445.55958 -57.309624)
			(xy 445.518282 -57.27351) (xy 445.482584 -57.231852) (xy 445.453222 -57.185509) (xy 445.441578 -57.160668)
			(xy 445.436517 -57.15084) (xy 445.419862 -57.13635) (xy 445.398659 -57.130199) (xy 445.376835 -57.133527)
			(xy 445.358428 -57.145717) (xy 445.35217 -57.154826) (xy 445.343856 -57.167909) (xy 445.325419 -57.192833)
			(xy 445.31534 -57.20461) (xy 445.306088 -57.215927) (xy 445.293908 -57.242488) (xy 445.289735 -57.271409)
			(xy 445.293913 -57.30033) (xy 445.306098 -57.326888) (xy 445.31534 -57.338214) (xy 445.332959 -57.359162)
			(xy 445.362672 -57.405131) (xy 445.385512 -57.454875) (xy 445.401008 -57.507372) (xy 445.408843 -57.561544)
			(xy 445.40932 -57.588912) (xy 445.408834 -57.616163) (xy 445.405448 -57.639712) (xy 452.723504 -57.639712)
			(xy 452.723976 -57.612342) (xy 452.731792 -57.558163) (xy 452.74728 -57.50566) (xy 452.77012 -57.455913)
			(xy 452.799843 -57.409946) (xy 452.817484 -57.389014) (xy 452.826711 -57.377679) (xy 452.838891 -57.351124)
			(xy 452.843067 -57.322209) (xy 452.838896 -57.293293) (xy 452.82672 -57.266737) (xy 452.817484 -57.25541)
			(xy 452.799857 -57.234467) (xy 452.770135 -57.1885) (xy 452.747291 -57.138755) (xy 452.731796 -57.086255)
			(xy 452.723967 -57.032079) (xy 452.723966 -56.977339) (xy 452.731792 -56.923163) (xy 452.747285 -56.870662)
			(xy 452.770126 -56.820916) (xy 452.799846 -56.774948) (xy 452.817484 -56.754014) (xy 452.826711 -56.742679)
			(xy 452.838891 -56.716124) (xy 452.843067 -56.687209) (xy 452.838896 -56.658293) (xy 452.82672 -56.631737)
			(xy 452.817484 -56.62041) (xy 452.799857 -56.599467) (xy 452.770135 -56.5535) (xy 452.747291 -56.503755)
			(xy 452.731796 -56.451255) (xy 452.723967 -56.397079) (xy 452.723966 -56.342339) (xy 452.731792 -56.288163)
			(xy 452.747285 -56.235662) (xy 452.770126 -56.185916) (xy 452.799846 -56.139948) (xy 452.817484 -56.119014)
			(xy 452.826711 -56.107679) (xy 452.838891 -56.081124) (xy 452.843067 -56.052209) (xy 452.838896 -56.023293)
			(xy 452.82672 -55.996737) (xy 452.817484 -55.98541) (xy 452.799857 -55.964467) (xy 452.770135 -55.9185)
			(xy 452.747291 -55.868755) (xy 452.731796 -55.816255) (xy 452.723967 -55.762079) (xy 452.723966 -55.707339)
			(xy 452.731792 -55.653163) (xy 452.747285 -55.600662) (xy 452.770126 -55.550916) (xy 452.799846 -55.504948)
			(xy 452.817484 -55.484014) (xy 452.826711 -55.472679) (xy 452.838891 -55.446124) (xy 452.843067 -55.417209)
			(xy 452.838896 -55.388293) (xy 452.82672 -55.361737) (xy 452.817484 -55.35041) (xy 452.799834 -55.329487)
			(xy 452.770124 -55.283511) (xy 452.747291 -55.233762) (xy 452.731802 -55.181259) (xy 452.723977 -55.127082)
			(xy 452.723504 -55.099712) (xy 452.72399 -55.072461) (xy 452.731746 -55.018513) (xy 452.747101 -54.966218)
			(xy 452.769743 -54.916641) (xy 452.799209 -54.870791) (xy 452.8349 -54.8296) (xy 452.876091 -54.793909)
			(xy 452.921941 -54.764443) (xy 452.971518 -54.741801) (xy 453.023813 -54.726446) (xy 453.077761 -54.71869)
			(xy 453.132263 -54.71869) (xy 453.186211 -54.726446) (xy 453.238506 -54.741801) (xy 453.288083 -54.764443)
			(xy 453.333933 -54.793909) (xy 453.375124 -54.8296) (xy 453.410815 -54.870791) (xy 453.440281 -54.916641)
			(xy 453.462923 -54.966218) (xy 453.478278 -55.018513) (xy 453.486034 -55.072461) (xy 453.48652 -55.099712)
			(xy 453.48608 -55.127083) (xy 453.478259 -55.181264) (xy 453.462765 -55.233769) (xy 453.439917 -55.283515)
			(xy 453.410185 -55.32948) (xy 453.39254 -55.35041) (xy 453.383288 -55.361727) (xy 453.371108 -55.388288)
			(xy 453.366935 -55.417209) (xy 453.371113 -55.44613) (xy 453.383298 -55.472688) (xy 453.39254 -55.484014)
			(xy 453.410194 -55.504937) (xy 453.439921 -55.550905) (xy 453.462767 -55.600653) (xy 453.478264 -55.653157)
			(xy 453.486092 -55.707337) (xy 453.486091 -55.762081) (xy 453.47826 -55.816261) (xy 453.462761 -55.868764)
			(xy 453.439912 -55.918511) (xy 453.410183 -55.964478) (xy 453.39254 -55.98541) (xy 453.383288 -55.996727)
			(xy 453.371108 -56.023288) (xy 453.366935 -56.052209) (xy 453.371113 -56.08113) (xy 453.383298 -56.107688)
			(xy 453.39254 -56.119014) (xy 453.410194 -56.139937) (xy 453.439921 -56.185905) (xy 453.462767 -56.235653)
			(xy 453.478264 -56.288157) (xy 453.486092 -56.342337) (xy 453.486091 -56.397081) (xy 453.47826 -56.451261)
			(xy 453.462761 -56.503764) (xy 453.439912 -56.553511) (xy 453.410183 -56.599478) (xy 453.39254 -56.62041)
			(xy 453.383288 -56.631727) (xy 453.371108 -56.658288) (xy 453.366935 -56.687209) (xy 453.371113 -56.71613)
			(xy 453.383298 -56.742688) (xy 453.39254 -56.754014) (xy 453.410194 -56.774937) (xy 453.439921 -56.820905)
			(xy 453.462767 -56.870653) (xy 453.478264 -56.923157) (xy 453.486092 -56.977337) (xy 453.486091 -57.032081)
			(xy 453.47826 -57.086261) (xy 453.462761 -57.138764) (xy 453.439912 -57.188511) (xy 453.410183 -57.234478)
			(xy 453.39254 -57.25541) (xy 453.383288 -57.266727) (xy 453.371108 -57.293288) (xy 453.366935 -57.322209)
			(xy 453.371113 -57.35113) (xy 453.383298 -57.377688) (xy 453.39254 -57.389014) (xy 453.410159 -57.409962)
			(xy 453.439872 -57.455931) (xy 453.462712 -57.505675) (xy 453.478208 -57.558172) (xy 453.486043 -57.612344)
			(xy 453.48652 -57.639712) (xy 453.486034 -57.666963) (xy 453.478278 -57.720911) (xy 453.462923 -57.773206)
			(xy 453.440281 -57.822783) (xy 453.410815 -57.868633) (xy 453.375124 -57.909824) (xy 453.333933 -57.945515)
			(xy 453.288083 -57.974981) (xy 453.238506 -57.997623) (xy 453.186211 -58.012978) (xy 453.132263 -58.020734)
			(xy 453.077761 -58.020734) (xy 453.023813 -58.012978) (xy 452.971518 -57.997623) (xy 452.921941 -57.974981)
			(xy 452.876091 -57.945515) (xy 452.8349 -57.909824) (xy 452.799209 -57.868633) (xy 452.769743 -57.822783)
			(xy 452.747101 -57.773206) (xy 452.731746 -57.720911) (xy 452.72399 -57.666963) (xy 452.723504 -57.639712)
			(xy 445.405448 -57.639712) (xy 445.401078 -57.670111) (xy 445.385723 -57.722406) (xy 445.363081 -57.771983)
			(xy 445.333615 -57.817833) (xy 445.297924 -57.859024) (xy 445.256733 -57.894715) (xy 445.210883 -57.924181)
			(xy 445.161306 -57.946823) (xy 445.109011 -57.962178) (xy 445.055063 -57.969934) (xy 445.000561 -57.969934)
			(xy 444.946613 -57.962178) (xy 444.894318 -57.946823) (xy 444.844741 -57.924181) (xy 444.798891 -57.894715)
			(xy 444.7577 -57.859024) (xy 444.722009 -57.817833) (xy 444.692543 -57.771983) (xy 444.669901 -57.722406)
			(xy 444.654546 -57.670111) (xy 444.64679 -57.616163) (xy 444.646304 -57.588912) (xy 442.463308 -57.588912)
			(xy 442.46797 -57.619433) (xy 442.468508 -57.648348) (xy 442.468067 -57.6756) (xy 442.460304 -57.72955)
			(xy 442.444943 -57.781845) (xy 442.422296 -57.831423) (xy 442.392825 -57.877273) (xy 442.357129 -57.918463)
			(xy 442.315934 -57.954153) (xy 442.270081 -57.983619) (xy 442.2205 -58.006259) (xy 442.168203 -58.021614)
			(xy 442.114252 -58.02937) (xy 442.087 -58.029856) (xy 442.058082 -58.029354) (xy 442.00091 -58.020624)
			(xy 441.94571 -58.003364) (xy 441.893748 -57.977969) (xy 441.846214 -57.945022) (xy 441.804199 -57.905277)
			(xy 441.78601 -57.88279) (xy 441.776113 -57.870985) (xy 441.750789 -57.853466) (xy 441.721396 -57.84429)
			(xy 441.690604 -57.84429) (xy 441.661211 -57.853466) (xy 441.635887 -57.870985) (xy 441.62599 -57.88279)
			(xy 441.607802 -57.905276) (xy 441.565782 -57.945012) (xy 441.518247 -57.977951) (xy 441.466285 -58.003339)
			(xy 441.411086 -58.020594) (xy 441.353916 -58.029322) (xy 441.325 -58.029856) (xy 441.297751 -58.029322)
			(xy 441.243807 -58.021567) (xy 441.191516 -58.006214) (xy 441.141942 -57.983577) (xy 441.096094 -57.954115)
			(xy 441.054905 -57.918429) (xy 441.019214 -57.877244) (xy 440.989746 -57.8314) (xy 440.967102 -57.781829)
			(xy 440.951743 -57.72954) (xy 440.943981 -57.675597) (xy 440.943492 -57.648348) (xy 440.94401 -57.619431)
			(xy 440.952734 -57.562258) (xy 440.96999 -57.507058) (xy 440.995382 -57.455095) (xy 441.028327 -57.407562)
			(xy 441.068071 -57.365547) (xy 441.090558 -57.347358) (xy 441.102318 -57.33741) (xy 441.119841 -57.312102)
			(xy 441.129025 -57.282721) (xy 441.129034 -57.251938) (xy 441.119868 -57.222552) (xy 441.102359 -57.197234)
			(xy 441.090558 -57.187338) (xy 441.069823 -57.170528) (xy 441.032693 -57.132181) (xy 441.001272 -57.089033)
			(xy 440.976172 -57.041927) (xy 440.957883 -56.991781) (xy 440.946764 -56.939575) (xy 440.94303 -56.88633)
			(xy 433.886597 -56.88633) (xy 433.896673 -56.908295) (xy 433.905914 -56.919622) (xy 433.923532 -56.940571)
			(xy 433.953247 -56.986539) (xy 433.976086 -57.036283) (xy 433.991582 -57.088779) (xy 433.999417 -57.142952)
			(xy 433.999894 -57.17032) (xy 433.999408 -57.197571) (xy 433.991652 -57.251519) (xy 433.976297 -57.303814)
			(xy 433.953655 -57.353391) (xy 433.924189 -57.399241) (xy 433.888498 -57.440432) (xy 433.847307 -57.476123)
			(xy 433.801457 -57.505589) (xy 433.75188 -57.528231) (xy 433.699585 -57.543586) (xy 433.645637 -57.551342)
			(xy 433.591135 -57.551342) (xy 433.537187 -57.543586) (xy 433.484892 -57.528231) (xy 433.435315 -57.505589)
			(xy 433.389465 -57.476123) (xy 433.348274 -57.440432) (xy 433.312583 -57.399241) (xy 433.283117 -57.353391)
			(xy 433.260475 -57.303814) (xy 433.24512 -57.251519) (xy 433.237364 -57.197571) (xy 433.236878 -57.17032)
			(xy 433.237337 -57.142949) (xy 433.245153 -57.088769) (xy 433.260643 -57.036265) (xy 433.283487 -56.986518)
			(xy 433.313215 -56.940553) (xy 433.330858 -56.919622) (xy 433.340071 -56.908278) (xy 433.352244 -56.881726)
			(xy 433.356417 -56.852815) (xy 433.352252 -56.823904) (xy 433.340087 -56.797347) (xy 433.330858 -56.786018)
			(xy 433.330604 -56.785764) (xy 433.320196 -56.774568) (xy 433.294269 -56.758405) (xy 433.264722 -56.750633)
			(xy 433.234198 -56.751946) (xy 433.205427 -56.762227) (xy 433.180983 -56.780556) (xy 433.1716 -56.792622)
			(xy 433.156153 -56.813153) (xy 433.120646 -56.850289) (xy 433.080475 -56.882323) (xy 433.036368 -56.908674)
			(xy 432.989122 -56.928866) (xy 432.939594 -56.942534) (xy 432.88868 -56.949429) (xy 432.86299 -56.949848)
			(xy 432.83574 -56.949332) (xy 432.781796 -56.941575) (xy 432.729504 -56.92622) (xy 432.679929 -56.903581)
			(xy 432.634081 -56.874117) (xy 432.592892 -56.838429) (xy 432.557201 -56.797243) (xy 432.527733 -56.751397)
			(xy 432.50509 -56.701824) (xy 432.489732 -56.649534) (xy 432.481971 -56.59559) (xy 432.481482 -56.56834)
			(xy 432.481903 -56.541695) (xy 432.489309 -56.488921) (xy 432.503997 -56.437695) (xy 432.525678 -56.389015)
			(xy 432.553931 -56.34383) (xy 432.588205 -56.303023) (xy 432.60772 -56.284876) (xy 432.617643 -56.275375)
			(xy 432.632425 -56.252231) (xy 432.64051 -56.225985) (xy 432.641313 -56.198534) (xy 432.634776 -56.171861)
			(xy 432.621371 -56.147892) (xy 432.612038 -56.13781) (xy 432.604111 -56.129693) (xy 432.589114 -56.112665)
			(xy 432.582066 -56.103774) (xy 432.572169 -56.091969) (xy 432.546845 -56.07445) (xy 432.517452 -56.065274)
			(xy 432.48666 -56.065274) (xy 432.457267 -56.07445) (xy 432.431943 -56.091969) (xy 432.422046 -56.103774)
			(xy 432.403822 -56.12623) (xy 432.36181 -56.165968) (xy 432.314282 -56.198911) (xy 432.262327 -56.224304)
			(xy 432.207135 -56.241566) (xy 432.14997 -56.250302) (xy 432.121056 -56.25084) (xy 432.092423 -56.250308)
			(xy 432.035799 -56.241768) (xy 431.981088 -56.224857) (xy 431.929522 -56.199954) (xy 431.882259 -56.167621)
			(xy 431.86096 -56.148478) (xy 431.849747 -56.13867) (xy 431.823058 -56.125462) (xy 431.793693 -56.120517)
			(xy 431.76415 -56.124254) (xy 431.736942 -56.136357) (xy 431.725324 -56.145684) (xy 431.704466 -56.1631)
			(xy 431.658712 -56.192416) (xy 431.609259 -56.214937) (xy 431.55711 -56.230207) (xy 431.50332 -56.237916)
			(xy 431.47615 -56.238394) (xy 431.448781 -56.2379) (xy 431.394603 -56.230089) (xy 431.3421 -56.214607)
			(xy 431.292353 -56.191771) (xy 431.246385 -56.162052) (xy 431.225452 -56.144414) (xy 431.214124 -56.135178)
			(xy 431.187567 -56.123002) (xy 431.15865 -56.118829) (xy 431.129733 -56.123002) (xy 431.103176 -56.135178)
			(xy 431.091848 -56.144414) (xy 431.070915 -56.162055) (xy 431.024947 -56.191779) (xy 430.975201 -56.214625)
			(xy 430.922699 -56.230121) (xy 430.868521 -56.23795) (xy 430.813779 -56.23795) (xy 430.759601 -56.230121)
			(xy 430.707099 -56.214625) (xy 430.657353 -56.191779) (xy 430.611385 -56.162055) (xy 430.590452 -56.144414)
			(xy 430.579124 -56.135178) (xy 430.552567 -56.123002) (xy 430.52365 -56.118829) (xy 430.494733 -56.123002)
			(xy 430.468176 -56.135178) (xy 430.456848 -56.144414) (xy 430.43591 -56.162046) (xy 430.389939 -56.191759)
			(xy 430.340193 -56.214596) (xy 430.287693 -56.230088) (xy 430.233519 -56.237919) (xy 430.20615 -56.238394)
			(xy 430.178898 -56.237898) (xy 430.124947 -56.230148) (xy 430.072649 -56.214797) (xy 430.023068 -56.19216)
			(xy 429.977214 -56.162695) (xy 429.936021 -56.127005) (xy 429.900326 -56.085815) (xy 429.870858 -56.039963)
			(xy 429.848215 -55.990385) (xy 429.83286 -55.938088) (xy 429.825104 -55.884138) (xy 429.824642 -55.856886)
			(xy 429.82509 -55.829515) (xy 429.83291 -55.775335) (xy 429.848403 -55.722831) (xy 429.871249 -55.673084)
			(xy 429.900978 -55.627119) (xy 429.918622 -55.606188) (xy 429.927871 -55.59487) (xy 429.940044 -55.568309)
			(xy 429.944213 -55.539389) (xy 429.940038 -55.510471) (xy 429.927859 -55.483912) (xy 429.918622 -55.472584)
			(xy 429.901012 -55.451628) (xy 429.871295 -55.405662) (xy 429.848453 -55.355921) (xy 429.832955 -55.303425)
			(xy 429.82512 -55.249254) (xy 429.824642 -55.221886) (xy 429.825083 -55.195161) (xy 429.832537 -55.142234)
			(xy 429.847296 -55.090863) (xy 429.869073 -55.042052) (xy 429.897442 -54.996753) (xy 429.914304 -54.976014)
			(xy 429.922662 -54.9654) (xy 429.934098 -54.940939) (xy 429.938707 -54.914332) (xy 429.936164 -54.88745)
			(xy 429.926649 -54.862179) (xy 429.910829 -54.840296) (xy 429.900588 -54.831488) (xy 429.878857 -54.813288)
			(xy 429.840524 -54.771532) (xy 429.808792 -54.724563) (xy 429.78436 -54.673416) (xy 429.767766 -54.619216)
			(xy 429.759375 -54.563158) (xy 429.758856 -54.534816) (xy 429.38446 -54.534816) (xy 429.38446 -59.210448)
			(xy 429.592994 -59.418982) (xy 462.938622 -59.418982) (xy 462.939072 -59.391611) (xy 462.946893 -59.337431)
			(xy 462.962386 -59.284928) (xy 462.985231 -59.235181) (xy 463.014959 -59.189215) (xy 463.032602 -59.168284)
			(xy 463.041856 -59.15697) (xy 463.054031 -59.130407) (xy 463.0582 -59.101486) (xy 463.054023 -59.072567)
			(xy 463.041841 -59.046007) (xy 463.032602 -59.03468) (xy 463.014945 -59.013761) (xy 462.985223 -58.96779)
			(xy 462.96238 -58.918042) (xy 462.946886 -58.865538) (xy 462.93906 -58.811358) (xy 462.939062 -58.756615)
			(xy 462.946892 -58.702436) (xy 462.962389 -58.649933) (xy 462.985236 -58.600186) (xy 463.014961 -58.554217)
			(xy 463.032602 -58.533284) (xy 463.041856 -58.52197) (xy 463.054031 -58.495407) (xy 463.0582 -58.466486)
			(xy 463.054023 -58.437567) (xy 463.041841 -58.411007) (xy 463.032602 -58.39968) (xy 463.014987 -58.378728)
			(xy 462.985272 -58.332761) (xy 462.962431 -58.283018) (xy 462.946934 -58.230522) (xy 462.9391 -58.17635)
			(xy 462.938622 -58.148982) (xy 462.939156 -58.120244) (xy 462.947779 -58.063418) (xy 462.964828 -58.008528)
			(xy 462.989917 -57.956816) (xy 463.022478 -57.909452) (xy 463.041746 -57.888124) (xy 463.051837 -57.876605)
			(xy 463.065181 -57.849054) (xy 463.069763 -57.818787) (xy 463.065173 -57.788521) (xy 463.051822 -57.760973)
			(xy 463.041746 -57.74944) (xy 463.022456 -57.728129) (xy 462.98989 -57.680765) (xy 462.964798 -57.62905)
			(xy 462.947748 -57.574157) (xy 462.939127 -57.517327) (xy 462.939129 -57.459847) (xy 462.947754 -57.403017)
			(xy 462.964807 -57.348125) (xy 462.989903 -57.296413) (xy 463.022473 -57.24905) (xy 463.041746 -57.227724)
			(xy 463.051837 -57.216205) (xy 463.065181 -57.188654) (xy 463.069763 -57.158387) (xy 463.065173 -57.128121)
			(xy 463.051822 -57.100573) (xy 463.041746 -57.08904) (xy 463.022468 -57.067719) (xy 462.989902 -57.020356)
			(xy 462.964811 -56.968642) (xy 462.947762 -56.91375) (xy 462.939142 -56.856921) (xy 462.938622 -56.828182)
			(xy 462.939038 -56.800927) (xy 462.946798 -56.746973) (xy 462.962158 -56.694672) (xy 462.984805 -56.64509)
			(xy 463.014278 -56.599236) (xy 463.049976 -56.558042) (xy 463.091174 -56.522349) (xy 463.137032 -56.492882)
			(xy 463.186618 -56.470241) (xy 463.23892 -56.454888) (xy 463.292875 -56.447135) (xy 463.32013 -56.446674)
			(xy 463.349046 -56.447215) (xy 463.406218 -56.455935) (xy 463.461417 -56.473187) (xy 463.51338 -56.498574)
			(xy 463.560914 -56.531515) (xy 463.60293 -56.571255) (xy 463.62112 -56.59374) (xy 463.631017 -56.605545)
			(xy 463.656341 -56.623064) (xy 463.685734 -56.63224) (xy 463.716526 -56.63224) (xy 463.745919 -56.623064)
			(xy 463.771243 -56.605545) (xy 463.78114 -56.59374) (xy 463.799319 -56.571246) (xy 463.84134 -56.531509)
			(xy 463.888877 -56.49857) (xy 463.940841 -56.473184) (xy 463.996041 -56.45593) (xy 464.053213 -56.447206)
			(xy 464.08213 -56.446674) (xy 464.110869 -56.447186) (xy 464.167697 -56.455813) (xy 464.222587 -56.472866)
			(xy 464.274299 -56.49796) (xy 464.321661 -56.530527) (xy 464.342988 -56.549798) (xy 464.354522 -56.55987)
			(xy 464.382068 -56.573212) (xy 464.41233 -56.577797) (xy 464.442592 -56.573212) (xy 464.470138 -56.55987)
			(xy 464.481672 -56.549798) (xy 464.502999 -56.530528) (xy 464.550362 -56.497963) (xy 464.602073 -56.472872)
			(xy 464.656964 -56.455822) (xy 464.713791 -56.4472) (xy 464.771269 -56.4472) (xy 464.828096 -56.455822)
			(xy 464.882987 -56.472872) (xy 464.934698 -56.497963) (xy 464.982061 -56.530528) (xy 465.003388 -56.549798)
			(xy 465.014922 -56.55987) (xy 465.042468 -56.573212) (xy 465.07273 -56.577797) (xy 465.102992 -56.573212)
			(xy 465.130538 -56.55987) (xy 465.142072 -56.549798) (xy 465.163399 -56.530528) (xy 465.210762 -56.497963)
			(xy 465.262473 -56.472872) (xy 465.317364 -56.455822) (xy 465.374191 -56.4472) (xy 465.431669 -56.4472)
			(xy 465.488496 -56.455822) (xy 465.543387 -56.472872) (xy 465.595098 -56.497963) (xy 465.642461 -56.530528)
			(xy 465.663788 -56.549798) (xy 465.675322 -56.55987) (xy 465.702868 -56.573212) (xy 465.73313 -56.577797)
			(xy 465.763392 -56.573212) (xy 465.790938 -56.55987) (xy 465.802472 -56.549798) (xy 465.823796 -56.530523)
			(xy 465.871158 -56.497955) (xy 465.92287 -56.472863) (xy 465.977762 -56.455813) (xy 466.034591 -56.447193)
			(xy 466.06333 -56.446674) (xy 466.092246 -56.447215) (xy 466.149418 -56.455935) (xy 466.204617 -56.473187)
			(xy 466.25658 -56.498574) (xy 466.304114 -56.531515) (xy 466.34613 -56.571255) (xy 466.36432 -56.59374)
			(xy 466.374217 -56.605545) (xy 466.399541 -56.623064) (xy 466.428934 -56.63224) (xy 466.459726 -56.63224)
			(xy 466.489119 -56.623064) (xy 466.514443 -56.605545) (xy 466.52434 -56.59374) (xy 466.542519 -56.571246)
			(xy 466.58454 -56.531509) (xy 466.632077 -56.49857) (xy 466.684041 -56.473184) (xy 466.739241 -56.45593)
			(xy 466.796413 -56.447206) (xy 466.82533 -56.446674) (xy 466.852581 -56.44715) (xy 466.906528 -56.45491)
			(xy 466.958822 -56.470268) (xy 467.008398 -56.492911) (xy 467.054248 -56.522379) (xy 467.095437 -56.558071)
			(xy 467.131128 -56.599262) (xy 467.160594 -56.645112) (xy 467.183236 -56.694689) (xy 467.198593 -56.746983)
			(xy 467.206351 -56.800931) (xy 467.206838 -56.828182) (xy 467.206293 -56.85692) (xy 467.197674 -56.913746)
			(xy 467.180628 -56.968636) (xy 467.155542 -57.020348) (xy 467.122982 -57.067712) (xy 467.103714 -57.08904)
			(xy 467.093661 -57.100589) (xy 467.080319 -57.12813) (xy 467.075732 -57.158387) (xy 467.080311 -57.188645)
			(xy 467.093646 -57.21619) (xy 467.103714 -57.227724) (xy 467.122965 -57.249067) (xy 467.155528 -57.296428)
			(xy 467.180618 -57.348137) (xy 467.197667 -57.403025) (xy 467.206291 -57.459849) (xy 467.206293 -57.517324)
			(xy 467.197673 -57.574149) (xy 467.180628 -57.629038) (xy 467.155541 -57.680749) (xy 467.122982 -57.728112)
			(xy 467.103714 -57.74944) (xy 467.093661 -57.760989) (xy 467.080319 -57.78853) (xy 467.075732 -57.818787)
			(xy 467.080311 -57.849045) (xy 467.093646 -57.87659) (xy 467.103714 -57.888124) (xy 467.122968 -57.909465)
			(xy 467.155539 -57.956823) (xy 467.180635 -58.008531) (xy 467.197689 -58.063418) (xy 467.206316 -58.120244)
			(xy 467.206838 -58.148982) (xy 467.206376 -58.176353) (xy 467.19856 -58.230532) (xy 467.183071 -58.283036)
			(xy 467.160227 -58.332783) (xy 467.130501 -58.378749) (xy 467.112858 -58.39968) (xy 467.103642 -58.411022)
			(xy 467.091467 -58.437575) (xy 467.087293 -58.466486) (xy 467.09146 -58.495399) (xy 467.103627 -58.521955)
			(xy 467.112858 -58.533284) (xy 467.130482 -58.554231) (xy 467.160208 -58.600196) (xy 467.183056 -58.64994)
			(xy 467.198554 -58.70244) (xy 467.206385 -58.756617) (xy 467.206387 -58.811356) (xy 467.19856 -58.865534)
			(xy 467.183065 -58.918035) (xy 467.160221 -58.96778) (xy 467.130498 -59.013748) (xy 467.112858 -59.03468)
			(xy 467.103642 -59.046022) (xy 467.091467 -59.072575) (xy 467.087293 -59.101486) (xy 467.09146 -59.130399)
			(xy 467.103627 -59.156955) (xy 467.112858 -59.168284) (xy 467.130497 -59.189217) (xy 467.16021 -59.235189)
			(xy 467.183047 -59.284936) (xy 467.198538 -59.337437) (xy 467.206365 -59.391613) (xy 467.206838 -59.418982)
			(xy 467.206305 -59.446231) (xy 467.198552 -59.500176) (xy 467.1832 -59.552468) (xy 467.160564 -59.602043)
			(xy 467.131102 -59.647892) (xy 467.095416 -59.689082) (xy 467.05423 -59.724773) (xy 467.008385 -59.754241)
			(xy 466.958813 -59.776884) (xy 466.906523 -59.792242) (xy 466.852579 -59.800002) (xy 466.82533 -59.80049)
			(xy 466.796414 -59.799954) (xy 466.739243 -59.791229) (xy 466.684045 -59.773975) (xy 466.632083 -59.748587)
			(xy 466.584548 -59.715646) (xy 466.542531 -59.675908) (xy 466.52434 -59.653424) (xy 466.514443 -59.641619)
			(xy 466.489119 -59.6241) (xy 466.459726 -59.614924) (xy 466.428934 -59.614924) (xy 466.399541 -59.6241)
			(xy 466.374217 -59.641619) (xy 466.36432 -59.653424) (xy 466.346124 -59.675903) (xy 466.304104 -59.715637)
			(xy 466.25657 -59.748576) (xy 466.20461 -59.773965) (xy 466.149414 -59.791223) (xy 466.092246 -59.799954)
			(xy 466.06333 -59.80049) (xy 466.034592 -59.799951) (xy 465.977765 -59.791332) (xy 465.922874 -59.774286)
			(xy 465.871162 -59.749198) (xy 465.823799 -59.716636) (xy 465.802472 -59.697366) (xy 465.790938 -59.687294)
			(xy 465.763392 -59.673952) (xy 465.73313 -59.669367) (xy 465.702868 -59.673952) (xy 465.675322 -59.687294)
			(xy 465.663788 -59.697366) (xy 465.642461 -59.716636) (xy 465.595098 -59.749201) (xy 465.543387 -59.774292)
			(xy 465.488496 -59.791342) (xy 465.431669 -59.799964) (xy 465.374191 -59.799964) (xy 465.317364 -59.791342)
			(xy 465.262473 -59.774292) (xy 465.210762 -59.749201) (xy 465.163399 -59.716636) (xy 465.142072 -59.697366)
			(xy 465.130538 -59.687294) (xy 465.102992 -59.673952) (xy 465.07273 -59.669367) (xy 465.042468 -59.673952)
			(xy 465.014922 -59.687294) (xy 465.003388 -59.697366) (xy 464.982061 -59.716636) (xy 464.934698 -59.749201)
			(xy 464.882987 -59.774292) (xy 464.828096 -59.791342) (xy 464.771269 -59.799964) (xy 464.713791 -59.799964)
			(xy 464.656964 -59.791342) (xy 464.602073 -59.774292) (xy 464.550362 -59.749201) (xy 464.502999 -59.716636)
			(xy 464.481672 -59.697366) (xy 464.470138 -59.687294) (xy 464.442592 -59.673952) (xy 464.41233 -59.669367)
			(xy 464.382068 -59.673952) (xy 464.354522 -59.687294) (xy 464.342988 -59.697366) (xy 464.321649 -59.716623)
			(xy 464.27429 -59.749191) (xy 464.222582 -59.774286) (xy 464.167694 -59.79134) (xy 464.110868 -59.799967)
			(xy 464.08213 -59.80049) (xy 464.053214 -59.799954) (xy 463.996043 -59.791229) (xy 463.940845 -59.773975)
			(xy 463.888883 -59.748587) (xy 463.841348 -59.715646) (xy 463.799331 -59.675908) (xy 463.78114 -59.653424)
			(xy 463.771243 -59.641619) (xy 463.745919 -59.6241) (xy 463.716526 -59.614924) (xy 463.685734 -59.614924)
			(xy 463.656341 -59.6241) (xy 463.631017 -59.641619) (xy 463.62112 -59.653424) (xy 463.602924 -59.675903)
			(xy 463.560904 -59.715637) (xy 463.51337 -59.748576) (xy 463.46141 -59.773965) (xy 463.406214 -59.791223)
			(xy 463.349046 -59.799954) (xy 463.32013 -59.80049) (xy 463.292877 -59.800017) (xy 463.238926 -59.792263)
			(xy 463.186627 -59.77691) (xy 463.137046 -59.75427) (xy 463.091191 -59.724803) (xy 463.049998 -59.689111)
			(xy 463.014304 -59.647918) (xy 462.984836 -59.602065) (xy 462.962194 -59.552484) (xy 462.946839 -59.500186)
			(xy 462.939084 -59.446235) (xy 462.938622 -59.418982) (xy 429.592994 -59.418982) (xy 434.1749 -64.000888)
			(xy 434.1749 -68.56215) (xy 463.017866 -68.56215) (xy 463.017866 -68.477454) (xy 463.025917 -68.39314)
			(xy 463.041946 -68.309974) (xy 463.065807 -68.228707) (xy 463.097286 -68.150077) (xy 463.136097 -68.074796)
			(xy 463.181887 -68.003544) (xy 463.234243 -67.936968) (xy 463.292691 -67.87567) (xy 463.356701 -67.820205)
			(xy 463.425693 -67.771076) (xy 463.499043 -67.728727) (xy 463.576086 -67.693543) (xy 463.656125 -67.665841)
			(xy 463.738434 -67.645873) (xy 463.822269 -67.63382) (xy 463.90687 -67.62979) (xy 463.991471 -67.63382)
			(xy 464.075306 -67.645873) (xy 464.157615 -67.665841) (xy 464.237654 -67.693543) (xy 464.314697 -67.728727)
			(xy 464.388047 -67.771076) (xy 464.457039 -67.820205) (xy 464.521049 -67.87567) (xy 464.579497 -67.936968)
			(xy 464.631853 -68.003544) (xy 464.677643 -68.074796) (xy 464.716454 -68.150077) (xy 464.747933 -68.228707)
			(xy 464.771794 -68.309974) (xy 464.787823 -68.39314) (xy 464.795874 -68.477454) (xy 464.796378 -68.519802)
			(xy 465.542379 -68.519802) (xy 465.546415 -68.436355) (xy 465.558487 -68.353687) (xy 465.57848 -68.27257)
			(xy 465.606209 -68.193761) (xy 465.641415 -68.117996) (xy 465.683769 -68.045983) (xy 465.732875 -67.978394)
			(xy 465.788276 -67.91586) (xy 465.849453 -67.858965) (xy 465.915836 -67.808239) (xy 465.986804 -67.764158)
			(xy 466.061696 -67.727132) (xy 466.139812 -67.697506) (xy 466.220422 -67.675558) (xy 466.302774 -67.661493)
			(xy 466.3861 -67.655441) (xy 466.46962 -67.65746) (xy 466.552556 -67.66753) (xy 466.634132 -67.685558)
			(xy 466.713588 -67.711375) (xy 466.790181 -67.74474) (xy 466.863197 -67.785341) (xy 466.931953 -67.8328)
			(xy 466.995807 -67.886673) (xy 467.054164 -67.946458) (xy 467.106479 -68.011595) (xy 467.152262 -68.081478)
			(xy 467.191087 -68.155453) (xy 467.222592 -68.23283) (xy 467.246481 -68.312887) (xy 467.262532 -68.394875)
			(xy 467.270595 -68.47803) (xy 467.2711 -68.519802) (xy 467.270595 -68.561574) (xy 467.262532 -68.644729)
			(xy 467.246481 -68.726717) (xy 467.222592 -68.806774) (xy 467.191087 -68.884151) (xy 467.152262 -68.958126)
			(xy 467.106479 -69.028009) (xy 467.054164 -69.093146) (xy 466.995807 -69.152931) (xy 466.931953 -69.206804)
			(xy 466.863197 -69.254263) (xy 466.790181 -69.294864) (xy 466.713588 -69.328229) (xy 466.634132 -69.354046)
			(xy 466.552556 -69.372074) (xy 466.46962 -69.382144) (xy 466.3861 -69.384163) (xy 466.302774 -69.378111)
			(xy 466.220422 -69.364046) (xy 466.139812 -69.342098) (xy 466.061696 -69.312472) (xy 465.986804 -69.275446)
			(xy 465.915836 -69.231365) (xy 465.849453 -69.180639) (xy 465.788276 -69.123744) (xy 465.732875 -69.06121)
			(xy 465.683769 -68.993621) (xy 465.641415 -68.921608) (xy 465.606209 -68.845843) (xy 465.57848 -68.767034)
			(xy 465.558487 -68.685917) (xy 465.546415 -68.603249) (xy 465.542379 -68.519802) (xy 464.796378 -68.519802)
			(xy 464.795874 -68.56215) (xy 464.787823 -68.646464) (xy 464.771794 -68.72963) (xy 464.747933 -68.810897)
			(xy 464.716454 -68.889527) (xy 464.677643 -68.964808) (xy 464.631853 -69.03606) (xy 464.579497 -69.102636)
			(xy 464.521049 -69.163934) (xy 464.457039 -69.219399) (xy 464.388047 -69.268528) (xy 464.314697 -69.310877)
			(xy 464.237654 -69.346061) (xy 464.157615 -69.373763) (xy 464.075306 -69.393731) (xy 463.991471 -69.405784)
			(xy 463.90687 -69.409815) (xy 463.822269 -69.405784) (xy 463.738434 -69.393731) (xy 463.656125 -69.373763)
			(xy 463.576086 -69.346061) (xy 463.499043 -69.310877) (xy 463.425693 -69.268528) (xy 463.356701 -69.219399)
			(xy 463.292691 -69.163934) (xy 463.234243 -69.102636) (xy 463.181887 -69.03606) (xy 463.136097 -68.964808)
			(xy 463.097286 -68.889527) (xy 463.065807 -68.810897) (xy 463.041946 -68.72963) (xy 463.025917 -68.646464)
			(xy 463.017866 -68.56215) (xy 434.1749 -68.56215) (xy 434.1749 -71.039228) (xy 443.224918 -71.039228)
			(xy 443.228989 -70.983606) (xy 443.241115 -70.929169) (xy 443.261038 -70.877078) (xy 443.288334 -70.828443)
			(xy 443.32242 -70.7843) (xy 443.362569 -70.745591) (xy 443.407927 -70.71314) (xy 443.457527 -70.687639)
			(xy 443.510311 -70.669632) (xy 443.565154 -70.659502) (xy 443.620888 -70.657465) (xy 443.676325 -70.663565)
			(xy 443.730282 -70.677671) (xy 443.781611 -70.699483) (xy 443.829217 -70.728537) (xy 443.872085 -70.764212)
			(xy 443.909302 -70.805749) (xy 443.940075 -70.852262) (xy 443.963747 -70.902759) (xy 443.979815 -70.956166)
			(xy 443.987935 -71.011342) (xy 443.988444 -71.039228) (xy 443.987935 -71.067114) (xy 443.979815 -71.12229)
			(xy 443.963747 -71.175697) (xy 443.940075 -71.226194) (xy 443.909302 -71.272707) (xy 443.872085 -71.314244)
			(xy 443.829217 -71.349919) (xy 443.781611 -71.378973) (xy 443.730282 -71.400785) (xy 443.676325 -71.414891)
			(xy 443.620888 -71.420991) (xy 443.565154 -71.418954) (xy 443.510311 -71.408824) (xy 443.457527 -71.390817)
			(xy 443.407927 -71.365316) (xy 443.362569 -71.332865) (xy 443.32242 -71.294156) (xy 443.288334 -71.250013)
			(xy 443.261038 -71.201378) (xy 443.241115 -71.149287) (xy 443.228989 -71.09485) (xy 443.224918 -71.039228)
			(xy 434.1749 -71.039228) (xy 434.1749 -73.088052) (xy 452.643969 -73.088052) (xy 452.643969 -73.033548)
			(xy 452.651726 -72.979599) (xy 452.667082 -72.927303) (xy 452.689723 -72.877724) (xy 452.719191 -72.831873)
			(xy 452.754883 -72.790682) (xy 452.796074 -72.754989) (xy 452.841926 -72.725522) (xy 452.891505 -72.702881)
			(xy 452.943801 -72.687526) (xy 452.99775 -72.679769) (xy 453.025002 -72.679306) (xy 453.052711 -72.679821)
			(xy 453.107544 -72.687844) (xy 453.160639 -72.703721) (xy 453.210876 -72.727117) (xy 453.257196 -72.75754)
			(xy 453.27824 -72.775572) (xy 453.289642 -72.78504) (xy 453.316492 -72.797557) (xy 453.345804 -72.80185)
			(xy 453.375116 -72.797557) (xy 453.401966 -72.78504) (xy 453.413368 -72.775572) (xy 453.434411 -72.757537)
			(xy 453.480729 -72.727108) (xy 453.530966 -72.703707) (xy 453.584061 -72.687827) (xy 453.638896 -72.679803)
			(xy 453.666606 -72.679306) (xy 453.693858 -72.679764) (xy 453.747807 -72.687522) (xy 453.800103 -72.702878)
			(xy 453.849681 -72.72552) (xy 453.895533 -72.754988) (xy 453.936724 -72.790681) (xy 453.972416 -72.831872)
			(xy 454.001883 -72.877724) (xy 454.024524 -72.927303) (xy 454.03988 -72.979599) (xy 454.047636 -73.033548)
			(xy 454.047636 -73.088052) (xy 454.047636 -73.088053) (xy 454.467669 -73.088053) (xy 454.467669 -73.033547)
			(xy 454.475427 -72.979596) (xy 454.490783 -72.927299) (xy 454.513426 -72.877719) (xy 454.542895 -72.831866)
			(xy 454.57859 -72.790675) (xy 454.619784 -72.754982) (xy 454.665638 -72.725516) (xy 454.715219 -72.702876)
			(xy 454.767518 -72.687522) (xy 454.821469 -72.679768) (xy 454.848722 -72.679306) (xy 454.876431 -72.679809)
			(xy 454.931265 -72.687835) (xy 454.98436 -72.703715) (xy 455.034596 -72.727113) (xy 455.080916 -72.757538)
			(xy 455.10196 -72.775572) (xy 455.113362 -72.78504) (xy 455.140212 -72.797557) (xy 455.169524 -72.80185)
			(xy 455.198836 -72.797557) (xy 455.225686 -72.78504) (xy 455.237088 -72.775572) (xy 455.258124 -72.757528)
			(xy 455.304444 -72.7271) (xy 455.354682 -72.703701) (xy 455.407779 -72.687823) (xy 455.462616 -72.679801)
			(xy 455.490326 -72.679306) (xy 455.517577 -72.679766) (xy 455.571524 -72.687525) (xy 455.623817 -72.702883)
			(xy 455.673393 -72.725527) (xy 455.719242 -72.754995) (xy 455.760431 -72.790688) (xy 455.796121 -72.831879)
			(xy 455.825586 -72.87773) (xy 455.848226 -72.927307) (xy 455.86358 -72.979602) (xy 455.871336 -73.033549)
			(xy 455.871336 -73.088051) (xy 455.86358 -73.141998) (xy 455.848226 -73.194293) (xy 455.825586 -73.24387)
			(xy 455.796121 -73.289721) (xy 455.760431 -73.330912) (xy 455.719242 -73.366605) (xy 455.673393 -73.396073)
			(xy 455.623817 -73.418717) (xy 455.571524 -73.434075) (xy 455.517577 -73.441834) (xy 455.490326 -73.442322)
			(xy 455.462616 -73.441843) (xy 455.407781 -73.43381) (xy 455.354686 -73.417924) (xy 455.30445 -73.39452)
			(xy 455.258131 -73.364091) (xy 455.237088 -73.346056) (xy 455.225686 -73.336588) (xy 455.198836 -73.324071)
			(xy 455.169524 -73.319778) (xy 455.140212 -73.324071) (xy 455.113362 -73.336588) (xy 455.10196 -73.346056)
			(xy 455.08091 -73.364082) (xy 455.034593 -73.394511) (xy 454.984358 -73.417914) (xy 454.931265 -73.433796)
			(xy 454.876431 -73.441823) (xy 454.848722 -73.442322) (xy 454.821469 -73.441832) (xy 454.767518 -73.434078)
			(xy 454.715219 -73.418724) (xy 454.665638 -73.396084) (xy 454.619784 -73.366618) (xy 454.57859 -73.330925)
			(xy 454.542895 -73.289734) (xy 454.513426 -73.243881) (xy 454.490783 -73.194301) (xy 454.475427 -73.142004)
			(xy 454.467669 -73.088053) (xy 454.047636 -73.088053) (xy 454.03988 -73.142001) (xy 454.024524 -73.194297)
			(xy 454.001883 -73.243876) (xy 453.972416 -73.289728) (xy 453.936724 -73.330919) (xy 453.895533 -73.366612)
			(xy 453.849681 -73.39608) (xy 453.800103 -73.418722) (xy 453.747807 -73.434078) (xy 453.693858 -73.441836)
			(xy 453.666606 -73.442322) (xy 453.638898 -73.441795) (xy 453.584065 -73.433774) (xy 453.530971 -73.4179)
			(xy 453.480734 -73.394506) (xy 453.434413 -73.364087) (xy 453.413368 -73.346056) (xy 453.401966 -73.336588)
			(xy 453.375116 -73.324071) (xy 453.345804 -73.319778) (xy 453.316492 -73.324071) (xy 453.289642 -73.336588)
			(xy 453.27824 -73.346056) (xy 453.257197 -73.364091) (xy 453.210879 -73.394519) (xy 453.160642 -73.41792)
			(xy 453.107547 -73.4338) (xy 453.052712 -73.441825) (xy 453.025002 -73.442322) (xy 452.99775 -73.441831)
			(xy 452.943801 -73.434074) (xy 452.891505 -73.418719) (xy 452.841926 -73.396078) (xy 452.796074 -73.366611)
			(xy 452.754883 -73.330918) (xy 452.719191 -73.289727) (xy 452.689723 -73.243876) (xy 452.667082 -73.194297)
			(xy 452.651726 -73.142001) (xy 452.643969 -73.088052) (xy 434.1749 -73.088052) (xy 434.1749 -74.640948)
			(xy 443.978282 -74.640948) (xy 443.982353 -74.585326) (xy 443.994479 -74.530889) (xy 444.014402 -74.478798)
			(xy 444.041698 -74.430163) (xy 444.075784 -74.38602) (xy 444.115933 -74.347311) (xy 444.161291 -74.31486)
			(xy 444.210891 -74.289359) (xy 444.263675 -74.271352) (xy 444.318518 -74.261222) (xy 444.374252 -74.259185)
			(xy 444.429689 -74.265285) (xy 444.483646 -74.279391) (xy 444.534975 -74.301203) (xy 444.582581 -74.330257)
			(xy 444.625449 -74.365932) (xy 444.662666 -74.407469) (xy 444.693439 -74.453982) (xy 444.717111 -74.504479)
			(xy 444.733179 -74.557886) (xy 444.741299 -74.613062) (xy 444.741808 -74.640948) (xy 444.741299 -74.668834)
			(xy 444.733179 -74.72401) (xy 444.717111 -74.777417) (xy 444.693439 -74.827914) (xy 444.662666 -74.874427)
			(xy 444.625449 -74.915964) (xy 444.582581 -74.951639) (xy 444.534975 -74.980693) (xy 444.483646 -75.002505)
			(xy 444.429689 -75.016611) (xy 444.374252 -75.022711) (xy 444.318518 -75.020674) (xy 444.263675 -75.010544)
			(xy 444.210891 -74.992537) (xy 444.161291 -74.967036) (xy 444.115933 -74.934585) (xy 444.075784 -74.895876)
			(xy 444.041698 -74.851733) (xy 444.014402 -74.803098) (xy 443.994479 -74.751007) (xy 443.982353 -74.69657)
			(xy 443.978282 -74.640948) (xy 434.1749 -74.640948) (xy 434.1749 -75.054206) (xy 451.065898 -75.054206)
			(xy 451.069969 -74.998584) (xy 451.082095 -74.944147) (xy 451.102018 -74.892056) (xy 451.129314 -74.843421)
			(xy 451.1634 -74.799278) (xy 451.203549 -74.760569) (xy 451.248907 -74.728118) (xy 451.298507 -74.702617)
			(xy 451.351291 -74.68461) (xy 451.406134 -74.67448) (xy 451.461868 -74.672443) (xy 451.517305 -74.678543)
			(xy 451.571262 -74.692649) (xy 451.622591 -74.714461) (xy 451.670197 -74.743515) (xy 451.713065 -74.77919)
			(xy 451.745377 -74.815253) (xy 454.048569 -74.815253) (xy 454.048569 -74.760747) (xy 454.056327 -74.706796)
			(xy 454.071683 -74.654499) (xy 454.094326 -74.604919) (xy 454.123795 -74.559066) (xy 454.15949 -74.517875)
			(xy 454.200684 -74.482182) (xy 454.246538 -74.452716) (xy 454.296119 -74.430076) (xy 454.348418 -74.414722)
			(xy 454.402369 -74.406968) (xy 454.429622 -74.406506) (xy 454.457331 -74.407009) (xy 454.512165 -74.415035)
			(xy 454.56526 -74.430915) (xy 454.615496 -74.454313) (xy 454.661816 -74.484738) (xy 454.68286 -74.502772)
			(xy 454.694262 -74.51224) (xy 454.721112 -74.524757) (xy 454.750424 -74.52905) (xy 454.779736 -74.524757)
			(xy 454.806586 -74.51224) (xy 454.817988 -74.502772) (xy 454.839024 -74.484728) (xy 454.885344 -74.4543)
			(xy 454.935582 -74.430901) (xy 454.988679 -74.415023) (xy 455.043516 -74.407001) (xy 455.071226 -74.406506)
			(xy 455.098477 -74.406966) (xy 455.152424 -74.414725) (xy 455.204717 -74.430083) (xy 455.254293 -74.452727)
			(xy 455.300142 -74.482195) (xy 455.341331 -74.517888) (xy 455.377021 -74.559079) (xy 455.406486 -74.60493)
			(xy 455.429126 -74.654507) (xy 455.44448 -74.706802) (xy 455.452236 -74.760749) (xy 455.452236 -74.815251)
			(xy 455.44448 -74.869198) (xy 455.429126 -74.921493) (xy 455.406486 -74.97107) (xy 455.377021 -75.016921)
			(xy 455.341331 -75.058112) (xy 455.300142 -75.093805) (xy 455.254293 -75.123273) (xy 455.204717 -75.145917)
			(xy 455.152424 -75.161275) (xy 455.098477 -75.169034) (xy 455.071226 -75.169522) (xy 455.043516 -75.169043)
			(xy 454.988681 -75.16101) (xy 454.935586 -75.145124) (xy 454.88535 -75.12172) (xy 454.839031 -75.091291)
			(xy 454.817988 -75.073256) (xy 454.806586 -75.063788) (xy 454.779736 -75.051271) (xy 454.750424 -75.046978)
			(xy 454.721112 -75.051271) (xy 454.694262 -75.063788) (xy 454.68286 -75.073256) (xy 454.66181 -75.091282)
			(xy 454.615493 -75.121711) (xy 454.565258 -75.145114) (xy 454.512165 -75.160996) (xy 454.457331 -75.169023)
			(xy 454.429622 -75.169522) (xy 454.402369 -75.169032) (xy 454.348418 -75.161278) (xy 454.296119 -75.145924)
			(xy 454.246538 -75.123284) (xy 454.200684 -75.093818) (xy 454.15949 -75.058125) (xy 454.123795 -75.016934)
			(xy 454.094326 -74.971081) (xy 454.071683 -74.921501) (xy 454.056327 -74.869204) (xy 454.048569 -74.815253)
			(xy 451.745377 -74.815253) (xy 451.750282 -74.820727) (xy 451.781055 -74.86724) (xy 451.804727 -74.917737)
			(xy 451.820795 -74.971144) (xy 451.828915 -75.02632) (xy 451.829424 -75.054206) (xy 451.828915 -75.082092)
			(xy 451.820795 -75.137268) (xy 451.804727 -75.190675) (xy 451.781055 -75.241172) (xy 451.750282 -75.287685)
			(xy 451.713065 -75.329222) (xy 451.670197 -75.364897) (xy 451.622591 -75.393951) (xy 451.571262 -75.415763)
			(xy 451.517305 -75.429869) (xy 451.461868 -75.435969) (xy 451.406134 -75.433932) (xy 451.351291 -75.423802)
			(xy 451.298507 -75.405795) (xy 451.248907 -75.380294) (xy 451.203549 -75.347843) (xy 451.1634 -75.309134)
			(xy 451.129314 -75.264991) (xy 451.102018 -75.216356) (xy 451.082095 -75.164265) (xy 451.069969 -75.109828)
			(xy 451.065898 -75.054206) (xy 434.1749 -75.054206) (xy 434.1749 -76.002572) (xy 463.017866 -76.002572)
			(xy 463.017866 -75.917876) (xy 463.025917 -75.833562) (xy 463.041946 -75.750396) (xy 463.065807 -75.669129)
			(xy 463.097286 -75.590499) (xy 463.136097 -75.515218) (xy 463.181887 -75.443966) (xy 463.234243 -75.37739)
			(xy 463.292691 -75.316092) (xy 463.356701 -75.260627) (xy 463.425693 -75.211498) (xy 463.499043 -75.169149)
			(xy 463.576086 -75.133965) (xy 463.656125 -75.106263) (xy 463.738434 -75.086295) (xy 463.822269 -75.074242)
			(xy 463.90687 -75.070212) (xy 463.991471 -75.074242) (xy 464.075306 -75.086295) (xy 464.157615 -75.106263)
			(xy 464.237654 -75.133965) (xy 464.314697 -75.169149) (xy 464.388047 -75.211498) (xy 464.457039 -75.260627)
			(xy 464.521049 -75.316092) (xy 464.579497 -75.37739) (xy 464.631853 -75.443966) (xy 464.677643 -75.515218)
			(xy 464.716454 -75.590499) (xy 464.747933 -75.669129) (xy 464.771794 -75.750396) (xy 464.787823 -75.833562)
			(xy 464.795874 -75.917876) (xy 464.796378 -75.960224) (xy 465.542379 -75.960224) (xy 465.546415 -75.876777)
			(xy 465.558487 -75.794109) (xy 465.57848 -75.712992) (xy 465.606209 -75.634183) (xy 465.641415 -75.558418)
			(xy 465.683769 -75.486405) (xy 465.732875 -75.418816) (xy 465.788276 -75.356282) (xy 465.849453 -75.299387)
			(xy 465.915836 -75.248661) (xy 465.986804 -75.20458) (xy 466.061696 -75.167554) (xy 466.139812 -75.137928)
			(xy 466.220422 -75.11598) (xy 466.302774 -75.101915) (xy 466.3861 -75.095863) (xy 466.46962 -75.097882)
			(xy 466.552556 -75.107952) (xy 466.634132 -75.12598) (xy 466.713588 -75.151797) (xy 466.790181 -75.185162)
			(xy 466.863197 -75.225763) (xy 466.931953 -75.273222) (xy 466.995807 -75.327095) (xy 467.054164 -75.38688)
			(xy 467.106479 -75.452017) (xy 467.152262 -75.5219) (xy 467.191087 -75.595875) (xy 467.222592 -75.673252)
			(xy 467.246481 -75.753309) (xy 467.262532 -75.835297) (xy 467.270595 -75.918452) (xy 467.2711 -75.960224)
			(xy 467.270595 -76.001996) (xy 467.262532 -76.085151) (xy 467.246481 -76.167139) (xy 467.222592 -76.247196)
			(xy 467.191087 -76.324573) (xy 467.152262 -76.398548) (xy 467.106479 -76.468431) (xy 467.054164 -76.533568)
			(xy 466.995807 -76.593353) (xy 466.931953 -76.647226) (xy 466.863197 -76.694685) (xy 466.790181 -76.735286)
			(xy 466.713588 -76.768651) (xy 466.634132 -76.794468) (xy 466.552556 -76.812496) (xy 466.46962 -76.822566)
			(xy 466.3861 -76.824585) (xy 466.302774 -76.818533) (xy 466.220422 -76.804468) (xy 466.139812 -76.78252)
			(xy 466.061696 -76.752894) (xy 465.986804 -76.715868) (xy 465.915836 -76.671787) (xy 465.849453 -76.621061)
			(xy 465.788276 -76.564166) (xy 465.732875 -76.501632) (xy 465.683769 -76.434043) (xy 465.641415 -76.36203)
			(xy 465.606209 -76.286265) (xy 465.57848 -76.207456) (xy 465.558487 -76.126339) (xy 465.546415 -76.043671)
			(xy 465.542379 -75.960224) (xy 464.796378 -75.960224) (xy 464.795874 -76.002572) (xy 464.787823 -76.086886)
			(xy 464.771794 -76.170052) (xy 464.747933 -76.251319) (xy 464.716454 -76.329949) (xy 464.677643 -76.40523)
			(xy 464.631853 -76.476482) (xy 464.579497 -76.543058) (xy 464.521049 -76.604356) (xy 464.457039 -76.659821)
			(xy 464.388047 -76.70895) (xy 464.314697 -76.751299) (xy 464.237654 -76.786483) (xy 464.157615 -76.814185)
			(xy 464.075306 -76.834153) (xy 463.991471 -76.846206) (xy 463.90687 -76.850237) (xy 463.822269 -76.846206)
			(xy 463.738434 -76.834153) (xy 463.656125 -76.814185) (xy 463.576086 -76.786483) (xy 463.499043 -76.751299)
			(xy 463.425693 -76.70895) (xy 463.356701 -76.659821) (xy 463.292691 -76.604356) (xy 463.234243 -76.543058)
			(xy 463.181887 -76.476482) (xy 463.136097 -76.40523) (xy 463.097286 -76.329949) (xy 463.065807 -76.251319)
			(xy 463.041946 -76.170052) (xy 463.025917 -76.086886) (xy 463.017866 -76.002572) (xy 434.1749 -76.002572)
			(xy 434.1749 -76.63053) (xy 445.693798 -76.63053) (xy 445.697869 -76.574908) (xy 445.709995 -76.520471)
			(xy 445.729918 -76.46838) (xy 445.757214 -76.419745) (xy 445.7913 -76.375602) (xy 445.831449 -76.336893)
			(xy 445.876807 -76.304442) (xy 445.926407 -76.278941) (xy 445.979191 -76.260934) (xy 446.034034 -76.250804)
			(xy 446.089768 -76.248767) (xy 446.145205 -76.254867) (xy 446.199162 -76.268973) (xy 446.250491 -76.290785)
			(xy 446.298097 -76.319839) (xy 446.340965 -76.355514) (xy 446.378182 -76.397051) (xy 446.408955 -76.443564)
			(xy 446.432627 -76.494061) (xy 446.448695 -76.547468) (xy 446.456815 -76.602644) (xy 446.457106 -76.618592)
			(xy 446.684398 -76.618592) (xy 446.688469 -76.56297) (xy 446.700595 -76.508533) (xy 446.720518 -76.456442)
			(xy 446.747814 -76.407807) (xy 446.7819 -76.363664) (xy 446.822049 -76.324955) (xy 446.867407 -76.292504)
			(xy 446.917007 -76.267003) (xy 446.969791 -76.248996) (xy 447.024634 -76.238866) (xy 447.080368 -76.236829)
			(xy 447.135805 -76.242929) (xy 447.189762 -76.257035) (xy 447.241091 -76.278847) (xy 447.288697 -76.307901)
			(xy 447.331565 -76.343576) (xy 447.368782 -76.385113) (xy 447.399555 -76.431626) (xy 447.423227 -76.482123)
			(xy 447.439295 -76.53553) (xy 447.447415 -76.590706) (xy 447.447924 -76.618592) (xy 447.447548 -76.639166)
			(xy 452.504554 -76.639166) (xy 452.508625 -76.583544) (xy 452.520751 -76.529107) (xy 452.540674 -76.477016)
			(xy 452.56797 -76.428381) (xy 452.602056 -76.384238) (xy 452.642205 -76.345529) (xy 452.687563 -76.313078)
			(xy 452.737163 -76.287577) (xy 452.789947 -76.26957) (xy 452.84479 -76.25944) (xy 452.900524 -76.257403)
			(xy 452.955961 -76.263503) (xy 453.009918 -76.277609) (xy 453.061247 -76.299421) (xy 453.108853 -76.328475)
			(xy 453.151721 -76.36415) (xy 453.188938 -76.405687) (xy 453.219711 -76.4522) (xy 453.243383 -76.502697)
			(xy 453.259451 -76.556104) (xy 453.267571 -76.61128) (xy 453.26808 -76.639166) (xy 453.267571 -76.667052)
			(xy 453.259451 -76.722228) (xy 453.243383 -76.775635) (xy 453.219711 -76.826132) (xy 453.188938 -76.872645)
			(xy 453.151721 -76.914182) (xy 453.108853 -76.949857) (xy 453.061247 -76.978911) (xy 453.009918 -77.000723)
			(xy 452.955961 -77.014829) (xy 452.900524 -77.020929) (xy 452.84479 -77.018892) (xy 452.789947 -77.008762)
			(xy 452.737163 -76.990755) (xy 452.687563 -76.965254) (xy 452.642205 -76.932803) (xy 452.602056 -76.894094)
			(xy 452.56797 -76.849951) (xy 452.540674 -76.801316) (xy 452.520751 -76.749225) (xy 452.508625 -76.694788)
			(xy 452.504554 -76.639166) (xy 447.447548 -76.639166) (xy 447.447415 -76.646478) (xy 447.439295 -76.701654)
			(xy 447.423227 -76.755061) (xy 447.399555 -76.805558) (xy 447.368782 -76.852071) (xy 447.331565 -76.893608)
			(xy 447.288697 -76.929283) (xy 447.241091 -76.958337) (xy 447.189762 -76.980149) (xy 447.135805 -76.994255)
			(xy 447.080368 -77.000355) (xy 447.024634 -76.998318) (xy 446.969791 -76.988188) (xy 446.917007 -76.970181)
			(xy 446.867407 -76.94468) (xy 446.822049 -76.912229) (xy 446.7819 -76.87352) (xy 446.747814 -76.829377)
			(xy 446.720518 -76.780742) (xy 446.700595 -76.728651) (xy 446.688469 -76.674214) (xy 446.684398 -76.618592)
			(xy 446.457106 -76.618592) (xy 446.457324 -76.63053) (xy 446.456815 -76.658416) (xy 446.448695 -76.713592)
			(xy 446.432627 -76.766999) (xy 446.408955 -76.817496) (xy 446.378182 -76.864009) (xy 446.340965 -76.905546)
			(xy 446.298097 -76.941221) (xy 446.250491 -76.970275) (xy 446.199162 -76.992087) (xy 446.145205 -77.006193)
			(xy 446.089768 -77.012293) (xy 446.034034 -77.010256) (xy 445.979191 -77.000126) (xy 445.926407 -76.982119)
			(xy 445.876807 -76.956618) (xy 445.831449 -76.924167) (xy 445.7913 -76.885458) (xy 445.757214 -76.841315)
			(xy 445.729918 -76.79268) (xy 445.709995 -76.740589) (xy 445.697869 -76.686152) (xy 445.693798 -76.63053)
			(xy 434.1749 -76.63053) (xy 434.1749 -77.518768) (xy 434.52288 -77.866748) (xy 444.625982 -77.866748)
			(xy 444.630053 -77.811126) (xy 444.642179 -77.756689) (xy 444.662102 -77.704598) (xy 444.689398 -77.655963)
			(xy 444.723484 -77.61182) (xy 444.763633 -77.573111) (xy 444.808991 -77.54066) (xy 444.858591 -77.515159)
			(xy 444.911375 -77.497152) (xy 444.966218 -77.487022) (xy 445.021952 -77.484985) (xy 445.077389 -77.491085)
			(xy 445.131346 -77.505191) (xy 445.182675 -77.527003) (xy 445.230281 -77.556057) (xy 445.273149 -77.591732)
			(xy 445.310366 -77.633269) (xy 445.341139 -77.679782) (xy 445.364811 -77.730279) (xy 445.380879 -77.783686)
			(xy 445.388999 -77.838862) (xy 445.389508 -77.866748) (xy 445.388999 -77.894634) (xy 445.380879 -77.94981)
			(xy 445.364811 -78.003217) (xy 445.341139 -78.053714) (xy 445.310366 -78.100227) (xy 445.273149 -78.141764)
			(xy 445.230281 -78.177439) (xy 445.182675 -78.206493) (xy 445.131346 -78.228305) (xy 445.077389 -78.242411)
			(xy 445.021952 -78.248511) (xy 444.966218 -78.246474) (xy 444.911375 -78.236344) (xy 444.858591 -78.218337)
			(xy 444.808991 -78.192836) (xy 444.763633 -78.160385) (xy 444.723484 -78.121676) (xy 444.689398 -78.077533)
			(xy 444.662102 -78.028898) (xy 444.642179 -77.976807) (xy 444.630053 -77.92237) (xy 444.625982 -77.866748)
			(xy 434.52288 -77.866748) (xy 435.576218 -78.920086) (xy 447.149726 -78.920086) (xy 447.153797 -78.864464)
			(xy 447.165923 -78.810027) (xy 447.185846 -78.757936) (xy 447.213142 -78.709301) (xy 447.247228 -78.665158)
			(xy 447.287377 -78.626449) (xy 447.332735 -78.593998) (xy 447.382335 -78.568497) (xy 447.435119 -78.55049)
			(xy 447.489962 -78.54036) (xy 447.545696 -78.538323) (xy 447.601133 -78.544423) (xy 447.65509 -78.558529)
			(xy 447.706419 -78.580341) (xy 447.754025 -78.609395) (xy 447.796893 -78.64507) (xy 447.83411 -78.686607)
			(xy 447.864883 -78.73312) (xy 447.888555 -78.783617) (xy 447.904623 -78.837024) (xy 447.908212 -78.861412)
			(xy 449.002402 -78.861412) (xy 449.006473 -78.80579) (xy 449.018599 -78.751353) (xy 449.038522 -78.699262)
			(xy 449.065818 -78.650627) (xy 449.099904 -78.606484) (xy 449.140053 -78.567775) (xy 449.185411 -78.535324)
			(xy 449.235011 -78.509823) (xy 449.287795 -78.491816) (xy 449.342638 -78.481686) (xy 449.398372 -78.479649)
			(xy 449.453809 -78.485749) (xy 449.507766 -78.499855) (xy 449.559095 -78.521667) (xy 449.606701 -78.550721)
			(xy 449.649569 -78.586396) (xy 449.686786 -78.627933) (xy 449.717559 -78.674446) (xy 449.741231 -78.724943)
			(xy 449.757299 -78.77835) (xy 449.765419 -78.833526) (xy 449.765928 -78.861412) (xy 449.765419 -78.889298)
			(xy 449.757299 -78.944474) (xy 449.741231 -78.997881) (xy 449.717559 -79.048378) (xy 449.686786 -79.094891)
			(xy 449.649569 -79.136428) (xy 449.606701 -79.172103) (xy 449.559095 -79.201157) (xy 449.507766 -79.222969)
			(xy 449.453809 -79.237075) (xy 449.398372 -79.243175) (xy 449.342638 -79.241138) (xy 449.287795 -79.231008)
			(xy 449.235011 -79.213001) (xy 449.185411 -79.1875) (xy 449.140053 -79.155049) (xy 449.099904 -79.11634)
			(xy 449.065818 -79.072197) (xy 449.038522 -79.023562) (xy 449.018599 -78.971471) (xy 449.006473 -78.917034)
			(xy 449.002402 -78.861412) (xy 447.908212 -78.861412) (xy 447.912743 -78.8922) (xy 447.913252 -78.920086)
			(xy 447.912743 -78.947972) (xy 447.904623 -79.003148) (xy 447.888555 -79.056555) (xy 447.864883 -79.107052)
			(xy 447.83411 -79.153565) (xy 447.796893 -79.195102) (xy 447.754025 -79.230777) (xy 447.706419 -79.259831)
			(xy 447.65509 -79.281643) (xy 447.601133 -79.295749) (xy 447.545696 -79.301849) (xy 447.489962 -79.299812)
			(xy 447.435119 -79.289682) (xy 447.382335 -79.271675) (xy 447.332735 -79.246174) (xy 447.287377 -79.213723)
			(xy 447.247228 -79.175014) (xy 447.213142 -79.130871) (xy 447.185846 -79.082236) (xy 447.165923 -79.030145)
			(xy 447.153797 -78.975708) (xy 447.149726 -78.920086) (xy 435.576218 -78.920086) (xy 436.78094 -80.124808)
			(xy 442.31306 -80.124808) (xy 442.3156 -80.127348) (xy 466.17128 -80.127348)
		)
		(stroke
			(width 0)
			(type solid)
		)
		(fill yes)
		(layer "In4.Cu")
		(net "GND")
	)
	(gr_poly
		(pts
			(xy 106.14914 -427.31182) (xy 106.14914 -419.502082) (xy 106.105706 -419.495732) (xy 106.078906 -419.491264)
			(xy 106.02684 -419.475735) (xy 105.977504 -419.452977) (xy 105.931895 -419.423452) (xy 105.890935 -419.387755)
			(xy 105.855453 -419.346609) (xy 105.826166 -419.300847) (xy 105.803666 -419.251392) (xy 105.788408 -419.199247)
			(xy 105.780702 -419.145464) (xy 105.780702 -419.091132) (xy 105.788409 -419.03735) (xy 105.803667 -418.985204)
			(xy 105.826167 -418.93575) (xy 105.855455 -418.889988) (xy 105.890938 -418.848843) (xy 105.931898 -418.813146)
			(xy 105.977507 -418.783621) (xy 106.026844 -418.760864) (xy 106.078909 -418.745335) (xy 106.105706 -418.740844)
			(xy 106.14914 -418.734494) (xy 106.14914 -411.999176) (xy 106.1487 -411.985207) (xy 106.141125 -411.958316)
			(xy 106.126549 -411.934482) (xy 106.106061 -411.915488) (xy 106.081194 -411.902754) (xy 106.053807 -411.897232)
			(xy 106.025949 -411.899336) (xy 105.999702 -411.908909) (xy 105.97703 -411.925233) (xy 105.968038 -411.93593)
			(xy 105.949842 -411.958059) (xy 105.907943 -411.997132) (xy 105.860673 -412.029501) (xy 105.809096 -412.05444)
			(xy 105.75437 -412.071389) (xy 105.697725 -412.079965) (xy 105.66908 -412.080456) (xy 105.641826 -412.079969)
			(xy 105.587874 -412.072209) (xy 105.535575 -412.05685) (xy 105.485994 -412.034205) (xy 105.44014 -412.004734)
			(xy 105.398947 -411.969038) (xy 105.363254 -411.927844) (xy 105.333785 -411.881988) (xy 105.311143 -411.832406)
			(xy 105.295787 -411.780107) (xy 105.28803 -411.726154) (xy 105.28803 -411.671646) (xy 105.295787 -411.617693)
			(xy 105.311143 -411.565394) (xy 105.333785 -411.515812) (xy 105.363254 -411.469956) (xy 105.398947 -411.428762)
			(xy 105.44014 -411.393066) (xy 105.485994 -411.363595) (xy 105.535575 -411.34095) (xy 105.587874 -411.325591)
			(xy 105.641826 -411.317831) (xy 105.66908 -411.31744) (xy 105.697725 -411.317952) (xy 105.754372 -411.326517)
			(xy 105.809101 -411.343456) (xy 105.860681 -411.36839) (xy 105.907953 -411.400756) (xy 105.949853 -411.439828)
			(xy 105.968038 -411.461966) (xy 105.977075 -411.472615) (xy 105.999732 -411.488929) (xy 106.025962 -411.498496)
			(xy 106.053803 -411.500599) (xy 106.081172 -411.495081) (xy 106.106023 -411.482355) (xy 106.126497 -411.463373)
			(xy 106.141063 -411.439554) (xy 106.148632 -411.41268) (xy 106.14914 -411.39872) (xy 106.14914 -409.55722)
			(xy 107.7214 -407.98496) (xy 108.570776 -407.98496) (xy 108.580174 -407.946098) (xy 108.587333 -407.918744)
			(xy 108.608619 -407.866363) (xy 108.637401 -407.817696) (xy 108.67305 -407.773808) (xy 108.714784 -407.735662)
			(xy 108.761691 -407.704092) (xy 108.812742 -407.679788) (xy 108.866821 -407.663284) (xy 108.922743 -407.654941)
			(xy 108.979285 -407.654941) (xy 109.035207 -407.663284) (xy 109.089286 -407.679788) (xy 109.140337 -407.704092)
			(xy 109.187244 -407.735662) (xy 109.228978 -407.773808) (xy 109.264627 -407.817696) (xy 109.293409 -407.866363)
			(xy 109.314695 -407.918744) (xy 109.321854 -407.946098) (xy 109.331252 -407.98496) (xy 109.459268 -407.98496)
			(xy 109.474437 -407.962529) (xy 109.510104 -407.921786) (xy 109.551176 -407.886499) (xy 109.596828 -407.857378)
			(xy 109.64614 -407.835008) (xy 109.698121 -407.81984) (xy 109.751726 -407.812179) (xy 109.805874 -407.812179)
			(xy 109.859479 -407.81984) (xy 109.91146 -407.835008) (xy 109.960772 -407.857378) (xy 110.006424 -407.886499)
			(xy 110.047496 -407.921786) (xy 110.083163 -407.962529) (xy 110.098332 -407.98496) (xy 112.7887 -407.98496)
			(xy 113.53546 -407.2382) (xy 113.53546 -402.328126) (xy 113.515902 -402.308314) (xy 113.492746 -402.284398)
			(xy 113.452208 -402.231597) (xy 113.418902 -402.17396) (xy 113.393399 -402.112471) (xy 113.376132 -402.048181)
			(xy 113.367398 -401.982188) (xy 113.366804 -401.948904) (xy 113.367371 -401.915105) (xy 113.376353 -401.848107)
			(xy 113.394133 -401.78289) (xy 113.420397 -401.720603) (xy 113.454682 -401.662346) (xy 113.496384 -401.609144)
			(xy 113.52022 -401.585176) (xy 113.53546 -401.57019) (xy 113.53546 -401.54352) (xy 113.568226 -401.54352)
			(xy 113.58118 -401.534122) (xy 113.607044 -401.516354) (xy 113.66231 -401.486632) (xy 113.720813 -401.463933)
			(xy 113.781663 -401.448603) (xy 113.843936 -401.440873) (xy 113.875312 -401.440396) (xy 113.908266 -401.440937)
			(xy 113.973618 -401.449484) (xy 114.03732 -401.466395) (xy 114.098307 -401.491387) (xy 114.155557 -401.524042)
			(xy 114.182144 -401.54352) (xy 114.43716 -401.54352) (xy 115.89004 -402.9964) (xy 116.5987 -402.9964)
			(xy 117.26672 -402.32838) (xy 117.26672 -399.702528) (xy 117.2337 -399.690082) (xy 117.208425 -399.680055)
			(xy 117.16077 -399.65387) (xy 117.117316 -399.621185) (xy 117.078942 -399.582661) (xy 117.046426 -399.53908)
			(xy 117.020427 -399.491324) (xy 117.001471 -399.440361) (xy 116.989942 -399.387222) (xy 116.986075 -399.332985)
			(xy 116.989947 -399.278749) (xy 117.001479 -399.225611) (xy 117.020439 -399.174649) (xy 117.046442 -399.126895)
			(xy 117.078961 -399.083316) (xy 117.117338 -399.044796) (xy 117.160795 -399.012114) (xy 117.208452 -398.985933)
			(xy 117.2337 -398.975834) (xy 117.26672 -398.963388) (xy 117.26672 -396.82928) (xy 116.61521 -396.17777)
			(xy 116.605104 -396.168312) (xy 116.58101 -396.154714) (xy 116.554148 -396.148093) (xy 116.526494 -396.148936)
			(xy 116.500085 -396.157181) (xy 116.476864 -396.172222) (xy 116.458541 -396.19295) (xy 116.446464 -396.217842)
			(xy 116.443506 -396.231364) (xy 116.438305 -396.257398) (xy 116.421653 -396.307809) (xy 116.398173 -396.355423)
			(xy 116.368316 -396.399321) (xy 116.33266 -396.438655) (xy 116.291895 -396.472665) (xy 116.246808 -396.500693)
			(xy 116.198269 -396.522199) (xy 116.147217 -396.536766) (xy 116.094639 -396.544113) (xy 116.068094 -396.544546)
			(xy 116.040842 -396.54406) (xy 115.986893 -396.536303) (xy 115.934597 -396.520948) (xy 115.885018 -396.498307)
			(xy 115.839165 -396.468841) (xy 115.797973 -396.43315) (xy 115.762278 -396.39196) (xy 115.732809 -396.34611)
			(xy 115.710164 -396.296533) (xy 115.694804 -396.244238) (xy 115.687042 -396.19029) (xy 115.686586 -396.163038)
			(xy 115.687047 -396.136498) (xy 115.694412 -396.083931) (xy 115.708991 -396.032893) (xy 115.730502 -395.984367)
			(xy 115.758531 -395.939291) (xy 115.792537 -395.898534) (xy 115.831863 -395.862884) (xy 115.87575 -395.833027)
			(xy 115.923351 -395.809541) (xy 115.973748 -395.792878) (xy 115.999768 -395.787626) (xy 116.013278 -395.784672)
			(xy 116.038128 -395.772563) (xy 116.058818 -395.75423) (xy 116.07383 -395.731019) (xy 116.082064 -395.70463)
			(xy 116.082915 -395.677) (xy 116.076322 -395.650154) (xy 116.062767 -395.626062) (xy 116.053362 -395.615922)
			(xy 115.75034 -395.3129) (xy 115.75034 -394.1699) (xy 114.7191 -393.13866) (xy 104.03078 -393.13866)
			(xy 101.51618 -390.62406) (xy 101.201982 -390.62406) (xy 101.191822 -390.661144) (xy 101.18395 -390.687541)
			(xy 101.161663 -390.737914) (xy 101.132366 -390.784559) (xy 101.096666 -390.826506) (xy 101.055305 -390.862885)
			(xy 101.009144 -390.892939) (xy 100.959141 -390.916044) (xy 100.906336 -390.931719) (xy 100.851825 -390.939639)
			(xy 100.796743 -390.939639) (xy 100.742232 -390.931719) (xy 100.689427 -390.916044) (xy 100.639424 -390.892939)
			(xy 100.593263 -390.862885) (xy 100.551902 -390.826506) (xy 100.516202 -390.784559) (xy 100.486905 -390.737914)
			(xy 100.464618 -390.687541) (xy 100.456746 -390.661144) (xy 100.446586 -390.62406) (xy 98.139504 -390.62406)
			(xy 98.125927 -390.624528) (xy 98.099752 -390.631762) (xy 98.076409 -390.645639) (xy 98.057549 -390.665177)
			(xy 98.044506 -390.688996) (xy 98.038201 -390.71541) (xy 98.039082 -390.742552) (xy 98.047085 -390.768502)
			(xy 98.061644 -390.791426) (xy 98.071432 -390.800844) (xy 98.090819 -390.819019) (xy 98.124882 -390.859808)
			(xy 98.152957 -390.904928) (xy 98.174502 -390.953505) (xy 98.189102 -391.004602) (xy 98.196473 -391.057229)
			(xy 98.196908 -391.0838) (xy 98.196422 -391.111051) (xy 98.188666 -391.164999) (xy 98.173311 -391.217294)
			(xy 98.150669 -391.266871) (xy 98.121203 -391.312721) (xy 98.085512 -391.353912) (xy 98.044321 -391.389603)
			(xy 97.998471 -391.419069) (xy 97.948894 -391.441711) (xy 97.896599 -391.457066) (xy 97.842651 -391.464822)
			(xy 97.8154 -391.465308) (xy 97.785912 -391.464751) (xy 97.72764 -391.455665) (xy 97.671459 -391.437724)
			(xy 97.618706 -391.411356) (xy 97.570637 -391.377188) (xy 97.528395 -391.336033) (xy 97.492985 -391.28887)
			(xy 97.478596 -391.263124) (xy 97.470949 -391.249867) (xy 97.449225 -391.228329) (xy 97.422103 -391.21418)
			(xy 97.392009 -391.208687) (xy 97.361637 -391.212341) (xy 97.333704 -391.224816) (xy 97.310712 -391.244994)
			(xy 97.30232 -391.25779) (xy 97.287358 -391.281255) (xy 97.251706 -391.323984) (xy 97.21022 -391.361075)
			(xy 97.163782 -391.391741) (xy 97.113379 -391.415329) (xy 97.060083 -391.431338) (xy 97.005025 -391.439429)
			(xy 96.9772 -391.439908) (xy 96.949949 -391.439422) (xy 96.896001 -391.431666) (xy 96.843706 -391.416311)
			(xy 96.794129 -391.393669) (xy 96.748279 -391.364203) (xy 96.707088 -391.328512) (xy 96.671397 -391.287321)
			(xy 96.641931 -391.241471) (xy 96.619289 -391.191894) (xy 96.603934 -391.139599) (xy 96.596178 -391.085651)
			(xy 96.595692 -391.0584) (xy 96.596232 -391.029389) (xy 96.605009 -390.972033) (xy 96.622361 -390.916666)
			(xy 96.647889 -390.86456) (xy 96.681005 -390.816916) (xy 96.700594 -390.79551) (xy 96.710419 -390.784403)
			(xy 96.723774 -390.757941) (xy 96.728976 -390.728761) (xy 96.725588 -390.699314) (xy 96.713894 -390.672078)
			(xy 96.694877 -390.649341) (xy 96.670137 -390.633016) (xy 96.641754 -390.624474) (xy 96.626934 -390.62406)
			(xy 94.79788 -390.62406) (xy 94.6023 -390.81964) (xy 94.6023 -392.812851) (xy 94.818178 -392.812851)
			(xy 94.818178 -392.758349) (xy 94.825934 -392.704401) (xy 94.841289 -392.652106) (xy 94.863931 -392.602529)
			(xy 94.893397 -392.556679) (xy 94.929088 -392.515488) (xy 94.970279 -392.479797) (xy 95.016129 -392.450331)
			(xy 95.065706 -392.427689) (xy 95.118001 -392.412334) (xy 95.171949 -392.404578) (xy 95.1992 -392.404092)
			(xy 95.226459 -392.404551) (xy 95.28042 -392.412319) (xy 95.332727 -392.427683) (xy 95.382318 -392.45033)
			(xy 95.428184 -392.479801) (xy 95.469391 -392.515496) (xy 95.505103 -392.556688) (xy 95.520256 -392.579352)
			(xy 95.528537 -392.591279) (xy 95.550473 -392.610283) (xy 95.576873 -392.622338) (xy 95.6056 -392.626468)
			(xy 95.634327 -392.622338) (xy 95.660727 -392.610283) (xy 95.682663 -392.591279) (xy 95.690944 -392.579352)
			(xy 95.706125 -392.556708) (xy 95.741826 -392.515509) (xy 95.783026 -392.479811) (xy 95.828888 -392.450339)
			(xy 95.878476 -392.427694) (xy 95.930783 -392.412336) (xy 95.984743 -392.404578) (xy 96.012 -392.404092)
			(xy 96.037689 -392.404519) (xy 96.088603 -392.411415) (xy 96.138131 -392.425082) (xy 96.185377 -392.445272)
			(xy 96.229485 -392.471621) (xy 96.269658 -392.503651) (xy 96.305168 -392.540783) (xy 96.32061 -392.561318)
			(xy 96.330094 -392.573507) (xy 96.354878 -392.591914) (xy 96.384024 -392.602092) (xy 96.414879 -392.603114)
			(xy 96.444635 -392.594887) (xy 96.470583 -392.57816) (xy 96.480884 -392.566652) (xy 96.499118 -392.54558)
			(xy 96.540664 -392.508444) (xy 96.587167 -392.477742) (xy 96.637638 -392.454127) (xy 96.691007 -392.438098)
			(xy 96.746138 -392.429998) (xy 96.774 -392.429492) (xy 96.802919 -392.429975) (xy 96.860093 -392.438707)
			(xy 96.915294 -392.455969) (xy 96.967256 -392.481367) (xy 97.014789 -392.514319) (xy 97.056803 -392.554068)
			(xy 97.07499 -392.576558) (xy 97.084887 -392.588363) (xy 97.110211 -392.605882) (xy 97.139604 -392.615058)
			(xy 97.170396 -392.615058) (xy 97.199789 -392.605882) (xy 97.225113 -392.588363) (xy 97.23501 -392.576558)
			(xy 97.253185 -392.554061) (xy 97.295209 -392.514329) (xy 97.342748 -392.481392) (xy 97.394712 -392.456007)
			(xy 97.449912 -392.438753) (xy 97.507083 -392.430026) (xy 97.536 -392.429492) (xy 97.563251 -392.429978)
			(xy 97.617199 -392.437734) (xy 97.669494 -392.453089) (xy 97.719071 -392.475731) (xy 97.764921 -392.505197)
			(xy 97.806112 -392.540888) (xy 97.841803 -392.582079) (xy 97.871269 -392.627929) (xy 97.893911 -392.677506)
			(xy 97.909266 -392.729801) (xy 97.917022 -392.783749) (xy 97.917022 -392.838251) (xy 97.909266 -392.892199)
			(xy 97.893911 -392.944494) (xy 97.871269 -392.994071) (xy 97.841803 -393.039921) (xy 97.806112 -393.081112)
			(xy 97.764921 -393.116803) (xy 97.719071 -393.146269) (xy 97.669494 -393.168911) (xy 97.617199 -393.184266)
			(xy 97.563251 -393.192022) (xy 97.536 -393.192508) (xy 97.507081 -393.192025) (xy 97.449907 -393.183293)
			(xy 97.394706 -393.166031) (xy 97.342744 -393.140633) (xy 97.295211 -393.107681) (xy 97.253197 -393.067932)
			(xy 97.23501 -393.045442) (xy 97.225113 -393.033637) (xy 97.199789 -393.016118) (xy 97.170396 -393.006942)
			(xy 97.139604 -393.006942) (xy 97.110211 -393.016118) (xy 97.084887 -393.033637) (xy 97.07499 -393.045442)
			(xy 97.056815 -393.067939) (xy 97.014791 -393.107671) (xy 96.967252 -393.140608) (xy 96.915288 -393.165993)
			(xy 96.860088 -393.183247) (xy 96.802917 -393.191974) (xy 96.774 -393.192508) (xy 96.748311 -393.192081)
			(xy 96.697397 -393.185185) (xy 96.647869 -393.171518) (xy 96.600623 -393.151328) (xy 96.556515 -393.124979)
			(xy 96.516342 -393.092949) (xy 96.480832 -393.055817) (xy 96.46539 -393.035282) (xy 96.455906 -393.023093)
			(xy 96.431122 -393.004686) (xy 96.401976 -392.994508) (xy 96.371121 -392.993486) (xy 96.341365 -393.001713)
			(xy 96.315417 -393.01844) (xy 96.305116 -393.029948) (xy 96.286882 -393.05102) (xy 96.245336 -393.088156)
			(xy 96.198833 -393.118858) (xy 96.148362 -393.142473) (xy 96.094993 -393.158502) (xy 96.039862 -393.166602)
			(xy 96.012 -393.167108) (xy 95.984741 -393.166649) (xy 95.93078 -393.158881) (xy 95.878473 -393.143517)
			(xy 95.828882 -393.12087) (xy 95.783016 -393.091399) (xy 95.741809 -393.055704) (xy 95.706097 -393.014512)
			(xy 95.690944 -392.991848) (xy 95.682663 -392.979921) (xy 95.660727 -392.960917) (xy 95.634327 -392.948862)
			(xy 95.6056 -392.944732) (xy 95.576873 -392.948862) (xy 95.550473 -392.960917) (xy 95.528537 -392.979921)
			(xy 95.520256 -392.991848) (xy 95.505075 -393.014492) (xy 95.469374 -393.055691) (xy 95.428174 -393.091389)
			(xy 95.382312 -393.120861) (xy 95.332724 -393.143506) (xy 95.280417 -393.158864) (xy 95.226457 -393.166622)
			(xy 95.1992 -393.167108) (xy 95.171949 -393.166622) (xy 95.118001 -393.158866) (xy 95.065706 -393.143511)
			(xy 95.016129 -393.120869) (xy 94.970279 -393.091403) (xy 94.929088 -393.055712) (xy 94.893397 -393.014521)
			(xy 94.863931 -392.968671) (xy 94.841289 -392.919094) (xy 94.825934 -392.866799) (xy 94.818178 -392.812851)
			(xy 94.6023 -392.812851) (xy 94.6023 -393.1793) (xy 95.07474 -393.65174) (xy 100.435916 -393.65174)
			(xy 100.439987 -393.596118) (xy 100.452113 -393.541681) (xy 100.472036 -393.48959) (xy 100.499332 -393.440955)
			(xy 100.533418 -393.396812) (xy 100.573567 -393.358103) (xy 100.618925 -393.325652) (xy 100.668525 -393.300151)
			(xy 100.721309 -393.282144) (xy 100.776152 -393.272014) (xy 100.831886 -393.269977) (xy 100.887323 -393.276077)
			(xy 100.94128 -393.290183) (xy 100.992609 -393.311995) (xy 101.040215 -393.341049) (xy 101.083083 -393.376724)
			(xy 101.1203 -393.418261) (xy 101.151073 -393.464774) (xy 101.174745 -393.515271) (xy 101.190813 -393.568678)
			(xy 101.198933 -393.623854) (xy 101.199442 -393.65174) (xy 101.198933 -393.679626) (xy 101.194215 -393.711684)
			(xy 106.949746 -393.711684) (xy 106.953817 -393.656062) (xy 106.965943 -393.601625) (xy 106.985866 -393.549534)
			(xy 107.013162 -393.500899) (xy 107.047248 -393.456756) (xy 107.087397 -393.418047) (xy 107.132755 -393.385596)
			(xy 107.182355 -393.360095) (xy 107.235139 -393.342088) (xy 107.289982 -393.331958) (xy 107.345716 -393.329921)
			(xy 107.401153 -393.336021) (xy 107.45511 -393.350127) (xy 107.506439 -393.371939) (xy 107.554045 -393.400993)
			(xy 107.596913 -393.436668) (xy 107.63413 -393.478205) (xy 107.664903 -393.524718) (xy 107.688575 -393.575215)
			(xy 107.704643 -393.628622) (xy 107.712763 -393.683798) (xy 107.713272 -393.711684) (xy 107.712763 -393.73957)
			(xy 107.704643 -393.794746) (xy 107.688575 -393.848153) (xy 107.664903 -393.89865) (xy 107.63413 -393.945163)
			(xy 107.596913 -393.9867) (xy 107.554045 -394.022375) (xy 107.506439 -394.051429) (xy 107.45511 -394.073241)
			(xy 107.401153 -394.087347) (xy 107.345716 -394.093447) (xy 107.289982 -394.09141) (xy 107.235139 -394.08128)
			(xy 107.182355 -394.063273) (xy 107.132755 -394.037772) (xy 107.087397 -394.005321) (xy 107.047248 -393.966612)
			(xy 107.013162 -393.922469) (xy 106.985866 -393.873834) (xy 106.965943 -393.821743) (xy 106.953817 -393.767306)
			(xy 106.949746 -393.711684) (xy 101.194215 -393.711684) (xy 101.190813 -393.734802) (xy 101.174745 -393.788209)
			(xy 101.151073 -393.838706) (xy 101.1203 -393.885219) (xy 101.083083 -393.926756) (xy 101.040215 -393.962431)
			(xy 100.992609 -393.991485) (xy 100.94128 -394.013297) (xy 100.887323 -394.027403) (xy 100.831886 -394.033503)
			(xy 100.776152 -394.031466) (xy 100.721309 -394.021336) (xy 100.668525 -394.003329) (xy 100.618925 -393.977828)
			(xy 100.573567 -393.945377) (xy 100.533418 -393.906668) (xy 100.499332 -393.862525) (xy 100.472036 -393.81389)
			(xy 100.452113 -393.761799) (xy 100.439987 -393.707362) (xy 100.435916 -393.65174) (xy 95.07474 -393.65174)
			(xy 95.745808 -394.322808) (xy 102.354632 -394.322808) (xy 102.358703 -394.267186) (xy 102.370829 -394.212749)
			(xy 102.390752 -394.160658) (xy 102.418048 -394.112023) (xy 102.452134 -394.06788) (xy 102.492283 -394.029171)
			(xy 102.537641 -393.99672) (xy 102.587241 -393.971219) (xy 102.640025 -393.953212) (xy 102.694868 -393.943082)
			(xy 102.750602 -393.941045) (xy 102.806039 -393.947145) (xy 102.859996 -393.961251) (xy 102.911325 -393.983063)
			(xy 102.958931 -394.012117) (xy 103.001799 -394.047792) (xy 103.039016 -394.089329) (xy 103.069789 -394.135842)
			(xy 103.093461 -394.186339) (xy 103.109529 -394.239746) (xy 103.117649 -394.294922) (xy 103.118158 -394.322808)
			(xy 103.117649 -394.350694) (xy 103.116034 -394.36167) (xy 107.522262 -394.36167) (xy 107.526333 -394.306048)
			(xy 107.538459 -394.251611) (xy 107.558382 -394.19952) (xy 107.585678 -394.150885) (xy 107.619764 -394.106742)
			(xy 107.659913 -394.068033) (xy 107.705271 -394.035582) (xy 107.754871 -394.010081) (xy 107.807655 -393.992074)
			(xy 107.862498 -393.981944) (xy 107.918232 -393.979907) (xy 107.973669 -393.986007) (xy 108.027626 -394.000113)
			(xy 108.078955 -394.021925) (xy 108.126561 -394.050979) (xy 108.169429 -394.086654) (xy 108.206646 -394.128191)
			(xy 108.237419 -394.174704) (xy 108.261091 -394.225201) (xy 108.277159 -394.278608) (xy 108.285279 -394.333784)
			(xy 108.285788 -394.36167) (xy 108.285279 -394.389556) (xy 108.277159 -394.444732) (xy 108.261091 -394.498139)
			(xy 108.237419 -394.548636) (xy 108.206646 -394.595149) (xy 108.169429 -394.636686) (xy 108.126561 -394.672361)
			(xy 108.078955 -394.701415) (xy 108.027626 -394.723227) (xy 107.973669 -394.737333) (xy 107.918232 -394.743433)
			(xy 107.862498 -394.741396) (xy 107.807655 -394.731266) (xy 107.754871 -394.713259) (xy 107.705271 -394.687758)
			(xy 107.659913 -394.655307) (xy 107.619764 -394.616598) (xy 107.585678 -394.572455) (xy 107.558382 -394.52382)
			(xy 107.538459 -394.471729) (xy 107.526333 -394.417292) (xy 107.522262 -394.36167) (xy 103.116034 -394.36167)
			(xy 103.109529 -394.40587) (xy 103.093461 -394.459277) (xy 103.069789 -394.509774) (xy 103.039016 -394.556287)
			(xy 103.001799 -394.597824) (xy 102.958931 -394.633499) (xy 102.911325 -394.662553) (xy 102.859996 -394.684365)
			(xy 102.806039 -394.698471) (xy 102.750602 -394.704571) (xy 102.694868 -394.702534) (xy 102.640025 -394.692404)
			(xy 102.587241 -394.674397) (xy 102.537641 -394.648896) (xy 102.492283 -394.616445) (xy 102.452134 -394.577736)
			(xy 102.418048 -394.533593) (xy 102.390752 -394.484958) (xy 102.370829 -394.432867) (xy 102.358703 -394.37843)
			(xy 102.354632 -394.322808) (xy 95.745808 -394.322808) (xy 96.611948 -395.188948) (xy 106.252262 -395.188948)
			(xy 106.256333 -395.133326) (xy 106.268459 -395.078889) (xy 106.288382 -395.026798) (xy 106.315678 -394.978163)
			(xy 106.349764 -394.93402) (xy 106.389913 -394.895311) (xy 106.435271 -394.86286) (xy 106.484871 -394.837359)
			(xy 106.537655 -394.819352) (xy 106.592498 -394.809222) (xy 106.648232 -394.807185) (xy 106.703669 -394.813285)
			(xy 106.757626 -394.827391) (xy 106.808955 -394.849203) (xy 106.856561 -394.878257) (xy 106.899429 -394.913932)
			(xy 106.936646 -394.955469) (xy 106.967419 -395.001982) (xy 106.991091 -395.052479) (xy 107.007159 -395.105886)
			(xy 107.009664 -395.122908) (xy 112.371122 -395.122908) (xy 112.375193 -395.067286) (xy 112.387319 -395.012849)
			(xy 112.407242 -394.960758) (xy 112.434538 -394.912123) (xy 112.468624 -394.86798) (xy 112.508773 -394.829271)
			(xy 112.554131 -394.79682) (xy 112.603731 -394.771319) (xy 112.656515 -394.753312) (xy 112.711358 -394.743182)
			(xy 112.767092 -394.741145) (xy 112.822529 -394.747245) (xy 112.876486 -394.761351) (xy 112.927815 -394.783163)
			(xy 112.975421 -394.812217) (xy 113.018289 -394.847892) (xy 113.055506 -394.889429) (xy 113.086279 -394.935942)
			(xy 113.109951 -394.986439) (xy 113.126019 -395.039846) (xy 113.134139 -395.095022) (xy 113.134648 -395.122908)
			(xy 113.134139 -395.150794) (xy 113.126019 -395.20597) (xy 113.109951 -395.259377) (xy 113.086279 -395.309874)
			(xy 113.055506 -395.356387) (xy 113.018289 -395.397924) (xy 112.975421 -395.433599) (xy 112.927815 -395.462653)
			(xy 112.876486 -395.484465) (xy 112.822529 -395.498571) (xy 112.767092 -395.504671) (xy 112.711358 -395.502634)
			(xy 112.656515 -395.492504) (xy 112.603731 -395.474497) (xy 112.554131 -395.448996) (xy 112.508773 -395.416545)
			(xy 112.468624 -395.377836) (xy 112.434538 -395.333693) (xy 112.407242 -395.285058) (xy 112.387319 -395.232967)
			(xy 112.375193 -395.17853) (xy 112.371122 -395.122908) (xy 107.009664 -395.122908) (xy 107.015279 -395.161062)
			(xy 107.015788 -395.188948) (xy 107.015279 -395.216834) (xy 107.007159 -395.27201) (xy 106.991091 -395.325417)
			(xy 106.967419 -395.375914) (xy 106.936646 -395.422427) (xy 106.899429 -395.463964) (xy 106.856561 -395.499639)
			(xy 106.808955 -395.528693) (xy 106.757626 -395.550505) (xy 106.703669 -395.564611) (xy 106.648232 -395.570711)
			(xy 106.592498 -395.568674) (xy 106.537655 -395.558544) (xy 106.484871 -395.540537) (xy 106.435271 -395.515036)
			(xy 106.389913 -395.482585) (xy 106.349764 -395.443876) (xy 106.315678 -395.399733) (xy 106.288382 -395.351098)
			(xy 106.268459 -395.299007) (xy 106.256333 -395.24457) (xy 106.252262 -395.188948) (xy 96.611948 -395.188948)
			(xy 97.236788 -395.813788) (xy 109.598966 -395.813788) (xy 109.603037 -395.758166) (xy 109.615163 -395.703729)
			(xy 109.635086 -395.651638) (xy 109.662382 -395.603003) (xy 109.696468 -395.55886) (xy 109.736617 -395.520151)
			(xy 109.781975 -395.4877) (xy 109.831575 -395.462199) (xy 109.884359 -395.444192) (xy 109.939202 -395.434062)
			(xy 109.994936 -395.432025) (xy 110.050373 -395.438125) (xy 110.10433 -395.452231) (xy 110.155659 -395.474043)
			(xy 110.203265 -395.503097) (xy 110.246133 -395.538772) (xy 110.28335 -395.580309) (xy 110.314123 -395.626822)
			(xy 110.337795 -395.677319) (xy 110.353863 -395.730726) (xy 110.361983 -395.785902) (xy 110.362492 -395.813788)
			(xy 110.361983 -395.841674) (xy 110.353863 -395.89685) (xy 110.337795 -395.950257) (xy 110.314123 -396.000754)
			(xy 110.28335 -396.047267) (xy 110.246133 -396.088804) (xy 110.203265 -396.124479) (xy 110.155659 -396.153533)
			(xy 110.10433 -396.175345) (xy 110.050373 -396.189451) (xy 109.994936 -396.195551) (xy 109.939202 -396.193514)
			(xy 109.884359 -396.183384) (xy 109.831575 -396.165377) (xy 109.781975 -396.139876) (xy 109.736617 -396.107425)
			(xy 109.696468 -396.068716) (xy 109.662382 -396.024573) (xy 109.635086 -395.975938) (xy 109.615163 -395.923847)
			(xy 109.603037 -395.86941) (xy 109.598966 -395.813788) (xy 97.236788 -395.813788) (xy 97.50806 -396.08506)
			(xy 97.50806 -396.44574) (xy 100.442266 -396.44574) (xy 100.446337 -396.390118) (xy 100.458463 -396.335681)
			(xy 100.478386 -396.28359) (xy 100.505682 -396.234955) (xy 100.539768 -396.190812) (xy 100.579917 -396.152103)
			(xy 100.625275 -396.119652) (xy 100.674875 -396.094151) (xy 100.727659 -396.076144) (xy 100.782502 -396.066014)
			(xy 100.838236 -396.063977) (xy 100.893673 -396.070077) (xy 100.94763 -396.084183) (xy 100.998959 -396.105995)
			(xy 101.046565 -396.135049) (xy 101.089433 -396.170724) (xy 101.12665 -396.212261) (xy 101.157423 -396.258774)
			(xy 101.181095 -396.309271) (xy 101.197163 -396.362678) (xy 101.205283 -396.417854) (xy 101.205792 -396.44574)
			(xy 101.205283 -396.473626) (xy 101.197163 -396.528802) (xy 101.181095 -396.582209) (xy 101.157423 -396.632706)
			(xy 101.12665 -396.679219) (xy 101.089433 -396.720756) (xy 101.046565 -396.756431) (xy 100.998959 -396.785485)
			(xy 100.981373 -396.792958) (xy 113.430048 -396.792958) (xy 113.434119 -396.737336) (xy 113.446245 -396.682899)
			(xy 113.466168 -396.630808) (xy 113.493464 -396.582173) (xy 113.52755 -396.53803) (xy 113.567699 -396.499321)
			(xy 113.613057 -396.46687) (xy 113.662657 -396.441369) (xy 113.715441 -396.423362) (xy 113.770284 -396.413232)
			(xy 113.826018 -396.411195) (xy 113.881455 -396.417295) (xy 113.935412 -396.431401) (xy 113.986741 -396.453213)
			(xy 114.034347 -396.482267) (xy 114.077215 -396.517942) (xy 114.114432 -396.559479) (xy 114.145205 -396.605992)
			(xy 114.168877 -396.656489) (xy 114.184945 -396.709896) (xy 114.193065 -396.765072) (xy 114.193574 -396.792958)
			(xy 114.193065 -396.820844) (xy 114.184945 -396.87602) (xy 114.168877 -396.929427) (xy 114.145205 -396.979924)
			(xy 114.114432 -397.026437) (xy 114.077215 -397.067974) (xy 114.034347 -397.103649) (xy 113.986741 -397.132703)
			(xy 113.935412 -397.154515) (xy 113.881455 -397.168621) (xy 113.826018 -397.174721) (xy 113.770284 -397.172684)
			(xy 113.715441 -397.162554) (xy 113.662657 -397.144547) (xy 113.613057 -397.119046) (xy 113.567699 -397.086595)
			(xy 113.52755 -397.047886) (xy 113.493464 -397.003743) (xy 113.466168 -396.955108) (xy 113.446245 -396.903017)
			(xy 113.434119 -396.84858) (xy 113.430048 -396.792958) (xy 100.981373 -396.792958) (xy 100.94763 -396.807297)
			(xy 100.893673 -396.821403) (xy 100.838236 -396.827503) (xy 100.782502 -396.825466) (xy 100.727659 -396.815336)
			(xy 100.674875 -396.797329) (xy 100.625275 -396.771828) (xy 100.579917 -396.739377) (xy 100.539768 -396.700668)
			(xy 100.505682 -396.656525) (xy 100.478386 -396.60789) (xy 100.458463 -396.555799) (xy 100.446337 -396.501362)
			(xy 100.442266 -396.44574) (xy 97.50806 -396.44574) (xy 97.50806 -397.474948) (xy 114.558062 -397.474948)
			(xy 114.562133 -397.419326) (xy 114.574259 -397.364889) (xy 114.594182 -397.312798) (xy 114.621478 -397.264163)
			(xy 114.655564 -397.22002) (xy 114.695713 -397.181311) (xy 114.741071 -397.14886) (xy 114.790671 -397.123359)
			(xy 114.843455 -397.105352) (xy 114.898298 -397.095222) (xy 114.954032 -397.093185) (xy 115.009469 -397.099285)
			(xy 115.063426 -397.113391) (xy 115.114755 -397.135203) (xy 115.162361 -397.164257) (xy 115.205229 -397.199932)
			(xy 115.242446 -397.241469) (xy 115.273219 -397.287982) (xy 115.296891 -397.338479) (xy 115.312959 -397.391886)
			(xy 115.321079 -397.447062) (xy 115.321588 -397.474948) (xy 115.321079 -397.502834) (xy 115.312959 -397.55801)
			(xy 115.296891 -397.611417) (xy 115.273219 -397.661914) (xy 115.242446 -397.708427) (xy 115.205229 -397.749964)
			(xy 115.162361 -397.785639) (xy 115.114755 -397.814693) (xy 115.063426 -397.836505) (xy 115.009469 -397.850611)
			(xy 114.954032 -397.856711) (xy 114.898298 -397.854674) (xy 114.843455 -397.844544) (xy 114.790671 -397.826537)
			(xy 114.741071 -397.801036) (xy 114.695713 -397.768585) (xy 114.655564 -397.729876) (xy 114.621478 -397.685733)
			(xy 114.594182 -397.637098) (xy 114.574259 -397.585007) (xy 114.562133 -397.53057) (xy 114.558062 -397.474948)
			(xy 97.50806 -397.474948) (xy 97.50806 -397.93418) (xy 102.487982 -397.93418) (xy 102.492053 -397.878558)
			(xy 102.504179 -397.824121) (xy 102.524102 -397.77203) (xy 102.551398 -397.723395) (xy 102.585484 -397.679252)
			(xy 102.625633 -397.640543) (xy 102.670991 -397.608092) (xy 102.720591 -397.582591) (xy 102.773375 -397.564584)
			(xy 102.828218 -397.554454) (xy 102.883952 -397.552417) (xy 102.939389 -397.558517) (xy 102.993346 -397.572623)
			(xy 103.044675 -397.594435) (xy 103.092281 -397.623489) (xy 103.135149 -397.659164) (xy 103.172366 -397.700701)
			(xy 103.203139 -397.747214) (xy 103.226811 -397.797711) (xy 103.242879 -397.851118) (xy 103.250999 -397.906294)
			(xy 103.251508 -397.93418) (xy 103.250999 -397.962066) (xy 103.246804 -397.990568) (xy 103.539542 -397.990568)
			(xy 103.543613 -397.934946) (xy 103.555739 -397.880509) (xy 103.575662 -397.828418) (xy 103.602958 -397.779783)
			(xy 103.637044 -397.73564) (xy 103.677193 -397.696931) (xy 103.722551 -397.66448) (xy 103.772151 -397.638979)
			(xy 103.824935 -397.620972) (xy 103.879778 -397.610842) (xy 103.935512 -397.608805) (xy 103.990949 -397.614905)
			(xy 104.044906 -397.629011) (xy 104.096235 -397.650823) (xy 104.143841 -397.679877) (xy 104.186709 -397.715552)
			(xy 104.223926 -397.757089) (xy 104.254699 -397.803602) (xy 104.278371 -397.854099) (xy 104.294439 -397.907506)
			(xy 104.302559 -397.962682) (xy 104.303068 -397.990568) (xy 104.302559 -398.018454) (xy 104.294439 -398.07363)
			(xy 104.278371 -398.127037) (xy 104.262568 -398.160748) (xy 109.963202 -398.160748) (xy 109.967273 -398.105126)
			(xy 109.979399 -398.050689) (xy 109.999322 -397.998598) (xy 110.026618 -397.949963) (xy 110.060704 -397.90582)
			(xy 110.100853 -397.867111) (xy 110.146211 -397.83466) (xy 110.195811 -397.809159) (xy 110.248595 -397.791152)
			(xy 110.303438 -397.781022) (xy 110.359172 -397.778985) (xy 110.414609 -397.785085) (xy 110.468566 -397.799191)
			(xy 110.519895 -397.821003) (xy 110.567501 -397.850057) (xy 110.610369 -397.885732) (xy 110.647586 -397.927269)
			(xy 110.678359 -397.973782) (xy 110.702031 -398.024279) (xy 110.718099 -398.077686) (xy 110.726219 -398.132862)
			(xy 110.726728 -398.160748) (xy 110.726219 -398.188634) (xy 110.718099 -398.24381) (xy 110.702031 -398.297217)
			(xy 110.678359 -398.347714) (xy 110.647586 -398.394227) (xy 110.610369 -398.435764) (xy 110.567501 -398.471439)
			(xy 110.519895 -398.500493) (xy 110.468566 -398.522305) (xy 110.414609 -398.536411) (xy 110.359172 -398.542511)
			(xy 110.303438 -398.540474) (xy 110.248595 -398.530344) (xy 110.195811 -398.512337) (xy 110.146211 -398.486836)
			(xy 110.100853 -398.454385) (xy 110.060704 -398.415676) (xy 110.026618 -398.371533) (xy 109.999322 -398.322898)
			(xy 109.979399 -398.270807) (xy 109.967273 -398.21637) (xy 109.963202 -398.160748) (xy 104.262568 -398.160748)
			(xy 104.254699 -398.177534) (xy 104.223926 -398.224047) (xy 104.186709 -398.265584) (xy 104.143841 -398.301259)
			(xy 104.096235 -398.330313) (xy 104.044906 -398.352125) (xy 103.990949 -398.366231) (xy 103.935512 -398.372331)
			(xy 103.879778 -398.370294) (xy 103.824935 -398.360164) (xy 103.772151 -398.342157) (xy 103.722551 -398.316656)
			(xy 103.677193 -398.284205) (xy 103.637044 -398.245496) (xy 103.602958 -398.201353) (xy 103.575662 -398.152718)
			(xy 103.555739 -398.100627) (xy 103.543613 -398.04619) (xy 103.539542 -397.990568) (xy 103.246804 -397.990568)
			(xy 103.242879 -398.017242) (xy 103.226811 -398.070649) (xy 103.203139 -398.121146) (xy 103.172366 -398.167659)
			(xy 103.135149 -398.209196) (xy 103.092281 -398.244871) (xy 103.044675 -398.273925) (xy 102.993346 -398.295737)
			(xy 102.939389 -398.309843) (xy 102.883952 -398.315943) (xy 102.828218 -398.313906) (xy 102.773375 -398.303776)
			(xy 102.720591 -398.285769) (xy 102.670991 -398.260268) (xy 102.625633 -398.227817) (xy 102.585484 -398.189108)
			(xy 102.551398 -398.144965) (xy 102.524102 -398.09633) (xy 102.504179 -398.044239) (xy 102.492053 -397.989802)
			(xy 102.487982 -397.93418) (xy 97.50806 -397.93418) (xy 97.50806 -398.884648) (xy 113.923062 -398.884648)
			(xy 113.927133 -398.829026) (xy 113.939259 -398.774589) (xy 113.959182 -398.722498) (xy 113.986478 -398.673863)
			(xy 114.020564 -398.62972) (xy 114.060713 -398.591011) (xy 114.106071 -398.55856) (xy 114.155671 -398.533059)
			(xy 114.208455 -398.515052) (xy 114.263298 -398.504922) (xy 114.319032 -398.502885) (xy 114.374469 -398.508985)
			(xy 114.428426 -398.523091) (xy 114.479755 -398.544903) (xy 114.527361 -398.573957) (xy 114.570229 -398.609632)
			(xy 114.607446 -398.651169) (xy 114.638219 -398.697682) (xy 114.661891 -398.748179) (xy 114.677959 -398.801586)
			(xy 114.686079 -398.856762) (xy 114.686588 -398.884648) (xy 114.686079 -398.912534) (xy 114.677959 -398.96771)
			(xy 114.661891 -399.021117) (xy 114.638219 -399.071614) (xy 114.607446 -399.118127) (xy 114.570229 -399.159664)
			(xy 114.527361 -399.195339) (xy 114.479755 -399.224393) (xy 114.428426 -399.246205) (xy 114.374469 -399.260311)
			(xy 114.319032 -399.266411) (xy 114.263298 -399.264374) (xy 114.208455 -399.254244) (xy 114.155671 -399.236237)
			(xy 114.106071 -399.210736) (xy 114.060713 -399.178285) (xy 114.020564 -399.139576) (xy 113.986478 -399.095433)
			(xy 113.959182 -399.046798) (xy 113.939259 -398.994707) (xy 113.927133 -398.94027) (xy 113.923062 -398.884648)
			(xy 97.50806 -398.884648) (xy 97.50806 -400.536742) (xy 111.38374 -400.536742) (xy 111.383742 -400.482233)
			(xy 111.391501 -400.428279) (xy 111.40686 -400.375979) (xy 111.429506 -400.326396) (xy 111.458978 -400.280542)
			(xy 111.494676 -400.239349) (xy 111.535873 -400.203655) (xy 111.58173 -400.174188) (xy 111.631315 -400.151547)
			(xy 111.683617 -400.136193) (xy 111.737571 -400.128439) (xy 111.764826 -400.127978) (xy 111.775261 -400.128055)
			(xy 111.796101 -400.129197) (xy 111.806482 -400.130264) (xy 111.820863 -400.131284) (xy 111.849232 -400.126232)
			(xy 111.875065 -400.113465) (xy 111.89631 -400.093997) (xy 111.911279 -400.069375) (xy 111.918784 -400.041555)
			(xy 111.919004 -400.02714) (xy 111.919004 -400.019266) (xy 111.919515 -399.992018) (xy 111.927275 -399.938077)
			(xy 111.942632 -399.88579) (xy 111.965275 -399.83622) (xy 111.994741 -399.790377) (xy 112.030431 -399.749194)
			(xy 112.071619 -399.71351) (xy 112.117466 -399.68405) (xy 112.167039 -399.661414) (xy 112.219329 -399.646064)
			(xy 112.273271 -399.638311) (xy 112.327767 -399.638313) (xy 112.381708 -399.646072) (xy 112.433996 -399.661427)
			(xy 112.483567 -399.684067) (xy 112.529411 -399.713532) (xy 112.570595 -399.749221) (xy 112.606281 -399.790407)
			(xy 112.635743 -399.836253) (xy 112.658381 -399.885825) (xy 112.673733 -399.938114) (xy 112.681488 -399.992055)
			(xy 112.681488 -400.014948) (xy 113.597942 -400.014948) (xy 113.602013 -399.959326) (xy 113.614139 -399.904889)
			(xy 113.634062 -399.852798) (xy 113.661358 -399.804163) (xy 113.695444 -399.76002) (xy 113.735593 -399.721311)
			(xy 113.780951 -399.68886) (xy 113.830551 -399.663359) (xy 113.883335 -399.645352) (xy 113.938178 -399.635222)
			(xy 113.993912 -399.633185) (xy 114.049349 -399.639285) (xy 114.103306 -399.653391) (xy 114.154635 -399.675203)
			(xy 114.202241 -399.704257) (xy 114.245109 -399.739932) (xy 114.282326 -399.781469) (xy 114.313099 -399.827982)
			(xy 114.336771 -399.878479) (xy 114.352839 -399.931886) (xy 114.360959 -399.987062) (xy 114.361468 -400.014948)
			(xy 114.360959 -400.042834) (xy 114.352839 -400.09801) (xy 114.336771 -400.151417) (xy 114.313099 -400.201914)
			(xy 114.282326 -400.248427) (xy 114.245109 -400.289964) (xy 114.202241 -400.325639) (xy 114.154635 -400.354693)
			(xy 114.103306 -400.376505) (xy 114.049349 -400.390611) (xy 113.993912 -400.396711) (xy 113.938178 -400.394674)
			(xy 113.883335 -400.384544) (xy 113.830551 -400.366537) (xy 113.780951 -400.341036) (xy 113.735593 -400.308585)
			(xy 113.695444 -400.269876) (xy 113.661358 -400.225733) (xy 113.634062 -400.177098) (xy 113.614139 -400.125007)
			(xy 113.602013 -400.07057) (xy 113.597942 -400.014948) (xy 112.681488 -400.014948) (xy 112.681488 -400.046551)
			(xy 112.673732 -400.100493) (xy 112.658378 -400.152782) (xy 112.63574 -400.202353) (xy 112.606277 -400.248198)
			(xy 112.57059 -400.289384) (xy 112.529405 -400.325072) (xy 112.483561 -400.354536) (xy 112.43399 -400.377175)
			(xy 112.381701 -400.39253) (xy 112.32776 -400.400287) (xy 112.300512 -400.400774) (xy 112.290076 -400.400703)
			(xy 112.269237 -400.399557) (xy 112.258856 -400.398488) (xy 112.244474 -400.397452) (xy 112.216098 -400.402497)
			(xy 112.190259 -400.415264) (xy 112.169011 -400.434736) (xy 112.154043 -400.459366) (xy 112.146547 -400.487194)
			(xy 112.146334 -400.501612) (xy 112.146334 -400.509486) (xy 112.14586 -400.536741) (xy 112.138104 -400.590695)
			(xy 112.122749 -400.642996) (xy 112.100107 -400.69258) (xy 112.070638 -400.738437) (xy 112.034943 -400.779633)
			(xy 111.993748 -400.815329) (xy 111.947893 -400.8448) (xy 111.89831 -400.867444) (xy 111.846009 -400.882801)
			(xy 111.792055 -400.890559) (xy 111.737546 -400.890559) (xy 111.683592 -400.882802) (xy 111.631291 -400.867444)
			(xy 111.581708 -400.8448) (xy 111.535853 -400.81533) (xy 111.494658 -400.779634) (xy 111.458963 -400.738438)
			(xy 111.429494 -400.692581) (xy 111.406851 -400.642998) (xy 111.391496 -400.590696) (xy 111.38374 -400.536742)
			(xy 97.50806 -400.536742) (xy 97.50806 -401.195286) (xy 109.688882 -401.195286) (xy 109.692953 -401.139664)
			(xy 109.705079 -401.085227) (xy 109.725002 -401.033136) (xy 109.752298 -400.984501) (xy 109.786384 -400.940358)
			(xy 109.826533 -400.901649) (xy 109.871891 -400.869198) (xy 109.921491 -400.843697) (xy 109.974275 -400.82569)
			(xy 110.029118 -400.81556) (xy 110.084852 -400.813523) (xy 110.140289 -400.819623) (xy 110.194246 -400.833729)
			(xy 110.245575 -400.855541) (xy 110.293181 -400.884595) (xy 110.336049 -400.92027) (xy 110.373266 -400.961807)
			(xy 110.404039 -401.00832) (xy 110.427711 -401.058817) (xy 110.443779 -401.112224) (xy 110.451899 -401.1674)
			(xy 110.452408 -401.195286) (xy 110.451899 -401.223172) (xy 110.443779 -401.278348) (xy 110.427711 -401.331755)
			(xy 110.404039 -401.382252) (xy 110.37599 -401.424648) (xy 115.447062 -401.424648) (xy 115.451133 -401.369026)
			(xy 115.463259 -401.314589) (xy 115.483182 -401.262498) (xy 115.510478 -401.213863) (xy 115.544564 -401.16972)
			(xy 115.584713 -401.131011) (xy 115.630071 -401.09856) (xy 115.679671 -401.073059) (xy 115.732455 -401.055052)
			(xy 115.787298 -401.044922) (xy 115.843032 -401.042885) (xy 115.898469 -401.048985) (xy 115.952426 -401.063091)
			(xy 116.003755 -401.084903) (xy 116.051361 -401.113957) (xy 116.094229 -401.149632) (xy 116.131446 -401.191169)
			(xy 116.162219 -401.237682) (xy 116.185891 -401.288179) (xy 116.201959 -401.341586) (xy 116.210079 -401.396762)
			(xy 116.210588 -401.424648) (xy 116.210079 -401.452534) (xy 116.201959 -401.50771) (xy 116.185891 -401.561117)
			(xy 116.162219 -401.611614) (xy 116.131446 -401.658127) (xy 116.094229 -401.699664) (xy 116.051361 -401.735339)
			(xy 116.003755 -401.764393) (xy 115.952426 -401.786205) (xy 115.898469 -401.800311) (xy 115.843032 -401.806411)
			(xy 115.787298 -401.804374) (xy 115.732455 -401.794244) (xy 115.679671 -401.776237) (xy 115.630071 -401.750736)
			(xy 115.584713 -401.718285) (xy 115.544564 -401.679576) (xy 115.510478 -401.635433) (xy 115.483182 -401.586798)
			(xy 115.463259 -401.534707) (xy 115.451133 -401.48027) (xy 115.447062 -401.424648) (xy 110.37599 -401.424648)
			(xy 110.373266 -401.428765) (xy 110.336049 -401.470302) (xy 110.293181 -401.505977) (xy 110.245575 -401.535031)
			(xy 110.194246 -401.556843) (xy 110.140289 -401.570949) (xy 110.084852 -401.577049) (xy 110.029118 -401.575012)
			(xy 109.974275 -401.564882) (xy 109.921491 -401.546875) (xy 109.871891 -401.521374) (xy 109.826533 -401.488923)
			(xy 109.786384 -401.450214) (xy 109.752298 -401.406071) (xy 109.725002 -401.357436) (xy 109.705079 -401.305345)
			(xy 109.692953 -401.250908) (xy 109.688882 -401.195286) (xy 97.50806 -401.195286) (xy 97.50806 -401.995386)
			(xy 97.92208 -401.995386) (xy 97.922563 -401.967065) (xy 97.930276 -401.910949) (xy 97.945558 -401.856407)
			(xy 97.968125 -401.804453) (xy 97.997555 -401.756056) (xy 98.033302 -401.712118) (xy 98.074699 -401.673456)
			(xy 98.120974 -401.640791) (xy 98.171267 -401.614732) (xy 98.224639 -401.595763) (xy 98.280097 -401.584239)
			(xy 98.336608 -401.580374) (xy 98.393119 -401.584239) (xy 98.448577 -401.595763) (xy 98.501949 -401.614732)
			(xy 98.552242 -401.640791) (xy 98.598517 -401.673456) (xy 98.639914 -401.712118) (xy 98.675661 -401.756056)
			(xy 98.705091 -401.804453) (xy 98.727658 -401.856407) (xy 98.74294 -401.910949) (xy 98.750653 -401.967065)
			(xy 98.751136 -401.995386) (xy 98.750513 -402.026144) (xy 98.741336 -402.086974) (xy 98.732848 -402.116544)
			(xy 98.729429 -402.129668) (xy 98.728683 -402.15676) (xy 98.735092 -402.183094) (xy 98.748205 -402.206813)
			(xy 98.767097 -402.226246) (xy 98.790437 -402.240023) (xy 98.816579 -402.247173) (xy 98.83013 -402.247608)
			(xy 99.10191 -402.247608) (xy 99.11547 -402.247142) (xy 99.141637 -402.240022) (xy 99.165004 -402.22626)
			(xy 99.183921 -402.206829) (xy 99.197051 -402.183101) (xy 99.203467 -402.156752) (xy 99.202716 -402.129644)
			(xy 99.199192 -402.116544) (xy 99.190677 -402.08698) (xy 99.181498 -402.026146) (xy 99.180904 -401.995386)
			(xy 99.181387 -401.967065) (xy 99.1891 -401.910949) (xy 99.204382 -401.856407) (xy 99.226949 -401.804453)
			(xy 99.256379 -401.756056) (xy 99.292126 -401.712118) (xy 99.333523 -401.673456) (xy 99.379798 -401.640791)
			(xy 99.430091 -401.614732) (xy 99.483463 -401.595763) (xy 99.538921 -401.584239) (xy 99.595432 -401.580374)
			(xy 99.651943 -401.584239) (xy 99.707401 -401.595763) (xy 99.760773 -401.614732) (xy 99.811066 -401.640791)
			(xy 99.857341 -401.673456) (xy 99.898738 -401.712118) (xy 99.934485 -401.756056) (xy 99.963915 -401.804453)
			(xy 99.986482 -401.856407) (xy 100.001764 -401.910949) (xy 100.009477 -401.967065) (xy 100.00996 -401.995386)
			(xy 100.009466 -402.022999) (xy 100.002134 -402.077737) (xy 99.987599 -402.131016) (xy 99.966118 -402.181894)
			(xy 99.938072 -402.229469) (xy 99.903956 -402.272898) (xy 99.864376 -402.311412) (xy 99.820032 -402.34433)
			(xy 99.796092 -402.358098) (xy 99.783392 -402.365703) (xy 99.762668 -402.386817) (xy 99.74887 -402.412988)
			(xy 99.743157 -402.442017) (xy 99.746011 -402.471465) (xy 99.751134 -402.485352) (xy 99.760073 -402.508296)
			(xy 99.772617 -402.555914) (xy 99.778943 -402.604749) (xy 99.779328 -402.62937) (xy 99.778848 -402.656629)
			(xy 99.771097 -402.710592) (xy 99.755746 -402.762903) (xy 99.733109 -402.812499) (xy 99.703647 -402.858369)
			(xy 99.667959 -402.899582) (xy 99.649454 -402.915628) (xy 108.355128 -402.915628) (xy 108.359199 -402.860006)
			(xy 108.371325 -402.805569) (xy 108.391248 -402.753478) (xy 108.418544 -402.704843) (xy 108.45263 -402.6607)
			(xy 108.492779 -402.621991) (xy 108.538137 -402.58954) (xy 108.587737 -402.564039) (xy 108.640521 -402.546032)
			(xy 108.695364 -402.535902) (xy 108.751098 -402.533865) (xy 108.806535 -402.539965) (xy 108.860492 -402.554071)
			(xy 108.911821 -402.575883) (xy 108.959427 -402.604937) (xy 109.002295 -402.640612) (xy 109.039512 -402.682149)
			(xy 109.070285 -402.728662) (xy 109.093957 -402.779159) (xy 109.110025 -402.832566) (xy 109.118145 -402.887742)
			(xy 109.118654 -402.915628) (xy 109.118145 -402.943514) (xy 109.110025 -402.99869) (xy 109.093957 -403.052097)
			(xy 109.070285 -403.102594) (xy 109.039512 -403.149107) (xy 109.002295 -403.190644) (xy 108.959427 -403.226319)
			(xy 108.911821 -403.255373) (xy 108.860492 -403.277185) (xy 108.806535 -403.291291) (xy 108.751098 -403.297391)
			(xy 108.695364 -403.295354) (xy 108.640521 -403.285224) (xy 108.587737 -403.267217) (xy 108.538137 -403.241716)
			(xy 108.492779 -403.209265) (xy 108.45263 -403.170556) (xy 108.418544 -403.126413) (xy 108.391248 -403.077778)
			(xy 108.371325 -403.025687) (xy 108.359199 -402.97125) (xy 108.355128 -402.915628) (xy 99.649454 -402.915628)
			(xy 99.62677 -402.935297) (xy 99.580919 -402.964789) (xy 99.531338 -402.987459) (xy 99.479036 -403.002843)
			(xy 99.425078 -403.010631) (xy 99.39782 -403.011132) (xy 98.53422 -403.011132) (xy 98.506957 -403.010625)
			(xy 98.452987 -403.002865) (xy 98.400671 -402.9875) (xy 98.351075 -402.964843) (xy 98.305211 -402.935356)
			(xy 98.264012 -402.899639) (xy 98.228318 -402.858421) (xy 98.198856 -402.81254) (xy 98.176226 -402.762932)
			(xy 98.16089 -402.710608) (xy 98.15316 -402.656633) (xy 98.152712 -402.62937) (xy 98.153093 -402.604748)
			(xy 98.159408 -402.555912) (xy 98.171968 -402.508297) (xy 98.180906 -402.485352) (xy 98.186034 -402.471466)
			(xy 98.188886 -402.442015) (xy 98.183175 -402.412983) (xy 98.16938 -402.386807) (xy 98.148658 -402.365686)
			(xy 98.135948 -402.358098) (xy 98.111995 -402.344348) (xy 98.067646 -402.311431) (xy 98.02806 -402.272915)
			(xy 97.99394 -402.229485) (xy 97.965889 -402.181907) (xy 97.944405 -402.131027) (xy 97.929868 -402.077743)
			(xy 97.922535 -402.023001) (xy 97.92208 -401.995386) (xy 97.50806 -401.995386) (xy 97.50806 -404.678642)
			(xy 97.508556 -404.693358) (xy 97.516946 -404.72157) (xy 97.533021 -404.746226) (xy 97.55545 -404.765285)
			(xy 97.582377 -404.777171) (xy 97.611573 -404.780899) (xy 97.62617 -404.778972) (xy 97.641617 -404.776592)
			(xy 97.672771 -404.774046) (xy 97.6884 -404.773892) (xy 97.715651 -404.774378) (xy 97.769599 -404.782134)
			(xy 97.821894 -404.797489) (xy 97.871471 -404.820131) (xy 97.917321 -404.849597) (xy 97.958512 -404.885288)
			(xy 97.994203 -404.926479) (xy 98.023669 -404.972329) (xy 98.046311 -405.021906) (xy 98.061666 -405.074201)
			(xy 98.069422 -405.128149) (xy 98.069422 -405.182651) (xy 98.06275 -405.22906) (xy 102.242112 -405.22906)
			(xy 102.242112 -404.36546) (xy 102.242541 -404.338207) (xy 102.250303 -404.284256) (xy 102.265664 -404.231959)
			(xy 102.288312 -404.18238) (xy 102.317784 -404.136529) (xy 102.353481 -404.095339) (xy 102.394677 -404.059648)
			(xy 102.440533 -404.030183) (xy 102.490115 -404.007543) (xy 102.542415 -403.99219) (xy 102.596367 -403.984436)
			(xy 102.62362 -403.983952) (xy 102.652606 -403.984479) (xy 102.709912 -403.993246) (xy 102.765239 -404.010561)
			(xy 102.791514 -404.022814) (xy 102.805618 -404.029124) (xy 102.836145 -404.033807) (xy 102.866676 -404.029158)
			(xy 102.894426 -404.0156) (xy 102.916858 -403.994374) (xy 102.924864 -403.981158) (xy 102.939464 -403.956226)
			(xy 102.975013 -403.910682) (xy 103.017022 -403.871018) (xy 103.06453 -403.838141) (xy 103.116453 -403.812802)
			(xy 103.171602 -403.795581) (xy 103.228716 -403.786872) (xy 103.257604 -403.78634) (xy 103.284858 -403.78673)
			(xy 103.338813 -403.794488) (xy 103.391113 -403.809846) (xy 103.440696 -403.83249) (xy 103.486552 -403.86196)
			(xy 103.527747 -403.897656) (xy 103.563443 -403.938851) (xy 103.592912 -403.984707) (xy 103.615556 -404.03429)
			(xy 103.630913 -404.086591) (xy 103.63867 -404.140546) (xy 103.63867 -404.195054) (xy 103.630913 -404.249009)
			(xy 103.615556 -404.30131) (xy 103.592912 -404.350893) (xy 103.563443 -404.396749) (xy 103.527747 -404.437944)
			(xy 103.486552 -404.47364) (xy 103.440696 -404.50311) (xy 103.391113 -404.525754) (xy 103.338813 -404.541112)
			(xy 103.284858 -404.54887) (xy 103.257604 -404.549356) (xy 103.227298 -404.548793) (xy 103.167449 -404.539218)
			(xy 103.138478 -404.530306) (xy 103.125291 -404.526458) (xy 103.097865 -404.525134) (xy 103.071078 -404.53117)
			(xy 103.046871 -404.544129) (xy 103.026995 -404.563073) (xy 103.012889 -404.586631) (xy 103.005575 -404.613097)
			(xy 103.005128 -404.626826) (xy 103.005128 -404.967694) (xy 103.005539 -404.981426) (xy 103.012859 -405.007898)
			(xy 103.026971 -405.03146) (xy 103.046853 -405.050407) (xy 103.071068 -405.063368) (xy 103.097861 -405.069405)
			(xy 103.125294 -405.068081) (xy 103.138478 -405.064214) (xy 103.167454 -405.055324) (xy 103.227301 -405.04575)
			(xy 103.257604 -405.045164) (xy 103.284853 -405.045706) (xy 103.338796 -405.053463) (xy 103.391087 -405.068817)
			(xy 103.44066 -405.091457) (xy 103.486506 -405.120921) (xy 103.527693 -405.15661) (xy 103.563381 -405.197797)
			(xy 103.592845 -405.243644) (xy 103.615484 -405.293217) (xy 103.630838 -405.345508) (xy 103.638594 -405.399451)
			(xy 103.638594 -405.453949) (xy 103.630838 -405.507892) (xy 103.615484 -405.560183) (xy 103.592845 -405.609756)
			(xy 103.563381 -405.655603) (xy 103.527693 -405.69679) (xy 103.486506 -405.732479) (xy 103.44066 -405.761943)
			(xy 103.391087 -405.784583) (xy 103.338796 -405.799937) (xy 103.284853 -405.807694) (xy 103.257604 -405.80818)
			(xy 103.228717 -405.807606) (xy 103.171603 -405.798909) (xy 103.116453 -405.781698) (xy 103.06453 -405.756367)
			(xy 103.017021 -405.723495) (xy 102.975012 -405.683835) (xy 102.939465 -405.638292) (xy 102.924864 -405.613362)
			(xy 102.916851 -405.600151) (xy 102.894422 -405.578922) (xy 102.866675 -405.565363) (xy 102.836144 -405.560713)
			(xy 102.805618 -405.565397) (xy 102.791514 -405.571706) (xy 102.76525 -405.583987) (xy 102.709924 -405.601316)
			(xy 102.652609 -405.610053) (xy 102.62362 -405.610568) (xy 102.596366 -405.610126) (xy 102.542412 -405.602371)
			(xy 102.490111 -405.587015) (xy 102.440529 -405.564372) (xy 102.394673 -405.534902) (xy 102.35348 -405.499206)
			(xy 102.317786 -405.45801) (xy 102.288318 -405.412154) (xy 102.265678 -405.36257) (xy 102.250325 -405.310268)
			(xy 102.242573 -405.256314) (xy 102.242112 -405.22906) (xy 98.06275 -405.22906) (xy 98.061666 -405.236599)
			(xy 98.046311 -405.288894) (xy 98.023669 -405.338471) (xy 97.994203 -405.384321) (xy 97.958512 -405.425512)
			(xy 97.917321 -405.461203) (xy 97.871471 -405.490669) (xy 97.821894 -405.513311) (xy 97.769599 -405.528666)
			(xy 97.715651 -405.536422) (xy 97.6884 -405.536908) (xy 97.672771 -405.536761) (xy 97.641616 -405.534217)
			(xy 97.62617 -405.531828) (xy 97.611564 -405.529912) (xy 97.582351 -405.533596) (xy 97.555404 -405.545464)
			(xy 97.532963 -405.564527) (xy 97.516896 -405.589201) (xy 97.508537 -405.617435) (xy 97.50806 -405.632158)
			(xy 97.50806 -406.654) (xy 104.418382 -406.654) (xy 104.422453 -406.598378) (xy 104.434579 -406.543941)
			(xy 104.454502 -406.49185) (xy 104.481798 -406.443215) (xy 104.515884 -406.399072) (xy 104.556033 -406.360363)
			(xy 104.601391 -406.327912) (xy 104.650991 -406.302411) (xy 104.703775 -406.284404) (xy 104.758618 -406.274274)
			(xy 104.814352 -406.272237) (xy 104.869789 -406.278337) (xy 104.923746 -406.292443) (xy 104.975075 -406.314255)
			(xy 105.022681 -406.343309) (xy 105.065549 -406.378984) (xy 105.102766 -406.420521) (xy 105.133539 -406.467034)
			(xy 105.13855 -406.477724) (xy 106.01198 -406.477724) (xy 106.012463 -406.449403) (xy 106.020176 -406.393287)
			(xy 106.035458 -406.338745) (xy 106.058025 -406.286791) (xy 106.087455 -406.238394) (xy 106.123202 -406.194456)
			(xy 106.164599 -406.155794) (xy 106.210874 -406.123129) (xy 106.261167 -406.09707) (xy 106.314539 -406.078101)
			(xy 106.369997 -406.066577) (xy 106.426508 -406.062712) (xy 106.483019 -406.066577) (xy 106.538477 -406.078101)
			(xy 106.591849 -406.09707) (xy 106.642142 -406.123129) (xy 106.688417 -406.155794) (xy 106.729814 -406.194456)
			(xy 106.765561 -406.238394) (xy 106.794991 -406.286791) (xy 106.817558 -406.338745) (xy 106.83284 -406.393287)
			(xy 106.840553 -406.449403) (xy 106.841036 -406.477724) (xy 106.840421 -406.508482) (xy 106.831239 -406.569312)
			(xy 106.822748 -406.598882) (xy 106.819261 -406.61201) (xy 106.818478 -406.639148) (xy 106.82487 -406.665534)
			(xy 106.837984 -406.689306) (xy 106.856896 -406.708784) (xy 106.88027 -406.722595) (xy 106.906456 -406.729763)
			(xy 106.92003 -406.7302) (xy 107.19181 -406.7302) (xy 107.205395 -406.729733) (xy 107.231612 -406.722611)
			(xy 107.25502 -406.708823) (xy 107.273959 -406.689345) (xy 107.287085 -406.665559) (xy 107.293469 -406.639152)
			(xy 107.292656 -406.611997) (xy 107.289092 -406.598882) (xy 107.280585 -406.569316) (xy 107.271401 -406.508484)
			(xy 107.270804 -406.477724) (xy 107.271287 -406.449403) (xy 107.279 -406.393287) (xy 107.294282 -406.338745)
			(xy 107.316849 -406.286791) (xy 107.346279 -406.238394) (xy 107.382026 -406.194456) (xy 107.423423 -406.155794)
			(xy 107.469698 -406.123129) (xy 107.519991 -406.09707) (xy 107.573363 -406.078101) (xy 107.628821 -406.066577)
			(xy 107.685332 -406.062712) (xy 107.741843 -406.066577) (xy 107.797301 -406.078101) (xy 107.850673 -406.09707)
			(xy 107.900966 -406.123129) (xy 107.947241 -406.155794) (xy 107.988638 -406.194456) (xy 108.024385 -406.238394)
			(xy 108.053815 -406.286791) (xy 108.076382 -406.338745) (xy 108.091664 -406.393287) (xy 108.099377 -406.449403)
			(xy 108.09986 -406.477724) (xy 108.099396 -406.505338) (xy 108.09206 -406.560077) (xy 108.07752 -406.613357)
			(xy 108.056035 -406.664235) (xy 108.027984 -406.71181) (xy 107.993865 -406.755238) (xy 107.954281 -406.793752)
			(xy 107.909934 -406.826669) (xy 107.885992 -406.840436) (xy 107.873267 -406.848003) (xy 107.852542 -406.869127)
			(xy 107.838747 -406.895308) (xy 107.833041 -406.924347) (xy 107.835905 -406.953801) (xy 107.841034 -406.96769)
			(xy 107.849955 -406.990641) (xy 107.862506 -407.038256) (xy 107.866333 -407.067766) (xy 109.697264 -407.067766)
			(xy 109.701335 -407.012144) (xy 109.713461 -406.957707) (xy 109.733384 -406.905616) (xy 109.76068 -406.856981)
			(xy 109.794766 -406.812838) (xy 109.834915 -406.774129) (xy 109.880273 -406.741678) (xy 109.929873 -406.716177)
			(xy 109.982657 -406.69817) (xy 110.0375 -406.68804) (xy 110.093234 -406.686003) (xy 110.148671 -406.692103)
			(xy 110.202628 -406.706209) (xy 110.253957 -406.728021) (xy 110.301563 -406.757075) (xy 110.344431 -406.79275)
			(xy 110.381648 -406.834287) (xy 110.412421 -406.8808) (xy 110.436093 -406.931297) (xy 110.452161 -406.984704)
			(xy 110.460281 -407.03988) (xy 110.46079 -407.067766) (xy 110.460674 -407.074116) (xy 111.710214 -407.074116)
			(xy 111.714285 -407.018494) (xy 111.726411 -406.964057) (xy 111.746334 -406.911966) (xy 111.77363 -406.863331)
			(xy 111.807716 -406.819188) (xy 111.847865 -406.780479) (xy 111.893223 -406.748028) (xy 111.942823 -406.722527)
			(xy 111.995607 -406.70452) (xy 112.05045 -406.69439) (xy 112.106184 -406.692353) (xy 112.161621 -406.698453)
			(xy 112.215578 -406.712559) (xy 112.266907 -406.734371) (xy 112.314513 -406.763425) (xy 112.357381 -406.7991)
			(xy 112.394598 -406.840637) (xy 112.425371 -406.88715) (xy 112.449043 -406.937647) (xy 112.465111 -406.991054)
			(xy 112.473231 -407.04623) (xy 112.47374 -407.074116) (xy 112.473231 -407.102002) (xy 112.465111 -407.157178)
			(xy 112.449043 -407.210585) (xy 112.425371 -407.261082) (xy 112.394598 -407.307595) (xy 112.357381 -407.349132)
			(xy 112.314513 -407.384807) (xy 112.266907 -407.413861) (xy 112.215578 -407.435673) (xy 112.161621 -407.449779)
			(xy 112.106184 -407.455879) (xy 112.05045 -407.453842) (xy 111.995607 -407.443712) (xy 111.942823 -407.425705)
			(xy 111.893223 -407.400204) (xy 111.847865 -407.367753) (xy 111.807716 -407.329044) (xy 111.77363 -407.284901)
			(xy 111.746334 -407.236266) (xy 111.726411 -407.184175) (xy 111.714285 -407.129738) (xy 111.710214 -407.074116)
			(xy 110.460674 -407.074116) (xy 110.460281 -407.095652) (xy 110.452161 -407.150828) (xy 110.436093 -407.204235)
			(xy 110.412421 -407.254732) (xy 110.381648 -407.301245) (xy 110.344431 -407.342782) (xy 110.301563 -407.378457)
			(xy 110.253957 -407.407511) (xy 110.202628 -407.429323) (xy 110.148671 -407.443429) (xy 110.093234 -407.449529)
			(xy 110.0375 -407.447492) (xy 109.982657 -407.437362) (xy 109.929873 -407.419355) (xy 109.880273 -407.393854)
			(xy 109.834915 -407.361403) (xy 109.794766 -407.322694) (xy 109.76068 -407.278551) (xy 109.733384 -407.229916)
			(xy 109.713461 -407.177825) (xy 109.701335 -407.123388) (xy 109.697264 -407.067766) (xy 107.866333 -407.067766)
			(xy 107.868839 -407.087088) (xy 107.869228 -407.111708) (xy 107.86873 -407.138959) (xy 107.860973 -407.192905)
			(xy 107.845618 -407.245198) (xy 107.822977 -407.294774) (xy 107.793512 -407.340623) (xy 107.757822 -407.381813)
			(xy 107.716633 -407.417504) (xy 107.670785 -407.446971) (xy 107.621209 -407.469613) (xy 107.568917 -407.48497)
			(xy 107.514971 -407.492729) (xy 107.48772 -407.493216) (xy 106.62412 -407.493216) (xy 106.596868 -407.492726)
			(xy 106.542918 -407.484972) (xy 106.490622 -407.469619) (xy 106.441042 -407.446979) (xy 106.395189 -407.417514)
			(xy 106.353997 -407.381823) (xy 106.318303 -407.340633) (xy 106.288834 -407.294783) (xy 106.266191 -407.245205)
			(xy 106.250834 -407.192909) (xy 106.243076 -407.13896) (xy 106.242612 -407.111708) (xy 106.242973 -407.087085)
			(xy 106.249296 -407.038248) (xy 106.261864 -406.990634) (xy 106.270806 -406.96769) (xy 106.275893 -406.95379)
			(xy 106.278754 -406.924347) (xy 106.273052 -406.89532) (xy 106.259266 -406.869146) (xy 106.238554 -406.848025)
			(xy 106.225848 -406.840436) (xy 106.201912 -406.826658) (xy 106.157562 -406.793745) (xy 106.117976 -406.755234)
			(xy 106.083855 -406.711807) (xy 106.055802 -406.664234) (xy 106.034315 -406.613357) (xy 106.019774 -406.560077)
			(xy 106.012437 -406.505338) (xy 106.01198 -406.477724) (xy 105.13855 -406.477724) (xy 105.157211 -406.517531)
			(xy 105.173279 -406.570938) (xy 105.181399 -406.626114) (xy 105.181908 -406.654) (xy 105.181399 -406.681886)
			(xy 105.173279 -406.737062) (xy 105.157211 -406.790469) (xy 105.133539 -406.840966) (xy 105.102766 -406.887479)
			(xy 105.065549 -406.929016) (xy 105.022681 -406.964691) (xy 104.975075 -406.993745) (xy 104.923746 -407.015557)
			(xy 104.869789 -407.029663) (xy 104.814352 -407.035763) (xy 104.758618 -407.033726) (xy 104.703775 -407.023596)
			(xy 104.650991 -407.005589) (xy 104.601391 -406.980088) (xy 104.556033 -406.947637) (xy 104.515884 -406.908928)
			(xy 104.481798 -406.864785) (xy 104.454502 -406.81615) (xy 104.434579 -406.764059) (xy 104.422453 -406.709622)
			(xy 104.418382 -406.654) (xy 97.50806 -406.654) (xy 97.50806 -407.289) (xy 103.427782 -407.289) (xy 103.431853 -407.233378)
			(xy 103.443979 -407.178941) (xy 103.463902 -407.12685) (xy 103.491198 -407.078215) (xy 103.525284 -407.034072)
			(xy 103.565433 -406.995363) (xy 103.610791 -406.962912) (xy 103.660391 -406.937411) (xy 103.713175 -406.919404)
			(xy 103.768018 -406.909274) (xy 103.823752 -406.907237) (xy 103.879189 -406.913337) (xy 103.933146 -406.927443)
			(xy 103.984475 -406.949255) (xy 104.032081 -406.978309) (xy 104.074949 -407.013984) (xy 104.112166 -407.055521)
			(xy 104.142939 -407.102034) (xy 104.166611 -407.152531) (xy 104.182679 -407.205938) (xy 104.190799 -407.261114)
			(xy 104.191308 -407.289) (xy 104.190799 -407.316886) (xy 104.182679 -407.372062) (xy 104.166611 -407.425469)
			(xy 104.142939 -407.475966) (xy 104.112166 -407.522479) (xy 104.074949 -407.564016) (xy 104.032081 -407.599691)
			(xy 103.984475 -407.628745) (xy 103.933146 -407.650557) (xy 103.879189 -407.664663) (xy 103.823752 -407.670763)
			(xy 103.768018 -407.668726) (xy 103.713175 -407.658596) (xy 103.660391 -407.640589) (xy 103.610791 -407.615088)
			(xy 103.565433 -407.582637) (xy 103.525284 -407.543928) (xy 103.491198 -407.499785) (xy 103.463902 -407.45115)
			(xy 103.443979 -407.399059) (xy 103.431853 -407.344622) (xy 103.427782 -407.289) (xy 97.50806 -407.289)
			(xy 97.50806 -410.56052) (xy 99.785422 -410.56052) (xy 99.789493 -410.504898) (xy 99.801619 -410.450461)
			(xy 99.821542 -410.39837) (xy 99.848838 -410.349735) (xy 99.882924 -410.305592) (xy 99.923073 -410.266883)
			(xy 99.968431 -410.234432) (xy 100.018031 -410.208931) (xy 100.070815 -410.190924) (xy 100.125658 -410.180794)
			(xy 100.181392 -410.178757) (xy 100.236829 -410.184857) (xy 100.290786 -410.198963) (xy 100.342115 -410.220775)
			(xy 100.389721 -410.249829) (xy 100.432589 -410.285504) (xy 100.469806 -410.327041) (xy 100.500579 -410.373554)
			(xy 100.524251 -410.424051) (xy 100.540319 -410.477458) (xy 100.548439 -410.532634) (xy 100.548948 -410.56052)
			(xy 100.548596 -410.579824) (xy 101.64572 -410.579824) (xy 101.646203 -410.551503) (xy 101.653916 -410.495387)
			(xy 101.669198 -410.440845) (xy 101.691765 -410.388891) (xy 101.721195 -410.340494) (xy 101.756942 -410.296556)
			(xy 101.798339 -410.257894) (xy 101.844614 -410.225229) (xy 101.894907 -410.19917) (xy 101.948279 -410.180201)
			(xy 102.003737 -410.168677) (xy 102.060248 -410.164812) (xy 102.116759 -410.168677) (xy 102.172217 -410.180201)
			(xy 102.225589 -410.19917) (xy 102.275882 -410.225229) (xy 102.322157 -410.257894) (xy 102.363554 -410.296556)
			(xy 102.399301 -410.340494) (xy 102.428731 -410.388891) (xy 102.451298 -410.440845) (xy 102.46658 -410.495387)
			(xy 102.474293 -410.551503) (xy 102.474776 -410.579824) (xy 102.474163 -410.610583) (xy 102.46498 -410.671413)
			(xy 102.456488 -410.700982) (xy 102.452963 -410.714102) (xy 102.452178 -410.741247) (xy 102.458572 -410.767641)
			(xy 102.471693 -410.791417) (xy 102.490613 -410.810898) (xy 102.513997 -410.824707) (xy 102.540192 -410.831868)
			(xy 102.55377 -410.8323) (xy 102.82555 -410.8323) (xy 102.839136 -410.831866) (xy 102.865354 -410.824735)
			(xy 102.888761 -410.810939) (xy 102.907698 -410.791456) (xy 102.920824 -410.767667) (xy 102.927207 -410.741257)
			(xy 102.926395 -410.714099) (xy 102.922832 -410.700982) (xy 102.914326 -410.671415) (xy 102.905141 -410.610584)
			(xy 102.904544 -410.579824) (xy 102.905122 -410.550216) (xy 102.913546 -410.491602) (xy 102.930226 -410.434784)
			(xy 102.954822 -410.380918) (xy 102.986833 -410.3311) (xy 103.025609 -410.286345) (xy 103.070359 -410.247564)
			(xy 103.120172 -410.215547) (xy 103.174035 -410.190944) (xy 103.230851 -410.174257) (xy 103.289464 -410.165826)
			(xy 103.319072 -410.165296) (xy 103.32593 -410.16555) (xy 103.339957 -410.165338) (xy 103.367065 -410.15816)
			(xy 103.391201 -410.143883) (xy 103.410548 -410.123583) (xy 103.423648 -410.098789) (xy 103.429515 -410.071367)
			(xy 103.429054 -410.057346) (xy 103.428292 -410.0322) (xy 103.428778 -410.004949) (xy 103.436534 -409.951001)
			(xy 103.451889 -409.898706) (xy 103.474531 -409.849129) (xy 103.503997 -409.803279) (xy 103.539688 -409.762088)
			(xy 103.580879 -409.726397) (xy 103.626729 -409.696931) (xy 103.676306 -409.674289) (xy 103.728601 -409.658934)
			(xy 103.782549 -409.651178) (xy 103.837051 -409.651178) (xy 103.890999 -409.658934) (xy 103.943294 -409.674289)
			(xy 103.992871 -409.696931) (xy 104.038721 -409.726397) (xy 104.079912 -409.762088) (xy 104.115603 -409.803279)
			(xy 104.145069 -409.849129) (xy 104.167711 -409.898706) (xy 104.183066 -409.951001) (xy 104.190822 -410.004949)
			(xy 104.191308 -410.0322) (xy 104.190877 -410.058696) (xy 104.183569 -410.111181) (xy 104.169066 -410.162149)
			(xy 104.147648 -410.210618) (xy 104.119725 -410.255656) (xy 104.085838 -410.296396) (xy 104.046636 -410.332051)
			(xy 104.002877 -410.361938) (xy 103.955402 -410.385478) (xy 103.905125 -410.402221) (xy 103.853014 -410.411842)
			(xy 103.826564 -410.413454) (xy 103.81257 -410.414507) (xy 103.785932 -410.423299) (xy 103.762698 -410.439017)
			(xy 103.744626 -410.460472) (xy 103.733086 -410.486041) (xy 103.728951 -410.513786) (xy 103.730298 -410.527754)
			(xy 103.731835 -410.540717) (xy 103.733487 -410.566771) (xy 103.7336 -410.579824) (xy 103.733116 -410.607437)
			(xy 103.72578 -410.662175) (xy 103.711242 -410.715453) (xy 103.689759 -410.76633) (xy 103.661711 -410.813904)
			(xy 103.627595 -410.857333) (xy 103.588015 -410.895848) (xy 103.543672 -410.928767) (xy 103.519732 -410.942536)
			(xy 103.506998 -410.950086) (xy 103.486279 -410.971219) (xy 103.472489 -410.997404) (xy 103.466786 -411.026444)
			(xy 103.469647 -411.0559) (xy 103.474774 -411.06979) (xy 103.483697 -411.09274) (xy 103.496246 -411.140355)
			(xy 103.502579 -411.189187) (xy 103.502968 -411.213808) (xy 103.502552 -411.241063) (xy 103.494793 -411.295018)
			(xy 103.479434 -411.347319) (xy 103.456787 -411.396902) (xy 103.427315 -411.442757) (xy 103.391616 -411.48395)
			(xy 103.350418 -411.519644) (xy 103.304559 -411.549111) (xy 103.254974 -411.571751) (xy 103.202671 -411.587103)
			(xy 103.148715 -411.594855) (xy 103.12146 -411.595316) (xy 102.25786 -411.595316) (xy 102.230608 -411.594859)
			(xy 102.17666 -411.587098) (xy 102.124365 -411.571738) (xy 102.074788 -411.549093) (xy 102.028938 -411.519623)
			(xy 101.987749 -411.483929) (xy 101.952058 -411.442736) (xy 101.922592 -411.396884) (xy 101.899951 -411.347305)
			(xy 101.884596 -411.295009) (xy 101.876838 -411.24106) (xy 101.876352 -411.213808) (xy 101.876718 -411.189186)
			(xy 101.88304 -411.140349) (xy 101.895605 -411.092735) (xy 101.904546 -411.06979) (xy 101.909661 -411.055898)
			(xy 101.912525 -411.026448) (xy 101.90682 -410.997415) (xy 101.893025 -410.971239) (xy 101.8723 -410.950121)
			(xy 101.859588 -410.942536) (xy 101.835661 -410.928742) (xy 101.79131 -410.895833) (xy 101.751722 -410.857325)
			(xy 101.717599 -410.813901) (xy 101.689545 -410.766329) (xy 101.668056 -410.715454) (xy 101.653515 -410.662175)
			(xy 101.646177 -410.607438) (xy 101.64572 -410.579824) (xy 100.548596 -410.579824) (xy 100.548439 -410.588406)
			(xy 100.540319 -410.643582) (xy 100.524251 -410.696989) (xy 100.500579 -410.747486) (xy 100.469806 -410.793999)
			(xy 100.432589 -410.835536) (xy 100.389721 -410.871211) (xy 100.342115 -410.900265) (xy 100.290786 -410.922077)
			(xy 100.236829 -410.936183) (xy 100.181392 -410.942283) (xy 100.125658 -410.940246) (xy 100.070815 -410.930116)
			(xy 100.018031 -410.912109) (xy 99.968431 -410.886608) (xy 99.923073 -410.854157) (xy 99.882924 -410.815448)
			(xy 99.848838 -410.771305) (xy 99.821542 -410.72267) (xy 99.801619 -410.670579) (xy 99.789493 -410.616142)
			(xy 99.785422 -410.56052) (xy 97.50806 -410.56052) (xy 97.50806 -412.5504) (xy 104.210022 -412.5504)
			(xy 104.213889 -412.493877) (xy 104.225416 -412.438407) (xy 104.24439 -412.385023) (xy 104.270457 -412.33472)
			(xy 104.30313 -412.288436) (xy 104.341802 -412.247032) (xy 104.385753 -412.21128) (xy 104.434162 -412.181846)
			(xy 104.486128 -412.159278) (xy 104.540684 -412.143997) (xy 104.596812 -412.136287) (xy 104.62514 -412.135828)
			(xy 104.652754 -412.136285) (xy 104.707493 -412.143623) (xy 104.760773 -412.158164) (xy 104.811651 -412.179651)
			(xy 104.859225 -412.207703) (xy 104.902654 -412.241823) (xy 104.941168 -412.281407) (xy 104.974085 -412.325754)
			(xy 104.987852 -412.349696) (xy 104.995476 -412.36238) (xy 105.016591 -412.383094) (xy 105.042757 -412.396888)
			(xy 105.071777 -412.402605) (xy 105.101219 -412.399767) (xy 105.115106 -412.394654) (xy 105.138055 -412.385728)
			(xy 105.185671 -412.373179) (xy 105.234503 -412.366848) (xy 105.259124 -412.36646) (xy 105.286374 -412.366955)
			(xy 105.34032 -412.374714) (xy 105.392613 -412.390071) (xy 105.442188 -412.412712) (xy 105.488037 -412.442178)
			(xy 105.529226 -412.477869) (xy 105.564917 -412.519057) (xy 105.594384 -412.564905) (xy 105.617026 -412.61448)
			(xy 105.632384 -412.666772) (xy 105.640144 -412.720718) (xy 105.640632 -412.747968) (xy 105.640632 -413.611568)
			(xy 105.640115 -413.638819) (xy 105.632363 -413.692767) (xy 105.617012 -413.745062) (xy 105.594375 -413.794641)
			(xy 105.564913 -413.840493) (xy 105.529225 -413.881685) (xy 105.488038 -413.917379) (xy 105.44219 -413.946848)
			(xy 105.392615 -413.969493) (xy 105.340322 -413.984851) (xy 105.286375 -413.992611) (xy 105.259124 -413.993076)
			(xy 105.234502 -413.992711) (xy 105.185665 -413.986389) (xy 105.138051 -413.973823) (xy 105.115106 -413.964882)
			(xy 105.101212 -413.959771) (xy 105.071763 -413.956902) (xy 105.042728 -413.962605) (xy 105.016552 -413.9764)
			(xy 104.995435 -413.997126) (xy 104.987852 -414.00984) (xy 104.97413 -414.03381) (xy 104.94121 -414.07816)
			(xy 104.902691 -414.117746) (xy 104.859256 -414.151866) (xy 104.811674 -414.179914) (xy 104.760789 -414.201396)
			(xy 104.707502 -414.215929) (xy 104.652757 -414.223256) (xy 104.62514 -414.223708) (xy 104.596814 -414.223289)
			(xy 104.540689 -414.21558) (xy 104.486136 -414.2003) (xy 104.434173 -414.177733) (xy 104.385766 -414.148301)
			(xy 104.341819 -414.112551) (xy 104.303149 -414.071149) (xy 104.270477 -414.024867) (xy 104.244412 -413.974568)
			(xy 104.225439 -413.921187) (xy 104.213912 -413.86572) (xy 104.210046 -413.8092) (xy 104.213912 -413.75268)
			(xy 104.225439 -413.697213) (xy 104.244412 -413.643832) (xy 104.270477 -413.593533) (xy 104.303149 -413.547251)
			(xy 104.341819 -413.505849) (xy 104.385766 -413.470099) (xy 104.434173 -413.440667) (xy 104.486136 -413.4181)
			(xy 104.540689 -413.40282) (xy 104.596814 -413.395111) (xy 104.62514 -413.394652) (xy 104.655899 -413.395264)
			(xy 104.716729 -413.404448) (xy 104.746298 -413.41294) (xy 104.759419 -413.416456) (xy 104.786562 -413.417236)
			(xy 104.812951 -413.410841) (xy 104.836725 -413.397722) (xy 104.856204 -413.378805) (xy 104.870015 -413.355425)
			(xy 104.87718 -413.329234) (xy 104.877616 -413.315658) (xy 104.877616 -413.043878) (xy 104.877138 -413.030295)
			(xy 104.870015 -413.00408) (xy 104.856227 -412.980675) (xy 104.836752 -412.961738) (xy 104.812969 -412.948611)
			(xy 104.786565 -412.942226) (xy 104.759412 -412.943035) (xy 104.746298 -412.946596) (xy 104.716731 -412.955099)
			(xy 104.6559 -412.964286) (xy 104.62514 -412.964884) (xy 104.596812 -412.964513) (xy 104.540684 -412.956803)
			(xy 104.486128 -412.941522) (xy 104.434162 -412.918954) (xy 104.385753 -412.88952) (xy 104.341802 -412.853768)
			(xy 104.30313 -412.812364) (xy 104.270457 -412.76608) (xy 104.24439 -412.715777) (xy 104.225416 -412.662393)
			(xy 104.213889 -412.606923) (xy 104.210022 -412.5504) (xy 97.50806 -412.5504) (xy 97.50806 -414.13176)
			(xy 97.263204 -414.376616) (xy 98.225862 -414.376616) (xy 98.229933 -414.320994) (xy 98.242059 -414.266557)
			(xy 98.261982 -414.214466) (xy 98.289278 -414.165831) (xy 98.323364 -414.121688) (xy 98.363513 -414.082979)
			(xy 98.408871 -414.050528) (xy 98.458471 -414.025027) (xy 98.511255 -414.00702) (xy 98.566098 -413.99689)
			(xy 98.621832 -413.994853) (xy 98.677269 -414.000953) (xy 98.731226 -414.015059) (xy 98.782555 -414.036871)
			(xy 98.830161 -414.065925) (xy 98.873029 -414.1016) (xy 98.910246 -414.143137) (xy 98.941019 -414.18965)
			(xy 98.964691 -414.240147) (xy 98.980759 -414.293554) (xy 98.988879 -414.34873) (xy 98.989388 -414.376616)
			(xy 98.988879 -414.404502) (xy 98.980759 -414.459678) (xy 98.964691 -414.513085) (xy 98.941019 -414.563582)
			(xy 98.910246 -414.610095) (xy 98.8765 -414.647758) (xy 99.926011 -414.647758) (xy 99.926011 -414.593242)
			(xy 99.93377 -414.539281) (xy 99.94913 -414.486974) (xy 99.971778 -414.437386) (xy 100.001253 -414.391525)
			(xy 100.036955 -414.350327) (xy 100.078157 -414.314629) (xy 100.124021 -414.285159) (xy 100.173612 -414.262516)
			(xy 100.225921 -414.247161) (xy 100.279882 -414.239408) (xy 100.30714 -414.238948) (xy 100.336029 -414.239472)
			(xy 100.393146 -414.248177) (xy 100.448297 -414.265395) (xy 100.500222 -414.290734) (xy 100.54773 -414.323614)
			(xy 100.589737 -414.363282) (xy 100.625282 -414.408832) (xy 100.63988 -414.433766) (xy 100.647866 -414.446997)
			(xy 100.670298 -414.468236) (xy 100.698053 -414.481798) (xy 100.728594 -414.486441) (xy 100.759126 -414.481742)
			(xy 100.77323 -414.475422) (xy 100.799503 -414.463162) (xy 100.854825 -414.445824) (xy 100.912136 -414.437079)
			(xy 100.941124 -414.43656) (xy 100.968374 -414.437055) (xy 101.02232 -414.444814) (xy 101.074613 -414.460171)
			(xy 101.124188 -414.482812) (xy 101.170037 -414.512278) (xy 101.211226 -414.547969) (xy 101.246917 -414.589157)
			(xy 101.276384 -414.635005) (xy 101.299026 -414.68458) (xy 101.314384 -414.736872) (xy 101.322144 -414.790818)
			(xy 101.322632 -414.818068) (xy 101.322632 -415.681668) (xy 101.322115 -415.708919) (xy 101.314363 -415.762867)
			(xy 101.299012 -415.815162) (xy 101.276375 -415.864741) (xy 101.246913 -415.910593) (xy 101.211225 -415.951785)
			(xy 101.170038 -415.987479) (xy 101.12419 -416.016948) (xy 101.074615 -416.039593) (xy 101.022322 -416.054951)
			(xy 100.968375 -416.062711) (xy 100.941124 -416.063176) (xy 100.912139 -416.062631) (xy 100.854833 -416.053871)
			(xy 100.799506 -416.036563) (xy 100.77323 -416.024314) (xy 100.759111 -416.01804) (xy 100.728591 -416.013345)
			(xy 100.698063 -416.017985) (xy 100.670316 -416.031535) (xy 100.647885 -416.052757) (xy 100.63988 -416.06597)
			(xy 100.62526 -416.09089) (xy 100.589713 -416.136432) (xy 100.547707 -416.176095) (xy 100.500202 -416.208973)
			(xy 100.448283 -416.234313) (xy 100.393138 -416.251538) (xy 100.336026 -416.260253) (xy 100.30714 -416.260788)
			(xy 100.279884 -416.260368) (xy 100.225926 -416.252615) (xy 100.17362 -416.237262) (xy 100.124032 -416.21462)
			(xy 100.078172 -416.185152) (xy 100.036972 -416.149456) (xy 100.001272 -416.10826) (xy 99.971799 -416.062403)
			(xy 99.949152 -416.012817) (xy 99.933793 -415.960513) (xy 99.926035 -415.906556) (xy 99.926035 -415.852044)
			(xy 99.933793 -415.798087) (xy 99.949152 -415.745783) (xy 99.971799 -415.696197) (xy 100.001272 -415.65034)
			(xy 100.036972 -415.609144) (xy 100.078172 -415.573448) (xy 100.124032 -415.54398) (xy 100.17362 -415.521338)
			(xy 100.225926 -415.505985) (xy 100.279884 -415.498232) (xy 100.30714 -415.497772) (xy 100.337445 -415.498352)
			(xy 100.397294 -415.507916) (xy 100.426266 -415.516822) (xy 100.439446 -415.520693) (xy 100.466873 -415.522007)
			(xy 100.493658 -415.515964) (xy 100.517864 -415.503) (xy 100.53774 -415.484055) (xy 100.551847 -415.460497)
			(xy 100.559166 -415.434031) (xy 100.559616 -415.420302) (xy 100.559616 -415.079434) (xy 100.559125 -415.065707)
			(xy 100.551816 -415.039245) (xy 100.537716 -415.015689) (xy 100.517848 -414.996744) (xy 100.493648 -414.983781)
			(xy 100.466868 -414.977738) (xy 100.439446 -414.979053) (xy 100.426266 -414.982914) (xy 100.397293 -414.991817)
			(xy 100.337444 -415.001382) (xy 100.30714 -415.001964) (xy 100.279882 -415.001592) (xy 100.225921 -414.993839)
			(xy 100.173612 -414.978484) (xy 100.124021 -414.955841) (xy 100.078157 -414.926371) (xy 100.036955 -414.890673)
			(xy 100.001253 -414.849475) (xy 99.971778 -414.803614) (xy 99.94913 -414.754026) (xy 99.93377 -414.701719)
			(xy 99.926011 -414.647758) (xy 98.8765 -414.647758) (xy 98.873029 -414.651632) (xy 98.830161 -414.687307)
			(xy 98.782555 -414.716361) (xy 98.731226 -414.738173) (xy 98.677269 -414.752279) (xy 98.621832 -414.758379)
			(xy 98.566098 -414.756342) (xy 98.511255 -414.746212) (xy 98.458471 -414.728205) (xy 98.408871 -414.702704)
			(xy 98.363513 -414.670253) (xy 98.323364 -414.631544) (xy 98.289278 -414.587401) (xy 98.261982 -414.538766)
			(xy 98.242059 -414.486675) (xy 98.229933 -414.432238) (xy 98.225862 -414.376616) (xy 97.263204 -414.376616)
			(xy 94.82582 -416.814) (xy 100.557582 -416.814) (xy 100.561653 -416.758378) (xy 100.573779 -416.703941)
			(xy 100.593702 -416.65185) (xy 100.620998 -416.603215) (xy 100.655084 -416.559072) (xy 100.695233 -416.520363)
			(xy 100.740591 -416.487912) (xy 100.790191 -416.462411) (xy 100.842975 -416.444404) (xy 100.897818 -416.434274)
			(xy 100.953552 -416.432237) (xy 101.008989 -416.438337) (xy 101.062946 -416.452443) (xy 101.114275 -416.474255)
			(xy 101.161881 -416.503309) (xy 101.204749 -416.538984) (xy 101.241966 -416.580521) (xy 101.272739 -416.627034)
			(xy 101.296411 -416.677531) (xy 101.312479 -416.730938) (xy 101.320599 -416.786114) (xy 101.321108 -416.814)
			(xy 101.320599 -416.841886) (xy 101.312479 -416.897062) (xy 101.296411 -416.950469) (xy 101.272739 -417.000966)
			(xy 101.241966 -417.047479) (xy 101.204749 -417.089016) (xy 101.161881 -417.124691) (xy 101.114275 -417.153745)
			(xy 101.062946 -417.175557) (xy 101.008989 -417.189663) (xy 100.953552 -417.195763) (xy 100.897818 -417.193726)
			(xy 100.842975 -417.183596) (xy 100.790191 -417.165589) (xy 100.740591 -417.140088) (xy 100.695233 -417.107637)
			(xy 100.655084 -417.068928) (xy 100.620998 -417.024785) (xy 100.593702 -416.97615) (xy 100.573779 -416.924059)
			(xy 100.561653 -416.869622) (xy 100.557582 -416.814) (xy 94.82582 -416.814) (xy 93.62567 -418.01415)
			(xy 93.622114 -418.027358) (xy 93.614248 -418.05487) (xy 93.591413 -418.107336) (xy 93.560995 -418.155801)
			(xy 93.523679 -418.199179) (xy 93.480301 -418.236495) (xy 93.431836 -418.266913) (xy 93.37937 -418.289748)
			(xy 93.351858 -418.297614) (xy 93.33865 -418.30117) (xy 93.2434 -418.39642) (xy 93.2434 -418.476684)
			(xy 93.276166 -418.488876) (xy 93.301446 -418.498902) (xy 93.34911 -418.525085) (xy 93.392574 -418.55777)
			(xy 93.430957 -418.596295) (xy 93.443294 -418.612828) (xy 101.660452 -418.612828) (xy 101.661014 -418.582524)
			(xy 101.670607 -418.522678) (xy 101.689539 -418.465102) (xy 101.717335 -418.411243) (xy 101.753296 -418.362455)
			(xy 101.774498 -418.340794) (xy 101.785249 -418.329495) (xy 101.7999 -418.301979) (xy 101.805588 -418.271328)
			(xy 101.801784 -418.240387) (xy 101.788841 -418.212027) (xy 101.778816 -418.200078) (xy 101.760439 -418.178971)
			(xy 101.72946 -418.132363) (xy 101.705624 -418.081728) (xy 101.689443 -418.028154) (xy 101.681264 -417.97279)
			(xy 101.680772 -417.944808) (xy 101.681285 -417.917558) (xy 101.68904 -417.863612) (xy 101.704393 -417.811319)
			(xy 101.727032 -417.761743) (xy 101.756496 -417.715894) (xy 101.792184 -417.674704) (xy 101.833371 -417.639012)
			(xy 101.879219 -417.609545) (xy 101.928793 -417.586903) (xy 101.981085 -417.571546) (xy 102.03503 -417.563787)
			(xy 102.06228 -417.5633) (xy 102.08965 -417.563778) (xy 102.143828 -417.571593) (xy 102.196331 -417.587079)
			(xy 102.246078 -417.609918) (xy 102.292046 -417.63964) (xy 102.312978 -417.65728) (xy 102.324306 -417.666516)
			(xy 102.350863 -417.678692) (xy 102.37978 -417.682865) (xy 102.408697 -417.678692) (xy 102.435254 -417.666516)
			(xy 102.446582 -417.65728) (xy 102.467507 -417.639633) (xy 102.513482 -417.609923) (xy 102.563232 -417.587089)
			(xy 102.615734 -417.5716) (xy 102.66991 -417.563773) (xy 102.69728 -417.5633) (xy 102.724533 -417.563774)
			(xy 102.778484 -417.571528) (xy 102.830782 -417.586882) (xy 102.880362 -417.609523) (xy 102.926216 -417.63899)
			(xy 102.967409 -417.674682) (xy 103.003103 -417.715874) (xy 103.032571 -417.761727) (xy 103.055213 -417.811307)
			(xy 103.070569 -417.863605) (xy 103.078325 -417.917555) (xy 103.078788 -417.944808) (xy 103.078173 -417.97511)
			(xy 103.068592 -418.034952) (xy 103.049671 -418.092528) (xy 103.021887 -418.146388) (xy 102.985938 -418.195179)
			(xy 102.964742 -418.216842) (xy 102.954056 -418.228196) (xy 102.939407 -418.255694) (xy 102.933712 -418.286327)
			(xy 102.937498 -418.317254) (xy 102.950414 -418.345608) (xy 102.960424 -418.357558) (xy 102.978761 -418.378699)
			(xy 103.009748 -418.425297) (xy 103.033592 -418.475923) (xy 103.049783 -418.52949) (xy 103.057971 -418.584848)
			(xy 103.058468 -418.612828) (xy 103.058071 -418.640083) (xy 103.050309 -418.694039) (xy 103.034948 -418.74634)
			(xy 103.012299 -418.795923) (xy 102.982824 -418.841778) (xy 102.947124 -418.882972) (xy 102.905924 -418.918665)
			(xy 102.860064 -418.948132) (xy 102.810477 -418.970771) (xy 102.758172 -418.986124) (xy 102.704215 -418.993876)
			(xy 102.67696 -418.994336) (xy 102.64959 -418.99385) (xy 102.595411 -418.98604) (xy 102.542908 -418.970556)
			(xy 102.493161 -418.947718) (xy 102.447194 -418.917996) (xy 102.426262 -418.900356) (xy 102.414934 -418.89112)
			(xy 102.388377 -418.878944) (xy 102.35946 -418.874771) (xy 102.330543 -418.878944) (xy 102.303986 -418.89112)
			(xy 102.292658 -418.900356) (xy 102.271709 -418.917975) (xy 102.225742 -418.947691) (xy 102.175999 -418.970532)
			(xy 102.123501 -418.986027) (xy 102.069328 -418.99386) (xy 102.04196 -418.994336) (xy 102.014709 -418.993859)
			(xy 101.960762 -418.986098) (xy 101.908469 -418.970739) (xy 101.858894 -418.948096) (xy 101.813045 -418.918628)
			(xy 101.771856 -418.882936) (xy 101.736165 -418.841745) (xy 101.706699 -418.795896) (xy 101.684056 -418.746319)
			(xy 101.668699 -418.694026) (xy 101.66094 -418.640079) (xy 101.660452 -418.612828) (xy 93.443294 -418.612828)
			(xy 93.463481 -418.63988) (xy 93.489487 -418.687641) (xy 93.508449 -418.73861) (xy 93.519982 -418.791756)
			(xy 93.523852 -418.846) (xy 93.519982 -418.900244) (xy 93.508449 -418.95339) (xy 93.489487 -419.004359)
			(xy 93.463481 -419.05212) (xy 93.458457 -419.058852) (xy 104.381806 -419.058852) (xy 104.385877 -419.00323)
			(xy 104.398003 -418.948793) (xy 104.417926 -418.896702) (xy 104.445222 -418.848067) (xy 104.479308 -418.803924)
			(xy 104.519457 -418.765215) (xy 104.564815 -418.732764) (xy 104.614415 -418.707263) (xy 104.667199 -418.689256)
			(xy 104.722042 -418.679126) (xy 104.777776 -418.677089) (xy 104.833213 -418.683189) (xy 104.88717 -418.697295)
			(xy 104.938499 -418.719107) (xy 104.986105 -418.748161) (xy 105.028973 -418.783836) (xy 105.06619 -418.825373)
			(xy 105.096963 -418.871886) (xy 105.120635 -418.922383) (xy 105.136703 -418.97579) (xy 105.144823 -419.030966)
			(xy 105.145332 -419.058852) (xy 105.144823 -419.086738) (xy 105.136703 -419.141914) (xy 105.120635 -419.195321)
			(xy 105.096963 -419.245818) (xy 105.06619 -419.292331) (xy 105.028973 -419.333868) (xy 104.986105 -419.369543)
			(xy 104.938499 -419.398597) (xy 104.88717 -419.420409) (xy 104.833213 -419.434515) (xy 104.777776 -419.440615)
			(xy 104.722042 -419.438578) (xy 104.667199 -419.428448) (xy 104.614415 -419.410441) (xy 104.564815 -419.38494)
			(xy 104.519457 -419.352489) (xy 104.479308 -419.31378) (xy 104.445222 -419.269637) (xy 104.417926 -419.221002)
			(xy 104.398003 -419.168911) (xy 104.385877 -419.114474) (xy 104.381806 -419.058852) (xy 93.458457 -419.058852)
			(xy 93.430957 -419.095705) (xy 93.392574 -419.13423) (xy 93.34911 -419.166915) (xy 93.301446 -419.193098)
			(xy 93.276166 -419.203124) (xy 93.2434 -419.215316) (xy 93.2434 -420.207948) (xy 93.724982 -420.207948)
			(xy 93.729053 -420.152326) (xy 93.741179 -420.097889) (xy 93.761102 -420.045798) (xy 93.788398 -419.997163)
			(xy 93.822484 -419.95302) (xy 93.862633 -419.914311) (xy 93.907991 -419.88186) (xy 93.957591 -419.856359)
			(xy 94.010375 -419.838352) (xy 94.065218 -419.828222) (xy 94.120952 -419.826185) (xy 94.176389 -419.832285)
			(xy 94.230346 -419.846391) (xy 94.281675 -419.868203) (xy 94.329281 -419.897257) (xy 94.372149 -419.932932)
			(xy 94.409366 -419.974469) (xy 94.440139 -420.020982) (xy 94.463811 -420.071479) (xy 94.479879 -420.124886)
			(xy 94.480403 -420.128446) (xy 96.15754 -420.128446) (xy 96.161611 -420.072824) (xy 96.173737 -420.018387)
			(xy 96.19366 -419.966296) (xy 96.220956 -419.917661) (xy 96.255042 -419.873518) (xy 96.295191 -419.834809)
			(xy 96.340549 -419.802358) (xy 96.390149 -419.776857) (xy 96.442933 -419.75885) (xy 96.497776 -419.74872)
			(xy 96.55351 -419.746683) (xy 96.608947 -419.752783) (xy 96.662904 -419.766889) (xy 96.714233 -419.788701)
			(xy 96.761839 -419.817755) (xy 96.804707 -419.85343) (xy 96.841924 -419.894967) (xy 96.872697 -419.94148)
			(xy 96.896369 -419.991977) (xy 96.912437 -420.045384) (xy 96.920557 -420.10056) (xy 96.921066 -420.128446)
			(xy 96.920557 -420.156332) (xy 96.912437 -420.211508) (xy 96.896369 -420.264915) (xy 96.872697 -420.315412)
			(xy 96.841924 -420.361925) (xy 96.804707 -420.403462) (xy 96.761839 -420.439137) (xy 96.714233 -420.468191)
			(xy 96.662904 -420.490003) (xy 96.608947 -420.504109) (xy 96.55351 -420.510209) (xy 96.497776 -420.508172)
			(xy 96.442933 -420.498042) (xy 96.390149 -420.480035) (xy 96.340549 -420.454534) (xy 96.295191 -420.422083)
			(xy 96.255042 -420.383374) (xy 96.220956 -420.339231) (xy 96.19366 -420.290596) (xy 96.173737 -420.238505)
			(xy 96.161611 -420.184068) (xy 96.15754 -420.128446) (xy 94.480403 -420.128446) (xy 94.487999 -420.180062)
			(xy 94.488508 -420.207948) (xy 94.487999 -420.235834) (xy 94.479879 -420.29101) (xy 94.463811 -420.344417)
			(xy 94.440139 -420.394914) (xy 94.409366 -420.441427) (xy 94.372149 -420.482964) (xy 94.329281 -420.518639)
			(xy 94.281675 -420.547693) (xy 94.230346 -420.569505) (xy 94.176389 -420.583611) (xy 94.120952 -420.589711)
			(xy 94.065218 -420.587674) (xy 94.010375 -420.577544) (xy 93.957591 -420.559537) (xy 93.907991 -420.534036)
			(xy 93.862633 -420.501585) (xy 93.822484 -420.462876) (xy 93.788398 -420.418733) (xy 93.761102 -420.370098)
			(xy 93.741179 -420.318007) (xy 93.729053 -420.26357) (xy 93.724982 -420.207948) (xy 93.2434 -420.207948)
			(xy 93.2434 -421.24884) (xy 103.935782 -421.24884) (xy 103.939853 -421.193218) (xy 103.951979 -421.138781)
			(xy 103.971902 -421.08669) (xy 103.999198 -421.038055) (xy 104.033284 -420.993912) (xy 104.073433 -420.955203)
			(xy 104.118791 -420.922752) (xy 104.168391 -420.897251) (xy 104.221175 -420.879244) (xy 104.276018 -420.869114)
			(xy 104.331752 -420.867077) (xy 104.387189 -420.873177) (xy 104.441146 -420.887283) (xy 104.492475 -420.909095)
			(xy 104.540081 -420.938149) (xy 104.582949 -420.973824) (xy 104.620166 -421.015361) (xy 104.650939 -421.061874)
			(xy 104.674611 -421.112371) (xy 104.690679 -421.165778) (xy 104.698799 -421.220954) (xy 104.699308 -421.24884)
			(xy 104.698799 -421.276726) (xy 104.690679 -421.331902) (xy 104.674611 -421.385309) (xy 104.650939 -421.435806)
			(xy 104.620166 -421.482319) (xy 104.582949 -421.523856) (xy 104.540081 -421.559531) (xy 104.492475 -421.588585)
			(xy 104.441146 -421.610397) (xy 104.387189 -421.624503) (xy 104.331752 -421.630603) (xy 104.276018 -421.628566)
			(xy 104.221175 -421.618436) (xy 104.168391 -421.600429) (xy 104.118791 -421.574928) (xy 104.073433 -421.542477)
			(xy 104.033284 -421.503768) (xy 103.999198 -421.459625) (xy 103.971902 -421.41099) (xy 103.951979 -421.358899)
			(xy 103.939853 -421.304462) (xy 103.935782 -421.24884) (xy 93.2434 -421.24884) (xy 93.2434 -421.640508)
			(xy 96.181162 -421.640508) (xy 96.185233 -421.584886) (xy 96.197359 -421.530449) (xy 96.217282 -421.478358)
			(xy 96.244578 -421.429723) (xy 96.278664 -421.38558) (xy 96.318813 -421.346871) (xy 96.364171 -421.31442)
			(xy 96.413771 -421.288919) (xy 96.466555 -421.270912) (xy 96.521398 -421.260782) (xy 96.577132 -421.258745)
			(xy 96.632569 -421.264845) (xy 96.686526 -421.278951) (xy 96.737855 -421.300763) (xy 96.785461 -421.329817)
			(xy 96.828329 -421.365492) (xy 96.865546 -421.407029) (xy 96.896319 -421.453542) (xy 96.919991 -421.504039)
			(xy 96.936059 -421.557446) (xy 96.944179 -421.612622) (xy 96.944688 -421.640508) (xy 96.944179 -421.668394)
			(xy 96.936059 -421.72357) (xy 96.919991 -421.776977) (xy 96.896319 -421.827474) (xy 96.865546 -421.873987)
			(xy 96.828329 -421.915524) (xy 96.785461 -421.951199) (xy 96.737855 -421.980253) (xy 96.686526 -422.002065)
			(xy 96.632569 -422.016171) (xy 96.577132 -422.022271) (xy 96.521398 -422.020234) (xy 96.466555 -422.010104)
			(xy 96.413771 -421.992097) (xy 96.364171 -421.966596) (xy 96.318813 -421.934145) (xy 96.278664 -421.895436)
			(xy 96.244578 -421.851293) (xy 96.217282 -421.802658) (xy 96.197359 -421.750567) (xy 96.185233 -421.69613)
			(xy 96.181162 -421.640508) (xy 93.2434 -421.640508) (xy 93.2434 -422.203646) (xy 94.269626 -422.203646)
			(xy 94.269626 -422.149154) (xy 94.277381 -422.095217) (xy 94.292732 -422.042932) (xy 94.315367 -421.993363)
			(xy 94.344826 -421.947521) (xy 94.380509 -421.906337) (xy 94.421689 -421.87065) (xy 94.467528 -421.841186)
			(xy 94.517094 -421.818546) (xy 94.569378 -421.803189) (xy 94.623314 -421.795429) (xy 94.65056 -421.79494)
			(xy 94.677608 -421.795429) (xy 94.731162 -421.803072) (xy 94.783101 -421.818197) (xy 94.832386 -421.840502)
			(xy 94.878029 -421.869539) (xy 94.919117 -421.904727) (xy 94.937326 -421.924734) (xy 94.947469 -421.935505)
			(xy 94.972491 -421.951259) (xy 95.000979 -421.959181) (xy 95.030542 -421.958608) (xy 95.058701 -421.949585)
			(xy 95.083093 -421.932872) (xy 95.092774 -421.921686) (xy 95.111006 -421.899942) (xy 95.152774 -421.861534)
			(xy 95.199771 -421.829738) (xy 95.250961 -421.805255) (xy 95.305212 -421.788627) (xy 95.361329 -421.780221)
			(xy 95.3897 -421.7797) (xy 95.416952 -421.78017) (xy 95.470901 -421.787926) (xy 95.523197 -421.803282)
			(xy 95.572775 -421.825924) (xy 95.618626 -421.85539) (xy 95.659817 -421.891083) (xy 95.69551 -421.932274)
			(xy 95.724976 -421.978125) (xy 95.747618 -422.027703) (xy 95.762974 -422.079999) (xy 95.77073 -422.133948)
			(xy 95.77073 -422.188452) (xy 95.762974 -422.242401) (xy 95.747618 -422.294697) (xy 95.724976 -422.344275)
			(xy 95.69551 -422.390126) (xy 95.659817 -422.431317) (xy 95.618626 -422.46701) (xy 95.572775 -422.496476)
			(xy 95.523197 -422.519118) (xy 95.470901 -422.534474) (xy 95.416952 -422.54223) (xy 95.3897 -422.542716)
			(xy 95.362652 -422.542236) (xy 95.309098 -422.534588) (xy 95.257159 -422.51946) (xy 95.207875 -422.497154)
			(xy 95.162232 -422.468117) (xy 95.121143 -422.432929) (xy 95.102934 -422.412922) (xy 95.092835 -422.402104)
			(xy 95.067802 -422.386343) (xy 95.039301 -422.37842) (xy 95.009725 -422.379002) (xy 94.981558 -422.388039)
			(xy 94.957164 -422.404773) (xy 94.947486 -422.41597) (xy 94.92929 -422.437745) (xy 94.887513 -422.476149)
			(xy 94.840508 -422.50794) (xy 94.789311 -422.532416) (xy 94.735054 -422.549038) (xy 94.678933 -422.557439)
			(xy 94.65056 -422.557956) (xy 94.623314 -422.557371) (xy 94.569378 -422.549611) (xy 94.517094 -422.534254)
			(xy 94.467528 -422.511614) (xy 94.421689 -422.48215) (xy 94.380509 -422.446463) (xy 94.344826 -422.405279)
			(xy 94.315367 -422.359437) (xy 94.292732 -422.309868) (xy 94.277381 -422.257583) (xy 94.269626 -422.203646)
			(xy 93.2434 -422.203646) (xy 93.2434 -424.457368) (xy 98.109022 -424.457368) (xy 98.113093 -424.401746)
			(xy 98.125219 -424.347309) (xy 98.145142 -424.295218) (xy 98.172438 -424.246583) (xy 98.206524 -424.20244)
			(xy 98.246673 -424.163731) (xy 98.292031 -424.13128) (xy 98.341631 -424.105779) (xy 98.394415 -424.087772)
			(xy 98.449258 -424.077642) (xy 98.504992 -424.075605) (xy 98.560429 -424.081705) (xy 98.614386 -424.095811)
			(xy 98.665715 -424.117623) (xy 98.713321 -424.146677) (xy 98.756189 -424.182352) (xy 98.793406 -424.223889)
			(xy 98.824179 -424.270402) (xy 98.847851 -424.320899) (xy 98.863919 -424.374306) (xy 98.872039 -424.429482)
			(xy 98.872548 -424.457368) (xy 98.872039 -424.485254) (xy 98.863919 -424.54043) (xy 98.847851 -424.593837)
			(xy 98.834072 -424.62323) (xy 101.788466 -424.62323) (xy 101.792537 -424.567608) (xy 101.804663 -424.513171)
			(xy 101.824586 -424.46108) (xy 101.851882 -424.412445) (xy 101.885968 -424.368302) (xy 101.926117 -424.329593)
			(xy 101.971475 -424.297142) (xy 102.021075 -424.271641) (xy 102.073859 -424.253634) (xy 102.128702 -424.243504)
			(xy 102.184436 -424.241467) (xy 102.189062 -424.241976) (xy 103.81742 -424.241976) (xy 103.817906 -424.214725)
			(xy 103.825662 -424.160777) (xy 103.841017 -424.108482) (xy 103.863659 -424.058905) (xy 103.893125 -424.013055)
			(xy 103.928816 -423.971864) (xy 103.970007 -423.936173) (xy 104.015857 -423.906707) (xy 104.065434 -423.884065)
			(xy 104.117729 -423.86871) (xy 104.171677 -423.860954) (xy 104.226179 -423.860954) (xy 104.280127 -423.86871)
			(xy 104.332422 -423.884065) (xy 104.381999 -423.906707) (xy 104.427849 -423.936173) (xy 104.46904 -423.971864)
			(xy 104.504731 -424.013055) (xy 104.534197 -424.058905) (xy 104.556839 -424.108482) (xy 104.572194 -424.160777)
			(xy 104.57995 -424.214725) (xy 104.580436 -424.241976) (xy 104.579957 -424.268576) (xy 104.572584 -424.321262)
			(xy 104.557965 -424.372414) (xy 104.536383 -424.421039) (xy 104.508256 -424.466195) (xy 104.474129 -424.507006)
			(xy 104.454706 -424.525186) (xy 104.444427 -424.535077) (xy 104.429413 -424.559324) (xy 104.421681 -424.586775)
			(xy 104.421832 -424.615293) (xy 104.429853 -424.64266) (xy 104.445121 -424.666747) (xy 104.455468 -424.67657)
			(xy 104.475422 -424.694749) (xy 104.510483 -424.735792) (xy 104.53941 -424.781365) (xy 104.561625 -424.830561)
			(xy 104.576685 -424.882397) (xy 104.584289 -424.935838) (xy 104.584754 -424.962828) (xy 104.584268 -424.990079)
			(xy 104.576512 -425.044027) (xy 104.561157 -425.096322) (xy 104.538515 -425.145899) (xy 104.509049 -425.191749)
			(xy 104.473358 -425.23294) (xy 104.432167 -425.268631) (xy 104.386317 -425.298097) (xy 104.33674 -425.320739)
			(xy 104.284445 -425.336094) (xy 104.230497 -425.34385) (xy 104.175995 -425.34385) (xy 104.122047 -425.336094)
			(xy 104.069752 -425.320739) (xy 104.020175 -425.298097) (xy 103.974325 -425.268631) (xy 103.933134 -425.23294)
			(xy 103.897443 -425.191749) (xy 103.867977 -425.145899) (xy 103.845335 -425.096322) (xy 103.82998 -425.044027)
			(xy 103.822224 -424.990079) (xy 103.821738 -424.962828) (xy 103.822228 -424.936229) (xy 103.8296 -424.883543)
			(xy 103.844217 -424.832392) (xy 103.865797 -424.783767) (xy 103.893922 -424.738611) (xy 103.928046 -424.697799)
			(xy 103.947468 -424.679618) (xy 103.957746 -424.669724) (xy 103.972763 -424.645479) (xy 103.980498 -424.618028)
			(xy 103.980348 -424.58951) (xy 103.972326 -424.562142) (xy 103.957055 -424.538055) (xy 103.946706 -424.528234)
			(xy 103.926749 -424.510058) (xy 103.891689 -424.469015) (xy 103.862763 -424.42344) (xy 103.840549 -424.374243)
			(xy 103.825489 -424.322407) (xy 103.817885 -424.268966) (xy 103.81742 -424.241976) (xy 102.189062 -424.241976)
			(xy 102.239873 -424.247567) (xy 102.29383 -424.261673) (xy 102.345159 -424.283485) (xy 102.392765 -424.312539)
			(xy 102.435633 -424.348214) (xy 102.47285 -424.389751) (xy 102.503623 -424.436264) (xy 102.527295 -424.486761)
			(xy 102.543363 -424.540168) (xy 102.551483 -424.595344) (xy 102.551992 -424.62323) (xy 102.551483 -424.651116)
			(xy 102.543363 -424.706292) (xy 102.527295 -424.759699) (xy 102.503623 -424.810196) (xy 102.47285 -424.856709)
			(xy 102.435633 -424.898246) (xy 102.392765 -424.933921) (xy 102.345159 -424.962975) (xy 102.29383 -424.984787)
			(xy 102.239873 -424.998893) (xy 102.184436 -425.004993) (xy 102.128702 -425.002956) (xy 102.073859 -424.992826)
			(xy 102.021075 -424.974819) (xy 101.971475 -424.949318) (xy 101.926117 -424.916867) (xy 101.885968 -424.878158)
			(xy 101.851882 -424.834015) (xy 101.824586 -424.78538) (xy 101.804663 -424.733289) (xy 101.792537 -424.678852)
			(xy 101.788466 -424.62323) (xy 98.834072 -424.62323) (xy 98.824179 -424.644334) (xy 98.793406 -424.690847)
			(xy 98.756189 -424.732384) (xy 98.713321 -424.768059) (xy 98.665715 -424.797113) (xy 98.614386 -424.818925)
			(xy 98.560429 -424.833031) (xy 98.504992 -424.839131) (xy 98.449258 -424.837094) (xy 98.394415 -424.826964)
			(xy 98.341631 -424.808957) (xy 98.292031 -424.783456) (xy 98.246673 -424.751005) (xy 98.206524 -424.712296)
			(xy 98.172438 -424.668153) (xy 98.145142 -424.619518) (xy 98.125219 -424.567427) (xy 98.113093 -424.51299)
			(xy 98.109022 -424.457368) (xy 93.2434 -424.457368) (xy 93.2434 -425.65828) (xy 93.759272 -425.65828)
			(xy 93.763343 -425.602658) (xy 93.775469 -425.548221) (xy 93.795392 -425.49613) (xy 93.822688 -425.447495)
			(xy 93.856774 -425.403352) (xy 93.896923 -425.364643) (xy 93.942281 -425.332192) (xy 93.991881 -425.306691)
			(xy 94.044665 -425.288684) (xy 94.099508 -425.278554) (xy 94.155242 -425.276517) (xy 94.210679 -425.282617)
			(xy 94.264636 -425.296723) (xy 94.315965 -425.318535) (xy 94.363571 -425.347589) (xy 94.406439 -425.383264)
			(xy 94.42618 -425.405296) (xy 96.409254 -425.405296) (xy 96.413325 -425.349674) (xy 96.425451 -425.295237)
			(xy 96.445374 -425.243146) (xy 96.47267 -425.194511) (xy 96.506756 -425.150368) (xy 96.546905 -425.111659)
			(xy 96.592263 -425.079208) (xy 96.641863 -425.053707) (xy 96.694647 -425.0357) (xy 96.74949 -425.02557)
			(xy 96.805224 -425.023533) (xy 96.860661 -425.029633) (xy 96.914618 -425.043739) (xy 96.965947 -425.065551)
			(xy 97.013553 -425.094605) (xy 97.03223 -425.110148) (xy 100.411278 -425.110148) (xy 100.415349 -425.054526)
			(xy 100.427475 -425.000089) (xy 100.447398 -424.947998) (xy 100.474694 -424.899363) (xy 100.50878 -424.85522)
			(xy 100.548929 -424.816511) (xy 100.594287 -424.78406) (xy 100.643887 -424.758559) (xy 100.696671 -424.740552)
			(xy 100.751514 -424.730422) (xy 100.807248 -424.728385) (xy 100.862685 -424.734485) (xy 100.916642 -424.748591)
			(xy 100.967971 -424.770403) (xy 101.015577 -424.799457) (xy 101.058445 -424.835132) (xy 101.095662 -424.876669)
			(xy 101.126435 -424.923182) (xy 101.150107 -424.973679) (xy 101.166175 -425.027086) (xy 101.174295 -425.082262)
			(xy 101.174804 -425.110148) (xy 101.174295 -425.138034) (xy 101.166175 -425.19321) (xy 101.150107 -425.246617)
			(xy 101.126435 -425.297114) (xy 101.095662 -425.343627) (xy 101.058445 -425.385164) (xy 101.015577 -425.420839)
			(xy 100.967971 -425.449893) (xy 100.916642 -425.471705) (xy 100.862685 -425.485811) (xy 100.807248 -425.491911)
			(xy 100.751514 -425.489874) (xy 100.696671 -425.479744) (xy 100.643887 -425.461737) (xy 100.594287 -425.436236)
			(xy 100.548929 -425.403785) (xy 100.50878 -425.365076) (xy 100.474694 -425.320933) (xy 100.447398 -425.272298)
			(xy 100.427475 -425.220207) (xy 100.415349 -425.16577) (xy 100.411278 -425.110148) (xy 97.03223 -425.110148)
			(xy 97.056421 -425.13028) (xy 97.093638 -425.171817) (xy 97.124411 -425.21833) (xy 97.148083 -425.268827)
			(xy 97.164151 -425.322234) (xy 97.172271 -425.37741) (xy 97.17278 -425.405296) (xy 97.172271 -425.433182)
			(xy 97.164151 -425.488358) (xy 97.148083 -425.541765) (xy 97.124411 -425.592262) (xy 97.093638 -425.638775)
			(xy 97.056421 -425.680312) (xy 97.013553 -425.715987) (xy 96.965947 -425.745041) (xy 96.914618 -425.766853)
			(xy 96.860661 -425.780959) (xy 96.805224 -425.787059) (xy 96.74949 -425.785022) (xy 96.694647 -425.774892)
			(xy 96.641863 -425.756885) (xy 96.592263 -425.731384) (xy 96.546905 -425.698933) (xy 96.506756 -425.660224)
			(xy 96.47267 -425.616081) (xy 96.445374 -425.567446) (xy 96.425451 -425.515355) (xy 96.413325 -425.460918)
			(xy 96.409254 -425.405296) (xy 94.42618 -425.405296) (xy 94.443656 -425.424801) (xy 94.474429 -425.471314)
			(xy 94.498101 -425.521811) (xy 94.514169 -425.575218) (xy 94.522289 -425.630394) (xy 94.522798 -425.65828)
			(xy 94.522289 -425.686166) (xy 94.514169 -425.741342) (xy 94.498101 -425.794749) (xy 94.485632 -425.821348)
			(xy 94.977202 -425.821348) (xy 94.981273 -425.765726) (xy 94.993399 -425.711289) (xy 95.013322 -425.659198)
			(xy 95.040618 -425.610563) (xy 95.074704 -425.56642) (xy 95.114853 -425.527711) (xy 95.160211 -425.49526)
			(xy 95.209811 -425.469759) (xy 95.262595 -425.451752) (xy 95.317438 -425.441622) (xy 95.373172 -425.439585)
			(xy 95.428609 -425.445685) (xy 95.482566 -425.459791) (xy 95.533895 -425.481603) (xy 95.581501 -425.510657)
			(xy 95.624369 -425.546332) (xy 95.661586 -425.587869) (xy 95.692359 -425.634382) (xy 95.716031 -425.684879)
			(xy 95.732099 -425.738286) (xy 95.740219 -425.793462) (xy 95.740728 -425.821348) (xy 95.740219 -425.849234)
			(xy 95.732099 -425.90441) (xy 95.716031 -425.957817) (xy 95.692359 -426.008314) (xy 95.661586 -426.054827)
			(xy 95.624369 -426.096364) (xy 95.581501 -426.132039) (xy 95.533895 -426.161093) (xy 95.482566 -426.182905)
			(xy 95.428609 -426.197011) (xy 95.373172 -426.203111) (xy 95.317438 -426.201074) (xy 95.262595 -426.190944)
			(xy 95.209811 -426.172937) (xy 95.160211 -426.147436) (xy 95.114853 -426.114985) (xy 95.074704 -426.076276)
			(xy 95.040618 -426.032133) (xy 95.013322 -425.983498) (xy 94.993399 -425.931407) (xy 94.981273 -425.87697)
			(xy 94.977202 -425.821348) (xy 94.485632 -425.821348) (xy 94.474429 -425.845246) (xy 94.443656 -425.891759)
			(xy 94.406439 -425.933296) (xy 94.363571 -425.968971) (xy 94.315965 -425.998025) (xy 94.264636 -426.019837)
			(xy 94.210679 -426.033943) (xy 94.155242 -426.040043) (xy 94.099508 -426.038006) (xy 94.044665 -426.027876)
			(xy 93.991881 -426.009869) (xy 93.942281 -425.984368) (xy 93.896923 -425.951917) (xy 93.856774 -425.913208)
			(xy 93.822688 -425.869065) (xy 93.795392 -425.82043) (xy 93.775469 -425.768339) (xy 93.763343 -425.713902)
			(xy 93.759272 -425.65828) (xy 93.2434 -425.65828) (xy 93.2434 -427.4566) (xy 93.420692 -427.4566)
			(xy 93.42116 -427.42923) (xy 93.428978 -427.375051) (xy 93.444466 -427.322548) (xy 93.467308 -427.272801)
			(xy 93.497031 -427.226834) (xy 93.514672 -427.205902) (xy 93.523911 -427.194576) (xy 93.536092 -427.168018)
			(xy 93.540266 -427.1391) (xy 93.536092 -427.110182) (xy 93.523911 -427.083624) (xy 93.514672 -427.072298)
			(xy 93.497014 -427.051381) (xy 93.467306 -427.005404) (xy 93.444474 -426.955652) (xy 93.428987 -426.903148)
			(xy 93.421164 -426.84897) (xy 93.420692 -426.8216) (xy 93.421178 -426.794349) (xy 93.428934 -426.740401)
			(xy 93.444289 -426.688106) (xy 93.466931 -426.638529) (xy 93.496397 -426.592679) (xy 93.532088 -426.551488)
			(xy 93.573279 -426.515797) (xy 93.619129 -426.486331) (xy 93.668706 -426.463689) (xy 93.721001 -426.448334)
			(xy 93.774949 -426.440578) (xy 93.829451 -426.440578) (xy 93.883399 -426.448334) (xy 93.935694 -426.463689)
			(xy 93.985271 -426.486331) (xy 94.031121 -426.515797) (xy 94.072312 -426.551488) (xy 94.108003 -426.592679)
			(xy 94.137469 -426.638529) (xy 94.160111 -426.688106) (xy 94.175466 -426.740401) (xy 94.183222 -426.794349)
			(xy 94.183708 -426.8216) (xy 94.183248 -426.847836) (xy 94.176053 -426.899811) (xy 94.161798 -426.95031)
			(xy 94.140754 -426.998376) (xy 94.113318 -427.043103) (xy 94.080007 -427.083645) (xy 94.061026 -427.101762)
			(xy 94.053658 -427.109292) (xy 94.045232 -427.128577) (xy 94.045232 -427.149623) (xy 94.053658 -427.168908)
			(xy 94.061026 -427.176438) (xy 94.079314 -427.194472) (xy 94.086087 -427.201152) (xy 94.103269 -427.209295)
			(xy 94.122235 -427.210631) (xy 94.140389 -427.204978) (xy 94.155243 -427.193109) (xy 94.16034 -427.185074)
			(xy 94.175074 -427.160673) (xy 94.210657 -427.116146) (xy 94.252472 -427.077413) (xy 94.299587 -427.045336)
			(xy 94.350953 -427.02063) (xy 94.405424 -427.003847) (xy 94.461787 -426.99536) (xy 94.490286 -426.994828)
			(xy 94.517542 -426.995218) (xy 94.5715 -427.002974) (xy 94.623804 -427.01833) (xy 94.673391 -427.040974)
			(xy 94.71925 -427.070445) (xy 94.760448 -427.106142) (xy 94.796147 -427.147339) (xy 94.825619 -427.193197)
			(xy 94.848265 -427.242783) (xy 94.863623 -427.295087) (xy 94.871381 -427.349044) (xy 94.871381 -427.403556)
			(xy 94.864996 -427.447964) (xy 97.871278 -427.447964) (xy 97.875349 -427.392342) (xy 97.887475 -427.337905)
			(xy 97.907398 -427.285814) (xy 97.934694 -427.237179) (xy 97.96878 -427.193036) (xy 98.008929 -427.154327)
			(xy 98.054287 -427.121876) (xy 98.103887 -427.096375) (xy 98.156671 -427.078368) (xy 98.211514 -427.068238)
			(xy 98.267248 -427.066201) (xy 98.322685 -427.072301) (xy 98.376642 -427.086407) (xy 98.427971 -427.108219)
			(xy 98.475577 -427.137273) (xy 98.518445 -427.172948) (xy 98.555662 -427.214485) (xy 98.586435 -427.260998)
			(xy 98.610107 -427.311495) (xy 98.626175 -427.364902) (xy 98.634295 -427.420078) (xy 98.634804 -427.447964)
			(xy 98.634295 -427.47585) (xy 98.626175 -427.531026) (xy 98.610107 -427.584433) (xy 98.586435 -427.63493)
			(xy 98.555662 -427.681443) (xy 98.518445 -427.72298) (xy 98.475577 -427.758655) (xy 98.427971 -427.787709)
			(xy 98.376642 -427.809521) (xy 98.322685 -427.823627) (xy 98.267248 -427.829727) (xy 98.211514 -427.82769)
			(xy 98.156671 -427.81756) (xy 98.103887 -427.799553) (xy 98.054287 -427.774052) (xy 98.008929 -427.741601)
			(xy 97.96878 -427.702892) (xy 97.934694 -427.658749) (xy 97.907398 -427.610114) (xy 97.887475 -427.558023)
			(xy 97.875349 -427.503586) (xy 97.871278 -427.447964) (xy 94.864996 -427.447964) (xy 94.863623 -427.457513)
			(xy 94.848265 -427.509817) (xy 94.825619 -427.559403) (xy 94.796147 -427.605261) (xy 94.760448 -427.646458)
			(xy 94.71925 -427.682155) (xy 94.673391 -427.711626) (xy 94.623804 -427.73427) (xy 94.5715 -427.749626)
			(xy 94.517542 -427.757382) (xy 94.490286 -427.757844) (xy 94.464216 -427.757413) (xy 94.412561 -427.750311)
			(xy 94.362355 -427.736241) (xy 94.314532 -427.715465) (xy 94.269984 -427.688371) (xy 94.249494 -427.672246)
			(xy 94.238748 -427.66395) (xy 94.213936 -427.652948) (xy 94.187103 -427.648868) (xy 94.160142 -427.651998)
			(xy 94.134957 -427.662119) (xy 94.113327 -427.678514) (xy 94.104714 -427.68901) (xy 94.086526 -427.711766)
			(xy 94.044434 -427.752035) (xy 93.996709 -427.785435) (xy 93.944459 -427.811189) (xy 93.888901 -427.828699)
			(xy 93.831326 -427.837557) (xy 93.8022 -427.838108) (xy 93.774949 -427.837622) (xy 93.721001 -427.829866)
			(xy 93.668706 -427.814511) (xy 93.619129 -427.791869) (xy 93.573279 -427.762403) (xy 93.532088 -427.726712)
			(xy 93.496397 -427.685521) (xy 93.466931 -427.639671) (xy 93.444289 -427.590094) (xy 93.428934 -427.537799)
			(xy 93.421178 -427.483851) (xy 93.420692 -427.4566) (xy 93.2434 -427.4566) (xy 93.2434 -428.625)
			(xy 93.421708 -428.803308) (xy 94.441262 -428.803308) (xy 94.445333 -428.747686) (xy 94.457459 -428.693249)
			(xy 94.477382 -428.641158) (xy 94.504678 -428.592523) (xy 94.538764 -428.54838) (xy 94.578913 -428.509671)
			(xy 94.624271 -428.47722) (xy 94.673871 -428.451719) (xy 94.726655 -428.433712) (xy 94.781498 -428.423582)
			(xy 94.837232 -428.421545) (xy 94.892669 -428.427645) (xy 94.946626 -428.441751) (xy 94.997955 -428.463563)
			(xy 95.045561 -428.492617) (xy 95.088429 -428.528292) (xy 95.125646 -428.569829) (xy 95.156419 -428.616342)
			(xy 95.180091 -428.666839) (xy 95.196159 -428.720246) (xy 95.204279 -428.775422) (xy 95.204788 -428.803308)
			(xy 95.204279 -428.831194) (xy 95.196159 -428.88637) (xy 95.180091 -428.939777) (xy 95.156419 -428.990274)
			(xy 95.125646 -429.036787) (xy 95.088429 -429.078324) (xy 95.045561 -429.113999) (xy 94.997955 -429.143053)
			(xy 94.946626 -429.164865) (xy 94.892669 -429.178971) (xy 94.837232 -429.185071) (xy 94.781498 -429.183034)
			(xy 94.726655 -429.172904) (xy 94.673871 -429.154897) (xy 94.624271 -429.129396) (xy 94.578913 -429.096945)
			(xy 94.538764 -429.058236) (xy 94.504678 -429.014093) (xy 94.477382 -428.965458) (xy 94.457459 -428.913367)
			(xy 94.445333 -428.85893) (xy 94.441262 -428.803308) (xy 93.421708 -428.803308) (xy 94.12986 -429.51146)
			(xy 103.9495 -429.51146)
		)
		(stroke
			(width 0)
			(type solid)
		)
		(fill yes)
		(layer "In4.Cu")
		(net "P3V3_AUX")
	)
	(gr_poly
		(pts
			(xy 55.483506 -366.872012) (xy 55.465218 -366.846612) (xy 55.448499 -366.822391) (xy 55.421921 -366.769881)
			(xy 55.403718 -366.713914) (xy 55.39432 -366.655816) (xy 55.39359 -366.626394) (xy 55.39359 -366.619282)
			(xy 55.394402 -366.592256) (xy 55.402712 -366.538829) (xy 55.418481 -366.487111) (xy 55.441393 -366.438138)
			(xy 55.47099 -366.392889) (xy 55.506679 -366.352272) (xy 55.547744 -366.3171) (xy 55.593363 -366.288078)
			(xy 55.642623 -366.265787) (xy 55.694537 -366.250673) (xy 55.748064 -366.24304) (xy 55.802132 -366.24304)
			(xy 55.855659 -366.250673) (xy 55.907573 -366.265787) (xy 55.956833 -366.288078) (xy 56.002452 -366.3171)
			(xy 56.043517 -366.352272) (xy 56.079206 -366.392889) (xy 56.108803 -366.438138) (xy 56.131715 -366.487111)
			(xy 56.147484 -366.538829) (xy 56.155794 -366.592256) (xy 56.156606 -366.619282) (xy 56.156606 -366.624362)
			(xy 56.15602 -366.654041) (xy 56.146781 -366.712678) (xy 56.128567 -366.769174) (xy 56.101819 -366.822165)
			(xy 56.084978 -366.846612) (xy 56.06669 -366.872012) (xy 56.136286 -367.007648) (xy 56.6928 -367.007648)
			(xy 57.861708 -365.83874) (xy 57.861708 -362.455968) (xy 56.419496 -333.99349) (xy 35.595814 -333.99349)
			(xy 34.902394 -334.68691) (xy 34.902394 -335.51361) (xy 39.617392 -335.51361) (xy 39.617392 -335.428914)
			(xy 39.625443 -335.3446) (xy 39.641472 -335.261434) (xy 39.665333 -335.180167) (xy 39.696812 -335.101537)
			(xy 39.735623 -335.026256) (xy 39.781413 -334.955004) (xy 39.833769 -334.888428) (xy 39.892217 -334.82713)
			(xy 39.956227 -334.771665) (xy 40.025219 -334.722536) (xy 40.098569 -334.680187) (xy 40.175612 -334.645003)
			(xy 40.255651 -334.617301) (xy 40.33796 -334.597333) (xy 40.421795 -334.58528) (xy 40.506396 -334.58125)
			(xy 40.590997 -334.58528) (xy 40.674832 -334.597333) (xy 40.757141 -334.617301) (xy 40.83718 -334.645003)
			(xy 40.914223 -334.680187) (xy 40.987573 -334.722536) (xy 41.056565 -334.771665) (xy 41.120575 -334.82713)
			(xy 41.179023 -334.888428) (xy 41.231379 -334.955004) (xy 41.277169 -335.026256) (xy 41.31598 -335.101537)
			(xy 41.347459 -335.180167) (xy 41.37132 -335.261434) (xy 41.387349 -335.3446) (xy 41.3954 -335.428914)
			(xy 41.395904 -335.471262) (xy 41.3954 -335.51361) (xy 41.394794 -335.51996) (xy 45.808134 -335.51996)
			(xy 45.808134 -335.435264) (xy 45.816185 -335.35095) (xy 45.832214 -335.267784) (xy 45.856075 -335.186517)
			(xy 45.887554 -335.107887) (xy 45.926365 -335.032606) (xy 45.972155 -334.961354) (xy 46.024511 -334.894778)
			(xy 46.082959 -334.83348) (xy 46.146969 -334.778015) (xy 46.215961 -334.728886) (xy 46.289311 -334.686537)
			(xy 46.366354 -334.651353) (xy 46.446393 -334.623651) (xy 46.528702 -334.603683) (xy 46.612537 -334.59163)
			(xy 46.697138 -334.5876) (xy 46.781739 -334.59163) (xy 46.865574 -334.603683) (xy 46.947883 -334.623651)
			(xy 47.027922 -334.651353) (xy 47.104965 -334.686537) (xy 47.178315 -334.728886) (xy 47.247307 -334.778015)
			(xy 47.311317 -334.83348) (xy 47.369765 -334.894778) (xy 47.422121 -334.961354) (xy 47.467911 -335.032606)
			(xy 47.506722 -335.107887) (xy 47.538201 -335.186517) (xy 47.562062 -335.267784) (xy 47.578091 -335.35095)
			(xy 47.586142 -335.435264) (xy 47.586646 -335.477612) (xy 47.586142 -335.51996) (xy 52.005734 -335.51996)
			(xy 52.005734 -335.435264) (xy 52.013785 -335.35095) (xy 52.029814 -335.267784) (xy 52.053675 -335.186517)
			(xy 52.085154 -335.107887) (xy 52.123965 -335.032606) (xy 52.169755 -334.961354) (xy 52.222111 -334.894778)
			(xy 52.280559 -334.83348) (xy 52.344569 -334.778015) (xy 52.413561 -334.728886) (xy 52.486911 -334.686537)
			(xy 52.563954 -334.651353) (xy 52.643993 -334.623651) (xy 52.726302 -334.603683) (xy 52.810137 -334.59163)
			(xy 52.894738 -334.5876) (xy 52.979339 -334.59163) (xy 53.063174 -334.603683) (xy 53.145483 -334.623651)
			(xy 53.225522 -334.651353) (xy 53.302565 -334.686537) (xy 53.375915 -334.728886) (xy 53.444907 -334.778015)
			(xy 53.508917 -334.83348) (xy 53.567365 -334.894778) (xy 53.619721 -334.961354) (xy 53.665511 -335.032606)
			(xy 53.704322 -335.107887) (xy 53.735801 -335.186517) (xy 53.759662 -335.267784) (xy 53.775691 -335.35095)
			(xy 53.783742 -335.435264) (xy 53.784246 -335.477612) (xy 53.783742 -335.51996) (xy 53.775691 -335.604274)
			(xy 53.759662 -335.68744) (xy 53.735801 -335.768707) (xy 53.704322 -335.847337) (xy 53.665511 -335.922618)
			(xy 53.619721 -335.99387) (xy 53.567365 -336.060446) (xy 53.508917 -336.121744) (xy 53.444907 -336.177209)
			(xy 53.375915 -336.226338) (xy 53.302565 -336.268687) (xy 53.225522 -336.303871) (xy 53.145483 -336.331573)
			(xy 53.063174 -336.351541) (xy 52.979339 -336.363594) (xy 52.894738 -336.367625) (xy 52.810137 -336.363594)
			(xy 52.726302 -336.351541) (xy 52.643993 -336.331573) (xy 52.563954 -336.303871) (xy 52.486911 -336.268687)
			(xy 52.413561 -336.226338) (xy 52.344569 -336.177209) (xy 52.280559 -336.121744) (xy 52.222111 -336.060446)
			(xy 52.169755 -335.99387) (xy 52.123965 -335.922618) (xy 52.085154 -335.847337) (xy 52.053675 -335.768707)
			(xy 52.029814 -335.68744) (xy 52.013785 -335.604274) (xy 52.005734 -335.51996) (xy 47.586142 -335.51996)
			(xy 47.578091 -335.604274) (xy 47.562062 -335.68744) (xy 47.538201 -335.768707) (xy 47.506722 -335.847337)
			(xy 47.467911 -335.922618) (xy 47.422121 -335.99387) (xy 47.369765 -336.060446) (xy 47.311317 -336.121744)
			(xy 47.247307 -336.177209) (xy 47.178315 -336.226338) (xy 47.104965 -336.268687) (xy 47.027922 -336.303871)
			(xy 46.947883 -336.331573) (xy 46.865574 -336.351541) (xy 46.781739 -336.363594) (xy 46.697138 -336.367625)
			(xy 46.612537 -336.363594) (xy 46.528702 -336.351541) (xy 46.446393 -336.331573) (xy 46.366354 -336.303871)
			(xy 46.289311 -336.268687) (xy 46.215961 -336.226338) (xy 46.146969 -336.177209) (xy 46.082959 -336.121744)
			(xy 46.024511 -336.060446) (xy 45.972155 -335.99387) (xy 45.926365 -335.922618) (xy 45.887554 -335.847337)
			(xy 45.856075 -335.768707) (xy 45.832214 -335.68744) (xy 45.816185 -335.604274) (xy 45.808134 -335.51996)
			(xy 41.394794 -335.51996) (xy 41.387349 -335.597924) (xy 41.37132 -335.68109) (xy 41.347459 -335.762357)
			(xy 41.31598 -335.840987) (xy 41.277169 -335.916268) (xy 41.231379 -335.98752) (xy 41.179023 -336.054096)
			(xy 41.120575 -336.115394) (xy 41.056565 -336.170859) (xy 40.987573 -336.219988) (xy 40.914223 -336.262337)
			(xy 40.83718 -336.297521) (xy 40.757141 -336.325223) (xy 40.674832 -336.345191) (xy 40.590997 -336.357244)
			(xy 40.506396 -336.361275) (xy 40.421795 -336.357244) (xy 40.33796 -336.345191) (xy 40.255651 -336.325223)
			(xy 40.175612 -336.297521) (xy 40.098569 -336.262337) (xy 40.025219 -336.219988) (xy 39.956227 -336.170859)
			(xy 39.892217 -336.115394) (xy 39.833769 -336.054096) (xy 39.781413 -335.98752) (xy 39.735623 -335.916268)
			(xy 39.696812 -335.840987) (xy 39.665333 -335.762357) (xy 39.641472 -335.68109) (xy 39.625443 -335.597924)
			(xy 39.617392 -335.51361) (xy 34.902394 -335.51361) (xy 34.902394 -337.471258) (xy 39.590985 -337.471258)
			(xy 39.595007 -337.385538) (xy 39.607038 -337.30057) (xy 39.626974 -337.217103) (xy 39.654637 -337.135869)
			(xy 39.689786 -337.057583) (xy 39.732112 -336.982932) (xy 39.781241 -336.912573) (xy 39.836744 -336.847123)
			(xy 39.898131 -336.787159) (xy 39.964864 -336.733206) (xy 40.036356 -336.685739) (xy 40.111978 -336.645175)
			(xy 40.191067 -336.611871) (xy 40.272927 -336.586119) (xy 40.356838 -336.568146) (xy 40.442064 -336.55811)
			(xy 40.527856 -336.556098) (xy 40.613458 -336.562129) (xy 40.69812 -336.576149) (xy 40.781097 -336.598035)
			(xy 40.86166 -336.627596) (xy 40.9391 -336.66457) (xy 41.012739 -336.708634) (xy 41.081927 -336.7594)
			(xy 41.146058 -336.816421) (xy 41.204567 -336.879197) (xy 41.25694 -336.947177) (xy 41.302718 -337.019762)
			(xy 41.341498 -337.096314) (xy 41.372939 -337.176162) (xy 41.396765 -337.258603) (xy 41.412766 -337.342913)
			(xy 41.420801 -337.428351) (xy 41.421304 -337.471258) (xy 41.42123 -337.477608) (xy 45.781727 -337.477608)
			(xy 45.785749 -337.391888) (xy 45.79778 -337.30692) (xy 45.817716 -337.223453) (xy 45.845379 -337.142219)
			(xy 45.880528 -337.063933) (xy 45.922854 -336.989282) (xy 45.971983 -336.918923) (xy 46.027486 -336.853473)
			(xy 46.088873 -336.793509) (xy 46.155606 -336.739556) (xy 46.227098 -336.692089) (xy 46.30272 -336.651525)
			(xy 46.381809 -336.618221) (xy 46.463669 -336.592469) (xy 46.54758 -336.574496) (xy 46.632806 -336.56446)
			(xy 46.718598 -336.562448) (xy 46.8042 -336.568479) (xy 46.888862 -336.582499) (xy 46.971839 -336.604385)
			(xy 47.052402 -336.633946) (xy 47.129842 -336.67092) (xy 47.203481 -336.714984) (xy 47.272669 -336.76575)
			(xy 47.3368 -336.822771) (xy 47.395309 -336.885547) (xy 47.447682 -336.953527) (xy 47.49346 -337.026112)
			(xy 47.53224 -337.102664) (xy 47.563681 -337.182512) (xy 47.587507 -337.264953) (xy 47.603508 -337.349263)
			(xy 47.611543 -337.434701) (xy 47.612046 -337.477608) (xy 51.97983 -337.477608) (xy 51.980318 -337.435332)
			(xy 51.98812 -337.35114) (xy 52.003656 -337.268027) (xy 52.026795 -337.186703) (xy 52.057339 -337.10786)
			(xy 52.095027 -337.032172) (xy 52.139538 -336.960284) (xy 52.190492 -336.89281) (xy 52.247455 -336.830325)
			(xy 52.30994 -336.773362) (xy 52.377414 -336.722408) (xy 52.449302 -336.677897) (xy 52.52499 -336.640209)
			(xy 52.603833 -336.609665) (xy 52.685157 -336.586526) (xy 52.76827 -336.57099) (xy 52.852462 -336.563188)
			(xy 52.937014 -336.563188) (xy 53.021206 -336.57099) (xy 53.104319 -336.586526) (xy 53.185643 -336.609665)
			(xy 53.264486 -336.640209) (xy 53.340174 -336.677897) (xy 53.412062 -336.722408) (xy 53.479536 -336.773362)
			(xy 53.542021 -336.830325) (xy 53.598984 -336.89281) (xy 53.649938 -336.960284) (xy 53.694449 -337.032172)
			(xy 53.732137 -337.10786) (xy 53.762681 -337.186703) (xy 53.78582 -337.268027) (xy 53.801356 -337.35114)
			(xy 53.809158 -337.435332) (xy 53.809646 -337.477608) (xy 53.809142 -337.519569) (xy 53.801456 -337.603139)
			(xy 53.786148 -337.685654) (xy 53.763347 -337.766421) (xy 53.733246 -337.844759) (xy 53.696097 -337.920012)
			(xy 53.652212 -337.991547) (xy 53.60196 -338.058761) (xy 53.545764 -338.121091) (xy 53.484096 -338.178013)
			(xy 53.417474 -338.229047) (xy 53.346458 -338.273766) (xy 53.309266 -338.293202) (xy 53.296167 -338.300524)
			(xy 53.274558 -338.321321) (xy 53.259912 -338.347494) (xy 53.25349 -338.37679) (xy 53.255844 -338.406689)
			(xy 53.266772 -338.434619) (xy 53.285333 -338.458177) (xy 53.297328 -338.467192) (xy 53.308811 -338.475301)
			(xy 53.330676 -338.492974) (xy 53.341016 -338.502498) (xy 53.35255 -338.51257) (xy 53.380096 -338.525912)
			(xy 53.410358 -338.530497) (xy 53.44062 -338.525912) (xy 53.468166 -338.51257) (xy 53.4797 -338.502498)
			(xy 53.501027 -338.483228) (xy 53.54839 -338.450663) (xy 53.600101 -338.425572) (xy 53.654992 -338.408522)
			(xy 53.711819 -338.3999) (xy 53.769297 -338.3999) (xy 53.826124 -338.408522) (xy 53.881015 -338.425572)
			(xy 53.932726 -338.450663) (xy 53.980089 -338.483228) (xy 54.001416 -338.502498) (xy 54.01295 -338.51257)
			(xy 54.040496 -338.525912) (xy 54.070758 -338.530497) (xy 54.10102 -338.525912) (xy 54.128566 -338.51257)
			(xy 54.1401 -338.502498) (xy 54.161412 -338.48321) (xy 54.208777 -338.450644) (xy 54.260493 -338.425554)
			(xy 54.315387 -338.408508) (xy 54.372218 -338.399891) (xy 54.400958 -338.399374) (xy 54.428209 -338.399894)
			(xy 54.482157 -338.407645) (xy 54.534453 -338.422995) (xy 54.584031 -338.445631) (xy 54.629884 -338.475093)
			(xy 54.671077 -338.510781) (xy 54.706771 -338.551968) (xy 54.73624 -338.597816) (xy 54.758884 -338.647391)
			(xy 54.774242 -338.699684) (xy 54.782001 -338.753631) (xy 54.782466 -338.780882) (xy 54.781914 -338.80962)
			(xy 54.773295 -338.866445) (xy 54.756251 -338.921335) (xy 54.731166 -338.973047) (xy 54.698609 -339.020411)
			(xy 54.679342 -339.04174) (xy 54.669287 -339.053288) (xy 54.655941 -339.080829) (xy 54.651353 -339.111087)
			(xy 54.655934 -339.141346) (xy 54.669272 -339.16889) (xy 54.679342 -339.180424) (xy 54.698601 -339.201761)
			(xy 54.73117 -339.24912) (xy 54.756265 -339.300829) (xy 54.773318 -339.355718) (xy 54.781944 -339.412544)
			(xy 54.782466 -339.441282) (xy 54.782015 -339.468272) (xy 54.774408 -339.521712) (xy 54.759344 -339.573547)
			(xy 54.737124 -339.622741) (xy 54.70819 -339.668311) (xy 54.673122 -339.709347) (xy 54.65318 -339.72754)
			(xy 54.642465 -339.737466) (xy 54.626852 -339.762143) (xy 54.618868 -339.790231) (xy 54.619166 -339.819431)
			(xy 54.627722 -339.84735) (xy 54.643835 -339.871703) (xy 54.654704 -339.881464) (xy 54.675503 -339.899686)
			(xy 54.712176 -339.941068) (xy 54.742483 -339.987316) (xy 54.765788 -340.037458) (xy 54.781602 -340.090442)
			(xy 54.789593 -340.145155) (xy 54.790086 -340.172802) (xy 54.789559 -340.202244) (xy 54.780511 -340.26043)
			(xy 54.76263 -340.316534) (xy 54.736341 -340.369224) (xy 54.702268 -340.417249) (xy 54.682136 -340.43874)
			(xy 54.671747 -340.450216) (xy 54.657858 -340.477865) (xy 54.652857 -340.508401) (xy 54.657201 -340.539036)
			(xy 54.670494 -340.566978) (xy 54.680612 -340.578694) (xy 54.699625 -340.600011) (xy 54.731799 -340.647204)
			(xy 54.75658 -340.698665) (xy 54.773417 -340.753245) (xy 54.781931 -340.809723) (xy 54.782466 -340.838282)
			(xy 54.781998 -340.865652) (xy 54.774182 -340.919832) (xy 54.758694 -340.972335) (xy 54.735852 -341.022082)
			(xy 54.706127 -341.068049) (xy 54.688486 -341.08898) (xy 54.679268 -341.100321) (xy 54.66709 -341.126874)
			(xy 54.662914 -341.155786) (xy 54.667082 -341.1847) (xy 54.679253 -341.211256) (xy 54.688486 -341.222584)
			(xy 54.706109 -341.243531) (xy 54.735833 -341.289497) (xy 54.758679 -341.339241) (xy 54.774176 -341.391741)
			(xy 54.782006 -341.445917) (xy 54.782008 -341.500656) (xy 54.774182 -341.554833) (xy 54.758688 -341.607334)
			(xy 54.735846 -341.657079) (xy 54.706125 -341.703047) (xy 54.688486 -341.72398) (xy 54.679268 -341.735321)
			(xy 54.66709 -341.761874) (xy 54.662914 -341.790786) (xy 54.667082 -341.8197) (xy 54.679253 -341.846256)
			(xy 54.688486 -341.857584) (xy 54.706109 -341.878531) (xy 54.735833 -341.924497) (xy 54.758679 -341.974241)
			(xy 54.774176 -342.026741) (xy 54.782006 -342.080917) (xy 54.782008 -342.135656) (xy 54.774182 -342.189833)
			(xy 54.758688 -342.242334) (xy 54.735846 -342.292079) (xy 54.706125 -342.338047) (xy 54.688486 -342.35898)
			(xy 54.679268 -342.370321) (xy 54.66709 -342.396874) (xy 54.662914 -342.425786) (xy 54.667082 -342.4547)
			(xy 54.679253 -342.481256) (xy 54.688486 -342.492584) (xy 54.706129 -342.513513) (xy 54.735841 -342.559486)
			(xy 54.758676 -342.609235) (xy 54.774166 -342.661736) (xy 54.781993 -342.715913) (xy 54.782466 -342.743282)
			(xy 54.782028 -342.770536) (xy 54.774272 -342.82449) (xy 54.758916 -342.876791) (xy 54.736273 -342.926374)
			(xy 54.706803 -342.972229) (xy 54.671106 -343.013423) (xy 54.62991 -343.049117) (xy 54.584053 -343.078584)
			(xy 54.534469 -343.101225) (xy 54.482167 -343.116577) (xy 54.428212 -343.12433) (xy 54.400958 -343.12479)
			(xy 54.372218 -343.124294) (xy 54.315389 -343.115665) (xy 54.260498 -343.098609) (xy 54.208787 -343.073511)
			(xy 54.161426 -343.04094) (xy 54.1401 -343.021666) (xy 54.128566 -343.011594) (xy 54.10102 -342.998252)
			(xy 54.070758 -342.993667) (xy 54.040496 -342.998252) (xy 54.01295 -343.011594) (xy 54.001416 -343.021666)
			(xy 53.980089 -343.040936) (xy 53.932726 -343.073501) (xy 53.881015 -343.098592) (xy 53.826124 -343.115642)
			(xy 53.769297 -343.124264) (xy 53.711819 -343.124264) (xy 53.654992 -343.115642) (xy 53.600101 -343.098592)
			(xy 53.54839 -343.073501) (xy 53.501027 -343.040936) (xy 53.4797 -343.021666) (xy 53.468166 -343.011594)
			(xy 53.44062 -342.998252) (xy 53.410358 -342.993667) (xy 53.380096 -342.998252) (xy 53.35255 -343.011594)
			(xy 53.341016 -343.021666) (xy 53.319707 -343.040957) (xy 53.27234 -343.073521) (xy 53.220624 -343.098609)
			(xy 53.165729 -343.115655) (xy 53.108898 -343.124272) (xy 53.080158 -343.12479) (xy 53.052905 -343.124361)
			(xy 52.998954 -343.116599) (xy 52.946657 -343.101237) (xy 52.897079 -343.07859) (xy 52.851228 -343.049117)
			(xy 52.810037 -343.01342) (xy 52.774347 -342.972224) (xy 52.744881 -342.926369) (xy 52.722242 -342.876786)
			(xy 52.706889 -342.824487) (xy 52.699135 -342.770535) (xy 52.69865 -342.743282) (xy 52.699093 -342.715911)
			(xy 52.706915 -342.66173) (xy 52.722408 -342.609226) (xy 52.745256 -342.55948) (xy 52.774986 -342.513514)
			(xy 52.79263 -342.492584) (xy 52.801882 -342.481269) (xy 52.814053 -342.454706) (xy 52.818221 -342.425786)
			(xy 52.814046 -342.396868) (xy 52.801867 -342.370308) (xy 52.79263 -342.35898) (xy 52.774972 -342.338062)
			(xy 52.745247 -342.292091) (xy 52.722403 -342.242343) (xy 52.706908 -342.189839) (xy 52.699081 -342.135658)
			(xy 52.699083 -342.080915) (xy 52.706914 -342.026735) (xy 52.722412 -341.974232) (xy 52.74526 -341.924485)
			(xy 52.774988 -341.878517) (xy 52.79263 -341.857584) (xy 52.801882 -341.846269) (xy 52.814053 -341.819706)
			(xy 52.818221 -341.790786) (xy 52.814046 -341.761868) (xy 52.801867 -341.735308) (xy 52.79263 -341.72398)
			(xy 52.774972 -341.703062) (xy 52.745247 -341.657091) (xy 52.722403 -341.607343) (xy 52.706908 -341.554839)
			(xy 52.699081 -341.500658) (xy 52.699083 -341.445915) (xy 52.706914 -341.391735) (xy 52.722412 -341.339232)
			(xy 52.74526 -341.289485) (xy 52.774988 -341.243517) (xy 52.79263 -341.222584) (xy 52.801882 -341.211269)
			(xy 52.814053 -341.184706) (xy 52.818221 -341.155786) (xy 52.814046 -341.126868) (xy 52.801867 -341.100308)
			(xy 52.79263 -341.08898) (xy 52.77502 -341.068025) (xy 52.745302 -341.022059) (xy 52.72246 -340.972317)
			(xy 52.706963 -340.919822) (xy 52.699128 -340.86565) (xy 52.69865 -340.838282) (xy 52.69922 -340.808841)
			(xy 52.708256 -340.750657) (xy 52.726126 -340.694554) (xy 52.752406 -340.641862) (xy 52.786471 -340.593836)
			(xy 52.8066 -340.572344) (xy 52.817009 -340.560883) (xy 52.830906 -340.53323) (xy 52.835907 -340.502688)
			(xy 52.831556 -340.472046) (xy 52.81825 -340.444104) (xy 52.808124 -340.43239) (xy 52.789093 -340.411088)
			(xy 52.756924 -340.36389) (xy 52.732147 -340.312425) (xy 52.715315 -340.257843) (xy 52.706803 -340.201361)
			(xy 52.70627 -340.172802) (xy 52.706698 -340.145811) (xy 52.714308 -340.092369) (xy 52.729376 -340.040533)
			(xy 52.7516 -339.99134) (xy 52.780538 -339.94577) (xy 52.815611 -339.904735) (xy 52.835556 -339.886544)
			(xy 52.846182 -339.876532) (xy 52.861793 -339.851879) (xy 52.869785 -339.823814) (xy 52.869503 -339.794635)
			(xy 52.86097 -339.766729) (xy 52.844886 -339.742382) (xy 52.834032 -339.73262) (xy 52.813233 -339.714399)
			(xy 52.776559 -339.673017) (xy 52.74625 -339.62677) (xy 52.722945 -339.576627) (xy 52.707131 -339.523643)
			(xy 52.699142 -339.468929) (xy 52.69865 -339.441282) (xy 52.699176 -339.412543) (xy 52.7078 -339.355717)
			(xy 52.72485 -339.300827) (xy 52.749941 -339.249115) (xy 52.782504 -339.201752) (xy 52.801774 -339.180424)
			(xy 52.811863 -339.168904) (xy 52.825203 -339.141353) (xy 52.829784 -339.111087) (xy 52.825195 -339.080822)
			(xy 52.811848 -339.053274) (xy 52.801774 -339.04174) (xy 52.782501 -339.020415) (xy 52.749933 -338.973053)
			(xy 52.724841 -338.921341) (xy 52.707791 -338.86645) (xy 52.69917 -338.809621) (xy 52.69865 -338.780882)
			(xy 52.699093 -338.754848) (xy 52.706182 -338.703265) (xy 52.720212 -338.653124) (xy 52.740924 -338.605353)
			(xy 52.767933 -338.560838) (xy 52.783994 -338.540344) (xy 52.792995 -338.528305) (xy 52.804369 -338.500505)
			(xy 52.807153 -338.470597) (xy 52.801105 -338.441174) (xy 52.78675 -338.414789) (xy 52.765333 -338.393729)
			(xy 52.73871 -338.37982) (xy 52.72405 -338.376514) (xy 52.682679 -338.368223) (xy 52.601583 -338.344902)
			(xy 52.522979 -338.314214) (xy 52.447534 -338.276419) (xy 52.375889 -338.231838) (xy 52.308653 -338.180851)
			(xy 52.246397 -338.12389) (xy 52.189649 -338.061439) (xy 52.138892 -337.994029) (xy 52.094557 -337.922232)
			(xy 52.05702 -337.846659) (xy 52.0266 -337.76795) (xy 52.003557 -337.686775) (xy 51.988084 -337.603823)
			(xy 51.980315 -337.519799) (xy 51.97983 -337.477608) (xy 47.612046 -337.477608) (xy 47.611543 -337.520515)
			(xy 47.603508 -337.605953) (xy 47.587507 -337.690263) (xy 47.563681 -337.772704) (xy 47.53224 -337.852552)
			(xy 47.49346 -337.929104) (xy 47.447682 -338.001689) (xy 47.395309 -338.069669) (xy 47.3368 -338.132445)
			(xy 47.272669 -338.189466) (xy 47.203481 -338.240232) (xy 47.129842 -338.284296) (xy 47.052402 -338.32127)
			(xy 46.971839 -338.350831) (xy 46.888862 -338.372717) (xy 46.8042 -338.386737) (xy 46.718598 -338.392768)
			(xy 46.632806 -338.390756) (xy 46.54758 -338.38072) (xy 46.463669 -338.362747) (xy 46.381809 -338.336995)
			(xy 46.30272 -338.303691) (xy 46.227098 -338.263127) (xy 46.155606 -338.21566) (xy 46.088873 -338.161707)
			(xy 46.027486 -338.101743) (xy 45.971983 -338.036293) (xy 45.922854 -337.965934) (xy 45.880528 -337.891283)
			(xy 45.845379 -337.812997) (xy 45.817716 -337.731763) (xy 45.79778 -337.648296) (xy 45.785749 -337.563328)
			(xy 45.781727 -337.477608) (xy 41.42123 -337.477608) (xy 41.420801 -337.514165) (xy 41.412766 -337.599603)
			(xy 41.396765 -337.683913) (xy 41.372939 -337.766354) (xy 41.341498 -337.846202) (xy 41.302718 -337.922754)
			(xy 41.25694 -337.995339) (xy 41.204567 -338.063319) (xy 41.146058 -338.126095) (xy 41.081927 -338.183116)
			(xy 41.012739 -338.233882) (xy 40.9391 -338.277946) (xy 40.86166 -338.31492) (xy 40.781097 -338.344481)
			(xy 40.69812 -338.366367) (xy 40.613458 -338.380387) (xy 40.527856 -338.386418) (xy 40.442064 -338.384406)
			(xy 40.356838 -338.37437) (xy 40.272927 -338.356397) (xy 40.191067 -338.330645) (xy 40.111978 -338.297341)
			(xy 40.036356 -338.256777) (xy 39.964864 -338.20931) (xy 39.898131 -338.155357) (xy 39.836744 -338.095393)
			(xy 39.781241 -338.029943) (xy 39.732112 -337.959584) (xy 39.689786 -337.884933) (xy 39.654637 -337.806647)
			(xy 39.626974 -337.725413) (xy 39.607038 -337.641946) (xy 39.595007 -337.556978) (xy 39.590985 -337.471258)
			(xy 34.902394 -337.471258) (xy 34.902394 -339.443822) (xy 38.02761 -339.443822) (xy 38.028087 -339.416452)
			(xy 38.035901 -339.362273) (xy 38.051388 -339.30977) (xy 38.074227 -339.260023) (xy 38.10395 -339.214056)
			(xy 38.12159 -339.193124) (xy 38.130806 -339.181781) (xy 38.142988 -339.155229) (xy 38.147165 -339.126317)
			(xy 38.142997 -339.097403) (xy 38.130825 -339.070847) (xy 38.12159 -339.05952) (xy 38.103945 -339.038593)
			(xy 38.074235 -338.992618) (xy 38.0514 -338.94287) (xy 38.03591 -338.890368) (xy 38.028083 -338.836191)
			(xy 38.02761 -338.808822) (xy 38.028076 -338.781569) (xy 38.03583 -338.727617) (xy 38.051184 -338.675318)
			(xy 38.073826 -338.625737) (xy 38.103293 -338.579883) (xy 38.138987 -338.538689) (xy 38.18018 -338.502995)
			(xy 38.226033 -338.473528) (xy 38.275614 -338.450886) (xy 38.327913 -338.435531) (xy 38.381865 -338.427776)
			(xy 38.409118 -338.427314) (xy 38.437856 -338.42785) (xy 38.494682 -338.436473) (xy 38.549572 -338.453521)
			(xy 38.601284 -338.47861) (xy 38.648648 -338.51117) (xy 38.669976 -338.530438) (xy 38.68151 -338.54051)
			(xy 38.709056 -338.553852) (xy 38.739318 -338.558437) (xy 38.76958 -338.553852) (xy 38.797126 -338.54051)
			(xy 38.80866 -338.530438) (xy 38.829987 -338.511168) (xy 38.87735 -338.478603) (xy 38.929061 -338.453512)
			(xy 38.983952 -338.436462) (xy 39.040779 -338.42784) (xy 39.098257 -338.42784) (xy 39.155084 -338.436462)
			(xy 39.209975 -338.453512) (xy 39.261686 -338.478603) (xy 39.309049 -338.511168) (xy 39.330376 -338.530438)
			(xy 39.341283 -338.539936) (xy 39.367057 -338.553021) (xy 39.395469 -338.558337) (xy 39.42423 -338.555455)
			(xy 39.437818 -338.550504) (xy 39.456048 -338.52959) (xy 39.497498 -338.492717) (xy 39.543854 -338.462239)
			(xy 39.594137 -338.4388) (xy 39.647286 -338.422894) (xy 39.702179 -338.414858) (xy 39.729918 -338.41436)
			(xy 39.75719 -338.414785) (xy 39.81118 -338.42255) (xy 39.863515 -338.43792) (xy 39.913129 -338.460581)
			(xy 39.959014 -338.490072) (xy 40.000234 -338.525794) (xy 40.035952 -338.567018) (xy 40.065438 -338.612906)
			(xy 40.088094 -338.662523) (xy 40.103459 -338.714859) (xy 40.111218 -338.768849) (xy 40.11168 -338.796122)
			(xy 40.111426 -338.810092) (xy 40.110907 -338.837335) (xy 40.102977 -338.891244) (xy 40.087449 -338.943474)
			(xy 40.06464 -338.99296) (xy 40.035015 -339.038692) (xy 40.017446 -339.05952) (xy 40.009031 -339.069826)
			(xy 39.997353 -339.093722) (xy 39.992231 -339.119822) (xy 39.994012 -339.146359) (xy 39.997888 -339.159088)
			(xy 40.019063 -339.180757) (xy 40.054942 -339.229573) (xy 40.082668 -339.283439) (xy 40.101546 -339.341006)
			(xy 40.111103 -339.40083) (xy 40.11168 -339.431122) (xy 40.111426 -339.445092) (xy 40.110952 -339.470505)
			(xy 40.104043 -339.520863) (xy 40.090504 -339.569857) (xy 40.070578 -339.616618) (xy 40.044616 -339.660317)
			(xy 40.013079 -339.70018) (xy 39.995094 -339.718142) (xy 39.985339 -339.728135) (xy 39.971307 -339.752272)
			(xy 39.964343 -339.779309) (xy 39.964969 -339.807221) (xy 39.973137 -339.833919) (xy 39.988236 -339.857403)
			(xy 39.998396 -339.866986) (xy 40.018206 -339.885169) (xy 40.052996 -339.926171) (xy 40.081692 -339.971647)
			(xy 40.103726 -340.020698) (xy 40.118662 -340.072355) (xy 40.126207 -340.125596) (xy 40.126666 -340.152482)
			(xy 40.126079 -340.182605) (xy 40.116601 -340.2421) (xy 40.097894 -340.299368) (xy 40.070422 -340.352985)
			(xy 40.034867 -340.40162) (xy 40.01389 -340.423246) (xy 40.004689 -340.432983) (xy 39.99124 -340.45614)
			(xy 39.984274 -340.481998) (xy 39.984271 -340.508777) (xy 39.99123 -340.534636) (xy 40.004673 -340.557797)
			(xy 40.01389 -340.567518) (xy 40.034854 -340.589158) (xy 40.070425 -340.637782) (xy 40.097908 -340.691395)
			(xy 40.11662 -340.748662) (xy 40.126095 -340.808159) (xy 40.126666 -340.838282) (xy 40.126198 -340.865652)
			(xy 40.118382 -340.919832) (xy 40.102894 -340.972335) (xy 40.080052 -341.022082) (xy 40.050327 -341.068049)
			(xy 40.032686 -341.08898) (xy 40.023468 -341.100321) (xy 40.01129 -341.126874) (xy 40.007114 -341.155786)
			(xy 40.011282 -341.1847) (xy 40.023453 -341.211256) (xy 40.032686 -341.222584) (xy 40.050309 -341.243531)
			(xy 40.080033 -341.289497) (xy 40.102879 -341.339241) (xy 40.118376 -341.391741) (xy 40.126206 -341.445917)
			(xy 40.126208 -341.500656) (xy 40.118382 -341.554833) (xy 40.102888 -341.607334) (xy 40.080046 -341.657079)
			(xy 40.050325 -341.703047) (xy 40.032686 -341.72398) (xy 40.023468 -341.735321) (xy 40.01129 -341.761874)
			(xy 40.007114 -341.790786) (xy 40.011282 -341.8197) (xy 40.023453 -341.846256) (xy 40.032686 -341.857584)
			(xy 40.050309 -341.878531) (xy 40.080033 -341.924497) (xy 40.102879 -341.974241) (xy 40.118376 -342.026741)
			(xy 40.126206 -342.080917) (xy 40.126208 -342.135656) (xy 40.118382 -342.189833) (xy 40.102888 -342.242334)
			(xy 40.080046 -342.292079) (xy 40.050325 -342.338047) (xy 40.032686 -342.35898) (xy 40.023468 -342.370321)
			(xy 40.01129 -342.396874) (xy 40.007114 -342.425786) (xy 40.011282 -342.4547) (xy 40.023453 -342.481256)
			(xy 40.032686 -342.492584) (xy 40.050329 -342.513513) (xy 40.080041 -342.559486) (xy 40.102876 -342.609235)
			(xy 40.118366 -342.661736) (xy 40.126193 -342.715913) (xy 40.126666 -342.743282) (xy 43.02125 -342.743282)
			(xy 43.021693 -342.715911) (xy 43.029515 -342.66173) (xy 43.045008 -342.609226) (xy 43.067856 -342.55948)
			(xy 43.097586 -342.513514) (xy 43.11523 -342.492584) (xy 43.124482 -342.481269) (xy 43.136653 -342.454706)
			(xy 43.140821 -342.425786) (xy 43.136646 -342.396868) (xy 43.124467 -342.370308) (xy 43.11523 -342.35898)
			(xy 43.097572 -342.338062) (xy 43.067847 -342.292091) (xy 43.045003 -342.242343) (xy 43.029508 -342.189839)
			(xy 43.021681 -342.135658) (xy 43.021683 -342.080915) (xy 43.029514 -342.026735) (xy 43.045012 -341.974232)
			(xy 43.06786 -341.924485) (xy 43.097588 -341.878517) (xy 43.11523 -341.857584) (xy 43.124482 -341.846269)
			(xy 43.136653 -341.819706) (xy 43.140821 -341.790786) (xy 43.136646 -341.761868) (xy 43.124467 -341.735308)
			(xy 43.11523 -341.72398) (xy 43.097572 -341.703062) (xy 43.067847 -341.657091) (xy 43.045003 -341.607343)
			(xy 43.029508 -341.554839) (xy 43.021681 -341.500658) (xy 43.021683 -341.445915) (xy 43.029514 -341.391735)
			(xy 43.045012 -341.339232) (xy 43.06786 -341.289485) (xy 43.097588 -341.243517) (xy 43.11523 -341.222584)
			(xy 43.124482 -341.211269) (xy 43.136653 -341.184706) (xy 43.140821 -341.155786) (xy 43.136646 -341.126868)
			(xy 43.124467 -341.100308) (xy 43.11523 -341.08898) (xy 43.09762 -341.068025) (xy 43.067902 -341.022059)
			(xy 43.04506 -340.972317) (xy 43.029563 -340.919822) (xy 43.021728 -340.86565) (xy 43.02125 -340.838282)
			(xy 43.02125 -340.838028) (xy 43.021846 -340.808195) (xy 43.031143 -340.749256) (xy 43.049499 -340.692483)
			(xy 43.076467 -340.639258) (xy 43.11139 -340.590879) (xy 43.131994 -340.569296) (xy 43.142625 -340.557741)
			(xy 43.157002 -340.529852) (xy 43.162226 -340.498914) (xy 43.157801 -340.467851) (xy 43.144146 -340.439601)
			(xy 43.133772 -340.427818) (xy 43.114184 -340.406442) (xy 43.081067 -340.358854) (xy 43.055538 -340.3068)
			(xy 43.038186 -340.25148) (xy 43.02941 -340.194171) (xy 43.02887 -340.165182) (xy 43.029319 -340.138581)
			(xy 43.036697 -340.085893) (xy 43.051322 -340.034741) (xy 43.07291 -339.986116) (xy 43.101043 -339.940961)
			(xy 43.135174 -339.900151) (xy 43.1546 -339.881972) (xy 43.164941 -339.872005) (xy 43.180033 -339.847581)
			(xy 43.187736 -339.819924) (xy 43.187444 -339.791215) (xy 43.179179 -339.76372) (xy 43.163593 -339.739609)
			(xy 43.153076 -339.729826) (xy 43.132762 -339.711618) (xy 43.097025 -339.670401) (xy 43.067521 -339.624515)
			(xy 43.044852 -339.574896) (xy 43.029478 -339.522555) (xy 43.021713 -339.468558) (xy 43.02125 -339.441282)
			(xy 43.021776 -339.412543) (xy 43.0304 -339.355717) (xy 43.04745 -339.300827) (xy 43.072541 -339.249115)
			(xy 43.105104 -339.201752) (xy 43.124374 -339.180424) (xy 43.134463 -339.168904) (xy 43.147803 -339.141353)
			(xy 43.152384 -339.111087) (xy 43.147795 -339.080822) (xy 43.134448 -339.053274) (xy 43.124374 -339.04174)
			(xy 43.105101 -339.020415) (xy 43.072533 -338.973053) (xy 43.047441 -338.921341) (xy 43.030391 -338.86645)
			(xy 43.02177 -338.809621) (xy 43.02125 -338.780882) (xy 43.021761 -338.753632) (xy 43.029519 -338.699688)
			(xy 43.044874 -338.647396) (xy 43.067514 -338.597821) (xy 43.096979 -338.551973) (xy 43.132667 -338.510784)
			(xy 43.173854 -338.475093) (xy 43.2197 -338.445626) (xy 43.269273 -338.422982) (xy 43.321564 -338.407624)
			(xy 43.375508 -338.399863) (xy 43.402758 -338.399374) (xy 43.431498 -338.399869) (xy 43.488326 -338.4085)
			(xy 43.543217 -338.425557) (xy 43.594928 -338.450655) (xy 43.64229 -338.483225) (xy 43.663616 -338.502498)
			(xy 43.67515 -338.51257) (xy 43.702696 -338.525912) (xy 43.732958 -338.530497) (xy 43.76322 -338.525912)
			(xy 43.790766 -338.51257) (xy 43.8023 -338.502498) (xy 43.823627 -338.483228) (xy 43.87099 -338.450663)
			(xy 43.922701 -338.425572) (xy 43.977592 -338.408522) (xy 44.034419 -338.3999) (xy 44.091897 -338.3999)
			(xy 44.148724 -338.408522) (xy 44.203615 -338.425572) (xy 44.255326 -338.450663) (xy 44.302689 -338.483228)
			(xy 44.324016 -338.502498) (xy 44.33555 -338.51257) (xy 44.363096 -338.525912) (xy 44.393358 -338.530497)
			(xy 44.42362 -338.525912) (xy 44.451166 -338.51257) (xy 44.4627 -338.502498) (xy 44.484012 -338.48321)
			(xy 44.531377 -338.450644) (xy 44.583093 -338.425554) (xy 44.637987 -338.408508) (xy 44.694818 -338.399891)
			(xy 44.723558 -338.399374) (xy 44.750809 -338.399894) (xy 44.804757 -338.407645) (xy 44.857053 -338.422995)
			(xy 44.906631 -338.445631) (xy 44.952484 -338.475093) (xy 44.993677 -338.510781) (xy 45.029371 -338.551968)
			(xy 45.05884 -338.597816) (xy 45.081484 -338.647391) (xy 45.096842 -338.699684) (xy 45.104601 -338.753631)
			(xy 45.105066 -338.780882) (xy 45.104514 -338.80962) (xy 45.095895 -338.866445) (xy 45.078851 -338.921335)
			(xy 45.053766 -338.973047) (xy 45.021209 -339.020411) (xy 45.001942 -339.04174) (xy 44.991887 -339.053288)
			(xy 44.978541 -339.080829) (xy 44.973953 -339.111087) (xy 44.978534 -339.141346) (xy 44.991872 -339.16889)
			(xy 45.001942 -339.180424) (xy 45.021201 -339.201761) (xy 45.05377 -339.24912) (xy 45.078865 -339.300829)
			(xy 45.095918 -339.355718) (xy 45.104544 -339.412544) (xy 45.105066 -339.441282) (xy 45.104581 -339.467882)
			(xy 45.097208 -339.520567) (xy 45.08259 -339.571718) (xy 45.061009 -339.620343) (xy 45.032883 -339.665499)
			(xy 44.998758 -339.706312) (xy 44.979336 -339.724492) (xy 44.969028 -339.734492) (xy 44.953929 -339.758905)
			(xy 44.946218 -339.786555) (xy 44.946504 -339.815258) (xy 44.954764 -339.842749) (xy 44.970345 -339.866857)
			(xy 44.98086 -339.876638) (xy 45.001164 -339.894857) (xy 45.0369 -339.936073) (xy 45.066404 -339.981956)
			(xy 45.089075 -340.031573) (xy 45.104452 -340.083912) (xy 45.112221 -340.137907) (xy 45.112686 -340.165182)
			(xy 45.112686 -340.165436) (xy 45.112546 -340.172802) (xy 47.71263 -340.172802) (xy 47.713127 -340.145156)
			(xy 47.721126 -340.090444) (xy 47.736942 -340.037461) (xy 47.760243 -339.987318) (xy 47.790542 -339.941065)
			(xy 47.827203 -339.899672) (xy 47.848012 -339.881464) (xy 47.858786 -339.871635) (xy 47.874807 -339.847284)
			(xy 47.883311 -339.819404) (xy 47.883608 -339.790257) (xy 47.875673 -339.762209) (xy 47.860151 -339.737538)
			(xy 47.849536 -339.72754) (xy 47.829588 -339.709355) (xy 47.794526 -339.668314) (xy 47.765598 -339.622741)
			(xy 47.743382 -339.573546) (xy 47.728321 -339.521712) (xy 47.720716 -339.468271) (xy 47.72025 -339.441282)
			(xy 47.720776 -339.412543) (xy 47.7294 -339.355717) (xy 47.74645 -339.300827) (xy 47.771541 -339.249115)
			(xy 47.804104 -339.201752) (xy 47.823374 -339.180424) (xy 47.833463 -339.168904) (xy 47.846803 -339.141353)
			(xy 47.851384 -339.111087) (xy 47.846795 -339.080822) (xy 47.833448 -339.053274) (xy 47.823374 -339.04174)
			(xy 47.804101 -339.020415) (xy 47.771533 -338.973053) (xy 47.746441 -338.921341) (xy 47.729391 -338.86645)
			(xy 47.72077 -338.809621) (xy 47.72025 -338.780882) (xy 47.720761 -338.753632) (xy 47.728519 -338.699688)
			(xy 47.743874 -338.647396) (xy 47.766514 -338.597821) (xy 47.795979 -338.551973) (xy 47.831667 -338.510784)
			(xy 47.872854 -338.475093) (xy 47.9187 -338.445626) (xy 47.968273 -338.422982) (xy 48.020564 -338.407624)
			(xy 48.074508 -338.399863) (xy 48.101758 -338.399374) (xy 48.130498 -338.399869) (xy 48.187326 -338.4085)
			(xy 48.242217 -338.425557) (xy 48.293928 -338.450655) (xy 48.34129 -338.483225) (xy 48.362616 -338.502498)
			(xy 48.37415 -338.51257) (xy 48.401696 -338.525912) (xy 48.431958 -338.530497) (xy 48.46222 -338.525912)
			(xy 48.489766 -338.51257) (xy 48.5013 -338.502498) (xy 48.522627 -338.483228) (xy 48.56999 -338.450663)
			(xy 48.621701 -338.425572) (xy 48.676592 -338.408522) (xy 48.733419 -338.3999) (xy 48.790897 -338.3999)
			(xy 48.847724 -338.408522) (xy 48.902615 -338.425572) (xy 48.954326 -338.450663) (xy 49.001689 -338.483228)
			(xy 49.023016 -338.502498) (xy 49.03455 -338.51257) (xy 49.062096 -338.525912) (xy 49.092358 -338.530497)
			(xy 49.12262 -338.525912) (xy 49.150166 -338.51257) (xy 49.1617 -338.502498) (xy 49.183012 -338.48321)
			(xy 49.230377 -338.450644) (xy 49.282093 -338.425554) (xy 49.336987 -338.408508) (xy 49.393818 -338.399891)
			(xy 49.422558 -338.399374) (xy 49.449809 -338.399894) (xy 49.503757 -338.407645) (xy 49.556053 -338.422995)
			(xy 49.605631 -338.445631) (xy 49.651484 -338.475093) (xy 49.692677 -338.510781) (xy 49.728371 -338.551968)
			(xy 49.75784 -338.597816) (xy 49.780484 -338.647391) (xy 49.795842 -338.699684) (xy 49.803601 -338.753631)
			(xy 49.804066 -338.780882) (xy 49.803514 -338.80962) (xy 49.794895 -338.866445) (xy 49.777851 -338.921335)
			(xy 49.752766 -338.973047) (xy 49.720209 -339.020411) (xy 49.700942 -339.04174) (xy 49.690887 -339.053288)
			(xy 49.677541 -339.080829) (xy 49.672953 -339.111087) (xy 49.677534 -339.141346) (xy 49.690872 -339.16889)
			(xy 49.700942 -339.180424) (xy 49.720201 -339.201761) (xy 49.75277 -339.24912) (xy 49.777865 -339.300829)
			(xy 49.794918 -339.355718) (xy 49.803544 -339.412544) (xy 49.804066 -339.441282) (xy 49.80356 -339.468928)
			(xy 49.795563 -339.523639) (xy 49.779749 -339.576622) (xy 49.756449 -339.626766) (xy 49.726152 -339.673019)
			(xy 49.689493 -339.714412) (xy 49.668684 -339.73262) (xy 49.657819 -339.742361) (xy 49.641786 -339.766732)
			(xy 49.633283 -339.794638) (xy 49.633002 -339.823809) (xy 49.640965 -339.851874) (xy 49.656525 -339.87655)
			(xy 49.66716 -339.886544) (xy 49.687099 -339.904738) (xy 49.722162 -339.945777) (xy 49.751091 -339.991348)
			(xy 49.773309 -340.040541) (xy 49.788372 -340.092374) (xy 49.795979 -340.145813) (xy 49.796446 -340.172802)
			(xy 49.795882 -340.20136) (xy 49.787374 -340.257838) (xy 49.770547 -340.312419) (xy 49.745777 -340.363885)
			(xy 49.713618 -340.411086) (xy 49.694592 -340.43239) (xy 49.684469 -340.444114) (xy 49.671114 -340.472041)
			(xy 49.666746 -340.502687) (xy 49.671766 -340.533234) (xy 49.685713 -340.56087) (xy 49.696116 -340.572344)
			(xy 49.71624 -340.593841) (xy 49.750307 -340.641867) (xy 49.776592 -340.694557) (xy 49.794471 -340.750658)
			(xy 49.803519 -340.808841) (xy 49.804066 -340.838282) (xy 49.803598 -340.865652) (xy 49.795782 -340.919832)
			(xy 49.780294 -340.972335) (xy 49.757452 -341.022082) (xy 49.727727 -341.068049) (xy 49.710086 -341.08898)
			(xy 49.700868 -341.100321) (xy 49.68869 -341.126874) (xy 49.684514 -341.155786) (xy 49.688682 -341.1847)
			(xy 49.700853 -341.211256) (xy 49.710086 -341.222584) (xy 49.727709 -341.243531) (xy 49.757433 -341.289497)
			(xy 49.780279 -341.339241) (xy 49.795776 -341.391741) (xy 49.803606 -341.445917) (xy 49.803608 -341.500656)
			(xy 49.795782 -341.554833) (xy 49.780288 -341.607334) (xy 49.757446 -341.657079) (xy 49.727725 -341.703047)
			(xy 49.710086 -341.72398) (xy 49.700868 -341.735321) (xy 49.68869 -341.761874) (xy 49.684514 -341.790786)
			(xy 49.688682 -341.8197) (xy 49.700853 -341.846256) (xy 49.710086 -341.857584) (xy 49.727709 -341.878531)
			(xy 49.757433 -341.924497) (xy 49.780279 -341.974241) (xy 49.795776 -342.026741) (xy 49.803606 -342.080917)
			(xy 49.803608 -342.135656) (xy 49.795782 -342.189833) (xy 49.780288 -342.242334) (xy 49.757446 -342.292079)
			(xy 49.727725 -342.338047) (xy 49.710086 -342.35898) (xy 49.700868 -342.370321) (xy 49.68869 -342.396874)
			(xy 49.684514 -342.425786) (xy 49.688682 -342.4547) (xy 49.700853 -342.481256) (xy 49.710086 -342.492584)
			(xy 49.727729 -342.513513) (xy 49.757441 -342.559486) (xy 49.780276 -342.609235) (xy 49.795766 -342.661736)
			(xy 49.803593 -342.715913) (xy 49.804066 -342.743282) (xy 49.803628 -342.770536) (xy 49.795872 -342.82449)
			(xy 49.780516 -342.876791) (xy 49.757873 -342.926374) (xy 49.728403 -342.972229) (xy 49.692706 -343.013423)
			(xy 49.65151 -343.049117) (xy 49.605653 -343.078584) (xy 49.556069 -343.101225) (xy 49.503767 -343.116577)
			(xy 49.449812 -343.12433) (xy 49.422558 -343.12479) (xy 49.393818 -343.124294) (xy 49.336989 -343.115665)
			(xy 49.282098 -343.098609) (xy 49.230387 -343.073511) (xy 49.183026 -343.04094) (xy 49.1617 -343.021666)
			(xy 49.150166 -343.011594) (xy 49.12262 -342.998252) (xy 49.092358 -342.993667) (xy 49.062096 -342.998252)
			(xy 49.03455 -343.011594) (xy 49.023016 -343.021666) (xy 49.001689 -343.040936) (xy 48.954326 -343.073501)
			(xy 48.902615 -343.098592) (xy 48.847724 -343.115642) (xy 48.790897 -343.124264) (xy 48.733419 -343.124264)
			(xy 48.676592 -343.115642) (xy 48.621701 -343.098592) (xy 48.56999 -343.073501) (xy 48.522627 -343.040936)
			(xy 48.5013 -343.021666) (xy 48.489766 -343.011594) (xy 48.46222 -342.998252) (xy 48.431958 -342.993667)
			(xy 48.401696 -342.998252) (xy 48.37415 -343.011594) (xy 48.362616 -343.021666) (xy 48.341307 -343.040957)
			(xy 48.29394 -343.073521) (xy 48.242224 -343.098609) (xy 48.187329 -343.115655) (xy 48.130498 -343.124272)
			(xy 48.101758 -343.12479) (xy 48.074505 -343.124361) (xy 48.020554 -343.116599) (xy 47.968257 -343.101237)
			(xy 47.918679 -343.07859) (xy 47.872828 -343.049117) (xy 47.831637 -343.01342) (xy 47.795947 -342.972224)
			(xy 47.766481 -342.926369) (xy 47.743842 -342.876786) (xy 47.728489 -342.824487) (xy 47.720735 -342.770535)
			(xy 47.72025 -342.743282) (xy 47.720693 -342.715911) (xy 47.728515 -342.66173) (xy 47.744008 -342.609226)
			(xy 47.766856 -342.55948) (xy 47.796586 -342.513514) (xy 47.81423 -342.492584) (xy 47.823482 -342.481269)
			(xy 47.835653 -342.454706) (xy 47.839821 -342.425786) (xy 47.835646 -342.396868) (xy 47.823467 -342.370308)
			(xy 47.81423 -342.35898) (xy 47.796572 -342.338062) (xy 47.766847 -342.292091) (xy 47.744003 -342.242343)
			(xy 47.728508 -342.189839) (xy 47.720681 -342.135658) (xy 47.720683 -342.080915) (xy 47.728514 -342.026735)
			(xy 47.744012 -341.974232) (xy 47.76686 -341.924485) (xy 47.796588 -341.878517) (xy 47.81423 -341.857584)
			(xy 47.823482 -341.846269) (xy 47.835653 -341.819706) (xy 47.839821 -341.790786) (xy 47.835646 -341.761868)
			(xy 47.823467 -341.735308) (xy 47.81423 -341.72398) (xy 47.796572 -341.703062) (xy 47.766847 -341.657091)
			(xy 47.744003 -341.607343) (xy 47.728508 -341.554839) (xy 47.720681 -341.500658) (xy 47.720683 -341.445915)
			(xy 47.728514 -341.391735) (xy 47.744012 -341.339232) (xy 47.76686 -341.289485) (xy 47.796588 -341.243517)
			(xy 47.81423 -341.222584) (xy 47.823482 -341.211269) (xy 47.835653 -341.184706) (xy 47.839821 -341.155786)
			(xy 47.835646 -341.126868) (xy 47.823467 -341.100308) (xy 47.81423 -341.08898) (xy 47.79662 -341.068025)
			(xy 47.766902 -341.022059) (xy 47.74406 -340.972317) (xy 47.728563 -340.919822) (xy 47.720728 -340.86565)
			(xy 47.72025 -340.838282) (xy 47.720805 -340.809724) (xy 47.729316 -340.753245) (xy 47.746145 -340.698664)
			(xy 47.770916 -340.647199) (xy 47.803078 -340.599998) (xy 47.822104 -340.578694) (xy 47.832243 -340.566983)
			(xy 47.845597 -340.539051) (xy 47.849963 -340.508401) (xy 47.844938 -340.477852) (xy 47.830985 -340.450214)
			(xy 47.82058 -340.43874) (xy 47.800448 -340.417251) (xy 47.766382 -340.369222) (xy 47.740099 -340.316531)
			(xy 47.722222 -340.260427) (xy 47.713176 -340.202243) (xy 47.71263 -340.172802) (xy 45.112546 -340.172802)
			(xy 45.11212 -340.19527) (xy 45.102814 -340.254209) (xy 45.08445 -340.310983) (xy 45.057476 -340.364207)
			(xy 45.022548 -340.412585) (xy 45.001942 -340.434168) (xy 44.991253 -340.445671) (xy 44.976891 -340.47358)
			(xy 44.971683 -340.504532) (xy 44.976121 -340.535604) (xy 44.989785 -340.56386) (xy 45.000164 -340.575646)
			(xy 45.019724 -340.597046) (xy 45.052847 -340.644627) (xy 45.078382 -340.696675) (xy 45.095741 -340.751989)
			(xy 45.104523 -340.809295) (xy 45.105066 -340.838282) (xy 45.104598 -340.865652) (xy 45.096782 -340.919832)
			(xy 45.081294 -340.972335) (xy 45.058452 -341.022082) (xy 45.028727 -341.068049) (xy 45.011086 -341.08898)
			(xy 45.001868 -341.100321) (xy 44.98969 -341.126874) (xy 44.985514 -341.155786) (xy 44.989682 -341.1847)
			(xy 45.001853 -341.211256) (xy 45.011086 -341.222584) (xy 45.028709 -341.243531) (xy 45.058433 -341.289497)
			(xy 45.081279 -341.339241) (xy 45.096776 -341.391741) (xy 45.104606 -341.445917) (xy 45.104608 -341.500656)
			(xy 45.096782 -341.554833) (xy 45.081288 -341.607334) (xy 45.058446 -341.657079) (xy 45.028725 -341.703047)
			(xy 45.011086 -341.72398) (xy 45.001868 -341.735321) (xy 44.98969 -341.761874) (xy 44.985514 -341.790786)
			(xy 44.989682 -341.8197) (xy 45.001853 -341.846256) (xy 45.011086 -341.857584) (xy 45.028709 -341.878531)
			(xy 45.058433 -341.924497) (xy 45.081279 -341.974241) (xy 45.096776 -342.026741) (xy 45.104606 -342.080917)
			(xy 45.104608 -342.135656) (xy 45.096782 -342.189833) (xy 45.081288 -342.242334) (xy 45.058446 -342.292079)
			(xy 45.028725 -342.338047) (xy 45.011086 -342.35898) (xy 45.001868 -342.370321) (xy 44.98969 -342.396874)
			(xy 44.985514 -342.425786) (xy 44.989682 -342.4547) (xy 45.001853 -342.481256) (xy 45.011086 -342.492584)
			(xy 45.028729 -342.513513) (xy 45.058441 -342.559486) (xy 45.081276 -342.609235) (xy 45.096766 -342.661736)
			(xy 45.104593 -342.715913) (xy 45.105066 -342.743282) (xy 45.104628 -342.770536) (xy 45.096872 -342.82449)
			(xy 45.081516 -342.876791) (xy 45.058873 -342.926374) (xy 45.029403 -342.972229) (xy 44.993706 -343.013423)
			(xy 44.95251 -343.049117) (xy 44.906653 -343.078584) (xy 44.857069 -343.101225) (xy 44.804767 -343.116577)
			(xy 44.750812 -343.12433) (xy 44.723558 -343.12479) (xy 44.694818 -343.124294) (xy 44.637989 -343.115665)
			(xy 44.583098 -343.098609) (xy 44.531387 -343.073511) (xy 44.484026 -343.04094) (xy 44.4627 -343.021666)
			(xy 44.451166 -343.011594) (xy 44.42362 -342.998252) (xy 44.393358 -342.993667) (xy 44.363096 -342.998252)
			(xy 44.33555 -343.011594) (xy 44.324016 -343.021666) (xy 44.302689 -343.040936) (xy 44.255326 -343.073501)
			(xy 44.203615 -343.098592) (xy 44.148724 -343.115642) (xy 44.091897 -343.124264) (xy 44.034419 -343.124264)
			(xy 43.977592 -343.115642) (xy 43.922701 -343.098592) (xy 43.87099 -343.073501) (xy 43.823627 -343.040936)
			(xy 43.8023 -343.021666) (xy 43.790766 -343.011594) (xy 43.76322 -342.998252) (xy 43.732958 -342.993667)
			(xy 43.702696 -342.998252) (xy 43.67515 -343.011594) (xy 43.663616 -343.021666) (xy 43.642307 -343.040957)
			(xy 43.59494 -343.073521) (xy 43.543224 -343.098609) (xy 43.488329 -343.115655) (xy 43.431498 -343.124272)
			(xy 43.402758 -343.12479) (xy 43.375505 -343.124361) (xy 43.321554 -343.116599) (xy 43.269257 -343.101237)
			(xy 43.219679 -343.07859) (xy 43.173828 -343.049117) (xy 43.132637 -343.01342) (xy 43.096947 -342.972224)
			(xy 43.067481 -342.926369) (xy 43.044842 -342.876786) (xy 43.029489 -342.824487) (xy 43.021735 -342.770535)
			(xy 43.02125 -342.743282) (xy 40.126666 -342.743282) (xy 40.126228 -342.770536) (xy 40.118472 -342.82449)
			(xy 40.103116 -342.876791) (xy 40.080473 -342.926374) (xy 40.051003 -342.972229) (xy 40.015306 -343.013423)
			(xy 39.97411 -343.049117) (xy 39.928253 -343.078584) (xy 39.878669 -343.101225) (xy 39.826367 -343.116577)
			(xy 39.772412 -343.12433) (xy 39.745158 -343.12479) (xy 39.716418 -343.124294) (xy 39.659589 -343.115665)
			(xy 39.604698 -343.098609) (xy 39.552987 -343.073511) (xy 39.505626 -343.04094) (xy 39.4843 -343.021666)
			(xy 39.472766 -343.011594) (xy 39.44522 -342.998252) (xy 39.414958 -342.993667) (xy 39.384696 -342.998252)
			(xy 39.35715 -343.011594) (xy 39.345616 -343.021666) (xy 39.324289 -343.040936) (xy 39.276926 -343.073501)
			(xy 39.225215 -343.098592) (xy 39.170324 -343.115642) (xy 39.113497 -343.124264) (xy 39.056019 -343.124264)
			(xy 38.999192 -343.115642) (xy 38.944301 -343.098592) (xy 38.89259 -343.073501) (xy 38.845227 -343.040936)
			(xy 38.8239 -343.021666) (xy 38.812366 -343.011594) (xy 38.78482 -342.998252) (xy 38.754558 -342.993667)
			(xy 38.724296 -342.998252) (xy 38.69675 -343.011594) (xy 38.685216 -343.021666) (xy 38.663907 -343.040957)
			(xy 38.61654 -343.073521) (xy 38.564824 -343.098609) (xy 38.509929 -343.115655) (xy 38.453098 -343.124272)
			(xy 38.424358 -343.12479) (xy 38.397105 -343.124361) (xy 38.343154 -343.116599) (xy 38.290857 -343.101237)
			(xy 38.241279 -343.07859) (xy 38.195428 -343.049117) (xy 38.154237 -343.01342) (xy 38.118547 -342.972224)
			(xy 38.089081 -342.926369) (xy 38.066442 -342.876786) (xy 38.051089 -342.824487) (xy 38.043335 -342.770535)
			(xy 38.04285 -342.743282) (xy 38.043293 -342.715911) (xy 38.051115 -342.66173) (xy 38.066608 -342.609226)
			(xy 38.089456 -342.55948) (xy 38.119186 -342.513514) (xy 38.13683 -342.492584) (xy 38.146082 -342.481269)
			(xy 38.158253 -342.454706) (xy 38.162421 -342.425786) (xy 38.158246 -342.396868) (xy 38.146067 -342.370308)
			(xy 38.13683 -342.35898) (xy 38.119172 -342.338062) (xy 38.089447 -342.292091) (xy 38.066603 -342.242343)
			(xy 38.051108 -342.189839) (xy 38.043281 -342.135658) (xy 38.043283 -342.080915) (xy 38.051114 -342.026735)
			(xy 38.066612 -341.974232) (xy 38.08946 -341.924485) (xy 38.119188 -341.878517) (xy 38.13683 -341.857584)
			(xy 38.146082 -341.846269) (xy 38.158253 -341.819706) (xy 38.162421 -341.790786) (xy 38.158246 -341.761868)
			(xy 38.146067 -341.735308) (xy 38.13683 -341.72398) (xy 38.119172 -341.703062) (xy 38.089447 -341.657091)
			(xy 38.066603 -341.607343) (xy 38.051108 -341.554839) (xy 38.043281 -341.500658) (xy 38.043283 -341.445915)
			(xy 38.051114 -341.391735) (xy 38.066612 -341.339232) (xy 38.08946 -341.289485) (xy 38.119188 -341.243517)
			(xy 38.13683 -341.222584) (xy 38.146082 -341.211269) (xy 38.158253 -341.184706) (xy 38.162421 -341.155786)
			(xy 38.158246 -341.126868) (xy 38.146067 -341.100308) (xy 38.13683 -341.08898) (xy 38.11922 -341.068025)
			(xy 38.089502 -341.022059) (xy 38.06666 -340.972317) (xy 38.051163 -340.919822) (xy 38.043328 -340.86565)
			(xy 38.04285 -340.838282) (xy 38.043409 -340.808158) (xy 38.052893 -340.748661) (xy 38.071607 -340.691393)
			(xy 38.099085 -340.637776) (xy 38.134646 -340.589142) (xy 38.155626 -340.567518) (xy 38.164862 -340.557812)
			(xy 38.178306 -340.534645) (xy 38.185266 -340.50878) (xy 38.185263 -340.481995) (xy 38.178297 -340.456131)
			(xy 38.164846 -340.432968) (xy 38.155626 -340.423246) (xy 38.134647 -340.40162) (xy 38.099078 -340.352992)
			(xy 38.071597 -340.299376) (xy 38.052888 -340.242106) (xy 38.043418 -340.182606) (xy 38.04285 -340.152482)
			(xy 38.043236 -340.126961) (xy 38.050033 -340.076373) (xy 38.063518 -340.027143) (xy 38.083448 -339.980152)
			(xy 38.109469 -339.93624) (xy 38.141114 -339.896191) (xy 38.159182 -339.878162) (xy 38.168936 -339.868167)
			(xy 38.182971 -339.844031) (xy 38.189938 -339.816994) (xy 38.189313 -339.789081) (xy 38.181143 -339.762383)
			(xy 38.166041 -339.7389) (xy 38.15588 -339.729318) (xy 38.136067 -339.711138) (xy 38.101279 -339.670134)
			(xy 38.072584 -339.624658) (xy 38.05055 -339.575606) (xy 38.035614 -339.523949) (xy 38.02807 -339.470708)
			(xy 38.02761 -339.443822) (xy 34.902394 -339.443822) (xy 34.902394 -353.70643) (xy 35.21405 -353.70643)
			(xy 35.218121 -353.650808) (xy 35.230247 -353.596371) (xy 35.25017 -353.54428) (xy 35.277466 -353.495645)
			(xy 35.311552 -353.451502) (xy 35.351701 -353.412793) (xy 35.397059 -353.380342) (xy 35.446659 -353.354841)
			(xy 35.499443 -353.336834) (xy 35.554286 -353.326704) (xy 35.61002 -353.324667) (xy 35.665457 -353.330767)
			(xy 35.719414 -353.344873) (xy 35.770743 -353.366685) (xy 35.818349 -353.395739) (xy 35.861217 -353.431414)
			(xy 35.898434 -353.472951) (xy 35.929207 -353.519464) (xy 35.952879 -353.569961) (xy 35.968947 -353.623368)
			(xy 35.977067 -353.678544) (xy 35.977576 -353.70643) (xy 35.977067 -353.734316) (xy 35.968947 -353.789492)
			(xy 35.952879 -353.842899) (xy 35.929207 -353.893396) (xy 35.898434 -353.939909) (xy 35.861217 -353.981446)
			(xy 35.818349 -354.017121) (xy 35.770743 -354.046175) (xy 35.719414 -354.067987) (xy 35.665457 -354.082093)
			(xy 35.61002 -354.088193) (xy 35.554286 -354.086156) (xy 35.499443 -354.076026) (xy 35.446659 -354.058019)
			(xy 35.397059 -354.032518) (xy 35.351701 -354.000067) (xy 35.311552 -353.961358) (xy 35.277466 -353.917215)
			(xy 35.25017 -353.86858) (xy 35.230247 -353.816489) (xy 35.218121 -353.762052) (xy 35.21405 -353.70643)
			(xy 34.902394 -353.70643) (xy 34.902394 -354.65385) (xy 35.21405 -354.65385) (xy 35.218121 -354.598228)
			(xy 35.230247 -354.543791) (xy 35.25017 -354.4917) (xy 35.277466 -354.443065) (xy 35.311552 -354.398922)
			(xy 35.351701 -354.360213) (xy 35.397059 -354.327762) (xy 35.446659 -354.302261) (xy 35.499443 -354.284254)
			(xy 35.554286 -354.274124) (xy 35.61002 -354.272087) (xy 35.665457 -354.278187) (xy 35.719414 -354.292293)
			(xy 35.770743 -354.314105) (xy 35.818349 -354.343159) (xy 35.861217 -354.378834) (xy 35.898434 -354.420371)
			(xy 35.929207 -354.466884) (xy 35.952879 -354.517381) (xy 35.968947 -354.570788) (xy 35.977067 -354.625964)
			(xy 35.977576 -354.65385) (xy 35.977067 -354.681736) (xy 35.968947 -354.736912) (xy 35.952879 -354.790319)
			(xy 35.929207 -354.840816) (xy 35.898434 -354.887329) (xy 35.861217 -354.928866) (xy 35.818349 -354.964541)
			(xy 35.770743 -354.993595) (xy 35.721478 -355.01453) (xy 37.608764 -355.01453) (xy 37.608764 -355.014276)
			(xy 37.609295 -354.986262) (xy 37.617514 -354.93084) (xy 37.633742 -354.877213) (xy 37.657631 -354.826533)
			(xy 37.688668 -354.779887) (xy 37.707062 -354.758752) (xy 37.716729 -354.747326) (xy 37.729509 -354.720278)
			(xy 37.733892 -354.690685) (xy 37.7295 -354.661093) (xy 37.716712 -354.634049) (xy 37.707062 -354.622608)
			(xy 37.688634 -354.601497) (xy 37.657566 -354.55486) (xy 37.633664 -354.504176) (xy 37.617442 -354.450538)
			(xy 37.609252 -354.395103) (xy 37.608764 -354.367084) (xy 37.608764 -354.36683) (xy 37.609283 -354.339579)
			(xy 37.617035 -354.285632) (xy 37.632386 -354.233337) (xy 37.655023 -354.183758) (xy 37.684485 -354.137907)
			(xy 37.720173 -354.096714) (xy 37.76136 -354.06102) (xy 37.807207 -354.031551) (xy 37.856782 -354.008906)
			(xy 37.909075 -353.993548) (xy 37.963021 -353.985787) (xy 37.990272 -353.985322) (xy 38.018247 -353.98581)
			(xy 38.073597 -353.993985) (xy 38.127158 -354.010163) (xy 38.177778 -354.033997) (xy 38.201346 -354.049076)
			(xy 38.832536 -354.049076) (xy 38.857486 -354.04956) (xy 38.906769 -354.057377) (xy 38.954226 -354.072797)
			(xy 38.998692 -354.095441) (xy 39.039074 -354.124754) (xy 39.057072 -354.14204) (xy 39.39794 -354.482908)
			(xy 41.32961 -354.482908) (xy 41.80205 -354.010468) (xy 41.820014 -353.993142) (xy 41.860396 -353.963815)
			(xy 41.904869 -353.941167) (xy 41.952337 -353.925756) (xy 42.001632 -353.917961) (xy 42.026586 -353.917504)
			(xy 44.277534 -353.917504) (xy 44.855384 -353.3394) (xy 44.873382 -353.322113) (xy 44.913757 -353.292789)
			(xy 44.958222 -353.27014) (xy 45.005683 -353.254725) (xy 45.05497 -353.246924) (xy 45.07992 -353.246436)
			(xy 46.869858 -353.246436) (xy 46.894808 -353.246918) (xy 46.944091 -353.254737) (xy 46.991547 -353.270158)
			(xy 47.036013 -353.292802) (xy 47.076396 -353.322115) (xy 47.094394 -353.3394) (xy 47.753778 -353.998784)
			(xy 47.767748 -354.00234) (xy 47.79514 -354.009472) (xy 47.847617 -354.030684) (xy 47.896384 -354.059417)
			(xy 47.94037 -354.095039) (xy 47.97861 -354.13677) (xy 48.010264 -354.183692) (xy 48.034639 -354.234777)
			(xy 48.051198 -354.288902) (xy 48.059578 -354.344879) (xy 48.060102 -354.37318) (xy 48.059624 -354.40055)
			(xy 48.051809 -354.454728) (xy 48.036323 -354.507231) (xy 48.013484 -354.556978) (xy 47.983762 -354.602946)
			(xy 47.966122 -354.623878) (xy 47.956903 -354.635219) (xy 47.94472 -354.661771) (xy 47.940543 -354.690685)
			(xy 47.944712 -354.7196) (xy 47.956886 -354.746156) (xy 47.966122 -354.757482) (xy 47.98377 -354.778407)
			(xy 48.013479 -354.824382) (xy 48.036313 -354.874132) (xy 48.051802 -354.926634) (xy 48.059629 -354.98081)
			(xy 48.060102 -355.00818) (xy 48.059616 -355.035431) (xy 48.05186 -355.089379) (xy 48.036505 -355.141674)
			(xy 48.013863 -355.191251) (xy 47.984397 -355.237101) (xy 47.948706 -355.278292) (xy 47.907515 -355.313983)
			(xy 47.861665 -355.343449) (xy 47.812088 -355.366091) (xy 47.759793 -355.381446) (xy 47.705845 -355.389202)
			(xy 47.651343 -355.389202) (xy 47.597395 -355.381446) (xy 47.5451 -355.366091) (xy 47.495523 -355.343449)
			(xy 47.449673 -355.313983) (xy 47.408482 -355.278292) (xy 47.372791 -355.237101) (xy 47.343325 -355.191251)
			(xy 47.320683 -355.141674) (xy 47.305328 -355.089379) (xy 47.297572 -355.035431) (xy 47.297086 -355.00818)
			(xy 47.297544 -354.98081) (xy 47.305364 -354.92663) (xy 47.320855 -354.874127) (xy 47.343699 -354.82438)
			(xy 47.373424 -354.778414) (xy 47.391066 -354.757482) (xy 47.400325 -354.74617) (xy 47.412504 -354.719608)
			(xy 47.416674 -354.690685) (xy 47.412495 -354.661763) (xy 47.400308 -354.635204) (xy 47.391066 -354.623878)
			(xy 47.371448 -354.600431) (xy 47.339135 -354.548539) (xy 47.315509 -354.492159) (xy 47.307754 -354.462588)
			(xy 47.307754 -354.462334) (xy 47.304198 -354.448364) (xy 46.738032 -353.881944) (xy 45.211746 -353.881944)
			(xy 44.633896 -354.460048) (xy 44.615915 -354.477355) (xy 44.575537 -354.506684) (xy 44.531069 -354.529335)
			(xy 44.483604 -354.54475) (xy 44.434313 -354.552551) (xy 44.40936 -354.553012) (xy 42.158412 -354.553012)
			(xy 42.083522 -354.627942) (xy 45.58614 -354.627942) (xy 45.590211 -354.57232) (xy 45.602337 -354.517883)
			(xy 45.62226 -354.465792) (xy 45.649556 -354.417157) (xy 45.683642 -354.373014) (xy 45.723791 -354.334305)
			(xy 45.769149 -354.301854) (xy 45.818749 -354.276353) (xy 45.871533 -354.258346) (xy 45.926376 -354.248216)
			(xy 45.98211 -354.246179) (xy 46.037547 -354.252279) (xy 46.091504 -354.266385) (xy 46.142833 -354.288197)
			(xy 46.190439 -354.317251) (xy 46.233307 -354.352926) (xy 46.270524 -354.394463) (xy 46.301297 -354.440976)
			(xy 46.324969 -354.491473) (xy 46.341037 -354.54488) (xy 46.349157 -354.600056) (xy 46.349666 -354.627942)
			(xy 46.349157 -354.655828) (xy 46.341037 -354.711004) (xy 46.324969 -354.764411) (xy 46.301297 -354.814908)
			(xy 46.270524 -354.861421) (xy 46.233307 -354.902958) (xy 46.190439 -354.938633) (xy 46.142833 -354.967687)
			(xy 46.091504 -354.989499) (xy 46.037547 -355.003605) (xy 45.98211 -355.009705) (xy 45.926376 -355.007668)
			(xy 45.871533 -354.997538) (xy 45.818749 -354.979531) (xy 45.769149 -354.95403) (xy 45.723791 -354.921579)
			(xy 45.683642 -354.88287) (xy 45.649556 -354.838727) (xy 45.62226 -354.790092) (xy 45.602337 -354.738001)
			(xy 45.590211 -354.683564) (xy 45.58614 -354.627942) (xy 42.083522 -354.627942) (xy 41.685972 -355.025706)
			(xy 41.667949 -355.043013) (xy 41.627527 -355.072381) (xy 41.583015 -355.095078) (xy 41.535506 -355.110546)
			(xy 41.486164 -355.118407) (xy 41.461182 -355.118924) (xy 39.266368 -355.118924) (xy 39.241379 -355.118483)
			(xy 39.192017 -355.110652) (xy 39.144491 -355.095187) (xy 39.099973 -355.072471) (xy 39.059562 -355.043063)
			(xy 39.041578 -355.025706) (xy 38.70071 -354.684584) (xy 38.415976 -354.684584) (xy 38.400988 -354.685168)
			(xy 38.372311 -354.693905) (xy 38.347405 -354.71059) (xy 38.328415 -354.733786) (xy 38.316976 -354.761495)
			(xy 38.314073 -354.791333) (xy 38.319956 -354.820728) (xy 38.326568 -354.83419) (xy 38.340793 -354.862054)
			(xy 38.360947 -354.921277) (xy 38.371155 -354.982997) (xy 38.37178 -355.014276) (xy 38.37178 -355.01453)
			(xy 38.371294 -355.041781) (xy 38.363538 -355.095729) (xy 38.348183 -355.148024) (xy 38.325541 -355.197601)
			(xy 38.296075 -355.243451) (xy 38.260384 -355.284642) (xy 38.219193 -355.320333) (xy 38.173343 -355.349799)
			(xy 38.123766 -355.372441) (xy 38.071471 -355.387796) (xy 38.017523 -355.395552) (xy 37.963021 -355.395552)
			(xy 37.909073 -355.387796) (xy 37.856778 -355.372441) (xy 37.807201 -355.349799) (xy 37.761351 -355.320333)
			(xy 37.72016 -355.284642) (xy 37.684469 -355.243451) (xy 37.655003 -355.197601) (xy 37.632361 -355.148024)
			(xy 37.617006 -355.095729) (xy 37.60925 -355.041781) (xy 37.608764 -355.01453) (xy 35.721478 -355.01453)
			(xy 35.719414 -355.015407) (xy 35.665457 -355.029513) (xy 35.61002 -355.035613) (xy 35.554286 -355.033576)
			(xy 35.499443 -355.023446) (xy 35.446659 -355.005439) (xy 35.397059 -354.979938) (xy 35.351701 -354.947487)
			(xy 35.311552 -354.908778) (xy 35.277466 -354.864635) (xy 35.25017 -354.816) (xy 35.230247 -354.763909)
			(xy 35.218121 -354.709472) (xy 35.21405 -354.65385) (xy 34.902394 -354.65385) (xy 34.902394 -355.4108)
			(xy 41.857303 -355.4108) (xy 41.861472 -355.355173) (xy 41.873886 -355.30079) (xy 41.894268 -355.248864)
			(xy 41.922161 -355.200556) (xy 41.956943 -355.156945) (xy 41.997837 -355.119006) (xy 42.04393 -355.087586)
			(xy 42.09419 -355.063388) (xy 42.147496 -355.046951) (xy 42.202657 -355.038644) (xy 42.230548 -355.038152)
			(xy 42.25788 -355.038623) (xy 42.31196 -355.046592) (xy 42.364295 -355.062379) (xy 42.41376 -355.085647)
			(xy 42.459292 -355.115895) (xy 42.499914 -355.152474) (xy 42.534753 -355.194597) (xy 42.549318 -355.21773)
			(xy 42.557239 -355.229955) (xy 42.578713 -355.249623) (xy 42.604866 -355.262425) (xy 42.633571 -355.267321)
			(xy 42.66249 -355.26391) (xy 42.676064 -355.258624) (xy 42.69928 -355.249149) (xy 42.74761 -355.235794)
			(xy 42.797297 -355.229059) (xy 42.822368 -355.228652) (xy 42.847438 -355.229064) (xy 42.897121 -355.235818)
			(xy 42.945455 -355.249155) (xy 42.968672 -355.258624) (xy 42.982249 -355.263871) (xy 43.011149 -355.267234)
			(xy 43.039827 -355.262322) (xy 43.065961 -355.249534) (xy 43.087437 -355.229904) (xy 43.095418 -355.21773)
			(xy 43.109987 -355.194599) (xy 43.14483 -355.152478) (xy 43.185453 -355.115899) (xy 43.230984 -355.085648)
			(xy 43.280446 -355.062372) (xy 43.332777 -355.046572) (xy 43.386856 -355.038586) (xy 43.44152 -355.038586)
			(xy 43.495599 -355.046572) (xy 43.54793 -355.062372) (xy 43.597392 -355.085648) (xy 43.642923 -355.115899)
			(xy 43.683546 -355.152478) (xy 43.718389 -355.194599) (xy 43.732958 -355.21773) (xy 43.740841 -355.229983)
			(xy 43.762325 -355.24965) (xy 43.788489 -355.262449) (xy 43.817203 -355.267337) (xy 43.846128 -355.263916)
			(xy 43.859704 -355.258624) (xy 43.882915 -355.249137) (xy 43.931247 -355.235786) (xy 43.980937 -355.229057)
			(xy 44.006008 -355.228652) (xy 44.033193 -355.229125) (xy 44.086987 -355.237015) (xy 44.139062 -355.252639)
			(xy 44.188314 -355.275667) (xy 44.233695 -355.305609) (xy 44.274243 -355.34183) (xy 44.309095 -355.383559)
			(xy 44.337512 -355.429911) (xy 44.348654 -355.454712) (xy 44.354556 -355.467303) (xy 44.371962 -355.48897)
			(xy 44.394568 -355.50514) (xy 44.420697 -355.514612) (xy 44.448413 -355.516686) (xy 44.475661 -355.511206)
			(xy 44.500421 -355.498581) (xy 44.51096 -355.48951) (xy 44.532202 -355.470607) (xy 44.579249 -355.438674)
			(xy 44.630518 -355.414084) (xy 44.684871 -355.397383) (xy 44.741102 -355.388941) (xy 44.769532 -355.388418)
			(xy 44.787551 -355.38864) (xy 44.823426 -355.392074) (xy 44.84116 -355.395276) (xy 44.856375 -355.397561)
			(xy 44.88692 -355.394044) (xy 44.915035 -355.381595) (xy 44.93817 -355.361343) (xy 44.954229 -355.335122)
			(xy 44.958508 -355.320346) (xy 44.965907 -355.293302) (xy 44.987537 -355.241577) (xy 45.016502 -355.193572)
			(xy 45.052177 -355.15032) (xy 45.093796 -355.112754) (xy 45.140463 -355.081679) (xy 45.191174 -355.057766)
			(xy 45.244838 -355.041529) (xy 45.300299 -355.033317) (xy 45.328332 -355.032818) (xy 45.355585 -355.033248)
			(xy 45.409536 -355.04101) (xy 45.461834 -355.05637) (xy 45.511413 -355.079017) (xy 45.557264 -355.108489)
			(xy 45.598455 -355.144186) (xy 45.634146 -355.185382) (xy 45.663611 -355.231238) (xy 45.68625 -355.280821)
			(xy 45.701603 -355.33312) (xy 45.709356 -355.387073) (xy 45.709777 -355.4108) (xy 51.545729 -355.4108)
			(xy 51.549897 -355.355185) (xy 51.562307 -355.300812) (xy 51.582681 -355.248895) (xy 51.610566 -355.200595)
			(xy 51.645337 -355.15699) (xy 51.686219 -355.119054) (xy 51.732297 -355.087635) (xy 51.782544 -355.063434)
			(xy 51.835837 -355.046991) (xy 51.890984 -355.038675) (xy 51.91887 -355.038152) (xy 51.946203 -355.038606)
			(xy 52.000284 -355.046577) (xy 52.052619 -355.062368) (xy 52.102083 -355.085639) (xy 52.147616 -355.115889)
			(xy 52.188237 -355.15247) (xy 52.223075 -355.194596) (xy 52.23764 -355.21773) (xy 52.24554 -355.22997)
			(xy 52.267019 -355.249638) (xy 52.293179 -355.262438) (xy 52.321888 -355.26733) (xy 52.350811 -355.263914)
			(xy 52.364386 -355.258624) (xy 52.387599 -355.249143) (xy 52.43593 -355.235789) (xy 52.485619 -355.229058)
			(xy 52.51069 -355.228652) (xy 52.535759 -355.229089) (xy 52.585442 -355.235833) (xy 52.633776 -355.24916)
			(xy 52.656994 -355.258624) (xy 52.670599 -355.263789) (xy 52.699485 -355.267169) (xy 52.728153 -355.262276)
			(xy 52.754282 -355.249507) (xy 52.775757 -355.229895) (xy 52.78374 -355.21773) (xy 52.798309 -355.194599)
			(xy 52.833152 -355.152478) (xy 52.873775 -355.115899) (xy 52.919306 -355.085648) (xy 52.968768 -355.062372)
			(xy 53.021099 -355.046572) (xy 53.075178 -355.038586) (xy 53.129842 -355.038586) (xy 53.183921 -355.046572)
			(xy 53.236252 -355.062372) (xy 53.285714 -355.085648) (xy 53.331245 -355.115899) (xy 53.371868 -355.152478)
			(xy 53.406711 -355.194599) (xy 53.42128 -355.21773) (xy 53.429237 -355.229929) (xy 53.450701 -355.249597)
			(xy 53.476845 -355.262403) (xy 53.505541 -355.267305) (xy 53.534453 -355.263904) (xy 53.548026 -355.258624)
			(xy 53.571234 -355.24913) (xy 53.619568 -355.235782) (xy 53.669258 -355.229055) (xy 53.69433 -355.228652)
			(xy 53.721172 -355.22911) (xy 53.774301 -355.236818) (xy 53.825774 -355.25207) (xy 53.874526 -355.27455)
			(xy 53.919548 -355.303792) (xy 53.959907 -355.339193) (xy 53.994769 -355.380018) (xy 54.023412 -355.425424)
			(xy 54.045244 -355.47447) (xy 54.052978 -355.500178) (xy 54.057673 -355.514662) (xy 54.074188 -355.540221)
			(xy 54.097497 -355.559782) (xy 54.125532 -355.571613) (xy 54.155809 -355.574663) (xy 54.185641 -355.568663)
			(xy 54.199282 -355.5619) (xy 54.227424 -355.547258) (xy 54.287377 -355.526534) (xy 54.349937 -355.516039)
			(xy 54.381654 -355.515418) (xy 54.409825 -355.515918) (xy 54.465554 -355.524209) (xy 54.492652 -355.531928)
			(xy 54.506084 -355.535519) (xy 54.533869 -355.53613) (xy 54.56079 -355.529225) (xy 54.584851 -355.515317)
			(xy 54.60427 -355.495435) (xy 54.617608 -355.471053) (xy 54.623877 -355.443977) (xy 54.623716 -355.430074)
			(xy 54.623208 -355.413056) (xy 54.623208 -355.412802) (xy 54.623654 -355.385561) (xy 54.631447 -355.331638)
			(xy 54.64683 -355.279371) (xy 54.669492 -355.229825) (xy 54.698971 -355.184006) (xy 54.734668 -355.142846)
			(xy 54.775858 -355.107183) (xy 54.821701 -355.077741) (xy 54.871266 -355.05512) (xy 54.923545 -355.03978)
			(xy 54.977474 -355.032032) (xy 55.004716 -355.031548) (xy 55.031966 -355.032063) (xy 55.08591 -355.03982)
			(xy 55.138202 -355.055175) (xy 55.187776 -355.077815) (xy 55.233624 -355.107279) (xy 55.274813 -355.142967)
			(xy 55.310504 -355.184153) (xy 55.339972 -355.229999) (xy 55.362615 -355.279572) (xy 55.377974 -355.331863)
			(xy 55.385735 -355.385806) (xy 55.386224 -355.413056) (xy 55.38572 -355.440629) (xy 55.377774 -355.4952)
			(xy 55.362056 -355.548059) (xy 55.338893 -355.598105) (xy 55.308768 -355.644295) (xy 55.272308 -355.685669)
			(xy 55.251604 -355.703886) (xy 55.240751 -355.713829) (xy 55.224677 -355.738467) (xy 55.216288 -355.766663)
			(xy 55.216279 -355.79608) (xy 55.224653 -355.824281) (xy 55.240713 -355.848928) (xy 55.251604 -355.858826)
			(xy 55.272265 -355.87709) (xy 55.308728 -355.918455) (xy 55.338855 -355.964639) (xy 55.362019 -356.01468)
			(xy 55.377736 -356.067534) (xy 55.38568 -356.122101) (xy 55.385684 -356.177242) (xy 55.377749 -356.23181)
			(xy 55.362039 -356.284667) (xy 55.338883 -356.334711) (xy 55.308763 -356.3809) (xy 55.272306 -356.42227)
			(xy 55.251604 -356.440486) (xy 55.240751 -356.450429) (xy 55.224677 -356.475067) (xy 55.216288 -356.503263)
			(xy 55.216279 -356.53268) (xy 55.224653 -356.560881) (xy 55.240713 -356.585528) (xy 55.251604 -356.595426)
			(xy 55.272332 -356.613619) (xy 55.308801 -356.654992) (xy 55.338931 -356.701185) (xy 55.362093 -356.751237)
			(xy 55.377806 -356.804103) (xy 55.385741 -356.85868) (xy 55.386224 -356.886256) (xy 55.385704 -356.913507)
			(xy 55.377953 -356.967455) (xy 55.362604 -357.019751) (xy 55.339967 -357.06933) (xy 55.310505 -357.115182)
			(xy 55.274818 -357.156375) (xy 55.23363 -357.192069) (xy 55.187783 -357.221539) (xy 55.138207 -357.244183)
			(xy 55.085914 -357.25954) (xy 55.031967 -357.2673) (xy 55.004716 -357.267764) (xy 54.978798 -357.267319)
			(xy 54.927439 -357.26031) (xy 54.877503 -357.246404) (xy 54.829912 -357.22586) (xy 54.785546 -357.199055)
			(xy 54.745221 -357.166484) (xy 54.709682 -357.128749) (xy 54.679585 -357.086546) (xy 54.66715 -357.063802)
			(xy 54.659833 -357.051012) (xy 54.639245 -357.029952) (xy 54.613507 -357.015635) (xy 54.584755 -357.009251)
			(xy 54.555377 -357.011328) (xy 54.54142 -357.01605) (xy 54.509071 -357.027446) (xy 54.441598 -357.039713)
			(xy 54.407308 -357.040434) (xy 54.407054 -357.040434) (xy 54.392905 -357.040345) (xy 54.364682 -357.038308)
			(xy 54.350666 -357.03637) (xy 54.337314 -357.034836) (xy 54.31063 -357.037929) (xy 54.285681 -357.04789)
			(xy 54.264204 -357.064025) (xy 54.24769 -357.085213) (xy 54.237288 -357.10998) (xy 54.235096 -357.123238)
			(xy 54.231023 -357.150394) (xy 54.21605 -357.203226) (xy 54.193657 -357.253366) (xy 54.164308 -357.299777)
			(xy 54.12861 -357.341502) (xy 54.087298 -357.377679) (xy 54.041227 -357.407559) (xy 53.991348 -357.430527)
			(xy 53.938692 -357.446107) (xy 53.884346 -357.453977) (xy 53.85689 -357.454454) (xy 53.829641 -357.453932)
			(xy 53.775697 -357.446175) (xy 53.723405 -357.430821) (xy 53.673831 -357.408182) (xy 53.627983 -357.378719)
			(xy 53.586794 -357.343031) (xy 53.551103 -357.301846) (xy 53.521635 -357.256001) (xy 53.498992 -357.206428)
			(xy 53.483633 -357.154139) (xy 53.475871 -357.100195) (xy 53.475382 -357.072946) (xy 53.475886 -357.045373)
			(xy 53.483831 -356.990802) (xy 53.499549 -356.937943) (xy 53.522712 -356.887897) (xy 53.552838 -356.841707)
			(xy 53.589298 -356.800333) (xy 53.610002 -356.782116) (xy 53.620852 -356.77217) (xy 53.636926 -356.747533)
			(xy 53.645315 -356.719338) (xy 53.645323 -356.689921) (xy 53.636951 -356.661721) (xy 53.620892 -356.637075)
			(xy 53.610002 -356.627176) (xy 53.589276 -356.608981) (xy 53.552807 -356.567609) (xy 53.522677 -356.521415)
			(xy 53.499513 -356.471364) (xy 53.4838 -356.418499) (xy 53.475865 -356.363922) (xy 53.475382 -356.336346)
			(xy 53.475827 -356.309845) (xy 53.483175 -356.257353) (xy 53.497722 -356.206386) (xy 53.519187 -356.157924)
			(xy 53.547156 -356.112901) (xy 53.563774 -356.092252) (xy 53.573204 -356.080099) (xy 53.584989 -356.051701)
			(xy 53.587811 -356.021084) (xy 53.581417 -355.991011) (xy 53.566382 -355.964191) (xy 53.544063 -355.943044)
			(xy 53.5305 -355.935788) (xy 53.506801 -355.923703) (xy 53.462822 -355.893775) (xy 53.423543 -355.857899)
			(xy 53.389762 -355.816804) (xy 53.37556 -355.79431) (xy 53.36765 -355.782076) (xy 53.346176 -355.762403)
			(xy 53.320019 -355.749599) (xy 53.29131 -355.744707) (xy 53.262388 -355.748125) (xy 53.248814 -355.753416)
			(xy 53.2256 -355.762894) (xy 53.177269 -355.776249) (xy 53.127581 -355.782982) (xy 53.10251 -355.783388)
			(xy 53.077441 -355.782948) (xy 53.027759 -355.776205) (xy 52.979424 -355.762879) (xy 52.956206 -355.753416)
			(xy 52.942619 -355.748185) (xy 52.913715 -355.744801) (xy 52.885029 -355.749698) (xy 52.858885 -355.762479)
			(xy 52.837401 -355.782108) (xy 52.82946 -355.79431) (xy 52.814891 -355.817441) (xy 52.780048 -355.859562)
			(xy 52.739425 -355.896141) (xy 52.693894 -355.926392) (xy 52.644432 -355.949668) (xy 52.592101 -355.965468)
			(xy 52.538022 -355.973454) (xy 52.483358 -355.973454) (xy 52.429279 -355.965468) (xy 52.376948 -355.949668)
			(xy 52.327486 -355.926392) (xy 52.281955 -355.896141) (xy 52.241332 -355.859562) (xy 52.206489 -355.817441)
			(xy 52.19192 -355.79431) (xy 52.183953 -355.782117) (xy 52.162494 -355.762445) (xy 52.136353 -355.749635)
			(xy 52.107657 -355.744732) (xy 52.078746 -355.748134) (xy 52.065174 -355.753416) (xy 52.041965 -355.762907)
			(xy 51.993631 -355.776257) (xy 51.943942 -355.782985) (xy 51.91887 -355.783388) (xy 51.890984 -355.782925)
			(xy 51.835837 -355.774609) (xy 51.782544 -355.758166) (xy 51.732297 -355.733965) (xy 51.686219 -355.702546)
			(xy 51.645337 -355.66461) (xy 51.610566 -355.621005) (xy 51.582681 -355.572705) (xy 51.562307 -355.520788)
			(xy 51.549897 -355.466415) (xy 51.545729 -355.4108) (xy 45.709777 -355.4108) (xy 45.70984 -355.414326)
			(xy 45.709344 -355.4419) (xy 45.701401 -355.496472) (xy 45.685683 -355.549332) (xy 45.662519 -355.599379)
			(xy 45.632391 -355.645569) (xy 45.595926 -355.68694) (xy 45.57522 -355.705156) (xy 45.564295 -355.715027)
			(xy 45.548221 -355.739685) (xy 45.539839 -355.7679) (xy 45.539844 -355.797334) (xy 45.548235 -355.825546)
			(xy 45.564318 -355.850198) (xy 45.57522 -355.860096) (xy 45.595951 -355.878284) (xy 45.632412 -355.91966)
			(xy 45.662537 -355.965854) (xy 45.685697 -356.015904) (xy 45.70141 -356.068768) (xy 45.709347 -356.123342)
			(xy 45.709345 -356.178491) (xy 45.701402 -356.233065) (xy 45.685685 -356.285927) (xy 45.662521 -356.335976)
			(xy 45.632392 -356.382167) (xy 45.595927 -356.42354) (xy 45.57522 -356.441756) (xy 45.564295 -356.451627)
			(xy 45.548221 -356.476285) (xy 45.548141 -356.476554) (xy 48.08804 -356.476554) (xy 48.092111 -356.420932)
			(xy 48.104237 -356.366495) (xy 48.12416 -356.314404) (xy 48.151456 -356.265769) (xy 48.185542 -356.221626)
			(xy 48.225691 -356.182917) (xy 48.271049 -356.150466) (xy 48.320649 -356.124965) (xy 48.373433 -356.106958)
			(xy 48.428276 -356.096828) (xy 48.48401 -356.094791) (xy 48.539447 -356.100891) (xy 48.593404 -356.114997)
			(xy 48.644733 -356.136809) (xy 48.692339 -356.165863) (xy 48.735207 -356.201538) (xy 48.772424 -356.243075)
			(xy 48.803197 -356.289588) (xy 48.826869 -356.340085) (xy 48.842937 -356.393492) (xy 48.851057 -356.448668)
			(xy 48.851566 -356.476554) (xy 48.851057 -356.50444) (xy 48.842937 -356.559616) (xy 48.826869 -356.613023)
			(xy 48.803197 -356.66352) (xy 48.772424 -356.710033) (xy 48.735207 -356.75157) (xy 48.692339 -356.787245)
			(xy 48.644733 -356.816299) (xy 48.593404 -356.838111) (xy 48.539447 -356.852217) (xy 48.48401 -356.858317)
			(xy 48.428276 -356.85628) (xy 48.373433 -356.84615) (xy 48.320649 -356.828143) (xy 48.271049 -356.802642)
			(xy 48.225691 -356.770191) (xy 48.185542 -356.731482) (xy 48.151456 -356.687339) (xy 48.12416 -356.638704)
			(xy 48.104237 -356.586613) (xy 48.092111 -356.532176) (xy 48.08804 -356.476554) (xy 45.548141 -356.476554)
			(xy 45.539839 -356.5045) (xy 45.539844 -356.533934) (xy 45.548235 -356.562146) (xy 45.564318 -356.586798)
			(xy 45.57522 -356.596696) (xy 45.595936 -356.614901) (xy 45.632405 -356.656272) (xy 45.662536 -356.702463)
			(xy 45.685701 -356.752512) (xy 45.701417 -356.805375) (xy 45.709355 -356.859951) (xy 45.70984 -356.887526)
			(xy 45.709346 -356.914776) (xy 45.701587 -356.968722) (xy 45.68623 -357.021015) (xy 45.663589 -357.07059)
			(xy 45.634123 -357.116439) (xy 45.598432 -357.157628) (xy 45.557244 -357.193319) (xy 45.511395 -357.222786)
			(xy 45.46182 -357.245428) (xy 45.409528 -357.260786) (xy 45.355582 -357.268546) (xy 45.328332 -357.269034)
			(xy 45.300479 -357.268457) (xy 45.245367 -357.260339) (xy 45.192019 -357.244299) (xy 45.141568 -357.220679)
			(xy 45.095084 -357.189979) (xy 45.053555 -357.15285) (xy 45.01786 -357.110082) (xy 44.988758 -357.062581)
			(xy 44.966867 -357.011356) (xy 44.95927 -356.984554) (xy 44.955023 -356.97043) (xy 44.939621 -356.945288)
			(xy 44.917696 -356.925576) (xy 44.891063 -356.912927) (xy 44.861931 -356.90839) (xy 44.847256 -356.909878)
			(xy 44.834303 -356.911544) (xy 44.808245 -356.913321) (xy 44.795186 -356.913434) (xy 44.794932 -356.913434)
			(xy 44.794678 -356.913434) (xy 44.765642 -356.912893) (xy 44.708242 -356.90409) (xy 44.680378 -356.895908)
			(xy 44.66662 -356.892054) (xy 44.638072 -356.891306) (xy 44.610434 -356.898498) (xy 44.58587 -356.913066)
			(xy 44.566305 -356.933869) (xy 44.553269 -356.959279) (xy 44.547784 -356.987305) (xy 44.548552 -357.001572)
			(xy 44.550076 -357.034846) (xy 44.549665 -357.0621) (xy 44.541901 -357.116052) (xy 44.526539 -357.16835)
			(xy 44.50389 -357.21793) (xy 44.474416 -357.263781) (xy 44.443447 -357.299514) (xy 47.423576 -357.299514)
			(xy 47.427647 -357.243892) (xy 47.439773 -357.189455) (xy 47.459696 -357.137364) (xy 47.486992 -357.088729)
			(xy 47.521078 -357.044586) (xy 47.561227 -357.005877) (xy 47.606585 -356.973426) (xy 47.656185 -356.947925)
			(xy 47.708969 -356.929918) (xy 47.763812 -356.919788) (xy 47.819546 -356.917751) (xy 47.874983 -356.923851)
			(xy 47.92894 -356.937957) (xy 47.980269 -356.959769) (xy 48.027875 -356.988823) (xy 48.070743 -357.024498)
			(xy 48.10796 -357.066035) (xy 48.138733 -357.112548) (xy 48.162405 -357.163045) (xy 48.178473 -357.216452)
			(xy 48.186593 -357.271628) (xy 48.187102 -357.299514) (xy 48.186593 -357.3274) (xy 48.178473 -357.382576)
			(xy 48.162405 -357.435983) (xy 48.138733 -357.48648) (xy 48.10796 -357.532993) (xy 48.070743 -357.57453)
			(xy 48.027875 -357.610205) (xy 47.980269 -357.639259) (xy 47.92894 -357.661071) (xy 47.874983 -357.675177)
			(xy 47.819546 -357.681277) (xy 47.763812 -357.67924) (xy 47.708969 -357.66911) (xy 47.656185 -357.651103)
			(xy 47.606585 -357.625602) (xy 47.561227 -357.593151) (xy 47.521078 -357.554442) (xy 47.486992 -357.510299)
			(xy 47.459696 -357.461664) (xy 47.439773 -357.409573) (xy 47.427647 -357.355136) (xy 47.423576 -357.299514)
			(xy 44.443447 -357.299514) (xy 44.438717 -357.304972) (xy 44.397519 -357.340663) (xy 44.351661 -357.370127)
			(xy 44.302077 -357.392766) (xy 44.249776 -357.408118) (xy 44.195822 -357.41587) (xy 44.168568 -357.416354)
			(xy 44.141318 -357.415852) (xy 44.087373 -357.408092) (xy 44.035082 -357.392736) (xy 43.985507 -357.370094)
			(xy 43.939659 -357.340629) (xy 43.898471 -357.304939) (xy 43.86278 -357.263752) (xy 43.833313 -357.217905)
			(xy 43.810669 -357.168331) (xy 43.795311 -357.11604) (xy 43.787549 -357.062096) (xy 43.78706 -357.034846)
			(xy 43.787536 -357.007272) (xy 43.795484 -356.952698) (xy 43.811205 -356.899838) (xy 43.834373 -356.849791)
			(xy 43.864505 -356.803602) (xy 43.900973 -356.762231) (xy 43.92168 -356.744016) (xy 43.932533 -356.734071)
			(xy 43.948609 -356.709435) (xy 43.957 -356.681239) (xy 43.957009 -356.651821) (xy 43.948635 -356.623619)
			(xy 43.932572 -356.598973) (xy 43.92168 -356.589076) (xy 43.90095 -356.570885) (xy 43.864482 -356.529512)
			(xy 43.834353 -356.483317) (xy 43.81119 -356.433265) (xy 43.795478 -356.3804) (xy 43.787543 -356.325822)
			(xy 43.78706 -356.298246) (xy 43.787663 -356.268495) (xy 43.796938 -356.209719) (xy 43.81521 -356.15309)
			(xy 43.842036 -356.099976) (xy 43.858942 -356.075488) (xy 43.866861 -356.063559) (xy 43.87646 -356.036601)
			(xy 43.878193 -356.008037) (xy 43.871925 -355.980115) (xy 43.85815 -355.955033) (xy 43.83795 -355.934763)
			(xy 43.825668 -355.927406) (xy 43.804606 -355.915307) (xy 43.765515 -355.886475) (xy 43.7305 -355.852809)
			(xy 43.700154 -355.814881) (xy 43.687238 -355.79431) (xy 43.679349 -355.782061) (xy 43.657869 -355.762388)
			(xy 43.631706 -355.749586) (xy 43.602992 -355.744698) (xy 43.574067 -355.748121) (xy 43.560492 -355.753416)
			(xy 43.53728 -355.762901) (xy 43.488948 -355.776254) (xy 43.439259 -355.782984) (xy 43.414188 -355.783388)
			(xy 43.389119 -355.782955) (xy 43.339436 -355.776209) (xy 43.291102 -355.76288) (xy 43.267884 -355.753416)
			(xy 43.254305 -355.748162) (xy 43.225397 -355.744783) (xy 43.196708 -355.749685) (xy 43.170562 -355.762471)
			(xy 43.149078 -355.782106) (xy 43.141138 -355.79431) (xy 43.126569 -355.817441) (xy 43.091726 -355.859562)
			(xy 43.051103 -355.896141) (xy 43.005572 -355.926392) (xy 42.95611 -355.949668) (xy 42.903779 -355.965468)
			(xy 42.8497 -355.973454) (xy 42.795036 -355.973454) (xy 42.740957 -355.965468) (xy 42.688626 -355.949668)
			(xy 42.639164 -355.926392) (xy 42.593633 -355.896141) (xy 42.55301 -355.859562) (xy 42.518167 -355.817441)
			(xy 42.503598 -355.79431) (xy 42.495652 -355.782102) (xy 42.474188 -355.76243) (xy 42.44804 -355.749622)
			(xy 42.41934 -355.744723) (xy 42.390425 -355.748131) (xy 42.376852 -355.753416) (xy 42.353645 -355.762913)
			(xy 42.305311 -355.776261) (xy 42.25562 -355.782986) (xy 42.230548 -355.783388) (xy 42.202657 -355.782956)
			(xy 42.147496 -355.774649) (xy 42.09419 -355.758212) (xy 42.04393 -355.734014) (xy 41.997837 -355.702594)
			(xy 41.956943 -355.664655) (xy 41.922161 -355.621044) (xy 41.894268 -355.572736) (xy 41.873886 -355.52081)
			(xy 41.861472 -355.466427) (xy 41.857303 -355.4108) (xy 34.902394 -355.4108) (xy 34.902394 -356.80523)
			(xy 37.03396 -356.80523) (xy 37.038031 -356.749608) (xy 37.050157 -356.695171) (xy 37.07008 -356.64308)
			(xy 37.097376 -356.594445) (xy 37.131462 -356.550302) (xy 37.171611 -356.511593) (xy 37.216969 -356.479142)
			(xy 37.266569 -356.453641) (xy 37.319353 -356.435634) (xy 37.374196 -356.425504) (xy 37.42993 -356.423467)
			(xy 37.485367 -356.429567) (xy 37.539324 -356.443673) (xy 37.590653 -356.465485) (xy 37.60879 -356.476554)
			(xy 38.399718 -356.476554) (xy 38.403789 -356.420932) (xy 38.415915 -356.366495) (xy 38.435838 -356.314404)
			(xy 38.463134 -356.265769) (xy 38.49722 -356.221626) (xy 38.537369 -356.182917) (xy 38.582727 -356.150466)
			(xy 38.632327 -356.124965) (xy 38.685111 -356.106958) (xy 38.739954 -356.096828) (xy 38.795688 -356.094791)
			(xy 38.851125 -356.100891) (xy 38.905082 -356.114997) (xy 38.956411 -356.136809) (xy 39.004017 -356.165863)
			(xy 39.046885 -356.201538) (xy 39.084102 -356.243075) (xy 39.114875 -356.289588) (xy 39.138547 -356.340085)
			(xy 39.154615 -356.393492) (xy 39.162735 -356.448668) (xy 39.163244 -356.476554) (xy 39.162735 -356.50444)
			(xy 39.154615 -356.559616) (xy 39.138547 -356.613023) (xy 39.114875 -356.66352) (xy 39.084102 -356.710033)
			(xy 39.046885 -356.75157) (xy 39.004017 -356.787245) (xy 38.956411 -356.816299) (xy 38.905082 -356.838111)
			(xy 38.851125 -356.852217) (xy 38.795688 -356.858317) (xy 38.739954 -356.85628) (xy 38.685111 -356.84615)
			(xy 38.632327 -356.828143) (xy 38.582727 -356.802642) (xy 38.537369 -356.770191) (xy 38.49722 -356.731482)
			(xy 38.463134 -356.687339) (xy 38.435838 -356.638704) (xy 38.415915 -356.586613) (xy 38.403789 -356.532176)
			(xy 38.399718 -356.476554) (xy 37.60879 -356.476554) (xy 37.638259 -356.494539) (xy 37.681127 -356.530214)
			(xy 37.718344 -356.571751) (xy 37.749117 -356.618264) (xy 37.772789 -356.668761) (xy 37.788857 -356.722168)
			(xy 37.796977 -356.777344) (xy 37.797486 -356.80523) (xy 37.796977 -356.833116) (xy 37.788857 -356.888292)
			(xy 37.772789 -356.941699) (xy 37.749117 -356.992196) (xy 37.718344 -357.038709) (xy 37.681127 -357.080246)
			(xy 37.638259 -357.115921) (xy 37.590653 -357.144975) (xy 37.539324 -357.166787) (xy 37.485367 -357.180893)
			(xy 37.42993 -357.186993) (xy 37.374196 -357.184956) (xy 37.319353 -357.174826) (xy 37.266569 -357.156819)
			(xy 37.216969 -357.131318) (xy 37.171611 -357.098867) (xy 37.131462 -357.060158) (xy 37.097376 -357.016015)
			(xy 37.07008 -356.96738) (xy 37.050157 -356.915289) (xy 37.038031 -356.860852) (xy 37.03396 -356.80523)
			(xy 34.902394 -356.80523) (xy 34.902394 -357.98506) (xy 39.206424 -357.98506) (xy 39.206805 -357.95972)
			(xy 39.21352 -357.909488) (xy 39.226827 -357.860586) (xy 39.246491 -357.813877) (xy 39.272166 -357.770183)
			(xy 39.3034 -357.730272) (xy 39.321232 -357.712264) (xy 39.330672 -357.702529) (xy 39.344468 -357.679196)
			(xy 39.351619 -357.653049) (xy 39.351618 -357.625942) (xy 39.344464 -357.599795) (xy 39.330666 -357.576463)
			(xy 39.321232 -357.566722) (xy 39.30342 -357.548696) (xy 39.27219 -357.508788) (xy 39.246518 -357.465096)
			(xy 39.226857 -357.41839) (xy 39.213553 -357.369493) (xy 39.20684 -357.319264) (xy 39.206424 -357.293926)
			(xy 39.20691 -357.266675) (xy 39.214666 -357.212727) (xy 39.230021 -357.160432) (xy 39.252663 -357.110855)
			(xy 39.282129 -357.065005) (xy 39.31782 -357.023814) (xy 39.359011 -356.988123) (xy 39.404861 -356.958657)
			(xy 39.454438 -356.936015) (xy 39.506733 -356.92066) (xy 39.560681 -356.912904) (xy 39.615183 -356.912904)
			(xy 39.669131 -356.92066) (xy 39.721426 -356.936015) (xy 39.771003 -356.958657) (xy 39.816853 -356.988123)
			(xy 39.858044 -357.023814) (xy 39.893735 -357.065005) (xy 39.923201 -357.110855) (xy 39.945843 -357.160432)
			(xy 39.961198 -357.212727) (xy 39.968954 -357.266675) (xy 39.9691 -357.274876) (xy 40.83177 -357.274876)
			(xy 40.832255 -357.247625) (xy 40.840015 -357.193679) (xy 40.855372 -357.141385) (xy 40.878014 -357.091809)
			(xy 40.907481 -357.04596) (xy 40.943172 -357.004771) (xy 40.984362 -356.96908) (xy 41.030211 -356.939613)
			(xy 41.079787 -356.916971) (xy 41.132081 -356.901614) (xy 41.186027 -356.893855) (xy 41.213278 -356.893368)
			(xy 41.240528 -356.893899) (xy 41.294472 -356.901652) (xy 41.346765 -356.917003) (xy 41.39634 -356.939639)
			(xy 41.44219 -356.969101) (xy 41.483379 -357.004788) (xy 41.519071 -357.045974) (xy 41.548538 -357.091819)
			(xy 41.571181 -357.141392) (xy 41.586539 -357.193683) (xy 41.594298 -357.247626) (xy 41.594786 -357.274876)
			(xy 41.594544 -357.293543) (xy 41.590858 -357.330695) (xy 41.58742 -357.349044) (xy 41.585129 -357.363318)
			(xy 41.587649 -357.3921) (xy 41.598137 -357.419022) (xy 41.615752 -357.441924) (xy 41.63908 -357.458969)
			(xy 41.666252 -357.468792) (xy 41.680638 -357.470202) (xy 41.70929 -357.472578) (xy 41.765453 -357.484869)
			(xy 41.819137 -357.505447) (xy 41.869127 -357.533844) (xy 41.914291 -357.569419) (xy 41.953607 -357.611366)
			(xy 41.986186 -357.658737) (xy 42.01129 -357.710459) (xy 42.028351 -357.765361) (xy 42.036983 -357.822202)
			(xy 42.037508 -357.850948) (xy 42.037067 -357.8782) (xy 42.029304 -357.93215) (xy 42.013943 -357.984445)
			(xy 41.991296 -358.034023) (xy 41.963993 -358.0765) (xy 48.879506 -358.0765) (xy 48.879919 -358.051161)
			(xy 48.886628 -358.00093) (xy 48.899929 -357.95203) (xy 48.919587 -357.905321) (xy 48.945256 -357.861625)
			(xy 48.976485 -357.821713) (xy 48.994314 -357.803704) (xy 49.003707 -357.79393) (xy 49.017495 -357.770605)
			(xy 49.024645 -357.74447) (xy 49.024651 -357.717375) (xy 49.017513 -357.691237) (xy 49.003736 -357.667906)
			(xy 48.994314 -357.658162) (xy 48.97647 -357.640167) (xy 48.945243 -357.600252) (xy 48.919576 -357.556553)
			(xy 48.899921 -357.509842) (xy 48.886624 -357.460938) (xy 48.879918 -357.410705) (xy 48.879506 -357.385366)
			(xy 48.879992 -357.358115) (xy 48.887748 -357.304167) (xy 48.903103 -357.251872) (xy 48.925745 -357.202295)
			(xy 48.955211 -357.156445) (xy 48.990902 -357.115254) (xy 49.032093 -357.079563) (xy 49.077943 -357.050097)
			(xy 49.12752 -357.027455) (xy 49.179815 -357.0121) (xy 49.233763 -357.004344) (xy 49.288265 -357.004344)
			(xy 49.342213 -357.0121) (xy 49.394508 -357.027455) (xy 49.444085 -357.050097) (xy 49.489935 -357.079563)
			(xy 49.531126 -357.115254) (xy 49.566817 -357.156445) (xy 49.596283 -357.202295) (xy 49.618925 -357.251872)
			(xy 49.63428 -357.304167) (xy 49.642036 -357.358115) (xy 49.642522 -357.385366) (xy 49.642079 -357.410704)
			(xy 49.635374 -357.460933) (xy 49.622079 -357.509833) (xy 49.602426 -357.556542) (xy 49.576763 -357.600238)
			(xy 49.54554 -357.640151) (xy 49.527714 -357.658162) (xy 49.518299 -357.667899) (xy 49.504594 -357.691253)
			(xy 49.497496 -357.717384) (xy 49.497502 -357.744462) (xy 49.504612 -357.77059) (xy 49.518328 -357.793937)
			(xy 49.527714 -357.803704) (xy 49.545547 -357.82171) (xy 49.576774 -357.861623) (xy 49.602441 -357.905319)
			(xy 49.622098 -357.952029) (xy 49.635398 -358.00093) (xy 49.642108 -358.051161) (xy 49.642522 -358.0765)
			(xy 49.642036 -358.103751) (xy 49.63428 -358.157699) (xy 49.618925 -358.209994) (xy 49.596283 -358.259571)
			(xy 49.566817 -358.305421) (xy 49.531126 -358.346612) (xy 49.489935 -358.382303) (xy 49.444085 -358.411769)
			(xy 49.394508 -358.434411) (xy 49.342213 -358.449766) (xy 49.288265 -358.457522) (xy 49.233763 -358.457522)
			(xy 49.179815 -358.449766) (xy 49.12752 -358.434411) (xy 49.077943 -358.411769) (xy 49.032093 -358.382303)
			(xy 48.990902 -358.346612) (xy 48.955211 -358.305421) (xy 48.925745 -358.259571) (xy 48.903103 -358.209994)
			(xy 48.887748 -358.157699) (xy 48.879992 -358.103751) (xy 48.879506 -358.0765) (xy 41.963993 -358.0765)
			(xy 41.961825 -358.079873) (xy 41.926129 -358.121063) (xy 41.884934 -358.156753) (xy 41.839081 -358.186219)
			(xy 41.7895 -358.208859) (xy 41.737203 -358.224214) (xy 41.683252 -358.23197) (xy 41.656 -358.232456)
			(xy 41.628751 -358.231922) (xy 41.574807 -358.224167) (xy 41.522516 -358.208814) (xy 41.472942 -358.186177)
			(xy 41.427094 -358.156715) (xy 41.385905 -358.121029) (xy 41.350214 -358.079844) (xy 41.320746 -358.034)
			(xy 41.298102 -357.984429) (xy 41.282743 -357.93214) (xy 41.274981 -357.878197) (xy 41.274492 -357.850948)
			(xy 41.27473 -357.832281) (xy 41.278424 -357.79513) (xy 41.281858 -357.77678) (xy 41.284144 -357.762505)
			(xy 41.28163 -357.733721) (xy 41.271145 -357.706797) (xy 41.25353 -357.683894) (xy 41.2302 -357.666849)
			(xy 41.203027 -357.65703) (xy 41.18864 -357.655622) (xy 41.159985 -357.653254) (xy 41.103817 -357.64097)
			(xy 41.050129 -357.620398) (xy 41.000134 -357.592003) (xy 40.954967 -357.556428) (xy 40.915648 -357.514478)
			(xy 40.88307 -357.467103) (xy 40.857969 -357.415376) (xy 40.840913 -357.360469) (xy 40.83229 -357.303624)
			(xy 40.83177 -357.274876) (xy 39.9691 -357.274876) (xy 39.96944 -357.293926) (xy 39.969031 -357.319265)
			(xy 39.962318 -357.369495) (xy 39.949016 -357.418395) (xy 39.929357 -357.465104) (xy 39.903688 -357.508799)
			(xy 39.87246 -357.548712) (xy 39.854632 -357.566722) (xy 39.845256 -357.576494) (xy 39.831545 -357.599837)
			(xy 39.82444 -357.625959) (xy 39.824439 -357.653031) (xy 39.831541 -357.679154) (xy 39.84525 -357.702498)
			(xy 39.854632 -357.712264) (xy 39.872449 -357.730285) (xy 39.903676 -357.770195) (xy 39.929346 -357.813888)
			(xy 39.949006 -357.860595) (xy 39.962309 -357.909493) (xy 39.969023 -357.959722) (xy 39.969319 -357.977694)
			(xy 40.222424 -357.977694) (xy 40.22291 -357.950443) (xy 40.230666 -357.896495) (xy 40.246021 -357.8442)
			(xy 40.268663 -357.794623) (xy 40.298129 -357.748773) (xy 40.33382 -357.707582) (xy 40.375011 -357.671891)
			(xy 40.420861 -357.642425) (xy 40.470438 -357.619783) (xy 40.522733 -357.604428) (xy 40.576681 -357.596672)
			(xy 40.631183 -357.596672) (xy 40.685131 -357.604428) (xy 40.737426 -357.619783) (xy 40.787003 -357.642425)
			(xy 40.832853 -357.671891) (xy 40.874044 -357.707582) (xy 40.909735 -357.748773) (xy 40.939201 -357.794623)
			(xy 40.961843 -357.8442) (xy 40.977198 -357.896495) (xy 40.984954 -357.950443) (xy 40.98544 -357.977694)
			(xy 40.985022 -358.00443) (xy 40.977556 -358.057377) (xy 40.962769 -358.108763) (xy 40.94095 -358.157581)
			(xy 40.912528 -358.202873) (xy 40.87806 -358.243752) (xy 40.85844 -358.26192) (xy 40.85844 -358.646476)
			(xy 41.102026 -358.890316) (xy 45.237908 -358.890316) (xy 45.844206 -358.284018) (xy 45.862296 -358.266774)
			(xy 45.903863 -358.239038) (xy 45.950039 -358.219937) (xy 45.999052 -358.210203) (xy 46.024038 -358.209596)
			(xy 47.791878 -358.209596) (xy 47.816864 -358.210165) (xy 47.865875 -358.21992) (xy 47.912044 -358.239039)
			(xy 47.953602 -358.26679) (xy 47.97171 -358.284018) (xy 48.38573 -358.698038) (xy 48.402934 -358.716165)
			(xy 48.430679 -358.757718) (xy 48.449792 -358.803883) (xy 48.459538 -358.852888) (xy 48.460152 -358.87787)
			(xy 48.460152 -359.23728) (xy 48.666908 -359.444036) (xy 49.303178 -359.444036) (xy 50.038 -358.709214)
			(xy 50.038 -358.26192) (xy 50.018354 -358.24377) (xy 49.983856 -358.202895) (xy 49.955402 -358.157604)
			(xy 49.933548 -358.108786) (xy 49.918723 -358.057395) (xy 49.911216 -358.004437) (xy 49.910746 -357.977694)
			(xy 49.911272 -357.950445) (xy 49.919028 -357.896501) (xy 49.934382 -357.84421) (xy 49.95702 -357.794635)
			(xy 49.986483 -357.748787) (xy 50.02217 -357.707598) (xy 50.063355 -357.671907) (xy 50.1092 -357.642439)
			(xy 50.158772 -357.619796) (xy 50.211062 -357.604437) (xy 50.265005 -357.596675) (xy 50.292254 -357.596186)
			(xy 50.32106 -357.596711) (xy 50.378016 -357.605388) (xy 50.433023 -357.62252) (xy 50.484832 -357.647721)
			(xy 50.532268 -357.680417) (xy 50.574256 -357.719867) (xy 50.609841 -357.765176) (xy 50.624486 -357.789988)
			(xy 50.707798 -357.7971) (xy 50.730404 -357.772208) (xy 50.740446 -357.761125) (xy 50.754329 -357.734658)
			(xy 50.759967 -357.705307) (xy 50.756878 -357.67558) (xy 50.745326 -357.648016) (xy 50.726298 -357.624968)
			(xy 50.714148 -357.616252) (xy 50.69202 -357.601012) (xy 50.651853 -357.565328) (xy 50.617087 -357.524363)
			(xy 50.588411 -357.478927) (xy 50.566391 -357.429918) (xy 50.551463 -357.378305) (xy 50.543921 -357.325108)
			(xy 50.54346 -357.298244) (xy 50.543946 -357.270993) (xy 50.551702 -357.217045) (xy 50.567057 -357.16475)
			(xy 50.589699 -357.115173) (xy 50.619165 -357.069323) (xy 50.654856 -357.028132) (xy 50.696047 -356.992441)
			(xy 50.741897 -356.962975) (xy 50.791474 -356.940333) (xy 50.843769 -356.924978) (xy 50.897717 -356.917222)
			(xy 50.952219 -356.917222) (xy 51.006167 -356.924978) (xy 51.058462 -356.940333) (xy 51.108039 -356.962975)
			(xy 51.153889 -356.992441) (xy 51.19508 -357.028132) (xy 51.230771 -357.069323) (xy 51.260237 -357.115173)
			(xy 51.282879 -357.16475) (xy 51.298234 -357.217045) (xy 51.30599 -357.270993) (xy 51.306476 -357.298244)
			(xy 51.305909 -357.327899) (xy 51.296725 -357.386495) (xy 51.278585 -357.442963) (xy 51.251926 -357.495945)
			(xy 51.217391 -357.544164) (xy 51.197002 -357.565706) (xy 51.186943 -357.576775) (xy 51.17306 -357.603246)
			(xy 51.167424 -357.632601) (xy 51.170516 -357.662332) (xy 51.182073 -357.689898) (xy 51.201106 -357.712946)
			(xy 51.213258 -357.721662) (xy 51.235394 -357.736891) (xy 51.275561 -357.772577) (xy 51.310325 -357.813544)
			(xy 51.339 -357.858982) (xy 51.361019 -357.907993) (xy 51.375946 -357.959607) (xy 51.383486 -358.012805)
			(xy 51.383946 -358.03967) (xy 51.383394 -358.066919) (xy 51.375643 -358.120862) (xy 51.360293 -358.173153)
			(xy 51.337658 -358.222728) (xy 51.308199 -358.268576) (xy 51.272514 -358.309766) (xy 51.231331 -358.345458)
			(xy 51.185487 -358.374926) (xy 51.135917 -358.397569) (xy 51.083629 -358.412928) (xy 51.029687 -358.420689)
			(xy 51.002438 -358.421178) (xy 50.973631 -358.420677) (xy 50.916673 -358.411999) (xy 50.861665 -358.394863)
			(xy 50.809855 -358.369659) (xy 50.762418 -358.336959) (xy 50.720432 -358.297504) (xy 50.684849 -358.25219)
			(xy 50.670206 -358.227376) (xy 50.586894 -358.22001) (xy 50.577503 -358.231146) (xy 50.557288 -358.252122)
			(xy 50.546508 -358.26192) (xy 50.546508 -358.814624) (xy 50.545904 -358.839608) (xy 50.53616 -358.888617)
			(xy 50.517051 -358.934787) (xy 50.489309 -358.976347) (xy 50.472086 -358.994456) (xy 49.58842 -359.878122)
			(xy 49.57031 -359.895344) (xy 49.528751 -359.923087) (xy 49.482581 -359.942194) (xy 49.433572 -359.951934)
			(xy 49.408588 -359.952544) (xy 48.561498 -359.952544) (xy 48.536515 -359.951917) (xy 48.487508 -359.942179)
			(xy 48.441338 -359.923076) (xy 48.399777 -359.895342) (xy 48.381666 -359.878122) (xy 48.026066 -359.522522)
			(xy 48.008843 -359.504413) (xy 47.981101 -359.462854) (xy 47.961994 -359.416683) (xy 47.952254 -359.367674)
			(xy 47.951644 -359.34269) (xy 47.951644 -358.98328) (xy 47.686468 -358.718104) (xy 46.129448 -358.718104)
			(xy 45.52315 -359.324402) (xy 45.505024 -359.341607) (xy 45.463471 -359.369353) (xy 45.417306 -359.388466)
			(xy 45.368301 -359.398211) (xy 45.343318 -359.398824) (xy 40.996616 -359.398824) (xy 40.971633 -359.398191)
			(xy 40.922626 -359.388456) (xy 40.876456 -359.369355) (xy 40.834895 -359.341621) (xy 40.816784 -359.324402)
			(xy 40.4241 -358.931718) (xy 40.406859 -358.913609) (xy 40.379046 -358.872068) (xy 40.359869 -358.825902)
			(xy 40.350064 -358.776881) (xy 40.349424 -358.751886) (xy 40.349424 -358.26192) (xy 40.3298 -358.243758)
			(xy 40.295342 -358.202873) (xy 40.26693 -358.157578) (xy 40.245119 -358.10876) (xy 40.230336 -358.057374)
			(xy 40.222873 -358.004429) (xy 40.222424 -357.977694) (xy 39.969319 -357.977694) (xy 39.96944 -357.98506)
			(xy 39.968954 -358.012311) (xy 39.961198 -358.066259) (xy 39.945843 -358.118554) (xy 39.923201 -358.168131)
			(xy 39.893735 -358.213981) (xy 39.858044 -358.255172) (xy 39.816853 -358.290863) (xy 39.771003 -358.320329)
			(xy 39.721426 -358.342971) (xy 39.669131 -358.358326) (xy 39.615183 -358.366082) (xy 39.560681 -358.366082)
			(xy 39.506733 -358.358326) (xy 39.454438 -358.342971) (xy 39.404861 -358.320329) (xy 39.359011 -358.290863)
			(xy 39.31782 -358.255172) (xy 39.282129 -358.213981) (xy 39.252663 -358.168131) (xy 39.230021 -358.118554)
			(xy 39.214666 -358.066259) (xy 39.20691 -358.012311) (xy 39.206424 -357.98506) (xy 34.902394 -357.98506)
			(xy 34.902394 -358.488488) (xy 36.70427 -360.290364) (xy 36.944808 -360.531156) (xy 40.842184 -360.531156)
			(xy 40.866148 -360.531653) (xy 40.913481 -360.539194) (xy 40.959056 -360.554031) (xy 41.001757 -360.5758)
			(xy 41.040536 -360.603967) (xy 41.05783 -360.620564) (xy 41.190164 -360.752898) (xy 41.20681 -360.770151)
			(xy 41.235009 -360.80892) (xy 41.256786 -360.851629) (xy 41.271601 -360.897222) (xy 41.27909 -360.944574)
			(xy 41.279572 -360.968544) (xy 41.279572 -361.512612) (xy 44.706032 -361.512612) (xy 44.706601 -361.483444)
			(xy 44.715499 -361.425789) (xy 44.733074 -361.370162) (xy 44.758916 -361.317861) (xy 44.792423 -361.270106)
			(xy 44.832811 -361.228011) (xy 44.855638 -361.209844) (xy 44.866037 -361.201446) (xy 44.882331 -361.180263)
			(xy 44.892574 -361.155579) (xy 44.896065 -361.129083) (xy 44.892565 -361.102588) (xy 44.882314 -361.077908)
			(xy 44.866013 -361.05673) (xy 44.855638 -361.0483) (xy 44.832794 -361.03015) (xy 44.792392 -360.988061)
			(xy 44.758878 -360.940306) (xy 44.733034 -360.888) (xy 44.715466 -360.832365) (xy 44.706583 -360.774703)
			(xy 44.706032 -360.745532) (xy 44.706485 -360.718278) (xy 44.714239 -360.664325) (xy 44.729593 -360.612024)
			(xy 44.752235 -360.562442) (xy 44.781703 -360.516586) (xy 44.817398 -360.475392) (xy 44.858593 -360.439698)
			(xy 44.904449 -360.410231) (xy 44.954032 -360.38759) (xy 45.006333 -360.372237) (xy 45.060286 -360.364485)
			(xy 45.08754 -360.364024) (xy 45.116456 -360.364576) (xy 45.173626 -360.373297) (xy 45.228824 -360.390547)
			(xy 45.280786 -360.415933) (xy 45.328321 -360.448871) (xy 45.370339 -360.488607) (xy 45.38853 -360.51109)
			(xy 45.398427 -360.522895) (xy 45.423751 -360.540414) (xy 45.453144 -360.54959) (xy 45.483936 -360.54959)
			(xy 45.513329 -360.540414) (xy 45.538653 -360.522895) (xy 45.54855 -360.51109) (xy 45.566767 -360.488628)
			(xy 45.608781 -360.448892) (xy 45.656311 -360.415951) (xy 45.708267 -360.390559) (xy 45.76346 -360.373298)
			(xy 45.820626 -360.364563) (xy 45.84954 -360.364024) (xy 45.878086 -360.364584) (xy 45.934539 -360.373094)
			(xy 45.989094 -360.389919) (xy 46.040535 -360.414683) (xy 46.064424 -360.430318) (xy 46.075556 -360.4374)
			(xy 46.100412 -360.446212) (xy 46.126699 -360.448341) (xy 46.152649 -360.443643) (xy 46.176521 -360.432435)
			(xy 46.196711 -360.415469) (xy 46.204632 -360.404918) (xy 46.22004 -360.383903) (xy 46.255641 -360.345851)
			(xy 46.296087 -360.312995) (xy 46.340626 -360.285946) (xy 46.38843 -360.265206) (xy 46.438611 -360.251161)
			(xy 46.490235 -360.244072) (xy 46.51629 -360.243628) (xy 46.545207 -360.244143) (xy 46.602379 -360.252871)
			(xy 46.657578 -360.270129) (xy 46.70954 -360.295521) (xy 46.757074 -360.328466) (xy 46.79909 -360.368208)
			(xy 46.81728 -360.390694) (xy 46.827177 -360.402499) (xy 46.852501 -360.420018) (xy 46.881894 -360.429194)
			(xy 46.912686 -360.429194) (xy 46.942079 -360.420018) (xy 46.967403 -360.402499) (xy 46.9773 -360.390694)
			(xy 46.995489 -360.368209) (xy 47.03751 -360.328474) (xy 47.085045 -360.295536) (xy 47.137007 -360.270148)
			(xy 47.192204 -360.252892) (xy 47.249374 -360.244163) (xy 47.27829 -360.243628) (xy 47.305544 -360.244065)
			(xy 47.359498 -360.251821) (xy 47.411799 -360.267178) (xy 47.461381 -360.289822) (xy 47.507236 -360.319292)
			(xy 47.54843 -360.354989) (xy 47.584123 -360.396185) (xy 47.613591 -360.442042) (xy 47.636231 -360.491626)
			(xy 47.651584 -360.543927) (xy 47.659337 -360.597882) (xy 47.659798 -360.625136) (xy 47.659322 -360.651178)
			(xy 47.652244 -360.702778) (xy 47.638212 -360.752936) (xy 47.617485 -360.800718) (xy 47.59045 -360.845235)
			(xy 47.557609 -360.88566) (xy 47.538894 -360.903774) (xy 47.528968 -360.91375) (xy 47.514501 -360.937875)
			(xy 47.507156 -360.965029) (xy 47.507487 -360.993157) (xy 47.515471 -361.020131) (xy 47.530501 -361.043909)
			(xy 47.540672 -361.053634) (xy 47.56026 -361.07179) (xy 47.59465 -361.112652) (xy 47.623006 -361.157912)
			(xy 47.644772 -361.206684) (xy 47.659523 -361.258015) (xy 47.666971 -361.310902) (xy 47.667418 -361.337606)
			(xy 47.66692 -361.365376) (xy 47.658866 -361.420328) (xy 47.64293 -361.473533) (xy 47.619447 -361.523864)
			(xy 47.588915 -361.570258) (xy 47.551979 -361.611735) (xy 47.53102 -361.62996) (xy 47.520368 -361.639481)
			(xy 47.504384 -361.663145) (xy 47.495592 -361.690314) (xy 47.494682 -361.718856) (xy 47.501726 -361.74653)
			(xy 47.516171 -361.771164) (xy 47.526194 -361.781344) (xy 47.544559 -361.799414) (xy 47.576728 -361.839658)
			(xy 47.603195 -361.883862) (xy 47.623477 -361.931223) (xy 47.637207 -361.980882) (xy 47.644135 -362.031935)
			(xy 47.644558 -362.057696) (xy 47.6441 -362.085067) (xy 47.636282 -362.139246) (xy 47.620791 -362.19175)
			(xy 47.597948 -362.241497) (xy 47.568221 -362.287463) (xy 47.550578 -362.308394) (xy 47.541347 -362.319725)
			(xy 47.529172 -362.346282) (xy 47.524999 -362.375197) (xy 47.52917 -362.404112) (xy 47.541343 -362.43067)
			(xy 47.550578 -362.441998) (xy 47.568215 -362.462934) (xy 47.597939 -362.508901) (xy 47.620784 -362.558647)
			(xy 47.636281 -362.611149) (xy 47.64411 -362.665327) (xy 47.64411 -362.720067) (xy 47.636282 -362.774245)
			(xy 47.620787 -362.826747) (xy 47.597942 -362.876493) (xy 47.568218 -362.922461) (xy 47.550578 -362.943394)
			(xy 47.541347 -362.954725) (xy 47.529172 -362.981282) (xy 47.524999 -363.010197) (xy 47.52917 -363.039112)
			(xy 47.541343 -363.06567) (xy 47.550578 -363.076998) (xy 47.568215 -363.097934) (xy 47.597939 -363.143901)
			(xy 47.620784 -363.193647) (xy 47.636281 -363.246149) (xy 47.63987 -363.270984) (xy 48.72126 -363.270984)
			(xy 48.72126 -363.186288) (xy 48.729311 -363.101974) (xy 48.74534 -363.018808) (xy 48.769201 -362.937541)
			(xy 48.80068 -362.858911) (xy 48.839491 -362.78363) (xy 48.885281 -362.712378) (xy 48.937637 -362.645802)
			(xy 48.996085 -362.584504) (xy 49.060095 -362.529039) (xy 49.129087 -362.47991) (xy 49.202437 -362.437561)
			(xy 49.27948 -362.402377) (xy 49.359519 -362.374675) (xy 49.441828 -362.354707) (xy 49.525663 -362.342654)
			(xy 49.610264 -362.338624) (xy 49.694865 -362.342654) (xy 49.7787 -362.354707) (xy 49.861009 -362.374675)
			(xy 49.941048 -362.402377) (xy 50.018091 -362.437561) (xy 50.091441 -362.47991) (xy 50.160433 -362.529039)
			(xy 50.224443 -362.584504) (xy 50.282891 -362.645802) (xy 50.335247 -362.712378) (xy 50.381037 -362.78363)
			(xy 50.419848 -362.858911) (xy 50.451327 -362.937541) (xy 50.475188 -363.018808) (xy 50.491217 -363.101974)
			(xy 50.499268 -363.186288) (xy 50.499772 -363.228636) (xy 51.245773 -363.228636) (xy 51.249809 -363.145189)
			(xy 51.261881 -363.062521) (xy 51.281874 -362.981404) (xy 51.309603 -362.902595) (xy 51.344809 -362.82683)
			(xy 51.387163 -362.754817) (xy 51.436269 -362.687228) (xy 51.49167 -362.624694) (xy 51.552847 -362.567799)
			(xy 51.61923 -362.517073) (xy 51.690198 -362.472992) (xy 51.76509 -362.435966) (xy 51.843206 -362.40634)
			(xy 51.923816 -362.384392) (xy 52.006168 -362.370327) (xy 52.089494 -362.364275) (xy 52.173014 -362.366294)
			(xy 52.25595 -362.376364) (xy 52.337526 -362.394392) (xy 52.416982 -362.420209) (xy 52.493575 -362.453574)
			(xy 52.566591 -362.494175) (xy 52.635347 -362.541634) (xy 52.699201 -362.595507) (xy 52.757558 -362.655292)
			(xy 52.809873 -362.720429) (xy 52.855656 -362.790312) (xy 52.894481 -362.864287) (xy 52.925986 -362.941664)
			(xy 52.949875 -363.021721) (xy 52.965926 -363.103709) (xy 52.973989 -363.186864) (xy 52.974494 -363.228636)
			(xy 52.973989 -363.270408) (xy 52.965926 -363.353563) (xy 52.949875 -363.435551) (xy 52.925986 -363.515608)
			(xy 52.894481 -363.592985) (xy 52.855656 -363.66696) (xy 52.809873 -363.736843) (xy 52.757558 -363.80198)
			(xy 52.699201 -363.861765) (xy 52.635347 -363.915638) (xy 52.566591 -363.963097) (xy 52.493575 -364.003698)
			(xy 52.416982 -364.037063) (xy 52.337526 -364.06288) (xy 52.25595 -364.080908) (xy 52.173014 -364.090978)
			(xy 52.089494 -364.092997) (xy 52.006168 -364.086945) (xy 51.923816 -364.07288) (xy 51.843206 -364.050932)
			(xy 51.76509 -364.021306) (xy 51.690198 -363.98428) (xy 51.61923 -363.940199) (xy 51.552847 -363.889473)
			(xy 51.49167 -363.832578) (xy 51.436269 -363.770044) (xy 51.387163 -363.702455) (xy 51.344809 -363.630442)
			(xy 51.309603 -363.554677) (xy 51.281874 -363.475868) (xy 51.261881 -363.394751) (xy 51.249809 -363.312083)
			(xy 51.245773 -363.228636) (xy 50.499772 -363.228636) (xy 50.499268 -363.270984) (xy 50.491217 -363.355298)
			(xy 50.475188 -363.438464) (xy 50.451327 -363.519731) (xy 50.419848 -363.598361) (xy 50.381037 -363.673642)
			(xy 50.335247 -363.744894) (xy 50.282891 -363.81147) (xy 50.224443 -363.872768) (xy 50.160433 -363.928233)
			(xy 50.091441 -363.977362) (xy 50.018091 -364.019711) (xy 49.941048 -364.054895) (xy 49.861009 -364.082597)
			(xy 49.7787 -364.102565) (xy 49.694865 -364.114618) (xy 49.610264 -364.118649) (xy 49.525663 -364.114618)
			(xy 49.441828 -364.102565) (xy 49.359519 -364.082597) (xy 49.27948 -364.054895) (xy 49.202437 -364.019711)
			(xy 49.129087 -363.977362) (xy 49.060095 -363.928233) (xy 48.996085 -363.872768) (xy 48.937637 -363.81147)
			(xy 48.885281 -363.744894) (xy 48.839491 -363.673642) (xy 48.80068 -363.598361) (xy 48.769201 -363.519731)
			(xy 48.74534 -363.438464) (xy 48.729311 -363.355298) (xy 48.72126 -363.270984) (xy 47.63987 -363.270984)
			(xy 47.64411 -363.300327) (xy 47.64411 -363.355067) (xy 47.636282 -363.409245) (xy 47.620787 -363.461747)
			(xy 47.597942 -363.511493) (xy 47.568218 -363.557461) (xy 47.550578 -363.578394) (xy 47.541347 -363.589725)
			(xy 47.529172 -363.616282) (xy 47.524999 -363.645197) (xy 47.52917 -363.674112) (xy 47.541343 -363.70067)
			(xy 47.550578 -363.711998) (xy 47.568226 -363.732923) (xy 47.597937 -363.778897) (xy 47.620772 -363.828647)
			(xy 47.636261 -363.881149) (xy 47.644086 -363.935326) (xy 47.644558 -363.962696) (xy 47.644141 -363.989951)
			(xy 47.636383 -364.043906) (xy 47.621025 -364.096208) (xy 47.598379 -364.145791) (xy 47.568907 -364.191647)
			(xy 47.533208 -364.232841) (xy 47.49201 -364.268535) (xy 47.446151 -364.298001) (xy 47.396565 -364.320641)
			(xy 47.344261 -364.335993) (xy 47.290305 -364.343744) (xy 47.26305 -364.344204) (xy 47.234133 -364.343686)
			(xy 47.17696 -364.334962) (xy 47.121759 -364.317706) (xy 47.069797 -364.292315) (xy 47.022263 -364.259369)
			(xy 46.980249 -364.219625) (xy 46.96206 -364.197138) (xy 46.952163 -364.185333) (xy 46.926839 -364.167814)
			(xy 46.897446 -364.158638) (xy 46.866654 -364.158638) (xy 46.837261 -364.167814) (xy 46.811937 -364.185333)
			(xy 46.80204 -364.197138) (xy 46.783836 -364.21961) (xy 46.741818 -364.259344) (xy 46.694285 -364.292284)
			(xy 46.642327 -364.317674) (xy 46.587132 -364.334933) (xy 46.529965 -364.343666) (xy 46.50105 -364.344204)
			(xy 46.473798 -364.343698) (xy 46.419849 -364.335948) (xy 46.367551 -364.320598) (xy 46.317971 -364.297961)
			(xy 46.272117 -364.268498) (xy 46.230924 -364.232808) (xy 46.19523 -364.191619) (xy 46.165761 -364.145769)
			(xy 46.143118 -364.096192) (xy 46.127762 -364.043896) (xy 46.120005 -363.989948) (xy 46.119542 -363.962696)
			(xy 46.119995 -363.935325) (xy 46.127815 -363.881145) (xy 46.143306 -363.828642) (xy 46.166151 -363.778895)
			(xy 46.195879 -363.732929) (xy 46.213522 -363.711998) (xy 46.222761 -363.700673) (xy 46.234935 -363.674114)
			(xy 46.239106 -363.645197) (xy 46.234933 -363.61628) (xy 46.222758 -363.589722) (xy 46.213522 -363.578394)
			(xy 46.195878 -363.557464) (xy 46.166153 -363.511496) (xy 46.143309 -363.461749) (xy 46.127813 -363.409247)
			(xy 46.119985 -363.355068) (xy 46.119985 -363.300326) (xy 46.127814 -363.246148) (xy 46.143311 -363.193645)
			(xy 46.166156 -363.143899) (xy 46.195881 -363.097931) (xy 46.213522 -363.076998) (xy 46.222761 -363.065673)
			(xy 46.234935 -363.039114) (xy 46.239106 -363.010197) (xy 46.234933 -362.98128) (xy 46.222758 -362.954722)
			(xy 46.213522 -362.943394) (xy 46.195878 -362.922464) (xy 46.166153 -362.876496) (xy 46.143309 -362.826749)
			(xy 46.127813 -362.774247) (xy 46.119985 -362.720068) (xy 46.119985 -362.665326) (xy 46.127814 -362.611148)
			(xy 46.143311 -362.558645) (xy 46.166156 -362.508899) (xy 46.195881 -362.462931) (xy 46.213522 -362.441998)
			(xy 46.222761 -362.430673) (xy 46.234935 -362.404114) (xy 46.239106 -362.375197) (xy 46.234933 -362.34628)
			(xy 46.222758 -362.319722) (xy 46.213522 -362.308394) (xy 46.19587 -362.287472) (xy 46.166159 -362.241497)
			(xy 46.143326 -362.191747) (xy 46.127838 -362.139244) (xy 46.120014 -362.085066) (xy 46.119542 -362.057696)
			(xy 46.119779 -362.038641) (xy 46.123595 -362.000723) (xy 46.127162 -361.982004) (xy 46.129464 -361.968526)
			(xy 46.127624 -361.941254) (xy 46.118615 -361.915448) (xy 46.103081 -361.892958) (xy 46.082137 -361.875395)
			(xy 46.057284 -361.864018) (xy 46.030303 -361.859643) (xy 46.003128 -361.862584) (xy 45.990256 -361.867196)
			(xy 45.967794 -361.875742) (xy 45.921251 -361.887724) (xy 45.87357 -361.893759) (xy 45.84954 -361.89412)
			(xy 45.820623 -361.893603) (xy 45.76345 -361.884878) (xy 45.70825 -361.867622) (xy 45.656288 -361.84223)
			(xy 45.608754 -361.809285) (xy 45.566739 -361.769541) (xy 45.54855 -361.747054) (xy 45.538653 -361.735249)
			(xy 45.513329 -361.71773) (xy 45.483936 -361.708554) (xy 45.453144 -361.708554) (xy 45.423751 -361.71773)
			(xy 45.398427 -361.735249) (xy 45.38853 -361.747054) (xy 45.370336 -361.769534) (xy 45.328315 -361.809267)
			(xy 45.28078 -361.842205) (xy 45.22882 -361.867593) (xy 45.173624 -361.884851) (xy 45.116456 -361.893583)
			(xy 45.08754 -361.89412) (xy 45.060289 -361.893608) (xy 45.00634 -361.885856) (xy 44.954044 -361.870506)
			(xy 44.904465 -361.847869) (xy 44.858612 -361.818406) (xy 44.817419 -361.782718) (xy 44.781725 -361.74153)
			(xy 44.752256 -361.695681) (xy 44.729612 -361.646105) (xy 44.714255 -361.593811) (xy 44.706496 -361.539863)
			(xy 44.706032 -361.512612) (xy 41.279572 -361.512612) (xy 41.279572 -364.592108) (xy 55.39308 -364.592108)
			(xy 55.397151 -364.536486) (xy 55.409277 -364.482049) (xy 55.4292 -364.429958) (xy 55.456496 -364.381323)
			(xy 55.490582 -364.33718) (xy 55.530731 -364.298471) (xy 55.576089 -364.26602) (xy 55.625689 -364.240519)
			(xy 55.678473 -364.222512) (xy 55.733316 -364.212382) (xy 55.78905 -364.210345) (xy 55.844487 -364.216445)
			(xy 55.898444 -364.230551) (xy 55.949773 -364.252363) (xy 55.997379 -364.281417) (xy 56.040247 -364.317092)
			(xy 56.077464 -364.358629) (xy 56.108237 -364.405142) (xy 56.131909 -364.455639) (xy 56.147977 -364.509046)
			(xy 56.156097 -364.564222) (xy 56.156606 -364.592108) (xy 56.156097 -364.619994) (xy 56.147977 -364.67517)
			(xy 56.131909 -364.728577) (xy 56.108237 -364.779074) (xy 56.077464 -364.825587) (xy 56.040247 -364.867124)
			(xy 55.997379 -364.902799) (xy 55.949773 -364.931853) (xy 55.898444 -364.953665) (xy 55.844487 -364.967771)
			(xy 55.78905 -364.973871) (xy 55.733316 -364.971834) (xy 55.678473 -364.961704) (xy 55.625689 -364.943697)
			(xy 55.576089 -364.918196) (xy 55.530731 -364.885745) (xy 55.490582 -364.847036) (xy 55.456496 -364.802893)
			(xy 55.4292 -364.754258) (xy 55.409277 -364.702167) (xy 55.397151 -364.64773) (xy 55.39308 -364.592108)
			(xy 41.279572 -364.592108) (xy 41.279572 -365.851948) (xy 41.654982 -365.851948) (xy 41.659053 -365.796326)
			(xy 41.671179 -365.741889) (xy 41.691102 -365.689798) (xy 41.718398 -365.641163) (xy 41.752484 -365.59702)
			(xy 41.792633 -365.558311) (xy 41.837991 -365.52586) (xy 41.887591 -365.500359) (xy 41.940375 -365.482352)
			(xy 41.995218 -365.472222) (xy 42.050952 -365.470185) (xy 42.106389 -365.476285) (xy 42.160346 -365.490391)
			(xy 42.211675 -365.512203) (xy 42.259281 -365.541257) (xy 42.302149 -365.576932) (xy 42.330083 -365.608108)
			(xy 55.39308 -365.608108) (xy 55.397151 -365.552486) (xy 55.409277 -365.498049) (xy 55.4292 -365.445958)
			(xy 55.456496 -365.397323) (xy 55.490582 -365.35318) (xy 55.530731 -365.314471) (xy 55.576089 -365.28202)
			(xy 55.625689 -365.256519) (xy 55.678473 -365.238512) (xy 55.733316 -365.228382) (xy 55.78905 -365.226345)
			(xy 55.844487 -365.232445) (xy 55.898444 -365.246551) (xy 55.949773 -365.268363) (xy 55.997379 -365.297417)
			(xy 56.040247 -365.333092) (xy 56.077464 -365.374629) (xy 56.108237 -365.421142) (xy 56.131909 -365.471639)
			(xy 56.147977 -365.525046) (xy 56.156097 -365.580222) (xy 56.156606 -365.608108) (xy 56.156097 -365.635994)
			(xy 56.147977 -365.69117) (xy 56.131909 -365.744577) (xy 56.108237 -365.795074) (xy 56.077464 -365.841587)
			(xy 56.040247 -365.883124) (xy 55.997379 -365.918799) (xy 55.949773 -365.947853) (xy 55.898444 -365.969665)
			(xy 55.844487 -365.983771) (xy 55.78905 -365.989871) (xy 55.733316 -365.987834) (xy 55.678473 -365.977704)
			(xy 55.625689 -365.959697) (xy 55.576089 -365.934196) (xy 55.530731 -365.901745) (xy 55.490582 -365.863036)
			(xy 55.456496 -365.818893) (xy 55.4292 -365.770258) (xy 55.409277 -365.718167) (xy 55.397151 -365.66373)
			(xy 55.39308 -365.608108) (xy 42.330083 -365.608108) (xy 42.339366 -365.618469) (xy 42.370139 -365.664982)
			(xy 42.393811 -365.715479) (xy 42.409879 -365.768886) (xy 42.417999 -365.824062) (xy 42.418508 -365.851948)
			(xy 42.417999 -365.879834) (xy 42.409879 -365.93501) (xy 42.393811 -365.988417) (xy 42.370139 -366.038914)
			(xy 42.339366 -366.085427) (xy 42.302149 -366.126964) (xy 42.259281 -366.162639) (xy 42.211675 -366.191693)
			(xy 42.160346 -366.213505) (xy 42.106389 -366.227611) (xy 42.050952 -366.233711) (xy 41.995218 -366.231674)
			(xy 41.940375 -366.221544) (xy 41.887591 -366.203537) (xy 41.837991 -366.178036) (xy 41.792633 -366.145585)
			(xy 41.752484 -366.106876) (xy 41.718398 -366.062733) (xy 41.691102 -366.014098) (xy 41.671179 -365.962007)
			(xy 41.659053 -365.90757) (xy 41.654982 -365.851948) (xy 41.279572 -365.851948) (xy 41.279572 -366.51692)
			(xy 41.7703 -367.007648) (xy 55.41391 -367.007648)
		)
		(stroke
			(width 0)
			(type solid)
		)
		(fill yes)
		(layer "In4.Cu")
		(net "GND")
	)
	(gr_poly
		(pts
			(xy 188.82614 -372.555008) (xy 188.82614 -367.777014) (xy 188.841126 -367.740946) (xy 188.841126 -334.569054)
			(xy 188.82614 -334.554068) (xy 188.172852 -333.90078) (xy 188.017404 -333.837788) (xy 167.17899 -333.837788)
			(xy 167.023542 -333.90078) (xy 165.892734 -335.031588) (xy 165.877748 -335.046574) (xy 165.877748 -335.51996)
			(xy 170.076618 -335.51996) (xy 170.076618 -335.435264) (xy 170.084669 -335.35095) (xy 170.100698 -335.267784)
			(xy 170.124559 -335.186517) (xy 170.156038 -335.107887) (xy 170.194849 -335.032606) (xy 170.240639 -334.961354)
			(xy 170.292995 -334.894778) (xy 170.351443 -334.83348) (xy 170.415453 -334.778015) (xy 170.484445 -334.728886)
			(xy 170.557795 -334.686537) (xy 170.634838 -334.651353) (xy 170.714877 -334.623651) (xy 170.797186 -334.603683)
			(xy 170.881021 -334.59163) (xy 170.965622 -334.5876) (xy 171.050223 -334.59163) (xy 171.134058 -334.603683)
			(xy 171.216367 -334.623651) (xy 171.296406 -334.651353) (xy 171.373449 -334.686537) (xy 171.446799 -334.728886)
			(xy 171.515791 -334.778015) (xy 171.579801 -334.83348) (xy 171.638249 -334.894778) (xy 171.690605 -334.961354)
			(xy 171.736395 -335.032606) (xy 171.775206 -335.107887) (xy 171.806685 -335.186517) (xy 171.830546 -335.267784)
			(xy 171.846575 -335.35095) (xy 171.854626 -335.435264) (xy 171.85513 -335.477612) (xy 171.854626 -335.51996)
			(xy 171.85402 -335.52631) (xy 176.26736 -335.52631) (xy 176.26736 -335.441614) (xy 176.275411 -335.3573)
			(xy 176.29144 -335.274134) (xy 176.315301 -335.192867) (xy 176.34678 -335.114237) (xy 176.385591 -335.038956)
			(xy 176.431381 -334.967704) (xy 176.483737 -334.901128) (xy 176.542185 -334.83983) (xy 176.606195 -334.784365)
			(xy 176.675187 -334.735236) (xy 176.748537 -334.692887) (xy 176.82558 -334.657703) (xy 176.905619 -334.630001)
			(xy 176.987928 -334.610033) (xy 177.071763 -334.59798) (xy 177.156364 -334.59395) (xy 177.240965 -334.59798)
			(xy 177.3248 -334.610033) (xy 177.407109 -334.630001) (xy 177.487148 -334.657703) (xy 177.564191 -334.692887)
			(xy 177.637541 -334.735236) (xy 177.706533 -334.784365) (xy 177.770543 -334.83983) (xy 177.828991 -334.901128)
			(xy 177.881347 -334.967704) (xy 177.927137 -335.038956) (xy 177.965948 -335.114237) (xy 177.997427 -335.192867)
			(xy 178.021288 -335.274134) (xy 178.037317 -335.3573) (xy 178.045368 -335.441614) (xy 178.045872 -335.483962)
			(xy 178.045368 -335.52631) (xy 182.46496 -335.52631) (xy 182.46496 -335.441614) (xy 182.473011 -335.3573)
			(xy 182.48904 -335.274134) (xy 182.512901 -335.192867) (xy 182.54438 -335.114237) (xy 182.583191 -335.038956)
			(xy 182.628981 -334.967704) (xy 182.681337 -334.901128) (xy 182.739785 -334.83983) (xy 182.803795 -334.784365)
			(xy 182.872787 -334.735236) (xy 182.946137 -334.692887) (xy 183.02318 -334.657703) (xy 183.103219 -334.630001)
			(xy 183.185528 -334.610033) (xy 183.269363 -334.59798) (xy 183.353964 -334.59395) (xy 183.438565 -334.59798)
			(xy 183.5224 -334.610033) (xy 183.604709 -334.630001) (xy 183.684748 -334.657703) (xy 183.761791 -334.692887)
			(xy 183.835141 -334.735236) (xy 183.904133 -334.784365) (xy 183.968143 -334.83983) (xy 184.026591 -334.901128)
			(xy 184.078947 -334.967704) (xy 184.124737 -335.038956) (xy 184.163548 -335.114237) (xy 184.195027 -335.192867)
			(xy 184.218888 -335.274134) (xy 184.234917 -335.3573) (xy 184.242968 -335.441614) (xy 184.243472 -335.483962)
			(xy 184.242968 -335.52631) (xy 184.234917 -335.610624) (xy 184.218888 -335.69379) (xy 184.195027 -335.775057)
			(xy 184.163548 -335.853687) (xy 184.124737 -335.928968) (xy 184.078947 -336.00022) (xy 184.026591 -336.066796)
			(xy 183.968143 -336.128094) (xy 183.904133 -336.183559) (xy 183.835141 -336.232688) (xy 183.761791 -336.275037)
			(xy 183.684748 -336.310221) (xy 183.604709 -336.337923) (xy 183.5224 -336.357891) (xy 183.438565 -336.369944)
			(xy 183.353964 -336.373975) (xy 183.269363 -336.369944) (xy 183.185528 -336.357891) (xy 183.103219 -336.337923)
			(xy 183.02318 -336.310221) (xy 182.946137 -336.275037) (xy 182.872787 -336.232688) (xy 182.803795 -336.183559)
			(xy 182.739785 -336.128094) (xy 182.681337 -336.066796) (xy 182.628981 -336.00022) (xy 182.583191 -335.928968)
			(xy 182.54438 -335.853687) (xy 182.512901 -335.775057) (xy 182.48904 -335.69379) (xy 182.473011 -335.610624)
			(xy 182.46496 -335.52631) (xy 178.045368 -335.52631) (xy 178.037317 -335.610624) (xy 178.021288 -335.69379)
			(xy 177.997427 -335.775057) (xy 177.965948 -335.853687) (xy 177.927137 -335.928968) (xy 177.881347 -336.00022)
			(xy 177.828991 -336.066796) (xy 177.770543 -336.128094) (xy 177.706533 -336.183559) (xy 177.637541 -336.232688)
			(xy 177.564191 -336.275037) (xy 177.487148 -336.310221) (xy 177.407109 -336.337923) (xy 177.3248 -336.357891)
			(xy 177.240965 -336.369944) (xy 177.156364 -336.373975) (xy 177.071763 -336.369944) (xy 176.987928 -336.357891)
			(xy 176.905619 -336.337923) (xy 176.82558 -336.310221) (xy 176.748537 -336.275037) (xy 176.675187 -336.232688)
			(xy 176.606195 -336.183559) (xy 176.542185 -336.128094) (xy 176.483737 -336.066796) (xy 176.431381 -336.00022)
			(xy 176.385591 -335.928968) (xy 176.34678 -335.853687) (xy 176.315301 -335.775057) (xy 176.29144 -335.69379)
			(xy 176.275411 -335.610624) (xy 176.26736 -335.52631) (xy 171.85402 -335.52631) (xy 171.846575 -335.604274)
			(xy 171.830546 -335.68744) (xy 171.806685 -335.768707) (xy 171.775206 -335.847337) (xy 171.736395 -335.922618)
			(xy 171.690605 -335.99387) (xy 171.638249 -336.060446) (xy 171.579801 -336.121744) (xy 171.515791 -336.177209)
			(xy 171.446799 -336.226338) (xy 171.373449 -336.268687) (xy 171.296406 -336.303871) (xy 171.216367 -336.331573)
			(xy 171.134058 -336.351541) (xy 171.050223 -336.363594) (xy 170.965622 -336.367625) (xy 170.881021 -336.363594)
			(xy 170.797186 -336.351541) (xy 170.714877 -336.331573) (xy 170.634838 -336.303871) (xy 170.557795 -336.268687)
			(xy 170.484445 -336.226338) (xy 170.415453 -336.177209) (xy 170.351443 -336.121744) (xy 170.292995 -336.060446)
			(xy 170.240639 -335.99387) (xy 170.194849 -335.922618) (xy 170.156038 -335.847337) (xy 170.124559 -335.768707)
			(xy 170.100698 -335.68744) (xy 170.084669 -335.604274) (xy 170.076618 -335.51996) (xy 165.877748 -335.51996)
			(xy 165.877748 -337.477608) (xy 170.050211 -337.477608) (xy 170.054233 -337.391888) (xy 170.066264 -337.30692)
			(xy 170.0862 -337.223453) (xy 170.113863 -337.142219) (xy 170.149012 -337.063933) (xy 170.191338 -336.989282)
			(xy 170.240467 -336.918923) (xy 170.29597 -336.853473) (xy 170.357357 -336.793509) (xy 170.42409 -336.739556)
			(xy 170.495582 -336.692089) (xy 170.571204 -336.651525) (xy 170.650293 -336.618221) (xy 170.732153 -336.592469)
			(xy 170.816064 -336.574496) (xy 170.90129 -336.56446) (xy 170.987082 -336.562448) (xy 171.072684 -336.568479)
			(xy 171.157346 -336.582499) (xy 171.240323 -336.604385) (xy 171.320886 -336.633946) (xy 171.398326 -336.67092)
			(xy 171.471965 -336.714984) (xy 171.541153 -336.76575) (xy 171.605284 -336.822771) (xy 171.663793 -336.885547)
			(xy 171.716166 -336.953527) (xy 171.761944 -337.026112) (xy 171.800724 -337.102664) (xy 171.832165 -337.182512)
			(xy 171.855991 -337.264953) (xy 171.871992 -337.349263) (xy 171.880027 -337.434701) (xy 171.88053 -337.477608)
			(xy 171.880456 -337.483958) (xy 176.240953 -337.483958) (xy 176.244975 -337.398238) (xy 176.257006 -337.31327)
			(xy 176.276942 -337.229803) (xy 176.304605 -337.148569) (xy 176.339754 -337.070283) (xy 176.38208 -336.995632)
			(xy 176.431209 -336.925273) (xy 176.486712 -336.859823) (xy 176.548099 -336.799859) (xy 176.614832 -336.745906)
			(xy 176.686324 -336.698439) (xy 176.761946 -336.657875) (xy 176.841035 -336.624571) (xy 176.922895 -336.598819)
			(xy 177.006806 -336.580846) (xy 177.092032 -336.57081) (xy 177.177824 -336.568798) (xy 177.263426 -336.574829)
			(xy 177.348088 -336.588849) (xy 177.431065 -336.610735) (xy 177.511628 -336.640296) (xy 177.589068 -336.67727)
			(xy 177.662707 -336.721334) (xy 177.731895 -336.7721) (xy 177.796026 -336.829121) (xy 177.854535 -336.891897)
			(xy 177.906908 -336.959877) (xy 177.952686 -337.032462) (xy 177.991466 -337.109014) (xy 178.022907 -337.188862)
			(xy 178.046733 -337.271303) (xy 178.062734 -337.355613) (xy 178.070769 -337.441051) (xy 178.071272 -337.483958)
			(xy 182.439056 -337.483958) (xy 182.439544 -337.441682) (xy 182.447346 -337.35749) (xy 182.462882 -337.274377)
			(xy 182.486021 -337.193053) (xy 182.516565 -337.11421) (xy 182.554253 -337.038522) (xy 182.598764 -336.966634)
			(xy 182.649718 -336.89916) (xy 182.706681 -336.836675) (xy 182.769166 -336.779712) (xy 182.83664 -336.728758)
			(xy 182.908528 -336.684247) (xy 182.984216 -336.646559) (xy 183.063059 -336.616015) (xy 183.144383 -336.592876)
			(xy 183.227496 -336.57734) (xy 183.311688 -336.569538) (xy 183.39624 -336.569538) (xy 183.480432 -336.57734)
			(xy 183.563545 -336.592876) (xy 183.644869 -336.616015) (xy 183.723712 -336.646559) (xy 183.7994 -336.684247)
			(xy 183.871288 -336.728758) (xy 183.938762 -336.779712) (xy 184.001247 -336.836675) (xy 184.05821 -336.89916)
			(xy 184.109164 -336.966634) (xy 184.153675 -337.038522) (xy 184.191363 -337.11421) (xy 184.221907 -337.193053)
			(xy 184.245046 -337.274377) (xy 184.260582 -337.35749) (xy 184.268384 -337.441682) (xy 184.268872 -337.483958)
			(xy 184.268338 -337.527902) (xy 184.259914 -337.615385) (xy 184.243138 -337.701657) (xy 184.218167 -337.785923)
			(xy 184.185229 -337.867405) (xy 184.144629 -337.945353) (xy 184.096741 -338.019048) (xy 184.042007 -338.087812)
			(xy 183.98093 -338.151009) (xy 183.914074 -338.208057) (xy 183.842055 -338.258431) (xy 183.804052 -338.280502)
			(xy 183.792022 -338.28775) (xy 183.772209 -338.307642) (xy 183.758568 -338.332181) (xy 183.752134 -338.35951)
			(xy 183.753394 -338.387557) (xy 183.762252 -338.414199) (xy 183.778037 -338.437416) (xy 183.799554 -338.455452)
			(xy 183.81218 -338.461604) (xy 183.839112 -338.474322) (xy 183.889 -338.506852) (xy 183.911494 -338.526374)
			(xy 183.922936 -338.536019) (xy 183.949979 -338.548799) (xy 183.979566 -338.553185) (xy 184.009153 -338.548799)
			(xy 184.036196 -338.536019) (xy 184.047638 -338.526374) (xy 184.068792 -338.507958) (xy 184.115469 -338.476864)
			(xy 184.166199 -338.452947) (xy 184.219887 -338.436726) (xy 184.275373 -338.428551) (xy 184.303416 -338.428076)
			(xy 184.330787 -338.428514) (xy 184.384968 -338.436336) (xy 184.437473 -338.45183) (xy 184.487219 -338.474679)
			(xy 184.533184 -338.504411) (xy 184.554114 -338.522056) (xy 184.565442 -338.531292) (xy 184.591999 -338.543468)
			(xy 184.620916 -338.547641) (xy 184.649833 -338.543468) (xy 184.67639 -338.531292) (xy 184.687718 -338.522056)
			(xy 184.708664 -338.504435) (xy 184.754634 -338.474722) (xy 184.804378 -338.451883) (xy 184.856875 -338.436387)
			(xy 184.911048 -338.428553) (xy 184.938416 -338.428076) (xy 184.965667 -338.428563) (xy 185.019614 -338.436321)
			(xy 185.071908 -338.451677) (xy 185.121484 -338.474319) (xy 185.167333 -338.503786) (xy 185.208523 -338.539477)
			(xy 185.244214 -338.580667) (xy 185.273681 -338.626516) (xy 185.296323 -338.676092) (xy 185.311679 -338.728386)
			(xy 185.319437 -338.782333) (xy 185.319924 -338.809584) (xy 185.319467 -338.836955) (xy 185.31165 -338.891135)
			(xy 185.29616 -338.943639) (xy 185.273315 -338.993386) (xy 185.243587 -339.039351) (xy 185.225944 -339.060282)
			(xy 185.216727 -339.071623) (xy 185.204555 -339.098177) (xy 185.200381 -339.127088) (xy 185.204548 -339.156)
			(xy 185.216714 -339.182557) (xy 185.225944 -339.193886) (xy 185.24357 -339.214831) (xy 185.273298 -339.260796)
			(xy 185.296146 -339.31054) (xy 185.311645 -339.36304) (xy 185.319475 -339.417218) (xy 185.319477 -339.471958)
			(xy 185.31165 -339.526136) (xy 185.296154 -339.578637) (xy 185.273309 -339.628383) (xy 185.243585 -339.67435)
			(xy 185.225944 -339.695282) (xy 185.216727 -339.706623) (xy 185.204555 -339.733177) (xy 185.200381 -339.762088)
			(xy 185.204548 -339.791) (xy 185.216714 -339.817557) (xy 185.225944 -339.828886) (xy 185.24357 -339.849831)
			(xy 185.273298 -339.895796) (xy 185.296146 -339.94554) (xy 185.311645 -339.99804) (xy 185.319475 -340.052218)
			(xy 185.319477 -340.106958) (xy 185.31165 -340.161136) (xy 185.296154 -340.213637) (xy 185.273309 -340.263383)
			(xy 185.243585 -340.30935) (xy 185.225944 -340.330282) (xy 185.216727 -340.341623) (xy 185.204555 -340.368177)
			(xy 185.200381 -340.397088) (xy 185.204548 -340.426) (xy 185.216714 -340.452557) (xy 185.225944 -340.463886)
			(xy 185.24357 -340.484831) (xy 185.273298 -340.530796) (xy 185.296146 -340.58054) (xy 185.311645 -340.63304)
			(xy 185.319475 -340.687218) (xy 185.319477 -340.741958) (xy 185.31165 -340.796136) (xy 185.296154 -340.848637)
			(xy 185.273309 -340.898383) (xy 185.243585 -340.94435) (xy 185.225944 -340.965282) (xy 185.216727 -340.976623)
			(xy 185.204555 -341.003177) (xy 185.200381 -341.032088) (xy 185.204548 -341.061) (xy 185.216714 -341.087557)
			(xy 185.225944 -341.098886) (xy 185.24357 -341.119831) (xy 185.273298 -341.165796) (xy 185.296146 -341.21554)
			(xy 185.311645 -341.26804) (xy 185.319475 -341.322218) (xy 185.319477 -341.376958) (xy 185.31165 -341.431136)
			(xy 185.296154 -341.483637) (xy 185.273309 -341.533383) (xy 185.243585 -341.57935) (xy 185.225944 -341.600282)
			(xy 185.216727 -341.611623) (xy 185.204555 -341.638177) (xy 185.200381 -341.667088) (xy 185.204548 -341.696)
			(xy 185.216714 -341.722557) (xy 185.225944 -341.733886) (xy 185.24357 -341.754831) (xy 185.273298 -341.800796)
			(xy 185.296146 -341.85054) (xy 185.311645 -341.90304) (xy 185.319475 -341.957218) (xy 185.319477 -342.011958)
			(xy 185.31165 -342.066136) (xy 185.296154 -342.118637) (xy 185.273309 -342.168383) (xy 185.243585 -342.21435)
			(xy 185.225944 -342.235282) (xy 185.216727 -342.246623) (xy 185.204555 -342.273177) (xy 185.200381 -342.302088)
			(xy 185.204548 -342.331) (xy 185.216714 -342.357557) (xy 185.225944 -342.368886) (xy 185.243597 -342.389807)
			(xy 185.273306 -342.435783) (xy 185.296138 -342.485534) (xy 185.311626 -342.538037) (xy 185.319452 -342.592214)
			(xy 185.319924 -342.619584) (xy 185.319407 -342.646834) (xy 185.311653 -342.70078) (xy 185.296301 -342.753073)
			(xy 185.273663 -342.802649) (xy 185.2442 -342.848499) (xy 185.208511 -342.889689) (xy 185.167324 -342.92538)
			(xy 185.121477 -342.954847) (xy 185.071903 -342.97749) (xy 185.019611 -342.992846) (xy 184.965666 -343.000605)
			(xy 184.938416 -343.001092) (xy 184.911046 -343.000619) (xy 184.856867 -342.992803) (xy 184.804364 -342.977316)
			(xy 184.754617 -342.954475) (xy 184.70865 -342.924752) (xy 184.687718 -342.907112) (xy 184.67639 -342.897876)
			(xy 184.649833 -342.8857) (xy 184.620916 -342.881527) (xy 184.591999 -342.8857) (xy 184.565442 -342.897876)
			(xy 184.554114 -342.907112) (xy 184.533189 -342.92476) (xy 184.487214 -342.95447) (xy 184.437465 -342.977304)
			(xy 184.384963 -342.992793) (xy 184.330786 -343.000619) (xy 184.303416 -343.001092) (xy 184.275376 -343.000597)
			(xy 184.219898 -342.992398) (xy 184.166215 -342.976172) (xy 184.115483 -342.952271) (xy 184.068792 -342.921207)
			(xy 184.047638 -342.902794) (xy 184.036196 -342.893149) (xy 184.009153 -342.880369) (xy 183.979566 -342.875983)
			(xy 183.949979 -342.880369) (xy 183.922936 -342.893149) (xy 183.911494 -342.902794) (xy 183.890362 -342.921237)
			(xy 183.84368 -342.952329) (xy 183.792944 -342.97624) (xy 183.739251 -342.992455) (xy 183.683761 -343.000622)
			(xy 183.655716 -343.001092) (xy 183.628463 -343.00063) (xy 183.574511 -342.992875) (xy 183.522212 -342.97752)
			(xy 183.472631 -342.954878) (xy 183.426777 -342.92541) (xy 183.385584 -342.889716) (xy 183.34989 -342.848523)
			(xy 183.320422 -342.802669) (xy 183.29778 -342.753088) (xy 183.282425 -342.700789) (xy 183.27467 -342.646837)
			(xy 183.274208 -342.619584) (xy 183.274663 -342.592213) (xy 183.282483 -342.538034) (xy 183.297975 -342.48553)
			(xy 183.320819 -342.435784) (xy 183.350546 -342.389817) (xy 183.368188 -342.368886) (xy 183.377441 -342.357571)
			(xy 183.389618 -342.331009) (xy 183.393788 -342.302088) (xy 183.389611 -342.273168) (xy 183.377428 -342.246609)
			(xy 183.368188 -342.235282) (xy 183.350533 -342.214361) (xy 183.320812 -342.16839) (xy 183.29797 -342.118642)
			(xy 183.282477 -342.066138) (xy 183.27465 -342.011959) (xy 183.274652 -341.957217) (xy 183.282482 -341.903038)
			(xy 183.297979 -341.850535) (xy 183.320824 -341.800788) (xy 183.350548 -341.75482) (xy 183.368188 -341.733886)
			(xy 183.377441 -341.722571) (xy 183.389618 -341.696009) (xy 183.393788 -341.667088) (xy 183.389611 -341.638168)
			(xy 183.377428 -341.611609) (xy 183.368188 -341.600282) (xy 183.350533 -341.579361) (xy 183.320812 -341.53339)
			(xy 183.29797 -341.483642) (xy 183.282477 -341.431138) (xy 183.27465 -341.376959) (xy 183.274652 -341.322217)
			(xy 183.282482 -341.268038) (xy 183.297979 -341.215535) (xy 183.320824 -341.165788) (xy 183.350548 -341.11982)
			(xy 183.368188 -341.098886) (xy 183.377441 -341.087571) (xy 183.389618 -341.061009) (xy 183.393788 -341.032088)
			(xy 183.389611 -341.003168) (xy 183.377428 -340.976609) (xy 183.368188 -340.965282) (xy 183.350533 -340.944361)
			(xy 183.320812 -340.89839) (xy 183.29797 -340.848642) (xy 183.282477 -340.796138) (xy 183.27465 -340.741959)
			(xy 183.274652 -340.687217) (xy 183.282482 -340.633038) (xy 183.297979 -340.580535) (xy 183.320824 -340.530788)
			(xy 183.350548 -340.48482) (xy 183.368188 -340.463886) (xy 183.377441 -340.452571) (xy 183.389618 -340.426009)
			(xy 183.393788 -340.397088) (xy 183.389611 -340.368168) (xy 183.377428 -340.341609) (xy 183.368188 -340.330282)
			(xy 183.350533 -340.309361) (xy 183.320812 -340.26339) (xy 183.29797 -340.213642) (xy 183.282477 -340.161138)
			(xy 183.27465 -340.106959) (xy 183.274652 -340.052217) (xy 183.282482 -339.998038) (xy 183.297979 -339.945535)
			(xy 183.320824 -339.895788) (xy 183.350548 -339.84982) (xy 183.368188 -339.828886) (xy 183.377441 -339.817571)
			(xy 183.389618 -339.791009) (xy 183.393788 -339.762088) (xy 183.389611 -339.733168) (xy 183.377428 -339.706609)
			(xy 183.368188 -339.695282) (xy 183.350533 -339.674361) (xy 183.320812 -339.62839) (xy 183.29797 -339.578642)
			(xy 183.282477 -339.526138) (xy 183.27465 -339.471959) (xy 183.274652 -339.417217) (xy 183.282482 -339.363038)
			(xy 183.297979 -339.310535) (xy 183.320824 -339.260788) (xy 183.350548 -339.21482) (xy 183.368188 -339.193886)
			(xy 183.377441 -339.182571) (xy 183.389618 -339.156009) (xy 183.393788 -339.127088) (xy 183.389611 -339.098168)
			(xy 183.377428 -339.071609) (xy 183.368188 -339.060282) (xy 183.350572 -339.039331) (xy 183.320857 -338.993363)
			(xy 183.298017 -338.943621) (xy 183.28252 -338.891124) (xy 183.274686 -338.836952) (xy 183.274208 -338.809584)
			(xy 183.274668 -338.782851) (xy 183.282177 -338.729914) (xy 183.296991 -338.67854) (xy 183.318821 -338.629732)
			(xy 183.347239 -338.584443) (xy 183.364124 -338.563712) (xy 183.372832 -338.552699) (xy 183.384366 -338.527111)
			(xy 183.388505 -338.499351) (xy 183.384937 -338.471511) (xy 183.373932 -338.445692) (xy 183.356318 -338.423839)
			(xy 183.333425 -338.407602) (xy 183.306978 -338.398203) (xy 183.293004 -338.396834) (xy 183.250113 -338.393549)
			(xy 183.165193 -338.379781) (xy 183.081941 -338.358103) (xy 183.001091 -338.328705) (xy 182.923357 -338.291848)
			(xy 182.849427 -338.247857) (xy 182.779952 -338.19712) (xy 182.715547 -338.140086) (xy 182.65678 -338.077258)
			(xy 182.604169 -338.009191) (xy 182.558181 -337.936486) (xy 182.51922 -337.859785) (xy 182.487632 -337.779766)
			(xy 182.463694 -337.697135) (xy 182.447618 -337.612622) (xy 182.439547 -337.526972) (xy 182.439056 -337.483958)
			(xy 178.071272 -337.483958) (xy 178.070769 -337.526865) (xy 178.062734 -337.612303) (xy 178.046733 -337.696613)
			(xy 178.022907 -337.779054) (xy 177.991466 -337.858902) (xy 177.952686 -337.935454) (xy 177.906908 -338.008039)
			(xy 177.854535 -338.076019) (xy 177.796026 -338.138795) (xy 177.731895 -338.195816) (xy 177.662707 -338.246582)
			(xy 177.589068 -338.290646) (xy 177.511628 -338.32762) (xy 177.431065 -338.357181) (xy 177.348088 -338.379067)
			(xy 177.263426 -338.393087) (xy 177.177824 -338.399118) (xy 177.092032 -338.397106) (xy 177.006806 -338.38707)
			(xy 176.922895 -338.369097) (xy 176.841035 -338.343345) (xy 176.761946 -338.310041) (xy 176.686324 -338.269477)
			(xy 176.614832 -338.22201) (xy 176.548099 -338.168057) (xy 176.486712 -338.108093) (xy 176.431209 -338.042643)
			(xy 176.38208 -337.972284) (xy 176.339754 -337.897633) (xy 176.304605 -337.819347) (xy 176.276942 -337.738113)
			(xy 176.257006 -337.654646) (xy 176.244975 -337.569678) (xy 176.240953 -337.483958) (xy 171.880456 -337.483958)
			(xy 171.880027 -337.520515) (xy 171.871992 -337.605953) (xy 171.855991 -337.690263) (xy 171.832165 -337.772704)
			(xy 171.800724 -337.852552) (xy 171.761944 -337.929104) (xy 171.716166 -338.001689) (xy 171.663793 -338.069669)
			(xy 171.605284 -338.132445) (xy 171.541153 -338.189466) (xy 171.471965 -338.240232) (xy 171.398326 -338.284296)
			(xy 171.320886 -338.32127) (xy 171.240323 -338.350831) (xy 171.157346 -338.372717) (xy 171.072684 -338.386737)
			(xy 170.987082 -338.392768) (xy 170.90129 -338.390756) (xy 170.816064 -338.38072) (xy 170.732153 -338.362747)
			(xy 170.650293 -338.336995) (xy 170.571204 -338.303691) (xy 170.495582 -338.263127) (xy 170.42409 -338.21566)
			(xy 170.357357 -338.161707) (xy 170.29597 -338.101743) (xy 170.240467 -338.036293) (xy 170.191338 -337.965934)
			(xy 170.149012 -337.891283) (xy 170.113863 -337.812997) (xy 170.0862 -337.731763) (xy 170.066264 -337.648296)
			(xy 170.054233 -337.563328) (xy 170.050211 -337.477608) (xy 165.877748 -337.477608) (xy 165.877748 -338.838794)
			(xy 166.019226 -341.038942) (xy 166.021258 -341.085678) (xy 166.021512 -341.102188) (xy 166.021512 -341.102696)
			(xy 166.021258 -341.11311) (xy 166.021258 -341.117682) (xy 165.997988 -342.619584) (xy 168.52519 -342.619584)
			(xy 168.525649 -342.592214) (xy 168.533469 -342.538034) (xy 168.54896 -342.485531) (xy 168.571803 -342.435784)
			(xy 168.601528 -342.389818) (xy 168.61917 -342.368886) (xy 168.628425 -342.357571) (xy 168.640604 -342.33101)
			(xy 168.644775 -342.302088) (xy 168.640597 -342.273167) (xy 168.628412 -342.246608) (xy 168.61917 -342.235282)
			(xy 168.601512 -342.214363) (xy 168.571784 -342.168394) (xy 168.548937 -342.118645) (xy 168.53344 -342.066141)
			(xy 168.525612 -342.01196) (xy 168.525614 -341.957216) (xy 168.533446 -341.903035) (xy 168.548946 -341.850532)
			(xy 168.571796 -341.800785) (xy 168.601526 -341.754818) (xy 168.61917 -341.733886) (xy 168.628425 -341.722571)
			(xy 168.640604 -341.69601) (xy 168.644775 -341.667088) (xy 168.640597 -341.638167) (xy 168.628412 -341.611608)
			(xy 168.61917 -341.600282) (xy 168.601512 -341.579363) (xy 168.571784 -341.533394) (xy 168.548937 -341.483645)
			(xy 168.53344 -341.431141) (xy 168.525612 -341.37696) (xy 168.525614 -341.322216) (xy 168.533446 -341.268035)
			(xy 168.548946 -341.215532) (xy 168.571796 -341.165785) (xy 168.601526 -341.119818) (xy 168.61917 -341.098886)
			(xy 168.628425 -341.087571) (xy 168.640604 -341.06101) (xy 168.644775 -341.032088) (xy 168.640597 -341.003167)
			(xy 168.628412 -340.976608) (xy 168.61917 -340.965282) (xy 168.601512 -340.944363) (xy 168.571784 -340.898394)
			(xy 168.548937 -340.848645) (xy 168.53344 -340.796141) (xy 168.525612 -340.74196) (xy 168.525614 -340.687216)
			(xy 168.533446 -340.633035) (xy 168.548946 -340.580532) (xy 168.571796 -340.530785) (xy 168.601526 -340.484818)
			(xy 168.61917 -340.463886) (xy 168.628425 -340.452571) (xy 168.640604 -340.42601) (xy 168.644775 -340.397088)
			(xy 168.640597 -340.368167) (xy 168.628412 -340.341608) (xy 168.61917 -340.330282) (xy 168.601512 -340.309363)
			(xy 168.571784 -340.263394) (xy 168.548937 -340.213645) (xy 168.53344 -340.161141) (xy 168.525612 -340.10696)
			(xy 168.525614 -340.052216) (xy 168.533446 -339.998035) (xy 168.548946 -339.945532) (xy 168.571796 -339.895785)
			(xy 168.601526 -339.849818) (xy 168.61917 -339.828886) (xy 168.628425 -339.817571) (xy 168.640604 -339.79101)
			(xy 168.644775 -339.762088) (xy 168.640597 -339.733167) (xy 168.628412 -339.706608) (xy 168.61917 -339.695282)
			(xy 168.601512 -339.674363) (xy 168.571784 -339.628394) (xy 168.548937 -339.578645) (xy 168.53344 -339.526141)
			(xy 168.525612 -339.47196) (xy 168.525614 -339.417216) (xy 168.533446 -339.363035) (xy 168.548946 -339.310532)
			(xy 168.571796 -339.260785) (xy 168.601526 -339.214818) (xy 168.61917 -339.193886) (xy 168.628425 -339.182571)
			(xy 168.640604 -339.15601) (xy 168.644775 -339.127088) (xy 168.640597 -339.098167) (xy 168.628412 -339.071608)
			(xy 168.61917 -339.060282) (xy 168.601551 -339.039334) (xy 168.571837 -338.993365) (xy 168.548998 -338.943621)
			(xy 168.533502 -338.891125) (xy 168.525668 -338.836952) (xy 168.52519 -338.809584) (xy 168.525663 -338.782332)
			(xy 168.533422 -338.728384) (xy 168.548779 -338.676089) (xy 168.571421 -338.626512) (xy 168.600889 -338.580662)
			(xy 168.636582 -338.539472) (xy 168.677773 -338.503781) (xy 168.723625 -338.474315) (xy 168.773203 -338.451674)
			(xy 168.825498 -338.436319) (xy 168.879446 -338.428562) (xy 168.906698 -338.428076) (xy 168.934069 -338.428525)
			(xy 168.98825 -338.436344) (xy 169.040754 -338.451836) (xy 169.0905 -338.474682) (xy 169.136466 -338.504412)
			(xy 169.157396 -338.522056) (xy 169.168724 -338.531292) (xy 169.195281 -338.543468) (xy 169.224198 -338.547641)
			(xy 169.253115 -338.543468) (xy 169.279672 -338.531292) (xy 169.291 -338.522056) (xy 169.311915 -338.504396)
			(xy 169.357893 -338.474689) (xy 169.407645 -338.451858) (xy 169.460149 -338.436371) (xy 169.514328 -338.428547)
			(xy 169.541698 -338.428076) (xy 169.569738 -338.428571) (xy 169.625216 -338.436772) (xy 169.678898 -338.452997)
			(xy 169.72963 -338.476899) (xy 169.776322 -338.507962) (xy 169.797476 -338.526374) (xy 169.808918 -338.536019)
			(xy 169.835961 -338.548799) (xy 169.865548 -338.553185) (xy 169.895135 -338.548799) (xy 169.922178 -338.536019)
			(xy 169.93362 -338.526374) (xy 169.954781 -338.507967) (xy 170.001456 -338.476871) (xy 170.052184 -338.452953)
			(xy 170.105871 -338.43673) (xy 170.161356 -338.428552) (xy 170.189398 -338.428076) (xy 170.216648 -338.42858)
			(xy 170.270595 -338.436335) (xy 170.322888 -338.451689) (xy 170.372464 -338.474329) (xy 170.418314 -338.503794)
			(xy 170.459504 -338.539483) (xy 170.495195 -338.580672) (xy 170.524662 -338.62652) (xy 170.547304 -338.676095)
			(xy 170.562661 -338.728388) (xy 170.570419 -338.782334) (xy 170.570906 -338.809584) (xy 170.570429 -338.836954)
			(xy 170.562614 -338.891132) (xy 170.547127 -338.943635) (xy 170.524288 -338.993382) (xy 170.494566 -339.03935)
			(xy 170.476926 -339.060282) (xy 170.467702 -339.07162) (xy 170.45552 -339.098173) (xy 170.451343 -339.127088)
			(xy 170.455513 -339.156003) (xy 170.467689 -339.18256) (xy 170.476926 -339.193886) (xy 170.494553 -339.214831)
			(xy 170.524282 -339.260795) (xy 170.547131 -339.310539) (xy 170.562631 -339.36304) (xy 170.570462 -339.417218)
			(xy 170.570464 -339.471958) (xy 170.562636 -339.526137) (xy 170.54714 -339.578638) (xy 170.524294 -339.628384)
			(xy 170.494568 -339.67435) (xy 170.476926 -339.695282) (xy 170.467702 -339.70662) (xy 170.45552 -339.733173)
			(xy 170.451343 -339.762088) (xy 170.455513 -339.791003) (xy 170.467689 -339.81756) (xy 170.476926 -339.828886)
			(xy 170.494553 -339.849831) (xy 170.524282 -339.895795) (xy 170.547131 -339.945539) (xy 170.562631 -339.99804)
			(xy 170.570462 -340.052218) (xy 170.570464 -340.106958) (xy 170.562636 -340.161137) (xy 170.54714 -340.213638)
			(xy 170.524294 -340.263384) (xy 170.494568 -340.30935) (xy 170.476926 -340.330282) (xy 170.467702 -340.34162)
			(xy 170.45552 -340.368173) (xy 170.451343 -340.397088) (xy 170.455513 -340.426003) (xy 170.467689 -340.45256)
			(xy 170.476926 -340.463886) (xy 170.494553 -340.484831) (xy 170.524282 -340.530795) (xy 170.547131 -340.580539)
			(xy 170.562631 -340.63304) (xy 170.570462 -340.687218) (xy 170.570464 -340.741958) (xy 170.562636 -340.796137)
			(xy 170.54714 -340.848638) (xy 170.524294 -340.898384) (xy 170.494568 -340.94435) (xy 170.476926 -340.965282)
			(xy 170.467702 -340.97662) (xy 170.45552 -341.003173) (xy 170.451343 -341.032088) (xy 170.455513 -341.061003)
			(xy 170.467689 -341.08756) (xy 170.476926 -341.098886) (xy 170.494553 -341.119831) (xy 170.524282 -341.165795)
			(xy 170.547131 -341.215539) (xy 170.562631 -341.26804) (xy 170.570462 -341.322218) (xy 170.570464 -341.376958)
			(xy 170.562636 -341.431137) (xy 170.54714 -341.483638) (xy 170.524294 -341.533384) (xy 170.494568 -341.57935)
			(xy 170.476926 -341.600282) (xy 170.467702 -341.61162) (xy 170.45552 -341.638173) (xy 170.451343 -341.667088)
			(xy 170.455513 -341.696003) (xy 170.467689 -341.72256) (xy 170.476926 -341.733886) (xy 170.494553 -341.754831)
			(xy 170.524282 -341.800795) (xy 170.547131 -341.850539) (xy 170.562631 -341.90304) (xy 170.570462 -341.957218)
			(xy 170.570464 -342.011958) (xy 170.562636 -342.066137) (xy 170.54714 -342.118638) (xy 170.524294 -342.168384)
			(xy 170.494568 -342.21435) (xy 170.476926 -342.235282) (xy 170.467702 -342.24662) (xy 170.45552 -342.273173)
			(xy 170.451343 -342.302088) (xy 170.455513 -342.331003) (xy 170.467689 -342.35756) (xy 170.476926 -342.368886)
			(xy 170.494576 -342.389809) (xy 170.524285 -342.435785) (xy 170.547119 -342.485535) (xy 170.562607 -342.538037)
			(xy 170.570433 -342.592214) (xy 170.570906 -342.619584) (xy 173.495462 -342.619584) (xy 173.495904 -342.592213)
			(xy 173.503725 -342.538032) (xy 173.519219 -342.485528) (xy 173.542067 -342.435781) (xy 173.571797 -342.389816)
			(xy 173.589442 -342.368886) (xy 173.598691 -342.357569) (xy 173.610861 -342.331007) (xy 173.615029 -342.302088)
			(xy 173.610854 -342.27317) (xy 173.598678 -342.246611) (xy 173.589442 -342.235282) (xy 173.571785 -342.214362)
			(xy 173.54206 -342.168393) (xy 173.519214 -342.118644) (xy 173.503719 -342.06614) (xy 173.495891 -342.011959)
			(xy 173.495893 -341.957216) (xy 173.503724 -341.903036) (xy 173.519223 -341.850533) (xy 173.542071 -341.800786)
			(xy 173.5718 -341.754818) (xy 173.589442 -341.733886) (xy 173.598691 -341.722569) (xy 173.610861 -341.696007)
			(xy 173.615029 -341.667088) (xy 173.610854 -341.63817) (xy 173.598678 -341.611611) (xy 173.589442 -341.600282)
			(xy 173.571785 -341.579362) (xy 173.54206 -341.533393) (xy 173.519214 -341.483644) (xy 173.503719 -341.43114)
			(xy 173.495891 -341.376959) (xy 173.495893 -341.322216) (xy 173.503724 -341.268036) (xy 173.519223 -341.215533)
			(xy 173.542071 -341.165786) (xy 173.5718 -341.119818) (xy 173.589442 -341.098886) (xy 173.598691 -341.087569)
			(xy 173.610861 -341.061007) (xy 173.615029 -341.032088) (xy 173.610854 -341.00317) (xy 173.598678 -340.976611)
			(xy 173.589442 -340.965282) (xy 173.571785 -340.944362) (xy 173.54206 -340.898393) (xy 173.519214 -340.848644)
			(xy 173.503719 -340.79614) (xy 173.495891 -340.741959) (xy 173.495893 -340.687216) (xy 173.503724 -340.633036)
			(xy 173.519223 -340.580533) (xy 173.542071 -340.530786) (xy 173.5718 -340.484818) (xy 173.589442 -340.463886)
			(xy 173.598691 -340.452569) (xy 173.610861 -340.426007) (xy 173.615029 -340.397088) (xy 173.610854 -340.36817)
			(xy 173.598678 -340.341611) (xy 173.589442 -340.330282) (xy 173.571785 -340.309362) (xy 173.54206 -340.263393)
			(xy 173.519214 -340.213644) (xy 173.503719 -340.16114) (xy 173.495891 -340.106959) (xy 173.495893 -340.052216)
			(xy 173.503724 -339.998036) (xy 173.519223 -339.945533) (xy 173.542071 -339.895786) (xy 173.5718 -339.849818)
			(xy 173.589442 -339.828886) (xy 173.598691 -339.817569) (xy 173.610861 -339.791007) (xy 173.615029 -339.762088)
			(xy 173.610854 -339.73317) (xy 173.598678 -339.706611) (xy 173.589442 -339.695282) (xy 173.571785 -339.674362)
			(xy 173.54206 -339.628393) (xy 173.519214 -339.578644) (xy 173.503719 -339.52614) (xy 173.495891 -339.471959)
			(xy 173.495893 -339.417216) (xy 173.503724 -339.363036) (xy 173.519223 -339.310533) (xy 173.542071 -339.260786)
			(xy 173.5718 -339.214818) (xy 173.589442 -339.193886) (xy 173.598691 -339.182569) (xy 173.610861 -339.156007)
			(xy 173.615029 -339.127088) (xy 173.610854 -339.09817) (xy 173.598678 -339.071611) (xy 173.589442 -339.060282)
			(xy 173.571834 -339.039324) (xy 173.542116 -338.993359) (xy 173.519274 -338.943618) (xy 173.503775 -338.891123)
			(xy 173.49594 -338.836952) (xy 173.495462 -338.809584) (xy 173.495963 -338.782334) (xy 173.503721 -338.728388)
			(xy 173.519076 -338.676095) (xy 173.541717 -338.62652) (xy 173.571182 -338.580671) (xy 173.606872 -338.539482)
			(xy 173.64806 -338.503791) (xy 173.693908 -338.474324) (xy 173.743482 -338.451681) (xy 173.795774 -338.436324)
			(xy 173.84972 -338.428564) (xy 173.87697 -338.428076) (xy 173.90501 -338.428587) (xy 173.960487 -338.436784)
			(xy 174.014169 -338.453006) (xy 174.064901 -338.476904) (xy 174.111593 -338.507964) (xy 174.132748 -338.526374)
			(xy 174.14419 -338.536019) (xy 174.171233 -338.548799) (xy 174.20082 -338.553185) (xy 174.230407 -338.548799)
			(xy 174.25745 -338.536019) (xy 174.268892 -338.526374) (xy 174.290025 -338.507932) (xy 174.336707 -338.476842)
			(xy 174.387443 -338.45293) (xy 174.441136 -338.436715) (xy 174.496626 -338.428547) (xy 174.52467 -338.428076)
			(xy 174.55204 -338.428541) (xy 174.60622 -338.436356) (xy 174.658724 -338.451845) (xy 174.708471 -338.474687)
			(xy 174.754437 -338.504413) (xy 174.775368 -338.522056) (xy 174.786696 -338.531292) (xy 174.813253 -338.543468)
			(xy 174.84217 -338.547641) (xy 174.871087 -338.543468) (xy 174.897644 -338.531292) (xy 174.908972 -338.522056)
			(xy 174.929898 -338.504409) (xy 174.975873 -338.4747) (xy 175.025622 -338.451866) (xy 175.078124 -338.436377)
			(xy 175.132301 -338.428549) (xy 175.15967 -338.428076) (xy 175.186921 -338.428583) (xy 175.24087 -338.436336)
			(xy 175.293166 -338.451687) (xy 175.342745 -338.474325) (xy 175.388597 -338.503788) (xy 175.42979 -338.539477)
			(xy 175.465484 -338.580666) (xy 175.494953 -338.626515) (xy 175.517597 -338.676091) (xy 175.532955 -338.728385)
			(xy 175.540714 -338.782333) (xy 175.541178 -338.809584) (xy 175.540708 -338.836954) (xy 175.532892 -338.891133)
			(xy 175.517404 -338.943637) (xy 175.494563 -338.993383) (xy 175.464839 -339.03935) (xy 175.447198 -339.060282)
			(xy 175.437977 -339.071621) (xy 175.425798 -339.098174) (xy 175.421622 -339.127088) (xy 175.425791 -339.156002)
			(xy 175.437964 -339.182559) (xy 175.447198 -339.193886) (xy 175.464822 -339.214832) (xy 175.494546 -339.260798)
			(xy 175.51739 -339.310542) (xy 175.532887 -339.363042) (xy 175.540716 -339.417218) (xy 175.540718 -339.471958)
			(xy 175.532892 -339.526134) (xy 175.517399 -339.578635) (xy 175.494557 -339.628381) (xy 175.464837 -339.674349)
			(xy 175.447198 -339.695282) (xy 175.437977 -339.706621) (xy 175.425798 -339.733174) (xy 175.421622 -339.762088)
			(xy 175.425791 -339.791002) (xy 175.437964 -339.817559) (xy 175.447198 -339.828886) (xy 175.464822 -339.849832)
			(xy 175.494546 -339.895798) (xy 175.51739 -339.945542) (xy 175.532887 -339.998042) (xy 175.540716 -340.052218)
			(xy 175.540718 -340.106958) (xy 175.532892 -340.161134) (xy 175.517399 -340.213635) (xy 175.494557 -340.263381)
			(xy 175.464837 -340.309349) (xy 175.447198 -340.330282) (xy 175.437977 -340.341621) (xy 175.425798 -340.368174)
			(xy 175.421622 -340.397088) (xy 175.425791 -340.426002) (xy 175.437964 -340.452559) (xy 175.447198 -340.463886)
			(xy 175.464822 -340.484832) (xy 175.494546 -340.530798) (xy 175.51739 -340.580542) (xy 175.532887 -340.633042)
			(xy 175.540716 -340.687218) (xy 175.540718 -340.741958) (xy 175.532892 -340.796134) (xy 175.517399 -340.848635)
			(xy 175.494557 -340.898381) (xy 175.464837 -340.944349) (xy 175.447198 -340.965282) (xy 175.437977 -340.976621)
			(xy 175.425798 -341.003174) (xy 175.421622 -341.032088) (xy 175.425791 -341.061002) (xy 175.437964 -341.087559)
			(xy 175.447198 -341.098886) (xy 175.464822 -341.119832) (xy 175.494546 -341.165798) (xy 175.51739 -341.215542)
			(xy 175.532887 -341.268042) (xy 175.540716 -341.322218) (xy 175.540718 -341.376958) (xy 175.532892 -341.431134)
			(xy 175.517399 -341.483635) (xy 175.494557 -341.533381) (xy 175.464837 -341.579349) (xy 175.447198 -341.600282)
			(xy 175.437977 -341.611621) (xy 175.425798 -341.638174) (xy 175.421622 -341.667088) (xy 175.425791 -341.696002)
			(xy 175.437964 -341.722559) (xy 175.447198 -341.733886) (xy 175.464822 -341.754832) (xy 175.494546 -341.800798)
			(xy 175.51739 -341.850542) (xy 175.532887 -341.903042) (xy 175.540716 -341.957218) (xy 175.540718 -342.011958)
			(xy 175.532892 -342.066134) (xy 175.517399 -342.118635) (xy 175.494557 -342.168381) (xy 175.464837 -342.214349)
			(xy 175.447198 -342.235282) (xy 175.437977 -342.246621) (xy 175.425798 -342.273174) (xy 175.421622 -342.302088)
			(xy 175.425791 -342.331002) (xy 175.437964 -342.357559) (xy 175.447198 -342.368886) (xy 175.464844 -342.389813)
			(xy 175.494555 -342.435787) (xy 175.517389 -342.485536) (xy 175.532879 -342.538038) (xy 175.540705 -342.592214)
			(xy 175.541178 -342.619584) (xy 178.20259 -342.619584) (xy 178.203049 -342.592214) (xy 178.210869 -342.538034)
			(xy 178.22636 -342.485531) (xy 178.249203 -342.435784) (xy 178.278928 -342.389818) (xy 178.29657 -342.368886)
			(xy 178.305825 -342.357571) (xy 178.318004 -342.33101) (xy 178.322175 -342.302088) (xy 178.317997 -342.273167)
			(xy 178.305812 -342.246608) (xy 178.29657 -342.235282) (xy 178.278912 -342.214363) (xy 178.249184 -342.168394)
			(xy 178.226337 -342.118645) (xy 178.21084 -342.066141) (xy 178.203012 -342.01196) (xy 178.203014 -341.957216)
			(xy 178.210846 -341.903035) (xy 178.226346 -341.850532) (xy 178.249196 -341.800785) (xy 178.278926 -341.754818)
			(xy 178.29657 -341.733886) (xy 178.305825 -341.722571) (xy 178.318004 -341.69601) (xy 178.322175 -341.667088)
			(xy 178.317997 -341.638167) (xy 178.305812 -341.611608) (xy 178.29657 -341.600282) (xy 178.278912 -341.579363)
			(xy 178.249184 -341.533394) (xy 178.226337 -341.483645) (xy 178.21084 -341.431141) (xy 178.203012 -341.37696)
			(xy 178.203014 -341.322216) (xy 178.210846 -341.268035) (xy 178.226346 -341.215532) (xy 178.249196 -341.165785)
			(xy 178.278926 -341.119818) (xy 178.29657 -341.098886) (xy 178.305825 -341.087571) (xy 178.318004 -341.06101)
			(xy 178.322175 -341.032088) (xy 178.317997 -341.003167) (xy 178.305812 -340.976608) (xy 178.29657 -340.965282)
			(xy 178.278912 -340.944363) (xy 178.249184 -340.898394) (xy 178.226337 -340.848645) (xy 178.21084 -340.796141)
			(xy 178.203012 -340.74196) (xy 178.203014 -340.687216) (xy 178.210846 -340.633035) (xy 178.226346 -340.580532)
			(xy 178.249196 -340.530785) (xy 178.278926 -340.484818) (xy 178.29657 -340.463886) (xy 178.305825 -340.452571)
			(xy 178.318004 -340.42601) (xy 178.322175 -340.397088) (xy 178.317997 -340.368167) (xy 178.305812 -340.341608)
			(xy 178.29657 -340.330282) (xy 178.278912 -340.309363) (xy 178.249184 -340.263394) (xy 178.226337 -340.213645)
			(xy 178.21084 -340.161141) (xy 178.203012 -340.10696) (xy 178.203014 -340.052216) (xy 178.210846 -339.998035)
			(xy 178.226346 -339.945532) (xy 178.249196 -339.895785) (xy 178.278926 -339.849818) (xy 178.29657 -339.828886)
			(xy 178.305825 -339.817571) (xy 178.318004 -339.79101) (xy 178.322175 -339.762088) (xy 178.317997 -339.733167)
			(xy 178.305812 -339.706608) (xy 178.29657 -339.695282) (xy 178.278912 -339.674363) (xy 178.249184 -339.628394)
			(xy 178.226337 -339.578645) (xy 178.21084 -339.526141) (xy 178.203012 -339.47196) (xy 178.203014 -339.417216)
			(xy 178.210846 -339.363035) (xy 178.226346 -339.310532) (xy 178.249196 -339.260785) (xy 178.278926 -339.214818)
			(xy 178.29657 -339.193886) (xy 178.305825 -339.182571) (xy 178.318004 -339.15601) (xy 178.322175 -339.127088)
			(xy 178.317997 -339.098167) (xy 178.305812 -339.071608) (xy 178.29657 -339.060282) (xy 178.278951 -339.039334)
			(xy 178.249237 -338.993365) (xy 178.226398 -338.943621) (xy 178.210902 -338.891125) (xy 178.203068 -338.836952)
			(xy 178.20259 -338.809584) (xy 178.203063 -338.782332) (xy 178.210822 -338.728384) (xy 178.226179 -338.676089)
			(xy 178.248821 -338.626512) (xy 178.278289 -338.580662) (xy 178.313982 -338.539472) (xy 178.355173 -338.503781)
			(xy 178.401025 -338.474315) (xy 178.450603 -338.451674) (xy 178.502898 -338.436319) (xy 178.556846 -338.428562)
			(xy 178.584098 -338.428076) (xy 178.611469 -338.428525) (xy 178.66565 -338.436344) (xy 178.718154 -338.451836)
			(xy 178.7679 -338.474682) (xy 178.813866 -338.504412) (xy 178.834796 -338.522056) (xy 178.846124 -338.531292)
			(xy 178.872681 -338.543468) (xy 178.901598 -338.547641) (xy 178.930515 -338.543468) (xy 178.957072 -338.531292)
			(xy 178.9684 -338.522056) (xy 178.989315 -338.504396) (xy 179.035293 -338.474689) (xy 179.085045 -338.451858)
			(xy 179.137549 -338.436371) (xy 179.191728 -338.428547) (xy 179.219098 -338.428076) (xy 179.247138 -338.428571)
			(xy 179.302616 -338.436772) (xy 179.356298 -338.452997) (xy 179.40703 -338.476899) (xy 179.453722 -338.507962)
			(xy 179.474876 -338.526374) (xy 179.486318 -338.536019) (xy 179.513361 -338.548799) (xy 179.542948 -338.553185)
			(xy 179.572535 -338.548799) (xy 179.599578 -338.536019) (xy 179.61102 -338.526374) (xy 179.632181 -338.507967)
			(xy 179.678856 -338.476871) (xy 179.729584 -338.452953) (xy 179.783271 -338.43673) (xy 179.838756 -338.428552)
			(xy 179.866798 -338.428076) (xy 179.894048 -338.42858) (xy 179.947995 -338.436335) (xy 180.000288 -338.451689)
			(xy 180.049864 -338.474329) (xy 180.095714 -338.503794) (xy 180.136904 -338.539483) (xy 180.172595 -338.580672)
			(xy 180.202062 -338.62652) (xy 180.224704 -338.676095) (xy 180.240061 -338.728388) (xy 180.247819 -338.782334)
			(xy 180.248306 -338.809584) (xy 180.247829 -338.836954) (xy 180.240014 -338.891132) (xy 180.224527 -338.943635)
			(xy 180.201688 -338.993382) (xy 180.171966 -339.03935) (xy 180.154326 -339.060282) (xy 180.145102 -339.07162)
			(xy 180.13292 -339.098173) (xy 180.128743 -339.127088) (xy 180.132913 -339.156003) (xy 180.145089 -339.18256)
			(xy 180.154326 -339.193886) (xy 180.171953 -339.214831) (xy 180.201682 -339.260795) (xy 180.224531 -339.310539)
			(xy 180.240031 -339.36304) (xy 180.247862 -339.417218) (xy 180.247864 -339.471958) (xy 180.240036 -339.526137)
			(xy 180.22454 -339.578638) (xy 180.201694 -339.628384) (xy 180.171968 -339.67435) (xy 180.154326 -339.695282)
			(xy 180.145102 -339.70662) (xy 180.13292 -339.733173) (xy 180.128743 -339.762088) (xy 180.132913 -339.791003)
			(xy 180.145089 -339.81756) (xy 180.154326 -339.828886) (xy 180.171953 -339.849831) (xy 180.201682 -339.895795)
			(xy 180.224531 -339.945539) (xy 180.240031 -339.99804) (xy 180.247862 -340.052218) (xy 180.247864 -340.106958)
			(xy 180.240036 -340.161137) (xy 180.22454 -340.213638) (xy 180.201694 -340.263384) (xy 180.171968 -340.30935)
			(xy 180.154326 -340.330282) (xy 180.145102 -340.34162) (xy 180.13292 -340.368173) (xy 180.128743 -340.397088)
			(xy 180.132913 -340.426003) (xy 180.145089 -340.45256) (xy 180.154326 -340.463886) (xy 180.171953 -340.484831)
			(xy 180.201682 -340.530795) (xy 180.224531 -340.580539) (xy 180.240031 -340.63304) (xy 180.247862 -340.687218)
			(xy 180.247864 -340.741958) (xy 180.240036 -340.796137) (xy 180.22454 -340.848638) (xy 180.201694 -340.898384)
			(xy 180.171968 -340.94435) (xy 180.154326 -340.965282) (xy 180.145102 -340.97662) (xy 180.13292 -341.003173)
			(xy 180.128743 -341.032088) (xy 180.132913 -341.061003) (xy 180.145089 -341.08756) (xy 180.154326 -341.098886)
			(xy 180.171953 -341.119831) (xy 180.201682 -341.165795) (xy 180.224531 -341.215539) (xy 180.240031 -341.26804)
			(xy 180.247862 -341.322218) (xy 180.247864 -341.376958) (xy 180.240036 -341.431137) (xy 180.22454 -341.483638)
			(xy 180.201694 -341.533384) (xy 180.171968 -341.57935) (xy 180.154326 -341.600282) (xy 180.145102 -341.61162)
			(xy 180.13292 -341.638173) (xy 180.128743 -341.667088) (xy 180.132913 -341.696003) (xy 180.145089 -341.72256)
			(xy 180.154326 -341.733886) (xy 180.171953 -341.754831) (xy 180.201682 -341.800795) (xy 180.224531 -341.850539)
			(xy 180.240031 -341.90304) (xy 180.247862 -341.957218) (xy 180.247864 -342.011958) (xy 180.240036 -342.066137)
			(xy 180.22454 -342.118638) (xy 180.201694 -342.168384) (xy 180.171968 -342.21435) (xy 180.154326 -342.235282)
			(xy 180.145102 -342.24662) (xy 180.13292 -342.273173) (xy 180.128743 -342.302088) (xy 180.132913 -342.331003)
			(xy 180.145089 -342.35756) (xy 180.154326 -342.368886) (xy 180.171976 -342.389809) (xy 180.201685 -342.435785)
			(xy 180.224519 -342.485535) (xy 180.240007 -342.538037) (xy 180.247833 -342.592214) (xy 180.248306 -342.619584)
			(xy 180.24783 -342.646837) (xy 180.240075 -342.700787) (xy 180.224721 -342.753085) (xy 180.20208 -342.802665)
			(xy 180.172614 -342.848518) (xy 180.136921 -342.889711) (xy 180.09573 -342.925405) (xy 180.049877 -342.954873)
			(xy 180.000298 -342.977516) (xy 179.948001 -342.992872) (xy 179.894051 -343.000629) (xy 179.866798 -343.001092)
			(xy 179.838757 -343.000608) (xy 179.783279 -342.992406) (xy 179.729596 -342.976178) (xy 179.678864 -342.952274)
			(xy 179.632173 -342.921208) (xy 179.61102 -342.902794) (xy 179.599578 -342.893149) (xy 179.572535 -342.880369)
			(xy 179.542948 -342.875983) (xy 179.513361 -342.880369) (xy 179.486318 -342.893149) (xy 179.474876 -342.902794)
			(xy 179.453712 -342.921198) (xy 179.407039 -342.952296) (xy 179.356311 -342.976215) (xy 179.302625 -342.992438)
			(xy 179.24714 -343.000616) (xy 179.219098 -343.001092) (xy 179.191728 -343.000629) (xy 179.137548 -342.992811)
			(xy 179.085045 -342.977321) (xy 179.035298 -342.954479) (xy 178.989332 -342.924753) (xy 178.9684 -342.907112)
			(xy 178.957072 -342.897876) (xy 178.930515 -342.8857) (xy 178.901598 -342.881527) (xy 178.872681 -342.8857)
			(xy 178.846124 -342.897876) (xy 178.834796 -342.907112) (xy 178.813878 -342.924768) (xy 178.767901 -342.954477)
			(xy 178.71815 -342.97731) (xy 178.665646 -342.992797) (xy 178.611468 -343.00062) (xy 178.584098 -343.001092)
			(xy 178.556844 -343.000646) (xy 178.502892 -342.992889) (xy 178.450593 -342.977532) (xy 178.401012 -342.954888)
			(xy 178.355158 -342.925418) (xy 178.313965 -342.889723) (xy 178.278271 -342.848528) (xy 178.248804 -342.802673)
			(xy 178.226162 -342.75309) (xy 178.210807 -342.70079) (xy 178.203052 -342.646838) (xy 178.20259 -342.619584)
			(xy 175.541178 -342.619584) (xy 175.54073 -342.646838) (xy 175.532974 -342.700791) (xy 175.517619 -342.753091)
			(xy 175.494976 -342.802673) (xy 175.465507 -342.848528) (xy 175.429811 -342.889721) (xy 175.388616 -342.925415)
			(xy 175.342761 -342.954883) (xy 175.293178 -342.977524) (xy 175.240877 -342.992877) (xy 175.186924 -343.000631)
			(xy 175.15967 -343.001092) (xy 175.132299 -343.000645) (xy 175.078119 -342.992823) (xy 175.025616 -342.97733)
			(xy 174.975869 -342.954484) (xy 174.929903 -342.924755) (xy 174.908972 -342.907112) (xy 174.897644 -342.897876)
			(xy 174.871087 -342.8857) (xy 174.84217 -342.881527) (xy 174.813253 -342.8857) (xy 174.786696 -342.897876)
			(xy 174.775368 -342.907112) (xy 174.754423 -342.924735) (xy 174.708453 -342.954448) (xy 174.658709 -342.977287)
			(xy 174.606211 -342.992782) (xy 174.552038 -343.000615) (xy 174.52467 -343.001092) (xy 174.496629 -343.000624)
			(xy 174.441149 -342.992418) (xy 174.387467 -342.976187) (xy 174.336735 -342.952279) (xy 174.290045 -342.921209)
			(xy 174.268892 -342.902794) (xy 174.25745 -342.893149) (xy 174.230407 -342.880369) (xy 174.20082 -342.875983)
			(xy 174.171233 -342.880369) (xy 174.14419 -342.893149) (xy 174.132748 -342.902794) (xy 174.111595 -342.921212)
			(xy 174.064919 -342.952307) (xy 174.014188 -342.976223) (xy 173.9605 -342.992444) (xy 173.905013 -343.000618)
			(xy 173.87697 -343.001092) (xy 173.849717 -343.00065) (xy 173.795767 -342.992889) (xy 173.743471 -342.977529)
			(xy 173.693892 -342.954883) (xy 173.648041 -342.925413) (xy 173.606851 -342.889717) (xy 173.57116 -342.848522)
			(xy 173.541694 -342.802667) (xy 173.519055 -342.753086) (xy 173.503701 -342.700788) (xy 173.495947 -342.646837)
			(xy 173.495462 -342.619584) (xy 170.570906 -342.619584) (xy 170.57043 -342.646837) (xy 170.562675 -342.700787)
			(xy 170.547321 -342.753085) (xy 170.52468 -342.802665) (xy 170.495214 -342.848518) (xy 170.459521 -342.889711)
			(xy 170.41833 -342.925405) (xy 170.372477 -342.954873) (xy 170.322898 -342.977516) (xy 170.270601 -342.992872)
			(xy 170.216651 -343.000629) (xy 170.189398 -343.001092) (xy 170.161357 -343.000608) (xy 170.105879 -342.992406)
			(xy 170.052196 -342.976178) (xy 170.001464 -342.952274) (xy 169.954773 -342.921208) (xy 169.93362 -342.902794)
			(xy 169.922178 -342.893149) (xy 169.895135 -342.880369) (xy 169.865548 -342.875983) (xy 169.835961 -342.880369)
			(xy 169.808918 -342.893149) (xy 169.797476 -342.902794) (xy 169.776312 -342.921198) (xy 169.729639 -342.952296)
			(xy 169.678911 -342.976215) (xy 169.625225 -342.992438) (xy 169.56974 -343.000616) (xy 169.541698 -343.001092)
			(xy 169.514328 -343.000629) (xy 169.460148 -342.992811) (xy 169.407645 -342.977321) (xy 169.357898 -342.954479)
			(xy 169.311932 -342.924753) (xy 169.291 -342.907112) (xy 169.279672 -342.897876) (xy 169.253115 -342.8857)
			(xy 169.224198 -342.881527) (xy 169.195281 -342.8857) (xy 169.168724 -342.897876) (xy 169.157396 -342.907112)
			(xy 169.136478 -342.924768) (xy 169.090501 -342.954477) (xy 169.04075 -342.97731) (xy 168.988246 -342.992797)
			(xy 168.934068 -343.00062) (xy 168.906698 -343.001092) (xy 168.879444 -343.000646) (xy 168.825492 -342.992889)
			(xy 168.773193 -342.977532) (xy 168.723612 -342.954888) (xy 168.677758 -342.925418) (xy 168.636565 -342.889723)
			(xy 168.600871 -342.848528) (xy 168.571404 -342.802673) (xy 168.548762 -342.75309) (xy 168.533407 -342.70079)
			(xy 168.525652 -342.646838) (xy 168.52519 -342.619584) (xy 165.997988 -342.619584) (xy 165.877748 -350.3803)
			(xy 165.877748 -351.307908) (xy 167.357298 -352.787458) (xy 167.357298 -355.02088) (xy 168.06799 -355.02088)
			(xy 168.068468 -354.992839) (xy 168.076672 -354.93736) (xy 168.092902 -354.883678) (xy 168.116807 -354.832946)
			(xy 168.147874 -354.786255) (xy 168.166288 -354.765102) (xy 168.175903 -354.753637) (xy 168.188686 -354.726603)
			(xy 168.193077 -354.697022) (xy 168.188699 -354.66744) (xy 168.175928 -354.6404) (xy 168.166288 -354.628958)
			(xy 168.147872 -354.607803) (xy 168.116777 -354.561127) (xy 168.092861 -354.510397) (xy 168.07664 -354.456709)
			(xy 168.068464 -354.401223) (xy 168.06799 -354.37318) (xy 168.068459 -354.345928) (xy 168.076218 -354.29198)
			(xy 168.091576 -354.239685) (xy 168.114219 -354.190108) (xy 168.143687 -354.144258) (xy 168.179381 -354.103068)
			(xy 168.220572 -354.067377) (xy 168.266424 -354.037911) (xy 168.316002 -354.01527) (xy 168.368298 -353.999915)
			(xy 168.422246 -353.992158) (xy 168.449498 -353.991672) (xy 168.477465 -353.992119) (xy 168.532805 -354.000235)
			(xy 168.586365 -354.016352) (xy 168.636995 -354.040124) (xy 168.660572 -354.055172) (xy 169.291508 -354.055172)
			(xy 169.316497 -354.055629) (xy 169.365857 -354.063457) (xy 169.413383 -354.078918) (xy 169.457901 -354.10163)
			(xy 169.498314 -354.131035) (xy 169.516298 -354.14839) (xy 169.857166 -354.489512) (xy 171.74337 -354.489512)
			(xy 172.316648 -353.91598) (xy 172.334617 -353.898623) (xy 172.375051 -353.869278) (xy 172.41958 -353.846626)
			(xy 172.467106 -353.831225) (xy 172.516458 -353.823455) (xy 172.541438 -353.823016) (xy 174.346108 -353.823016)
			(xy 174.75835 -353.41052) (xy 174.776325 -353.393169) (xy 174.816756 -353.363822) (xy 174.861283 -353.341168)
			(xy 174.908809 -353.325765) (xy 174.95816 -353.317995) (xy 174.98314 -353.317556) (xy 177.3936 -353.317556)
			(xy 177.418575 -353.318017) (xy 177.467914 -353.325812) (xy 177.515427 -353.341226) (xy 177.559945 -353.363881)
			(xy 177.600373 -353.393217) (xy 177.61839 -353.41052) (xy 178.213004 -354.005134) (xy 178.226974 -354.00869)
			(xy 178.254366 -354.015826) (xy 178.306847 -354.037032) (xy 178.355617 -354.065761) (xy 178.399606 -354.101381)
			(xy 178.437848 -354.143112) (xy 178.469504 -354.190035) (xy 178.493877 -354.241122) (xy 178.510433 -354.295249)
			(xy 178.518808 -354.351229) (xy 178.519328 -354.37953) (xy 178.518897 -354.406902) (xy 178.511073 -354.461083)
			(xy 178.495577 -354.513587) (xy 178.472727 -354.563334) (xy 178.442994 -354.609298) (xy 178.425348 -354.630228)
			(xy 178.419106 -354.637848) (xy 185.603386 -354.637848) (xy 185.607457 -354.582226) (xy 185.619583 -354.527789)
			(xy 185.639506 -354.475698) (xy 185.666802 -354.427063) (xy 185.700888 -354.38292) (xy 185.741037 -354.344211)
			(xy 185.786395 -354.31176) (xy 185.835995 -354.286259) (xy 185.888779 -354.268252) (xy 185.943622 -354.258122)
			(xy 185.999356 -354.256085) (xy 186.054793 -354.262185) (xy 186.10875 -354.276291) (xy 186.160079 -354.298103)
			(xy 186.207685 -354.327157) (xy 186.250553 -354.362832) (xy 186.28777 -354.404369) (xy 186.318543 -354.450882)
			(xy 186.342215 -354.501379) (xy 186.358283 -354.554786) (xy 186.366403 -354.609962) (xy 186.366912 -354.637848)
			(xy 186.366403 -354.665734) (xy 186.358283 -354.72091) (xy 186.342215 -354.774317) (xy 186.318543 -354.824814)
			(xy 186.28777 -354.871327) (xy 186.250553 -354.912864) (xy 186.207685 -354.948539) (xy 186.160079 -354.977593)
			(xy 186.10875 -354.999405) (xy 186.054793 -355.013511) (xy 185.999356 -355.019611) (xy 185.943622 -355.017574)
			(xy 185.888779 -355.007444) (xy 185.835995 -354.989437) (xy 185.786395 -354.963936) (xy 185.741037 -354.931485)
			(xy 185.700888 -354.892776) (xy 185.666802 -354.848633) (xy 185.639506 -354.799998) (xy 185.619583 -354.747907)
			(xy 185.607457 -354.69347) (xy 185.603386 -354.637848) (xy 178.419106 -354.637848) (xy 178.416086 -354.641535)
			(xy 178.403918 -354.668101) (xy 178.399754 -354.697023) (xy 178.403931 -354.725942) (xy 178.416111 -354.752503)
			(xy 178.425348 -354.763832) (xy 178.442961 -354.784786) (xy 178.472678 -354.830752) (xy 178.49552 -354.880494)
			(xy 178.511017 -354.93299) (xy 178.518851 -354.987162) (xy 178.519328 -355.01453) (xy 178.518842 -355.041781)
			(xy 178.511086 -355.095729) (xy 178.495731 -355.148024) (xy 178.473089 -355.197601) (xy 178.443623 -355.243451)
			(xy 178.407932 -355.284642) (xy 178.366741 -355.320333) (xy 178.320891 -355.349799) (xy 178.271314 -355.372441)
			(xy 178.219019 -355.387796) (xy 178.165071 -355.395552) (xy 178.110569 -355.395552) (xy 178.056621 -355.387796)
			(xy 178.004326 -355.372441) (xy 177.954749 -355.349799) (xy 177.908899 -355.320333) (xy 177.867708 -355.284642)
			(xy 177.832017 -355.243451) (xy 177.802551 -355.197601) (xy 177.779909 -355.148024) (xy 177.764554 -355.095729)
			(xy 177.756798 -355.041781) (xy 177.756312 -355.01453) (xy 177.756793 -354.98716) (xy 177.764607 -354.932982)
			(xy 177.780092 -354.880479) (xy 177.802931 -354.830732) (xy 177.832652 -354.784764) (xy 177.850292 -354.763832)
			(xy 177.859501 -354.752483) (xy 177.871683 -354.725934) (xy 177.875861 -354.697023) (xy 177.871695 -354.66811)
			(xy 177.859525 -354.641555) (xy 177.850292 -354.630228) (xy 177.830667 -354.606738) (xy 177.798355 -354.554757)
			(xy 177.774731 -354.498295) (xy 177.76698 -354.468684) (xy 177.763424 -354.454714) (xy 177.262028 -353.953064)
			(xy 175.114712 -353.953064) (xy 174.70247 -354.36556) (xy 174.684483 -354.382898) (xy 174.644056 -354.412248)
			(xy 174.599531 -354.434905) (xy 174.552008 -354.45031) (xy 174.502659 -354.458083) (xy 174.47768 -354.458524)
			(xy 172.67301 -354.458524) (xy 172.49732 -354.634292) (xy 176.045366 -354.634292) (xy 176.049437 -354.57867)
			(xy 176.061563 -354.524233) (xy 176.081486 -354.472142) (xy 176.108782 -354.423507) (xy 176.142868 -354.379364)
			(xy 176.183017 -354.340655) (xy 176.228375 -354.308204) (xy 176.277975 -354.282703) (xy 176.330759 -354.264696)
			(xy 176.385602 -354.254566) (xy 176.441336 -354.252529) (xy 176.496773 -354.258629) (xy 176.55073 -354.272735)
			(xy 176.602059 -354.294547) (xy 176.649665 -354.323601) (xy 176.692533 -354.359276) (xy 176.72975 -354.400813)
			(xy 176.760523 -354.447326) (xy 176.784195 -354.497823) (xy 176.800263 -354.55123) (xy 176.808383 -354.606406)
			(xy 176.808892 -354.634292) (xy 176.808383 -354.662178) (xy 176.800263 -354.717354) (xy 176.784195 -354.770761)
			(xy 176.760523 -354.821258) (xy 176.72975 -354.867771) (xy 176.692533 -354.909308) (xy 176.649665 -354.944983)
			(xy 176.602059 -354.974037) (xy 176.55073 -354.995849) (xy 176.496773 -355.009955) (xy 176.441336 -355.016055)
			(xy 176.385602 -355.014018) (xy 176.330759 -355.003888) (xy 176.277975 -354.985881) (xy 176.228375 -354.96038)
			(xy 176.183017 -354.927929) (xy 176.142868 -354.88922) (xy 176.108782 -354.845077) (xy 176.081486 -354.796442)
			(xy 176.061563 -354.744351) (xy 176.049437 -354.689914) (xy 176.045366 -354.634292) (xy 172.49732 -354.634292)
			(xy 172.099732 -355.032056) (xy 172.081717 -355.049364) (xy 172.041297 -355.078717) (xy 171.99678 -355.10138)
			(xy 171.949263 -355.116793) (xy 171.899919 -355.124574) (xy 171.874942 -355.12502) (xy 169.725594 -355.12502)
			(xy 169.700618 -355.12457) (xy 169.651279 -355.116773) (xy 169.603765 -355.101357) (xy 169.559248 -355.0787)
			(xy 169.518821 -355.04936) (xy 169.500804 -355.032056) (xy 169.159936 -354.691188) (xy 168.875202 -354.691188)
			(xy 168.860243 -354.691753) (xy 168.83163 -354.700503) (xy 168.806778 -354.717166) (xy 168.787817 -354.740312)
			(xy 168.776373 -354.767958) (xy 168.773427 -354.797733) (xy 168.779231 -354.827086) (xy 168.785794 -354.84054)
			(xy 168.80002 -354.868451) (xy 168.820194 -354.927754) (xy 168.830395 -354.989559) (xy 168.831006 -355.02088)
			(xy 168.83052 -355.048131) (xy 168.822764 -355.102079) (xy 168.807409 -355.154374) (xy 168.784767 -355.203951)
			(xy 168.755301 -355.249801) (xy 168.71961 -355.290992) (xy 168.678419 -355.326683) (xy 168.632569 -355.356149)
			(xy 168.582992 -355.378791) (xy 168.530697 -355.394146) (xy 168.476749 -355.401902) (xy 168.422247 -355.401902)
			(xy 168.368299 -355.394146) (xy 168.316004 -355.378791) (xy 168.266427 -355.356149) (xy 168.220577 -355.326683)
			(xy 168.179386 -355.290992) (xy 168.143695 -355.249801) (xy 168.114229 -355.203951) (xy 168.091587 -355.154374)
			(xy 168.076232 -355.102079) (xy 168.068476 -355.048131) (xy 168.06799 -355.02088) (xy 167.357298 -355.02088)
			(xy 167.357298 -355.4171) (xy 172.316679 -355.4171) (xy 172.320847 -355.361492) (xy 172.333255 -355.307126)
			(xy 172.353627 -355.255216) (xy 172.381508 -355.206922) (xy 172.416275 -355.163323) (xy 172.457152 -355.125392)
			(xy 172.503225 -355.093977) (xy 172.553465 -355.069779) (xy 172.606751 -355.053339) (xy 172.661892 -355.045025)
			(xy 172.689774 -355.044502) (xy 172.717106 -355.044977) (xy 172.771185 -355.052948) (xy 172.823518 -355.068736)
			(xy 172.872982 -355.092004) (xy 172.918514 -355.122251) (xy 172.959137 -355.158828) (xy 172.993977 -355.200949)
			(xy 173.008544 -355.22408) (xy 173.016453 -355.236315) (xy 173.037926 -355.255989) (xy 173.064084 -355.268794)
			(xy 173.092794 -355.273686) (xy 173.121716 -355.270266) (xy 173.13529 -355.264974) (xy 173.158503 -355.255494)
			(xy 173.206835 -355.24214) (xy 173.256523 -355.235408) (xy 173.281594 -355.235002) (xy 173.306663 -355.235442)
			(xy 173.356345 -355.242185) (xy 173.40468 -355.255511) (xy 173.427898 -355.264974) (xy 173.441482 -355.270214)
			(xy 173.470388 -355.273597) (xy 173.499075 -355.268699) (xy 173.52522 -355.255916) (xy 173.546704 -355.236283)
			(xy 173.554644 -355.22408) (xy 173.569213 -355.200949) (xy 173.604056 -355.158828) (xy 173.644679 -355.122249)
			(xy 173.69021 -355.091998) (xy 173.739672 -355.068722) (xy 173.792003 -355.052922) (xy 173.846082 -355.044936)
			(xy 173.900746 -355.044936) (xy 173.954825 -355.052922) (xy 174.007156 -355.068722) (xy 174.056618 -355.091998)
			(xy 174.102149 -355.122249) (xy 174.142772 -355.158828) (xy 174.177615 -355.200949) (xy 174.192184 -355.22408)
			(xy 174.20015 -355.236274) (xy 174.221608 -355.255948) (xy 174.24775 -355.268758) (xy 174.276446 -355.273661)
			(xy 174.305358 -355.270257) (xy 174.31893 -355.264974) (xy 174.342139 -355.255482) (xy 174.390472 -355.242132)
			(xy 174.440162 -355.235405) (xy 174.465234 -355.235002) (xy 174.492078 -355.23542) (xy 174.545211 -355.24313)
			(xy 174.596686 -355.258385) (xy 174.64544 -355.280868) (xy 174.690463 -355.310116) (xy 174.730823 -355.345522)
			(xy 174.765683 -355.386354) (xy 174.794323 -355.431765) (xy 174.81615 -355.480817) (xy 174.823882 -355.506528)
			(xy 174.828594 -355.521008) (xy 174.845101 -355.546571) (xy 174.868405 -355.566137) (xy 174.896439 -355.577971)
			(xy 174.926716 -355.58102) (xy 174.956547 -355.575016) (xy 174.970186 -355.56825) (xy 174.998325 -355.553603)
			(xy 175.05828 -355.532881) (xy 175.120841 -355.522389) (xy 175.152558 -355.521768) (xy 175.170577 -355.521985)
			(xy 175.206452 -355.525422) (xy 175.224186 -355.528626) (xy 175.239394 -355.530974) (xy 175.269951 -355.527449)
			(xy 175.298072 -355.514987) (xy 175.321208 -355.494718) (xy 175.337261 -355.46848) (xy 175.341534 -355.453696)
			(xy 175.348943 -355.426655) (xy 175.370568 -355.374927) (xy 175.399529 -355.32692) (xy 175.435203 -355.283666)
			(xy 175.476821 -355.246098) (xy 175.523487 -355.215023) (xy 175.574199 -355.191111) (xy 175.627863 -355.174875)
			(xy 175.683325 -355.166666) (xy 175.711358 -355.166168) (xy 175.738609 -355.166694) (xy 175.792556 -355.174445)
			(xy 175.844851 -355.189794) (xy 175.89443 -355.21243) (xy 175.940282 -355.241892) (xy 175.981474 -355.277579)
			(xy 176.017169 -355.318765) (xy 176.046638 -355.364612) (xy 176.069282 -355.414187) (xy 176.070138 -355.4171)
			(xy 182.004979 -355.4171) (xy 182.009147 -355.36149) (xy 182.021556 -355.307122) (xy 182.04193 -355.25521)
			(xy 182.069813 -355.206915) (xy 182.104582 -355.163315) (xy 182.145461 -355.125384) (xy 182.191537 -355.09397)
			(xy 182.241781 -355.069773) (xy 182.29507 -355.053335) (xy 182.350213 -355.045023) (xy 182.378096 -355.044502)
			(xy 182.405428 -355.044959) (xy 182.459508 -355.052933) (xy 182.511842 -355.068725) (xy 182.561306 -355.091995)
			(xy 182.606838 -355.122245) (xy 182.64746 -355.158824) (xy 182.6823 -355.200947) (xy 182.696866 -355.22408)
			(xy 182.704754 -355.23633) (xy 182.726233 -355.256004) (xy 182.752397 -355.268807) (xy 182.781111 -355.273695)
			(xy 182.810037 -355.27027) (xy 182.823612 -355.264974) (xy 182.846823 -355.255487) (xy 182.895155 -355.242135)
			(xy 182.944844 -355.235406) (xy 182.969916 -355.235002) (xy 182.994985 -355.235435) (xy 183.044668 -355.242181)
			(xy 183.093002 -355.25551) (xy 183.11622 -355.264974) (xy 183.129796 -355.270237) (xy 183.158706 -355.273615)
			(xy 183.187396 -355.268712) (xy 183.213543 -355.255923) (xy 183.235026 -355.236286) (xy 183.242966 -355.22408)
			(xy 183.257535 -355.200949) (xy 183.292378 -355.158828) (xy 183.333001 -355.122249) (xy 183.378532 -355.091998)
			(xy 183.427994 -355.068722) (xy 183.480325 -355.052922) (xy 183.534404 -355.044936) (xy 183.589068 -355.044936)
			(xy 183.643147 -355.052922) (xy 183.695478 -355.068722) (xy 183.74494 -355.091998) (xy 183.790471 -355.122249)
			(xy 183.831094 -355.158828) (xy 183.865937 -355.200949) (xy 183.880506 -355.22408) (xy 183.888451 -355.236289)
			(xy 183.909915 -355.255963) (xy 183.936063 -355.268771) (xy 183.964764 -355.27367) (xy 183.99368 -355.270261)
			(xy 184.007252 -355.264974) (xy 184.030458 -355.255475) (xy 184.078793 -355.242128) (xy 184.128484 -355.235403)
			(xy 184.153556 -355.235002) (xy 184.180398 -355.23549) (xy 184.233527 -355.243189) (xy 184.285002 -355.258433)
			(xy 184.333755 -355.280907) (xy 184.378778 -355.310146) (xy 184.419139 -355.345544) (xy 184.454001 -355.386368)
			(xy 184.482643 -355.431774) (xy 184.504471 -355.48082) (xy 184.512204 -355.506528) (xy 184.516888 -355.521018)
			(xy 184.533399 -355.546585) (xy 184.55671 -355.566152) (xy 184.58475 -355.577984) (xy 184.615032 -355.58103)
			(xy 184.644867 -355.575019) (xy 184.658508 -355.56825) (xy 184.686661 -355.553631) (xy 184.746609 -355.5329)
			(xy 184.809164 -355.522395) (xy 184.84088 -355.521768) (xy 184.8589 -355.521982) (xy 184.894774 -355.525421)
			(xy 184.912508 -355.528626) (xy 184.927714 -355.530997) (xy 184.958273 -355.527466) (xy 184.986395 -355.514998)
			(xy 185.009532 -355.494724) (xy 185.025584 -355.468482) (xy 185.029856 -355.453696) (xy 185.037245 -355.426649)
			(xy 185.058872 -355.374919) (xy 185.087835 -355.326911) (xy 185.123511 -355.283658) (xy 185.165131 -355.24609)
			(xy 185.211801 -355.215015) (xy 185.262515 -355.191104) (xy 185.316182 -355.174871) (xy 185.371646 -355.166664)
			(xy 185.39968 -355.166168) (xy 185.42693 -355.166697) (xy 185.480875 -355.17445) (xy 185.533167 -355.189801)
			(xy 185.582742 -355.212438) (xy 185.628592 -355.2419) (xy 185.669782 -355.277587) (xy 185.705473 -355.318773)
			(xy 185.734941 -355.364619) (xy 185.757583 -355.414192) (xy 185.772941 -355.466482) (xy 185.7807 -355.520426)
			(xy 185.781188 -355.547676) (xy 185.78071 -355.57525) (xy 185.772761 -355.629823) (xy 185.757038 -355.682682)
			(xy 185.733871 -355.732729) (xy 185.70374 -355.778918) (xy 185.667274 -355.82029) (xy 185.646568 -355.838506)
			(xy 185.635698 -355.848431) (xy 185.61963 -355.873075) (xy 185.611247 -355.901275) (xy 185.611243 -355.930694)
			(xy 185.619617 -355.958897) (xy 185.635678 -355.983546) (xy 185.646568 -355.993446) (xy 185.667251 -356.011687)
			(xy 185.703717 -356.053054) (xy 185.733847 -356.09924) (xy 185.757012 -356.149284) (xy 185.77273 -356.202142)
			(xy 185.780673 -356.256712) (xy 185.780675 -356.311857) (xy 185.772737 -356.366428) (xy 185.757023 -356.419287)
			(xy 185.733862 -356.469333) (xy 185.703736 -356.515521) (xy 185.667273 -356.556891) (xy 185.646568 -356.575106)
			(xy 185.635698 -356.585031) (xy 185.61963 -356.609675) (xy 185.611247 -356.637875) (xy 185.611243 -356.667294)
			(xy 185.619617 -356.695497) (xy 185.635678 -356.720146) (xy 185.646568 -356.730046) (xy 185.66725 -356.748289)
			(xy 185.703724 -356.78965) (xy 185.73386 -356.835833) (xy 185.757032 -356.885875) (xy 185.772754 -356.938732)
			(xy 185.7807 -356.993303) (xy 185.781188 -357.020876) (xy 185.780722 -357.048129) (xy 185.772968 -357.102081)
			(xy 185.757614 -357.15438) (xy 185.734973 -357.203961) (xy 185.705506 -357.249816) (xy 185.669812 -357.291009)
			(xy 185.628619 -357.326703) (xy 185.582765 -357.356171) (xy 185.533184 -357.378813) (xy 185.480885 -357.394167)
			(xy 185.426933 -357.401922) (xy 185.39968 -357.402384) (xy 185.371824 -357.401891) (xy 185.316706 -357.393764)
			(xy 185.263355 -357.377715) (xy 185.212901 -357.354085) (xy 185.166416 -357.323374) (xy 185.124887 -357.286235)
			(xy 185.089195 -357.243456) (xy 185.060097 -357.195945) (xy 185.038211 -357.144711) (xy 185.030618 -357.117904)
			(xy 185.026394 -357.10377) (xy 185.010993 -357.078621) (xy 184.989063 -357.058905) (xy 184.962422 -357.046259)
			(xy 184.933281 -357.041732) (xy 184.918604 -357.043228) (xy 184.905587 -357.044895) (xy 184.879403 -357.046676)
			(xy 184.86628 -357.046784) (xy 184.852131 -357.046693) (xy 184.823908 -357.044657) (xy 184.809892 -357.04272)
			(xy 184.79654 -357.041169) (xy 184.769851 -357.044258) (xy 184.744897 -357.054218) (xy 184.723417 -357.070357)
			(xy 184.706905 -357.091552) (xy 184.696509 -357.116327) (xy 184.694322 -357.129588) (xy 184.690263 -357.156746)
			(xy 184.675284 -357.209576) (xy 184.652888 -357.259714) (xy 184.623536 -357.306124) (xy 184.587835 -357.347847)
			(xy 184.546523 -357.384023) (xy 184.500452 -357.413903) (xy 184.450573 -357.436871) (xy 184.397918 -357.452452)
			(xy 184.343572 -357.460326) (xy 184.316116 -357.460804) (xy 184.288863 -357.46033) (xy 184.234913 -357.452575)
			(xy 184.182615 -357.437221) (xy 184.133034 -357.41458) (xy 184.087181 -357.385113) (xy 184.045988 -357.34942)
			(xy 184.010294 -357.308229) (xy 183.980826 -357.262376) (xy 183.958184 -357.212797) (xy 183.942828 -357.160499)
			(xy 183.935071 -357.106549) (xy 183.934608 -357.079296) (xy 183.935068 -357.051721) (xy 183.943021 -356.997148)
			(xy 183.958747 -356.944288) (xy 183.981918 -356.894242) (xy 184.012052 -356.848052) (xy 184.04852 -356.806682)
			(xy 184.069228 -356.788466) (xy 184.080126 -356.77857) (xy 184.096194 -356.753918) (xy 184.104574 -356.72571)
			(xy 184.104573 -356.696284) (xy 184.096191 -356.668078) (xy 184.080123 -356.643426) (xy 184.069228 -356.633526)
			(xy 184.048532 -356.615298) (xy 184.012059 -356.573934) (xy 183.981924 -356.527748) (xy 183.958756 -356.477703)
			(xy 183.943037 -356.424843) (xy 183.935094 -356.37027) (xy 183.934608 -356.342696) (xy 183.935076 -356.316195)
			(xy 183.942417 -356.263705) (xy 183.956958 -356.212737) (xy 183.978418 -356.164275) (xy 184.006384 -356.119251)
			(xy 184.023 -356.098602) (xy 184.032398 -356.086423) (xy 184.0442 -356.058034) (xy 184.047035 -356.027421)
			(xy 184.040647 -355.997347) (xy 184.025613 -355.970529) (xy 184.003291 -355.949389) (xy 183.989726 -355.942138)
			(xy 183.96604 -355.93003) (xy 183.922058 -355.900108) (xy 183.882776 -355.864239) (xy 183.848991 -355.823151)
			(xy 183.834786 -355.80066) (xy 183.826864 -355.788436) (xy 183.80539 -355.76877) (xy 183.779237 -355.755968)
			(xy 183.750533 -355.751072) (xy 183.721614 -355.754481) (xy 183.70804 -355.759766) (xy 183.684836 -355.76927)
			(xy 183.6365 -355.782615) (xy 183.586808 -355.789337) (xy 183.561736 -355.789738) (xy 183.536666 -355.789326)
			(xy 183.486983 -355.782572) (xy 183.438649 -355.769235) (xy 183.415432 -355.759766) (xy 183.401852 -355.754528)
			(xy 183.372954 -355.751164) (xy 183.344277 -355.756074) (xy 183.318144 -355.76886) (xy 183.296668 -355.788488)
			(xy 183.288686 -355.80066) (xy 183.274117 -355.823791) (xy 183.239274 -355.865912) (xy 183.198651 -355.902491)
			(xy 183.15312 -355.932742) (xy 183.103658 -355.956018) (xy 183.051327 -355.971818) (xy 182.997248 -355.979804)
			(xy 182.942584 -355.979804) (xy 182.888505 -355.971818) (xy 182.836174 -355.956018) (xy 182.786712 -355.932742)
			(xy 182.741181 -355.902491) (xy 182.700558 -355.865912) (xy 182.665715 -355.823791) (xy 182.651146 -355.80066)
			(xy 182.643262 -355.788408) (xy 182.621778 -355.768742) (xy 182.595614 -355.755943) (xy 182.566901 -355.751055)
			(xy 182.537976 -355.754474) (xy 182.5244 -355.759766) (xy 182.501189 -355.769251) (xy 182.452856 -355.782603)
			(xy 182.403167 -355.789333) (xy 182.378096 -355.789738) (xy 182.350213 -355.789177) (xy 182.29507 -355.780865)
			(xy 182.241781 -355.764427) (xy 182.191537 -355.74023) (xy 182.145461 -355.708816) (xy 182.104582 -355.670885)
			(xy 182.069813 -355.627285) (xy 182.04193 -355.57899) (xy 182.021556 -355.527078) (xy 182.009147 -355.47271)
			(xy 182.004979 -355.4171) (xy 176.070138 -355.4171) (xy 176.084641 -355.466479) (xy 176.092401 -355.520425)
			(xy 176.092866 -355.547676) (xy 176.092396 -355.575251) (xy 176.084446 -355.629824) (xy 176.068722 -355.682684)
			(xy 176.045553 -355.73273) (xy 176.015421 -355.77892) (xy 175.978953 -355.820291) (xy 175.958246 -355.838506)
			(xy 175.947369 -355.848427) (xy 175.931289 -355.873069) (xy 175.922898 -355.901272) (xy 175.922894 -355.930697)
			(xy 175.931276 -355.958903) (xy 175.947348 -355.98355) (xy 175.958246 -355.993446) (xy 175.97893 -356.011686)
			(xy 176.015398 -356.053052) (xy 176.04553 -356.099239) (xy 176.068696 -356.149282) (xy 176.084415 -356.202141)
			(xy 176.092358 -356.256712) (xy 176.092361 -356.311857) (xy 176.084422 -356.366429) (xy 176.068707 -356.419288)
			(xy 176.045545 -356.469334) (xy 176.036694 -356.482904) (xy 178.547266 -356.482904) (xy 178.551337 -356.427282)
			(xy 178.563463 -356.372845) (xy 178.583386 -356.320754) (xy 178.610682 -356.272119) (xy 178.644768 -356.227976)
			(xy 178.684917 -356.189267) (xy 178.730275 -356.156816) (xy 178.779875 -356.131315) (xy 178.832659 -356.113308)
			(xy 178.887502 -356.103178) (xy 178.943236 -356.101141) (xy 178.998673 -356.107241) (xy 179.05263 -356.121347)
			(xy 179.103959 -356.143159) (xy 179.151565 -356.172213) (xy 179.194433 -356.207888) (xy 179.23165 -356.249425)
			(xy 179.262423 -356.295938) (xy 179.286095 -356.346435) (xy 179.302163 -356.399842) (xy 179.310283 -356.455018)
			(xy 179.310792 -356.482904) (xy 179.310283 -356.51079) (xy 179.302163 -356.565966) (xy 179.286095 -356.619373)
			(xy 179.262423 -356.66987) (xy 179.23165 -356.716383) (xy 179.194433 -356.75792) (xy 179.151565 -356.793595)
			(xy 179.103959 -356.822649) (xy 179.05263 -356.844461) (xy 178.998673 -356.858567) (xy 178.943236 -356.864667)
			(xy 178.887502 -356.86263) (xy 178.832659 -356.8525) (xy 178.779875 -356.834493) (xy 178.730275 -356.808992)
			(xy 178.684917 -356.776541) (xy 178.644768 -356.737832) (xy 178.610682 -356.693689) (xy 178.583386 -356.645054)
			(xy 178.563463 -356.592963) (xy 178.551337 -356.538526) (xy 178.547266 -356.482904) (xy 176.036694 -356.482904)
			(xy 176.015417 -356.515523) (xy 175.978952 -356.556892) (xy 175.958246 -356.575106) (xy 175.947369 -356.585027)
			(xy 175.931289 -356.609669) (xy 175.922898 -356.637872) (xy 175.922894 -356.667297) (xy 175.931276 -356.695503)
			(xy 175.947348 -356.72015) (xy 175.958246 -356.730046) (xy 175.978943 -356.748272) (xy 176.015413 -356.789639)
			(xy 176.045546 -356.835826) (xy 176.068713 -356.885871) (xy 176.084433 -356.93873) (xy 176.092378 -356.993302)
			(xy 176.092866 -357.020876) (xy 176.092422 -357.04813) (xy 176.084667 -357.102084) (xy 176.069312 -357.154385)
			(xy 176.04667 -357.203968) (xy 176.0172 -357.249823) (xy 175.981504 -357.291017) (xy 175.940308 -357.326711)
			(xy 175.894452 -357.356178) (xy 175.844868 -357.378819) (xy 175.792566 -357.394171) (xy 175.738612 -357.401924)
			(xy 175.711358 -357.402384) (xy 175.683501 -357.401911) (xy 175.628383 -357.393781) (xy 175.575031 -357.377729)
			(xy 175.524577 -357.354095) (xy 175.478092 -357.323382) (xy 175.436563 -357.286241) (xy 175.400871 -357.24346)
			(xy 175.371774 -357.195948) (xy 175.349889 -357.144711) (xy 175.342296 -357.117904) (xy 175.337994 -357.103798)
			(xy 175.322609 -357.078656) (xy 175.300697 -357.058941) (xy 175.274076 -357.046287) (xy 175.244953 -357.041743)
			(xy 175.230282 -357.043228) (xy 175.217265 -357.044897) (xy 175.191081 -357.046677) (xy 175.177958 -357.046784)
			(xy 175.163809 -357.046695) (xy 175.135586 -357.044658) (xy 175.12157 -357.04272) (xy 175.10822 -357.041147)
			(xy 175.081529 -357.044241) (xy 175.056574 -357.054206) (xy 175.035094 -357.070349) (xy 175.018582 -357.091547)
			(xy 175.008187 -357.116326) (xy 175.006 -357.129588) (xy 175.001962 -357.15675) (xy 174.986983 -357.209582)
			(xy 174.964584 -357.259721) (xy 174.935231 -357.306132) (xy 174.899527 -357.347855) (xy 174.858212 -357.384031)
			(xy 174.812138 -357.41391) (xy 174.762257 -357.436877) (xy 174.709599 -357.452457) (xy 174.655251 -357.460327)
			(xy 174.627794 -357.460804) (xy 177.882802 -357.460804) (xy 177.886873 -357.405182) (xy 177.898999 -357.350745)
			(xy 177.918922 -357.298654) (xy 177.946218 -357.250019) (xy 177.980304 -357.205876) (xy 178.020453 -357.167167)
			(xy 178.065811 -357.134716) (xy 178.115411 -357.109215) (xy 178.168195 -357.091208) (xy 178.223038 -357.081078)
			(xy 178.278772 -357.079041) (xy 178.334209 -357.085141) (xy 178.388166 -357.099247) (xy 178.439495 -357.121059)
			(xy 178.487101 -357.150113) (xy 178.529969 -357.185788) (xy 178.567186 -357.227325) (xy 178.597959 -357.273838)
			(xy 178.621631 -357.324335) (xy 178.637699 -357.377742) (xy 178.645819 -357.432918) (xy 178.646328 -357.460804)
			(xy 178.645819 -357.48869) (xy 178.637699 -357.543866) (xy 178.621631 -357.597273) (xy 178.597959 -357.64777)
			(xy 178.567186 -357.694283) (xy 178.529969 -357.73582) (xy 178.487101 -357.771495) (xy 178.439495 -357.800549)
			(xy 178.388166 -357.822361) (xy 178.334209 -357.836467) (xy 178.278772 -357.842567) (xy 178.223038 -357.84053)
			(xy 178.168195 -357.8304) (xy 178.115411 -357.812393) (xy 178.065811 -357.786892) (xy 178.020453 -357.754441)
			(xy 177.980304 -357.715732) (xy 177.946218 -357.671589) (xy 177.918922 -357.622954) (xy 177.898999 -357.570863)
			(xy 177.886873 -357.516426) (xy 177.882802 -357.460804) (xy 174.627794 -357.460804) (xy 174.600542 -357.460328)
			(xy 174.546594 -357.45257) (xy 174.494299 -357.437214) (xy 174.444721 -357.414572) (xy 174.398871 -357.385105)
			(xy 174.357681 -357.349412) (xy 174.321989 -357.308221) (xy 174.292523 -357.26237) (xy 174.269882 -357.212792)
			(xy 174.254528 -357.160496) (xy 174.246772 -357.106548) (xy 174.246286 -357.079296) (xy 174.246754 -357.051722)
			(xy 174.254707 -356.997149) (xy 174.270432 -356.944289) (xy 174.293601 -356.894244) (xy 174.323733 -356.848054)
			(xy 174.3602 -356.806682) (xy 174.380906 -356.788466) (xy 174.391806 -356.778571) (xy 174.407877 -356.753919)
			(xy 174.41626 -356.725711) (xy 174.416259 -356.696284) (xy 174.407875 -356.668076) (xy 174.391803 -356.643425)
			(xy 174.380906 -356.633526) (xy 174.360205 -356.615303) (xy 174.323734 -356.573937) (xy 174.2936 -356.52775)
			(xy 174.270433 -356.477704) (xy 174.254714 -356.424843) (xy 174.246772 -356.37027) (xy 174.246286 -356.342696)
			(xy 174.246759 -356.316196) (xy 174.2541 -356.263705) (xy 174.26864 -356.212738) (xy 174.290099 -356.164275)
			(xy 174.318063 -356.119252) (xy 174.334678 -356.098602) (xy 174.344049 -356.086407) (xy 174.355839 -356.058023)
			(xy 174.35867 -356.027419) (xy 174.352287 -355.997354) (xy 174.337266 -355.97054) (xy 174.31496 -355.949395)
			(xy 174.301404 -355.942138) (xy 174.277714 -355.930037) (xy 174.233734 -355.900113) (xy 174.194453 -355.864242)
			(xy 174.160669 -355.823152) (xy 174.146464 -355.80066) (xy 174.138563 -355.788421) (xy 174.117083 -355.768755)
			(xy 174.090924 -355.755954) (xy 174.062215 -355.751063) (xy 174.033293 -355.754477) (xy 174.019718 -355.759766)
			(xy 173.996504 -355.769246) (xy 173.948173 -355.7826) (xy 173.898485 -355.789332) (xy 173.873414 -355.789738)
			(xy 173.848345 -355.7893) (xy 173.798662 -355.782557) (xy 173.750328 -355.76923) (xy 173.72711 -355.759766)
			(xy 173.713502 -355.75461) (xy 173.684618 -355.751229) (xy 173.655952 -355.756121) (xy 173.629823 -355.768887)
			(xy 173.608347 -355.788496) (xy 173.600364 -355.80066) (xy 173.585795 -355.823791) (xy 173.550952 -355.865912)
			(xy 173.510329 -355.902491) (xy 173.464798 -355.932742) (xy 173.415336 -355.956018) (xy 173.363005 -355.971818)
			(xy 173.308926 -355.979804) (xy 173.254262 -355.979804) (xy 173.200183 -355.971818) (xy 173.147852 -355.956018)
			(xy 173.09839 -355.932742) (xy 173.052859 -355.902491) (xy 173.012236 -355.865912) (xy 172.977393 -355.823791)
			(xy 172.962824 -355.80066) (xy 172.954866 -355.788462) (xy 172.933402 -355.768796) (xy 172.907258 -355.75599)
			(xy 172.878563 -355.751087) (xy 172.849651 -355.754487) (xy 172.836078 -355.759766) (xy 172.812869 -355.769258)
			(xy 172.764536 -355.782607) (xy 172.714846 -355.789335) (xy 172.689774 -355.789738) (xy 172.661892 -355.789175)
			(xy 172.606751 -355.780861) (xy 172.553465 -355.764421) (xy 172.503225 -355.740223) (xy 172.457152 -355.708808)
			(xy 172.416275 -355.670877) (xy 172.381508 -355.627278) (xy 172.353627 -355.578984) (xy 172.333255 -355.527074)
			(xy 172.320847 -355.472708) (xy 172.316679 -355.4171) (xy 167.357298 -355.4171) (xy 167.357298 -356.482904)
			(xy 168.858944 -356.482904) (xy 168.863015 -356.427282) (xy 168.875141 -356.372845) (xy 168.895064 -356.320754)
			(xy 168.92236 -356.272119) (xy 168.956446 -356.227976) (xy 168.996595 -356.189267) (xy 169.041953 -356.156816)
			(xy 169.091553 -356.131315) (xy 169.144337 -356.113308) (xy 169.19918 -356.103178) (xy 169.254914 -356.101141)
			(xy 169.310351 -356.107241) (xy 169.364308 -356.121347) (xy 169.415637 -356.143159) (xy 169.463243 -356.172213)
			(xy 169.506111 -356.207888) (xy 169.543328 -356.249425) (xy 169.574101 -356.295938) (xy 169.597773 -356.346435)
			(xy 169.613841 -356.399842) (xy 169.621961 -356.455018) (xy 169.62247 -356.482904) (xy 169.621961 -356.51079)
			(xy 169.613841 -356.565966) (xy 169.597773 -356.619373) (xy 169.574101 -356.66987) (xy 169.543328 -356.716383)
			(xy 169.506111 -356.75792) (xy 169.463243 -356.793595) (xy 169.415637 -356.822649) (xy 169.364308 -356.844461)
			(xy 169.310351 -356.858567) (xy 169.254914 -356.864667) (xy 169.19918 -356.86263) (xy 169.144337 -356.8525)
			(xy 169.091553 -356.834493) (xy 169.041953 -356.808992) (xy 168.996595 -356.776541) (xy 168.956446 -356.737832)
			(xy 168.92236 -356.693689) (xy 168.895064 -356.645054) (xy 168.875141 -356.592963) (xy 168.863015 -356.538526)
			(xy 168.858944 -356.482904) (xy 167.357298 -356.482904) (xy 167.357298 -357.448866) (xy 168.19448 -357.448866)
			(xy 168.198551 -357.393244) (xy 168.210677 -357.338807) (xy 168.2306 -357.286716) (xy 168.257896 -357.238081)
			(xy 168.291982 -357.193938) (xy 168.332131 -357.155229) (xy 168.377489 -357.122778) (xy 168.427089 -357.097277)
			(xy 168.479873 -357.07927) (xy 168.534716 -357.06914) (xy 168.59045 -357.067103) (xy 168.645887 -357.073203)
			(xy 168.699844 -357.087309) (xy 168.751173 -357.109121) (xy 168.798779 -357.138175) (xy 168.841647 -357.17385)
			(xy 168.878864 -357.215387) (xy 168.909637 -357.2619) (xy 168.933309 -357.312397) (xy 168.949377 -357.365804)
			(xy 168.957497 -357.42098) (xy 168.958006 -357.448866) (xy 168.957497 -357.476752) (xy 168.949377 -357.531928)
			(xy 168.933309 -357.585335) (xy 168.909637 -357.635832) (xy 168.878864 -357.682345) (xy 168.841647 -357.723882)
			(xy 168.798779 -357.759557) (xy 168.751173 -357.788611) (xy 168.699844 -357.810423) (xy 168.645887 -357.824529)
			(xy 168.59045 -357.830629) (xy 168.534716 -357.828592) (xy 168.479873 -357.818462) (xy 168.427089 -357.800455)
			(xy 168.377489 -357.774954) (xy 168.332131 -357.742503) (xy 168.291982 -357.703794) (xy 168.257896 -357.659651)
			(xy 168.2306 -357.611016) (xy 168.210677 -357.558925) (xy 168.198551 -357.504488) (xy 168.19448 -357.448866)
			(xy 167.357298 -357.448866) (xy 167.357298 -357.99141) (xy 169.66565 -357.99141) (xy 169.666086 -357.966072)
			(xy 169.672793 -357.915843) (xy 169.686091 -357.866943) (xy 169.705744 -357.820235) (xy 169.731409 -357.776539)
			(xy 169.762632 -357.736625) (xy 169.780458 -357.718614) (xy 169.789846 -357.708834) (xy 169.803642 -357.685512)
			(xy 169.810797 -357.659378) (xy 169.810805 -357.632282) (xy 169.803665 -357.606143) (xy 169.789883 -357.582814)
			(xy 169.780458 -357.573072) (xy 169.762627 -357.555065) (xy 169.731397 -357.515153) (xy 169.705728 -357.471458)
			(xy 169.68607 -357.424748) (xy 169.67277 -357.375847) (xy 169.666063 -357.325615) (xy 169.66565 -357.300276)
			(xy 169.666136 -357.273025) (xy 169.673892 -357.219077) (xy 169.689247 -357.166782) (xy 169.711889 -357.117205)
			(xy 169.741355 -357.071355) (xy 169.777046 -357.030164) (xy 169.818237 -356.994473) (xy 169.864087 -356.965007)
			(xy 169.913664 -356.942365) (xy 169.965959 -356.92701) (xy 170.019907 -356.919254) (xy 170.074409 -356.919254)
			(xy 170.128357 -356.92701) (xy 170.180652 -356.942365) (xy 170.230229 -356.965007) (xy 170.276079 -356.994473)
			(xy 170.31727 -357.030164) (xy 170.352961 -357.071355) (xy 170.382427 -357.117205) (xy 170.405069 -357.166782)
			(xy 170.420424 -357.219077) (xy 170.42818 -357.273025) (xy 170.428326 -357.281226) (xy 171.290996 -357.281226)
			(xy 171.291482 -357.253975) (xy 171.299238 -357.200027) (xy 171.314593 -357.147732) (xy 171.337235 -357.098155)
			(xy 171.366701 -357.052305) (xy 171.402392 -357.011114) (xy 171.443583 -356.975423) (xy 171.489433 -356.945957)
			(xy 171.53901 -356.923315) (xy 171.591305 -356.90796) (xy 171.645253 -356.900204) (xy 171.699755 -356.900204)
			(xy 171.753703 -356.90796) (xy 171.805998 -356.923315) (xy 171.855575 -356.945957) (xy 171.901425 -356.975423)
			(xy 171.942616 -357.011114) (xy 171.978307 -357.052305) (xy 172.007773 -357.098155) (xy 172.030415 -357.147732)
			(xy 172.04577 -357.200027) (xy 172.053526 -357.253975) (xy 172.054012 -357.281226) (xy 172.05377 -357.299893)
			(xy 172.050079 -357.337044) (xy 172.046646 -357.355394) (xy 172.044279 -357.369658) (xy 172.046811 -357.398451)
			(xy 172.057314 -357.425379) (xy 172.074943 -357.448283) (xy 172.098287 -357.465328) (xy 172.125472 -357.475145)
			(xy 172.139864 -357.476552) (xy 172.168516 -357.478943) (xy 172.224682 -357.491225) (xy 172.278369 -357.511796)
			(xy 172.328362 -357.54019) (xy 172.373528 -357.575762) (xy 172.412846 -357.61771) (xy 172.445425 -357.665081)
			(xy 172.470528 -357.716805) (xy 172.487586 -357.771709) (xy 172.496212 -357.828551) (xy 172.496734 -357.857298)
			(xy 172.496248 -357.884549) (xy 172.488492 -357.938497) (xy 172.473137 -357.990792) (xy 172.450495 -358.040369)
			(xy 172.441966 -358.05364) (xy 179.353972 -358.05364) (xy 179.35445 -358.025192) (xy 179.362913 -357.96893)
			(xy 179.379643 -357.91455) (xy 179.404268 -357.86326) (xy 179.436242 -357.816198) (xy 179.474853 -357.77441)
			(xy 179.49672 -357.756206) (xy 179.508238 -357.746308) (xy 179.525265 -357.721175) (xy 179.534167 -357.692153)
			(xy 179.534159 -357.661795) (xy 179.525242 -357.632777) (xy 179.508202 -357.607653) (xy 179.49672 -357.59771)
			(xy 179.474849 -357.579513) (xy 179.436246 -357.537721) (xy 179.404282 -357.490657) (xy 179.379667 -357.439365)
			(xy 179.362948 -357.384984) (xy 179.354497 -357.328722) (xy 179.353972 -357.300276) (xy 179.354458 -357.273025)
			(xy 179.362214 -357.219077) (xy 179.377569 -357.166782) (xy 179.400211 -357.117205) (xy 179.429677 -357.071355)
			(xy 179.465368 -357.030164) (xy 179.506559 -356.994473) (xy 179.552409 -356.965007) (xy 179.601986 -356.942365)
			(xy 179.654281 -356.92701) (xy 179.708229 -356.919254) (xy 179.762731 -356.919254) (xy 179.816679 -356.92701)
			(xy 179.868974 -356.942365) (xy 179.918551 -356.965007) (xy 179.964401 -356.994473) (xy 180.005592 -357.030164)
			(xy 180.041283 -357.071355) (xy 180.070749 -357.117205) (xy 180.093391 -357.166782) (xy 180.108746 -357.219077)
			(xy 180.116502 -357.273025) (xy 180.116648 -357.281226) (xy 180.979318 -357.281226) (xy 180.979804 -357.253975)
			(xy 180.98756 -357.200027) (xy 181.002915 -357.147732) (xy 181.025557 -357.098155) (xy 181.055023 -357.052305)
			(xy 181.090714 -357.011114) (xy 181.131905 -356.975423) (xy 181.177755 -356.945957) (xy 181.227332 -356.923315)
			(xy 181.279627 -356.90796) (xy 181.333575 -356.900204) (xy 181.388077 -356.900204) (xy 181.442025 -356.90796)
			(xy 181.49432 -356.923315) (xy 181.543897 -356.945957) (xy 181.589747 -356.975423) (xy 181.630938 -357.011114)
			(xy 181.666629 -357.052305) (xy 181.696095 -357.098155) (xy 181.718737 -357.147732) (xy 181.734092 -357.200027)
			(xy 181.741848 -357.253975) (xy 181.742334 -357.281226) (xy 181.742101 -357.299893) (xy 181.738409 -357.337045)
			(xy 181.734968 -357.355394) (xy 181.73258 -357.369656) (xy 181.735113 -357.398452) (xy 181.745618 -357.425384)
			(xy 181.763252 -357.44829) (xy 181.786601 -357.465334) (xy 181.813792 -357.475148) (xy 181.828186 -357.476552)
			(xy 181.85684 -357.478924) (xy 181.913006 -357.49121) (xy 181.966693 -357.511783) (xy 182.016686 -357.540179)
			(xy 182.061852 -357.575754) (xy 182.10117 -357.617703) (xy 182.133748 -357.665077) (xy 182.158851 -357.716802)
			(xy 182.175908 -357.771707) (xy 182.184534 -357.828551) (xy 182.185056 -357.857298) (xy 182.18457 -357.884549)
			(xy 182.176814 -357.938497) (xy 182.161459 -357.990792) (xy 182.138817 -358.040369) (xy 182.109351 -358.086219)
			(xy 182.07366 -358.12741) (xy 182.032469 -358.163101) (xy 181.986619 -358.192567) (xy 181.937042 -358.215209)
			(xy 181.884747 -358.230564) (xy 181.830799 -358.23832) (xy 181.776297 -358.23832) (xy 181.722349 -358.230564)
			(xy 181.670054 -358.215209) (xy 181.620477 -358.192567) (xy 181.574627 -358.163101) (xy 181.533436 -358.12741)
			(xy 181.497745 -358.086219) (xy 181.468279 -358.040369) (xy 181.445637 -357.990792) (xy 181.430282 -357.938497)
			(xy 181.422526 -357.884549) (xy 181.42204 -357.857298) (xy 181.422277 -357.838631) (xy 181.425967 -357.801479)
			(xy 181.429406 -357.78313) (xy 181.431793 -357.768867) (xy 181.429265 -357.740068) (xy 181.418763 -357.713134)
			(xy 181.401128 -357.690227) (xy 181.377777 -357.673184) (xy 181.350583 -357.663373) (xy 181.336188 -357.661972)
			(xy 181.307535 -357.659599) (xy 181.25137 -357.64731) (xy 181.197685 -357.626735) (xy 181.147693 -357.598338)
			(xy 181.102528 -357.562763) (xy 181.063211 -357.520815) (xy 181.030633 -357.473442) (xy 181.00553 -357.421719)
			(xy 180.98847 -357.366815) (xy 180.979841 -357.309973) (xy 180.979318 -357.281226) (xy 180.116648 -357.281226)
			(xy 180.116988 -357.300276) (xy 180.116428 -357.32872) (xy 180.107979 -357.384978) (xy 180.091264 -357.439356)
			(xy 180.066654 -357.490646) (xy 180.034696 -357.53771) (xy 179.9961 -357.579502) (xy 179.97424 -357.59771)
			(xy 179.96281 -357.6077) (xy 179.945787 -357.632808) (xy 179.93688 -357.661806) (xy 179.936872 -357.692141)
			(xy 179.945764 -357.721144) (xy 179.962774 -357.746261) (xy 179.97424 -357.756206) (xy 179.99611 -357.774404)
			(xy 180.034716 -357.816194) (xy 180.066681 -357.863258) (xy 180.091296 -357.914551) (xy 180.108014 -357.968932)
			(xy 180.116464 -358.025193) (xy 180.116988 -358.05364) (xy 180.116502 -358.080891) (xy 180.108746 -358.134839)
			(xy 180.093391 -358.187134) (xy 180.070749 -358.236711) (xy 180.041283 -358.282561) (xy 180.005592 -358.323752)
			(xy 179.964401 -358.359443) (xy 179.918551 -358.388909) (xy 179.868974 -358.411551) (xy 179.816679 -358.426906)
			(xy 179.762731 -358.434662) (xy 179.708229 -358.434662) (xy 179.654281 -358.426906) (xy 179.601986 -358.411551)
			(xy 179.552409 -358.388909) (xy 179.506559 -358.359443) (xy 179.465368 -358.323752) (xy 179.429677 -358.282561)
			(xy 179.400211 -358.236711) (xy 179.377569 -358.187134) (xy 179.362214 -358.134839) (xy 179.354458 -358.080891)
			(xy 179.353972 -358.05364) (xy 172.441966 -358.05364) (xy 172.421029 -358.086219) (xy 172.385338 -358.12741)
			(xy 172.344147 -358.163101) (xy 172.298297 -358.192567) (xy 172.24872 -358.215209) (xy 172.196425 -358.230564)
			(xy 172.142477 -358.23832) (xy 172.087975 -358.23832) (xy 172.034027 -358.230564) (xy 171.981732 -358.215209)
			(xy 171.932155 -358.192567) (xy 171.886305 -358.163101) (xy 171.845114 -358.12741) (xy 171.809423 -358.086219)
			(xy 171.779957 -358.040369) (xy 171.757315 -357.990792) (xy 171.74196 -357.938497) (xy 171.734204 -357.884549)
			(xy 171.733718 -357.857298) (xy 171.733956 -357.838631) (xy 171.737645 -357.801479) (xy 171.741084 -357.78313)
			(xy 171.743398 -357.76886) (xy 171.740872 -357.740075) (xy 171.730379 -357.713153) (xy 171.71276 -357.690251)
			(xy 171.689428 -357.673205) (xy 171.662253 -357.663383) (xy 171.647866 -357.661972) (xy 171.619211 -357.659618)
			(xy 171.563046 -357.647326) (xy 171.50936 -357.626748) (xy 171.459369 -357.598348) (xy 171.414205 -357.562771)
			(xy 171.374888 -357.520821) (xy 171.34231 -357.473447) (xy 171.317207 -357.421722) (xy 171.300148 -357.366816)
			(xy 171.291519 -357.309973) (xy 171.290996 -357.281226) (xy 170.428326 -357.281226) (xy 170.428666 -357.300276)
			(xy 170.428216 -357.325613) (xy 170.421511 -357.375842) (xy 170.408216 -357.424741) (xy 170.388565 -357.47145)
			(xy 170.362903 -357.515146) (xy 170.331683 -357.555061) (xy 170.313858 -357.573072) (xy 170.30443 -357.582799)
			(xy 170.290719 -357.606154) (xy 170.283619 -357.632289) (xy 170.283627 -357.659371) (xy 170.290743 -357.685502)
			(xy 170.304467 -357.708849) (xy 170.313858 -357.718614) (xy 170.331685 -357.736625) (xy 170.362915 -357.776536)
			(xy 170.388585 -357.820231) (xy 170.408243 -357.86694) (xy 170.421543 -357.91584) (xy 170.428252 -357.966071)
			(xy 170.428546 -357.984044) (xy 170.68165 -357.984044) (xy 170.682136 -357.956793) (xy 170.689892 -357.902845)
			(xy 170.705247 -357.85055) (xy 170.727889 -357.800973) (xy 170.757355 -357.755123) (xy 170.793046 -357.713932)
			(xy 170.834237 -357.678241) (xy 170.880087 -357.648775) (xy 170.929664 -357.626133) (xy 170.981959 -357.610778)
			(xy 171.035907 -357.603022) (xy 171.090409 -357.603022) (xy 171.144357 -357.610778) (xy 171.196652 -357.626133)
			(xy 171.246229 -357.648775) (xy 171.292079 -357.678241) (xy 171.33327 -357.713932) (xy 171.368961 -357.755123)
			(xy 171.398427 -357.800973) (xy 171.421069 -357.85055) (xy 171.436424 -357.902845) (xy 171.44418 -357.956793)
			(xy 171.444666 -357.984044) (xy 171.444204 -358.010788) (xy 171.43671 -358.063749) (xy 171.421889 -358.115144)
			(xy 171.400032 -358.163963) (xy 171.371567 -358.209249) (xy 171.337054 -358.250114) (xy 171.317412 -358.26827)
			(xy 171.317412 -358.652826) (xy 171.521882 -358.857296) (xy 175.13173 -358.857296) (xy 175.572928 -358.416098)
			(xy 175.591063 -358.398904) (xy 175.632613 -358.371155) (xy 175.678775 -358.35204) (xy 175.727778 -358.342291)
			(xy 175.75276 -358.341676) (xy 177.94478 -358.341676) (xy 177.969762 -358.342311) (xy 178.01877 -358.352046)
			(xy 178.06494 -358.371146) (xy 178.106501 -358.398879) (xy 178.124612 -358.416098) (xy 178.414172 -358.705658)
			(xy 178.431444 -358.72374) (xy 178.459252 -358.765289) (xy 178.478422 -358.811464) (xy 178.488215 -358.860492)
			(xy 178.488848 -358.88549) (xy 178.488848 -359.26522) (xy 178.89347 -359.670096) (xy 179.542694 -359.670096)
			(xy 180.496972 -358.715564) (xy 180.496972 -358.26827) (xy 180.477363 -358.250094) (xy 180.442905 -358.209211)
			(xy 180.414492 -358.163918) (xy 180.392679 -358.115103) (xy 180.377893 -358.063721) (xy 180.370424 -358.010778)
			(xy 180.369972 -357.984044) (xy 180.370458 -357.956793) (xy 180.378214 -357.902845) (xy 180.393569 -357.85055)
			(xy 180.416211 -357.800973) (xy 180.445677 -357.755123) (xy 180.481368 -357.713932) (xy 180.522559 -357.678241)
			(xy 180.568409 -357.648775) (xy 180.617986 -357.626133) (xy 180.670281 -357.610778) (xy 180.724229 -357.603022)
			(xy 180.778731 -357.603022) (xy 180.832679 -357.610778) (xy 180.884974 -357.626133) (xy 180.934551 -357.648775)
			(xy 180.980401 -357.678241) (xy 181.021592 -357.713932) (xy 181.057283 -357.755123) (xy 181.086749 -357.800973)
			(xy 181.109391 -357.85055) (xy 181.124746 -357.902845) (xy 181.132502 -357.956793) (xy 181.132988 -357.984044)
			(xy 181.132521 -358.010778) (xy 181.125062 -358.063723) (xy 181.110284 -358.115107) (xy 181.088474 -358.163924)
			(xy 181.060062 -358.209218) (xy 181.025603 -358.2501) (xy 181.005988 -358.26827) (xy 181.005988 -358.820974)
			(xy 181.005333 -358.845969) (xy 180.995534 -358.894991) (xy 180.976366 -358.941161) (xy 180.948564 -358.982709)
			(xy 180.931312 -359.000806) (xy 179.827936 -360.104182) (xy 179.809829 -360.121406) (xy 179.768268 -360.149146)
			(xy 179.722097 -360.168252) (xy 179.673088 -360.177993) (xy 179.648104 -360.178604) (xy 178.78806 -360.178604)
			(xy 178.763075 -360.178012) (xy 178.714066 -360.168265) (xy 178.667896 -360.149152) (xy 178.626336 -360.121407)
			(xy 178.608228 -360.104182) (xy 178.054508 -359.550462) (xy 178.037242 -359.532375) (xy 178.009434 -359.490827)
			(xy 177.990263 -359.444653) (xy 177.980467 -359.395627) (xy 177.979832 -359.37063) (xy 177.979832 -358.9909)
			(xy 177.83937 -358.850184) (xy 175.85817 -358.850184) (xy 175.416972 -359.291382) (xy 175.398849 -359.308589)
			(xy 175.357294 -359.336332) (xy 175.311128 -359.355443) (xy 175.262122 -359.365189) (xy 175.23714 -359.365804)
			(xy 171.416472 -359.365804) (xy 171.391488 -359.365204) (xy 171.342478 -359.355459) (xy 171.296309 -359.336349)
			(xy 171.254749 -359.308606) (xy 171.23664 -359.291382) (xy 170.883326 -358.938068) (xy 170.866118 -358.919946)
			(xy 170.838375 -358.87839) (xy 170.819264 -358.832224) (xy 170.809518 -358.783219) (xy 170.808904 -358.758236)
			(xy 170.808904 -358.26827) (xy 170.789283 -358.250094) (xy 170.754783 -358.209224) (xy 170.726325 -358.16394)
			(xy 170.704467 -358.115126) (xy 170.689636 -358.063739) (xy 170.682123 -358.010786) (xy 170.68165 -357.984044)
			(xy 170.428546 -357.984044) (xy 170.428666 -357.99141) (xy 170.42818 -358.018661) (xy 170.420424 -358.072609)
			(xy 170.405069 -358.124904) (xy 170.382427 -358.174481) (xy 170.352961 -358.220331) (xy 170.31727 -358.261522)
			(xy 170.276079 -358.297213) (xy 170.230229 -358.326679) (xy 170.180652 -358.349321) (xy 170.128357 -358.364676)
			(xy 170.074409 -358.372432) (xy 170.019907 -358.372432) (xy 169.965959 -358.364676) (xy 169.913664 -358.349321)
			(xy 169.864087 -358.326679) (xy 169.818237 -358.297213) (xy 169.777046 -358.261522) (xy 169.741355 -358.220331)
			(xy 169.711889 -358.174481) (xy 169.689247 -358.124904) (xy 169.673892 -358.072609) (xy 169.666136 -358.018661)
			(xy 169.66565 -357.99141) (xy 167.357298 -357.99141) (xy 167.357298 -358.969564) (xy 168.351708 -359.96372)
			(xy 168.370465 -359.983161) (xy 168.402874 -360.026381) (xy 168.428868 -360.073737) (xy 168.43883 -360.098848)
			(xy 168.44264 -360.109008) (xy 168.542716 -360.209084) (xy 168.542716 -361.518962) (xy 175.165258 -361.518962)
			(xy 175.165781 -361.489792) (xy 175.174688 -361.432135) (xy 175.192271 -361.376507) (xy 175.218122 -361.324205)
			(xy 175.251636 -361.276451) (xy 175.292033 -361.234359) (xy 175.314864 -361.216194) (xy 175.325211 -361.207738)
			(xy 175.341501 -361.186567) (xy 175.351744 -361.161896) (xy 175.355241 -361.135413) (xy 175.351751 -361.10893)
			(xy 175.341514 -361.084257) (xy 175.32523 -361.063081) (xy 175.314864 -361.05465) (xy 175.292028 -361.036491)
			(xy 175.251629 -360.994402) (xy 175.218116 -360.946647) (xy 175.192271 -360.894343) (xy 175.1747 -360.838712)
			(xy 175.165812 -360.781052) (xy 175.165258 -360.751882) (xy 175.165761 -360.724632) (xy 175.173519 -360.670687)
			(xy 175.188875 -360.618394) (xy 175.211515 -360.568819) (xy 175.24098 -360.52297) (xy 175.27667 -360.481781)
			(xy 175.317858 -360.44609) (xy 175.363705 -360.416623) (xy 175.413279 -360.39398) (xy 175.465571 -360.378622)
			(xy 175.519516 -360.370862) (xy 175.546766 -360.370374) (xy 175.575683 -360.370889) (xy 175.632856 -360.379614)
			(xy 175.688056 -360.396871) (xy 175.740019 -360.422263) (xy 175.787552 -360.455209) (xy 175.829567 -360.494953)
			(xy 175.847756 -360.51744) (xy 175.857653 -360.529245) (xy 175.882977 -360.546764) (xy 175.91237 -360.55594)
			(xy 175.943162 -360.55594) (xy 175.972555 -360.546764) (xy 175.997879 -360.529245) (xy 176.007776 -360.51744)
			(xy 176.025991 -360.494976) (xy 176.068004 -360.455238) (xy 176.115534 -360.422296) (xy 176.167491 -360.396903)
			(xy 176.222685 -360.379643) (xy 176.279851 -360.370911) (xy 176.308766 -360.370374) (xy 176.337312 -360.37093)
			(xy 176.393765 -360.379443) (xy 176.44832 -360.396269) (xy 176.499761 -360.421033) (xy 176.52365 -360.436668)
			(xy 176.534772 -360.443765) (xy 176.559632 -360.452568) (xy 176.585919 -360.45469) (xy 176.61187 -360.449989)
			(xy 176.635742 -360.438781) (xy 176.655935 -360.421817) (xy 176.663858 -360.411268) (xy 176.679265 -360.390252)
			(xy 176.714864 -360.352198) (xy 176.75531 -360.31934) (xy 176.799849 -360.29229) (xy 176.847654 -360.27155)
			(xy 176.897835 -360.257507) (xy 176.949461 -360.25042) (xy 176.975516 -360.249978) (xy 177.004432 -360.250527)
			(xy 177.061603 -360.259246) (xy 177.116803 -360.276496) (xy 177.168765 -360.301881) (xy 177.2163 -360.334821)
			(xy 177.258316 -360.37456) (xy 177.276506 -360.397044) (xy 177.286403 -360.408849) (xy 177.311727 -360.426368)
			(xy 177.34112 -360.435544) (xy 177.371912 -360.435544) (xy 177.401305 -360.426368) (xy 177.426629 -360.408849)
			(xy 177.436526 -360.397044) (xy 177.454713 -360.374557) (xy 177.496733 -360.33482) (xy 177.544268 -360.30188)
			(xy 177.59623 -360.276492) (xy 177.651429 -360.259237) (xy 177.7086 -360.250511) (xy 177.737516 -360.249978)
			(xy 177.764767 -360.250463) (xy 177.818714 -360.258221) (xy 177.871008 -360.273578) (xy 177.920584 -360.29622)
			(xy 177.966434 -360.325686) (xy 178.007624 -360.361378) (xy 178.043315 -360.402568) (xy 178.072781 -360.448417)
			(xy 178.095423 -360.497994) (xy 178.110779 -360.550288) (xy 178.118537 -360.604235) (xy 178.119024 -360.631486)
			(xy 178.118573 -360.657529) (xy 178.111489 -360.70913) (xy 178.097451 -360.759287) (xy 178.076719 -360.807069)
			(xy 178.04968 -360.851586) (xy 178.016836 -360.89201) (xy 177.99812 -360.910124) (xy 177.988141 -360.920052)
			(xy 177.973673 -360.94419) (xy 177.966332 -360.971357) (xy 177.966673 -360.999497) (xy 177.97467 -361.026479)
			(xy 177.989718 -361.050259) (xy 177.999898 -361.059984) (xy 178.019495 -361.07813) (xy 178.053888 -361.118993)
			(xy 178.082244 -361.164254) (xy 178.104009 -361.213028) (xy 178.118757 -361.264362) (xy 178.1262 -361.317251)
			(xy 178.126644 -361.343956) (xy 178.126102 -361.371724) (xy 178.118056 -361.426674) (xy 178.102127 -361.479877)
			(xy 178.078653 -361.530208) (xy 178.048129 -361.576604) (xy 178.011201 -361.618083) (xy 177.990246 -361.63631)
			(xy 177.979642 -361.645881) (xy 177.963652 -361.66953) (xy 177.954852 -361.696687) (xy 177.953933 -361.725219)
			(xy 177.960967 -361.752886) (xy 177.975402 -361.777515) (xy 177.98542 -361.787694) (xy 178.003747 -361.805801)
			(xy 178.035923 -361.846035) (xy 178.062396 -361.890231) (xy 178.082685 -361.937585) (xy 178.096422 -361.987238)
			(xy 178.103357 -362.038287) (xy 178.103784 -362.064046) (xy 178.10329 -362.091415) (xy 178.09548 -362.145593)
			(xy 178.079997 -362.198096) (xy 178.057162 -362.247844) (xy 178.027443 -362.293812) (xy 178.009804 -362.314744)
			(xy 178.000523 -362.326038) (xy 177.98835 -362.352608) (xy 177.984186 -362.381535) (xy 177.98837 -362.410459)
			(xy 178.00056 -362.437021) (xy 178.009804 -362.448348) (xy 178.027488 -362.469245) (xy 178.057209 -362.51522)
			(xy 178.08005 -362.564972) (xy 178.095541 -362.617479) (xy 178.103365 -362.671662) (xy 178.10336 -362.726407)
			(xy 178.095526 -362.780589) (xy 178.080025 -362.833093) (xy 178.057176 -362.882841) (xy 178.027447 -362.928811)
			(xy 178.009804 -362.949744) (xy 178.000523 -362.961038) (xy 177.98835 -362.987608) (xy 177.984186 -363.016535)
			(xy 177.98837 -363.045459) (xy 178.00056 -363.072021) (xy 178.009804 -363.083348) (xy 178.027433 -363.104288)
			(xy 178.057146 -363.150259) (xy 178.059513 -363.155414) (xy 179.144926 -363.155414) (xy 179.144926 -363.070718)
			(xy 179.152977 -362.986404) (xy 179.169006 -362.903238) (xy 179.192867 -362.821971) (xy 179.224346 -362.743341)
			(xy 179.263157 -362.66806) (xy 179.308947 -362.596808) (xy 179.361303 -362.530232) (xy 179.419751 -362.468934)
			(xy 179.483761 -362.413469) (xy 179.552753 -362.36434) (xy 179.626103 -362.321991) (xy 179.703146 -362.286807)
			(xy 179.783185 -362.259105) (xy 179.865494 -362.239137) (xy 179.949329 -362.227084) (xy 180.03393 -362.223054)
			(xy 180.118531 -362.227084) (xy 180.202366 -362.239137) (xy 180.284675 -362.259105) (xy 180.364714 -362.286807)
			(xy 180.441757 -362.321991) (xy 180.515107 -362.36434) (xy 180.584099 -362.413469) (xy 180.648109 -362.468934)
			(xy 180.706557 -362.530232) (xy 180.758913 -362.596808) (xy 180.804703 -362.66806) (xy 180.843514 -362.743341)
			(xy 180.874993 -362.821971) (xy 180.898854 -362.903238) (xy 180.914883 -362.986404) (xy 180.922934 -363.070718)
			(xy 180.923438 -363.113066) (xy 181.669439 -363.113066) (xy 181.673475 -363.029619) (xy 181.685547 -362.946951)
			(xy 181.70554 -362.865834) (xy 181.733269 -362.787025) (xy 181.768475 -362.71126) (xy 181.810829 -362.639247)
			(xy 181.859935 -362.571658) (xy 181.915336 -362.509124) (xy 181.976513 -362.452229) (xy 182.042896 -362.401503)
			(xy 182.113864 -362.357422) (xy 182.188756 -362.320396) (xy 182.266872 -362.29077) (xy 182.347482 -362.268822)
			(xy 182.429834 -362.254757) (xy 182.51316 -362.248705) (xy 182.59668 -362.250724) (xy 182.679616 -362.260794)
			(xy 182.761192 -362.278822) (xy 182.840648 -362.304639) (xy 182.917241 -362.338004) (xy 182.990257 -362.378605)
			(xy 183.059013 -362.426064) (xy 183.122867 -362.479937) (xy 183.181224 -362.539722) (xy 183.233539 -362.604859)
			(xy 183.279322 -362.674742) (xy 183.318147 -362.748717) (xy 183.349652 -362.826094) (xy 183.373541 -362.906151)
			(xy 183.389592 -362.988139) (xy 183.397655 -363.071294) (xy 183.39816 -363.113066) (xy 183.397655 -363.154838)
			(xy 183.389592 -363.237993) (xy 183.373541 -363.319981) (xy 183.349652 -363.400038) (xy 183.318147 -363.477415)
			(xy 183.279322 -363.55139) (xy 183.233539 -363.621273) (xy 183.181224 -363.68641) (xy 183.122867 -363.746195)
			(xy 183.059013 -363.800068) (xy 182.990257 -363.847527) (xy 182.917241 -363.888128) (xy 182.840648 -363.921493)
			(xy 182.761192 -363.94731) (xy 182.679616 -363.965338) (xy 182.59668 -363.975408) (xy 182.51316 -363.977427)
			(xy 182.429834 -363.971375) (xy 182.347482 -363.95731) (xy 182.266872 -363.935362) (xy 182.188756 -363.905736)
			(xy 182.113864 -363.86871) (xy 182.042896 -363.824629) (xy 181.976513 -363.773903) (xy 181.915336 -363.717008)
			(xy 181.859935 -363.654474) (xy 181.810829 -363.586885) (xy 181.768475 -363.514872) (xy 181.733269 -363.439107)
			(xy 181.70554 -363.360298) (xy 181.685547 -363.279181) (xy 181.673475 -363.196513) (xy 181.669439 -363.113066)
			(xy 180.923438 -363.113066) (xy 180.922934 -363.155414) (xy 180.914883 -363.239728) (xy 180.898854 -363.322894)
			(xy 180.874993 -363.404161) (xy 180.843514 -363.482791) (xy 180.804703 -363.558072) (xy 180.758913 -363.629324)
			(xy 180.706557 -363.6959) (xy 180.648109 -363.757198) (xy 180.584099 -363.812663) (xy 180.515107 -363.861792)
			(xy 180.441757 -363.904141) (xy 180.364714 -363.939325) (xy 180.284675 -363.967027) (xy 180.202366 -363.986995)
			(xy 180.118531 -363.999048) (xy 180.03393 -364.003079) (xy 179.949329 -363.999048) (xy 179.865494 -363.986995)
			(xy 179.783185 -363.967027) (xy 179.703146 -363.939325) (xy 179.626103 -363.904141) (xy 179.552753 -363.861792)
			(xy 179.483761 -363.812663) (xy 179.419751 -363.757198) (xy 179.361303 -363.6959) (xy 179.308947 -363.629324)
			(xy 179.263157 -363.558072) (xy 179.224346 -363.482791) (xy 179.192867 -363.404161) (xy 179.169006 -363.322894)
			(xy 179.152977 -363.239728) (xy 179.144926 -363.155414) (xy 178.059513 -363.155414) (xy 178.079984 -363.200004)
			(xy 178.095477 -363.252503) (xy 178.103308 -363.306677) (xy 178.103784 -363.334046) (xy 178.103365 -363.361299)
			(xy 178.095601 -363.415251) (xy 178.080239 -363.467548) (xy 178.057591 -363.517127) (xy 178.028118 -363.562979)
			(xy 177.992419 -363.604169) (xy 177.951222 -363.63986) (xy 177.905366 -363.669325) (xy 177.855783 -363.691964)
			(xy 177.803482 -363.707316) (xy 177.74953 -363.71507) (xy 177.722276 -363.715554) (xy 177.69336 -363.714998)
			(xy 177.63619 -363.706279) (xy 177.580991 -363.68903) (xy 177.529029 -363.663645) (xy 177.481494 -363.630708)
			(xy 177.439477 -363.590971) (xy 177.421286 -363.568488) (xy 177.411389 -363.556683) (xy 177.386065 -363.539164)
			(xy 177.356672 -363.529988) (xy 177.32588 -363.529988) (xy 177.296487 -363.539164) (xy 177.271163 -363.556683)
			(xy 177.261266 -363.568488) (xy 177.243091 -363.590985) (xy 177.201068 -363.63072) (xy 177.15353 -363.663658)
			(xy 177.101566 -363.689044) (xy 177.046365 -363.706297) (xy 176.989193 -363.715022) (xy 176.960276 -363.715554)
			(xy 176.933026 -363.715045) (xy 176.879082 -363.707286) (xy 176.82679 -363.69193) (xy 176.777216 -363.66929)
			(xy 176.731368 -363.639825) (xy 176.690179 -363.604136) (xy 176.654488 -363.56295) (xy 176.625021 -363.517103)
			(xy 176.602377 -363.46753) (xy 176.587019 -363.41524) (xy 176.579257 -363.361296) (xy 176.578768 -363.334046)
			(xy 176.579244 -363.306676) (xy 176.587057 -363.252497) (xy 176.602543 -363.199993) (xy 176.625383 -363.150246)
			(xy 176.655107 -363.104279) (xy 176.672748 -363.083348) (xy 176.681937 -363.071986) (xy 176.694114 -363.04544)
			(xy 176.698293 -363.016535) (xy 176.694133 -362.987627) (xy 176.681975 -362.961073) (xy 176.672748 -362.949744)
			(xy 176.655151 -362.928775) (xy 176.625423 -362.882814) (xy 176.602574 -362.833074) (xy 176.587073 -362.780577)
			(xy 176.57924 -362.726403) (xy 176.579235 -362.671666) (xy 176.587058 -362.617491) (xy 176.60255 -362.564991)
			(xy 176.62539 -362.515247) (xy 176.65511 -362.46928) (xy 176.672748 -362.448348) (xy 176.681937 -362.436986)
			(xy 176.694114 -362.41044) (xy 176.698293 -362.381535) (xy 176.694133 -362.352627) (xy 176.681975 -362.326073)
			(xy 176.672748 -362.314744) (xy 176.655124 -362.2938) (xy 176.625408 -362.247831) (xy 176.602568 -362.198087)
			(xy 176.587074 -362.145589) (xy 176.579243 -362.091414) (xy 176.578768 -362.064046) (xy 176.578999 -362.044991)
			(xy 176.582819 -362.007073) (xy 176.586388 -361.988354) (xy 176.588705 -361.97488) (xy 176.586854 -361.947611)
			(xy 176.577837 -361.92181) (xy 176.562301 -361.899324) (xy 176.541357 -361.881763) (xy 176.516507 -361.870386)
			(xy 176.489529 -361.866007) (xy 176.462355 -361.868939) (xy 176.449482 -361.873546) (xy 176.427016 -361.882082)
			(xy 176.380475 -361.894068) (xy 176.332796 -361.900107) (xy 176.308766 -361.90047) (xy 176.27985 -361.899916)
			(xy 176.22268 -361.891196) (xy 176.167482 -361.873946) (xy 176.115519 -361.848561) (xy 176.067985 -361.815623)
			(xy 176.025967 -361.775887) (xy 176.007776 -361.753404) (xy 175.997879 -361.741599) (xy 175.972555 -361.72408)
			(xy 175.943162 -361.714904) (xy 175.91237 -361.714904) (xy 175.882977 -361.72408) (xy 175.857653 -361.741599)
			(xy 175.847756 -361.753404) (xy 175.829591 -361.775909) (xy 175.787566 -361.815643) (xy 175.740025 -361.848579)
			(xy 175.688059 -361.873964) (xy 175.632857 -361.891215) (xy 175.575684 -361.899938) (xy 175.546766 -361.90047)
			(xy 175.519511 -361.900077) (xy 175.465555 -361.892314) (xy 175.413254 -361.876952) (xy 175.363671 -361.854303)
			(xy 175.317816 -361.824827) (xy 175.276623 -361.789126) (xy 175.240929 -361.747926) (xy 175.211463 -361.702066)
			(xy 175.188823 -361.652479) (xy 175.173471 -361.600174) (xy 175.165718 -361.546218) (xy 175.165258 -361.518962)
			(xy 168.542716 -361.518962) (xy 168.542716 -364.273846) (xy 169.455338 -364.273846) (xy 169.455875 -364.24493)
			(xy 169.464598 -364.187759) (xy 169.481851 -364.13256) (xy 169.507239 -364.080597) (xy 169.54018 -364.033063)
			(xy 169.579919 -363.991046) (xy 169.602404 -363.972856) (xy 169.614161 -363.962907) (xy 169.631677 -363.937597)
			(xy 169.640856 -363.908218) (xy 169.640864 -363.877438) (xy 169.631702 -363.848054) (xy 169.614201 -363.822734)
			(xy 169.602404 -363.812836) (xy 169.579939 -363.794624) (xy 169.540202 -363.752608) (xy 169.507261 -363.705078)
			(xy 169.481869 -363.653121) (xy 169.464609 -363.597927) (xy 169.455876 -363.540761) (xy 169.455338 -363.511846)
			(xy 169.455822 -363.484476) (xy 169.463634 -363.430298) (xy 169.479118 -363.377794) (xy 169.501956 -363.328047)
			(xy 169.531678 -363.28208) (xy 169.549318 -363.261148) (xy 169.558509 -363.249787) (xy 169.57069 -363.223241)
			(xy 169.57487 -363.194335) (xy 169.570709 -363.165426) (xy 169.558547 -363.138872) (xy 169.549318 -363.127544)
			(xy 169.531723 -363.106575) (xy 169.501997 -363.060613) (xy 169.479149 -363.010873) (xy 169.46365 -362.958376)
			(xy 169.455817 -362.904203) (xy 169.455812 -362.849466) (xy 169.463635 -362.795292) (xy 169.479125 -362.742792)
			(xy 169.501963 -362.693048) (xy 169.531681 -362.647081) (xy 169.549318 -362.626148) (xy 169.558509 -362.614787)
			(xy 169.57069 -362.588241) (xy 169.57487 -362.559335) (xy 169.570709 -362.530426) (xy 169.558547 -362.503872)
			(xy 169.549318 -362.492544) (xy 169.531689 -362.471604) (xy 169.501975 -362.425634) (xy 169.479137 -362.375888)
			(xy 169.463643 -362.323389) (xy 169.455813 -362.269215) (xy 169.455338 -362.241846) (xy 169.455798 -362.214592)
			(xy 169.46355 -362.160639) (xy 169.478903 -362.108338) (xy 169.501543 -362.058755) (xy 169.531011 -362.012899)
			(xy 169.566705 -361.971705) (xy 169.607899 -361.936011) (xy 169.653755 -361.906543) (xy 169.703338 -361.883903)
			(xy 169.755639 -361.86855) (xy 169.809592 -361.860798) (xy 169.836846 -361.860338) (xy 169.864216 -361.860826)
			(xy 169.918394 -361.868637) (xy 169.970897 -361.884121) (xy 170.020645 -361.906958) (xy 170.066612 -361.936678)
			(xy 170.087544 -361.954318) (xy 170.098872 -361.963554) (xy 170.125429 -361.97573) (xy 170.154346 -361.979903)
			(xy 170.183263 -361.97573) (xy 170.20982 -361.963554) (xy 170.221148 -361.954318) (xy 170.242091 -361.936693)
			(xy 170.288061 -361.906978) (xy 170.337805 -361.884139) (xy 170.390304 -361.868645) (xy 170.444478 -361.860814)
			(xy 170.471846 -361.860338) (xy 170.500762 -361.860881) (xy 170.557933 -361.869602) (xy 170.613132 -361.886855)
			(xy 170.665094 -361.912242) (xy 170.712628 -361.945182) (xy 170.754646 -361.98492) (xy 170.772836 -362.007404)
			(xy 170.782733 -362.019209) (xy 170.808057 -362.036728) (xy 170.83745 -362.045904) (xy 170.868242 -362.045904)
			(xy 170.897635 -362.036728) (xy 170.922959 -362.019209) (xy 170.932856 -362.007404) (xy 170.951073 -361.984942)
			(xy 170.993087 -361.945206) (xy 171.040617 -361.912264) (xy 171.092573 -361.886872) (xy 171.147766 -361.869611)
			(xy 171.204932 -361.860876) (xy 171.233846 -361.860338) (xy 171.2611 -361.860735) (xy 171.315054 -361.868499)
			(xy 171.367353 -361.883862) (xy 171.416933 -361.906512) (xy 171.462786 -361.935988) (xy 171.503977 -361.971688)
			(xy 171.539668 -362.012888) (xy 171.569132 -362.058747) (xy 171.59177 -362.108333) (xy 171.60712 -362.160636)
			(xy 171.614871 -362.214591) (xy 171.615354 -362.241846) (xy 171.614867 -362.269216) (xy 171.607056 -362.323394)
			(xy 171.591573 -362.375898) (xy 171.568735 -362.425645) (xy 171.539014 -362.471612) (xy 171.521374 -362.492544)
			(xy 171.512095 -362.503839) (xy 171.499926 -362.530409) (xy 171.495763 -362.559335) (xy 171.499946 -362.588258)
			(xy 171.512133 -362.61482) (xy 171.521374 -362.626148) (xy 171.532804 -362.639864) (xy 171.542155 -362.650819)
			(xy 171.565655 -362.667446) (xy 171.592863 -362.676855) (xy 171.621615 -362.678296) (xy 171.649627 -362.671655)
			(xy 171.674673 -362.657461) (xy 171.694761 -362.63684) (xy 171.701968 -362.62437) (xy 171.716343 -362.59857)
			(xy 171.751735 -362.551293) (xy 171.793987 -362.510033) (xy 171.842091 -362.475774) (xy 171.894898 -362.449334)
			(xy 171.951148 -362.431345) (xy 172.009498 -362.422236) (xy 172.039026 -362.421678) (xy 172.066277 -362.422154)
			(xy 172.120225 -362.429913) (xy 172.172519 -362.445271) (xy 172.222095 -362.467914) (xy 172.267945 -362.497382)
			(xy 172.309134 -362.533074) (xy 172.344825 -362.574265) (xy 172.374292 -362.620115) (xy 172.396933 -362.669693)
			(xy 172.412289 -362.721987) (xy 172.420047 -362.775935) (xy 172.420534 -362.803186) (xy 172.420076 -362.830557)
			(xy 172.412259 -362.884737) (xy 172.396769 -362.937241) (xy 172.373925 -362.986987) (xy 172.344197 -363.032953)
			(xy 172.326554 -363.053884) (xy 172.317334 -363.065223) (xy 172.305161 -363.091777) (xy 172.300988 -363.120689)
			(xy 172.305155 -363.149602) (xy 172.317323 -363.176159) (xy 172.326554 -363.187488) (xy 172.344182 -363.208431)
			(xy 172.373909 -363.254397) (xy 172.396756 -363.304141) (xy 172.412254 -363.356642) (xy 172.420084 -363.410819)
			(xy 172.420086 -363.46556) (xy 172.412259 -363.519737) (xy 172.396763 -363.572239) (xy 172.373919 -363.621985)
			(xy 172.344194 -363.667952) (xy 172.326554 -363.688884) (xy 172.317334 -363.700223) (xy 172.305161 -363.726777)
			(xy 172.300988 -363.755689) (xy 172.305155 -363.784602) (xy 172.317323 -363.811159) (xy 172.326554 -363.822488)
			(xy 172.344194 -363.84342) (xy 172.373907 -363.889392) (xy 172.396744 -363.939139) (xy 172.412234 -363.99164)
			(xy 172.420061 -364.045817) (xy 172.420534 -364.073186) (xy 172.420009 -364.100436) (xy 172.412255 -364.154381)
			(xy 172.396903 -364.206673) (xy 172.377828 -364.248446) (xy 172.820838 -364.248446) (xy 172.821375 -364.21953)
			(xy 172.830098 -364.162359) (xy 172.847351 -364.10716) (xy 172.872739 -364.055197) (xy 172.90568 -364.007663)
			(xy 172.945419 -363.965646) (xy 172.967904 -363.947456) (xy 172.979661 -363.937507) (xy 172.997177 -363.912197)
			(xy 173.006356 -363.882818) (xy 173.006364 -363.852038) (xy 172.997202 -363.822654) (xy 172.979701 -363.797334)
			(xy 172.967904 -363.787436) (xy 172.945439 -363.769224) (xy 172.905702 -363.727208) (xy 172.872761 -363.679678)
			(xy 172.847369 -363.627721) (xy 172.830109 -363.572527) (xy 172.821376 -363.515361) (xy 172.820838 -363.486446)
			(xy 172.821322 -363.459076) (xy 172.829134 -363.404898) (xy 172.844618 -363.352394) (xy 172.867456 -363.302647)
			(xy 172.897178 -363.25668) (xy 172.914818 -363.235748) (xy 172.924009 -363.224387) (xy 172.93619 -363.197841)
			(xy 172.94037 -363.168935) (xy 172.936209 -363.140026) (xy 172.924047 -363.113472) (xy 172.914818 -363.102144)
			(xy 172.897223 -363.081175) (xy 172.867497 -363.035213) (xy 172.844649 -362.985473) (xy 172.82915 -362.932976)
			(xy 172.821317 -362.878803) (xy 172.821312 -362.824066) (xy 172.829135 -362.769892) (xy 172.844625 -362.717392)
			(xy 172.867463 -362.667648) (xy 172.897181 -362.621681) (xy 172.914818 -362.600748) (xy 172.924009 -362.589387)
			(xy 172.93619 -362.562841) (xy 172.94037 -362.533935) (xy 172.936209 -362.505026) (xy 172.924047 -362.478472)
			(xy 172.914818 -362.467144) (xy 172.897189 -362.446204) (xy 172.867475 -362.400234) (xy 172.844637 -362.350488)
			(xy 172.829143 -362.297989) (xy 172.821313 -362.243815) (xy 172.820838 -362.216446) (xy 172.821324 -362.189195)
			(xy 172.82908 -362.135247) (xy 172.844435 -362.082952) (xy 172.867077 -362.033375) (xy 172.896543 -361.987525)
			(xy 172.932234 -361.946334) (xy 172.973425 -361.910643) (xy 173.019275 -361.881177) (xy 173.068852 -361.858535)
			(xy 173.121147 -361.84318) (xy 173.175095 -361.835424) (xy 173.229597 -361.835424) (xy 173.283545 -361.84318)
			(xy 173.33584 -361.858535) (xy 173.385417 -361.881177) (xy 173.431267 -361.910643) (xy 173.472458 -361.946334)
			(xy 173.508149 -361.987525) (xy 173.537615 -362.033375) (xy 173.560257 -362.082952) (xy 173.575612 -362.135247)
			(xy 173.583368 -362.189195) (xy 173.583854 -362.216446) (xy 173.583367 -362.243816) (xy 173.575556 -362.297994)
			(xy 173.560073 -362.350498) (xy 173.537235 -362.400245) (xy 173.507514 -362.446212) (xy 173.489874 -362.467144)
			(xy 173.480595 -362.478439) (xy 173.468426 -362.505009) (xy 173.464263 -362.533935) (xy 173.468446 -362.562858)
			(xy 173.480633 -362.58942) (xy 173.489874 -362.600748) (xy 173.50756 -362.621644) (xy 173.537283 -362.667618)
			(xy 173.560125 -362.717371) (xy 173.575618 -362.769878) (xy 173.583442 -362.824062) (xy 173.583437 -362.878807)
			(xy 173.575603 -362.932989) (xy 173.560101 -362.985494) (xy 173.537249 -363.035242) (xy 173.507518 -363.081211)
			(xy 173.489874 -363.102144) (xy 173.480595 -363.113439) (xy 173.468426 -363.140009) (xy 173.464263 -363.168935)
			(xy 173.468446 -363.197858) (xy 173.480633 -363.22442) (xy 173.489874 -363.235748) (xy 173.507498 -363.256692)
			(xy 173.537213 -363.302661) (xy 173.560052 -363.352406) (xy 173.575547 -363.404904) (xy 173.583378 -363.459078)
			(xy 173.583854 -363.486446) (xy 173.583314 -363.515362) (xy 173.574592 -363.572533) (xy 173.55734 -363.627733)
			(xy 173.531952 -363.679695) (xy 173.499012 -363.727229) (xy 173.459273 -363.769246) (xy 173.436788 -363.787436)
			(xy 173.424939 -363.797285) (xy 173.407427 -363.822623) (xy 173.398258 -363.852028) (xy 173.398267 -363.882829)
			(xy 173.407452 -363.912229) (xy 173.424978 -363.937557) (xy 173.436788 -363.947456) (xy 173.459248 -363.965675)
			(xy 173.498985 -364.007688) (xy 173.531927 -364.055217) (xy 173.55732 -364.107173) (xy 173.574581 -364.162366)
			(xy 173.583316 -364.219532) (xy 173.583854 -364.248446) (xy 173.583368 -364.275697) (xy 173.575612 -364.329645)
			(xy 173.560257 -364.38194) (xy 173.537615 -364.431517) (xy 173.508149 -364.477367) (xy 173.472458 -364.518558)
			(xy 173.431267 -364.554249) (xy 173.385417 -364.583715) (xy 173.33584 -364.606357) (xy 173.283545 -364.621712)
			(xy 173.229597 -364.629468) (xy 173.175095 -364.629468) (xy 173.121147 -364.621712) (xy 173.068852 -364.606357)
			(xy 173.019275 -364.583715) (xy 172.973425 -364.554249) (xy 172.932234 -364.518558) (xy 172.896543 -364.477367)
			(xy 172.867077 -364.431517) (xy 172.844435 -364.38194) (xy 172.82908 -364.329645) (xy 172.821324 -364.275697)
			(xy 172.820838 -364.248446) (xy 172.377828 -364.248446) (xy 172.374265 -364.256248) (xy 172.344803 -364.302098)
			(xy 172.309116 -364.343287) (xy 172.26793 -364.378979) (xy 172.222084 -364.408446) (xy 172.172511 -364.431089)
			(xy 172.12022 -364.446446) (xy 172.066276 -364.454206) (xy 172.039026 -364.454694) (xy 172.008913 -364.454148)
			(xy 171.949431 -364.44471) (xy 171.892169 -364.426048) (xy 171.838548 -364.398626) (xy 171.789899 -364.363123)
			(xy 171.768262 -364.342172) (xy 171.757249 -364.331965) (xy 171.730832 -364.31774) (xy 171.701418 -364.311816)
			(xy 171.671553 -364.314704) (xy 171.64382 -364.326156) (xy 171.620618 -364.34518) (xy 171.603954 -364.370131)
			(xy 171.599098 -364.384336) (xy 171.590828 -364.410127) (xy 171.567947 -364.459219) (xy 171.538357 -364.504584)
			(xy 171.502652 -364.545312) (xy 171.461549 -364.580584) (xy 171.415873 -364.609692) (xy 171.366542 -364.632053)
			(xy 171.314545 -364.647216) (xy 171.260927 -364.654878) (xy 171.233846 -364.655354) (xy 171.204929 -364.65482)
			(xy 171.147758 -364.646097) (xy 171.092559 -364.628843) (xy 171.040597 -364.603455) (xy 170.993063 -364.570513)
			(xy 170.951046 -364.530773) (xy 170.932856 -364.508288) (xy 170.922959 -364.496483) (xy 170.897635 -364.478964)
			(xy 170.868242 -364.469788) (xy 170.83745 -364.469788) (xy 170.808057 -364.478964) (xy 170.782733 -364.496483)
			(xy 170.772836 -364.508288) (xy 170.754622 -364.530752) (xy 170.712607 -364.570489) (xy 170.665077 -364.60343)
			(xy 170.61312 -364.628822) (xy 170.557927 -364.646083) (xy 170.500761 -364.654816) (xy 170.471846 -364.655354)
			(xy 170.444476 -364.654872) (xy 170.390297 -364.64706) (xy 170.337794 -364.631575) (xy 170.288047 -364.608737)
			(xy 170.24208 -364.579014) (xy 170.221148 -364.561374) (xy 170.20982 -364.552138) (xy 170.183263 -364.539962)
			(xy 170.154346 -364.535789) (xy 170.125429 -364.539962) (xy 170.098872 -364.552138) (xy 170.087544 -364.561374)
			(xy 170.066603 -364.579002) (xy 170.020633 -364.608716) (xy 169.970888 -364.631555) (xy 169.918389 -364.647048)
			(xy 169.864215 -364.654879) (xy 169.836846 -364.655354) (xy 169.809598 -364.654779) (xy 169.755656 -364.64703)
			(xy 169.703366 -364.631683) (xy 169.653792 -364.609051) (xy 169.607943 -364.579594) (xy 169.566754 -364.543911)
			(xy 169.531062 -364.50273) (xy 169.501593 -364.456889) (xy 169.478949 -364.407321) (xy 169.46359 -364.355034)
			(xy 169.455827 -364.301094) (xy 169.455338 -364.273846) (xy 168.542716 -364.273846) (xy 168.542716 -366.491012)
			(xy 170.70832 -368.65687) (xy 170.70832 -369.132104) (xy 171.117768 -369.541298) (xy 171.138547 -369.562913)
			(xy 171.173783 -369.611418) (xy 171.201 -369.664837) (xy 171.219529 -369.721855) (xy 171.228913 -369.78107)
			(xy 171.229528 -369.811046) (xy 171.229528 -373.258842) (xy 171.28998 -373.319548) (xy 188.0616 -373.319548)
		)
		(stroke
			(width 0)
			(type solid)
		)
		(fill yes)
		(layer "In4.Cu")
		(net "GND")
	)
	(gr_poly
		(pts
			(xy 304.278284 -374.892824) (xy 304.278284 -370.37264) (xy 304.259733 -370.354632) (xy 304.227636 -370.314104)
			(xy 304.201903 -370.269264) (xy 304.183103 -370.221104) (xy 304.171653 -370.170689) (xy 304.167804 -370.119133)
			(xy 304.171643 -370.067576) (xy 304.183084 -370.017159) (xy 304.201874 -369.968996) (xy 304.227599 -369.924151)
			(xy 304.259688 -369.883616) (xy 304.278284 -369.865656) (xy 304.278284 -369.311936) (xy 304.013108 -366.446816)
			(xy 304.005742 -366.436148) (xy 303.99191 -366.41461) (xy 303.970045 -366.368329) (xy 303.955215 -366.319339)
			(xy 303.94774 -366.268701) (xy 303.947322 -366.243108) (xy 303.947687 -366.219692) (xy 303.953952 -366.173282)
			(xy 303.96641 -366.128137) (xy 303.975262 -366.106456) (xy 303.980342 -366.094518) (xy 302.71085 -352.382074)
			(xy 302.544734 -352.215958) (xy 302.544734 -350.587564) (xy 302.014636 -344.86215) (xy 302.012694 -344.839404)
			(xy 302.010662 -344.793793) (xy 302.010572 -344.770964) (xy 302.010572 -342.367362) (xy 301.176436 -341.533226)
			(xy 290.580064 -341.533226) (xy 290.555172 -341.558372) (xy 286.001714 -343.678764) (xy 284.937778 -344.7427)
			(xy 286.410396 -344.7427) (xy 286.410396 -344.658004) (xy 286.418447 -344.57369) (xy 286.434476 -344.490524)
			(xy 286.458337 -344.409257) (xy 286.489816 -344.330627) (xy 286.528627 -344.255346) (xy 286.574417 -344.184094)
			(xy 286.626773 -344.117518) (xy 286.685221 -344.05622) (xy 286.749231 -344.000755) (xy 286.818223 -343.951626)
			(xy 286.891573 -343.909277) (xy 286.968616 -343.874093) (xy 287.048655 -343.846391) (xy 287.130964 -343.826423)
			(xy 287.214799 -343.81437) (xy 287.2994 -343.81034) (xy 287.384001 -343.81437) (xy 287.467836 -343.826423)
			(xy 287.550145 -343.846391) (xy 287.630184 -343.874093) (xy 287.707227 -343.909277) (xy 287.780577 -343.951626)
			(xy 287.849569 -344.000755) (xy 287.913579 -344.05622) (xy 287.972027 -344.117518) (xy 288.024383 -344.184094)
			(xy 288.070173 -344.255346) (xy 288.108984 -344.330627) (xy 288.140463 -344.409257) (xy 288.164324 -344.490524)
			(xy 288.180353 -344.57369) (xy 288.188404 -344.658004) (xy 288.188908 -344.700352) (xy 288.188404 -344.7427)
			(xy 292.607996 -344.7427) (xy 292.607996 -344.658004) (xy 292.616047 -344.57369) (xy 292.632076 -344.490524)
			(xy 292.655937 -344.409257) (xy 292.687416 -344.330627) (xy 292.726227 -344.255346) (xy 292.772017 -344.184094)
			(xy 292.824373 -344.117518) (xy 292.882821 -344.05622) (xy 292.946831 -344.000755) (xy 293.015823 -343.951626)
			(xy 293.089173 -343.909277) (xy 293.166216 -343.874093) (xy 293.246255 -343.846391) (xy 293.328564 -343.826423)
			(xy 293.412399 -343.81437) (xy 293.497 -343.81034) (xy 293.581601 -343.81437) (xy 293.665436 -343.826423)
			(xy 293.747745 -343.846391) (xy 293.827784 -343.874093) (xy 293.904827 -343.909277) (xy 293.978177 -343.951626)
			(xy 294.047169 -344.000755) (xy 294.111179 -344.05622) (xy 294.169627 -344.117518) (xy 294.221983 -344.184094)
			(xy 294.267773 -344.255346) (xy 294.306584 -344.330627) (xy 294.338063 -344.409257) (xy 294.361924 -344.490524)
			(xy 294.377953 -344.57369) (xy 294.386004 -344.658004) (xy 294.386508 -344.700352) (xy 294.386004 -344.7427)
			(xy 298.805596 -344.7427) (xy 298.805596 -344.658004) (xy 298.813647 -344.57369) (xy 298.829676 -344.490524)
			(xy 298.853537 -344.409257) (xy 298.885016 -344.330627) (xy 298.923827 -344.255346) (xy 298.969617 -344.184094)
			(xy 299.021973 -344.117518) (xy 299.080421 -344.05622) (xy 299.144431 -344.000755) (xy 299.213423 -343.951626)
			(xy 299.286773 -343.909277) (xy 299.363816 -343.874093) (xy 299.443855 -343.846391) (xy 299.526164 -343.826423)
			(xy 299.609999 -343.81437) (xy 299.6946 -343.81034) (xy 299.779201 -343.81437) (xy 299.863036 -343.826423)
			(xy 299.945345 -343.846391) (xy 300.025384 -343.874093) (xy 300.102427 -343.909277) (xy 300.175777 -343.951626)
			(xy 300.244769 -344.000755) (xy 300.308779 -344.05622) (xy 300.367227 -344.117518) (xy 300.419583 -344.184094)
			(xy 300.465373 -344.255346) (xy 300.504184 -344.330627) (xy 300.535663 -344.409257) (xy 300.559524 -344.490524)
			(xy 300.575553 -344.57369) (xy 300.583604 -344.658004) (xy 300.584108 -344.700352) (xy 300.583604 -344.7427)
			(xy 300.575553 -344.827014) (xy 300.559524 -344.91018) (xy 300.535663 -344.991447) (xy 300.504184 -345.070077)
			(xy 300.465373 -345.145358) (xy 300.419583 -345.21661) (xy 300.367227 -345.283186) (xy 300.308779 -345.344484)
			(xy 300.244769 -345.399949) (xy 300.175777 -345.449078) (xy 300.102427 -345.491427) (xy 300.025384 -345.526611)
			(xy 299.945345 -345.554313) (xy 299.863036 -345.574281) (xy 299.779201 -345.586334) (xy 299.6946 -345.590365)
			(xy 299.609999 -345.586334) (xy 299.526164 -345.574281) (xy 299.443855 -345.554313) (xy 299.363816 -345.526611)
			(xy 299.286773 -345.491427) (xy 299.213423 -345.449078) (xy 299.144431 -345.399949) (xy 299.080421 -345.344484)
			(xy 299.021973 -345.283186) (xy 298.969617 -345.21661) (xy 298.923827 -345.145358) (xy 298.885016 -345.070077)
			(xy 298.853537 -344.991447) (xy 298.829676 -344.91018) (xy 298.813647 -344.827014) (xy 298.805596 -344.7427)
			(xy 294.386004 -344.7427) (xy 294.377953 -344.827014) (xy 294.361924 -344.91018) (xy 294.338063 -344.991447)
			(xy 294.306584 -345.070077) (xy 294.267773 -345.145358) (xy 294.221983 -345.21661) (xy 294.169627 -345.283186)
			(xy 294.111179 -345.344484) (xy 294.047169 -345.399949) (xy 293.978177 -345.449078) (xy 293.904827 -345.491427)
			(xy 293.827784 -345.526611) (xy 293.747745 -345.554313) (xy 293.665436 -345.574281) (xy 293.581601 -345.586334)
			(xy 293.497 -345.590365) (xy 293.412399 -345.586334) (xy 293.328564 -345.574281) (xy 293.246255 -345.554313)
			(xy 293.166216 -345.526611) (xy 293.089173 -345.491427) (xy 293.015823 -345.449078) (xy 292.946831 -345.399949)
			(xy 292.882821 -345.344484) (xy 292.824373 -345.283186) (xy 292.772017 -345.21661) (xy 292.726227 -345.145358)
			(xy 292.687416 -345.070077) (xy 292.655937 -344.991447) (xy 292.632076 -344.91018) (xy 292.616047 -344.827014)
			(xy 292.607996 -344.7427) (xy 288.188404 -344.7427) (xy 288.180353 -344.827014) (xy 288.164324 -344.91018)
			(xy 288.140463 -344.991447) (xy 288.108984 -345.070077) (xy 288.070173 -345.145358) (xy 288.024383 -345.21661)
			(xy 287.972027 -345.283186) (xy 287.913579 -345.344484) (xy 287.849569 -345.399949) (xy 287.780577 -345.449078)
			(xy 287.707227 -345.491427) (xy 287.630184 -345.526611) (xy 287.550145 -345.554313) (xy 287.467836 -345.574281)
			(xy 287.384001 -345.586334) (xy 287.2994 -345.590365) (xy 287.214799 -345.586334) (xy 287.130964 -345.574281)
			(xy 287.048655 -345.554313) (xy 286.968616 -345.526611) (xy 286.891573 -345.491427) (xy 286.818223 -345.449078)
			(xy 286.749231 -345.399949) (xy 286.685221 -345.344484) (xy 286.626773 -345.283186) (xy 286.574417 -345.21661)
			(xy 286.528627 -345.145358) (xy 286.489816 -345.070077) (xy 286.458337 -344.991447) (xy 286.434476 -344.91018)
			(xy 286.418447 -344.827014) (xy 286.410396 -344.7427) (xy 284.937778 -344.7427) (xy 283.004514 -346.675964)
			(xy 283.004514 -351.8408) (xy 285.286958 -351.8408) (xy 285.28741 -351.813429) (xy 285.295229 -351.759249)
			(xy 285.310721 -351.706745) (xy 285.333566 -351.656998) (xy 285.363295 -351.611033) (xy 285.380938 -351.590102)
			(xy 285.390172 -351.578773) (xy 285.402345 -351.552215) (xy 285.406515 -351.5233) (xy 285.402345 -351.494385)
			(xy 285.390172 -351.467827) (xy 285.380938 -351.456498) (xy 285.363297 -351.435565) (xy 285.333571 -351.389598)
			(xy 285.310725 -351.339852) (xy 285.295228 -351.28735) (xy 285.2874 -351.233171) (xy 285.2874 -351.178429)
			(xy 285.295228 -351.12425) (xy 285.310725 -351.071748) (xy 285.333571 -351.022002) (xy 285.363297 -350.976035)
			(xy 285.380938 -350.955102) (xy 285.390172 -350.943773) (xy 285.402345 -350.917215) (xy 285.406515 -350.8883)
			(xy 285.402345 -350.859385) (xy 285.390172 -350.832827) (xy 285.380938 -350.821498) (xy 285.363297 -350.800565)
			(xy 285.333571 -350.754598) (xy 285.310725 -350.704852) (xy 285.295228 -350.65235) (xy 285.2874 -350.598171)
			(xy 285.2874 -350.543429) (xy 285.295228 -350.48925) (xy 285.310725 -350.436748) (xy 285.333571 -350.387002)
			(xy 285.363297 -350.341035) (xy 285.380938 -350.320102) (xy 285.390172 -350.308773) (xy 285.402345 -350.282215)
			(xy 285.406515 -350.2533) (xy 285.402345 -350.224385) (xy 285.390172 -350.197827) (xy 285.380938 -350.186498)
			(xy 285.363297 -350.165565) (xy 285.333571 -350.119598) (xy 285.310725 -350.069852) (xy 285.295228 -350.01735)
			(xy 285.2874 -349.963171) (xy 285.2874 -349.908429) (xy 285.295228 -349.85425) (xy 285.310725 -349.801748)
			(xy 285.333571 -349.752002) (xy 285.363297 -349.706035) (xy 285.380938 -349.685102) (xy 285.390172 -349.673773)
			(xy 285.402345 -349.647215) (xy 285.406515 -349.6183) (xy 285.402345 -349.589385) (xy 285.390172 -349.562827)
			(xy 285.380938 -349.551498) (xy 285.363297 -349.530565) (xy 285.333571 -349.484598) (xy 285.310725 -349.434852)
			(xy 285.295228 -349.38235) (xy 285.2874 -349.328171) (xy 285.2874 -349.273429) (xy 285.295228 -349.21925)
			(xy 285.310725 -349.166748) (xy 285.333571 -349.117002) (xy 285.363297 -349.071035) (xy 285.380938 -349.050102)
			(xy 285.390172 -349.038773) (xy 285.402345 -349.012215) (xy 285.406515 -348.9833) (xy 285.402345 -348.954385)
			(xy 285.390172 -348.927827) (xy 285.380938 -348.916498) (xy 285.363297 -348.895565) (xy 285.333571 -348.849598)
			(xy 285.310725 -348.799852) (xy 285.295228 -348.74735) (xy 285.2874 -348.693171) (xy 285.2874 -348.638429)
			(xy 285.295228 -348.58425) (xy 285.310725 -348.531748) (xy 285.333571 -348.482002) (xy 285.363297 -348.436035)
			(xy 285.380938 -348.415102) (xy 285.390172 -348.403773) (xy 285.402345 -348.377215) (xy 285.406515 -348.3483)
			(xy 285.402345 -348.319385) (xy 285.390172 -348.292827) (xy 285.380938 -348.281498) (xy 285.36329 -348.260573)
			(xy 285.333579 -348.214599) (xy 285.310744 -348.164849) (xy 285.295255 -348.112347) (xy 285.28743 -348.05817)
			(xy 285.286958 -348.0308) (xy 285.287478 -348.00355) (xy 285.295233 -347.949606) (xy 285.310587 -347.897314)
			(xy 285.333225 -347.847739) (xy 285.362689 -347.80189) (xy 285.398376 -347.7607) (xy 285.439563 -347.725009)
			(xy 285.485409 -347.695542) (xy 285.534982 -347.672899) (xy 285.587272 -347.657541) (xy 285.641216 -347.64978)
			(xy 285.668466 -347.649292) (xy 285.695835 -347.64978) (xy 285.750013 -347.657593) (xy 285.802516 -347.673077)
			(xy 285.852263 -347.695914) (xy 285.898231 -347.725633) (xy 285.919164 -347.743272) (xy 285.930492 -347.752508)
			(xy 285.957049 -347.764684) (xy 285.985966 -347.768857) (xy 286.014883 -347.764684) (xy 286.04144 -347.752508)
			(xy 286.052768 -347.743272) (xy 286.073698 -347.72563) (xy 286.119672 -347.69592) (xy 286.16942 -347.673085)
			(xy 286.221921 -347.657594) (xy 286.276097 -347.649766) (xy 286.303466 -347.649292) (xy 286.331506 -347.649802)
			(xy 286.386983 -347.657998) (xy 286.440665 -347.67422) (xy 286.491398 -347.698118) (xy 286.53809 -347.729179)
			(xy 286.559244 -347.74759) (xy 286.570686 -347.757235) (xy 286.597729 -347.770015) (xy 286.627316 -347.774401)
			(xy 286.656903 -347.770015) (xy 286.683946 -347.757235) (xy 286.695388 -347.74759) (xy 286.71379 -347.731553)
			(xy 286.753943 -347.703798) (xy 286.797303 -347.68138) (xy 286.820102 -347.67266) (xy 286.833437 -347.667262)
			(xy 286.856596 -347.650215) (xy 286.874094 -347.627394) (xy 286.884546 -347.600604) (xy 286.887126 -347.571964)
			(xy 286.88163 -347.543737) (xy 286.868493 -347.518156) (xy 286.848753 -347.497245) (xy 286.836612 -347.489526)
			(xy 286.799538 -347.467197) (xy 286.729339 -347.416569) (xy 286.664236 -347.359536) (xy 286.604811 -347.296608)
			(xy 286.551597 -347.228348) (xy 286.505069 -347.155367) (xy 286.465642 -347.078317) (xy 286.433671 -346.997887)
			(xy 286.40944 -346.914797) (xy 286.393166 -346.829789) (xy 286.384995 -346.743624) (xy 286.384492 -346.700348)
			(xy 286.38498 -346.658072) (xy 286.392782 -346.57388) (xy 286.408318 -346.490767) (xy 286.431457 -346.409443)
			(xy 286.462001 -346.3306) (xy 286.499689 -346.254912) (xy 286.5442 -346.183024) (xy 286.595154 -346.11555)
			(xy 286.652117 -346.053065) (xy 286.714602 -345.996102) (xy 286.782076 -345.945148) (xy 286.853964 -345.900637)
			(xy 286.929652 -345.862949) (xy 287.008495 -345.832405) (xy 287.089819 -345.809266) (xy 287.172932 -345.79373)
			(xy 287.257124 -345.785928) (xy 287.341676 -345.785928) (xy 287.425868 -345.79373) (xy 287.508981 -345.809266)
			(xy 287.590305 -345.832405) (xy 287.669148 -345.862949) (xy 287.744836 -345.900637) (xy 287.816724 -345.945148)
			(xy 287.884198 -345.996102) (xy 287.946683 -346.053065) (xy 288.003646 -346.11555) (xy 288.0546 -346.183024)
			(xy 288.099111 -346.254912) (xy 288.136799 -346.3306) (xy 288.167343 -346.409443) (xy 288.190482 -346.490767)
			(xy 288.206018 -346.57388) (xy 288.21382 -346.658072) (xy 288.214308 -346.700348) (xy 292.581589 -346.700348)
			(xy 292.585611 -346.614628) (xy 292.597642 -346.52966) (xy 292.617578 -346.446193) (xy 292.645241 -346.364959)
			(xy 292.68039 -346.286673) (xy 292.722716 -346.212022) (xy 292.771845 -346.141663) (xy 292.827348 -346.076213)
			(xy 292.888735 -346.016249) (xy 292.955468 -345.962296) (xy 293.02696 -345.914829) (xy 293.102582 -345.874265)
			(xy 293.181671 -345.840961) (xy 293.263531 -345.815209) (xy 293.347442 -345.797236) (xy 293.432668 -345.7872)
			(xy 293.51846 -345.785188) (xy 293.604062 -345.791219) (xy 293.688724 -345.805239) (xy 293.771701 -345.827125)
			(xy 293.852264 -345.856686) (xy 293.929704 -345.89366) (xy 294.003343 -345.937724) (xy 294.072531 -345.98849)
			(xy 294.136662 -346.045511) (xy 294.195171 -346.108287) (xy 294.247544 -346.176267) (xy 294.293322 -346.248852)
			(xy 294.332102 -346.325404) (xy 294.363543 -346.405252) (xy 294.387369 -346.487693) (xy 294.40337 -346.572003)
			(xy 294.411405 -346.657441) (xy 294.411908 -346.700348) (xy 298.779189 -346.700348) (xy 298.783211 -346.614628)
			(xy 298.795242 -346.52966) (xy 298.815178 -346.446193) (xy 298.842841 -346.364959) (xy 298.87799 -346.286673)
			(xy 298.920316 -346.212022) (xy 298.969445 -346.141663) (xy 299.024948 -346.076213) (xy 299.086335 -346.016249)
			(xy 299.153068 -345.962296) (xy 299.22456 -345.914829) (xy 299.300182 -345.874265) (xy 299.379271 -345.840961)
			(xy 299.461131 -345.815209) (xy 299.545042 -345.797236) (xy 299.630268 -345.7872) (xy 299.71606 -345.785188)
			(xy 299.801662 -345.791219) (xy 299.886324 -345.805239) (xy 299.969301 -345.827125) (xy 300.049864 -345.856686)
			(xy 300.127304 -345.89366) (xy 300.200943 -345.937724) (xy 300.270131 -345.98849) (xy 300.334262 -346.045511)
			(xy 300.392771 -346.108287) (xy 300.445144 -346.176267) (xy 300.490922 -346.248852) (xy 300.529702 -346.325404)
			(xy 300.561143 -346.405252) (xy 300.584969 -346.487693) (xy 300.60097 -346.572003) (xy 300.609005 -346.657441)
			(xy 300.609508 -346.700348) (xy 300.609005 -346.743255) (xy 300.60097 -346.828693) (xy 300.584969 -346.913003)
			(xy 300.561143 -346.995444) (xy 300.529702 -347.075292) (xy 300.490922 -347.151844) (xy 300.445144 -347.224429)
			(xy 300.392771 -347.292409) (xy 300.334262 -347.355185) (xy 300.270131 -347.412206) (xy 300.200943 -347.462972)
			(xy 300.127304 -347.507036) (xy 300.049864 -347.54401) (xy 299.969301 -347.573571) (xy 299.886324 -347.595457)
			(xy 299.801662 -347.609477) (xy 299.71606 -347.615508) (xy 299.630268 -347.613496) (xy 299.545042 -347.60346)
			(xy 299.461131 -347.585487) (xy 299.379271 -347.559735) (xy 299.300182 -347.526431) (xy 299.22456 -347.485867)
			(xy 299.153068 -347.4384) (xy 299.086335 -347.384447) (xy 299.024948 -347.324483) (xy 298.969445 -347.259033)
			(xy 298.920316 -347.188674) (xy 298.87799 -347.114023) (xy 298.842841 -347.035737) (xy 298.815178 -346.954503)
			(xy 298.795242 -346.871036) (xy 298.783211 -346.786068) (xy 298.779189 -346.700348) (xy 294.411908 -346.700348)
			(xy 294.411405 -346.743255) (xy 294.40337 -346.828693) (xy 294.387369 -346.913003) (xy 294.363543 -346.995444)
			(xy 294.332102 -347.075292) (xy 294.293322 -347.151844) (xy 294.247544 -347.224429) (xy 294.195171 -347.292409)
			(xy 294.136662 -347.355185) (xy 294.072531 -347.412206) (xy 294.003343 -347.462972) (xy 293.929704 -347.507036)
			(xy 293.852264 -347.54401) (xy 293.771701 -347.573571) (xy 293.688724 -347.595457) (xy 293.604062 -347.609477)
			(xy 293.51846 -347.615508) (xy 293.432668 -347.613496) (xy 293.347442 -347.60346) (xy 293.263531 -347.585487)
			(xy 293.181671 -347.559735) (xy 293.102582 -347.526431) (xy 293.02696 -347.485867) (xy 292.955468 -347.4384)
			(xy 292.888735 -347.384447) (xy 292.827348 -347.324483) (xy 292.771845 -347.259033) (xy 292.722716 -347.188674)
			(xy 292.68039 -347.114023) (xy 292.645241 -347.035737) (xy 292.617578 -346.954503) (xy 292.597642 -346.871036)
			(xy 292.585611 -346.786068) (xy 292.581589 -346.700348) (xy 288.214308 -346.700348) (xy 288.21379 -346.742119)
			(xy 288.206161 -346.825312) (xy 288.190979 -346.907463) (xy 288.168372 -346.987888) (xy 288.138526 -347.065917)
			(xy 288.101692 -347.140901) (xy 288.058175 -347.212214) (xy 288.008338 -347.279263) (xy 287.952597 -347.34149)
			(xy 287.891415 -347.398376) (xy 287.825301 -347.449448) (xy 287.754807 -347.49428) (xy 287.68052 -347.532499)
			(xy 287.603058 -347.563786) (xy 287.523066 -347.587882) (xy 287.44121 -347.604585) (xy 287.358173 -347.613756)
			(xy 287.316418 -347.615002) (xy 287.302046 -347.615754) (xy 287.274565 -347.624259) (xy 287.250547 -347.640089)
			(xy 287.231895 -347.661989) (xy 287.22009 -347.688222) (xy 287.216068 -347.716706) (xy 287.220149 -347.745181)
			(xy 287.232008 -347.771389) (xy 287.24098 -347.782642) (xy 287.258186 -347.803491) (xy 287.287192 -347.849105)
			(xy 287.309471 -347.898356) (xy 287.324576 -347.950258) (xy 287.332204 -348.003772) (xy 287.332674 -348.0308)
			(xy 287.332214 -348.058171) (xy 287.324396 -348.11235) (xy 287.308906 -348.164854) (xy 287.286062 -348.2146)
			(xy 287.256336 -348.260567) (xy 287.238694 -348.281498) (xy 287.229458 -348.292825) (xy 287.217281 -348.319383)
			(xy 287.213109 -348.3483) (xy 287.217281 -348.377217) (xy 287.229458 -348.403775) (xy 287.238694 -348.415102)
			(xy 287.256334 -348.436035) (xy 287.286057 -348.482003) (xy 287.308901 -348.53175) (xy 287.324396 -348.584252)
			(xy 287.332225 -348.63843) (xy 287.332225 -348.69317) (xy 287.324396 -348.747348) (xy 287.308901 -348.79985)
			(xy 287.286057 -348.849597) (xy 287.256334 -348.895565) (xy 287.238694 -348.916498) (xy 287.229458 -348.927825)
			(xy 287.217281 -348.954383) (xy 287.213109 -348.9833) (xy 287.217281 -349.012217) (xy 287.229458 -349.038775)
			(xy 287.238694 -349.050102) (xy 287.256334 -349.071035) (xy 287.286057 -349.117003) (xy 287.308901 -349.16675)
			(xy 287.324396 -349.219252) (xy 287.332225 -349.27343) (xy 287.332225 -349.32817) (xy 287.324396 -349.382348)
			(xy 287.308901 -349.43485) (xy 287.286057 -349.484597) (xy 287.256334 -349.530565) (xy 287.238694 -349.551498)
			(xy 287.229458 -349.562825) (xy 287.217281 -349.589383) (xy 287.213109 -349.6183) (xy 287.217281 -349.647217)
			(xy 287.229458 -349.673775) (xy 287.238694 -349.685102) (xy 287.256334 -349.706035) (xy 287.286057 -349.752003)
			(xy 287.308901 -349.80175) (xy 287.324396 -349.854252) (xy 287.332225 -349.90843) (xy 287.332225 -349.96317)
			(xy 287.324396 -350.017348) (xy 287.308901 -350.06985) (xy 287.286057 -350.119597) (xy 287.256334 -350.165565)
			(xy 287.238694 -350.186498) (xy 287.229458 -350.197825) (xy 287.217281 -350.224383) (xy 287.213109 -350.2533)
			(xy 287.217281 -350.282217) (xy 287.229458 -350.308775) (xy 287.238694 -350.320102) (xy 287.256334 -350.341035)
			(xy 287.286057 -350.387003) (xy 287.308901 -350.43675) (xy 287.324396 -350.489252) (xy 287.332225 -350.54343)
			(xy 287.332225 -350.59817) (xy 287.324396 -350.652348) (xy 287.308901 -350.70485) (xy 287.286057 -350.754597)
			(xy 287.256334 -350.800565) (xy 287.238694 -350.821498) (xy 287.229458 -350.832825) (xy 287.217281 -350.859383)
			(xy 287.213109 -350.8883) (xy 287.217281 -350.917217) (xy 287.229458 -350.943775) (xy 287.238694 -350.955102)
			(xy 287.256334 -350.976035) (xy 287.286057 -351.022003) (xy 287.308901 -351.07175) (xy 287.324396 -351.124252)
			(xy 287.332225 -351.17843) (xy 287.332225 -351.23317) (xy 287.324396 -351.287348) (xy 287.308901 -351.33985)
			(xy 287.286057 -351.389597) (xy 287.256334 -351.435565) (xy 287.238694 -351.456498) (xy 287.229458 -351.467825)
			(xy 287.217281 -351.494383) (xy 287.213109 -351.5233) (xy 287.217281 -351.552217) (xy 287.229458 -351.578775)
			(xy 287.238694 -351.590102) (xy 287.256347 -351.611023) (xy 287.286057 -351.656999) (xy 287.30889 -351.706749)
			(xy 287.324378 -351.759252) (xy 287.332202 -351.81343) (xy 287.332674 -351.8408) (xy 290.25723 -351.8408)
			(xy 290.257689 -351.813429) (xy 290.265507 -351.75925) (xy 290.280998 -351.706746) (xy 290.303841 -351.656999)
			(xy 290.333568 -351.611033) (xy 290.35121 -351.590102) (xy 290.360446 -351.578774) (xy 290.372622 -351.552217)
			(xy 290.376794 -351.5233) (xy 290.372622 -351.494383) (xy 290.360446 -351.467826) (xy 290.35121 -351.456498)
			(xy 290.33357 -351.435565) (xy 290.303847 -351.389597) (xy 290.281002 -351.33985) (xy 290.265507 -351.287349)
			(xy 290.257678 -351.23317) (xy 290.257678 -351.17843) (xy 290.265507 -351.124251) (xy 290.281002 -351.07175)
			(xy 290.303847 -351.022003) (xy 290.33357 -350.976035) (xy 290.35121 -350.955102) (xy 290.360446 -350.943774)
			(xy 290.372622 -350.917217) (xy 290.376794 -350.8883) (xy 290.372622 -350.859383) (xy 290.360446 -350.832826)
			(xy 290.35121 -350.821498) (xy 290.33357 -350.800565) (xy 290.303847 -350.754597) (xy 290.281002 -350.70485)
			(xy 290.265507 -350.652349) (xy 290.257678 -350.59817) (xy 290.257678 -350.54343) (xy 290.265507 -350.489251)
			(xy 290.281002 -350.43675) (xy 290.303847 -350.387003) (xy 290.33357 -350.341035) (xy 290.35121 -350.320102)
			(xy 290.360446 -350.308774) (xy 290.372622 -350.282217) (xy 290.376794 -350.2533) (xy 290.372622 -350.224383)
			(xy 290.360446 -350.197826) (xy 290.35121 -350.186498) (xy 290.33357 -350.165565) (xy 290.303847 -350.119597)
			(xy 290.281002 -350.06985) (xy 290.265507 -350.017349) (xy 290.257678 -349.96317) (xy 290.257678 -349.90843)
			(xy 290.265507 -349.854251) (xy 290.281002 -349.80175) (xy 290.303847 -349.752003) (xy 290.33357 -349.706035)
			(xy 290.35121 -349.685102) (xy 290.360446 -349.673774) (xy 290.372622 -349.647217) (xy 290.376794 -349.6183)
			(xy 290.372622 -349.589383) (xy 290.360446 -349.562826) (xy 290.35121 -349.551498) (xy 290.33357 -349.530565)
			(xy 290.303847 -349.484597) (xy 290.281002 -349.43485) (xy 290.265507 -349.382349) (xy 290.257678 -349.32817)
			(xy 290.257678 -349.27343) (xy 290.265507 -349.219251) (xy 290.281002 -349.16675) (xy 290.303847 -349.117003)
			(xy 290.33357 -349.071035) (xy 290.35121 -349.050102) (xy 290.360446 -349.038774) (xy 290.372622 -349.012217)
			(xy 290.376794 -348.9833) (xy 290.372622 -348.954383) (xy 290.360446 -348.927826) (xy 290.35121 -348.916498)
			(xy 290.33357 -348.895565) (xy 290.303847 -348.849597) (xy 290.281002 -348.79985) (xy 290.265507 -348.747349)
			(xy 290.257678 -348.69317) (xy 290.257678 -348.63843) (xy 290.265507 -348.584251) (xy 290.281002 -348.53175)
			(xy 290.303847 -348.482003) (xy 290.33357 -348.436035) (xy 290.35121 -348.415102) (xy 290.360446 -348.403774)
			(xy 290.372622 -348.377217) (xy 290.376794 -348.3483) (xy 290.372622 -348.319383) (xy 290.360446 -348.292826)
			(xy 290.35121 -348.281498) (xy 290.333558 -348.260576) (xy 290.303848 -348.214601) (xy 290.281014 -348.164851)
			(xy 290.265526 -348.112348) (xy 290.257702 -348.05817) (xy 290.25723 -348.0308) (xy 290.257655 -348.003545)
			(xy 290.265413 -347.949591) (xy 290.280771 -347.89729) (xy 290.303417 -347.847708) (xy 290.332888 -347.801853)
			(xy 290.368586 -347.760659) (xy 290.409783 -347.724965) (xy 290.455641 -347.695498) (xy 290.505226 -347.672858)
			(xy 290.557528 -347.657505) (xy 290.611483 -347.649753) (xy 290.638738 -347.649292) (xy 290.666779 -347.649759)
			(xy 290.722259 -347.657966) (xy 290.775941 -347.674198) (xy 290.826673 -347.698105) (xy 290.873363 -347.729175)
			(xy 290.894516 -347.74759) (xy 290.905958 -347.757235) (xy 290.933001 -347.770015) (xy 290.962588 -347.774401)
			(xy 290.992175 -347.770015) (xy 291.019218 -347.757235) (xy 291.03066 -347.74759) (xy 291.051808 -347.729166)
			(xy 291.098486 -347.698072) (xy 291.149217 -347.674157) (xy 291.202907 -347.657938) (xy 291.258395 -347.649765)
			(xy 291.286438 -347.649292) (xy 291.313807 -347.649796) (xy 291.367984 -347.657605) (xy 291.420487 -347.673085)
			(xy 291.470234 -347.695919) (xy 291.516203 -347.725635) (xy 291.537136 -347.743272) (xy 291.548464 -347.752508)
			(xy 291.575021 -347.764684) (xy 291.603938 -347.768857) (xy 291.632855 -347.764684) (xy 291.659412 -347.752508)
			(xy 291.67074 -347.743272) (xy 291.69168 -347.725643) (xy 291.737651 -347.695931) (xy 291.787397 -347.673093)
			(xy 291.839895 -347.6576) (xy 291.894069 -347.649768) (xy 291.921438 -347.649292) (xy 291.94869 -347.649742)
			(xy 292.002639 -347.657504) (xy 292.054935 -347.672864) (xy 292.104512 -347.69551) (xy 292.150362 -347.72498)
			(xy 292.191552 -347.760675) (xy 292.227243 -347.801868) (xy 292.256709 -347.847721) (xy 292.279349 -347.897301)
			(xy 292.294704 -347.949598) (xy 292.30246 -348.003548) (xy 292.302946 -348.0308) (xy 292.302493 -348.058171)
			(xy 292.294674 -348.112351) (xy 292.279183 -348.164855) (xy 292.256338 -348.214602) (xy 292.226609 -348.260567)
			(xy 292.208966 -348.281498) (xy 292.199732 -348.292826) (xy 292.187559 -348.319384) (xy 292.183388 -348.3483)
			(xy 292.187559 -348.377216) (xy 292.199732 -348.403774) (xy 292.208966 -348.415102) (xy 292.226607 -348.436035)
			(xy 292.256332 -348.482002) (xy 292.279178 -348.531748) (xy 292.294675 -348.584251) (xy 292.302503 -348.638429)
			(xy 292.302503 -348.693171) (xy 292.294675 -348.747349) (xy 292.279178 -348.799852) (xy 292.256332 -348.849598)
			(xy 292.226607 -348.895565) (xy 292.208966 -348.916498) (xy 292.199732 -348.927826) (xy 292.187559 -348.954384)
			(xy 292.183388 -348.9833) (xy 292.187559 -349.012216) (xy 292.199732 -349.038774) (xy 292.208966 -349.050102)
			(xy 292.226607 -349.071035) (xy 292.256332 -349.117002) (xy 292.279178 -349.166748) (xy 292.294675 -349.219251)
			(xy 292.302503 -349.273429) (xy 292.302503 -349.328171) (xy 292.294675 -349.382349) (xy 292.279178 -349.434852)
			(xy 292.256332 -349.484598) (xy 292.226607 -349.530565) (xy 292.208966 -349.551498) (xy 292.199732 -349.562826)
			(xy 292.187559 -349.589384) (xy 292.183388 -349.6183) (xy 292.187559 -349.647216) (xy 292.199732 -349.673774)
			(xy 292.208966 -349.685102) (xy 292.226607 -349.706035) (xy 292.256332 -349.752002) (xy 292.279178 -349.801748)
			(xy 292.294675 -349.854251) (xy 292.302503 -349.908429) (xy 292.302503 -349.963171) (xy 292.294675 -350.017349)
			(xy 292.279178 -350.069852) (xy 292.256332 -350.119598) (xy 292.226607 -350.165565) (xy 292.208966 -350.186498)
			(xy 292.199732 -350.197826) (xy 292.187559 -350.224384) (xy 292.183388 -350.2533) (xy 292.187559 -350.282216)
			(xy 292.199732 -350.308774) (xy 292.208966 -350.320102) (xy 292.226607 -350.341035) (xy 292.256332 -350.387002)
			(xy 292.279178 -350.436748) (xy 292.294675 -350.489251) (xy 292.302503 -350.543429) (xy 292.302503 -350.598171)
			(xy 292.294675 -350.652349) (xy 292.279178 -350.704852) (xy 292.256332 -350.754598) (xy 292.226607 -350.800565)
			(xy 292.208966 -350.821498) (xy 292.199732 -350.832826) (xy 292.187559 -350.859384) (xy 292.183388 -350.8883)
			(xy 292.187559 -350.917216) (xy 292.199732 -350.943774) (xy 292.208966 -350.955102) (xy 292.226607 -350.976035)
			(xy 292.256332 -351.022002) (xy 292.279178 -351.071748) (xy 292.294675 -351.124251) (xy 292.302503 -351.178429)
			(xy 292.302503 -351.233171) (xy 292.294675 -351.287349) (xy 292.279178 -351.339852) (xy 292.256332 -351.389598)
			(xy 292.226607 -351.435565) (xy 292.208966 -351.456498) (xy 292.199732 -351.467826) (xy 292.187559 -351.494384)
			(xy 292.183388 -351.5233) (xy 292.187559 -351.552216) (xy 292.199732 -351.578774) (xy 292.208966 -351.590102)
			(xy 292.226614 -351.611027) (xy 292.256326 -351.657001) (xy 292.279161 -351.70675) (xy 292.294649 -351.759253)
			(xy 292.302474 -351.81343) (xy 292.302946 -351.8408) (xy 294.964358 -351.8408) (xy 294.96481 -351.813429)
			(xy 294.972629 -351.759249) (xy 294.988121 -351.706745) (xy 295.010966 -351.656998) (xy 295.040695 -351.611033)
			(xy 295.058338 -351.590102) (xy 295.067572 -351.578773) (xy 295.079745 -351.552215) (xy 295.083915 -351.5233)
			(xy 295.079745 -351.494385) (xy 295.067572 -351.467827) (xy 295.058338 -351.456498) (xy 295.040697 -351.435565)
			(xy 295.010971 -351.389598) (xy 294.988125 -351.339852) (xy 294.972628 -351.28735) (xy 294.9648 -351.233171)
			(xy 294.9648 -351.178429) (xy 294.972628 -351.12425) (xy 294.988125 -351.071748) (xy 295.010971 -351.022002)
			(xy 295.040697 -350.976035) (xy 295.058338 -350.955102) (xy 295.067572 -350.943773) (xy 295.079745 -350.917215)
			(xy 295.083915 -350.8883) (xy 295.079745 -350.859385) (xy 295.067572 -350.832827) (xy 295.058338 -350.821498)
			(xy 295.040697 -350.800565) (xy 295.010971 -350.754598) (xy 294.988125 -350.704852) (xy 294.972628 -350.65235)
			(xy 294.9648 -350.598171) (xy 294.9648 -350.543429) (xy 294.972628 -350.48925) (xy 294.988125 -350.436748)
			(xy 295.010971 -350.387002) (xy 295.040697 -350.341035) (xy 295.058338 -350.320102) (xy 295.067572 -350.308773)
			(xy 295.079745 -350.282215) (xy 295.083915 -350.2533) (xy 295.079745 -350.224385) (xy 295.067572 -350.197827)
			(xy 295.058338 -350.186498) (xy 295.040697 -350.165565) (xy 295.010971 -350.119598) (xy 294.988125 -350.069852)
			(xy 294.972628 -350.01735) (xy 294.9648 -349.963171) (xy 294.9648 -349.908429) (xy 294.972628 -349.85425)
			(xy 294.988125 -349.801748) (xy 295.010971 -349.752002) (xy 295.040697 -349.706035) (xy 295.058338 -349.685102)
			(xy 295.067572 -349.673773) (xy 295.079745 -349.647215) (xy 295.083915 -349.6183) (xy 295.079745 -349.589385)
			(xy 295.067572 -349.562827) (xy 295.058338 -349.551498) (xy 295.040697 -349.530565) (xy 295.010971 -349.484598)
			(xy 294.988125 -349.434852) (xy 294.972628 -349.38235) (xy 294.9648 -349.328171) (xy 294.9648 -349.273429)
			(xy 294.972628 -349.21925) (xy 294.988125 -349.166748) (xy 295.010971 -349.117002) (xy 295.040697 -349.071035)
			(xy 295.058338 -349.050102) (xy 295.067572 -349.038773) (xy 295.079745 -349.012215) (xy 295.083915 -348.9833)
			(xy 295.079745 -348.954385) (xy 295.067572 -348.927827) (xy 295.058338 -348.916498) (xy 295.040697 -348.895565)
			(xy 295.010971 -348.849598) (xy 294.988125 -348.799852) (xy 294.972628 -348.74735) (xy 294.9648 -348.693171)
			(xy 294.9648 -348.638429) (xy 294.972628 -348.58425) (xy 294.988125 -348.531748) (xy 295.010971 -348.482002)
			(xy 295.040697 -348.436035) (xy 295.058338 -348.415102) (xy 295.067572 -348.403773) (xy 295.079745 -348.377215)
			(xy 295.083915 -348.3483) (xy 295.079745 -348.319385) (xy 295.067572 -348.292827) (xy 295.058338 -348.281498)
			(xy 295.04069 -348.260573) (xy 295.010979 -348.214599) (xy 294.988144 -348.164849) (xy 294.972655 -348.112347)
			(xy 294.96483 -348.05817) (xy 294.964358 -348.0308) (xy 294.964878 -348.00355) (xy 294.972633 -347.949606)
			(xy 294.987987 -347.897314) (xy 295.010625 -347.847739) (xy 295.040089 -347.80189) (xy 295.075776 -347.7607)
			(xy 295.116963 -347.725009) (xy 295.162809 -347.695542) (xy 295.212382 -347.672899) (xy 295.264672 -347.657541)
			(xy 295.318616 -347.64978) (xy 295.345866 -347.649292) (xy 295.373235 -347.64978) (xy 295.427413 -347.657593)
			(xy 295.479916 -347.673077) (xy 295.529663 -347.695914) (xy 295.575631 -347.725633) (xy 295.596564 -347.743272)
			(xy 295.607892 -347.752508) (xy 295.634449 -347.764684) (xy 295.663366 -347.768857) (xy 295.692283 -347.764684)
			(xy 295.71884 -347.752508) (xy 295.730168 -347.743272) (xy 295.751098 -347.72563) (xy 295.797072 -347.69592)
			(xy 295.84682 -347.673085) (xy 295.899321 -347.657594) (xy 295.953497 -347.649766) (xy 295.980866 -347.649292)
			(xy 296.008906 -347.649802) (xy 296.064383 -347.657998) (xy 296.118065 -347.67422) (xy 296.168798 -347.698118)
			(xy 296.21549 -347.729179) (xy 296.236644 -347.74759) (xy 296.248086 -347.757235) (xy 296.275129 -347.770015)
			(xy 296.304716 -347.774401) (xy 296.334303 -347.770015) (xy 296.361346 -347.757235) (xy 296.372788 -347.74759)
			(xy 296.393925 -347.729153) (xy 296.440606 -347.698061) (xy 296.49134 -347.674149) (xy 296.545032 -347.657932)
			(xy 296.600522 -347.649763) (xy 296.628566 -347.649292) (xy 296.655818 -347.649787) (xy 296.709768 -347.657539)
			(xy 296.762065 -347.672891) (xy 296.811645 -347.69553) (xy 296.857498 -347.724994) (xy 296.898691 -347.760684)
			(xy 296.934386 -347.801874) (xy 296.963854 -347.847725) (xy 296.986497 -347.897303) (xy 297.001853 -347.949599)
			(xy 297.009611 -348.003548) (xy 297.010074 -348.0308) (xy 297.009614 -348.058171) (xy 297.001796 -348.11235)
			(xy 296.986306 -348.164854) (xy 296.963462 -348.2146) (xy 296.933736 -348.260567) (xy 296.916094 -348.281498)
			(xy 296.906858 -348.292825) (xy 296.894681 -348.319383) (xy 296.890509 -348.3483) (xy 296.894681 -348.377217)
			(xy 296.906858 -348.403775) (xy 296.916094 -348.415102) (xy 296.933734 -348.436035) (xy 296.963457 -348.482003)
			(xy 296.986301 -348.53175) (xy 297.001796 -348.584252) (xy 297.009625 -348.63843) (xy 297.009625 -348.69317)
			(xy 297.001796 -348.747348) (xy 296.986301 -348.79985) (xy 296.963457 -348.849597) (xy 296.933734 -348.895565)
			(xy 296.916094 -348.916498) (xy 296.906858 -348.927825) (xy 296.894681 -348.954383) (xy 296.890509 -348.9833)
			(xy 296.894681 -349.012217) (xy 296.906858 -349.038775) (xy 296.916094 -349.050102) (xy 296.933734 -349.071035)
			(xy 296.963457 -349.117003) (xy 296.986301 -349.16675) (xy 297.001796 -349.219252) (xy 297.009625 -349.27343)
			(xy 297.009625 -349.32817) (xy 297.001796 -349.382348) (xy 296.986301 -349.43485) (xy 296.963457 -349.484597)
			(xy 296.933734 -349.530565) (xy 296.916094 -349.551498) (xy 296.906858 -349.562825) (xy 296.894681 -349.589383)
			(xy 296.890509 -349.6183) (xy 296.894681 -349.647217) (xy 296.906858 -349.673775) (xy 296.916094 -349.685102)
			(xy 296.933734 -349.706035) (xy 296.963457 -349.752003) (xy 296.986301 -349.80175) (xy 297.001796 -349.854252)
			(xy 297.009625 -349.90843) (xy 297.009625 -349.96317) (xy 297.001796 -350.017348) (xy 296.986301 -350.06985)
			(xy 296.963457 -350.119597) (xy 296.933734 -350.165565) (xy 296.916094 -350.186498) (xy 296.906858 -350.197825)
			(xy 296.894681 -350.224383) (xy 296.890509 -350.2533) (xy 296.894681 -350.282217) (xy 296.906858 -350.308775)
			(xy 296.916094 -350.320102) (xy 296.933734 -350.341035) (xy 296.963457 -350.387003) (xy 296.986301 -350.43675)
			(xy 297.001796 -350.489252) (xy 297.009625 -350.54343) (xy 297.009625 -350.59817) (xy 297.001796 -350.652348)
			(xy 296.986301 -350.70485) (xy 296.963457 -350.754597) (xy 296.933734 -350.800565) (xy 296.916094 -350.821498)
			(xy 296.906858 -350.832825) (xy 296.894681 -350.859383) (xy 296.890509 -350.8883) (xy 296.894681 -350.917217)
			(xy 296.906858 -350.943775) (xy 296.916094 -350.955102) (xy 296.933734 -350.976035) (xy 296.963457 -351.022003)
			(xy 296.986301 -351.07175) (xy 297.001796 -351.124252) (xy 297.009625 -351.17843) (xy 297.009625 -351.23317)
			(xy 297.001796 -351.287348) (xy 296.986301 -351.33985) (xy 296.963457 -351.389597) (xy 296.933734 -351.435565)
			(xy 296.916094 -351.456498) (xy 296.906858 -351.467825) (xy 296.894681 -351.494383) (xy 296.890509 -351.5233)
			(xy 296.894681 -351.552217) (xy 296.906858 -351.578775) (xy 296.916094 -351.590102) (xy 296.933747 -351.611023)
			(xy 296.963457 -351.656999) (xy 296.98629 -351.706749) (xy 297.001778 -351.759252) (xy 297.009602 -351.81343)
			(xy 297.010074 -351.8408) (xy 300.03623 -351.8408) (xy 300.036689 -351.813429) (xy 300.044507 -351.75925)
			(xy 300.059998 -351.706746) (xy 300.082841 -351.656999) (xy 300.112568 -351.611033) (xy 300.13021 -351.590102)
			(xy 300.139446 -351.578774) (xy 300.151622 -351.552217) (xy 300.155794 -351.5233) (xy 300.151622 -351.494383)
			(xy 300.139446 -351.467826) (xy 300.13021 -351.456498) (xy 300.11257 -351.435565) (xy 300.082847 -351.389597)
			(xy 300.060002 -351.33985) (xy 300.044507 -351.287349) (xy 300.036678 -351.23317) (xy 300.036678 -351.17843)
			(xy 300.044507 -351.124251) (xy 300.060002 -351.07175) (xy 300.082847 -351.022003) (xy 300.11257 -350.976035)
			(xy 300.13021 -350.955102) (xy 300.139446 -350.943774) (xy 300.151622 -350.917217) (xy 300.155794 -350.8883)
			(xy 300.151622 -350.859383) (xy 300.139446 -350.832826) (xy 300.13021 -350.821498) (xy 300.11257 -350.800565)
			(xy 300.082847 -350.754597) (xy 300.060002 -350.70485) (xy 300.044507 -350.652349) (xy 300.036678 -350.59817)
			(xy 300.036678 -350.54343) (xy 300.044507 -350.489251) (xy 300.060002 -350.43675) (xy 300.082847 -350.387003)
			(xy 300.11257 -350.341035) (xy 300.13021 -350.320102) (xy 300.139446 -350.308774) (xy 300.151622 -350.282217)
			(xy 300.155794 -350.2533) (xy 300.151622 -350.224383) (xy 300.139446 -350.197826) (xy 300.13021 -350.186498)
			(xy 300.11257 -350.165565) (xy 300.082847 -350.119597) (xy 300.060002 -350.06985) (xy 300.044507 -350.017349)
			(xy 300.036678 -349.96317) (xy 300.036678 -349.90843) (xy 300.044507 -349.854251) (xy 300.060002 -349.80175)
			(xy 300.082847 -349.752003) (xy 300.11257 -349.706035) (xy 300.13021 -349.685102) (xy 300.139446 -349.673774)
			(xy 300.151622 -349.647217) (xy 300.155794 -349.6183) (xy 300.151622 -349.589383) (xy 300.139446 -349.562826)
			(xy 300.13021 -349.551498) (xy 300.11257 -349.530565) (xy 300.082847 -349.484597) (xy 300.060002 -349.43485)
			(xy 300.044507 -349.382349) (xy 300.036678 -349.32817) (xy 300.036678 -349.27343) (xy 300.044507 -349.219251)
			(xy 300.060002 -349.16675) (xy 300.082847 -349.117003) (xy 300.11257 -349.071035) (xy 300.13021 -349.050102)
			(xy 300.139446 -349.038774) (xy 300.151622 -349.012217) (xy 300.155794 -348.9833) (xy 300.151622 -348.954383)
			(xy 300.139446 -348.927826) (xy 300.13021 -348.916498) (xy 300.11257 -348.895565) (xy 300.082847 -348.849597)
			(xy 300.060002 -348.79985) (xy 300.044507 -348.747349) (xy 300.036678 -348.69317) (xy 300.036678 -348.63843)
			(xy 300.044507 -348.584251) (xy 300.060002 -348.53175) (xy 300.082847 -348.482003) (xy 300.11257 -348.436035)
			(xy 300.13021 -348.415102) (xy 300.139446 -348.403774) (xy 300.151622 -348.377217) (xy 300.155794 -348.3483)
			(xy 300.151622 -348.319383) (xy 300.139446 -348.292826) (xy 300.13021 -348.281498) (xy 300.112558 -348.260576)
			(xy 300.082848 -348.214601) (xy 300.060014 -348.164851) (xy 300.044526 -348.112348) (xy 300.036702 -348.05817)
			(xy 300.03623 -348.0308) (xy 300.036655 -348.003545) (xy 300.044413 -347.949591) (xy 300.059771 -347.89729)
			(xy 300.082417 -347.847708) (xy 300.111888 -347.801853) (xy 300.147586 -347.760659) (xy 300.188783 -347.724965)
			(xy 300.234641 -347.695498) (xy 300.284226 -347.672858) (xy 300.336528 -347.657505) (xy 300.390483 -347.649753)
			(xy 300.417738 -347.649292) (xy 300.445779 -347.649759) (xy 300.501259 -347.657966) (xy 300.554941 -347.674198)
			(xy 300.605673 -347.698105) (xy 300.652363 -347.729175) (xy 300.673516 -347.74759) (xy 300.684958 -347.757235)
			(xy 300.712001 -347.770015) (xy 300.741588 -347.774401) (xy 300.771175 -347.770015) (xy 300.798218 -347.757235)
			(xy 300.80966 -347.74759) (xy 300.830808 -347.729166) (xy 300.877486 -347.698072) (xy 300.928217 -347.674157)
			(xy 300.981907 -347.657938) (xy 301.037395 -347.649765) (xy 301.065438 -347.649292) (xy 301.092807 -347.649796)
			(xy 301.146984 -347.657605) (xy 301.199487 -347.673085) (xy 301.249234 -347.695919) (xy 301.295203 -347.725635)
			(xy 301.316136 -347.743272) (xy 301.327464 -347.752508) (xy 301.354021 -347.764684) (xy 301.382938 -347.768857)
			(xy 301.411855 -347.764684) (xy 301.438412 -347.752508) (xy 301.44974 -347.743272) (xy 301.47068 -347.725643)
			(xy 301.516651 -347.695931) (xy 301.566397 -347.673093) (xy 301.618895 -347.6576) (xy 301.673069 -347.649768)
			(xy 301.700438 -347.649292) (xy 301.72769 -347.649742) (xy 301.781639 -347.657504) (xy 301.833935 -347.672864)
			(xy 301.883512 -347.69551) (xy 301.929362 -347.72498) (xy 301.970552 -347.760675) (xy 302.006243 -347.801868)
			(xy 302.035709 -347.847721) (xy 302.058349 -347.897301) (xy 302.073704 -347.949598) (xy 302.08146 -348.003548)
			(xy 302.081946 -348.0308) (xy 302.081493 -348.058171) (xy 302.073674 -348.112351) (xy 302.058183 -348.164855)
			(xy 302.035338 -348.214602) (xy 302.005609 -348.260567) (xy 301.987966 -348.281498) (xy 301.978732 -348.292826)
			(xy 301.966559 -348.319384) (xy 301.962388 -348.3483) (xy 301.966559 -348.377216) (xy 301.978732 -348.403774)
			(xy 301.987966 -348.415102) (xy 302.005607 -348.436035) (xy 302.035332 -348.482002) (xy 302.058178 -348.531748)
			(xy 302.073675 -348.584251) (xy 302.081503 -348.638429) (xy 302.081503 -348.693171) (xy 302.073675 -348.747349)
			(xy 302.058178 -348.799852) (xy 302.035332 -348.849598) (xy 302.005607 -348.895565) (xy 301.987966 -348.916498)
			(xy 301.978732 -348.927826) (xy 301.966559 -348.954384) (xy 301.962388 -348.9833) (xy 301.966559 -349.012216)
			(xy 301.978732 -349.038774) (xy 301.987966 -349.050102) (xy 302.005607 -349.071035) (xy 302.035332 -349.117002)
			(xy 302.058178 -349.166748) (xy 302.073675 -349.219251) (xy 302.081503 -349.273429) (xy 302.081503 -349.328171)
			(xy 302.073675 -349.382349) (xy 302.058178 -349.434852) (xy 302.035332 -349.484598) (xy 302.005607 -349.530565)
			(xy 301.987966 -349.551498) (xy 301.978732 -349.562826) (xy 301.966559 -349.589384) (xy 301.962388 -349.6183)
			(xy 301.966559 -349.647216) (xy 301.978732 -349.673774) (xy 301.987966 -349.685102) (xy 302.005607 -349.706035)
			(xy 302.035332 -349.752002) (xy 302.058178 -349.801748) (xy 302.073675 -349.854251) (xy 302.081503 -349.908429)
			(xy 302.081503 -349.963171) (xy 302.073675 -350.017349) (xy 302.058178 -350.069852) (xy 302.035332 -350.119598)
			(xy 302.005607 -350.165565) (xy 301.987966 -350.186498) (xy 301.978732 -350.197826) (xy 301.966559 -350.224384)
			(xy 301.962388 -350.2533) (xy 301.966559 -350.282216) (xy 301.978732 -350.308774) (xy 301.987966 -350.320102)
			(xy 302.005607 -350.341035) (xy 302.035332 -350.387002) (xy 302.058178 -350.436748) (xy 302.073675 -350.489251)
			(xy 302.081503 -350.543429) (xy 302.081503 -350.598171) (xy 302.073675 -350.652349) (xy 302.058178 -350.704852)
			(xy 302.035332 -350.754598) (xy 302.005607 -350.800565) (xy 301.987966 -350.821498) (xy 301.978732 -350.832826)
			(xy 301.966559 -350.859384) (xy 301.962388 -350.8883) (xy 301.966559 -350.917216) (xy 301.978732 -350.943774)
			(xy 301.987966 -350.955102) (xy 302.005607 -350.976035) (xy 302.035332 -351.022002) (xy 302.058178 -351.071748)
			(xy 302.073675 -351.124251) (xy 302.081503 -351.178429) (xy 302.081503 -351.233171) (xy 302.073675 -351.287349)
			(xy 302.058178 -351.339852) (xy 302.035332 -351.389598) (xy 302.005607 -351.435565) (xy 301.987966 -351.456498)
			(xy 301.978732 -351.467826) (xy 301.966559 -351.494384) (xy 301.962388 -351.5233) (xy 301.966559 -351.552216)
			(xy 301.978732 -351.578774) (xy 301.987966 -351.590102) (xy 302.005614 -351.611027) (xy 302.035326 -351.657001)
			(xy 302.058161 -351.70675) (xy 302.073649 -351.759253) (xy 302.081474 -351.81343) (xy 302.081946 -351.8408)
			(xy 302.081422 -351.86805) (xy 302.073667 -351.921994) (xy 302.058314 -351.974286) (xy 302.035675 -352.02386)
			(xy 302.006212 -352.069709) (xy 301.970525 -352.110898) (xy 301.929339 -352.14659) (xy 301.883494 -352.176057)
			(xy 301.833921 -352.1987) (xy 301.781631 -352.214059) (xy 301.727687 -352.22182) (xy 301.700438 -352.222308)
			(xy 301.673069 -352.221818) (xy 301.618891 -352.214005) (xy 301.566388 -352.198522) (xy 301.516641 -352.175686)
			(xy 301.470673 -352.145967) (xy 301.44974 -352.128328) (xy 301.438412 -352.119092) (xy 301.411855 -352.106916)
			(xy 301.382938 -352.102743) (xy 301.354021 -352.106916) (xy 301.327464 -352.119092) (xy 301.316136 -352.128328)
			(xy 301.295205 -352.145968) (xy 301.249231 -352.175679) (xy 301.199484 -352.198514) (xy 301.146983 -352.214005)
			(xy 301.092807 -352.221834) (xy 301.065438 -352.222308) (xy 301.037398 -352.221796) (xy 300.981921 -352.2136)
			(xy 300.928239 -352.197379) (xy 300.877507 -352.173481) (xy 300.830814 -352.142421) (xy 300.80966 -352.12401)
			(xy 300.798218 -352.114365) (xy 300.771175 -352.101585) (xy 300.741588 -352.097199) (xy 300.712001 -352.101585)
			(xy 300.684958 -352.114365) (xy 300.673516 -352.12401) (xy 300.652378 -352.142445) (xy 300.605697 -352.173537)
			(xy 300.554963 -352.19745) (xy 300.501271 -352.213667) (xy 300.445782 -352.221837) (xy 300.417738 -352.222308)
			(xy 300.390486 -352.221809) (xy 300.336536 -352.214058) (xy 300.284239 -352.198706) (xy 300.234659 -352.176068)
			(xy 300.188806 -352.146604) (xy 300.147613 -352.110914) (xy 300.111919 -352.069725) (xy 300.08245 -352.023874)
			(xy 300.059807 -351.974296) (xy 300.044451 -351.922001) (xy 300.036693 -351.868052) (xy 300.03623 -351.8408)
			(xy 297.010074 -351.8408) (xy 297.009645 -351.868054) (xy 297.001887 -351.922008) (xy 296.986529 -351.974309)
			(xy 296.963884 -352.023891) (xy 296.934413 -352.069746) (xy 296.898715 -352.11094) (xy 296.857519 -352.146633)
			(xy 296.811661 -352.1761) (xy 296.762077 -352.198741) (xy 296.709775 -352.214094) (xy 296.65582 -352.221847)
			(xy 296.628566 -352.222308) (xy 296.600525 -352.221839) (xy 296.545046 -352.213632) (xy 296.491363 -352.197401)
			(xy 296.440631 -352.173494) (xy 296.393941 -352.142425) (xy 296.372788 -352.12401) (xy 296.361346 -352.114365)
			(xy 296.334303 -352.101585) (xy 296.304716 -352.097199) (xy 296.275129 -352.101585) (xy 296.248086 -352.114365)
			(xy 296.236644 -352.12401) (xy 296.215495 -352.142432) (xy 296.168817 -352.173526) (xy 296.118086 -352.197441)
			(xy 296.064396 -352.213661) (xy 296.008909 -352.221835) (xy 295.980866 -352.222308) (xy 295.953495 -352.22186)
			(xy 295.899315 -352.214037) (xy 295.846812 -352.198544) (xy 295.797066 -352.175698) (xy 295.751099 -352.145971)
			(xy 295.730168 -352.128328) (xy 295.71884 -352.119092) (xy 295.692283 -352.106916) (xy 295.663366 -352.102743)
			(xy 295.634449 -352.106916) (xy 295.607892 -352.119092) (xy 295.596564 -352.128328) (xy 295.575622 -352.145955)
			(xy 295.529652 -352.175668) (xy 295.479907 -352.198505) (xy 295.427408 -352.213999) (xy 295.373234 -352.221832)
			(xy 295.345866 -352.222308) (xy 295.318614 -352.221854) (xy 295.264665 -352.214093) (xy 295.21237 -352.198733)
			(xy 295.162792 -352.176088) (xy 295.116942 -352.146618) (xy 295.075752 -352.110924) (xy 295.040061 -352.069731)
			(xy 295.010596 -352.023878) (xy 294.987955 -351.974298) (xy 294.9726 -351.922002) (xy 294.964844 -351.868052)
			(xy 294.964358 -351.8408) (xy 292.302946 -351.8408) (xy 292.302422 -351.86805) (xy 292.294667 -351.921994)
			(xy 292.279314 -351.974286) (xy 292.256675 -352.02386) (xy 292.227212 -352.069709) (xy 292.191525 -352.110898)
			(xy 292.150339 -352.14659) (xy 292.104494 -352.176057) (xy 292.054921 -352.1987) (xy 292.002631 -352.214059)
			(xy 291.948687 -352.22182) (xy 291.921438 -352.222308) (xy 291.894069 -352.221818) (xy 291.839891 -352.214005)
			(xy 291.787388 -352.198522) (xy 291.737641 -352.175686) (xy 291.691673 -352.145967) (xy 291.67074 -352.128328)
			(xy 291.659412 -352.119092) (xy 291.632855 -352.106916) (xy 291.603938 -352.102743) (xy 291.575021 -352.106916)
			(xy 291.548464 -352.119092) (xy 291.537136 -352.128328) (xy 291.516205 -352.145968) (xy 291.470231 -352.175679)
			(xy 291.420484 -352.198514) (xy 291.367983 -352.214005) (xy 291.313807 -352.221834) (xy 291.286438 -352.222308)
			(xy 291.258398 -352.221796) (xy 291.202921 -352.2136) (xy 291.149239 -352.197379) (xy 291.098507 -352.173481)
			(xy 291.051814 -352.142421) (xy 291.03066 -352.12401) (xy 291.019218 -352.114365) (xy 290.992175 -352.101585)
			(xy 290.962588 -352.097199) (xy 290.933001 -352.101585) (xy 290.905958 -352.114365) (xy 290.894516 -352.12401)
			(xy 290.873378 -352.142445) (xy 290.826697 -352.173537) (xy 290.775963 -352.19745) (xy 290.722271 -352.213667)
			(xy 290.666782 -352.221837) (xy 290.638738 -352.222308) (xy 290.611486 -352.221809) (xy 290.557536 -352.214058)
			(xy 290.505239 -352.198706) (xy 290.455659 -352.176068) (xy 290.409806 -352.146604) (xy 290.368613 -352.110914)
			(xy 290.332919 -352.069725) (xy 290.30345 -352.023874) (xy 290.280807 -351.974296) (xy 290.265451 -351.922001)
			(xy 290.257693 -351.868052) (xy 290.25723 -351.8408) (xy 287.332674 -351.8408) (xy 287.332245 -351.868054)
			(xy 287.324487 -351.922008) (xy 287.309129 -351.974309) (xy 287.286484 -352.023891) (xy 287.257013 -352.069746)
			(xy 287.221315 -352.11094) (xy 287.180119 -352.146633) (xy 287.134261 -352.1761) (xy 287.084677 -352.198741)
			(xy 287.032375 -352.214094) (xy 286.97842 -352.221847) (xy 286.951166 -352.222308) (xy 286.923125 -352.221839)
			(xy 286.867646 -352.213632) (xy 286.813963 -352.197401) (xy 286.763231 -352.173494) (xy 286.716541 -352.142425)
			(xy 286.695388 -352.12401) (xy 286.683946 -352.114365) (xy 286.656903 -352.101585) (xy 286.627316 -352.097199)
			(xy 286.597729 -352.101585) (xy 286.570686 -352.114365) (xy 286.559244 -352.12401) (xy 286.538095 -352.142432)
			(xy 286.491417 -352.173526) (xy 286.440686 -352.197441) (xy 286.386996 -352.213661) (xy 286.331509 -352.221835)
			(xy 286.303466 -352.222308) (xy 286.276095 -352.22186) (xy 286.221915 -352.214037) (xy 286.169412 -352.198544)
			(xy 286.119666 -352.175698) (xy 286.073699 -352.145971) (xy 286.052768 -352.128328) (xy 286.04144 -352.119092)
			(xy 286.014883 -352.106916) (xy 285.985966 -352.102743) (xy 285.957049 -352.106916) (xy 285.930492 -352.119092)
			(xy 285.919164 -352.128328) (xy 285.898222 -352.145955) (xy 285.852252 -352.175668) (xy 285.802507 -352.198505)
			(xy 285.750008 -352.213999) (xy 285.695834 -352.221832) (xy 285.668466 -352.222308) (xy 285.641214 -352.221854)
			(xy 285.587265 -352.214093) (xy 285.53497 -352.198733) (xy 285.485392 -352.176088) (xy 285.439542 -352.146618)
			(xy 285.398352 -352.110924) (xy 285.362661 -352.069731) (xy 285.333196 -352.023878) (xy 285.310555 -351.974298)
			(xy 285.2952 -351.922002) (xy 285.287444 -351.868052) (xy 285.286958 -351.8408) (xy 283.004514 -351.8408)
			(xy 283.004514 -361.929426) (xy 283.004981 -361.944034) (xy 283.013238 -361.97206) (xy 283.029097 -361.996597)
			(xy 283.051258 -362.015636) (xy 283.077905 -362.027616) (xy 283.106855 -362.031555) (xy 283.135734 -362.027132)
			(xy 283.162177 -362.014707) (xy 283.173424 -362.005372) (xy 283.194485 -361.987377) (xy 283.240825 -361.957024)
			(xy 283.291064 -361.933686) (xy 283.344149 -361.917853) (xy 283.398964 -361.909857) (xy 283.426662 -361.90936)
			(xy 283.453919 -361.90982) (xy 283.507879 -361.917574) (xy 283.560185 -361.932928) (xy 283.609775 -361.95557)
			(xy 283.655636 -361.985039) (xy 283.696837 -362.020736) (xy 283.732538 -362.061933) (xy 283.762012 -362.107792)
			(xy 283.784659 -362.157379) (xy 283.800018 -362.209684) (xy 283.807777 -362.263643) (xy 283.807777 -362.318157)
			(xy 283.800018 -362.372116) (xy 283.784659 -362.424421) (xy 283.762012 -362.474008) (xy 283.732538 -362.519867)
			(xy 283.696837 -362.561064) (xy 283.655636 -362.596761) (xy 283.609775 -362.62623) (xy 283.560185 -362.648872)
			(xy 283.507879 -362.664226) (xy 283.453919 -362.67198) (xy 283.426662 -362.672376) (xy 283.398961 -362.671905)
			(xy 283.344135 -362.663935) (xy 283.291041 -362.648109) (xy 283.240799 -362.624762) (xy 283.194467 -362.594386)
			(xy 283.173424 -362.576364) (xy 283.162181 -362.567043) (xy 283.135741 -362.554665) (xy 283.10688 -362.550272)
			(xy 283.077955 -362.554223) (xy 283.05133 -362.566197) (xy 283.029179 -362.585214) (xy 283.013314 -362.60972)
			(xy 283.00503 -362.637714) (xy 283.004514 -362.65231) (xy 283.004514 -364.242096) (xy 284.829758 -364.242096)
			(xy 284.830254 -364.214056) (xy 284.838455 -364.158578) (xy 284.854681 -364.104896) (xy 284.878582 -364.054164)
			(xy 284.909644 -364.007472) (xy 284.928056 -363.986318) (xy 284.937658 -363.974842) (xy 284.950447 -363.947812)
			(xy 284.954843 -363.918234) (xy 284.950467 -363.888653) (xy 284.937697 -363.861615) (xy 284.928056 -363.850174)
			(xy 284.909643 -363.829017) (xy 284.878549 -363.782341) (xy 284.854632 -363.731612) (xy 284.83841 -363.677924)
			(xy 284.830233 -363.622439) (xy 284.829758 -363.594396) (xy 284.830274 -363.567146) (xy 284.83803 -363.513201)
			(xy 284.853384 -363.460909) (xy 284.876023 -363.411334) (xy 284.905487 -363.365485) (xy 284.941175 -363.324296)
			(xy 284.982361 -363.288605) (xy 285.028208 -363.259138) (xy 285.077781 -363.236495) (xy 285.130072 -363.221137)
			(xy 285.184016 -363.213376) (xy 285.211266 -363.212888) (xy 285.239232 -363.213348) (xy 285.294572 -363.221459)
			(xy 285.348132 -363.237573) (xy 285.398762 -363.261341) (xy 285.42234 -363.276388) (xy 286.053276 -363.276388)
			(xy 286.078262 -363.276884) (xy 286.127617 -363.284715) (xy 286.175139 -363.300171) (xy 286.219658 -363.322873)
			(xy 286.260076 -363.35226) (xy 286.278066 -363.369606) (xy 286.618934 -363.710728) (xy 288.51606 -363.710728)
			(xy 288.964878 -363.261656) (xy 288.982891 -363.244346) (xy 289.023311 -363.214992) (xy 289.067828 -363.192329)
			(xy 289.115346 -363.176918) (xy 289.16469 -363.169137) (xy 289.189668 -363.168692) (xy 291.474906 -363.168692)
			(xy 292.104826 -362.538518) (xy 292.122828 -362.521181) (xy 292.163233 -362.491771) (xy 292.207747 -362.469055)
			(xy 292.25527 -362.453592) (xy 292.304628 -362.445765) (xy 292.329616 -362.4453) (xy 294.06215 -362.4453)
			(xy 294.087138 -362.445746) (xy 294.136496 -362.453588) (xy 294.184019 -362.469056) (xy 294.228536 -362.491769)
			(xy 294.268952 -362.521167) (xy 294.28694 -362.538518) (xy 294.974772 -363.22635) (xy 294.988742 -363.229906)
			(xy 295.016151 -363.236982) (xy 295.068631 -363.258198) (xy 295.117401 -363.286936) (xy 295.161388 -363.322565)
			(xy 295.199628 -363.364303) (xy 295.231281 -363.411234) (xy 295.255651 -363.462326) (xy 295.272205 -363.516458)
			(xy 295.280577 -363.572443) (xy 295.281096 -363.600746) (xy 295.280599 -363.628115) (xy 295.272789 -363.682293)
			(xy 295.257307 -363.734796) (xy 295.234472 -363.784543) (xy 295.204754 -363.830511) (xy 295.187116 -363.851444)
			(xy 295.180853 -363.859064) (xy 302.365154 -363.859064) (xy 302.369225 -363.803442) (xy 302.381351 -363.749005)
			(xy 302.401274 -363.696914) (xy 302.42857 -363.648279) (xy 302.462656 -363.604136) (xy 302.502805 -363.565427)
			(xy 302.548163 -363.532976) (xy 302.597763 -363.507475) (xy 302.650547 -363.489468) (xy 302.70539 -363.479338)
			(xy 302.761124 -363.477301) (xy 302.816561 -363.483401) (xy 302.870518 -363.497507) (xy 302.921847 -363.519319)
			(xy 302.969453 -363.548373) (xy 303.012321 -363.584048) (xy 303.049538 -363.625585) (xy 303.080311 -363.672098)
			(xy 303.103983 -363.722595) (xy 303.120051 -363.776002) (xy 303.128171 -363.831178) (xy 303.12868 -363.859064)
			(xy 303.128171 -363.88695) (xy 303.120051 -363.942126) (xy 303.103983 -363.995533) (xy 303.080311 -364.04603)
			(xy 303.049538 -364.092543) (xy 303.012321 -364.13408) (xy 302.969453 -364.169755) (xy 302.921847 -364.198809)
			(xy 302.870518 -364.220621) (xy 302.816561 -364.234727) (xy 302.761124 -364.240827) (xy 302.70539 -364.23879)
			(xy 302.650547 -364.22866) (xy 302.597763 -364.210653) (xy 302.548163 -364.185152) (xy 302.502805 -364.152701)
			(xy 302.462656 -364.113992) (xy 302.42857 -364.069849) (xy 302.401274 -364.021214) (xy 302.381351 -363.969123)
			(xy 302.369225 -363.914686) (xy 302.365154 -363.859064) (xy 295.180853 -363.859064) (xy 295.177834 -363.862738)
			(xy 295.16566 -363.889307) (xy 295.161495 -363.918235) (xy 295.165679 -363.94716) (xy 295.177871 -363.973721)
			(xy 295.187116 -363.985048) (xy 295.204747 -364.005987) (xy 295.234459 -364.051958) (xy 295.257297 -364.101704)
			(xy 295.27279 -364.154203) (xy 295.28062 -364.208377) (xy 295.281096 -364.235746) (xy 295.28061 -364.262997)
			(xy 295.272854 -364.316945) (xy 295.257499 -364.36924) (xy 295.234857 -364.418817) (xy 295.205391 -364.464667)
			(xy 295.1697 -364.505858) (xy 295.128509 -364.541549) (xy 295.082659 -364.571015) (xy 295.033082 -364.593657)
			(xy 294.980787 -364.609012) (xy 294.926839 -364.616768) (xy 294.872337 -364.616768) (xy 294.818389 -364.609012)
			(xy 294.766094 -364.593657) (xy 294.716517 -364.571015) (xy 294.670667 -364.541549) (xy 294.629476 -364.505858)
			(xy 294.593785 -364.464667) (xy 294.564319 -364.418817) (xy 294.541677 -364.36924) (xy 294.526322 -364.316945)
			(xy 294.518566 -364.262997) (xy 294.51808 -364.235746) (xy 294.518554 -364.208376) (xy 294.526367 -364.154196)
			(xy 294.541853 -364.101692) (xy 294.564693 -364.051945) (xy 294.594418 -364.005979) (xy 294.61206 -363.985048)
			(xy 294.621255 -363.973689) (xy 294.633443 -363.947143) (xy 294.637626 -363.918235) (xy 294.633463 -363.889324)
			(xy 294.621293 -363.86277) (xy 294.61206 -363.851444) (xy 294.592436 -363.827954) (xy 294.560124 -363.775973)
			(xy 294.5365 -363.719511) (xy 294.528748 -363.6899) (xy 294.525192 -363.67593) (xy 293.930578 -363.081316)
			(xy 292.461188 -363.081316) (xy 291.831268 -363.711236) (xy 291.813278 -363.728571) (xy 291.772852 -363.757922)
			(xy 291.728328 -363.78058) (xy 291.680806 -363.795986) (xy 291.631457 -363.803759) (xy 291.606478 -363.8042)
			(xy 289.32124 -363.8042) (xy 289.269961 -363.855508) (xy 292.807134 -363.855508) (xy 292.811205 -363.799886)
			(xy 292.823331 -363.745449) (xy 292.843254 -363.693358) (xy 292.87055 -363.644723) (xy 292.904636 -363.60058)
			(xy 292.944785 -363.561871) (xy 292.990143 -363.52942) (xy 293.039743 -363.503919) (xy 293.092527 -363.485912)
			(xy 293.14737 -363.475782) (xy 293.203104 -363.473745) (xy 293.258541 -363.479845) (xy 293.312498 -363.493951)
			(xy 293.363827 -363.515763) (xy 293.411433 -363.544817) (xy 293.454301 -363.580492) (xy 293.491518 -363.622029)
			(xy 293.522291 -363.668542) (xy 293.545963 -363.719039) (xy 293.562031 -363.772446) (xy 293.570151 -363.827622)
			(xy 293.57066 -363.855508) (xy 293.570151 -363.883394) (xy 293.562031 -363.93857) (xy 293.545963 -363.991977)
			(xy 293.522291 -364.042474) (xy 293.491518 -364.088987) (xy 293.454301 -364.130524) (xy 293.411433 -364.166199)
			(xy 293.363827 -364.195253) (xy 293.312498 -364.217065) (xy 293.258541 -364.231171) (xy 293.203104 -364.237271)
			(xy 293.14737 -364.235234) (xy 293.092527 -364.225104) (xy 293.039743 -364.207097) (xy 292.990143 -364.181596)
			(xy 292.944785 -364.149145) (xy 292.904636 -364.110436) (xy 292.87055 -364.066293) (xy 292.843254 -364.017658)
			(xy 292.823331 -363.965567) (xy 292.811205 -363.91113) (xy 292.807134 -363.855508) (xy 289.269961 -363.855508)
			(xy 288.872422 -364.253272) (xy 288.854414 -364.270587) (xy 288.813992 -364.299939) (xy 288.769473 -364.3226)
			(xy 288.721955 -364.338011) (xy 288.67261 -364.345791) (xy 288.647632 -364.346236) (xy 286.487362 -364.346236)
			(xy 286.462388 -364.345739) (xy 286.413051 -364.337953) (xy 286.365539 -364.322547) (xy 286.32102 -364.299901)
			(xy 286.28059 -364.270571) (xy 286.262572 -364.253272) (xy 285.921704 -363.912404) (xy 285.63697 -363.912404)
			(xy 285.622011 -363.912996) (xy 285.593393 -363.921732) (xy 285.568534 -363.938386) (xy 285.549568 -363.96153)
			(xy 285.538123 -363.989176) (xy 285.535181 -364.018952) (xy 285.540994 -364.048304) (xy 285.547562 -364.061756)
			(xy 285.561792 -364.089665) (xy 285.581964 -364.148969) (xy 285.592164 -364.210775) (xy 285.592774 -364.242096)
			(xy 285.592288 -364.269347) (xy 285.584532 -364.323295) (xy 285.569177 -364.37559) (xy 285.546535 -364.425167)
			(xy 285.517069 -364.471017) (xy 285.481378 -364.512208) (xy 285.440187 -364.547899) (xy 285.394337 -364.577365)
			(xy 285.34476 -364.600007) (xy 285.292465 -364.615362) (xy 285.238517 -364.623118) (xy 285.184015 -364.623118)
			(xy 285.130067 -364.615362) (xy 285.077772 -364.600007) (xy 285.028195 -364.577365) (xy 284.982345 -364.547899)
			(xy 284.941154 -364.512208) (xy 284.905463 -364.471017) (xy 284.875997 -364.425167) (xy 284.853355 -364.37559)
			(xy 284.838 -364.323295) (xy 284.830244 -364.269347) (xy 284.829758 -364.242096) (xy 283.004514 -364.242096)
			(xy 283.004514 -364.263686) (xy 283.004976 -364.278299) (xy 283.013227 -364.306334) (xy 283.029085 -364.330882)
			(xy 283.051249 -364.34993) (xy 283.077903 -364.361915) (xy 283.106861 -364.365855) (xy 283.135748 -364.361428)
			(xy 283.162196 -364.348995) (xy 283.173424 -364.339632) (xy 283.194486 -364.321638) (xy 283.240827 -364.291289)
			(xy 283.291066 -364.267954) (xy 283.34415 -364.252122) (xy 283.398965 -364.244127) (xy 283.426662 -364.24362)
			(xy 283.453915 -364.244081) (xy 283.507866 -364.251833) (xy 283.560164 -364.267184) (xy 283.609746 -364.289823)
			(xy 283.6556 -364.319288) (xy 283.696794 -364.354979) (xy 283.732489 -364.396169) (xy 283.761959 -364.442021)
			(xy 283.784602 -364.4916) (xy 283.799959 -364.543897) (xy 283.807717 -364.597847) (xy 283.807717 -364.6383)
			(xy 289.07837 -364.6383) (xy 289.082538 -364.582684) (xy 289.094949 -364.52831) (xy 289.115327 -364.476394)
			(xy 289.143215 -364.428095) (xy 289.17799 -364.384492) (xy 289.218876 -364.34656) (xy 289.264959 -364.315146)
			(xy 289.31521 -364.290951) (xy 289.368506 -364.274517) (xy 289.423656 -364.26621) (xy 289.451542 -364.265718)
			(xy 289.478873 -364.26621) (xy 289.532952 -364.274177) (xy 289.585285 -364.289962) (xy 289.634749 -364.313227)
			(xy 289.680282 -364.343471) (xy 289.720905 -364.380046) (xy 289.755745 -364.422165) (xy 289.770312 -364.445296)
			(xy 289.778247 -364.457512) (xy 289.799715 -364.477184) (xy 289.825865 -364.48999) (xy 289.854568 -364.494887)
			(xy 289.883485 -364.491477) (xy 289.897058 -364.48619) (xy 289.920264 -364.47669) (xy 289.968599 -364.463343)
			(xy 290.01829 -364.456619) (xy 290.043362 -364.456218) (xy 290.068432 -364.456634) (xy 290.118115 -364.463387)
			(xy 290.166449 -364.476723) (xy 290.189666 -364.48619) (xy 290.203241 -364.491445) (xy 290.232143 -364.494811)
			(xy 290.260823 -364.4899) (xy 290.286959 -364.477108) (xy 290.308433 -364.457473) (xy 290.316412 -364.445296)
			(xy 290.330981 -364.422165) (xy 290.365824 -364.380044) (xy 290.406447 -364.343465) (xy 290.451978 -364.313214)
			(xy 290.50144 -364.289938) (xy 290.553771 -364.274138) (xy 290.60785 -364.266152) (xy 290.662514 -364.266152)
			(xy 290.716593 -364.274138) (xy 290.768924 -364.289938) (xy 290.818386 -364.313214) (xy 290.863917 -364.343465)
			(xy 290.90454 -364.380044) (xy 290.939383 -364.422165) (xy 290.953952 -364.445296) (xy 290.961849 -364.457539)
			(xy 290.983327 -364.477211) (xy 291.009488 -364.490013) (xy 291.038199 -364.494904) (xy 291.067123 -364.491483)
			(xy 291.080698 -364.48619) (xy 291.103911 -364.476708) (xy 291.152242 -364.463354) (xy 291.201931 -364.456623)
			(xy 291.227002 -364.456218) (xy 291.254319 -364.456686) (xy 291.308365 -364.464677) (xy 291.360665 -364.480472)
			(xy 291.410099 -364.503733) (xy 291.455607 -364.533963) (xy 291.496215 -364.570512) (xy 291.531052 -364.612598)
			(xy 291.559371 -364.659318) (xy 291.57041 -364.68431) (xy 291.575959 -364.69653) (xy 291.592461 -364.717688)
			(xy 291.613901 -364.733822) (xy 291.638801 -364.74382) (xy 291.665445 -364.746992) (xy 291.691997 -364.743119)
			(xy 291.716625 -364.73247) (xy 291.727382 -364.724442) (xy 291.747719 -364.708764) (xy 291.791824 -364.682466)
			(xy 291.839056 -364.662316) (xy 291.888563 -364.648679) (xy 291.939451 -364.641799) (xy 291.965126 -364.641384)
			(xy 291.983145 -364.641606) (xy 292.01902 -364.645039) (xy 292.036754 -364.648242) (xy 292.051967 -364.650546)
			(xy 292.082518 -364.64703) (xy 292.110636 -364.634578) (xy 292.133772 -364.614319) (xy 292.149827 -364.588091)
			(xy 292.154102 -364.573312) (xy 292.161484 -364.546264) (xy 292.183118 -364.494539) (xy 292.212086 -364.446535)
			(xy 292.247764 -364.403285) (xy 292.289385 -364.365719) (xy 292.336054 -364.334645) (xy 292.386766 -364.310733)
			(xy 292.44043 -364.294496) (xy 292.495893 -364.286284) (xy 292.523926 -364.285784) (xy 292.551178 -364.286254)
			(xy 292.605125 -364.294013) (xy 292.65742 -364.309371) (xy 292.706997 -364.332015) (xy 292.752847 -364.361483)
			(xy 292.794036 -364.397176) (xy 292.829728 -364.438368) (xy 292.859194 -364.484219) (xy 292.881835 -364.533797)
			(xy 292.89719 -364.586092) (xy 292.904698 -364.6383) (xy 298.766795 -364.6383) (xy 298.770962 -364.582695)
			(xy 298.783369 -364.528332) (xy 298.80374 -364.476425) (xy 298.831619 -364.428134) (xy 298.866383 -364.384537)
			(xy 298.907257 -364.346608) (xy 298.953327 -364.315194) (xy 299.003564 -364.290997) (xy 299.056846 -364.274557)
			(xy 299.111984 -364.266241) (xy 299.139864 -364.265718) (xy 299.167196 -364.266193) (xy 299.221275 -364.274163)
			(xy 299.273609 -364.289951) (xy 299.323073 -364.313218) (xy 299.368605 -364.343465) (xy 299.409228 -364.380043)
			(xy 299.444068 -364.422164) (xy 299.458634 -364.445296) (xy 299.466548 -364.457527) (xy 299.488021 -364.477199)
			(xy 299.514177 -364.490003) (xy 299.542885 -364.494896) (xy 299.571806 -364.49148) (xy 299.58538 -364.48619)
			(xy 299.608595 -364.476714) (xy 299.656925 -364.463358) (xy 299.706613 -364.456624) (xy 299.731684 -364.456218)
			(xy 299.756753 -364.45666) (xy 299.806435 -364.463402) (xy 299.85477 -364.476727) (xy 299.877988 -364.48619)
			(xy 299.891578 -364.491412) (xy 299.92048 -364.494797) (xy 299.949165 -364.489902) (xy 299.975309 -364.477123)
			(xy 299.996793 -364.457496) (xy 300.004734 -364.445296) (xy 300.019303 -364.422165) (xy 300.054146 -364.380044)
			(xy 300.094769 -364.343465) (xy 300.1403 -364.313214) (xy 300.189762 -364.289938) (xy 300.242093 -364.274138)
			(xy 300.296172 -364.266152) (xy 300.350836 -364.266152) (xy 300.404915 -364.274138) (xy 300.457246 -364.289938)
			(xy 300.506708 -364.313214) (xy 300.552239 -364.343465) (xy 300.592862 -364.380044) (xy 300.627705 -364.422165)
			(xy 300.642274 -364.445296) (xy 300.650245 -364.457486) (xy 300.671703 -364.477157) (xy 300.697843 -364.489967)
			(xy 300.726538 -364.494871) (xy 300.755449 -364.491471) (xy 300.76902 -364.48619) (xy 300.79223 -364.476701)
			(xy 300.840563 -364.46335) (xy 300.890252 -364.456622) (xy 300.915324 -364.456218) (xy 300.942169 -364.456634)
			(xy 300.995301 -364.464342) (xy 301.046778 -364.479596) (xy 301.095533 -364.50208) (xy 301.140556 -364.531328)
			(xy 301.180915 -364.566735) (xy 301.215776 -364.607567) (xy 301.244415 -364.65298) (xy 301.266241 -364.702032)
			(xy 301.273972 -364.727744) (xy 301.27869 -364.742221) (xy 301.295197 -364.767781) (xy 301.318501 -364.787346)
			(xy 301.346533 -364.799179) (xy 301.376807 -364.80223) (xy 301.406637 -364.796229) (xy 301.420276 -364.789466)
			(xy 301.448418 -364.774824) (xy 301.508371 -364.7541) (xy 301.570931 -364.743605) (xy 301.602648 -364.742984)
			(xy 301.620667 -364.743202) (xy 301.656542 -364.746638) (xy 301.674276 -364.749842) (xy 301.689487 -364.752168)
			(xy 301.720039 -364.748646) (xy 301.748159 -364.736189) (xy 301.771295 -364.715925) (xy 301.787349 -364.689693)
			(xy 301.791624 -364.674912) (xy 301.798986 -364.647858) (xy 301.820622 -364.596131) (xy 301.849592 -364.548127)
			(xy 301.885273 -364.504876) (xy 301.926896 -364.46731) (xy 301.973568 -364.436238) (xy 302.024282 -364.412327)
			(xy 302.077949 -364.396092) (xy 302.133414 -364.387882) (xy 302.161448 -364.387384) (xy 302.1887 -364.387833)
			(xy 302.242649 -364.395596) (xy 302.294944 -364.410957) (xy 302.34452 -364.433603) (xy 302.39037 -364.463073)
			(xy 302.43156 -364.498769) (xy 302.467251 -364.539962) (xy 302.496716 -364.585815) (xy 302.519357 -364.635394)
			(xy 302.534713 -364.68769) (xy 302.54247 -364.74164) (xy 302.542956 -364.768892) (xy 302.5425 -364.796467)
			(xy 302.534548 -364.851041) (xy 302.518822 -364.903902) (xy 302.49565 -364.953948) (xy 302.465515 -365.000137)
			(xy 302.429045 -365.041507) (xy 302.408336 -365.059722) (xy 302.397444 -365.069627) (xy 302.381366 -365.094274)
			(xy 302.372978 -365.122481) (xy 302.372977 -365.151909) (xy 302.381361 -365.180116) (xy 302.397437 -365.204765)
			(xy 302.408336 -365.214662) (xy 302.429032 -365.232888) (xy 302.465492 -365.274259) (xy 302.495616 -365.320449)
			(xy 302.518776 -365.370494) (xy 302.53449 -365.423352) (xy 302.54243 -365.477922) (xy 302.542431 -365.533067)
			(xy 302.534492 -365.587637) (xy 302.51878 -365.640496) (xy 302.495621 -365.690542) (xy 302.465498 -365.736733)
			(xy 302.429039 -365.778105) (xy 302.408336 -365.796322) (xy 302.397444 -365.806227) (xy 302.381366 -365.830874)
			(xy 302.372978 -365.859081) (xy 302.372977 -365.888509) (xy 302.381361 -365.916716) (xy 302.397437 -365.941365)
			(xy 302.408336 -365.951262) (xy 302.429039 -365.969482) (xy 302.465509 -366.010849) (xy 302.495641 -366.057038)
			(xy 302.518808 -366.107084) (xy 302.534526 -366.159945) (xy 302.542469 -366.214518) (xy 302.542956 -366.242092)
			(xy 302.542415 -366.269341) (xy 302.534661 -366.323284) (xy 302.519309 -366.375575) (xy 302.496672 -366.425149)
			(xy 302.467211 -366.470997) (xy 302.431526 -366.512186) (xy 302.390342 -366.547878) (xy 302.344498 -366.577345)
			(xy 302.294927 -366.599989) (xy 302.242639 -366.615349) (xy 302.188697 -366.623111) (xy 302.161448 -366.6236)
			(xy 302.133594 -366.623034) (xy 302.07848 -366.614917) (xy 302.025131 -366.598878) (xy 301.974679 -366.575257)
			(xy 301.928194 -366.544555) (xy 301.886664 -366.507425) (xy 301.85097 -366.464655) (xy 301.82187 -366.417151)
			(xy 301.799981 -366.365923) (xy 301.792386 -366.33912) (xy 301.788085 -366.325013) (xy 301.772701 -366.29987)
			(xy 301.75079 -366.280153) (xy 301.724168 -366.2675) (xy 301.695043 -366.262958) (xy 301.680372 -366.264444)
			(xy 301.667356 -366.266114) (xy 301.641171 -366.267893) (xy 301.628048 -366.268) (xy 301.613899 -366.267901)
			(xy 301.585676 -366.26587) (xy 301.57166 -366.263936) (xy 301.558312 -366.262339) (xy 301.531617 -366.265436)
			(xy 301.506661 -366.275405) (xy 301.485179 -366.291553) (xy 301.468668 -366.312756) (xy 301.458275 -366.337539)
			(xy 301.45609 -366.350804) (xy 301.451996 -366.377957) (xy 301.437027 -366.430789) (xy 301.414638 -366.480929)
			(xy 301.385293 -366.527342) (xy 301.349596 -366.569067) (xy 301.308286 -366.605245) (xy 301.262217 -366.635126)
			(xy 301.21234 -366.658094) (xy 301.159685 -366.673674) (xy 301.10534 -366.681544) (xy 301.077884 -366.68202)
			(xy 301.050633 -366.681537) (xy 300.996686 -366.673779) (xy 300.944392 -366.658422) (xy 300.894815 -366.63578)
			(xy 300.848965 -366.606313) (xy 300.807776 -366.570622) (xy 300.772084 -366.529431) (xy 300.742618 -366.483581)
			(xy 300.719976 -366.434005) (xy 300.70462 -366.38171) (xy 300.696863 -366.327763) (xy 300.696376 -366.300512)
			(xy 300.696858 -366.272938) (xy 300.704809 -366.218366) (xy 300.720531 -366.165507) (xy 300.743698 -366.115461)
			(xy 300.773827 -366.069271) (xy 300.810291 -366.027899) (xy 300.830996 -366.009682) (xy 300.841881 -365.999771)
			(xy 300.857954 -365.975124) (xy 300.866339 -365.94692) (xy 300.866342 -365.917495) (xy 300.857961 -365.88929)
			(xy 300.841891 -365.864641) (xy 300.830996 -365.854742) (xy 300.810301 -365.836513) (xy 300.77383 -365.795148)
			(xy 300.743696 -365.748962) (xy 300.720527 -365.698917) (xy 300.704807 -365.646058) (xy 300.696864 -365.591486)
			(xy 300.696376 -365.563912) (xy 300.69686 -365.537412) (xy 300.704199 -365.484922) (xy 300.718737 -365.433955)
			(xy 300.740193 -365.385492) (xy 300.768154 -365.340468) (xy 300.784768 -365.319818) (xy 300.79424 -365.307695)
			(xy 300.806022 -365.279286) (xy 300.808838 -365.248661) (xy 300.802436 -365.218581) (xy 300.787392 -365.191757)
			(xy 300.765062 -365.170609) (xy 300.751494 -365.163354) (xy 300.727822 -365.15122) (xy 300.683837 -365.121307)
			(xy 300.644551 -365.085446) (xy 300.610762 -365.044364) (xy 300.596554 -365.021876) (xy 300.588658 -365.009633)
			(xy 300.567178 -364.989964) (xy 300.541017 -364.977164) (xy 300.512307 -364.972273) (xy 300.483383 -364.975691)
			(xy 300.469808 -364.980982) (xy 300.446594 -364.99046) (xy 300.398263 -365.003816) (xy 300.348575 -365.010548)
			(xy 300.323504 -365.010954) (xy 300.298435 -365.010518) (xy 300.248752 -365.003774) (xy 300.200418 -364.990446)
			(xy 300.1772 -364.980982) (xy 300.163598 -364.975809) (xy 300.13471 -364.972429) (xy 300.106041 -364.977324)
			(xy 300.079911 -364.990095) (xy 300.058436 -365.009709) (xy 300.050454 -365.021876) (xy 300.035885 -365.045007)
			(xy 300.001042 -365.087128) (xy 299.960419 -365.123707) (xy 299.914888 -365.153958) (xy 299.865426 -365.177234)
			(xy 299.813095 -365.193034) (xy 299.759016 -365.20102) (xy 299.704352 -365.20102) (xy 299.650273 -365.193034)
			(xy 299.597942 -365.177234) (xy 299.54848 -365.153958) (xy 299.502949 -365.123707) (xy 299.462326 -365.087128)
			(xy 299.427483 -365.045007) (xy 299.412914 -365.021876) (xy 299.404961 -365.009674) (xy 299.383497 -364.990005)
			(xy 299.357351 -364.977199) (xy 299.328654 -364.972298) (xy 299.299741 -364.9757) (xy 299.286168 -364.980982)
			(xy 299.262959 -364.990473) (xy 299.214626 -365.003824) (xy 299.164936 -365.010551) (xy 299.139864 -365.010954)
			(xy 299.111984 -365.010359) (xy 299.056846 -365.002043) (xy 299.003564 -364.985603) (xy 298.953327 -364.961406)
			(xy 298.907257 -364.929992) (xy 298.866383 -364.892063) (xy 298.831619 -364.848466) (xy 298.80374 -364.800175)
			(xy 298.783369 -364.748268) (xy 298.770962 -364.693905) (xy 298.766795 -364.6383) (xy 292.904698 -364.6383)
			(xy 292.904948 -364.64004) (xy 292.905434 -364.667292) (xy 292.904986 -364.694867) (xy 292.897033 -364.749442)
			(xy 292.881306 -364.802303) (xy 292.858133 -364.85235) (xy 292.827996 -364.898539) (xy 292.791524 -364.939908)
			(xy 292.770814 -364.958122) (xy 292.759924 -364.968028) (xy 292.743849 -364.992676) (xy 292.735464 -365.020882)
			(xy 292.735462 -365.050308) (xy 292.743845 -365.078515) (xy 292.759917 -365.103164) (xy 292.770814 -365.113062)
			(xy 292.791511 -365.131287) (xy 292.827973 -365.172658) (xy 292.858099 -365.218847) (xy 292.88126 -365.268892)
			(xy 292.896975 -365.321751) (xy 292.904916 -365.376322) (xy 292.904916 -365.431468) (xy 292.896977 -365.486038)
			(xy 292.881264 -365.538898) (xy 292.858104 -365.588944) (xy 292.827979 -365.635134) (xy 292.791518 -365.676506)
			(xy 292.770814 -365.694722) (xy 292.760482 -365.70412) (xy 295.309034 -365.70412) (xy 295.313105 -365.648498)
			(xy 295.325231 -365.594061) (xy 295.345154 -365.54197) (xy 295.37245 -365.493335) (xy 295.406536 -365.449192)
			(xy 295.446685 -365.410483) (xy 295.492043 -365.378032) (xy 295.541643 -365.352531) (xy 295.594427 -365.334524)
			(xy 295.64927 -365.324394) (xy 295.705004 -365.322357) (xy 295.760441 -365.328457) (xy 295.814398 -365.342563)
			(xy 295.865727 -365.364375) (xy 295.913333 -365.393429) (xy 295.956201 -365.429104) (xy 295.993418 -365.470641)
			(xy 296.024191 -365.517154) (xy 296.047863 -365.567651) (xy 296.063931 -365.621058) (xy 296.072051 -365.676234)
			(xy 296.07256 -365.70412) (xy 296.072051 -365.732006) (xy 296.063931 -365.787182) (xy 296.047863 -365.840589)
			(xy 296.024191 -365.891086) (xy 295.993418 -365.937599) (xy 295.956201 -365.979136) (xy 295.913333 -366.014811)
			(xy 295.865727 -366.043865) (xy 295.814398 -366.065677) (xy 295.760441 -366.079783) (xy 295.705004 -366.085883)
			(xy 295.64927 -366.083846) (xy 295.594427 -366.073716) (xy 295.541643 -366.055709) (xy 295.492043 -366.030208)
			(xy 295.446685 -365.997757) (xy 295.406536 -365.959048) (xy 295.37245 -365.914905) (xy 295.345154 -365.86627)
			(xy 295.325231 -365.814179) (xy 295.313105 -365.759742) (xy 295.309034 -365.70412) (xy 292.760482 -365.70412)
			(xy 292.759924 -365.704628) (xy 292.743849 -365.729276) (xy 292.735464 -365.757482) (xy 292.735462 -365.786908)
			(xy 292.743845 -365.815115) (xy 292.759917 -365.839764) (xy 292.770814 -365.849662) (xy 292.791513 -365.867886)
			(xy 292.827983 -365.909253) (xy 292.858117 -365.95544) (xy 292.881285 -366.005485) (xy 292.897004 -366.058345)
			(xy 292.904947 -366.112918) (xy 292.905434 -366.140492) (xy 292.904915 -366.167742) (xy 292.89716 -366.221687)
			(xy 292.881807 -366.27398) (xy 292.859169 -366.323555) (xy 292.829706 -366.369404) (xy 292.794018 -366.410594)
			(xy 292.752832 -366.446286) (xy 292.706985 -366.475753) (xy 292.657412 -366.498395) (xy 292.60512 -366.513753)
			(xy 292.551176 -366.521512) (xy 292.523926 -366.522) (xy 292.496072 -366.521453) (xy 292.440957 -366.513334)
			(xy 292.387607 -366.497291) (xy 292.337155 -366.473668) (xy 292.29067 -366.442964) (xy 292.24914 -366.405831)
			(xy 292.213447 -366.363059) (xy 292.184347 -366.315553) (xy 292.162459 -366.264324) (xy 292.154864 -366.23752)
			(xy 292.150585 -366.223406) (xy 292.135197 -366.19826) (xy 292.11328 -366.178543) (xy 292.086652 -366.165892)
			(xy 292.057523 -366.161355) (xy 292.04285 -366.162844) (xy 292.029834 -366.164516) (xy 292.003649 -366.166294)
			(xy 291.990526 -366.1664) (xy 291.966978 -366.166093) (xy 291.920234 -366.160356) (xy 291.897308 -366.15497)
			(xy 291.884306 -366.152198) (xy 291.857736 -366.152613) (xy 291.832177 -366.159878) (xy 291.809361 -366.1735)
			(xy 291.79084 -366.192554) (xy 291.77787 -366.215746) (xy 291.771332 -366.241501) (xy 291.77107 -366.254792)
			(xy 291.77107 -366.259872) (xy 291.770584 -366.287123) (xy 291.762828 -366.341071) (xy 291.747473 -366.393366)
			(xy 291.724831 -366.442943) (xy 291.695365 -366.488793) (xy 291.659674 -366.529984) (xy 291.618483 -366.565675)
			(xy 291.572633 -366.595141) (xy 291.523056 -366.617783) (xy 291.470761 -366.633138) (xy 291.416813 -366.640894)
			(xy 291.362311 -366.640894) (xy 291.308363 -366.633138) (xy 291.256068 -366.617783) (xy 291.206491 -366.595141)
			(xy 291.160641 -366.565675) (xy 291.11945 -366.529984) (xy 291.083759 -366.488793) (xy 291.054293 -366.442943)
			(xy 291.031651 -366.393366) (xy 291.016296 -366.341071) (xy 291.00854 -366.287123) (xy 291.008054 -366.259872)
			(xy 291.00855 -366.232298) (xy 291.016494 -366.177726) (xy 291.032212 -366.124866) (xy 291.055376 -366.074819)
			(xy 291.085504 -366.028629) (xy 291.121968 -365.987258) (xy 291.142674 -365.969042) (xy 291.153601 -365.959173)
			(xy 291.169676 -365.934515) (xy 291.178059 -365.906299) (xy 291.178054 -365.876865) (xy 291.169661 -365.848652)
			(xy 291.153577 -365.824) (xy 291.142674 -365.814102) (xy 291.121955 -365.795899) (xy 291.085487 -365.754528)
			(xy 291.055356 -365.708336) (xy 291.032192 -365.658287) (xy 291.016477 -365.605423) (xy 291.008539 -365.550847)
			(xy 291.008054 -365.523272) (xy 291.008619 -365.493749) (xy 291.017752 -365.435413) (xy 291.035766 -365.379181)
			(xy 291.062229 -365.326397) (xy 291.07892 -365.302038) (xy 291.08686 -365.290159) (xy 291.096379 -365.263229)
			(xy 291.098067 -365.234716) (xy 291.09179 -365.206852) (xy 291.078041 -365.181816) (xy 291.057895 -365.161568)
			(xy 291.045646 -365.15421) (xy 291.024749 -365.14215) (xy 290.985971 -365.113443) (xy 290.951219 -365.079973)
			(xy 290.921074 -365.042301) (xy 290.908232 -365.021876) (xy 290.900357 -365.009618) (xy 290.878871 -364.989949)
			(xy 290.852705 -364.977151) (xy 290.823989 -364.972264) (xy 290.795062 -364.975688) (xy 290.781486 -364.980982)
			(xy 290.758274 -364.990467) (xy 290.709942 -365.00382) (xy 290.660253 -365.01055) (xy 290.635182 -365.010954)
			(xy 290.610113 -365.010525) (xy 290.56043 -365.003778) (xy 290.512095 -364.990447) (xy 290.488878 -364.980982)
			(xy 290.475284 -364.975785) (xy 290.446392 -364.972411) (xy 290.41772 -364.977311) (xy 290.391589 -364.990088)
			(xy 290.370114 -365.009707) (xy 290.362132 -365.021876) (xy 290.347563 -365.045007) (xy 290.31272 -365.087128)
			(xy 290.272097 -365.123707) (xy 290.226566 -365.153958) (xy 290.177104 -365.177234) (xy 290.124773 -365.193034)
			(xy 290.070694 -365.20102) (xy 290.01603 -365.20102) (xy 289.961951 -365.193034) (xy 289.90962 -365.177234)
			(xy 289.860158 -365.153958) (xy 289.814627 -365.123707) (xy 289.774004 -365.087128) (xy 289.739161 -365.045007)
			(xy 289.724592 -365.021876) (xy 289.71666 -365.009659) (xy 289.69519 -364.98999) (xy 289.669039 -364.977186)
			(xy 289.640337 -364.972289) (xy 289.61142 -364.975697) (xy 289.597846 -364.980982) (xy 289.574639 -364.99048)
			(xy 289.526305 -365.003828) (xy 289.476614 -365.010553) (xy 289.451542 -365.010954) (xy 289.423656 -365.01039)
			(xy 289.368506 -365.002083) (xy 289.31521 -364.985649) (xy 289.264959 -364.961454) (xy 289.218876 -364.93004)
			(xy 289.17799 -364.892108) (xy 289.143215 -364.848505) (xy 289.115327 -364.800206) (xy 289.094949 -364.74829)
			(xy 289.082538 -364.693916) (xy 289.07837 -364.6383) (xy 283.807717 -364.6383) (xy 283.807717 -364.652353)
			(xy 283.799959 -364.706303) (xy 283.784602 -364.7586) (xy 283.761959 -364.808179) (xy 283.732489 -364.854031)
			(xy 283.696794 -364.895221) (xy 283.6556 -364.930912) (xy 283.609746 -364.960377) (xy 283.560164 -364.983016)
			(xy 283.507866 -364.998367) (xy 283.453915 -365.006119) (xy 283.426662 -365.006636) (xy 283.39896 -365.006165)
			(xy 283.344134 -364.998196) (xy 283.291039 -364.982372) (xy 283.240794 -364.959028) (xy 283.194459 -364.928655)
			(xy 283.173424 -364.910624) (xy 283.162178 -364.901306) (xy 283.135736 -364.888932) (xy 283.106874 -364.884542)
			(xy 283.077949 -364.888494) (xy 283.051323 -364.900466) (xy 283.02917 -364.919479) (xy 283.013298 -364.943982)
			(xy 283.005006 -364.971974) (xy 283.004514 -364.98657) (xy 283.004514 -365.70412) (xy 285.620712 -365.70412)
			(xy 285.624783 -365.648498) (xy 285.636909 -365.594061) (xy 285.656832 -365.54197) (xy 285.684128 -365.493335)
			(xy 285.718214 -365.449192) (xy 285.758363 -365.410483) (xy 285.803721 -365.378032) (xy 285.853321 -365.352531)
			(xy 285.906105 -365.334524) (xy 285.960948 -365.324394) (xy 286.016682 -365.322357) (xy 286.072119 -365.328457)
			(xy 286.126076 -365.342563) (xy 286.177405 -365.364375) (xy 286.225011 -365.393429) (xy 286.267879 -365.429104)
			(xy 286.305096 -365.470641) (xy 286.335869 -365.517154) (xy 286.359541 -365.567651) (xy 286.375609 -365.621058)
			(xy 286.383729 -365.676234) (xy 286.384238 -365.70412) (xy 286.383729 -365.732006) (xy 286.375609 -365.787182)
			(xy 286.359541 -365.840589) (xy 286.335869 -365.891086) (xy 286.305096 -365.937599) (xy 286.267879 -365.979136)
			(xy 286.225011 -366.014811) (xy 286.177405 -366.043865) (xy 286.126076 -366.065677) (xy 286.072119 -366.079783)
			(xy 286.016682 -366.085883) (xy 285.960948 -366.083846) (xy 285.906105 -366.073716) (xy 285.853321 -366.055709)
			(xy 285.803721 -366.030208) (xy 285.758363 -365.997757) (xy 285.718214 -365.959048) (xy 285.684128 -365.914905)
			(xy 285.656832 -365.86627) (xy 285.636909 -365.814179) (xy 285.624783 -365.759742) (xy 285.620712 -365.70412)
			(xy 283.004514 -365.70412) (xy 283.004514 -366.670082) (xy 284.956248 -366.670082) (xy 284.960319 -366.61446)
			(xy 284.972445 -366.560023) (xy 284.992368 -366.507932) (xy 285.019664 -366.459297) (xy 285.05375 -366.415154)
			(xy 285.093899 -366.376445) (xy 285.139257 -366.343994) (xy 285.188857 -366.318493) (xy 285.241641 -366.300486)
			(xy 285.296484 -366.290356) (xy 285.352218 -366.288319) (xy 285.407655 -366.294419) (xy 285.461612 -366.308525)
			(xy 285.512941 -366.330337) (xy 285.560547 -366.359391) (xy 285.603415 -366.395066) (xy 285.640632 -366.436603)
			(xy 285.671405 -366.483116) (xy 285.695077 -366.533613) (xy 285.711145 -366.58702) (xy 285.719265 -366.642196)
			(xy 285.719774 -366.670082) (xy 285.719265 -366.697968) (xy 285.711145 -366.753144) (xy 285.695077 -366.806551)
			(xy 285.671405 -366.857048) (xy 285.640632 -366.903561) (xy 285.603415 -366.945098) (xy 285.560547 -366.980773)
			(xy 285.512941 -367.009827) (xy 285.461612 -367.031639) (xy 285.407655 -367.045745) (xy 285.352218 -367.051845)
			(xy 285.296484 -367.049808) (xy 285.241641 -367.039678) (xy 285.188857 -367.021671) (xy 285.139257 -366.99617)
			(xy 285.093899 -366.963719) (xy 285.05375 -366.92501) (xy 285.019664 -366.880867) (xy 284.992368 -366.832232)
			(xy 284.972445 -366.780141) (xy 284.960319 -366.725704) (xy 284.956248 -366.670082) (xy 283.004514 -366.670082)
			(xy 283.004514 -367.212626) (xy 286.427418 -367.212626) (xy 286.427844 -367.187288) (xy 286.43455 -367.137057)
			(xy 286.447848 -367.088157) (xy 286.467504 -367.041447) (xy 286.493171 -366.997752) (xy 286.524398 -366.95784)
			(xy 286.542226 -366.93983) (xy 286.5517 -366.930126) (xy 286.565495 -366.906784) (xy 286.572642 -366.880629)
			(xy 286.572634 -366.853515) (xy 286.565473 -366.827364) (xy 286.551665 -366.804029) (xy 286.542226 -366.794288)
			(xy 286.524397 -366.776279) (xy 286.493168 -366.736367) (xy 286.467499 -366.692672) (xy 286.447841 -366.645963)
			(xy 286.434541 -366.597062) (xy 286.427832 -366.546831) (xy 286.427418 -366.521492) (xy 286.427904 -366.494241)
			(xy 286.43566 -366.440293) (xy 286.451015 -366.387998) (xy 286.473657 -366.338421) (xy 286.503123 -366.292571)
			(xy 286.538814 -366.25138) (xy 286.580005 -366.215689) (xy 286.625855 -366.186223) (xy 286.675432 -366.163581)
			(xy 286.727727 -366.148226) (xy 286.781675 -366.14047) (xy 286.836177 -366.14047) (xy 286.890125 -366.148226)
			(xy 286.94242 -366.163581) (xy 286.991997 -366.186223) (xy 287.037847 -366.215689) (xy 287.079038 -366.25138)
			(xy 287.114729 -366.292571) (xy 287.144195 -366.338421) (xy 287.166837 -366.387998) (xy 287.182192 -366.440293)
			(xy 287.189948 -366.494241) (xy 287.190094 -366.502442) (xy 288.052764 -366.502442) (xy 288.05325 -366.475191)
			(xy 288.061006 -366.421243) (xy 288.076361 -366.368948) (xy 288.099003 -366.319371) (xy 288.128469 -366.273521)
			(xy 288.16416 -366.23233) (xy 288.205351 -366.196639) (xy 288.251201 -366.167173) (xy 288.300778 -366.144531)
			(xy 288.353073 -366.129176) (xy 288.407021 -366.12142) (xy 288.461523 -366.12142) (xy 288.515471 -366.129176)
			(xy 288.567766 -366.144531) (xy 288.617343 -366.167173) (xy 288.663193 -366.196639) (xy 288.704384 -366.23233)
			(xy 288.740075 -366.273521) (xy 288.769541 -366.319371) (xy 288.792183 -366.368948) (xy 288.807538 -366.421243)
			(xy 288.815294 -366.475191) (xy 288.81578 -366.502442) (xy 288.815548 -366.521109) (xy 288.811855 -366.558261)
			(xy 288.808414 -366.57661) (xy 288.806165 -366.590889) (xy 288.808676 -366.619667) (xy 288.819156 -366.646586)
			(xy 288.836762 -366.669487) (xy 288.853909 -366.68202) (xy 294.64457 -366.68202) (xy 294.648641 -366.626398)
			(xy 294.660767 -366.571961) (xy 294.68069 -366.51987) (xy 294.707986 -366.471235) (xy 294.742072 -366.427092)
			(xy 294.782221 -366.388383) (xy 294.827579 -366.355932) (xy 294.877179 -366.330431) (xy 294.929963 -366.312424)
			(xy 294.984806 -366.302294) (xy 295.04054 -366.300257) (xy 295.095977 -366.306357) (xy 295.149934 -366.320463)
			(xy 295.201263 -366.342275) (xy 295.248869 -366.371329) (xy 295.291737 -366.407004) (xy 295.328954 -366.448541)
			(xy 295.359727 -366.495054) (xy 295.383399 -366.545551) (xy 295.399467 -366.598958) (xy 295.407587 -366.654134)
			(xy 295.408096 -366.68202) (xy 295.407587 -366.709906) (xy 295.399467 -366.765082) (xy 295.383399 -366.818489)
			(xy 295.359727 -366.868986) (xy 295.328954 -366.915499) (xy 295.291737 -366.957036) (xy 295.248869 -366.992711)
			(xy 295.201263 -367.021765) (xy 295.149934 -367.043577) (xy 295.095977 -367.057683) (xy 295.04054 -367.063783)
			(xy 294.984806 -367.061746) (xy 294.929963 -367.051616) (xy 294.877179 -367.033609) (xy 294.827579 -367.008108)
			(xy 294.782221 -366.975657) (xy 294.742072 -366.936948) (xy 294.707986 -366.892805) (xy 294.68069 -366.84417)
			(xy 294.660767 -366.792079) (xy 294.648641 -366.737642) (xy 294.64457 -366.68202) (xy 288.853909 -366.68202)
			(xy 288.860084 -366.686533) (xy 288.887249 -366.696356) (xy 288.901632 -366.697768) (xy 288.930291 -366.700084)
			(xy 288.98646 -366.712378) (xy 289.040148 -366.732959) (xy 289.090142 -366.761361) (xy 289.135308 -366.796943)
			(xy 289.174624 -366.838898) (xy 289.207202 -366.886277) (xy 289.232302 -366.938007) (xy 289.249357 -366.992917)
			(xy 289.257982 -367.049765) (xy 289.258502 -367.078514) (xy 289.258016 -367.105765) (xy 289.25026 -367.159713)
			(xy 289.234905 -367.212008) (xy 289.212263 -367.261585) (xy 289.203734 -367.274856) (xy 296.11574 -367.274856)
			(xy 296.116241 -367.246409) (xy 296.124701 -367.190149) (xy 296.141428 -367.13577) (xy 296.166048 -367.084479)
			(xy 296.198017 -367.037417) (xy 296.236624 -366.995627) (xy 296.258488 -366.977422) (xy 296.269983 -366.967503)
			(xy 296.287 -366.942374) (xy 296.295897 -366.913358) (xy 296.295892 -366.883009) (xy 296.286985 -366.853997)
			(xy 296.269961 -366.828873) (xy 296.258488 -366.818926) (xy 296.236618 -366.800728) (xy 296.198016 -366.758936)
			(xy 296.166053 -366.711871) (xy 296.141438 -366.660579) (xy 296.124719 -366.606199) (xy 296.116266 -366.549938)
			(xy 296.11574 -366.521492) (xy 296.116226 -366.494241) (xy 296.123982 -366.440293) (xy 296.139337 -366.387998)
			(xy 296.161979 -366.338421) (xy 296.191445 -366.292571) (xy 296.227136 -366.25138) (xy 296.268327 -366.215689)
			(xy 296.314177 -366.186223) (xy 296.363754 -366.163581) (xy 296.416049 -366.148226) (xy 296.469997 -366.14047)
			(xy 296.524499 -366.14047) (xy 296.578447 -366.148226) (xy 296.630742 -366.163581) (xy 296.680319 -366.186223)
			(xy 296.726169 -366.215689) (xy 296.76736 -366.25138) (xy 296.803051 -366.292571) (xy 296.832517 -366.338421)
			(xy 296.855159 -366.387998) (xy 296.870514 -366.440293) (xy 296.87827 -366.494241) (xy 296.878416 -366.502442)
			(xy 297.741086 -366.502442) (xy 297.741572 -366.475191) (xy 297.749328 -366.421243) (xy 297.764683 -366.368948)
			(xy 297.787325 -366.319371) (xy 297.816791 -366.273521) (xy 297.852482 -366.23233) (xy 297.893673 -366.196639)
			(xy 297.939523 -366.167173) (xy 297.9891 -366.144531) (xy 298.041395 -366.129176) (xy 298.095343 -366.12142)
			(xy 298.149845 -366.12142) (xy 298.203793 -366.129176) (xy 298.256088 -366.144531) (xy 298.305665 -366.167173)
			(xy 298.351515 -366.196639) (xy 298.392706 -366.23233) (xy 298.428397 -366.273521) (xy 298.457863 -366.319371)
			(xy 298.480505 -366.368948) (xy 298.49586 -366.421243) (xy 298.503616 -366.475191) (xy 298.504102 -366.502442)
			(xy 298.503863 -366.521109) (xy 298.50017 -366.55826) (xy 298.496736 -366.57661) (xy 298.494466 -366.590887)
			(xy 298.496978 -366.619669) (xy 298.50746 -366.646591) (xy 298.525071 -366.669494) (xy 298.548398 -366.686539)
			(xy 298.575569 -366.696359) (xy 298.589954 -366.697768) (xy 298.618607 -366.700151) (xy 298.674774 -366.712433)
			(xy 298.728462 -366.733004) (xy 298.778456 -366.761398) (xy 298.823623 -366.796971) (xy 298.862942 -366.83892)
			(xy 298.895521 -366.886292) (xy 298.920622 -366.938017) (xy 298.937679 -366.992923) (xy 298.946304 -367.049767)
			(xy 298.946824 -367.078514) (xy 298.946338 -367.105765) (xy 298.938582 -367.159713) (xy 298.923227 -367.212008)
			(xy 298.900585 -367.261585) (xy 298.871119 -367.307435) (xy 298.835428 -367.348626) (xy 298.794237 -367.384317)
			(xy 298.748387 -367.413783) (xy 298.69881 -367.436425) (xy 298.646515 -367.45178) (xy 298.592567 -367.459536)
			(xy 298.538065 -367.459536) (xy 298.484117 -367.45178) (xy 298.431822 -367.436425) (xy 298.382245 -367.413783)
			(xy 298.336395 -367.384317) (xy 298.295204 -367.348626) (xy 298.259513 -367.307435) (xy 298.230047 -367.261585)
			(xy 298.207405 -367.212008) (xy 298.19205 -367.159713) (xy 298.184294 -367.105765) (xy 298.183808 -367.078514)
			(xy 298.184048 -367.059847) (xy 298.187736 -367.022695) (xy 298.191174 -367.004346) (xy 298.193481 -366.990074)
			(xy 298.190958 -366.96129) (xy 298.180467 -366.934367) (xy 298.16285 -366.911464) (xy 298.139518 -366.894419)
			(xy 298.112343 -366.884598) (xy 298.097956 -366.883188) (xy 298.069302 -366.880827) (xy 298.013138 -366.868534)
			(xy 297.959454 -366.847956) (xy 297.909464 -366.819557) (xy 297.864299 -366.78398) (xy 297.824983 -366.742031)
			(xy 297.792405 -366.694658) (xy 297.767301 -366.642935) (xy 297.750241 -366.588031) (xy 297.74161 -366.531189)
			(xy 297.741086 -366.502442) (xy 296.878416 -366.502442) (xy 296.878756 -366.521492) (xy 296.87822 -366.549937)
			(xy 296.869767 -366.606197) (xy 296.853048 -366.660575) (xy 296.828434 -366.711865) (xy 296.796471 -366.758929)
			(xy 296.75787 -366.80072) (xy 296.736008 -366.818926) (xy 296.724565 -366.8289) (xy 296.707548 -366.854015)
			(xy 296.698646 -366.883016) (xy 296.698641 -366.913352) (xy 296.707534 -366.942356) (xy 296.724543 -366.967475)
			(xy 296.736008 -366.977422) (xy 296.757852 -366.995649) (xy 296.796456 -367.037436) (xy 296.828422 -367.084494)
			(xy 296.853041 -367.13578) (xy 296.869766 -367.190155) (xy 296.878226 -367.246412) (xy 296.878756 -367.274856)
			(xy 296.87827 -367.302107) (xy 296.870514 -367.356055) (xy 296.855159 -367.40835) (xy 296.832517 -367.457927)
			(xy 296.803051 -367.503777) (xy 296.76736 -367.544968) (xy 296.726169 -367.580659) (xy 296.680319 -367.610125)
			(xy 296.630742 -367.632767) (xy 296.578447 -367.648122) (xy 296.524499 -367.655878) (xy 296.469997 -367.655878)
			(xy 296.416049 -367.648122) (xy 296.363754 -367.632767) (xy 296.314177 -367.610125) (xy 296.268327 -367.580659)
			(xy 296.227136 -367.544968) (xy 296.191445 -367.503777) (xy 296.161979 -367.457927) (xy 296.139337 -367.40835)
			(xy 296.123982 -367.356055) (xy 296.116226 -367.302107) (xy 296.11574 -367.274856) (xy 289.203734 -367.274856)
			(xy 289.182797 -367.307435) (xy 289.147106 -367.348626) (xy 289.105915 -367.384317) (xy 289.060065 -367.413783)
			(xy 289.010488 -367.436425) (xy 288.958193 -367.45178) (xy 288.904245 -367.459536) (xy 288.849743 -367.459536)
			(xy 288.795795 -367.45178) (xy 288.7435 -367.436425) (xy 288.693923 -367.413783) (xy 288.648073 -367.384317)
			(xy 288.606882 -367.348626) (xy 288.571191 -367.307435) (xy 288.541725 -367.261585) (xy 288.519083 -367.212008)
			(xy 288.503728 -367.159713) (xy 288.495972 -367.105765) (xy 288.495486 -367.078514) (xy 288.495734 -367.059847)
			(xy 288.499421 -367.022696) (xy 288.502852 -367.004346) (xy 288.505179 -366.990076) (xy 288.502656 -366.961288)
			(xy 288.492163 -366.934361) (xy 288.474541 -366.911457) (xy 288.451204 -366.894413) (xy 288.424024 -366.884595)
			(xy 288.409634 -366.883188) (xy 288.380986 -366.88076) (xy 288.324824 -366.868479) (xy 288.27114 -366.84791)
			(xy 288.221149 -366.81952) (xy 288.175984 -366.783951) (xy 288.136666 -366.742009) (xy 288.104086 -366.694643)
			(xy 288.078981 -366.642924) (xy 288.06192 -366.588025) (xy 288.053288 -366.531187) (xy 288.052764 -366.502442)
			(xy 287.190094 -366.502442) (xy 287.190434 -366.521492) (xy 287.190004 -366.54683) (xy 287.183297 -366.59706)
			(xy 287.169998 -366.64596) (xy 287.150343 -366.692669) (xy 287.124677 -366.736364) (xy 287.093453 -366.776278)
			(xy 287.075626 -366.794288) (xy 287.066284 -366.80409) (xy 287.052572 -366.827425) (xy 287.045463 -366.853539)
			(xy 287.045456 -366.880604) (xy 287.05255 -366.906722) (xy 287.066249 -366.930064) (xy 287.075626 -366.93983)
			(xy 287.093474 -366.957822) (xy 287.124698 -366.997738) (xy 287.150364 -367.041438) (xy 287.170018 -367.08815)
			(xy 287.183315 -367.137053) (xy 287.190021 -367.187287) (xy 287.190314 -367.20526) (xy 287.443418 -367.20526)
			(xy 287.443904 -367.178009) (xy 287.45166 -367.124061) (xy 287.467015 -367.071766) (xy 287.489657 -367.022189)
			(xy 287.519123 -366.976339) (xy 287.554814 -366.935148) (xy 287.596005 -366.899457) (xy 287.641855 -366.869991)
			(xy 287.691432 -366.847349) (xy 287.743727 -366.831994) (xy 287.797675 -366.824238) (xy 287.852177 -366.824238)
			(xy 287.906125 -366.831994) (xy 287.95842 -366.847349) (xy 288.007997 -366.869991) (xy 288.053847 -366.899457)
			(xy 288.095038 -366.935148) (xy 288.130729 -366.976339) (xy 288.160195 -367.022189) (xy 288.182837 -367.071766)
			(xy 288.198192 -367.124061) (xy 288.205948 -367.178009) (xy 288.206434 -367.20526) (xy 288.205993 -367.232005)
			(xy 288.198496 -367.284968) (xy 288.183672 -367.336363) (xy 288.161811 -367.385182) (xy 288.133342 -367.430468)
			(xy 288.098824 -367.471331) (xy 288.07918 -367.489486) (xy 288.07918 -367.874042) (xy 288.266632 -368.06124)
			(xy 293.242238 -368.06124) (xy 293.810436 -367.493296) (xy 293.828522 -367.476029) (xy 293.87007 -367.448221)
			(xy 293.916244 -367.429051) (xy 293.965271 -367.419255) (xy 293.990268 -367.41862) (xy 294.637968 -367.41862)
			(xy 294.662963 -367.419276) (xy 294.711985 -367.429074) (xy 294.758155 -367.448242) (xy 294.799703 -367.476044)
			(xy 294.8178 -367.493296) (xy 295.2369 -367.912396) (xy 295.254147 -367.9305) (xy 295.281959 -367.972042)
			(xy 295.301134 -368.01821) (xy 295.310937 -368.067232) (xy 295.311576 -368.092228) (xy 295.311576 -368.527838)
			(xy 295.462198 -368.67846) (xy 296.089578 -368.67846) (xy 297.0657 -367.702338) (xy 297.0657 -367.39576)
			(xy 297.066315 -367.370822) (xy 297.076023 -367.321899) (xy 297.095062 -367.2758) (xy 297.122703 -367.234283)
			(xy 297.139868 -367.216182) (xy 297.13936 -367.1951) (xy 297.139846 -367.167849) (xy 297.147602 -367.113901)
			(xy 297.162957 -367.061606) (xy 297.185599 -367.012029) (xy 297.215065 -366.966179) (xy 297.250756 -366.924988)
			(xy 297.291947 -366.889297) (xy 297.337797 -366.859831) (xy 297.387374 -366.837189) (xy 297.439669 -366.821834)
			(xy 297.493617 -366.814078) (xy 297.548119 -366.814078) (xy 297.602067 -366.821834) (xy 297.654362 -366.837189)
			(xy 297.703939 -366.859831) (xy 297.749789 -366.889297) (xy 297.79098 -366.924988) (xy 297.826671 -366.966179)
			(xy 297.856137 -367.012029) (xy 297.878779 -367.061606) (xy 297.894134 -367.113901) (xy 297.90189 -367.167849)
			(xy 297.902376 -367.1951) (xy 297.901828 -367.223229) (xy 297.893587 -367.278881) (xy 297.877254 -367.332716)
			(xy 297.853185 -367.383565) (xy 297.821902 -367.430323) (xy 297.784085 -367.471975) (xy 297.740556 -367.507615)
			(xy 297.692261 -367.536468) (xy 297.640248 -367.557909) (xy 297.61307 -367.565178) (xy 297.574716 -367.57483)
			(xy 297.574716 -367.807748) (xy 297.574065 -367.832743) (xy 297.564268 -367.881766) (xy 297.545099 -367.927937)
			(xy 297.517294 -367.969484) (xy 297.50004 -367.98758) (xy 296.37482 -369.1128) (xy 296.35671 -369.13004)
			(xy 296.31517 -369.157853) (xy 296.269003 -369.17703) (xy 296.219983 -369.186836) (xy 296.194988 -369.187476)
			(xy 295.356788 -369.187476) (xy 295.331792 -369.186848) (xy 295.282769 -369.177041) (xy 295.236598 -369.157865)
			(xy 295.195052 -369.130056) (xy 295.176956 -369.1128) (xy 294.877236 -368.81308) (xy 294.859983 -368.794981)
			(xy 294.832171 -368.753438) (xy 294.812997 -368.707268) (xy 294.803197 -368.658244) (xy 294.80256 -368.633248)
			(xy 294.80256 -368.197638) (xy 294.532558 -367.927636) (xy 294.095678 -367.927636) (xy 293.52748 -368.49558)
			(xy 293.509384 -368.512835) (xy 293.467839 -368.540646) (xy 293.421668 -368.55982) (xy 293.372644 -368.569619)
			(xy 293.347648 -368.570256) (xy 288.161222 -368.570256) (xy 288.136226 -368.569613) (xy 288.087204 -368.559812)
			(xy 288.041033 -368.54064) (xy 287.999486 -368.512834) (xy 287.98139 -368.49558) (xy 287.645094 -368.159284)
			(xy 287.627858 -368.141187) (xy 287.600117 -368.099624) (xy 287.581013 -368.05345) (xy 287.571279 -368.004437)
			(xy 287.570672 -367.979452) (xy 287.570672 -367.489486) (xy 287.551024 -367.471338) (xy 287.516523 -367.430464)
			(xy 287.488067 -367.385174) (xy 287.466213 -367.336355) (xy 287.451389 -367.284962) (xy 287.443886 -367.232004)
			(xy 287.443418 -367.20526) (xy 287.190314 -367.20526) (xy 287.190434 -367.212626) (xy 287.189948 -367.239877)
			(xy 287.182192 -367.293825) (xy 287.166837 -367.34612) (xy 287.144195 -367.395697) (xy 287.114729 -367.441547)
			(xy 287.079038 -367.482738) (xy 287.037847 -367.518429) (xy 286.991997 -367.547895) (xy 286.94242 -367.570537)
			(xy 286.890125 -367.585892) (xy 286.836177 -367.593648) (xy 286.781675 -367.593648) (xy 286.727727 -367.585892)
			(xy 286.675432 -367.570537) (xy 286.625855 -367.547895) (xy 286.580005 -367.518429) (xy 286.538814 -367.482738)
			(xy 286.503123 -367.441547) (xy 286.473657 -367.395697) (xy 286.451015 -367.34612) (xy 286.43566 -367.293825)
			(xy 286.427904 -367.239877) (xy 286.427418 -367.212626) (xy 283.004514 -367.212626) (xy 283.004514 -372.987077)
			(xy 286.21657 -372.987077) (xy 286.220304 -372.933821) (xy 286.231425 -372.881605) (xy 286.249717 -372.83145)
			(xy 286.274821 -372.784334) (xy 286.306249 -372.741178) (xy 286.343386 -372.702825) (xy 286.364172 -372.686072)
			(xy 286.376017 -372.676217) (xy 286.393536 -372.650882) (xy 286.402709 -372.621478) (xy 286.402702 -372.590676)
			(xy 286.393516 -372.561275) (xy 286.375984 -372.535949) (xy 286.364172 -372.526052) (xy 286.341708 -372.507839)
			(xy 286.301972 -372.465823) (xy 286.269032 -372.418292) (xy 286.243641 -372.366335) (xy 286.22638 -372.311142)
			(xy 286.217645 -372.253977) (xy 286.217106 -372.225062) (xy 286.217607 -372.197693) (xy 286.225416 -372.143515)
			(xy 286.240897 -372.091013) (xy 286.263731 -372.041265) (xy 286.293448 -371.995297) (xy 286.311086 -371.974364)
			(xy 286.320361 -371.963065) (xy 286.332535 -371.936497) (xy 286.336701 -371.907571) (xy 286.332519 -371.878648)
			(xy 286.320329 -371.852087) (xy 286.311086 -371.84076) (xy 286.29341 -371.819857) (xy 286.26369 -371.773883)
			(xy 286.240849 -371.724131) (xy 286.225357 -371.671625) (xy 286.217533 -371.617443) (xy 286.217537 -371.562699)
			(xy 286.22537 -371.508519) (xy 286.240869 -371.456015) (xy 286.263717 -371.406267) (xy 286.293444 -371.360298)
			(xy 286.311086 -371.339364) (xy 286.320361 -371.328065) (xy 286.332535 -371.301497) (xy 286.336701 -371.272571)
			(xy 286.332519 -371.243648) (xy 286.320329 -371.217087) (xy 286.311086 -371.20576) (xy 286.293459 -371.184818)
			(xy 286.263746 -371.138848) (xy 286.240908 -371.089103) (xy 286.225414 -371.036604) (xy 286.217582 -370.98243)
			(xy 286.217106 -370.955062) (xy 286.217543 -370.927809) (xy 286.225305 -370.873859) (xy 286.240665 -370.821562)
			(xy 286.263312 -370.771984) (xy 286.292783 -370.726133) (xy 286.32848 -370.684943) (xy 286.369675 -370.649252)
			(xy 286.41553 -370.619787) (xy 286.465111 -370.597147) (xy 286.51741 -370.581793) (xy 286.571361 -370.574039)
			(xy 286.598614 -370.573554) (xy 286.625985 -370.573999) (xy 286.680166 -370.58182) (xy 286.73267 -370.597313)
			(xy 286.782416 -370.62016) (xy 286.828382 -370.64989) (xy 286.849312 -370.667534) (xy 286.86064 -370.67677)
			(xy 286.887197 -370.688946) (xy 286.916114 -370.693119) (xy 286.945031 -370.688946) (xy 286.971588 -370.67677)
			(xy 286.982916 -370.667534) (xy 287.003873 -370.649926) (xy 287.049839 -370.620208) (xy 287.09958 -370.597366)
			(xy 287.152075 -370.581868) (xy 287.206246 -370.574032) (xy 287.233614 -370.573554) (xy 287.26253 -370.574114)
			(xy 287.3197 -370.582831) (xy 287.374899 -370.60008) (xy 287.426861 -370.625464) (xy 287.474396 -370.658401)
			(xy 287.516413 -370.698137) (xy 287.534604 -370.72062) (xy 287.544501 -370.732425) (xy 287.569825 -370.749944)
			(xy 287.599218 -370.75912) (xy 287.63001 -370.75912) (xy 287.659403 -370.749944) (xy 287.684727 -370.732425)
			(xy 287.694624 -370.72062) (xy 287.712807 -370.698129) (xy 287.754827 -370.658394) (xy 287.802364 -370.625455)
			(xy 287.854327 -370.600068) (xy 287.909526 -370.582813) (xy 287.966697 -370.574087) (xy 287.995614 -370.573554)
			(xy 288.022864 -370.574065) (xy 288.076809 -370.581822) (xy 288.129101 -370.597177) (xy 288.178675 -370.619817)
			(xy 288.224524 -370.649281) (xy 288.265713 -370.68497) (xy 288.301404 -370.726157) (xy 288.330871 -370.772003)
			(xy 288.353515 -370.821577) (xy 288.368873 -370.873868) (xy 288.376634 -370.927812) (xy 288.377122 -370.955062)
			(xy 288.376653 -370.982432) (xy 288.368839 -371.036612) (xy 288.353351 -371.089116) (xy 288.33051 -371.138863)
			(xy 288.300784 -371.184829) (xy 288.283142 -371.20576) (xy 288.273946 -371.217117) (xy 288.261772 -371.243665)
			(xy 288.257594 -371.272571) (xy 288.261755 -371.30148) (xy 288.273915 -371.328035) (xy 288.283142 -371.339364)
			(xy 288.300747 -371.360326) (xy 288.330475 -371.406288) (xy 288.353325 -371.456029) (xy 288.368825 -371.508527)
			(xy 288.376658 -371.562702) (xy 288.376662 -371.617441) (xy 288.368838 -371.671617) (xy 288.353345 -371.724117)
			(xy 288.330503 -371.773862) (xy 288.300781 -371.819828) (xy 288.283142 -371.84076) (xy 288.273946 -371.852117)
			(xy 288.261772 -371.878665) (xy 288.257594 -371.907571) (xy 288.261755 -371.93648) (xy 288.273915 -371.963035)
			(xy 288.283142 -371.974364) (xy 288.300785 -371.995293) (xy 288.330495 -372.041267) (xy 288.353329 -372.091016)
			(xy 288.36882 -372.143517) (xy 288.376648 -372.197693) (xy 288.377122 -372.225062) (xy 288.376606 -372.253979)
			(xy 288.367881 -372.311152) (xy 288.350624 -372.366352) (xy 288.325232 -372.418315) (xy 288.292287 -372.465848)
			(xy 288.252543 -372.507863) (xy 288.230056 -372.526052) (xy 288.218285 -372.535989) (xy 288.200759 -372.561299)
			(xy 288.191575 -372.590684) (xy 288.191568 -372.62147) (xy 288.200738 -372.650858) (xy 288.218252 -372.676177)
			(xy 288.230056 -372.686072) (xy 288.250801 -372.702871) (xy 288.287929 -372.741219) (xy 288.319349 -372.784369)
			(xy 288.344448 -372.831477) (xy 288.362735 -372.881624) (xy 288.373854 -372.93383) (xy 288.375806 -372.961677)
			(xy 289.58207 -372.961677) (xy 289.585804 -372.908421) (xy 289.596925 -372.856205) (xy 289.615217 -372.80605)
			(xy 289.640321 -372.758934) (xy 289.671749 -372.715778) (xy 289.708886 -372.677425) (xy 289.729672 -372.660672)
			(xy 289.741517 -372.650817) (xy 289.759036 -372.625482) (xy 289.768209 -372.596078) (xy 289.768202 -372.565276)
			(xy 289.759016 -372.535875) (xy 289.741484 -372.510549) (xy 289.729672 -372.500652) (xy 289.707208 -372.482439)
			(xy 289.667472 -372.440423) (xy 289.634532 -372.392892) (xy 289.609141 -372.340935) (xy 289.59188 -372.285742)
			(xy 289.583145 -372.228577) (xy 289.582606 -372.199662) (xy 289.583107 -372.172293) (xy 289.590916 -372.118115)
			(xy 289.606397 -372.065613) (xy 289.629231 -372.015865) (xy 289.658948 -371.969897) (xy 289.676586 -371.948964)
			(xy 289.685861 -371.937665) (xy 289.698035 -371.911097) (xy 289.702201 -371.882171) (xy 289.698019 -371.853248)
			(xy 289.685829 -371.826687) (xy 289.676586 -371.81536) (xy 289.65891 -371.794457) (xy 289.62919 -371.748483)
			(xy 289.606349 -371.698731) (xy 289.590857 -371.646225) (xy 289.583033 -371.592043) (xy 289.583037 -371.537299)
			(xy 289.59087 -371.483119) (xy 289.606369 -371.430615) (xy 289.629217 -371.380867) (xy 289.658944 -371.334898)
			(xy 289.676586 -371.313964) (xy 289.685861 -371.302665) (xy 289.698035 -371.276097) (xy 289.702201 -371.247171)
			(xy 289.698019 -371.218248) (xy 289.685829 -371.191687) (xy 289.676586 -371.18036) (xy 289.658959 -371.159418)
			(xy 289.629246 -371.113448) (xy 289.606408 -371.063703) (xy 289.590914 -371.011204) (xy 289.583082 -370.95703)
			(xy 289.582606 -370.929662) (xy 289.583092 -370.902411) (xy 289.590848 -370.848463) (xy 289.606203 -370.796168)
			(xy 289.628845 -370.746591) (xy 289.658311 -370.700741) (xy 289.694002 -370.65955) (xy 289.735193 -370.623859)
			(xy 289.781043 -370.594393) (xy 289.83062 -370.571751) (xy 289.882915 -370.556396) (xy 289.936863 -370.54864)
			(xy 289.991365 -370.54864) (xy 290.045313 -370.556396) (xy 290.097608 -370.571751) (xy 290.147185 -370.594393)
			(xy 290.193035 -370.623859) (xy 290.234226 -370.65955) (xy 290.269917 -370.700741) (xy 290.295262 -370.740178)
			(xy 291.927026 -370.740178) (xy 291.927573 -370.711009) (xy 291.936476 -370.653353) (xy 291.954056 -370.597726)
			(xy 291.979902 -370.545425) (xy 292.013412 -370.497671) (xy 292.053803 -370.455576) (xy 292.076632 -370.43741)
			(xy 292.086966 -370.428937) (xy 292.103261 -370.407771) (xy 292.113508 -370.383104) (xy 292.117008 -370.356623)
			(xy 292.113521 -370.330141) (xy 292.103284 -370.305469) (xy 292.086999 -370.284296) (xy 292.076632 -370.275866)
			(xy 292.053819 -370.25768) (xy 292.013415 -370.215598) (xy 291.979897 -370.16785) (xy 291.954048 -370.115551)
			(xy 291.936473 -370.059924) (xy 291.927582 -370.002267) (xy 291.927026 -369.973098) (xy 291.927454 -369.945844)
			(xy 291.935212 -369.89189) (xy 291.95057 -369.839589) (xy 291.973215 -369.790007) (xy 292.002686 -369.744152)
			(xy 292.038384 -369.702958) (xy 292.079581 -369.667265) (xy 292.125438 -369.637798) (xy 292.175023 -369.615157)
			(xy 292.227325 -369.599804) (xy 292.28128 -369.592051) (xy 292.308534 -369.59159) (xy 292.337451 -369.592122)
			(xy 292.394623 -369.600843) (xy 292.449823 -369.618096) (xy 292.501786 -369.643485) (xy 292.549319 -369.676428)
			(xy 292.591335 -369.71617) (xy 292.609524 -369.738656) (xy 292.619421 -369.750461) (xy 292.644745 -369.76798)
			(xy 292.674138 -369.777156) (xy 292.70493 -369.777156) (xy 292.734323 -369.76798) (xy 292.759647 -369.750461)
			(xy 292.769544 -369.738656) (xy 292.787699 -369.716142) (xy 292.829728 -369.676411) (xy 292.87727 -369.643477)
			(xy 292.929239 -369.618094) (xy 292.984442 -369.600844) (xy 293.041616 -369.592122) (xy 293.070534 -369.59159)
			(xy 293.099081 -369.59211) (xy 293.155536 -369.600633) (xy 293.210091 -369.61747) (xy 293.26153 -369.642244)
			(xy 293.285418 -369.657884) (xy 293.296563 -369.664941) (xy 293.321415 -369.673747) (xy 293.347695 -369.675874)
			(xy 293.37364 -369.671181) (xy 293.39751 -369.659982) (xy 293.417702 -369.643028) (xy 293.425626 -369.632484)
			(xy 293.441057 -369.611486) (xy 293.476652 -369.573431) (xy 293.517093 -369.540572) (xy 293.561628 -369.513519)
			(xy 293.609429 -369.492776) (xy 293.659607 -369.478729) (xy 293.71123 -369.471638) (xy 293.737284 -369.471194)
			(xy 293.766202 -369.471688) (xy 293.823376 -369.480417) (xy 293.878577 -369.497677) (xy 293.93054 -369.523073)
			(xy 293.978072 -369.556023) (xy 294.020086 -369.595771) (xy 294.038274 -369.61826) (xy 294.048171 -369.630065)
			(xy 294.073495 -369.647584) (xy 294.102888 -369.65676) (xy 294.13368 -369.65676) (xy 294.163073 -369.647584)
			(xy 294.188397 -369.630065) (xy 294.198294 -369.61826) (xy 294.216478 -369.595771) (xy 294.258501 -369.556038)
			(xy 294.306037 -369.523101) (xy 294.358 -369.497714) (xy 294.413198 -369.480458) (xy 294.470368 -369.471729)
			(xy 294.499284 -369.471194) (xy 294.526537 -369.47167) (xy 294.580487 -369.479425) (xy 294.632785 -369.494779)
			(xy 294.682365 -369.51742) (xy 294.728218 -369.546886) (xy 294.769411 -369.582579) (xy 294.805105 -369.62377)
			(xy 294.834573 -369.669623) (xy 294.857216 -369.719202) (xy 294.872572 -369.771499) (xy 294.880329 -369.825449)
			(xy 294.880792 -369.852702) (xy 294.880362 -369.878745) (xy 294.873275 -369.930348) (xy 294.859233 -369.980506)
			(xy 294.838498 -370.028288) (xy 294.811455 -370.072804) (xy 294.778606 -370.113227) (xy 294.759888 -370.13134)
			(xy 294.749997 -370.141348) (xy 294.735529 -370.165464) (xy 294.72818 -370.19261) (xy 294.728505 -370.220731)
			(xy 294.73648 -370.247699) (xy 294.7515 -370.271474) (xy 294.761666 -370.2812) (xy 294.781236 -370.299374)
			(xy 294.815628 -370.340233) (xy 294.843987 -370.385488) (xy 294.865756 -370.434257) (xy 294.880511 -370.485585)
			(xy 294.887963 -370.538469) (xy 294.888412 -370.565172) (xy 294.887892 -370.592941) (xy 294.879843 -370.647893)
			(xy 294.863911 -370.701096) (xy 294.840433 -370.751428) (xy 294.809904 -370.797823) (xy 294.772971 -370.8393)
			(xy 294.752014 -370.857526) (xy 294.741396 -370.867082) (xy 294.725411 -370.890736) (xy 294.716616 -370.917896)
			(xy 294.7157 -370.94643) (xy 294.722736 -370.974099) (xy 294.737171 -370.998729) (xy 294.747188 -371.00891)
			(xy 294.765535 -371.026997) (xy 294.797707 -371.067237) (xy 294.824176 -371.111437) (xy 294.844461 -371.158796)
			(xy 294.858194 -371.208451) (xy 294.865127 -371.259502) (xy 294.865552 -371.285262) (xy 294.865075 -371.312632)
			(xy 294.857262 -371.366811) (xy 294.841776 -371.419315) (xy 294.818936 -371.469062) (xy 294.789213 -371.515028)
			(xy 294.771572 -371.53596) (xy 294.762374 -371.547316) (xy 294.750196 -371.573864) (xy 294.746017 -371.602771)
			(xy 294.750179 -371.631681) (xy 294.762343 -371.658236) (xy 294.771572 -371.669564) (xy 294.789176 -371.690527)
			(xy 294.818902 -371.736489) (xy 294.84175 -371.786231) (xy 294.857249 -371.838728) (xy 294.865081 -371.892903)
			(xy 294.865085 -371.94764) (xy 294.857261 -372.001816) (xy 294.84177 -372.054316) (xy 294.81893 -372.10406)
			(xy 294.78921 -372.150027) (xy 294.771572 -372.17096) (xy 294.762374 -372.182316) (xy 294.750196 -372.208864)
			(xy 294.746017 -372.237771) (xy 294.750179 -372.266681) (xy 294.762343 -372.293236) (xy 294.771572 -372.304564)
			(xy 294.789176 -372.325527) (xy 294.818902 -372.371489) (xy 294.84175 -372.421231) (xy 294.857249 -372.473728)
			(xy 294.860837 -372.49855) (xy 295.942254 -372.49855) (xy 295.942254 -372.413854) (xy 295.950305 -372.32954)
			(xy 295.966334 -372.246374) (xy 295.990195 -372.165107) (xy 296.021674 -372.086477) (xy 296.060485 -372.011196)
			(xy 296.106275 -371.939944) (xy 296.158631 -371.873368) (xy 296.217079 -371.81207) (xy 296.281089 -371.756605)
			(xy 296.350081 -371.707476) (xy 296.423431 -371.665127) (xy 296.500474 -371.629943) (xy 296.580513 -371.602241)
			(xy 296.662822 -371.582273) (xy 296.746657 -371.57022) (xy 296.831258 -371.56619) (xy 296.915859 -371.57022)
			(xy 296.999694 -371.582273) (xy 297.082003 -371.602241) (xy 297.162042 -371.629943) (xy 297.239085 -371.665127)
			(xy 297.312435 -371.707476) (xy 297.381427 -371.756605) (xy 297.445437 -371.81207) (xy 297.503885 -371.873368)
			(xy 297.556241 -371.939944) (xy 297.602031 -372.011196) (xy 297.640842 -372.086477) (xy 297.672321 -372.165107)
			(xy 297.696182 -372.246374) (xy 297.712211 -372.32954) (xy 297.720262 -372.413854) (xy 297.720766 -372.456202)
			(xy 298.466767 -372.456202) (xy 298.470803 -372.372755) (xy 298.482875 -372.290087) (xy 298.502868 -372.20897)
			(xy 298.530597 -372.130161) (xy 298.565803 -372.054396) (xy 298.608157 -371.982383) (xy 298.657263 -371.914794)
			(xy 298.712664 -371.85226) (xy 298.773841 -371.795365) (xy 298.840224 -371.744639) (xy 298.911192 -371.700558)
			(xy 298.986084 -371.663532) (xy 299.0642 -371.633906) (xy 299.14481 -371.611958) (xy 299.227162 -371.597893)
			(xy 299.310488 -371.591841) (xy 299.394008 -371.59386) (xy 299.476944 -371.60393) (xy 299.55852 -371.621958)
			(xy 299.637976 -371.647775) (xy 299.714569 -371.68114) (xy 299.787585 -371.721741) (xy 299.856341 -371.7692)
			(xy 299.920195 -371.823073) (xy 299.978552 -371.882858) (xy 300.030867 -371.947995) (xy 300.07665 -372.017878)
			(xy 300.115475 -372.091853) (xy 300.14698 -372.16923) (xy 300.170869 -372.249287) (xy 300.18692 -372.331275)
			(xy 300.194983 -372.41443) (xy 300.195488 -372.456202) (xy 300.194983 -372.497974) (xy 300.18692 -372.581129)
			(xy 300.170869 -372.663117) (xy 300.14698 -372.743174) (xy 300.115475 -372.820551) (xy 300.07665 -372.894526)
			(xy 300.030867 -372.964409) (xy 299.978552 -373.029546) (xy 299.920195 -373.089331) (xy 299.856341 -373.143204)
			(xy 299.787585 -373.190663) (xy 299.714569 -373.231264) (xy 299.637976 -373.264629) (xy 299.55852 -373.290446)
			(xy 299.476944 -373.308474) (xy 299.394008 -373.318544) (xy 299.310488 -373.320563) (xy 299.227162 -373.314511)
			(xy 299.14481 -373.300446) (xy 299.0642 -373.278498) (xy 298.986084 -373.248872) (xy 298.911192 -373.211846)
			(xy 298.840224 -373.167765) (xy 298.773841 -373.117039) (xy 298.712664 -373.060144) (xy 298.657263 -372.99761)
			(xy 298.608157 -372.930021) (xy 298.565803 -372.858008) (xy 298.530597 -372.782243) (xy 298.502868 -372.703434)
			(xy 298.482875 -372.622317) (xy 298.470803 -372.539649) (xy 298.466767 -372.456202) (xy 297.720766 -372.456202)
			(xy 297.720262 -372.49855) (xy 297.712211 -372.582864) (xy 297.696182 -372.66603) (xy 297.672321 -372.747297)
			(xy 297.640842 -372.825927) (xy 297.602031 -372.901208) (xy 297.556241 -372.97246) (xy 297.503885 -373.039036)
			(xy 297.445437 -373.100334) (xy 297.381427 -373.155799) (xy 297.312435 -373.204928) (xy 297.239085 -373.247277)
			(xy 297.162042 -373.282461) (xy 297.082003 -373.310163) (xy 296.999694 -373.330131) (xy 296.915859 -373.342184)
			(xy 296.831258 -373.346215) (xy 296.746657 -373.342184) (xy 296.662822 -373.330131) (xy 296.580513 -373.310163)
			(xy 296.500474 -373.282461) (xy 296.423431 -373.247277) (xy 296.350081 -373.204928) (xy 296.281089 -373.155799)
			(xy 296.217079 -373.100334) (xy 296.158631 -373.039036) (xy 296.106275 -372.97246) (xy 296.060485 -372.901208)
			(xy 296.021674 -372.825927) (xy 295.990195 -372.747297) (xy 295.966334 -372.66603) (xy 295.950305 -372.582864)
			(xy 295.942254 -372.49855) (xy 294.860837 -372.49855) (xy 294.865081 -372.527903) (xy 294.865085 -372.58264)
			(xy 294.857261 -372.636816) (xy 294.84177 -372.689316) (xy 294.81893 -372.73906) (xy 294.78921 -372.785027)
			(xy 294.771572 -372.80596) (xy 294.762374 -372.817316) (xy 294.750196 -372.843864) (xy 294.746017 -372.872771)
			(xy 294.750179 -372.901681) (xy 294.762343 -372.928236) (xy 294.771572 -372.939564) (xy 294.789203 -372.960502)
			(xy 294.818917 -373.006473) (xy 294.841755 -373.056219) (xy 294.857248 -373.108718) (xy 294.865077 -373.162893)
			(xy 294.865552 -373.190262) (xy 294.864987 -373.21751) (xy 294.857236 -373.271453) (xy 294.841888 -373.323743)
			(xy 294.819255 -373.373317) (xy 294.789797 -373.419166) (xy 294.754113 -373.460355) (xy 294.712932 -373.496047)
			(xy 294.667089 -373.525515) (xy 294.61752 -373.54816) (xy 294.565233 -373.563519) (xy 294.511292 -373.571281)
			(xy 294.484044 -373.57177) (xy 294.455128 -373.571232) (xy 294.397957 -373.562508) (xy 294.342758 -373.545255)
			(xy 294.290796 -373.519867) (xy 294.243262 -373.486927) (xy 294.201244 -373.447188) (xy 294.183054 -373.424704)
			(xy 294.173157 -373.412899) (xy 294.147833 -373.39538) (xy 294.11844 -373.386204) (xy 294.087648 -373.386204)
			(xy 294.058255 -373.39538) (xy 294.032931 -373.412899) (xy 294.023034 -373.424704) (xy 294.004825 -373.447172)
			(xy 293.962809 -373.486908) (xy 293.915278 -373.519849) (xy 293.86332 -373.54524) (xy 293.808126 -373.562499)
			(xy 293.750959 -373.571233) (xy 293.722044 -373.57177) (xy 293.694791 -373.571304) (xy 293.640838 -373.563552)
			(xy 293.588538 -373.548199) (xy 293.538955 -373.525559) (xy 293.4931 -373.496092) (xy 293.451906 -373.460399)
			(xy 293.416211 -373.419205) (xy 293.386744 -373.37335) (xy 293.364103 -373.323768) (xy 293.34875 -373.271468)
			(xy 293.340997 -373.217515) (xy 293.340536 -373.190262) (xy 293.34103 -373.162893) (xy 293.348839 -373.108714)
			(xy 293.364322 -373.056211) (xy 293.387157 -373.006464) (xy 293.416877 -372.960496) (xy 293.434516 -372.939564)
			(xy 293.443788 -372.928264) (xy 293.455959 -372.901696) (xy 293.460124 -372.872771) (xy 293.455943 -372.843849)
			(xy 293.443757 -372.817288) (xy 293.434516 -372.80596) (xy 293.416839 -372.785057) (xy 293.387116 -372.739084)
			(xy 293.364274 -372.689333) (xy 293.348781 -372.636826) (xy 293.340956 -372.582644) (xy 293.34096 -372.527899)
			(xy 293.348793 -372.473718) (xy 293.364294 -372.421214) (xy 293.387144 -372.371466) (xy 293.416873 -372.325497)
			(xy 293.434516 -372.304564) (xy 293.443788 -372.293264) (xy 293.455959 -372.266696) (xy 293.460124 -372.237771)
			(xy 293.455943 -372.208849) (xy 293.443757 -372.182288) (xy 293.434516 -372.17096) (xy 293.416839 -372.150057)
			(xy 293.387116 -372.104084) (xy 293.364274 -372.054333) (xy 293.348781 -372.001826) (xy 293.340956 -371.947644)
			(xy 293.34096 -371.892899) (xy 293.348793 -371.838718) (xy 293.364294 -371.786214) (xy 293.387144 -371.736466)
			(xy 293.416873 -371.690497) (xy 293.434516 -371.669564) (xy 293.443788 -371.658264) (xy 293.455959 -371.631696)
			(xy 293.460124 -371.602771) (xy 293.455943 -371.573849) (xy 293.443757 -371.547288) (xy 293.434516 -371.53596)
			(xy 293.416894 -371.515014) (xy 293.387179 -371.469045) (xy 293.36434 -371.419301) (xy 293.348845 -371.366804)
			(xy 293.341012 -371.31263) (xy 293.340536 -371.285262) (xy 293.340768 -371.266207) (xy 293.344587 -371.228289)
			(xy 293.348156 -371.20957) (xy 293.3505 -371.196098) (xy 293.348653 -371.168823) (xy 293.339636 -371.143015)
			(xy 293.324096 -371.120524) (xy 293.303147 -371.102961) (xy 293.278289 -371.091584) (xy 293.251304 -371.087209)
			(xy 293.224125 -371.09015) (xy 293.21125 -371.094762) (xy 293.188788 -371.103308) (xy 293.142245 -371.11529)
			(xy 293.094564 -371.121325) (xy 293.070534 -371.121686) (xy 293.041618 -371.121149) (xy 292.984447 -371.112424)
			(xy 292.929249 -371.09517) (xy 292.877287 -371.069782) (xy 292.829752 -371.036842) (xy 292.787735 -370.997104)
			(xy 292.769544 -370.97462) (xy 292.759647 -370.962815) (xy 292.734323 -370.945296) (xy 292.70493 -370.93612)
			(xy 292.674138 -370.93612) (xy 292.644745 -370.945296) (xy 292.619421 -370.962815) (xy 292.609524 -370.97462)
			(xy 292.591324 -370.997096) (xy 292.549306 -371.036831) (xy 292.501773 -371.06977) (xy 292.449813 -371.09516)
			(xy 292.394617 -371.112418) (xy 292.337449 -371.121149) (xy 292.308534 -371.121686) (xy 292.281281 -371.121213)
			(xy 292.227329 -371.11346) (xy 292.17503 -371.098107) (xy 292.125449 -371.075467) (xy 292.079594 -371.046001)
			(xy 292.038401 -371.010308) (xy 292.002707 -370.969115) (xy 291.973239 -370.923262) (xy 291.950597 -370.873681)
			(xy 291.935242 -370.821382) (xy 291.927488 -370.767431) (xy 291.927026 -370.740178) (xy 290.295262 -370.740178)
			(xy 290.299383 -370.746591) (xy 290.322025 -370.796168) (xy 290.33738 -370.848463) (xy 290.345136 -370.902411)
			(xy 290.345622 -370.929662) (xy 290.345153 -370.957032) (xy 290.337339 -371.011212) (xy 290.321851 -371.063716)
			(xy 290.29901 -371.113463) (xy 290.269284 -371.159429) (xy 290.251642 -371.18036) (xy 290.242446 -371.191717)
			(xy 290.230272 -371.218265) (xy 290.226094 -371.247171) (xy 290.230255 -371.27608) (xy 290.242415 -371.302635)
			(xy 290.251642 -371.313964) (xy 290.269247 -371.334926) (xy 290.298975 -371.380888) (xy 290.321825 -371.430629)
			(xy 290.337325 -371.483127) (xy 290.345158 -371.537302) (xy 290.345162 -371.592041) (xy 290.337338 -371.646217)
			(xy 290.321845 -371.698717) (xy 290.299003 -371.748462) (xy 290.269281 -371.794428) (xy 290.251642 -371.81536)
			(xy 290.242446 -371.826717) (xy 290.230272 -371.853265) (xy 290.226094 -371.882171) (xy 290.230255 -371.91108)
			(xy 290.242415 -371.937635) (xy 290.251642 -371.948964) (xy 290.269285 -371.969893) (xy 290.298995 -372.015867)
			(xy 290.321829 -372.065616) (xy 290.33732 -372.118117) (xy 290.345148 -372.172293) (xy 290.345622 -372.199662)
			(xy 290.345106 -372.228579) (xy 290.336381 -372.285752) (xy 290.319124 -372.340952) (xy 290.293732 -372.392915)
			(xy 290.260787 -372.440448) (xy 290.221043 -372.482463) (xy 290.198556 -372.500652) (xy 290.186785 -372.510589)
			(xy 290.169259 -372.535899) (xy 290.160075 -372.565284) (xy 290.160068 -372.59607) (xy 290.169238 -372.625458)
			(xy 290.186752 -372.650777) (xy 290.198556 -372.660672) (xy 290.219301 -372.677471) (xy 290.256429 -372.715819)
			(xy 290.287849 -372.758969) (xy 290.312948 -372.806077) (xy 290.331235 -372.856224) (xy 290.342354 -372.90843)
			(xy 290.346086 -372.961677) (xy 290.34236 -373.014924) (xy 290.331248 -373.067131) (xy 290.312967 -373.11728)
			(xy 290.287874 -373.164392) (xy 290.256459 -373.207545) (xy 290.219335 -373.245898) (xy 290.198556 -373.262652)
			(xy 290.186785 -373.272589) (xy 290.169259 -373.297899) (xy 290.160075 -373.327284) (xy 290.160068 -373.35807)
			(xy 290.169238 -373.387458) (xy 290.186752 -373.412777) (xy 290.198556 -373.422672) (xy 290.221017 -373.44089)
			(xy 290.260756 -373.482903) (xy 290.293698 -373.530432) (xy 290.319091 -373.582388) (xy 290.336352 -373.637581)
			(xy 290.345085 -373.694747) (xy 290.345622 -373.723662) (xy 290.345136 -373.750913) (xy 290.33738 -373.804861)
			(xy 290.322025 -373.857156) (xy 290.299383 -373.906733) (xy 290.269917 -373.952583) (xy 290.234226 -373.993774)
			(xy 290.193035 -374.029465) (xy 290.147185 -374.058931) (xy 290.097608 -374.081573) (xy 290.045313 -374.096928)
			(xy 289.991365 -374.104684) (xy 289.936863 -374.104684) (xy 289.882915 -374.096928) (xy 289.83062 -374.081573)
			(xy 289.781043 -374.058931) (xy 289.735193 -374.029465) (xy 289.694002 -373.993774) (xy 289.658311 -373.952583)
			(xy 289.628845 -373.906733) (xy 289.606203 -373.857156) (xy 289.590848 -373.804861) (xy 289.583092 -373.750913)
			(xy 289.582606 -373.723662) (xy 289.583167 -373.694747) (xy 289.591886 -373.637577) (xy 289.609136 -373.582379)
			(xy 289.63452 -373.530417) (xy 289.667456 -373.482882) (xy 289.70719 -373.440863) (xy 289.729672 -373.422672)
			(xy 289.741517 -373.412817) (xy 289.759036 -373.387482) (xy 289.768209 -373.358078) (xy 289.768202 -373.327276)
			(xy 289.759016 -373.297875) (xy 289.741484 -373.272549) (xy 289.729672 -373.262652) (xy 289.708851 -373.245944)
			(xy 289.671719 -373.207586) (xy 289.640296 -373.164426) (xy 289.615197 -373.117307) (xy 289.596912 -373.06715)
			(xy 289.585797 -373.014933) (xy 289.58207 -372.961677) (xy 288.375806 -372.961677) (xy 288.377586 -372.987077)
			(xy 288.37386 -373.040324) (xy 288.362748 -373.092531) (xy 288.344467 -373.14268) (xy 288.319374 -373.189792)
			(xy 288.287959 -373.232945) (xy 288.250835 -373.271298) (xy 288.230056 -373.288052) (xy 288.218285 -373.297989)
			(xy 288.200759 -373.323299) (xy 288.191575 -373.352684) (xy 288.191568 -373.38347) (xy 288.200738 -373.412858)
			(xy 288.218252 -373.438177) (xy 288.230056 -373.448072) (xy 288.252517 -373.46629) (xy 288.292256 -373.508303)
			(xy 288.325198 -373.555832) (xy 288.350591 -373.607788) (xy 288.367852 -373.662981) (xy 288.376585 -373.720147)
			(xy 288.377122 -373.749062) (xy 288.376609 -373.776313) (xy 288.368858 -373.830262) (xy 288.353507 -373.882558)
			(xy 288.33087 -373.932137) (xy 288.301408 -373.977989) (xy 288.265719 -374.019182) (xy 288.224531 -374.054876)
			(xy 288.178683 -374.084345) (xy 288.129107 -374.106989) (xy 288.076813 -374.122347) (xy 288.022865 -374.130106)
			(xy 287.995614 -374.13057) (xy 287.966697 -374.130053) (xy 287.909525 -374.121325) (xy 287.854326 -374.104068)
			(xy 287.802364 -374.078676) (xy 287.75483 -374.045732) (xy 287.712814 -374.00599) (xy 287.694624 -373.983504)
			(xy 287.684727 -373.971699) (xy 287.659403 -373.95418) (xy 287.63001 -373.945004) (xy 287.599218 -373.945004)
			(xy 287.569825 -373.95418) (xy 287.544501 -373.971699) (xy 287.534604 -373.983504) (xy 287.516412 -374.005986)
			(xy 287.474392 -374.045721) (xy 287.426857 -374.07866) (xy 287.374896 -374.104049) (xy 287.319699 -374.121306)
			(xy 287.26253 -374.130035) (xy 287.233614 -374.13057) (xy 287.206244 -374.130103) (xy 287.152064 -374.122287)
			(xy 287.099561 -374.106798) (xy 287.049814 -374.083956) (xy 287.003847 -374.054232) (xy 286.982916 -374.03659)
			(xy 286.971588 -374.027354) (xy 286.945031 -374.015178) (xy 286.916114 -374.011005) (xy 286.887197 -374.015178)
			(xy 286.86064 -374.027354) (xy 286.849312 -374.03659) (xy 286.828385 -374.054235) (xy 286.782411 -374.083947)
			(xy 286.732662 -374.106782) (xy 286.68016 -374.122271) (xy 286.625984 -374.130097) (xy 286.598614 -374.13057)
			(xy 286.57136 -374.130132) (xy 286.517406 -374.122375) (xy 286.465105 -374.107019) (xy 286.415523 -374.084376)
			(xy 286.369668 -374.054906) (xy 286.328474 -374.019209) (xy 286.29278 -373.978013) (xy 286.263313 -373.932156)
			(xy 286.240672 -373.882572) (xy 286.225319 -373.830271) (xy 286.217567 -373.776316) (xy 286.217106 -373.749062)
			(xy 286.217667 -373.720147) (xy 286.226386 -373.662977) (xy 286.243636 -373.607779) (xy 286.26902 -373.555817)
			(xy 286.301956 -373.508282) (xy 286.34169 -373.466263) (xy 286.364172 -373.448072) (xy 286.376017 -373.438217)
			(xy 286.393536 -373.412882) (xy 286.402709 -373.383478) (xy 286.402702 -373.352676) (xy 286.393516 -373.323275)
			(xy 286.375984 -373.297949) (xy 286.364172 -373.288052) (xy 286.343351 -373.271344) (xy 286.306219 -373.232986)
			(xy 286.274796 -373.189826) (xy 286.249697 -373.142707) (xy 286.231412 -373.09255) (xy 286.220297 -373.040333)
			(xy 286.21657 -372.987077) (xy 283.004514 -372.987077) (xy 283.004514 -373.580152) (xy 285.042356 -375.617994)
			(xy 303.553114 -375.617994)
		)
		(stroke
			(width 0)
			(type solid)
		)
		(fill yes)
		(layer "In4.Cu")
		(net "GND")
	)
	(gr_poly
		(pts
			(xy 433.130706 -374.650254) (xy 433.130706 -363.565948) (xy 435.7116 -360.985054) (xy 435.7116 -340.782148)
			(xy 433.9844 -339.054948) (xy 410.337 -339.054948) (xy 409.51531 -339.876638) (xy 409.51531 -344.053344)
			(xy 414.212782 -344.053344) (xy 414.212782 -343.968648) (xy 414.220833 -343.884334) (xy 414.236862 -343.801168)
			(xy 414.260723 -343.719901) (xy 414.292202 -343.641271) (xy 414.331013 -343.56599) (xy 414.376803 -343.494738)
			(xy 414.429159 -343.428162) (xy 414.487607 -343.366864) (xy 414.551617 -343.311399) (xy 414.620609 -343.26227)
			(xy 414.693959 -343.219921) (xy 414.771002 -343.184737) (xy 414.851041 -343.157035) (xy 414.93335 -343.137067)
			(xy 415.017185 -343.125014) (xy 415.101786 -343.120984) (xy 415.186387 -343.125014) (xy 415.270222 -343.137067)
			(xy 415.352531 -343.157035) (xy 415.43257 -343.184737) (xy 415.509613 -343.219921) (xy 415.582963 -343.26227)
			(xy 415.651955 -343.311399) (xy 415.715965 -343.366864) (xy 415.774413 -343.428162) (xy 415.826769 -343.494738)
			(xy 415.872559 -343.56599) (xy 415.91137 -343.641271) (xy 415.942849 -343.719901) (xy 415.96671 -343.801168)
			(xy 415.982739 -343.884334) (xy 415.99079 -343.968648) (xy 415.991294 -344.010996) (xy 415.99079 -344.053344)
			(xy 415.990184 -344.059694) (xy 420.403524 -344.059694) (xy 420.403524 -343.974998) (xy 420.411575 -343.890684)
			(xy 420.427604 -343.807518) (xy 420.451465 -343.726251) (xy 420.482944 -343.647621) (xy 420.521755 -343.57234)
			(xy 420.567545 -343.501088) (xy 420.619901 -343.434512) (xy 420.678349 -343.373214) (xy 420.742359 -343.317749)
			(xy 420.811351 -343.26862) (xy 420.884701 -343.226271) (xy 420.961744 -343.191087) (xy 421.041783 -343.163385)
			(xy 421.124092 -343.143417) (xy 421.207927 -343.131364) (xy 421.292528 -343.127334) (xy 421.377129 -343.131364)
			(xy 421.460964 -343.143417) (xy 421.543273 -343.163385) (xy 421.623312 -343.191087) (xy 421.700355 -343.226271)
			(xy 421.773705 -343.26862) (xy 421.842697 -343.317749) (xy 421.906707 -343.373214) (xy 421.965155 -343.434512)
			(xy 422.017511 -343.501088) (xy 422.063301 -343.57234) (xy 422.102112 -343.647621) (xy 422.133591 -343.726251)
			(xy 422.157452 -343.807518) (xy 422.173481 -343.890684) (xy 422.181532 -343.974998) (xy 422.182036 -344.017346)
			(xy 422.181532 -344.059694) (xy 426.601124 -344.059694) (xy 426.601124 -343.974998) (xy 426.609175 -343.890684)
			(xy 426.625204 -343.807518) (xy 426.649065 -343.726251) (xy 426.680544 -343.647621) (xy 426.719355 -343.57234)
			(xy 426.765145 -343.501088) (xy 426.817501 -343.434512) (xy 426.875949 -343.373214) (xy 426.939959 -343.317749)
			(xy 427.008951 -343.26862) (xy 427.082301 -343.226271) (xy 427.159344 -343.191087) (xy 427.239383 -343.163385)
			(xy 427.321692 -343.143417) (xy 427.405527 -343.131364) (xy 427.490128 -343.127334) (xy 427.574729 -343.131364)
			(xy 427.658564 -343.143417) (xy 427.740873 -343.163385) (xy 427.820912 -343.191087) (xy 427.897955 -343.226271)
			(xy 427.971305 -343.26862) (xy 428.040297 -343.317749) (xy 428.104307 -343.373214) (xy 428.162755 -343.434512)
			(xy 428.215111 -343.501088) (xy 428.260901 -343.57234) (xy 428.299712 -343.647621) (xy 428.331191 -343.726251)
			(xy 428.355052 -343.807518) (xy 428.371081 -343.890684) (xy 428.379132 -343.974998) (xy 428.379636 -344.017346)
			(xy 428.379132 -344.059694) (xy 428.371081 -344.144008) (xy 428.355052 -344.227174) (xy 428.331191 -344.308441)
			(xy 428.299712 -344.387071) (xy 428.260901 -344.462352) (xy 428.215111 -344.533604) (xy 428.162755 -344.60018)
			(xy 428.104307 -344.661478) (xy 428.040297 -344.716943) (xy 427.971305 -344.766072) (xy 427.897955 -344.808421)
			(xy 427.820912 -344.843605) (xy 427.740873 -344.871307) (xy 427.658564 -344.891275) (xy 427.574729 -344.903328)
			(xy 427.490128 -344.907359) (xy 427.405527 -344.903328) (xy 427.321692 -344.891275) (xy 427.239383 -344.871307)
			(xy 427.159344 -344.843605) (xy 427.082301 -344.808421) (xy 427.008951 -344.766072) (xy 426.939959 -344.716943)
			(xy 426.875949 -344.661478) (xy 426.817501 -344.60018) (xy 426.765145 -344.533604) (xy 426.719355 -344.462352)
			(xy 426.680544 -344.387071) (xy 426.649065 -344.308441) (xy 426.625204 -344.227174) (xy 426.609175 -344.144008)
			(xy 426.601124 -344.059694) (xy 422.181532 -344.059694) (xy 422.173481 -344.144008) (xy 422.157452 -344.227174)
			(xy 422.133591 -344.308441) (xy 422.102112 -344.387071) (xy 422.063301 -344.462352) (xy 422.017511 -344.533604)
			(xy 421.965155 -344.60018) (xy 421.906707 -344.661478) (xy 421.842697 -344.716943) (xy 421.773705 -344.766072)
			(xy 421.700355 -344.808421) (xy 421.623312 -344.843605) (xy 421.543273 -344.871307) (xy 421.460964 -344.891275)
			(xy 421.377129 -344.903328) (xy 421.292528 -344.907359) (xy 421.207927 -344.903328) (xy 421.124092 -344.891275)
			(xy 421.041783 -344.871307) (xy 420.961744 -344.843605) (xy 420.884701 -344.808421) (xy 420.811351 -344.766072)
			(xy 420.742359 -344.716943) (xy 420.678349 -344.661478) (xy 420.619901 -344.60018) (xy 420.567545 -344.533604)
			(xy 420.521755 -344.462352) (xy 420.482944 -344.387071) (xy 420.451465 -344.308441) (xy 420.427604 -344.227174)
			(xy 420.411575 -344.144008) (xy 420.403524 -344.059694) (xy 415.990184 -344.059694) (xy 415.982739 -344.137658)
			(xy 415.96671 -344.220824) (xy 415.942849 -344.302091) (xy 415.91137 -344.380721) (xy 415.872559 -344.456002)
			(xy 415.826769 -344.527254) (xy 415.774413 -344.59383) (xy 415.715965 -344.655128) (xy 415.651955 -344.710593)
			(xy 415.582963 -344.759722) (xy 415.509613 -344.802071) (xy 415.43257 -344.837255) (xy 415.352531 -344.864957)
			(xy 415.270222 -344.884925) (xy 415.186387 -344.896978) (xy 415.101786 -344.901009) (xy 415.017185 -344.896978)
			(xy 414.93335 -344.884925) (xy 414.851041 -344.864957) (xy 414.771002 -344.837255) (xy 414.693959 -344.802071)
			(xy 414.620609 -344.759722) (xy 414.551617 -344.710593) (xy 414.487607 -344.655128) (xy 414.429159 -344.59383)
			(xy 414.376803 -344.527254) (xy 414.331013 -344.456002) (xy 414.292202 -344.380721) (xy 414.260723 -344.302091)
			(xy 414.236862 -344.220824) (xy 414.220833 -344.137658) (xy 414.212782 -344.053344) (xy 409.51531 -344.053344)
			(xy 409.51531 -346.010992) (xy 414.186375 -346.010992) (xy 414.190397 -345.925272) (xy 414.202428 -345.840304)
			(xy 414.222364 -345.756837) (xy 414.250027 -345.675603) (xy 414.285176 -345.597317) (xy 414.327502 -345.522666)
			(xy 414.376631 -345.452307) (xy 414.432134 -345.386857) (xy 414.493521 -345.326893) (xy 414.560254 -345.27294)
			(xy 414.631746 -345.225473) (xy 414.707368 -345.184909) (xy 414.786457 -345.151605) (xy 414.868317 -345.125853)
			(xy 414.952228 -345.10788) (xy 415.037454 -345.097844) (xy 415.123246 -345.095832) (xy 415.208848 -345.101863)
			(xy 415.29351 -345.115883) (xy 415.376487 -345.137769) (xy 415.45705 -345.16733) (xy 415.53449 -345.204304)
			(xy 415.608129 -345.248368) (xy 415.677317 -345.299134) (xy 415.741448 -345.356155) (xy 415.799957 -345.418931)
			(xy 415.85233 -345.486911) (xy 415.898108 -345.559496) (xy 415.936888 -345.636048) (xy 415.968329 -345.715896)
			(xy 415.992155 -345.798337) (xy 416.008156 -345.882647) (xy 416.016191 -345.968085) (xy 416.016694 -346.010992)
			(xy 416.01662 -346.017342) (xy 420.377117 -346.017342) (xy 420.381139 -345.931622) (xy 420.39317 -345.846654)
			(xy 420.413106 -345.763187) (xy 420.440769 -345.681953) (xy 420.475918 -345.603667) (xy 420.518244 -345.529016)
			(xy 420.567373 -345.458657) (xy 420.622876 -345.393207) (xy 420.684263 -345.333243) (xy 420.750996 -345.27929)
			(xy 420.822488 -345.231823) (xy 420.89811 -345.191259) (xy 420.977199 -345.157955) (xy 421.059059 -345.132203)
			(xy 421.14297 -345.11423) (xy 421.228196 -345.104194) (xy 421.313988 -345.102182) (xy 421.39959 -345.108213)
			(xy 421.484252 -345.122233) (xy 421.567229 -345.144119) (xy 421.647792 -345.17368) (xy 421.725232 -345.210654)
			(xy 421.798871 -345.254718) (xy 421.868059 -345.305484) (xy 421.93219 -345.362505) (xy 421.990699 -345.425281)
			(xy 422.043072 -345.493261) (xy 422.08885 -345.565846) (xy 422.12763 -345.642398) (xy 422.159071 -345.722246)
			(xy 422.182897 -345.804687) (xy 422.198898 -345.888997) (xy 422.206933 -345.974435) (xy 422.207436 -346.017342)
			(xy 426.574717 -346.017342) (xy 426.578739 -345.931622) (xy 426.59077 -345.846654) (xy 426.610706 -345.763187)
			(xy 426.638369 -345.681953) (xy 426.673518 -345.603667) (xy 426.715844 -345.529016) (xy 426.764973 -345.458657)
			(xy 426.820476 -345.393207) (xy 426.881863 -345.333243) (xy 426.948596 -345.27929) (xy 427.020088 -345.231823)
			(xy 427.09571 -345.191259) (xy 427.174799 -345.157955) (xy 427.256659 -345.132203) (xy 427.34057 -345.11423)
			(xy 427.425796 -345.104194) (xy 427.511588 -345.102182) (xy 427.59719 -345.108213) (xy 427.681852 -345.122233)
			(xy 427.764829 -345.144119) (xy 427.845392 -345.17368) (xy 427.922832 -345.210654) (xy 427.996471 -345.254718)
			(xy 428.065659 -345.305484) (xy 428.12979 -345.362505) (xy 428.188299 -345.425281) (xy 428.240672 -345.493261)
			(xy 428.28645 -345.565846) (xy 428.32523 -345.642398) (xy 428.356671 -345.722246) (xy 428.380497 -345.804687)
			(xy 428.396498 -345.888997) (xy 428.404533 -345.974435) (xy 428.405036 -346.017342) (xy 428.404533 -346.060249)
			(xy 428.396498 -346.145687) (xy 428.380497 -346.229997) (xy 428.356671 -346.312438) (xy 428.32523 -346.392286)
			(xy 428.28645 -346.468838) (xy 428.240672 -346.541423) (xy 428.188299 -346.609403) (xy 428.12979 -346.672179)
			(xy 428.065659 -346.7292) (xy 427.996471 -346.779966) (xy 427.922832 -346.82403) (xy 427.845392 -346.861004)
			(xy 427.764829 -346.890565) (xy 427.681852 -346.912451) (xy 427.59719 -346.926471) (xy 427.511588 -346.932502)
			(xy 427.425796 -346.93049) (xy 427.34057 -346.920454) (xy 427.256659 -346.902481) (xy 427.174799 -346.876729)
			(xy 427.09571 -346.843425) (xy 427.020088 -346.802861) (xy 426.948596 -346.755394) (xy 426.881863 -346.701441)
			(xy 426.820476 -346.641477) (xy 426.764973 -346.576027) (xy 426.715844 -346.505668) (xy 426.673518 -346.431017)
			(xy 426.638369 -346.352731) (xy 426.610706 -346.271497) (xy 426.59077 -346.18803) (xy 426.578739 -346.103062)
			(xy 426.574717 -346.017342) (xy 422.207436 -346.017342) (xy 422.206933 -346.060249) (xy 422.198898 -346.145687)
			(xy 422.182897 -346.229997) (xy 422.159071 -346.312438) (xy 422.12763 -346.392286) (xy 422.08885 -346.468838)
			(xy 422.043072 -346.541423) (xy 421.990699 -346.609403) (xy 421.93219 -346.672179) (xy 421.868059 -346.7292)
			(xy 421.798871 -346.779966) (xy 421.725232 -346.82403) (xy 421.647792 -346.861004) (xy 421.567229 -346.890565)
			(xy 421.484252 -346.912451) (xy 421.39959 -346.926471) (xy 421.313988 -346.932502) (xy 421.228196 -346.93049)
			(xy 421.14297 -346.920454) (xy 421.059059 -346.902481) (xy 420.977199 -346.876729) (xy 420.89811 -346.843425)
			(xy 420.822488 -346.802861) (xy 420.750996 -346.755394) (xy 420.684263 -346.701441) (xy 420.622876 -346.641477)
			(xy 420.567373 -346.576027) (xy 420.518244 -346.505668) (xy 420.475918 -346.431017) (xy 420.440769 -346.352731)
			(xy 420.413106 -346.271497) (xy 420.39317 -346.18803) (xy 420.381139 -346.103062) (xy 420.377117 -346.017342)
			(xy 416.01662 -346.017342) (xy 416.016191 -346.053899) (xy 416.008156 -346.139337) (xy 415.992155 -346.223647)
			(xy 415.968329 -346.306088) (xy 415.936888 -346.385936) (xy 415.898108 -346.462488) (xy 415.85233 -346.535073)
			(xy 415.799957 -346.603053) (xy 415.741448 -346.665829) (xy 415.677317 -346.72285) (xy 415.608129 -346.773616)
			(xy 415.53449 -346.81768) (xy 415.45705 -346.854654) (xy 415.376487 -346.884215) (xy 415.29351 -346.906101)
			(xy 415.208848 -346.920121) (xy 415.123246 -346.926152) (xy 415.037454 -346.92414) (xy 414.952228 -346.914104)
			(xy 414.868317 -346.896131) (xy 414.786457 -346.870379) (xy 414.707368 -346.837075) (xy 414.631746 -346.796511)
			(xy 414.560254 -346.749044) (xy 414.493521 -346.695091) (xy 414.432134 -346.635127) (xy 414.376631 -346.569677)
			(xy 414.327502 -346.499318) (xy 414.285176 -346.424667) (xy 414.250027 -346.346381) (xy 414.222364 -346.265147)
			(xy 414.202428 -346.18168) (xy 414.190397 -346.096712) (xy 414.186375 -346.010992) (xy 409.51531 -346.010992)
			(xy 409.51531 -351.152968) (xy 412.661354 -351.152968) (xy 412.661788 -351.125596) (xy 412.669612 -351.071415)
			(xy 412.685107 -351.018912) (xy 412.707957 -350.969165) (xy 412.737689 -350.9232) (xy 412.755334 -350.90227)
			(xy 412.764599 -350.890965) (xy 412.776768 -350.864398) (xy 412.780933 -350.835476) (xy 412.776755 -350.806555)
			(xy 412.764573 -350.779995) (xy 412.755334 -350.768666) (xy 412.737662 -350.747759) (xy 412.707938 -350.701787)
			(xy 412.685094 -350.652036) (xy 412.6696 -350.59953) (xy 412.661774 -350.545348) (xy 412.661777 -350.490604)
			(xy 412.66961 -350.436423) (xy 412.685111 -350.383918) (xy 412.707961 -350.334171) (xy 412.737691 -350.288203)
			(xy 412.755334 -350.26727) (xy 412.764599 -350.255965) (xy 412.776768 -350.229398) (xy 412.780933 -350.200476)
			(xy 412.776755 -350.171555) (xy 412.764573 -350.144995) (xy 412.755334 -350.133666) (xy 412.737662 -350.112759)
			(xy 412.707938 -350.066787) (xy 412.685094 -350.017036) (xy 412.6696 -349.96453) (xy 412.661774 -349.910348)
			(xy 412.661777 -349.855604) (xy 412.66961 -349.801423) (xy 412.685111 -349.748918) (xy 412.707961 -349.699171)
			(xy 412.737691 -349.653203) (xy 412.755334 -349.63227) (xy 412.764599 -349.620965) (xy 412.776768 -349.594398)
			(xy 412.780933 -349.565476) (xy 412.776755 -349.536555) (xy 412.764573 -349.509995) (xy 412.755334 -349.498666)
			(xy 412.737662 -349.477759) (xy 412.707938 -349.431787) (xy 412.685094 -349.382036) (xy 412.6696 -349.32953)
			(xy 412.661774 -349.275348) (xy 412.661777 -349.220604) (xy 412.66961 -349.166423) (xy 412.685111 -349.113918)
			(xy 412.707961 -349.064171) (xy 412.737691 -349.018203) (xy 412.755334 -348.99727) (xy 412.764599 -348.985965)
			(xy 412.776768 -348.959398) (xy 412.780933 -348.930476) (xy 412.776755 -348.901555) (xy 412.764573 -348.874995)
			(xy 412.755334 -348.863666) (xy 412.737662 -348.842759) (xy 412.707938 -348.796787) (xy 412.685094 -348.747036)
			(xy 412.6696 -348.69453) (xy 412.661774 -348.640348) (xy 412.661777 -348.585604) (xy 412.66961 -348.531423)
			(xy 412.685111 -348.478918) (xy 412.707961 -348.429171) (xy 412.737691 -348.383203) (xy 412.755334 -348.36227)
			(xy 412.764599 -348.350965) (xy 412.776768 -348.324398) (xy 412.780933 -348.295476) (xy 412.776755 -348.266555)
			(xy 412.764573 -348.239995) (xy 412.755334 -348.228666) (xy 412.737662 -348.207759) (xy 412.707938 -348.161787)
			(xy 412.685094 -348.112036) (xy 412.6696 -348.05953) (xy 412.661774 -348.005348) (xy 412.661777 -347.950604)
			(xy 412.66961 -347.896423) (xy 412.685111 -347.843918) (xy 412.707961 -347.794171) (xy 412.737691 -347.748203)
			(xy 412.755334 -347.72727) (xy 412.764599 -347.715965) (xy 412.776768 -347.689398) (xy 412.780933 -347.660476)
			(xy 412.776755 -347.631555) (xy 412.764573 -347.604995) (xy 412.755334 -347.593666) (xy 412.737718 -347.572715)
			(xy 412.708001 -347.526748) (xy 412.68516 -347.477006) (xy 412.669664 -347.424509) (xy 412.661831 -347.370336)
			(xy 412.661354 -347.342968) (xy 412.661848 -347.315718) (xy 412.669608 -347.261772) (xy 412.684965 -347.20948)
			(xy 412.707607 -347.159905) (xy 412.737073 -347.114057) (xy 412.772764 -347.072868) (xy 412.813952 -347.037177)
			(xy 412.8598 -347.00771) (xy 412.909374 -346.985067) (xy 412.961666 -346.969709) (xy 413.015612 -346.961948)
			(xy 413.042862 -346.96146) (xy 413.070232 -346.961934) (xy 413.124411 -346.969747) (xy 413.176915 -346.985234)
			(xy 413.226662 -347.008074) (xy 413.272629 -347.037799) (xy 413.29356 -347.05544) (xy 413.304888 -347.064676)
			(xy 413.331445 -347.076852) (xy 413.360362 -347.081025) (xy 413.389279 -347.076852) (xy 413.415836 -347.064676)
			(xy 413.427164 -347.05544) (xy 413.448104 -347.037811) (xy 413.494074 -347.008096) (xy 413.543819 -346.985257)
			(xy 413.596319 -346.969764) (xy 413.650493 -346.961935) (xy 413.677862 -346.96146) (xy 413.678116 -346.96146)
			(xy 413.70613 -346.961997) (xy 413.761552 -346.970214) (xy 413.815178 -346.986441) (xy 413.865858 -347.010328)
			(xy 413.912505 -347.041364) (xy 413.93364 -347.059758) (xy 413.945082 -347.069403) (xy 413.972125 -347.082183)
			(xy 414.001712 -347.086569) (xy 414.031299 -347.082183) (xy 414.058342 -347.069403) (xy 414.069784 -347.059758)
			(xy 414.090898 -347.041333) (xy 414.137534 -347.010265) (xy 414.188217 -346.986362) (xy 414.241854 -346.97014)
			(xy 414.297289 -346.961948) (xy 414.325308 -346.96146) (xy 414.325562 -346.96146) (xy 414.352812 -346.961991)
			(xy 414.406759 -346.969742) (xy 414.459054 -346.985091) (xy 414.508632 -347.007727) (xy 414.554484 -347.037188)
			(xy 414.595676 -347.072875) (xy 414.63137 -347.11406) (xy 414.66084 -347.159907) (xy 414.683484 -347.20948)
			(xy 414.698844 -347.261772) (xy 414.706604 -347.315718) (xy 414.70707 -347.342968) (xy 414.706592 -347.370338)
			(xy 414.698779 -347.424517) (xy 414.683293 -347.47702) (xy 414.660453 -347.526767) (xy 414.63073 -347.572734)
			(xy 414.61309 -347.593666) (xy 414.603885 -347.605017) (xy 414.591705 -347.631566) (xy 414.587527 -347.660476)
			(xy 414.591691 -347.689387) (xy 414.603858 -347.715943) (xy 414.61309 -347.72727) (xy 414.630699 -347.748228)
			(xy 414.660423 -347.794192) (xy 414.68327 -347.843934) (xy 414.698768 -347.896432) (xy 414.706599 -347.950607)
			(xy 414.706602 -348.005345) (xy 414.698778 -348.059521) (xy 414.683287 -348.11202) (xy 414.660447 -348.161765)
			(xy 414.630728 -348.207733) (xy 414.61309 -348.228666) (xy 414.603885 -348.240017) (xy 414.591705 -348.266566)
			(xy 414.587527 -348.295476) (xy 414.591691 -348.324387) (xy 414.603858 -348.350943) (xy 414.61309 -348.36227)
			(xy 414.630699 -348.383228) (xy 414.660423 -348.429192) (xy 414.68327 -348.478934) (xy 414.698768 -348.531432)
			(xy 414.706599 -348.585607) (xy 414.706602 -348.640345) (xy 414.698778 -348.694521) (xy 414.683287 -348.74702)
			(xy 414.660447 -348.796765) (xy 414.630728 -348.842733) (xy 414.61309 -348.863666) (xy 414.603885 -348.875017)
			(xy 414.591705 -348.901566) (xy 414.587527 -348.930476) (xy 414.591691 -348.959387) (xy 414.603858 -348.985943)
			(xy 414.61309 -348.99727) (xy 414.630699 -349.018228) (xy 414.660423 -349.064192) (xy 414.68327 -349.113934)
			(xy 414.698768 -349.166432) (xy 414.706599 -349.220607) (xy 414.706602 -349.275345) (xy 414.698778 -349.329521)
			(xy 414.683287 -349.38202) (xy 414.660447 -349.431765) (xy 414.630728 -349.477733) (xy 414.61309 -349.498666)
			(xy 414.603885 -349.510017) (xy 414.591705 -349.536566) (xy 414.587527 -349.565476) (xy 414.591691 -349.594387)
			(xy 414.603858 -349.620943) (xy 414.61309 -349.63227) (xy 414.630699 -349.653228) (xy 414.660423 -349.699192)
			(xy 414.68327 -349.748934) (xy 414.698768 -349.801432) (xy 414.706599 -349.855607) (xy 414.706602 -349.910345)
			(xy 414.698778 -349.964521) (xy 414.683287 -350.01702) (xy 414.660447 -350.066765) (xy 414.630728 -350.112733)
			(xy 414.61309 -350.133666) (xy 414.603885 -350.145017) (xy 414.591705 -350.171566) (xy 414.587527 -350.200476)
			(xy 414.591691 -350.229387) (xy 414.603858 -350.255943) (xy 414.61309 -350.26727) (xy 414.630699 -350.288228)
			(xy 414.660423 -350.334192) (xy 414.68327 -350.383934) (xy 414.698768 -350.436432) (xy 414.706599 -350.490607)
			(xy 414.706602 -350.545345) (xy 414.698778 -350.599521) (xy 414.683287 -350.65202) (xy 414.660447 -350.701765)
			(xy 414.630728 -350.747733) (xy 414.61309 -350.768666) (xy 414.603885 -350.780017) (xy 414.591705 -350.806566)
			(xy 414.587527 -350.835476) (xy 414.591691 -350.864387) (xy 414.603858 -350.890943) (xy 414.61309 -350.90227)
			(xy 414.630727 -350.923204) (xy 414.660439 -350.969176) (xy 414.683276 -351.018923) (xy 414.698767 -351.071423)
			(xy 414.706596 -351.125599) (xy 414.70707 -351.152968) (xy 417.631626 -351.152968) (xy 417.632067 -351.125597)
			(xy 417.63989 -351.071416) (xy 417.655384 -351.018913) (xy 417.678232 -350.969166) (xy 417.707962 -350.923201)
			(xy 417.725606 -350.90227) (xy 417.734873 -350.890966) (xy 417.747046 -350.864399) (xy 417.751212 -350.835476)
			(xy 417.747032 -350.806554) (xy 417.734847 -350.779994) (xy 417.725606 -350.768666) (xy 417.707935 -350.747758)
			(xy 417.678213 -350.701786) (xy 417.655371 -350.652035) (xy 417.639878 -350.599529) (xy 417.632053 -350.545348)
			(xy 417.632056 -350.490604) (xy 417.639888 -350.436423) (xy 417.655388 -350.38392) (xy 417.678236 -350.334172)
			(xy 417.707964 -350.288203) (xy 417.725606 -350.26727) (xy 417.734873 -350.255966) (xy 417.747046 -350.229399)
			(xy 417.751212 -350.200476) (xy 417.747032 -350.171554) (xy 417.734847 -350.144994) (xy 417.725606 -350.133666)
			(xy 417.707935 -350.112758) (xy 417.678213 -350.066786) (xy 417.655371 -350.017035) (xy 417.639878 -349.964529)
			(xy 417.632053 -349.910348) (xy 417.632056 -349.855604) (xy 417.639888 -349.801423) (xy 417.655388 -349.74892)
			(xy 417.678236 -349.699172) (xy 417.707964 -349.653203) (xy 417.725606 -349.63227) (xy 417.734873 -349.620966)
			(xy 417.747046 -349.594399) (xy 417.751212 -349.565476) (xy 417.747032 -349.536554) (xy 417.734847 -349.509994)
			(xy 417.725606 -349.498666) (xy 417.707935 -349.477758) (xy 417.678213 -349.431786) (xy 417.655371 -349.382035)
			(xy 417.639878 -349.329529) (xy 417.632053 -349.275348) (xy 417.632056 -349.220604) (xy 417.639888 -349.166423)
			(xy 417.655388 -349.11392) (xy 417.678236 -349.064172) (xy 417.707964 -349.018203) (xy 417.725606 -348.99727)
			(xy 417.734873 -348.985966) (xy 417.747046 -348.959399) (xy 417.751212 -348.930476) (xy 417.747032 -348.901554)
			(xy 417.734847 -348.874994) (xy 417.725606 -348.863666) (xy 417.707935 -348.842758) (xy 417.678213 -348.796786)
			(xy 417.655371 -348.747035) (xy 417.639878 -348.694529) (xy 417.632053 -348.640348) (xy 417.632056 -348.585604)
			(xy 417.639888 -348.531423) (xy 417.655388 -348.47892) (xy 417.678236 -348.429172) (xy 417.707964 -348.383203)
			(xy 417.725606 -348.36227) (xy 417.734873 -348.350966) (xy 417.747046 -348.324399) (xy 417.751212 -348.295476)
			(xy 417.747032 -348.266554) (xy 417.734847 -348.239994) (xy 417.725606 -348.228666) (xy 417.707935 -348.207758)
			(xy 417.678213 -348.161786) (xy 417.655371 -348.112035) (xy 417.639878 -348.059529) (xy 417.632053 -348.005348)
			(xy 417.632056 -347.950604) (xy 417.639888 -347.896423) (xy 417.655388 -347.84392) (xy 417.678236 -347.794172)
			(xy 417.707964 -347.748203) (xy 417.725606 -347.72727) (xy 417.734873 -347.715966) (xy 417.747046 -347.689399)
			(xy 417.751212 -347.660476) (xy 417.747032 -347.631554) (xy 417.734847 -347.604994) (xy 417.725606 -347.593666)
			(xy 417.707985 -347.572719) (xy 417.678271 -347.52675) (xy 417.655431 -347.477007) (xy 417.639936 -347.424509)
			(xy 417.632103 -347.370336) (xy 417.631626 -347.342968) (xy 417.632025 -347.315713) (xy 417.639787 -347.261758)
			(xy 417.655149 -347.209457) (xy 417.677798 -347.159874) (xy 417.707273 -347.114019) (xy 417.742973 -347.072826)
			(xy 417.784172 -347.037133) (xy 417.830032 -347.007666) (xy 417.879619 -346.985026) (xy 417.931922 -346.969673)
			(xy 417.985879 -346.96192) (xy 418.013134 -346.96146) (xy 418.013388 -346.96146) (xy 418.041403 -346.961954)
			(xy 418.096827 -346.970182) (xy 418.150454 -346.986419) (xy 418.201134 -347.010316) (xy 418.247778 -347.04136)
			(xy 418.268912 -347.059758) (xy 418.280354 -347.069403) (xy 418.307397 -347.082183) (xy 418.336984 -347.086569)
			(xy 418.366571 -347.082183) (xy 418.393614 -347.069403) (xy 418.405056 -347.059758) (xy 418.426181 -347.041347)
			(xy 418.472814 -347.010276) (xy 418.523494 -346.986371) (xy 418.577129 -346.970145) (xy 418.632562 -346.96195)
			(xy 418.66058 -346.96146) (xy 418.660834 -346.96146) (xy 418.688206 -346.961892) (xy 418.742387 -346.969715)
			(xy 418.794891 -346.985212) (xy 418.844637 -347.008062) (xy 418.890602 -347.037795) (xy 418.911532 -347.05544)
			(xy 418.92286 -347.064676) (xy 418.949417 -347.076852) (xy 418.978334 -347.081025) (xy 419.007251 -347.076852)
			(xy 419.033808 -347.064676) (xy 419.045136 -347.05544) (xy 419.066087 -347.037824) (xy 419.112054 -347.008107)
			(xy 419.161796 -346.985266) (xy 419.214293 -346.96977) (xy 419.268466 -346.961937) (xy 419.295834 -346.96146)
			(xy 419.323085 -346.961946) (xy 419.377031 -346.969706) (xy 419.429323 -346.985064) (xy 419.478899 -347.007707)
			(xy 419.524747 -347.037174) (xy 419.565936 -347.072865) (xy 419.601627 -347.114054) (xy 419.631094 -347.159903)
			(xy 419.653736 -347.209478) (xy 419.669094 -347.261771) (xy 419.676854 -347.315717) (xy 419.677342 -347.342968)
			(xy 419.676871 -347.370338) (xy 419.669057 -347.424518) (xy 419.65357 -347.477021) (xy 419.630728 -347.526768)
			(xy 419.601004 -347.572735) (xy 419.583362 -347.593666) (xy 419.574159 -347.605018) (xy 419.561982 -347.631567)
			(xy 419.557806 -347.660476) (xy 419.561969 -347.689386) (xy 419.574133 -347.715942) (xy 419.583362 -347.72727)
			(xy 419.600972 -347.748228) (xy 419.630699 -347.794191) (xy 419.653547 -347.843933) (xy 419.669046 -347.896431)
			(xy 419.676878 -347.950607) (xy 419.676881 -348.005345) (xy 419.669056 -348.059521) (xy 419.653564 -348.112022)
			(xy 419.630722 -348.161767) (xy 419.601001 -348.207734) (xy 419.583362 -348.228666) (xy 419.574159 -348.240018)
			(xy 419.561982 -348.266567) (xy 419.557806 -348.295476) (xy 419.561969 -348.324386) (xy 419.574133 -348.350942)
			(xy 419.583362 -348.36227) (xy 419.600972 -348.383228) (xy 419.630699 -348.429191) (xy 419.653547 -348.478933)
			(xy 419.669046 -348.531431) (xy 419.676878 -348.585607) (xy 419.676881 -348.640345) (xy 419.669056 -348.694521)
			(xy 419.653564 -348.747022) (xy 419.630722 -348.796767) (xy 419.601001 -348.842734) (xy 419.583362 -348.863666)
			(xy 419.574159 -348.875018) (xy 419.561982 -348.901567) (xy 419.557806 -348.930476) (xy 419.561969 -348.959386)
			(xy 419.574133 -348.985942) (xy 419.583362 -348.99727) (xy 419.600972 -349.018228) (xy 419.630699 -349.064191)
			(xy 419.653547 -349.113933) (xy 419.669046 -349.166431) (xy 419.676878 -349.220607) (xy 419.676881 -349.275345)
			(xy 419.669056 -349.329521) (xy 419.653564 -349.382022) (xy 419.630722 -349.431767) (xy 419.601001 -349.477734)
			(xy 419.583362 -349.498666) (xy 419.574159 -349.510018) (xy 419.561982 -349.536567) (xy 419.557806 -349.565476)
			(xy 419.561969 -349.594386) (xy 419.574133 -349.620942) (xy 419.583362 -349.63227) (xy 419.600972 -349.653228)
			(xy 419.630699 -349.699191) (xy 419.653547 -349.748933) (xy 419.669046 -349.801431) (xy 419.676878 -349.855607)
			(xy 419.676881 -349.910345) (xy 419.669056 -349.964521) (xy 419.653564 -350.017022) (xy 419.630722 -350.066767)
			(xy 419.601001 -350.112734) (xy 419.583362 -350.133666) (xy 419.574159 -350.145018) (xy 419.561982 -350.171567)
			(xy 419.557806 -350.200476) (xy 419.561969 -350.229386) (xy 419.574133 -350.255942) (xy 419.583362 -350.26727)
			(xy 419.600972 -350.288228) (xy 419.630699 -350.334191) (xy 419.653547 -350.383933) (xy 419.669046 -350.436431)
			(xy 419.676878 -350.490607) (xy 419.676881 -350.545345) (xy 419.669056 -350.599521) (xy 419.653564 -350.652022)
			(xy 419.630722 -350.701767) (xy 419.601001 -350.747734) (xy 419.583362 -350.768666) (xy 419.574159 -350.780018)
			(xy 419.561982 -350.806567) (xy 419.557806 -350.835476) (xy 419.561969 -350.864386) (xy 419.574133 -350.890942)
			(xy 419.583362 -350.90227) (xy 419.600995 -350.923207) (xy 419.630709 -350.969178) (xy 419.653547 -351.018924)
			(xy 419.669039 -351.071424) (xy 419.676868 -351.125599) (xy 419.677342 -351.152968) (xy 422.338754 -351.152968)
			(xy 422.339188 -351.125596) (xy 422.347012 -351.071415) (xy 422.362507 -351.018912) (xy 422.385357 -350.969165)
			(xy 422.415089 -350.9232) (xy 422.432734 -350.90227) (xy 422.441999 -350.890965) (xy 422.454168 -350.864398)
			(xy 422.458333 -350.835476) (xy 422.454155 -350.806555) (xy 422.441973 -350.779995) (xy 422.432734 -350.768666)
			(xy 422.415062 -350.747759) (xy 422.385338 -350.701787) (xy 422.362494 -350.652036) (xy 422.347 -350.59953)
			(xy 422.339174 -350.545348) (xy 422.339177 -350.490604) (xy 422.34701 -350.436423) (xy 422.362511 -350.383918)
			(xy 422.385361 -350.334171) (xy 422.415091 -350.288203) (xy 422.432734 -350.26727) (xy 422.441999 -350.255965)
			(xy 422.454168 -350.229398) (xy 422.458333 -350.200476) (xy 422.454155 -350.171555) (xy 422.441973 -350.144995)
			(xy 422.432734 -350.133666) (xy 422.415062 -350.112759) (xy 422.385338 -350.066787) (xy 422.362494 -350.017036)
			(xy 422.347 -349.96453) (xy 422.339174 -349.910348) (xy 422.339177 -349.855604) (xy 422.34701 -349.801423)
			(xy 422.362511 -349.748918) (xy 422.385361 -349.699171) (xy 422.415091 -349.653203) (xy 422.432734 -349.63227)
			(xy 422.441999 -349.620965) (xy 422.454168 -349.594398) (xy 422.458333 -349.565476) (xy 422.454155 -349.536555)
			(xy 422.441973 -349.509995) (xy 422.432734 -349.498666) (xy 422.415062 -349.477759) (xy 422.385338 -349.431787)
			(xy 422.362494 -349.382036) (xy 422.347 -349.32953) (xy 422.339174 -349.275348) (xy 422.339177 -349.220604)
			(xy 422.34701 -349.166423) (xy 422.362511 -349.113918) (xy 422.385361 -349.064171) (xy 422.415091 -349.018203)
			(xy 422.432734 -348.99727) (xy 422.441999 -348.985965) (xy 422.454168 -348.959398) (xy 422.458333 -348.930476)
			(xy 422.454155 -348.901555) (xy 422.441973 -348.874995) (xy 422.432734 -348.863666) (xy 422.415062 -348.842759)
			(xy 422.385338 -348.796787) (xy 422.362494 -348.747036) (xy 422.347 -348.69453) (xy 422.339174 -348.640348)
			(xy 422.339177 -348.585604) (xy 422.34701 -348.531423) (xy 422.362511 -348.478918) (xy 422.385361 -348.429171)
			(xy 422.415091 -348.383203) (xy 422.432734 -348.36227) (xy 422.441999 -348.350965) (xy 422.454168 -348.324398)
			(xy 422.458333 -348.295476) (xy 422.454155 -348.266555) (xy 422.441973 -348.239995) (xy 422.432734 -348.228666)
			(xy 422.415062 -348.207759) (xy 422.385338 -348.161787) (xy 422.362494 -348.112036) (xy 422.347 -348.05953)
			(xy 422.339174 -348.005348) (xy 422.339177 -347.950604) (xy 422.34701 -347.896423) (xy 422.362511 -347.843918)
			(xy 422.385361 -347.794171) (xy 422.415091 -347.748203) (xy 422.432734 -347.72727) (xy 422.441999 -347.715965)
			(xy 422.454168 -347.689398) (xy 422.458333 -347.660476) (xy 422.454155 -347.631555) (xy 422.441973 -347.604995)
			(xy 422.432734 -347.593666) (xy 422.415118 -347.572715) (xy 422.385401 -347.526748) (xy 422.36256 -347.477006)
			(xy 422.347064 -347.424509) (xy 422.339231 -347.370336) (xy 422.338754 -347.342968) (xy 422.339248 -347.315718)
			(xy 422.347008 -347.261772) (xy 422.362365 -347.20948) (xy 422.385007 -347.159905) (xy 422.414473 -347.114057)
			(xy 422.450164 -347.072868) (xy 422.491352 -347.037177) (xy 422.5372 -347.00771) (xy 422.586774 -346.985067)
			(xy 422.639066 -346.969709) (xy 422.693012 -346.961948) (xy 422.720262 -346.96146) (xy 422.747632 -346.961934)
			(xy 422.801811 -346.969747) (xy 422.854315 -346.985234) (xy 422.904062 -347.008074) (xy 422.950029 -347.037799)
			(xy 422.97096 -347.05544) (xy 422.982288 -347.064676) (xy 423.008845 -347.076852) (xy 423.037762 -347.081025)
			(xy 423.066679 -347.076852) (xy 423.093236 -347.064676) (xy 423.104564 -347.05544) (xy 423.125504 -347.037811)
			(xy 423.171474 -347.008096) (xy 423.221219 -346.985257) (xy 423.273719 -346.969764) (xy 423.327893 -346.961935)
			(xy 423.355262 -346.96146) (xy 423.355516 -346.96146) (xy 423.38353 -346.961997) (xy 423.438952 -346.970214)
			(xy 423.492578 -346.986441) (xy 423.543258 -347.010328) (xy 423.589905 -347.041364) (xy 423.61104 -347.059758)
			(xy 423.622482 -347.069403) (xy 423.649525 -347.082183) (xy 423.679112 -347.086569) (xy 423.708699 -347.082183)
			(xy 423.735742 -347.069403) (xy 423.747184 -347.059758) (xy 423.768298 -347.041333) (xy 423.814934 -347.010265)
			(xy 423.865617 -346.986362) (xy 423.919254 -346.97014) (xy 423.974689 -346.961948) (xy 424.002708 -346.96146)
			(xy 424.002962 -346.96146) (xy 424.030212 -346.961991) (xy 424.084159 -346.969742) (xy 424.136454 -346.985091)
			(xy 424.186032 -347.007727) (xy 424.231884 -347.037188) (xy 424.273076 -347.072875) (xy 424.30877 -347.11406)
			(xy 424.33824 -347.159907) (xy 424.360884 -347.20948) (xy 424.376244 -347.261772) (xy 424.384004 -347.315718)
			(xy 424.38447 -347.342968) (xy 424.383992 -347.370338) (xy 424.376179 -347.424517) (xy 424.360693 -347.47702)
			(xy 424.337853 -347.526767) (xy 424.30813 -347.572734) (xy 424.29049 -347.593666) (xy 424.281285 -347.605017)
			(xy 424.269105 -347.631566) (xy 424.264927 -347.660476) (xy 424.269091 -347.689387) (xy 424.281258 -347.715943)
			(xy 424.29049 -347.72727) (xy 424.308099 -347.748228) (xy 424.337823 -347.794192) (xy 424.36067 -347.843934)
			(xy 424.376168 -347.896432) (xy 424.383999 -347.950607) (xy 424.384002 -348.005345) (xy 424.376178 -348.059521)
			(xy 424.360687 -348.11202) (xy 424.337847 -348.161765) (xy 424.308128 -348.207733) (xy 424.29049 -348.228666)
			(xy 424.281285 -348.240017) (xy 424.269105 -348.266566) (xy 424.264927 -348.295476) (xy 424.269091 -348.324387)
			(xy 424.281258 -348.350943) (xy 424.29049 -348.36227) (xy 424.308099 -348.383228) (xy 424.337823 -348.429192)
			(xy 424.36067 -348.478934) (xy 424.376168 -348.531432) (xy 424.383999 -348.585607) (xy 424.384002 -348.640345)
			(xy 424.376178 -348.694521) (xy 424.360687 -348.74702) (xy 424.337847 -348.796765) (xy 424.308128 -348.842733)
			(xy 424.29049 -348.863666) (xy 424.281285 -348.875017) (xy 424.269105 -348.901566) (xy 424.264927 -348.930476)
			(xy 424.269091 -348.959387) (xy 424.281258 -348.985943) (xy 424.29049 -348.99727) (xy 424.308099 -349.018228)
			(xy 424.337823 -349.064192) (xy 424.36067 -349.113934) (xy 424.376168 -349.166432) (xy 424.383999 -349.220607)
			(xy 424.384002 -349.275345) (xy 424.376178 -349.329521) (xy 424.360687 -349.38202) (xy 424.337847 -349.431765)
			(xy 424.308128 -349.477733) (xy 424.29049 -349.498666) (xy 424.281285 -349.510017) (xy 424.269105 -349.536566)
			(xy 424.264927 -349.565476) (xy 424.269091 -349.594387) (xy 424.281258 -349.620943) (xy 424.29049 -349.63227)
			(xy 424.308099 -349.653228) (xy 424.337823 -349.699192) (xy 424.36067 -349.748934) (xy 424.376168 -349.801432)
			(xy 424.383999 -349.855607) (xy 424.384002 -349.910345) (xy 424.376178 -349.964521) (xy 424.360687 -350.01702)
			(xy 424.337847 -350.066765) (xy 424.308128 -350.112733) (xy 424.29049 -350.133666) (xy 424.281285 -350.145017)
			(xy 424.269105 -350.171566) (xy 424.264927 -350.200476) (xy 424.269091 -350.229387) (xy 424.281258 -350.255943)
			(xy 424.29049 -350.26727) (xy 424.308099 -350.288228) (xy 424.337823 -350.334192) (xy 424.36067 -350.383934)
			(xy 424.376168 -350.436432) (xy 424.383999 -350.490607) (xy 424.384002 -350.545345) (xy 424.376178 -350.599521)
			(xy 424.360687 -350.65202) (xy 424.337847 -350.701765) (xy 424.308128 -350.747733) (xy 424.29049 -350.768666)
			(xy 424.281285 -350.780017) (xy 424.269105 -350.806566) (xy 424.264927 -350.835476) (xy 424.269091 -350.864387)
			(xy 424.281258 -350.890943) (xy 424.29049 -350.90227) (xy 424.308127 -350.923204) (xy 424.337839 -350.969176)
			(xy 424.360676 -351.018923) (xy 424.376167 -351.071423) (xy 424.383996 -351.125599) (xy 424.38447 -351.152968)
			(xy 427.95444 -351.152968) (xy 427.954878 -351.125597) (xy 427.962701 -351.071416) (xy 427.978196 -351.018912)
			(xy 428.001044 -350.969166) (xy 428.030775 -350.9232) (xy 428.04842 -350.90227) (xy 428.057686 -350.890965)
			(xy 428.069857 -350.864399) (xy 428.074023 -350.835476) (xy 428.069843 -350.806555) (xy 428.05766 -350.779994)
			(xy 428.04842 -350.768666) (xy 428.030748 -350.747758) (xy 428.001025 -350.701786) (xy 427.978182 -350.652036)
			(xy 427.962689 -350.59953) (xy 427.954863 -350.545348) (xy 427.954867 -350.490604) (xy 427.962699 -350.436423)
			(xy 427.978199 -350.383919) (xy 428.001049 -350.334172) (xy 428.030777 -350.288203) (xy 428.04842 -350.26727)
			(xy 428.057686 -350.255965) (xy 428.069857 -350.229399) (xy 428.074023 -350.200476) (xy 428.069843 -350.171555)
			(xy 428.05766 -350.144994) (xy 428.04842 -350.133666) (xy 428.030748 -350.112758) (xy 428.001025 -350.066786)
			(xy 427.978182 -350.017036) (xy 427.962689 -349.96453) (xy 427.954863 -349.910348) (xy 427.954867 -349.855604)
			(xy 427.962699 -349.801423) (xy 427.978199 -349.748919) (xy 428.001049 -349.699172) (xy 428.030777 -349.653203)
			(xy 428.04842 -349.63227) (xy 428.057686 -349.620965) (xy 428.069857 -349.594399) (xy 428.074023 -349.565476)
			(xy 428.069843 -349.536555) (xy 428.05766 -349.509994) (xy 428.04842 -349.498666) (xy 428.030748 -349.477758)
			(xy 428.001025 -349.431786) (xy 427.978182 -349.382036) (xy 427.962689 -349.32953) (xy 427.954863 -349.275348)
			(xy 427.954867 -349.220604) (xy 427.962699 -349.166423) (xy 427.978199 -349.113919) (xy 428.001049 -349.064172)
			(xy 428.030777 -349.018203) (xy 428.04842 -348.99727) (xy 428.057686 -348.985965) (xy 428.069857 -348.959399)
			(xy 428.074023 -348.930476) (xy 428.069843 -348.901555) (xy 428.05766 -348.874994) (xy 428.04842 -348.863666)
			(xy 428.030748 -348.842758) (xy 428.001025 -348.796786) (xy 427.978182 -348.747036) (xy 427.962689 -348.69453)
			(xy 427.954863 -348.640348) (xy 427.954867 -348.585604) (xy 427.962699 -348.531423) (xy 427.978199 -348.478919)
			(xy 428.001049 -348.429172) (xy 428.030777 -348.383203) (xy 428.04842 -348.36227) (xy 428.057686 -348.350965)
			(xy 428.069857 -348.324399) (xy 428.074023 -348.295476) (xy 428.069843 -348.266555) (xy 428.05766 -348.239994)
			(xy 428.04842 -348.228666) (xy 428.030748 -348.207758) (xy 428.001025 -348.161786) (xy 427.978182 -348.112036)
			(xy 427.962689 -348.05953) (xy 427.954863 -348.005348) (xy 427.954867 -347.950604) (xy 427.962699 -347.896423)
			(xy 427.978199 -347.843919) (xy 428.001049 -347.794172) (xy 428.030777 -347.748203) (xy 428.04842 -347.72727)
			(xy 428.057686 -347.715965) (xy 428.069857 -347.689399) (xy 428.074023 -347.660476) (xy 428.069843 -347.631555)
			(xy 428.05766 -347.604994) (xy 428.04842 -347.593666) (xy 428.030801 -347.572717) (xy 428.001086 -347.526749)
			(xy 427.978246 -347.477006) (xy 427.96275 -347.424509) (xy 427.954917 -347.370336) (xy 427.95444 -347.342968)
			(xy 427.954825 -347.315712) (xy 427.962588 -347.261756) (xy 427.97795 -347.209454) (xy 428.0006 -347.15987)
			(xy 428.030076 -347.114015) (xy 428.065778 -347.072821) (xy 428.106979 -347.037128) (xy 428.15284 -347.007662)
			(xy 428.202429 -346.985022) (xy 428.254734 -346.969671) (xy 428.308692 -346.96192) (xy 428.335948 -346.96146)
			(xy 428.336202 -346.96146) (xy 428.364218 -346.961946) (xy 428.419642 -346.970176) (xy 428.473269 -346.986414)
			(xy 428.523948 -347.010313) (xy 428.570593 -347.041359) (xy 428.591726 -347.059758) (xy 428.603168 -347.069403)
			(xy 428.630211 -347.082183) (xy 428.659798 -347.086569) (xy 428.689385 -347.082183) (xy 428.716428 -347.069403)
			(xy 428.72787 -347.059758) (xy 428.74899 -347.04134) (xy 428.795624 -347.010271) (xy 428.846306 -346.986366)
			(xy 428.899942 -346.970142) (xy 428.955376 -346.961949) (xy 428.983394 -346.96146) (xy 428.983648 -346.96146)
			(xy 429.011018 -346.961942) (xy 429.065197 -346.969754) (xy 429.1177 -346.985238) (xy 429.167448 -347.008077)
			(xy 429.213414 -347.037799) (xy 429.234346 -347.05544) (xy 429.245674 -347.064676) (xy 429.272231 -347.076852)
			(xy 429.301148 -347.081025) (xy 429.330065 -347.076852) (xy 429.356622 -347.064676) (xy 429.36795 -347.05544)
			(xy 429.388895 -347.037817) (xy 429.434864 -347.008101) (xy 429.484608 -346.985262) (xy 429.537106 -346.969767)
			(xy 429.59128 -346.961936) (xy 429.618648 -346.96146) (xy 429.645899 -346.961933) (xy 429.699845 -346.969695)
			(xy 429.752138 -346.985055) (xy 429.801714 -347.007699) (xy 429.847562 -347.037168) (xy 429.888751 -347.07286)
			(xy 429.924442 -347.11405) (xy 429.953908 -347.1599) (xy 429.976551 -347.209477) (xy 429.991908 -347.26177)
			(xy 429.999668 -347.315717) (xy 430.000156 -347.342968) (xy 429.999682 -347.370338) (xy 429.991868 -347.424517)
			(xy 429.976381 -347.477021) (xy 429.953541 -347.526768) (xy 429.923817 -347.572734) (xy 429.906176 -347.593666)
			(xy 429.896972 -347.605017) (xy 429.884794 -347.631567) (xy 429.880616 -347.660476) (xy 429.88478 -347.689387)
			(xy 429.896946 -347.715942) (xy 429.906176 -347.72727) (xy 429.923785 -347.748228) (xy 429.953511 -347.794192)
			(xy 429.976358 -347.843934) (xy 429.991857 -347.896432) (xy 429.999688 -347.950607) (xy 429.999692 -348.005345)
			(xy 429.991867 -348.059521) (xy 429.976375 -348.112021) (xy 429.953534 -348.161766) (xy 429.923814 -348.207733)
			(xy 429.906176 -348.228666) (xy 429.896972 -348.240017) (xy 429.884794 -348.266567) (xy 429.880616 -348.295476)
			(xy 429.88478 -348.324387) (xy 429.896946 -348.350942) (xy 429.906176 -348.36227) (xy 429.923785 -348.383228)
			(xy 429.953511 -348.429192) (xy 429.976358 -348.478934) (xy 429.991857 -348.531432) (xy 429.999688 -348.585607)
			(xy 429.999692 -348.640345) (xy 429.991867 -348.694521) (xy 429.976375 -348.747021) (xy 429.953534 -348.796766)
			(xy 429.923814 -348.842733) (xy 429.906176 -348.863666) (xy 429.896972 -348.875017) (xy 429.884794 -348.901567)
			(xy 429.880616 -348.930476) (xy 429.88478 -348.959387) (xy 429.896946 -348.985942) (xy 429.906176 -348.99727)
			(xy 429.923785 -349.018228) (xy 429.953511 -349.064192) (xy 429.976358 -349.113934) (xy 429.991857 -349.166432)
			(xy 429.999688 -349.220607) (xy 429.999692 -349.275345) (xy 429.991867 -349.329521) (xy 429.976375 -349.382021)
			(xy 429.953534 -349.431766) (xy 429.923814 -349.477733) (xy 429.906176 -349.498666) (xy 429.896972 -349.510017)
			(xy 429.884794 -349.536567) (xy 429.880616 -349.565476) (xy 429.88478 -349.594387) (xy 429.896946 -349.620942)
			(xy 429.906176 -349.63227) (xy 429.923785 -349.653228) (xy 429.953511 -349.699192) (xy 429.976358 -349.748934)
			(xy 429.991857 -349.801432) (xy 429.999688 -349.855607) (xy 429.999692 -349.910345) (xy 429.991867 -349.964521)
			(xy 429.976375 -350.017021) (xy 429.953534 -350.066766) (xy 429.923814 -350.112733) (xy 429.906176 -350.133666)
			(xy 429.896972 -350.145017) (xy 429.884794 -350.171567) (xy 429.880616 -350.200476) (xy 429.88478 -350.229387)
			(xy 429.896946 -350.255942) (xy 429.906176 -350.26727) (xy 429.923785 -350.288228) (xy 429.953511 -350.334192)
			(xy 429.976358 -350.383934) (xy 429.991857 -350.436432) (xy 429.999688 -350.490607) (xy 429.999692 -350.545345)
			(xy 429.991867 -350.599521) (xy 429.976375 -350.652021) (xy 429.953534 -350.701766) (xy 429.923814 -350.747733)
			(xy 429.906176 -350.768666) (xy 429.896972 -350.780017) (xy 429.884794 -350.806567) (xy 429.880616 -350.835476)
			(xy 429.88478 -350.864387) (xy 429.896946 -350.890942) (xy 429.906176 -350.90227) (xy 429.923811 -350.923206)
			(xy 429.953524 -350.969177) (xy 429.976361 -351.018924) (xy 429.991853 -351.071424) (xy 429.999682 -351.125599)
			(xy 430.000156 -351.152968) (xy 429.999592 -351.180216) (xy 429.991841 -351.234159) (xy 429.976493 -351.286449)
			(xy 429.953859 -351.336023) (xy 429.9244 -351.381871) (xy 429.888717 -351.42306) (xy 429.847535 -351.458752)
			(xy 429.801693 -351.48822) (xy 429.752124 -351.510865) (xy 429.699837 -351.526224) (xy 429.645896 -351.533986)
			(xy 429.618648 -351.534476) (xy 429.591279 -351.533988) (xy 429.5371 -351.526176) (xy 429.484597 -351.510693)
			(xy 429.43485 -351.487856) (xy 429.388882 -351.458135) (xy 429.36795 -351.440496) (xy 429.356622 -351.43126)
			(xy 429.330065 -351.419084) (xy 429.301148 -351.414911) (xy 429.272231 -351.419084) (xy 429.245674 -351.43126)
			(xy 429.234346 -351.440496) (xy 429.213407 -351.458126) (xy 429.167436 -351.48784) (xy 429.11769 -351.510677)
			(xy 429.065191 -351.52617) (xy 429.011017 -351.534001) (xy 428.983648 -351.534476) (xy 428.983394 -351.534476)
			(xy 428.95538 -351.533949) (xy 428.899957 -351.525732) (xy 428.846329 -351.509504) (xy 428.795649 -351.485614)
			(xy 428.749004 -351.454574) (xy 428.72787 -351.436178) (xy 428.716428 -351.426533) (xy 428.689385 -351.413753)
			(xy 428.659798 -351.409367) (xy 428.630211 -351.413753) (xy 428.603168 -351.426533) (xy 428.591726 -351.436178)
			(xy 428.570613 -351.454604) (xy 428.523977 -351.485671) (xy 428.473293 -351.509573) (xy 428.419656 -351.525796)
			(xy 428.364221 -351.533988) (xy 428.336202 -351.534476) (xy 428.335948 -351.534476) (xy 428.308695 -351.534)
			(xy 428.254743 -351.526249) (xy 428.202443 -351.510897) (xy 428.152861 -351.488258) (xy 428.107006 -351.458792)
			(xy 428.065812 -351.423099) (xy 428.030118 -351.381907) (xy 428.00065 -351.336053) (xy 427.978008 -351.286472)
			(xy 427.962655 -351.234173) (xy 427.954901 -351.180221) (xy 427.95444 -351.152968) (xy 424.38447 -351.152968)
			(xy 424.384015 -351.180222) (xy 424.376261 -351.234175) (xy 424.360907 -351.286475) (xy 424.338266 -351.336058)
			(xy 424.308798 -351.381913) (xy 424.273103 -351.423107) (xy 424.231908 -351.458801) (xy 424.186053 -351.488269)
			(xy 424.13647 -351.510909) (xy 424.084169 -351.526262) (xy 424.030216 -351.534015) (xy 424.002962 -351.534476)
			(xy 424.002708 -351.534476) (xy 423.974692 -351.534) (xy 423.919267 -351.525771) (xy 423.865639 -351.509531)
			(xy 423.814959 -351.485629) (xy 423.768316 -351.454579) (xy 423.747184 -351.436178) (xy 423.735742 -351.426533)
			(xy 423.708699 -351.413753) (xy 423.679112 -351.409367) (xy 423.649525 -351.413753) (xy 423.622482 -351.426533)
			(xy 423.61104 -351.436178) (xy 423.589922 -351.454597) (xy 423.543287 -351.485665) (xy 423.492604 -351.509569)
			(xy 423.438968 -351.525793) (xy 423.383534 -351.533987) (xy 423.355516 -351.534476) (xy 423.355262 -351.534476)
			(xy 423.327893 -351.533979) (xy 423.273715 -351.52617) (xy 423.221212 -351.510688) (xy 423.171464 -351.487853)
			(xy 423.125496 -351.458135) (xy 423.104564 -351.440496) (xy 423.093236 -351.43126) (xy 423.066679 -351.419084)
			(xy 423.037762 -351.414911) (xy 423.008845 -351.419084) (xy 422.982288 -351.43126) (xy 422.97096 -351.440496)
			(xy 422.950016 -351.45812) (xy 422.904046 -351.487834) (xy 422.854302 -351.510673) (xy 422.801804 -351.526168)
			(xy 422.74763 -351.534) (xy 422.720262 -351.534476) (xy 422.693008 -351.534057) (xy 422.639057 -351.526295)
			(xy 422.586759 -351.510933) (xy 422.537179 -351.488285) (xy 422.491327 -351.458812) (xy 422.450137 -351.423114)
			(xy 422.414446 -351.381917) (xy 422.384981 -351.336059) (xy 422.362342 -351.286476) (xy 422.34699 -351.234175)
			(xy 422.339238 -351.180222) (xy 422.338754 -351.152968) (xy 419.677342 -351.152968) (xy 419.676792 -351.180217)
			(xy 419.669041 -351.234161) (xy 419.653691 -351.286452) (xy 419.631057 -351.336027) (xy 419.601597 -351.381876)
			(xy 419.565912 -351.423065) (xy 419.524728 -351.458757) (xy 419.478885 -351.488225) (xy 419.429314 -351.510868)
			(xy 419.377025 -351.526227) (xy 419.323083 -351.533987) (xy 419.295834 -351.534476) (xy 419.268464 -351.533996)
			(xy 419.214285 -351.526182) (xy 419.161782 -351.510697) (xy 419.112035 -351.487858) (xy 419.066068 -351.458136)
			(xy 419.045136 -351.440496) (xy 419.033808 -351.43126) (xy 419.007251 -351.419084) (xy 418.978334 -351.414911)
			(xy 418.949417 -351.419084) (xy 418.92286 -351.43126) (xy 418.911532 -351.440496) (xy 418.890598 -351.458133)
			(xy 418.844626 -351.487845) (xy 418.794879 -351.510682) (xy 418.742379 -351.526173) (xy 418.688203 -351.534002)
			(xy 418.660834 -351.534476) (xy 418.66058 -351.534476) (xy 418.632566 -351.533958) (xy 418.577142 -351.525738)
			(xy 418.523515 -351.509508) (xy 418.472835 -351.485616) (xy 418.42619 -351.454575) (xy 418.405056 -351.436178)
			(xy 418.393614 -351.426533) (xy 418.366571 -351.413753) (xy 418.336984 -351.409367) (xy 418.307397 -351.413753)
			(xy 418.280354 -351.426533) (xy 418.268912 -351.436178) (xy 418.247805 -351.454611) (xy 418.201167 -351.485677)
			(xy 418.150482 -351.509578) (xy 418.096843 -351.525798) (xy 418.041407 -351.533989) (xy 418.013388 -351.534476)
			(xy 418.013134 -351.534476) (xy 417.985881 -351.534013) (xy 417.931928 -351.52626) (xy 417.879628 -351.510906)
			(xy 417.830046 -351.488266) (xy 417.784191 -351.458798) (xy 417.742997 -351.423104) (xy 417.707303 -351.38191)
			(xy 417.677835 -351.336056) (xy 417.655194 -351.286474) (xy 417.639841 -351.234174) (xy 417.632087 -351.180221)
			(xy 417.631626 -351.152968) (xy 414.70707 -351.152968) (xy 414.706615 -351.180222) (xy 414.698861 -351.234175)
			(xy 414.683507 -351.286475) (xy 414.660866 -351.336058) (xy 414.631398 -351.381913) (xy 414.595703 -351.423107)
			(xy 414.554508 -351.458801) (xy 414.508653 -351.488269) (xy 414.45907 -351.510909) (xy 414.406769 -351.526262)
			(xy 414.352816 -351.534015) (xy 414.325562 -351.534476) (xy 414.325308 -351.534476) (xy 414.297292 -351.534)
			(xy 414.241867 -351.525771) (xy 414.188239 -351.509531) (xy 414.137559 -351.485629) (xy 414.090916 -351.454579)
			(xy 414.069784 -351.436178) (xy 414.058342 -351.426533) (xy 414.031299 -351.413753) (xy 414.001712 -351.409367)
			(xy 413.972125 -351.413753) (xy 413.945082 -351.426533) (xy 413.93364 -351.436178) (xy 413.912522 -351.454597)
			(xy 413.865887 -351.485665) (xy 413.815204 -351.509569) (xy 413.761568 -351.525793) (xy 413.706134 -351.533987)
			(xy 413.678116 -351.534476) (xy 413.677862 -351.534476) (xy 413.650493 -351.533979) (xy 413.596315 -351.52617)
			(xy 413.543812 -351.510688) (xy 413.494064 -351.487853) (xy 413.448096 -351.458135) (xy 413.427164 -351.440496)
			(xy 413.415836 -351.43126) (xy 413.389279 -351.419084) (xy 413.360362 -351.414911) (xy 413.331445 -351.419084)
			(xy 413.304888 -351.43126) (xy 413.29356 -351.440496) (xy 413.272616 -351.45812) (xy 413.226646 -351.487834)
			(xy 413.176902 -351.510673) (xy 413.124404 -351.526168) (xy 413.07023 -351.534) (xy 413.042862 -351.534476)
			(xy 413.015608 -351.534057) (xy 412.961657 -351.526295) (xy 412.909359 -351.510933) (xy 412.859779 -351.488285)
			(xy 412.813927 -351.458812) (xy 412.772737 -351.423114) (xy 412.737046 -351.381917) (xy 412.707581 -351.336059)
			(xy 412.684942 -351.286476) (xy 412.66959 -351.234175) (xy 412.661838 -351.180222) (xy 412.661354 -351.152968)
			(xy 409.51531 -351.152968) (xy 409.51531 -358.48163) (xy 409.621228 -359.206546) (xy 409.669996 -359.200958)
			(xy 409.680942 -359.199768) (xy 409.702927 -359.198498) (xy 409.713938 -359.198418) (xy 409.741187 -359.198907)
			(xy 409.795129 -359.206668) (xy 409.847418 -359.222027) (xy 409.896988 -359.24467) (xy 409.942832 -359.274138)
			(xy 409.984016 -359.30983) (xy 410.0197 -359.351019) (xy 410.04916 -359.396868) (xy 410.071796 -359.446442)
			(xy 410.087146 -359.498734) (xy 410.094898 -359.552677) (xy 410.095446 -359.579926) (xy 410.095008 -359.606572)
			(xy 410.0876 -359.659346) (xy 410.072919 -359.710575) (xy 410.05125 -359.759263) (xy 410.023016 -359.80446)
			(xy 409.988765 -359.845287) (xy 409.949164 -359.880949) (xy 409.904986 -359.910753) (xy 409.857089 -359.934116)
			(xy 409.806406 -359.950586) (xy 409.780232 -359.955592) (xy 409.731718 -359.964228) (xy 409.745434 -360.057192)
			(xy 409.769385 -360.067727) (xy 409.814169 -360.094787) (xy 409.854514 -360.128104) (xy 409.889555 -360.166963)
			(xy 409.918538 -360.210526) (xy 409.940839 -360.25786) (xy 409.95598 -360.307945) (xy 409.963635 -360.359706)
			(xy 409.964128 -360.385868) (xy 409.963665 -360.411674) (xy 409.956209 -360.462745) (xy 409.941463 -360.512206)
			(xy 409.919735 -360.559022) (xy 409.89148 -360.602214) (xy 409.85729 -360.640877) (xy 409.83789 -360.657902)
			(xy 409.844953 -360.67125) (xy 409.865463 -360.693394) (xy 409.89155 -360.708575) (xy 409.920936 -360.715467)
			(xy 409.951053 -360.713466) (xy 409.979269 -360.702748) (xy 409.99156 -360.69397) (xy 410.011728 -360.678819)
			(xy 410.055293 -360.653392) (xy 410.101828 -360.633926) (xy 410.150522 -360.620759) (xy 410.200527 -360.614121)
			(xy 410.225748 -360.613706) (xy 410.252996 -360.614196) (xy 410.306936 -360.621957) (xy 410.359223 -360.637316)
			(xy 410.408793 -360.659959) (xy 410.454635 -360.689425) (xy 410.495818 -360.725116) (xy 410.531503 -360.766303)
			(xy 410.560964 -360.812149) (xy 410.583601 -360.861722) (xy 410.598953 -360.914011) (xy 410.606708 -360.967952)
			(xy 410.606708 -361.022448) (xy 410.598953 -361.07639) (xy 410.583601 -361.128678) (xy 410.560964 -361.178251)
			(xy 410.531503 -361.224097) (xy 410.495818 -361.265284) (xy 410.454635 -361.300975) (xy 410.408793 -361.330441)
			(xy 410.359223 -361.353084) (xy 410.306936 -361.368443) (xy 410.252996 -361.376204) (xy 410.225748 -361.376722)
			(xy 410.22524 -361.376722) (xy 410.201709 -361.376357) (xy 410.155009 -361.370534) (xy 410.10938 -361.359007)
			(xy 410.087318 -361.350814) (xy 410.073003 -361.345891) (xy 410.042822 -361.343761) (xy 410.013341 -361.350565)
			(xy 409.987146 -361.365707) (xy 409.966535 -361.387857) (xy 409.953317 -361.415073) (xy 409.948651 -361.444967)
			(xy 409.950158 -361.460034) (xy 409.994608 -361.76458) (xy 409.997052 -361.778149) (xy 410.008189 -361.803359)
			(xy 410.025667 -361.824669) (xy 410.04821 -361.840524) (xy 410.074175 -361.849767) (xy 410.101666 -361.851725)
			(xy 410.115258 -361.849416) (xy 410.133914 -361.845857) (xy 410.171705 -361.842039) (xy 410.190696 -361.841796)
			(xy 410.191458 -361.841796) (xy 410.218713 -361.842256) (xy 410.272668 -361.850009) (xy 410.324971 -361.865361)
			(xy 410.374556 -361.888001) (xy 410.420414 -361.917468) (xy 410.461611 -361.953162) (xy 410.497309 -361.994356)
			(xy 410.526781 -362.040211) (xy 410.549426 -362.089794) (xy 410.564783 -362.142095) (xy 410.572541 -362.196049)
			(xy 410.572966 -362.223304) (xy 410.572452 -362.251589) (xy 410.564097 -362.307538) (xy 410.547572 -362.361639)
			(xy 410.523237 -362.412707) (xy 410.491628 -362.459622) (xy 410.453437 -362.501353) (xy 410.409502 -362.536988)
			(xy 410.360786 -362.565743) (xy 410.308358 -362.586988) (xy 410.253367 -362.600258) (xy 410.22524 -362.603288)
			(xy 410.211558 -362.604996) (xy 410.18578 -362.614746) (xy 410.163545 -362.631029) (xy 410.146467 -362.652661)
			(xy 410.135791 -362.67807) (xy 410.132291 -362.705407) (xy 410.1338 -362.719112) (xy 410.147262 -362.812076)
			(xy 410.191458 -362.812076) (xy 410.218713 -362.812536) (xy 410.27267 -362.820288) (xy 410.324974 -362.83564)
			(xy 410.37456 -362.85828) (xy 410.42042 -362.887747) (xy 410.461619 -362.92344) (xy 410.497318 -362.964634)
			(xy 410.526792 -363.010489) (xy 410.549439 -363.060072) (xy 410.5648 -363.112374) (xy 410.57256 -363.166329)
			(xy 410.572966 -363.193584) (xy 410.57248 -363.220743) (xy 410.564763 -363.274512) (xy 410.549496 -363.326641)
			(xy 410.52699 -363.376078) (xy 410.497697 -363.421823) (xy 410.462212 -363.462949) (xy 410.421252 -363.498626)
			(xy 410.375645 -363.528132) (xy 410.326314 -363.55087) (xy 410.315624 -363.554264) (xy 412.204154 -363.554264)
			(xy 412.204154 -363.55401) (xy 412.204649 -363.525995) (xy 412.212876 -363.470571) (xy 412.229113 -363.416944)
			(xy 412.25301 -363.366265) (xy 412.284054 -363.31962) (xy 412.302452 -363.298486) (xy 412.312086 -363.287035)
			(xy 412.324872 -363.259996) (xy 412.329261 -363.23041) (xy 412.324878 -363.200824) (xy 412.312097 -363.173783)
			(xy 412.302452 -363.162342) (xy 412.284039 -363.141219) (xy 412.252969 -363.094585) (xy 412.229064 -363.043905)
			(xy 412.212839 -362.990269) (xy 412.204644 -362.934836) (xy 412.204154 -362.906818) (xy 412.204154 -362.906564)
			(xy 412.204644 -362.879314) (xy 412.212405 -362.825368) (xy 412.227762 -362.773076) (xy 412.250405 -362.723501)
			(xy 412.279871 -362.677652) (xy 412.315562 -362.636464) (xy 412.356751 -362.600773) (xy 412.402599 -362.571306)
			(xy 412.452174 -362.548663) (xy 412.504466 -362.533305) (xy 412.558412 -362.525544) (xy 412.585662 -362.525056)
			(xy 412.58617 -362.525056) (xy 412.614072 -362.525555) (xy 412.669278 -362.533702) (xy 412.722706 -362.549813)
			(xy 412.773213 -362.573542) (xy 412.796736 -362.588556) (xy 413.543496 -362.588556) (xy 413.568482 -362.589049)
			(xy 413.617837 -362.596881) (xy 413.665359 -362.612339) (xy 413.709877 -362.635041) (xy 413.750296 -362.664428)
			(xy 413.768286 -362.681774) (xy 414.105852 -363.01934) (xy 415.900108 -363.01934) (xy 416.26409 -362.655358)
			(xy 416.282054 -362.63798) (xy 416.32247 -362.608578) (xy 416.366994 -362.58587) (xy 416.414525 -362.570417)
			(xy 416.46389 -362.5626) (xy 416.48888 -362.56214) (xy 418.821108 -362.56214) (xy 419.48989 -361.893358)
			(xy 419.507854 -361.87598) (xy 419.54827 -361.846578) (xy 419.592794 -361.82387) (xy 419.640325 -361.808417)
			(xy 419.68969 -361.8006) (xy 419.71468 -361.80014) (xy 421.479218 -361.80014) (xy 421.504202 -361.800649)
			(xy 421.553554 -361.808484) (xy 421.601071 -361.823943) (xy 421.645586 -361.846645) (xy 421.686001 -361.876031)
			(xy 421.704008 -361.893358) (xy 422.349168 -362.538518) (xy 422.363138 -362.542074) (xy 422.390538 -362.549182)
			(xy 422.443016 -362.570395) (xy 422.491785 -362.59913) (xy 422.535772 -362.634755) (xy 422.574012 -362.676489)
			(xy 422.605666 -362.723415) (xy 422.630038 -362.774503) (xy 422.646594 -362.828631) (xy 422.654971 -362.884612)
			(xy 422.655492 -362.912914) (xy 422.655036 -362.940285) (xy 422.647216 -362.994464) (xy 422.631725 -363.046968)
			(xy 422.608881 -363.096714) (xy 422.579154 -363.142681) (xy 422.561512 -363.163612) (xy 422.555283 -363.171232)
			(xy 429.73955 -363.171232) (xy 429.743621 -363.11561) (xy 429.755747 -363.061173) (xy 429.77567 -363.009082)
			(xy 429.802966 -362.960447) (xy 429.837052 -362.916304) (xy 429.877201 -362.877595) (xy 429.922559 -362.845144)
			(xy 429.972159 -362.819643) (xy 430.024943 -362.801636) (xy 430.079786 -362.791506) (xy 430.13552 -362.789469)
			(xy 430.190957 -362.795569) (xy 430.244914 -362.809675) (xy 430.296243 -362.831487) (xy 430.343849 -362.860541)
			(xy 430.386717 -362.896216) (xy 430.423934 -362.937753) (xy 430.454707 -362.984266) (xy 430.478379 -363.034763)
			(xy 430.494447 -363.08817) (xy 430.502567 -363.143346) (xy 430.503076 -363.171232) (xy 430.502567 -363.199118)
			(xy 430.494447 -363.254294) (xy 430.478379 -363.307701) (xy 430.454707 -363.358198) (xy 430.423934 -363.404711)
			(xy 430.386717 -363.446248) (xy 430.343849 -363.481923) (xy 430.296243 -363.510977) (xy 430.244914 -363.532789)
			(xy 430.190957 -363.546895) (xy 430.13552 -363.552995) (xy 430.079786 -363.550958) (xy 430.024943 -363.540828)
			(xy 429.972159 -363.522821) (xy 429.922559 -363.49732) (xy 429.877201 -363.464869) (xy 429.837052 -363.42616)
			(xy 429.802966 -363.382017) (xy 429.77567 -363.333382) (xy 429.755747 -363.281291) (xy 429.743621 -363.226854)
			(xy 429.73955 -363.171232) (xy 422.555283 -363.171232) (xy 422.552261 -363.174929) (xy 422.540084 -363.20149)
			(xy 422.535913 -363.230411) (xy 422.54009 -363.25933) (xy 422.552272 -363.285889) (xy 422.561512 -363.297216)
			(xy 422.579127 -363.318167) (xy 422.608842 -363.364135) (xy 422.631682 -363.413878) (xy 422.647179 -363.466374)
			(xy 422.655014 -363.520546) (xy 422.655492 -363.547914) (xy 422.655006 -363.575165) (xy 422.64725 -363.629113)
			(xy 422.631895 -363.681408) (xy 422.609253 -363.730985) (xy 422.579787 -363.776835) (xy 422.544096 -363.818026)
			(xy 422.502905 -363.853717) (xy 422.457055 -363.883183) (xy 422.407478 -363.905825) (xy 422.355183 -363.92118)
			(xy 422.301235 -363.928936) (xy 422.246733 -363.928936) (xy 422.192785 -363.92118) (xy 422.14049 -363.905825)
			(xy 422.090913 -363.883183) (xy 422.045063 -363.853717) (xy 422.003872 -363.818026) (xy 421.968181 -363.776835)
			(xy 421.938715 -363.730985) (xy 421.916073 -363.681408) (xy 421.900718 -363.629113) (xy 421.892962 -363.575165)
			(xy 421.892476 -363.547914) (xy 421.892932 -363.520543) (xy 421.900749 -363.466363) (xy 421.91624 -363.413859)
			(xy 421.939084 -363.364112) (xy 421.968813 -363.318147) (xy 421.986456 -363.297216) (xy 421.995675 -363.285877)
			(xy 422.007847 -363.259322) (xy 422.01202 -363.230411) (xy 422.007853 -363.201498) (xy 421.995686 -363.174941)
			(xy 421.986456 -363.163612) (xy 421.966822 -363.140129) (xy 421.934513 -363.088145) (xy 421.910893 -363.03168)
			(xy 421.903144 -363.002068) (xy 421.899588 -362.988098) (xy 421.347646 -362.436156) (xy 419.846252 -362.436156)
			(xy 419.17747 -363.104938) (xy 419.159479 -363.122287) (xy 419.11907 -363.151693) (xy 419.087744 -363.167676)
			(xy 420.18153 -363.167676) (xy 420.185601 -363.112054) (xy 420.197727 -363.057617) (xy 420.21765 -363.005526)
			(xy 420.244946 -362.956891) (xy 420.279032 -362.912748) (xy 420.319181 -362.874039) (xy 420.364539 -362.841588)
			(xy 420.414139 -362.816087) (xy 420.466923 -362.79808) (xy 420.521766 -362.78795) (xy 420.5775 -362.785913)
			(xy 420.632937 -362.792013) (xy 420.686894 -362.806119) (xy 420.738223 -362.827931) (xy 420.785829 -362.856985)
			(xy 420.828697 -362.89266) (xy 420.865914 -362.934197) (xy 420.896687 -362.98071) (xy 420.920359 -363.031207)
			(xy 420.936427 -363.084614) (xy 420.944547 -363.13979) (xy 420.945056 -363.167676) (xy 420.944547 -363.195562)
			(xy 420.936427 -363.250738) (xy 420.920359 -363.304145) (xy 420.896687 -363.354642) (xy 420.865914 -363.401155)
			(xy 420.828697 -363.442692) (xy 420.785829 -363.478367) (xy 420.738223 -363.507421) (xy 420.686894 -363.529233)
			(xy 420.632937 -363.543339) (xy 420.5775 -363.549439) (xy 420.521766 -363.547402) (xy 420.466923 -363.537272)
			(xy 420.414139 -363.519265) (xy 420.364539 -363.493764) (xy 420.319181 -363.461313) (xy 420.279032 -363.422604)
			(xy 420.244946 -363.378461) (xy 420.21765 -363.329826) (xy 420.197727 -363.277735) (xy 420.185601 -363.223298)
			(xy 420.18153 -363.167676) (xy 419.087744 -363.167676) (xy 419.074553 -363.174406) (xy 419.027028 -363.189866)
			(xy 418.977668 -363.197691) (xy 418.95268 -363.198156) (xy 416.620452 -363.198156) (xy 416.25647 -363.562138)
			(xy 416.238479 -363.579487) (xy 416.19807 -363.608893) (xy 416.153553 -363.631606) (xy 416.106028 -363.647066)
			(xy 416.056668 -363.654891) (xy 416.03168 -363.655356) (xy 413.97428 -363.655356) (xy 413.949293 -363.654875)
			(xy 413.899938 -363.647039) (xy 413.852416 -363.631578) (xy 413.807898 -363.608874) (xy 413.76748 -363.579485)
			(xy 413.74949 -363.562138) (xy 413.411924 -363.224572) (xy 413.011366 -363.224572) (xy 412.996411 -363.225208)
			(xy 412.967801 -363.233941) (xy 412.942948 -363.250589) (xy 412.923985 -363.273724) (xy 412.912539 -363.301361)
			(xy 412.909591 -363.331129) (xy 412.915395 -363.360474) (xy 412.921958 -363.373924) (xy 412.936166 -363.401796)
			(xy 412.956325 -363.461015) (xy 412.96654 -363.522732) (xy 412.96717 -363.55401) (xy 412.96717 -363.554264)
			(xy 412.966684 -363.581515) (xy 412.958928 -363.635463) (xy 412.943573 -363.687758) (xy 412.920931 -363.737335)
			(xy 412.891465 -363.783185) (xy 412.855774 -363.824376) (xy 412.814583 -363.860067) (xy 412.768733 -363.889533)
			(xy 412.719156 -363.912175) (xy 412.666861 -363.92753) (xy 412.612913 -363.935286) (xy 412.558411 -363.935286)
			(xy 412.504463 -363.92753) (xy 412.452168 -363.912175) (xy 412.402591 -363.889533) (xy 412.356741 -363.860067)
			(xy 412.31555 -363.824376) (xy 412.279859 -363.783185) (xy 412.250393 -363.737335) (xy 412.227751 -363.687758)
			(xy 412.212396 -363.635463) (xy 412.20464 -363.581515) (xy 412.204154 -363.554264) (xy 410.315624 -363.554264)
			(xy 410.300424 -363.55909) (xy 410.25826 -363.57179) (xy 410.313512 -363.9505) (xy 416.452737 -363.9505)
			(xy 416.456906 -363.894879) (xy 416.469318 -363.840501) (xy 416.489697 -363.788581) (xy 416.517587 -363.740278)
			(xy 416.552365 -363.696672) (xy 416.593254 -363.658736) (xy 416.639341 -363.627319) (xy 416.689595 -363.603122)
			(xy 416.742895 -363.586686) (xy 416.79805 -363.578378) (xy 416.825938 -363.577886) (xy 416.853268 -363.578397)
			(xy 416.907345 -363.586362) (xy 416.959677 -363.602145) (xy 417.009141 -363.625407) (xy 417.054673 -363.655648)
			(xy 417.095297 -363.692219) (xy 417.13014 -363.734335) (xy 417.144708 -363.757464) (xy 417.152655 -363.769672)
			(xy 417.174117 -363.789348) (xy 417.200265 -363.802157) (xy 417.228966 -363.807056) (xy 417.257882 -363.803645)
			(xy 417.271454 -363.798358) (xy 417.29466 -363.788857) (xy 417.342995 -363.775511) (xy 417.392686 -363.768787)
			(xy 417.417758 -363.768386) (xy 417.442827 -363.768806) (xy 417.49251 -363.775558) (xy 417.540845 -363.788892)
			(xy 417.564062 -363.798358) (xy 417.577647 -363.803579) (xy 417.606542 -363.806943) (xy 417.635215 -363.802036)
			(xy 417.661347 -363.789254) (xy 417.682824 -363.769633) (xy 417.690808 -363.757464) (xy 417.705377 -363.734333)
			(xy 417.74022 -363.692212) (xy 417.780843 -363.655633) (xy 417.826374 -363.625382) (xy 417.875836 -363.602106)
			(xy 417.928167 -363.586306) (xy 417.982246 -363.57832) (xy 418.03691 -363.57832) (xy 418.090989 -363.586306)
			(xy 418.14332 -363.602106) (xy 418.192782 -363.625382) (xy 418.238313 -363.655633) (xy 418.278936 -363.692212)
			(xy 418.313779 -363.734333) (xy 418.328348 -363.757464) (xy 418.336257 -363.7697) (xy 418.35773 -363.789375)
			(xy 418.383887 -363.802181) (xy 418.412598 -363.807072) (xy 418.44152 -363.803652) (xy 418.455094 -363.798358)
			(xy 418.478307 -363.788876) (xy 418.526638 -363.775523) (xy 418.576327 -363.768791) (xy 418.601398 -363.768386)
			(xy 418.627622 -363.768832) (xy 418.679552 -363.776174) (xy 418.72994 -363.790728) (xy 418.777787 -363.812206)
			(xy 418.822149 -363.840183) (xy 418.862149 -363.874105) (xy 418.896994 -363.913303) (xy 418.925997 -363.957001)
			(xy 418.937694 -363.980476) (xy 418.9441 -363.992667) (xy 418.962164 -364.013433) (xy 418.985123 -364.028613)
			(xy 419.011303 -364.037104) (xy 419.038801 -364.038288) (xy 419.065615 -364.032078) (xy 419.089792 -364.018927)
			(xy 419.1 -364.009686) (xy 419.121475 -363.98975) (xy 419.169373 -363.956) (xy 419.221866 -363.929965)
			(xy 419.277721 -363.912257) (xy 419.335625 -363.903292) (xy 419.364922 -363.902752) (xy 419.382941 -363.902975)
			(xy 419.418816 -363.906408) (xy 419.43655 -363.90961) (xy 419.451762 -363.911934) (xy 419.482317 -363.908418)
			(xy 419.510438 -363.895963) (xy 419.533574 -363.875698) (xy 419.549626 -363.849463) (xy 419.553898 -363.83468)
			(xy 419.561329 -363.807646) (xy 419.582954 -363.75592) (xy 419.611913 -363.707915) (xy 419.647584 -363.664662)
			(xy 419.689199 -363.627094) (xy 419.735863 -363.596019) (xy 419.78657 -363.572104) (xy 419.840231 -363.555866)
			(xy 419.89569 -363.547652) (xy 419.923722 -363.547152) (xy 419.950972 -363.547657) (xy 420.004917 -363.555416)
			(xy 420.057209 -363.570772) (xy 420.106783 -363.593412) (xy 420.152632 -363.622877) (xy 420.193821 -363.658566)
			(xy 420.229512 -363.699754) (xy 420.258979 -363.745601) (xy 420.281622 -363.795174) (xy 420.29698 -363.847465)
			(xy 420.304742 -363.90141) (xy 420.30523 -363.92866) (xy 420.304831 -363.9505) (xy 426.141163 -363.9505)
			(xy 426.145331 -363.894891) (xy 426.157739 -363.840523) (xy 426.178111 -363.788612) (xy 426.205992 -363.740317)
			(xy 426.240759 -363.696717) (xy 426.281635 -363.658784) (xy 426.327709 -363.627368) (xy 426.37795 -363.603168)
			(xy 426.431236 -363.586726) (xy 426.486377 -363.57841) (xy 426.51426 -363.577886) (xy 426.541591 -363.57838)
			(xy 426.595669 -363.586348) (xy 426.648001 -363.602134) (xy 426.697465 -363.625399) (xy 426.742997 -363.655643)
			(xy 426.78362 -363.692216) (xy 426.818463 -363.734334) (xy 426.83303 -363.757464) (xy 426.840956 -363.769687)
			(xy 426.862424 -363.789363) (xy 426.888577 -363.80217) (xy 426.917283 -363.807065) (xy 426.946203 -363.803649)
			(xy 426.959776 -363.798358) (xy 426.982991 -363.788881) (xy 427.031321 -363.775526) (xy 427.081009 -363.768793)
			(xy 427.10608 -363.768386) (xy 427.131148 -363.768832) (xy 427.180831 -363.775573) (xy 427.229166 -363.788896)
			(xy 427.252384 -363.798358) (xy 427.265997 -363.803497) (xy 427.294878 -363.806878) (xy 427.323541 -363.801989)
			(xy 427.349668 -363.789227) (xy 427.371145 -363.769625) (xy 427.37913 -363.757464) (xy 427.393699 -363.734333)
			(xy 427.428542 -363.692212) (xy 427.469165 -363.655633) (xy 427.514696 -363.625382) (xy 427.564158 -363.602106)
			(xy 427.616489 -363.586306) (xy 427.670568 -363.57832) (xy 427.725232 -363.57832) (xy 427.779311 -363.586306)
			(xy 427.831642 -363.602106) (xy 427.881104 -363.625382) (xy 427.926635 -363.655633) (xy 427.967258 -363.692212)
			(xy 428.002101 -363.734333) (xy 428.01667 -363.757464) (xy 428.024558 -363.769715) (xy 428.046036 -363.78939)
			(xy 428.0722 -363.802194) (xy 428.100915 -363.807082) (xy 428.129841 -363.803655) (xy 428.143416 -363.798358)
			(xy 428.166626 -363.788869) (xy 428.214959 -363.775518) (xy 428.264648 -363.76879) (xy 428.28972 -363.768386)
			(xy 428.316563 -363.768828) (xy 428.369694 -363.776536) (xy 428.421169 -363.791788) (xy 428.469922 -363.814269)
			(xy 428.514944 -363.843513) (xy 428.555304 -363.878916) (xy 428.590165 -363.919745) (xy 428.618807 -363.965153)
			(xy 428.640635 -364.014202) (xy 428.648368 -364.039912) (xy 428.653106 -364.054383) (xy 428.669606 -364.079945)
			(xy 428.692905 -364.099513) (xy 428.720934 -364.111348) (xy 428.751206 -364.1144) (xy 428.781034 -364.108398)
			(xy 428.794672 -364.101634) (xy 428.822813 -364.086991) (xy 428.882767 -364.066268) (xy 428.945327 -364.055774)
			(xy 428.977044 -364.055152) (xy 428.995063 -364.055372) (xy 429.030938 -364.058807) (xy 429.048672 -364.06201)
			(xy 429.063881 -364.064356) (xy 429.094438 -364.060834) (xy 429.122561 -364.048373) (xy 429.145697 -364.028104)
			(xy 429.161749 -364.001864) (xy 429.16602 -363.98708) (xy 429.173431 -363.960039) (xy 429.195057 -363.908313)
			(xy 429.224019 -363.860306) (xy 429.259692 -363.817054) (xy 429.30131 -363.779486) (xy 429.347976 -363.748411)
			(xy 429.398687 -363.724498) (xy 429.45235 -363.708261) (xy 429.507811 -363.700051) (xy 429.535844 -363.699552)
			(xy 429.563095 -363.700037) (xy 429.61704 -363.707798) (xy 429.669332 -363.723157) (xy 429.718907 -363.7458)
			(xy 429.764755 -363.775267) (xy 429.805944 -363.810959) (xy 429.841635 -363.852148) (xy 429.871102 -363.897996)
			(xy 429.893744 -363.947571) (xy 429.909103 -363.999864) (xy 429.916864 -364.053809) (xy 429.917352 -364.08106)
			(xy 429.916876 -364.108634) (xy 429.908928 -364.163207) (xy 429.893206 -364.216068) (xy 429.870038 -364.266114)
			(xy 429.839906 -364.312304) (xy 429.803439 -364.353675) (xy 429.782732 -364.37189) (xy 429.771872 -364.381828)
			(xy 429.755794 -364.406466) (xy 429.747403 -364.434664) (xy 429.747395 -364.464084) (xy 429.755772 -364.492287)
			(xy 429.771838 -364.516933) (xy 429.782732 -364.52683) (xy 429.803396 -364.54509) (xy 429.839856 -364.586457)
			(xy 429.869981 -364.632642) (xy 429.893143 -364.682683) (xy 429.908859 -364.735537) (xy 429.916801 -364.790103)
			(xy 429.916805 -364.845245) (xy 429.90887 -364.899812) (xy 429.893161 -364.952669) (xy 429.870006 -365.002713)
			(xy 429.839888 -365.048902) (xy 429.803433 -365.090273) (xy 429.782732 -365.10849) (xy 429.771872 -365.118428)
			(xy 429.755794 -365.143066) (xy 429.747403 -365.171264) (xy 429.747395 -365.200684) (xy 429.755772 -365.228887)
			(xy 429.771838 -365.253533) (xy 429.782732 -365.26343) (xy 429.803467 -365.281615) (xy 429.839934 -365.32299)
			(xy 429.870063 -365.369186) (xy 429.893224 -365.419239) (xy 429.908935 -365.472105) (xy 429.91687 -365.526684)
			(xy 429.917352 -365.55426) (xy 429.916785 -365.581508) (xy 429.909035 -365.635451) (xy 429.893687 -365.687741)
			(xy 429.871054 -365.737315) (xy 429.841596 -365.783164) (xy 429.805913 -365.824353) (xy 429.764731 -365.860045)
			(xy 429.718889 -365.889513) (xy 429.66932 -365.912158) (xy 429.617033 -365.927517) (xy 429.563092 -365.935279)
			(xy 429.535844 -365.935768) (xy 429.507989 -365.935229) (xy 429.452873 -365.927111) (xy 429.399522 -365.91107)
			(xy 429.349068 -365.887446) (xy 429.302582 -365.856741) (xy 429.261052 -365.819607) (xy 429.225359 -365.776832)
			(xy 429.196261 -365.729325) (xy 429.174375 -365.678093) (xy 429.166782 -365.651288) (xy 429.162503 -365.637174)
			(xy 429.147112 -365.612032) (xy 429.125194 -365.592318) (xy 429.098568 -365.579666) (xy 429.069441 -365.575125)
			(xy 429.054768 -365.576612) (xy 429.041752 -365.578282) (xy 429.015567 -365.580061) (xy 429.002444 -365.580168)
			(xy 428.988295 -365.58007) (xy 428.960072 -365.578039) (xy 428.946056 -365.576104) (xy 428.932707 -365.574531)
			(xy 428.906016 -365.577627) (xy 428.881063 -365.587594) (xy 428.859584 -365.603737) (xy 428.843071 -365.624934)
			(xy 428.832675 -365.64971) (xy 428.830486 -365.662972) (xy 428.826449 -365.690134) (xy 428.811471 -365.742967)
			(xy 428.789074 -365.793107) (xy 428.75972 -365.839519) (xy 428.724017 -365.881243) (xy 428.682701 -365.917419)
			(xy 428.636627 -365.947298) (xy 428.586745 -365.970264) (xy 428.534086 -365.985843) (xy 428.479738 -365.993712)
			(xy 428.45228 -365.994188) (xy 428.425027 -365.993741) (xy 428.371077 -365.985981) (xy 428.318781 -365.970622)
			(xy 428.269202 -365.947977) (xy 428.223351 -365.918507) (xy 428.18216 -365.882812) (xy 428.146469 -365.841617)
			(xy 428.117003 -365.795763) (xy 428.094364 -365.746182) (xy 428.07901 -365.693884) (xy 428.071256 -365.639933)
			(xy 428.070772 -365.61268) (xy 428.071303 -365.585108) (xy 428.079243 -365.530538) (xy 428.094956 -365.47768)
			(xy 428.118114 -365.427634) (xy 428.148235 -365.381443) (xy 428.18469 -365.340068) (xy 428.205392 -365.32185)
			(xy 428.21631 -365.311972) (xy 428.232382 -365.287316) (xy 428.240764 -365.259103) (xy 428.24076 -365.229671)
			(xy 428.232371 -365.20146) (xy 428.216292 -365.176809) (xy 428.205392 -365.16691) (xy 428.184681 -365.148699)
			(xy 428.148211 -365.10733) (xy 428.118079 -365.06114) (xy 428.094913 -365.011092) (xy 428.079197 -364.95823)
			(xy 428.071257 -364.903655) (xy 428.070772 -364.87608) (xy 428.071239 -364.849579) (xy 428.078582 -364.797089)
			(xy 428.093124 -364.746122) (xy 428.114584 -364.697659) (xy 428.142548 -364.652636) (xy 428.159164 -364.631986)
			(xy 428.168558 -364.619807) (xy 428.180349 -364.591418) (xy 428.183178 -364.560808) (xy 428.17679 -364.530739)
			(xy 428.161762 -364.503922) (xy 428.13945 -364.482778) (xy 428.12589 -364.475522) (xy 428.102212 -364.463399)
			(xy 428.058228 -364.433483) (xy 428.018943 -364.397619) (xy 427.985156 -364.356534) (xy 427.97095 -364.334044)
			(xy 427.963041 -364.321808) (xy 427.941569 -364.302132) (xy 427.915411 -364.289326) (xy 427.8867 -364.284434)
			(xy 427.857778 -364.287856) (xy 427.844204 -364.29315) (xy 427.820992 -364.302633) (xy 427.77266 -364.315986)
			(xy 427.722971 -364.322717) (xy 427.6979 -364.323122) (xy 427.672831 -364.32269) (xy 427.623148 -364.315945)
			(xy 427.574814 -364.302615) (xy 427.551596 -364.29315) (xy 427.537991 -364.287986) (xy 427.509106 -364.28461)
			(xy 427.480439 -364.289503) (xy 427.45431 -364.302271) (xy 427.432834 -364.32188) (xy 427.42485 -364.334044)
			(xy 427.410281 -364.357175) (xy 427.375438 -364.399296) (xy 427.334815 -364.435875) (xy 427.289284 -364.466126)
			(xy 427.239822 -364.489402) (xy 427.187491 -364.505202) (xy 427.133412 -364.513188) (xy 427.078748 -364.513188)
			(xy 427.024669 -364.505202) (xy 426.972338 -364.489402) (xy 426.922876 -364.466126) (xy 426.877345 -364.435875)
			(xy 426.836722 -364.399296) (xy 426.801879 -364.357175) (xy 426.78731 -364.334044) (xy 426.779344 -364.321849)
			(xy 426.757887 -364.302173) (xy 426.731745 -364.289362) (xy 426.703048 -364.284459) (xy 426.674135 -364.287865)
			(xy 426.660564 -364.29315) (xy 426.637357 -364.302646) (xy 426.589022 -364.315994) (xy 426.539332 -364.32272)
			(xy 426.51426 -364.323122) (xy 426.486377 -364.32259) (xy 426.431236 -364.314274) (xy 426.37795 -364.297832)
			(xy 426.327709 -364.273632) (xy 426.281635 -364.242216) (xy 426.240759 -364.204283) (xy 426.205992 -364.160683)
			(xy 426.178111 -364.112388) (xy 426.157739 -364.060477) (xy 426.145331 -364.006109) (xy 426.141163 -363.9505)
			(xy 420.304831 -363.9505) (xy 420.304726 -363.956233) (xy 420.29678 -364.010804) (xy 420.281062 -364.063662)
			(xy 420.257899 -364.113708) (xy 420.227774 -364.159899) (xy 420.191314 -364.201273) (xy 420.17061 -364.21949)
			(xy 420.159752 -364.229429) (xy 420.143677 -364.254067) (xy 420.135288 -364.282265) (xy 420.135281 -364.311684)
			(xy 420.143655 -364.339885) (xy 420.159718 -364.364532) (xy 420.17061 -364.37443) (xy 420.191275 -364.39269)
			(xy 420.227737 -364.434056) (xy 420.257864 -364.48024) (xy 420.281027 -364.530281) (xy 420.296744 -364.583136)
			(xy 420.304687 -364.637703) (xy 420.304691 -364.692845) (xy 420.296755 -364.747413) (xy 420.281046 -364.80027)
			(xy 420.257889 -364.850314) (xy 420.227769 -364.896503) (xy 420.191312 -364.937874) (xy 420.17061 -364.95609)
			(xy 420.159752 -364.966029) (xy 420.143677 -364.990667) (xy 420.136055 -365.016288) (xy 422.68343 -365.016288)
			(xy 422.687501 -364.960666) (xy 422.699627 -364.906229) (xy 422.71955 -364.854138) (xy 422.746846 -364.805503)
			(xy 422.780932 -364.76136) (xy 422.821081 -364.722651) (xy 422.866439 -364.6902) (xy 422.916039 -364.664699)
			(xy 422.968823 -364.646692) (xy 423.023666 -364.636562) (xy 423.0794 -364.634525) (xy 423.134837 -364.640625)
			(xy 423.188794 -364.654731) (xy 423.240123 -364.676543) (xy 423.287729 -364.705597) (xy 423.330597 -364.741272)
			(xy 423.367814 -364.782809) (xy 423.398587 -364.829322) (xy 423.422259 -364.879819) (xy 423.438327 -364.933226)
			(xy 423.446447 -364.988402) (xy 423.446956 -365.016288) (xy 423.446447 -365.044174) (xy 423.438327 -365.09935)
			(xy 423.422259 -365.152757) (xy 423.398587 -365.203254) (xy 423.367814 -365.249767) (xy 423.330597 -365.291304)
			(xy 423.287729 -365.326979) (xy 423.240123 -365.356033) (xy 423.188794 -365.377845) (xy 423.134837 -365.391951)
			(xy 423.0794 -365.398051) (xy 423.023666 -365.396014) (xy 422.968823 -365.385884) (xy 422.916039 -365.367877)
			(xy 422.866439 -365.342376) (xy 422.821081 -365.309925) (xy 422.780932 -365.271216) (xy 422.746846 -365.227073)
			(xy 422.71955 -365.178438) (xy 422.699627 -365.126347) (xy 422.687501 -365.07191) (xy 422.68343 -365.016288)
			(xy 420.136055 -365.016288) (xy 420.135288 -365.018865) (xy 420.135281 -365.048284) (xy 420.143655 -365.076485)
			(xy 420.159718 -365.101132) (xy 420.17061 -365.11103) (xy 420.191341 -365.12922) (xy 420.227809 -365.170593)
			(xy 420.257939 -365.216788) (xy 420.281101 -365.26684) (xy 420.296813 -365.319706) (xy 420.304748 -365.374284)
			(xy 420.30523 -365.40186) (xy 420.304708 -365.429111) (xy 420.296957 -365.483059) (xy 420.281607 -365.535354)
			(xy 420.258971 -365.584932) (xy 420.229509 -365.630785) (xy 420.193821 -365.671977) (xy 420.152634 -365.707672)
			(xy 420.106787 -365.737141) (xy 420.057212 -365.759785) (xy 420.004919 -365.775143) (xy 419.950973 -365.782903)
			(xy 419.923722 -365.783368) (xy 419.895866 -365.782849) (xy 419.840749 -365.774727) (xy 419.787398 -365.758683)
			(xy 419.736944 -365.735057) (xy 419.690459 -365.704349) (xy 419.648929 -365.667213) (xy 419.613236 -365.624437)
			(xy 419.584138 -365.576927) (xy 419.562253 -365.525694) (xy 419.55466 -365.498888) (xy 419.550403 -365.484766)
			(xy 419.535007 -365.459622) (xy 419.513085 -365.439908) (xy 419.486453 -365.427258) (xy 419.45732 -365.422722)
			(xy 419.442646 -365.424212) (xy 419.42963 -365.425885) (xy 419.403445 -365.427662) (xy 419.390322 -365.427768)
			(xy 419.361422 -365.427257) (xy 419.304278 -365.418587) (xy 419.27653 -365.410496) (xy 419.262999 -365.40669)
			(xy 419.234907 -365.405954) (xy 419.207676 -365.412891) (xy 419.183359 -365.426976) (xy 419.163794 -365.447148)
			(xy 419.150457 -365.471882) (xy 419.144354 -365.499313) (xy 419.144704 -365.513366) (xy 419.145466 -365.53648)
			(xy 419.14498 -365.563731) (xy 419.137224 -365.617679) (xy 419.121869 -365.669974) (xy 419.099227 -365.719551)
			(xy 419.069761 -365.765401) (xy 419.03407 -365.806592) (xy 418.992879 -365.842283) (xy 418.947029 -365.871749)
			(xy 418.897452 -365.894391) (xy 418.845157 -365.909746) (xy 418.791209 -365.917502) (xy 418.736707 -365.917502)
			(xy 418.682759 -365.909746) (xy 418.630464 -365.894391) (xy 418.580887 -365.871749) (xy 418.535037 -365.842283)
			(xy 418.493846 -365.806592) (xy 418.458155 -365.765401) (xy 418.428689 -365.719551) (xy 418.406047 -365.669974)
			(xy 418.390692 -365.617679) (xy 418.382936 -365.563731) (xy 418.38245 -365.53648) (xy 418.382953 -365.508907)
			(xy 418.390896 -365.454335) (xy 418.406612 -365.401475) (xy 418.429775 -365.351428) (xy 418.459902 -365.305238)
			(xy 418.496365 -365.263866) (xy 418.51707 -365.24565) (xy 418.52799 -365.235773) (xy 418.544066 -365.211118)
			(xy 418.552449 -365.182904) (xy 418.552446 -365.15347) (xy 418.544055 -365.125259) (xy 418.527972 -365.100607)
			(xy 418.51707 -365.09071) (xy 418.496354 -365.072504) (xy 418.459886 -365.031133) (xy 418.429755 -364.984942)
			(xy 418.40659 -364.934893) (xy 418.390874 -364.88203) (xy 418.382935 -364.827455) (xy 418.38245 -364.79988)
			(xy 418.38292 -364.77338) (xy 418.390262 -364.720892) (xy 418.404802 -364.669925) (xy 418.42626 -364.621464)
			(xy 418.439854 -364.598712) (xy 418.446578 -364.587148) (xy 418.454271 -364.561535) (xy 418.455055 -364.534802)
			(xy 418.448875 -364.508782) (xy 418.436156 -364.485257) (xy 418.417769 -364.465837) (xy 418.40658 -364.458504)
			(xy 418.381664 -364.442569) (xy 418.336742 -364.404103) (xy 418.298456 -364.359028) (xy 418.282628 -364.334044)
			(xy 418.27474 -364.321793) (xy 418.253262 -364.302117) (xy 418.227099 -364.289313) (xy 418.198383 -364.284425)
			(xy 418.169457 -364.287852) (xy 418.155882 -364.29315) (xy 418.132672 -364.30264) (xy 418.084339 -364.31599)
			(xy 418.03465 -364.322718) (xy 418.009578 -364.323122) (xy 417.984509 -364.322697) (xy 417.934826 -364.315949)
			(xy 417.886491 -364.302616) (xy 417.863274 -364.29315) (xy 417.849677 -364.287963) (xy 417.820788 -364.284591)
			(xy 417.792118 -364.28949) (xy 417.765988 -364.302264) (xy 417.744512 -364.321878) (xy 417.736528 -364.334044)
			(xy 417.721959 -364.357175) (xy 417.687116 -364.399296) (xy 417.646493 -364.435875) (xy 417.600962 -364.466126)
			(xy 417.5515 -364.489402) (xy 417.499169 -364.505202) (xy 417.44509 -364.513188) (xy 417.390426 -364.513188)
			(xy 417.336347 -364.505202) (xy 417.284016 -364.489402) (xy 417.234554 -364.466126) (xy 417.189023 -364.435875)
			(xy 417.1484 -364.399296) (xy 417.113557 -364.357175) (xy 417.098988 -364.334044) (xy 417.091043 -364.321834)
			(xy 417.06958 -364.302158) (xy 417.043432 -364.289349) (xy 417.014731 -364.28445) (xy 416.985814 -364.287862)
			(xy 416.972242 -364.29315) (xy 416.949037 -364.302652) (xy 416.900702 -364.315998) (xy 416.85101 -364.322721)
			(xy 416.825938 -364.323122) (xy 416.79805 -364.322622) (xy 416.742895 -364.314314) (xy 416.689595 -364.297878)
			(xy 416.639341 -364.273681) (xy 416.593254 -364.242264) (xy 416.552365 -364.204328) (xy 416.517587 -364.160722)
			(xy 416.489697 -364.112419) (xy 416.469318 -364.060499) (xy 416.456906 -364.006121) (xy 416.452737 -363.9505)
			(xy 410.313512 -363.9505) (xy 410.469006 -365.016288) (xy 412.995108 -365.016288) (xy 412.999179 -364.960666)
			(xy 413.011305 -364.906229) (xy 413.031228 -364.854138) (xy 413.058524 -364.805503) (xy 413.09261 -364.76136)
			(xy 413.132759 -364.722651) (xy 413.178117 -364.6902) (xy 413.227717 -364.664699) (xy 413.280501 -364.646692)
			(xy 413.335344 -364.636562) (xy 413.391078 -364.634525) (xy 413.446515 -364.640625) (xy 413.500472 -364.654731)
			(xy 413.551801 -364.676543) (xy 413.599407 -364.705597) (xy 413.642275 -364.741272) (xy 413.679492 -364.782809)
			(xy 413.710265 -364.829322) (xy 413.733937 -364.879819) (xy 413.750005 -364.933226) (xy 413.758125 -364.988402)
			(xy 413.758634 -365.016288) (xy 413.758125 -365.044174) (xy 413.750005 -365.09935) (xy 413.733937 -365.152757)
			(xy 413.710265 -365.203254) (xy 413.679492 -365.249767) (xy 413.642275 -365.291304) (xy 413.599407 -365.326979)
			(xy 413.551801 -365.356033) (xy 413.500472 -365.377845) (xy 413.446515 -365.391951) (xy 413.391078 -365.398051)
			(xy 413.335344 -365.396014) (xy 413.280501 -365.385884) (xy 413.227717 -365.367877) (xy 413.178117 -365.342376)
			(xy 413.132759 -365.309925) (xy 413.09261 -365.271216) (xy 413.058524 -365.227073) (xy 413.031228 -365.178438)
			(xy 413.011305 -365.126347) (xy 412.999179 -365.07191) (xy 412.995108 -365.016288) (xy 410.469006 -365.016288)
			(xy 410.542232 -365.518192) (xy 410.544813 -365.53238) (xy 410.556792 -365.558598) (xy 410.575624 -365.580421)
			(xy 410.599807 -365.596107) (xy 410.627411 -365.604407) (xy 410.656234 -365.604657) (xy 410.670248 -365.60125)
			(xy 410.69527 -365.594727) (xy 410.746502 -365.587719) (xy 410.772356 -365.58728) (xy 410.77261 -365.58728)
			(xy 410.799861 -365.587766) (xy 410.853808 -365.595524) (xy 410.906103 -365.61088) (xy 410.955679 -365.633521)
			(xy 411.001529 -365.662988) (xy 411.042719 -365.698679) (xy 411.078411 -365.739869) (xy 411.107878 -365.785719)
			(xy 411.130519 -365.835295) (xy 411.145876 -365.88759) (xy 411.153633 -365.941537) (xy 411.154118 -365.968788)
			(xy 411.153884 -365.98225) (xy 412.330644 -365.98225) (xy 412.334715 -365.926628) (xy 412.346841 -365.872191)
			(xy 412.366764 -365.8201) (xy 412.39406 -365.771465) (xy 412.428146 -365.727322) (xy 412.468295 -365.688613)
			(xy 412.513653 -365.656162) (xy 412.563253 -365.630661) (xy 412.616037 -365.612654) (xy 412.67088 -365.602524)
			(xy 412.726614 -365.600487) (xy 412.782051 -365.606587) (xy 412.836008 -365.620693) (xy 412.887337 -365.642505)
			(xy 412.934943 -365.671559) (xy 412.977811 -365.707234) (xy 413.015028 -365.748771) (xy 413.045801 -365.795284)
			(xy 413.069473 -365.845781) (xy 413.085541 -365.899188) (xy 413.093661 -365.954364) (xy 413.09417 -365.98225)
			(xy 413.093661 -366.010136) (xy 413.085541 -366.065312) (xy 413.069473 -366.118719) (xy 413.045801 -366.169216)
			(xy 413.015028 -366.215729) (xy 412.977811 -366.257266) (xy 412.934943 -366.292941) (xy 412.887337 -366.321995)
			(xy 412.836008 -366.343807) (xy 412.782051 -366.357913) (xy 412.726614 -366.364013) (xy 412.67088 -366.361976)
			(xy 412.616037 -366.351846) (xy 412.563253 -366.333839) (xy 412.513653 -366.308338) (xy 412.468295 -366.275887)
			(xy 412.428146 -366.237178) (xy 412.39406 -366.193035) (xy 412.366764 -366.1444) (xy 412.346841 -366.092309)
			(xy 412.334715 -366.037872) (xy 412.330644 -365.98225) (xy 411.153884 -365.98225) (xy 411.153649 -365.995727)
			(xy 411.146058 -366.049067) (xy 411.131041 -366.100809) (xy 411.108896 -366.149925) (xy 411.080062 -366.195438)
			(xy 411.045114 -366.236443) (xy 411.004746 -366.272125) (xy 410.95976 -366.301774) (xy 410.911051 -366.324801)
			(xy 410.859588 -366.340749) (xy 410.806393 -366.349299) (xy 410.779468 -366.350296) (xy 410.765094 -366.351051)
			(xy 410.737615 -366.35957) (xy 410.713601 -366.375414) (xy 410.694958 -366.397327) (xy 410.683165 -366.423568)
			(xy 410.679157 -366.452058) (xy 410.680662 -366.466374) (xy 410.692122 -366.54486) (xy 413.801814 -366.54486)
			(xy 413.801814 -366.544606) (xy 413.802272 -366.518311) (xy 413.809517 -366.466222) (xy 413.823843 -366.415621)
			(xy 413.844978 -366.367464) (xy 413.872524 -366.322665) (xy 413.905957 -366.28207) (xy 413.925004 -366.263936)
			(xy 413.935064 -366.254162) (xy 413.949759 -366.230278) (xy 413.957391 -366.203294) (xy 413.957384 -366.175252)
			(xy 413.949737 -366.148272) (xy 413.935029 -366.124396) (xy 413.925004 -366.114584) (xy 413.905932 -366.096472)
			(xy 413.872477 -366.055886) (xy 413.84492 -366.011086) (xy 413.823783 -365.962923) (xy 413.809469 -365.912312)
			(xy 413.80225 -365.860213) (xy 413.801814 -365.833914) (xy 413.801814 -365.83366) (xy 413.8023 -365.806409)
			(xy 413.810056 -365.752461) (xy 413.825411 -365.700166) (xy 413.848053 -365.650589) (xy 413.877519 -365.604739)
			(xy 413.91321 -365.563548) (xy 413.954401 -365.527857) (xy 414.000251 -365.498391) (xy 414.049828 -365.475749)
			(xy 414.102123 -365.460394) (xy 414.156071 -365.452638) (xy 414.210573 -365.452638) (xy 414.264521 -365.460394)
			(xy 414.316816 -365.475749) (xy 414.366393 -365.498391) (xy 414.412243 -365.527857) (xy 414.453434 -365.563548)
			(xy 414.489125 -365.604739) (xy 414.518591 -365.650589) (xy 414.541233 -365.700166) (xy 414.556588 -365.752461)
			(xy 414.564344 -365.806409) (xy 414.56449 -365.81461) (xy 415.42716 -365.81461) (xy 415.427646 -365.787359)
			(xy 415.435402 -365.733411) (xy 415.450757 -365.681116) (xy 415.473399 -365.631539) (xy 415.502865 -365.585689)
			(xy 415.538556 -365.544498) (xy 415.579747 -365.508807) (xy 415.625597 -365.479341) (xy 415.675174 -365.456699)
			(xy 415.727469 -365.441344) (xy 415.781417 -365.433588) (xy 415.835919 -365.433588) (xy 415.889867 -365.441344)
			(xy 415.942162 -365.456699) (xy 415.991739 -365.479341) (xy 416.037589 -365.508807) (xy 416.07878 -365.544498)
			(xy 416.114471 -365.585689) (xy 416.143937 -365.631539) (xy 416.166579 -365.681116) (xy 416.181934 -365.733411)
			(xy 416.18969 -365.787359) (xy 416.190176 -365.81461) (xy 416.189939 -365.833277) (xy 416.18625 -365.870429)
			(xy 416.18281 -365.888778) (xy 416.180493 -365.903048) (xy 416.183021 -365.931832) (xy 416.193516 -365.958754)
			(xy 416.211135 -365.981656) (xy 416.228289 -365.994188) (xy 422.018966 -365.994188) (xy 422.023037 -365.938566)
			(xy 422.035163 -365.884129) (xy 422.055086 -365.832038) (xy 422.082382 -365.783403) (xy 422.116468 -365.73926)
			(xy 422.156617 -365.700551) (xy 422.201975 -365.6681) (xy 422.251575 -365.642599) (xy 422.304359 -365.624592)
			(xy 422.359202 -365.614462) (xy 422.414936 -365.612425) (xy 422.470373 -365.618525) (xy 422.52433 -365.632631)
			(xy 422.575659 -365.654443) (xy 422.623265 -365.683497) (xy 422.666133 -365.719172) (xy 422.70335 -365.760709)
			(xy 422.734123 -365.807222) (xy 422.757795 -365.857719) (xy 422.773863 -365.911126) (xy 422.781983 -365.966302)
			(xy 422.782492 -365.994188) (xy 422.781983 -366.022074) (xy 422.773863 -366.07725) (xy 422.757795 -366.130657)
			(xy 422.734123 -366.181154) (xy 422.70335 -366.227667) (xy 422.666133 -366.269204) (xy 422.623265 -366.304879)
			(xy 422.575659 -366.333933) (xy 422.52433 -366.355745) (xy 422.470373 -366.369851) (xy 422.414936 -366.375951)
			(xy 422.359202 -366.373914) (xy 422.304359 -366.363784) (xy 422.251575 -366.345777) (xy 422.201975 -366.320276)
			(xy 422.156617 -366.287825) (xy 422.116468 -366.249116) (xy 422.082382 -366.204973) (xy 422.055086 -366.156338)
			(xy 422.035163 -366.104247) (xy 422.023037 -366.04981) (xy 422.018966 -365.994188) (xy 416.228289 -365.994188)
			(xy 416.234467 -365.998701) (xy 416.261641 -366.008525) (xy 416.276028 -366.009936) (xy 416.304683 -366.012287)
			(xy 416.360849 -366.024579) (xy 416.414535 -366.045157) (xy 416.464527 -366.073556) (xy 416.509692 -366.109134)
			(xy 416.549008 -366.151085) (xy 416.581587 -366.198459) (xy 416.606689 -366.250185) (xy 416.623747 -366.305091)
			(xy 416.632375 -366.361935) (xy 416.632898 -366.390682) (xy 416.632412 -366.417933) (xy 416.624656 -366.471881)
			(xy 416.609301 -366.524176) (xy 416.586659 -366.573753) (xy 416.57813 -366.587024) (xy 423.490136 -366.587024)
			(xy 423.490687 -366.558579) (xy 423.499137 -366.502321) (xy 423.515853 -366.447943) (xy 423.540465 -366.396652)
			(xy 423.572425 -366.349589) (xy 423.611023 -366.307797) (xy 423.632884 -366.28959) (xy 423.644312 -366.279599)
			(xy 423.66133 -366.25449) (xy 423.670235 -366.225493) (xy 423.670243 -366.19516) (xy 423.661353 -366.166158)
			(xy 423.644348 -366.14104) (xy 423.632884 -366.131094) (xy 423.610998 -366.112915) (xy 423.572397 -366.071118)
			(xy 423.540436 -366.02405) (xy 423.515824 -365.972754) (xy 423.499109 -365.918371) (xy 423.49066 -365.862107)
			(xy 423.490136 -365.83366) (xy 423.490622 -365.806409) (xy 423.498378 -365.752461) (xy 423.513733 -365.700166)
			(xy 423.536375 -365.650589) (xy 423.565841 -365.604739) (xy 423.601532 -365.563548) (xy 423.642723 -365.527857)
			(xy 423.688573 -365.498391) (xy 423.73815 -365.475749) (xy 423.790445 -365.460394) (xy 423.844393 -365.452638)
			(xy 423.898895 -365.452638) (xy 423.952843 -365.460394) (xy 424.005138 -365.475749) (xy 424.054715 -365.498391)
			(xy 424.100565 -365.527857) (xy 424.141756 -365.563548) (xy 424.177447 -365.604739) (xy 424.206913 -365.650589)
			(xy 424.229555 -365.700166) (xy 424.24491 -365.752461) (xy 424.252666 -365.806409) (xy 424.252812 -365.81461)
			(xy 425.115482 -365.81461) (xy 425.115968 -365.787359) (xy 425.123724 -365.733411) (xy 425.139079 -365.681116)
			(xy 425.161721 -365.631539) (xy 425.191187 -365.585689) (xy 425.226878 -365.544498) (xy 425.268069 -365.508807)
			(xy 425.313919 -365.479341) (xy 425.363496 -365.456699) (xy 425.415791 -365.441344) (xy 425.469739 -365.433588)
			(xy 425.524241 -365.433588) (xy 425.578189 -365.441344) (xy 425.630484 -365.456699) (xy 425.680061 -365.479341)
			(xy 425.725911 -365.508807) (xy 425.767102 -365.544498) (xy 425.802793 -365.585689) (xy 425.832259 -365.631539)
			(xy 425.854901 -365.681116) (xy 425.870256 -365.733411) (xy 425.878012 -365.787359) (xy 425.878498 -365.81461)
			(xy 425.878261 -365.833277) (xy 425.874571 -365.870429) (xy 425.871132 -365.888778) (xy 425.868794 -365.903046)
			(xy 425.871323 -365.931834) (xy 425.88182 -365.958759) (xy 425.899444 -365.981662) (xy 425.922781 -365.998707)
			(xy 425.94996 -366.008527) (xy 425.96435 -366.009936) (xy 425.993007 -366.012269) (xy 426.049173 -366.024563)
			(xy 426.10286 -366.045144) (xy 426.152851 -366.073546) (xy 426.198016 -366.109126) (xy 426.237332 -366.151079)
			(xy 426.26991 -366.198455) (xy 426.295011 -366.250182) (xy 426.312069 -366.305089) (xy 426.320697 -366.361934)
			(xy 426.32122 -366.390682) (xy 426.320734 -366.417933) (xy 426.312978 -366.471881) (xy 426.297623 -366.524176)
			(xy 426.274981 -366.573753) (xy 426.245515 -366.619603) (xy 426.209824 -366.660794) (xy 426.168633 -366.696485)
			(xy 426.122783 -366.725951) (xy 426.073206 -366.748593) (xy 426.020911 -366.763948) (xy 425.966963 -366.771704)
			(xy 425.912461 -366.771704) (xy 425.858513 -366.763948) (xy 425.806218 -366.748593) (xy 425.756641 -366.725951)
			(xy 425.710791 -366.696485) (xy 425.6696 -366.660794) (xy 425.633909 -366.619603) (xy 425.604443 -366.573753)
			(xy 425.581801 -366.524176) (xy 425.566446 -366.471881) (xy 425.55869 -366.417933) (xy 425.558204 -366.390682)
			(xy 425.55844 -366.372015) (xy 425.56213 -366.334863) (xy 425.56557 -366.316514) (xy 425.567914 -366.302247)
			(xy 425.565383 -366.273459) (xy 425.554885 -366.246533) (xy 425.53726 -366.22363) (xy 425.513922 -366.206585)
			(xy 425.486742 -366.196765) (xy 425.472352 -366.195356) (xy 425.443694 -366.19303) (xy 425.387527 -366.180735)
			(xy 425.33384 -366.160154) (xy 425.283849 -366.131752) (xy 425.238684 -366.096171) (xy 425.199367 -366.054217)
			(xy 425.16679 -366.00684) (xy 425.141688 -365.955112) (xy 425.124631 -365.900204) (xy 425.116004 -365.843358)
			(xy 425.115482 -365.81461) (xy 424.252812 -365.81461) (xy 424.253152 -365.83366) (xy 424.252665 -365.862107)
			(xy 424.244202 -365.918369) (xy 424.227473 -365.972748) (xy 424.20285 -366.024038) (xy 424.170879 -366.0711)
			(xy 424.13227 -366.112889) (xy 424.110404 -366.131094) (xy 424.098893 -366.140996) (xy 424.081878 -366.166131)
			(xy 424.072984 -366.19515) (xy 424.072992 -366.225502) (xy 424.081901 -366.254517) (xy 424.098929 -366.279643)
			(xy 424.110404 -366.28959) (xy 424.13228 -366.307781) (xy 424.170882 -366.349575) (xy 424.202845 -366.396641)
			(xy 424.227458 -366.447934) (xy 424.244176 -366.502315) (xy 424.252627 -366.558577) (xy 424.253152 -366.587024)
			(xy 424.252666 -366.614275) (xy 424.24491 -366.668223) (xy 424.229555 -366.720518) (xy 424.206913 -366.770095)
			(xy 424.177447 -366.815945) (xy 424.141756 -366.857136) (xy 424.100565 -366.892827) (xy 424.054715 -366.922293)
			(xy 424.005138 -366.944935) (xy 423.952843 -366.96029) (xy 423.898895 -366.968046) (xy 423.844393 -366.968046)
			(xy 423.790445 -366.96029) (xy 423.73815 -366.944935) (xy 423.688573 -366.922293) (xy 423.642723 -366.892827)
			(xy 423.601532 -366.857136) (xy 423.565841 -366.815945) (xy 423.536375 -366.770095) (xy 423.513733 -366.720518)
			(xy 423.498378 -366.668223) (xy 423.490622 -366.614275) (xy 423.490136 -366.587024) (xy 416.57813 -366.587024)
			(xy 416.557193 -366.619603) (xy 416.521502 -366.660794) (xy 416.480311 -366.696485) (xy 416.434461 -366.725951)
			(xy 416.384884 -366.748593) (xy 416.332589 -366.763948) (xy 416.278641 -366.771704) (xy 416.224139 -366.771704)
			(xy 416.170191 -366.763948) (xy 416.117896 -366.748593) (xy 416.068319 -366.725951) (xy 416.022469 -366.696485)
			(xy 415.981278 -366.660794) (xy 415.945587 -366.619603) (xy 415.916121 -366.573753) (xy 415.893479 -366.524176)
			(xy 415.878124 -366.471881) (xy 415.870368 -366.417933) (xy 415.869882 -366.390682) (xy 415.870116 -366.372015)
			(xy 415.873808 -366.334863) (xy 415.877248 -366.316514) (xy 415.879613 -366.302249) (xy 415.877082 -366.273457)
			(xy 415.86658 -366.246528) (xy 415.848951 -366.223623) (xy 415.825608 -366.206579) (xy 415.798422 -366.196762)
			(xy 415.78403 -366.195356) (xy 415.755378 -366.192963) (xy 415.699213 -366.180679) (xy 415.645527 -366.160108)
			(xy 415.595534 -366.131715) (xy 415.550368 -366.096142) (xy 415.51105 -366.054196) (xy 415.478471 -366.006825)
			(xy 415.453368 -365.955102) (xy 415.43631 -365.900198) (xy 415.427682 -365.843356) (xy 415.42716 -365.81461)
			(xy 414.56449 -365.81461) (xy 414.56483 -365.83366) (xy 414.56483 -365.833914) (xy 414.564371 -365.860209)
			(xy 414.557124 -365.912297) (xy 414.542798 -365.962898) (xy 414.521662 -366.011054) (xy 414.494118 -366.055854)
			(xy 414.460686 -366.096449) (xy 414.44164 -366.114584) (xy 414.431657 -366.124432) (xy 414.416951 -366.148293)
			(xy 414.409305 -366.175259) (xy 414.409298 -366.203287) (xy 414.416929 -366.230257) (xy 414.431622 -366.254126)
			(xy 414.44164 -366.263936) (xy 414.460711 -366.28205) (xy 414.494168 -366.322634) (xy 414.521727 -366.367433)
			(xy 414.542864 -366.415596) (xy 414.557178 -366.466208) (xy 414.564274 -366.517428) (xy 414.817814 -366.517428)
			(xy 414.8183 -366.490177) (xy 414.826056 -366.436229) (xy 414.841411 -366.383934) (xy 414.864053 -366.334357)
			(xy 414.893519 -366.288507) (xy 414.92921 -366.247316) (xy 414.970401 -366.211625) (xy 415.016251 -366.182159)
			(xy 415.065828 -366.159517) (xy 415.118123 -366.144162) (xy 415.172071 -366.136406) (xy 415.226573 -366.136406)
			(xy 415.280521 -366.144162) (xy 415.332816 -366.159517) (xy 415.382393 -366.182159) (xy 415.428243 -366.211625)
			(xy 415.469434 -366.247316) (xy 415.505125 -366.288507) (xy 415.534591 -366.334357) (xy 415.557233 -366.383934)
			(xy 415.572588 -366.436229) (xy 415.580344 -366.490177) (xy 415.58083 -366.517428) (xy 415.580369 -366.544172)
			(xy 415.572876 -366.597134) (xy 415.558056 -366.648529) (xy 415.536199 -366.697349) (xy 415.507733 -366.742635)
			(xy 415.473219 -366.783498) (xy 415.453576 -366.801654) (xy 415.453576 -367.06556) (xy 415.89071 -367.50244)
			(xy 418.40531 -367.50244) (xy 418.965888 -366.942116) (xy 418.983997 -366.924875) (xy 419.025537 -366.897062)
			(xy 419.071704 -366.877884) (xy 419.120725 -366.86808) (xy 419.14572 -366.86744) (xy 422.18864 -366.86744)
			(xy 422.213634 -366.868108) (xy 422.262656 -366.877901) (xy 422.308827 -366.897065) (xy 422.350375 -366.924865)
			(xy 422.368472 -366.942116) (xy 423.37609 -367.94948) (xy 424.13809 -367.94948) (xy 424.633136 -367.454434)
			(xy 424.633136 -366.801654) (xy 424.613531 -366.783473) (xy 424.579071 -366.742592) (xy 424.550656 -366.697301)
			(xy 424.528841 -366.648486) (xy 424.514055 -366.597105) (xy 424.506587 -366.544162) (xy 424.506136 -366.517428)
			(xy 424.506622 -366.490177) (xy 424.514378 -366.436229) (xy 424.529733 -366.383934) (xy 424.552375 -366.334357)
			(xy 424.581841 -366.288507) (xy 424.617532 -366.247316) (xy 424.658723 -366.211625) (xy 424.704573 -366.182159)
			(xy 424.75415 -366.159517) (xy 424.806445 -366.144162) (xy 424.860393 -366.136406) (xy 424.914895 -366.136406)
			(xy 424.968843 -366.144162) (xy 425.021138 -366.159517) (xy 425.070715 -366.182159) (xy 425.116565 -366.211625)
			(xy 425.157756 -366.247316) (xy 425.193447 -366.288507) (xy 425.222913 -366.334357) (xy 425.245555 -366.383934)
			(xy 425.26091 -366.436229) (xy 425.268666 -366.490177) (xy 425.269152 -366.517428) (xy 425.268686 -366.544162)
			(xy 425.261229 -366.597107) (xy 425.246451 -366.648492) (xy 425.224641 -366.69731) (xy 425.196228 -366.742603)
			(xy 425.161768 -366.783485) (xy 425.142152 -366.801654) (xy 425.142152 -367.559844) (xy 425.141489 -367.584839)
			(xy 425.131694 -367.633861) (xy 425.112529 -367.680031) (xy 425.084728 -367.721579) (xy 425.067476 -367.739676)
			(xy 424.423332 -368.38382) (xy 424.405262 -368.401105) (xy 424.363708 -368.428909) (xy 424.317529 -368.448074)
			(xy 424.268499 -368.457864) (xy 424.2435 -368.458496) (xy 423.27068 -368.458496) (xy 423.245684 -368.457867)
			(xy 423.196661 -368.448059) (xy 423.150491 -368.428883) (xy 423.108945 -368.401075) (xy 423.090848 -368.38382)
			(xy 422.08323 -367.376456) (xy 419.25113 -367.376456) (xy 418.690552 -367.93678) (xy 418.672467 -367.954048)
			(xy 418.630919 -367.981857) (xy 418.584744 -368.001027) (xy 418.535717 -368.010822) (xy 418.51072 -368.011456)
			(xy 415.7853 -368.011456) (xy 415.760304 -368.010826) (xy 415.71128 -368.001021) (xy 415.66511 -367.981845)
			(xy 415.623564 -367.954036) (xy 415.605468 -367.93678) (xy 415.01949 -367.350802) (xy 415.002261 -367.332698)
			(xy 414.974519 -367.291137) (xy 414.955413 -367.244965) (xy 414.945676 -367.195954) (xy 414.945068 -367.17097)
			(xy 414.945068 -366.801654) (xy 414.925452 -366.783472) (xy 414.890949 -366.742606) (xy 414.862489 -366.697323)
			(xy 414.840629 -366.64851) (xy 414.825798 -366.597123) (xy 414.818286 -366.54417) (xy 414.817814 -366.517428)
			(xy 414.564274 -366.517428) (xy 414.564396 -366.518307) (xy 414.56483 -366.544606) (xy 414.56483 -366.54486)
			(xy 414.564344 -366.572111) (xy 414.556588 -366.626059) (xy 414.541233 -366.678354) (xy 414.518591 -366.727931)
			(xy 414.489125 -366.773781) (xy 414.453434 -366.814972) (xy 414.412243 -366.850663) (xy 414.366393 -366.880129)
			(xy 414.316816 -366.902771) (xy 414.264521 -366.918126) (xy 414.210573 -366.925882) (xy 414.156071 -366.925882)
			(xy 414.102123 -366.918126) (xy 414.049828 -366.902771) (xy 414.000251 -366.880129) (xy 413.954401 -366.850663)
			(xy 413.91321 -366.814972) (xy 413.877519 -366.773781) (xy 413.848053 -366.727931) (xy 413.825411 -366.678354)
			(xy 413.810056 -366.626059) (xy 413.8023 -366.572111) (xy 413.801814 -366.54486) (xy 410.692122 -366.54486)
			(xy 410.92882 -368.165888) (xy 411.284166 -369.346988) (xy 412.67253 -370.735352) (xy 412.67253 -372.299218)
			(xy 413.591022 -372.299218) (xy 413.594749 -372.24597) (xy 413.605863 -372.193761) (xy 413.624146 -372.143611)
			(xy 413.649242 -372.096499) (xy 413.68066 -372.053346) (xy 413.717787 -372.014993) (xy 413.738568 -371.99824)
			(xy 413.750345 -371.988311) (xy 413.767866 -371.962997) (xy 413.777047 -371.933611) (xy 413.777053 -371.902825)
			(xy 413.767883 -371.873436) (xy 413.75037 -371.848116) (xy 413.738568 -371.83822) (xy 413.716087 -371.820026)
			(xy 413.676354 -371.778006) (xy 413.643415 -371.730471) (xy 413.618027 -371.678511) (xy 413.600769 -371.623314)
			(xy 413.592038 -371.566146) (xy 413.591502 -371.53723) (xy 413.591985 -371.50986) (xy 413.599799 -371.455682)
			(xy 413.615284 -371.403179) (xy 413.638122 -371.353432) (xy 413.667843 -371.307464) (xy 413.685482 -371.286532)
			(xy 413.694691 -371.275184) (xy 413.706874 -371.248634) (xy 413.711053 -371.219723) (xy 413.706887 -371.19081)
			(xy 413.694716 -371.164255) (xy 413.685482 -371.152928) (xy 413.667873 -371.131971) (xy 413.63815 -371.086006)
			(xy 413.615306 -371.036264) (xy 413.599809 -370.983766) (xy 413.591979 -370.929591) (xy 413.591975 -370.874854)
			(xy 413.599799 -370.820679) (xy 413.61529 -370.768179) (xy 413.638128 -370.718434) (xy 413.667845 -370.672466)
			(xy 413.685482 -370.651532) (xy 413.694691 -370.640184) (xy 413.706874 -370.613634) (xy 413.711053 -370.584723)
			(xy 413.706887 -370.55581) (xy 413.694716 -370.529255) (xy 413.685482 -370.517928) (xy 413.66784 -370.496999)
			(xy 413.638129 -370.451025) (xy 413.615294 -370.401277) (xy 413.599804 -370.348775) (xy 413.591976 -370.294599)
			(xy 413.591502 -370.26723) (xy 413.591983 -370.239977) (xy 413.599736 -370.186027) (xy 413.615089 -370.133728)
			(xy 413.637729 -370.084148) (xy 413.667195 -370.038294) (xy 413.702887 -369.997101) (xy 413.744078 -369.961407)
			(xy 413.78993 -369.931938) (xy 413.83951 -369.909296) (xy 413.891807 -369.893941) (xy 413.945757 -369.886185)
			(xy 413.97301 -369.885722) (xy 414.000381 -369.886177) (xy 414.05456 -369.893997) (xy 414.107064 -369.909488)
			(xy 414.156811 -369.932332) (xy 414.202777 -369.962059) (xy 414.223708 -369.979702) (xy 414.235036 -369.988938)
			(xy 414.261593 -370.001114) (xy 414.29051 -370.005287) (xy 414.319427 -370.001114) (xy 414.345984 -369.988938)
			(xy 414.357312 -369.979702) (xy 414.378267 -369.962091) (xy 414.424233 -369.932375) (xy 414.473975 -369.909533)
			(xy 414.526471 -369.894036) (xy 414.580642 -369.8862) (xy 414.60801 -369.885722) (xy 414.636925 -369.886297)
			(xy 414.694094 -369.895013) (xy 414.749292 -369.912259) (xy 414.801254 -369.93764) (xy 414.848789 -369.970574)
			(xy 414.890808 -370.010307) (xy 414.909 -370.032788) (xy 414.918897 -370.044593) (xy 414.944221 -370.062112)
			(xy 414.973614 -370.071288) (xy 415.004406 -370.071288) (xy 415.033799 -370.062112) (xy 415.059123 -370.044593)
			(xy 415.06902 -370.032788) (xy 415.087197 -370.010292) (xy 415.12922 -369.970559) (xy 415.176758 -369.937621)
			(xy 415.228722 -369.912235) (xy 415.283922 -369.894981) (xy 415.341093 -369.886255) (xy 415.37001 -369.885722)
			(xy 415.397264 -369.886146) (xy 415.451218 -369.893905) (xy 415.503519 -369.909264) (xy 415.553101 -369.931909)
			(xy 415.598956 -369.961381) (xy 415.640149 -369.997079) (xy 415.675843 -370.038276) (xy 415.70531 -370.084134)
			(xy 415.72795 -370.133719) (xy 415.743304 -370.186021) (xy 415.751057 -370.239975) (xy 415.751518 -370.26723)
			(xy 415.75109 -370.294602) (xy 415.743266 -370.348783) (xy 415.727769 -370.401288) (xy 415.704918 -370.451034)
			(xy 415.675184 -370.496998) (xy 415.657538 -370.517928) (xy 415.648269 -370.529232) (xy 415.636091 -370.555798)
			(xy 415.631922 -370.584723) (xy 415.636104 -370.613646) (xy 415.648294 -370.640206) (xy 415.657538 -370.651532)
			(xy 415.67521 -370.67244) (xy 415.704936 -370.718411) (xy 415.727782 -370.768162) (xy 415.743277 -370.820668)
			(xy 415.751104 -370.87485) (xy 415.7511 -370.929595) (xy 415.743267 -370.983777) (xy 415.727766 -371.036281)
			(xy 415.704914 -371.086028) (xy 415.675182 -371.131996) (xy 415.657538 -371.152928) (xy 415.648269 -371.164232)
			(xy 415.636091 -371.190798) (xy 415.631922 -371.219723) (xy 415.636104 -371.248646) (xy 415.648294 -371.275206)
			(xy 415.657538 -371.286532) (xy 415.675165 -371.307474) (xy 415.704877 -371.353444) (xy 415.727715 -371.40319)
			(xy 415.743209 -371.455688) (xy 415.751042 -371.509862) (xy 415.751518 -371.53723) (xy 415.75098 -371.566147)
			(xy 415.74226 -371.623318) (xy 415.725008 -371.678518) (xy 415.69962 -371.730481) (xy 415.666678 -371.778015)
			(xy 415.626937 -371.820031) (xy 415.604452 -371.83822) (xy 415.592613 -371.848083) (xy 415.575089 -371.873414)
			(xy 415.565913 -371.902817) (xy 415.565919 -371.933619) (xy 415.575106 -371.963019) (xy 415.592639 -371.988344)
			(xy 415.604452 -371.99824) (xy 415.625264 -372.014958) (xy 415.662394 -372.053316) (xy 415.693814 -372.096475)
			(xy 415.718912 -372.143593) (xy 415.737196 -372.193749) (xy 415.748311 -372.245964) (xy 415.75026 -372.273818)
			(xy 416.956522 -372.273818) (xy 416.960249 -372.22057) (xy 416.971363 -372.168361) (xy 416.989646 -372.118211)
			(xy 417.014742 -372.071099) (xy 417.04616 -372.027946) (xy 417.083287 -371.989593) (xy 417.104068 -371.97284)
			(xy 417.115845 -371.962911) (xy 417.133366 -371.937597) (xy 417.142547 -371.908211) (xy 417.142553 -371.877425)
			(xy 417.133383 -371.848036) (xy 417.11587 -371.822716) (xy 417.104068 -371.81282) (xy 417.081587 -371.794626)
			(xy 417.041854 -371.752606) (xy 417.008915 -371.705071) (xy 416.983527 -371.653111) (xy 416.966269 -371.597914)
			(xy 416.957538 -371.540746) (xy 416.957002 -371.51183) (xy 416.957485 -371.48446) (xy 416.965299 -371.430282)
			(xy 416.980784 -371.377779) (xy 417.003622 -371.328032) (xy 417.033343 -371.282064) (xy 417.050982 -371.261132)
			(xy 417.060191 -371.249784) (xy 417.072374 -371.223234) (xy 417.076553 -371.194323) (xy 417.072387 -371.16541)
			(xy 417.060216 -371.138855) (xy 417.050982 -371.127528) (xy 417.033373 -371.106571) (xy 417.00365 -371.060606)
			(xy 416.980806 -371.010864) (xy 416.965309 -370.958366) (xy 416.957479 -370.904191) (xy 416.957475 -370.849454)
			(xy 416.965299 -370.795279) (xy 416.98079 -370.742779) (xy 417.003628 -370.693034) (xy 417.033345 -370.647066)
			(xy 417.050982 -370.626132) (xy 417.060191 -370.614784) (xy 417.072374 -370.588234) (xy 417.076553 -370.559323)
			(xy 417.072387 -370.53041) (xy 417.060216 -370.503855) (xy 417.050982 -370.492528) (xy 417.03334 -370.471599)
			(xy 417.003629 -370.425625) (xy 416.980794 -370.375877) (xy 416.965304 -370.323375) (xy 416.957476 -370.269199)
			(xy 416.957002 -370.24183) (xy 416.957488 -370.214579) (xy 416.965244 -370.160631) (xy 416.980599 -370.108336)
			(xy 417.003241 -370.058759) (xy 417.032707 -370.012909) (xy 417.068398 -369.971718) (xy 417.109589 -369.936027)
			(xy 417.155439 -369.906561) (xy 417.205016 -369.883919) (xy 417.257311 -369.868564) (xy 417.311259 -369.860808)
			(xy 417.365761 -369.860808) (xy 417.419709 -369.868564) (xy 417.472004 -369.883919) (xy 417.521581 -369.906561)
			(xy 417.567431 -369.936027) (xy 417.608622 -369.971718) (xy 417.644313 -370.012909) (xy 417.669658 -370.052346)
			(xy 419.301422 -370.052346) (xy 419.301948 -370.023176) (xy 419.310856 -369.96552) (xy 419.32844 -369.909892)
			(xy 419.35429 -369.857592) (xy 419.387803 -369.809837) (xy 419.428198 -369.767744) (xy 419.451028 -369.749578)
			(xy 419.461394 -369.741142) (xy 419.47769 -369.719968) (xy 419.487936 -369.695292) (xy 419.491432 -369.668804)
			(xy 419.487938 -369.642315) (xy 419.477693 -369.617638) (xy 419.4614 -369.596464) (xy 419.451028 -369.588034)
			(xy 419.428198 -369.569867) (xy 419.387796 -369.527782) (xy 419.35428 -369.480029) (xy 419.328434 -369.427727)
			(xy 419.310862 -369.372096) (xy 419.301975 -369.314436) (xy 419.301422 -369.285266) (xy 419.301846 -369.258013)
			(xy 419.309608 -369.204061) (xy 419.324969 -369.151763) (xy 419.347616 -369.102184) (xy 419.377089 -369.056332)
			(xy 419.412787 -369.015142) (xy 419.453984 -368.979451) (xy 419.49984 -368.949986) (xy 419.549423 -368.927347)
			(xy 419.601724 -368.911995) (xy 419.655676 -368.904242) (xy 419.68293 -368.903758) (xy 419.711846 -368.904305)
			(xy 419.769017 -368.913025) (xy 419.824216 -368.930276) (xy 419.876178 -368.955662) (xy 419.923713 -368.988602)
			(xy 419.96573 -369.02834) (xy 419.98392 -369.050824) (xy 419.993817 -369.062629) (xy 420.019141 -369.080148)
			(xy 420.048534 -369.089324) (xy 420.079326 -369.089324) (xy 420.108719 -369.080148) (xy 420.134043 -369.062629)
			(xy 420.14394 -369.050824) (xy 420.162115 -369.028326) (xy 420.204137 -368.988591) (xy 420.251675 -368.955653)
			(xy 420.30364 -368.930267) (xy 420.358841 -368.913014) (xy 420.416013 -368.90429) (xy 420.44493 -368.903758)
			(xy 420.473478 -368.904268) (xy 420.529933 -368.912792) (xy 420.584489 -368.929632) (xy 420.635927 -368.95441)
			(xy 420.659814 -368.970052) (xy 420.670957 -368.977114) (xy 420.69581 -368.985923) (xy 420.722092 -368.988052)
			(xy 420.748038 -368.983358) (xy 420.771908 -368.972156) (xy 420.792099 -368.955198) (xy 420.800022 -368.944652)
			(xy 420.815446 -368.923649) (xy 420.851043 -368.885595) (xy 420.891486 -368.852737) (xy 420.936022 -368.825686)
			(xy 420.983824 -368.804944) (xy 421.034003 -368.790897) (xy 421.085626 -368.783806) (xy 421.11168 -368.783362)
			(xy 421.140598 -368.783871) (xy 421.19777 -368.792599) (xy 421.25297 -368.809857) (xy 421.304932 -368.83525)
			(xy 421.352466 -368.868197) (xy 421.394481 -368.907941) (xy 421.41267 -368.930428) (xy 421.422567 -368.942233)
			(xy 421.447891 -368.959752) (xy 421.477284 -368.968928) (xy 421.508076 -368.968928) (xy 421.537469 -368.959752)
			(xy 421.562793 -368.942233) (xy 421.57269 -368.930428) (xy 421.590894 -368.907955) (xy 421.63291 -368.868218)
			(xy 421.680442 -368.835277) (xy 421.732401 -368.809886) (xy 421.787597 -368.792628) (xy 421.844765 -368.783898)
			(xy 421.87368 -368.783362) (xy 421.900929 -368.783897) (xy 421.954874 -368.79165) (xy 422.007166 -368.807001)
			(xy 422.056741 -368.829637) (xy 422.10259 -368.859099) (xy 422.143779 -368.894785) (xy 422.179471 -368.93597)
			(xy 422.208939 -368.981815) (xy 422.231582 -369.031387) (xy 422.24694 -369.083677) (xy 422.2547 -369.137621)
			(xy 422.255188 -369.16487) (xy 422.254738 -369.190913) (xy 422.247655 -369.242514) (xy 422.233618 -369.292672)
			(xy 422.212886 -369.340454) (xy 422.185846 -369.384971) (xy 422.153001 -369.425395) (xy 422.134284 -369.443508)
			(xy 422.124324 -369.453453) (xy 422.109861 -369.477587) (xy 422.102521 -369.504749) (xy 422.102859 -369.532884)
			(xy 422.110849 -369.559862) (xy 422.125888 -369.583642) (xy 422.136062 -369.593368) (xy 422.155664 -369.611509)
			(xy 422.190054 -369.652374) (xy 422.218408 -369.697637) (xy 422.240172 -369.746412) (xy 422.25492 -369.797746)
			(xy 422.262364 -369.850635) (xy 422.262808 -369.87734) (xy 422.262337 -369.905111) (xy 422.254279 -369.960065)
			(xy 422.238337 -370.01327) (xy 422.214849 -370.063601) (xy 422.184312 -370.109994) (xy 422.147371 -370.15147)
			(xy 422.12641 -370.169694) (xy 422.115726 -370.179181) (xy 422.099744 -370.202854) (xy 422.090956 -370.230032)
			(xy 422.090053 -370.258581) (xy 422.097104 -370.28626) (xy 422.111557 -370.310897) (xy 422.121584 -370.321078)
			(xy 422.139964 -370.339133) (xy 422.172132 -370.37938) (xy 422.198597 -370.423587) (xy 422.218876 -370.470952)
			(xy 422.232603 -370.520613) (xy 422.239527 -370.571668) (xy 422.239948 -370.59743) (xy 422.239512 -370.624801)
			(xy 422.231689 -370.678982) (xy 422.216194 -370.731486) (xy 422.193345 -370.781233) (xy 422.163613 -370.827198)
			(xy 422.145968 -370.848128) (xy 422.136705 -370.859435) (xy 422.124535 -370.886001) (xy 422.120369 -370.914923)
			(xy 422.124548 -370.943843) (xy 422.136729 -370.970403) (xy 422.145968 -370.981732) (xy 422.163638 -371.002641)
			(xy 422.193362 -371.048613) (xy 422.216206 -371.098363) (xy 422.2317 -371.150869) (xy 422.239526 -371.20505)
			(xy 422.239523 -371.259795) (xy 422.231691 -371.313976) (xy 422.21619 -371.36648) (xy 422.19334 -371.416227)
			(xy 422.163611 -371.462195) (xy 422.145968 -371.483128) (xy 422.136705 -371.494435) (xy 422.124535 -371.521001)
			(xy 422.120369 -371.549923) (xy 422.124548 -371.578843) (xy 422.136729 -371.605403) (xy 422.145968 -371.616732)
			(xy 422.163638 -371.637641) (xy 422.193362 -371.683613) (xy 422.216206 -371.733363) (xy 422.2317 -371.785869)
			(xy 422.235289 -371.810718) (xy 423.31665 -371.810718) (xy 423.31665 -371.726022) (xy 423.324701 -371.641708)
			(xy 423.34073 -371.558542) (xy 423.364591 -371.477275) (xy 423.39607 -371.398645) (xy 423.434881 -371.323364)
			(xy 423.480671 -371.252112) (xy 423.533027 -371.185536) (xy 423.591475 -371.124238) (xy 423.655485 -371.068773)
			(xy 423.724477 -371.019644) (xy 423.797827 -370.977295) (xy 423.87487 -370.942111) (xy 423.954909 -370.914409)
			(xy 424.037218 -370.894441) (xy 424.121053 -370.882388) (xy 424.205654 -370.878358) (xy 424.290255 -370.882388)
			(xy 424.37409 -370.894441) (xy 424.456399 -370.914409) (xy 424.536438 -370.942111) (xy 424.613481 -370.977295)
			(xy 424.686831 -371.019644) (xy 424.755823 -371.068773) (xy 424.819833 -371.124238) (xy 424.878281 -371.185536)
			(xy 424.930637 -371.252112) (xy 424.976427 -371.323364) (xy 425.015238 -371.398645) (xy 425.046717 -371.477275)
			(xy 425.070578 -371.558542) (xy 425.086607 -371.641708) (xy 425.094658 -371.726022) (xy 425.095162 -371.76837)
			(xy 425.841163 -371.76837) (xy 425.845199 -371.684923) (xy 425.857271 -371.602255) (xy 425.877264 -371.521138)
			(xy 425.904993 -371.442329) (xy 425.940199 -371.366564) (xy 425.982553 -371.294551) (xy 426.031659 -371.226962)
			(xy 426.08706 -371.164428) (xy 426.148237 -371.107533) (xy 426.21462 -371.056807) (xy 426.285588 -371.012726)
			(xy 426.36048 -370.9757) (xy 426.438596 -370.946074) (xy 426.519206 -370.924126) (xy 426.601558 -370.910061)
			(xy 426.684884 -370.904009) (xy 426.768404 -370.906028) (xy 426.85134 -370.916098) (xy 426.932916 -370.934126)
			(xy 427.012372 -370.959943) (xy 427.088965 -370.993308) (xy 427.161981 -371.033909) (xy 427.230737 -371.081368)
			(xy 427.294591 -371.135241) (xy 427.352948 -371.195026) (xy 427.405263 -371.260163) (xy 427.451046 -371.330046)
			(xy 427.489871 -371.404021) (xy 427.521376 -371.481398) (xy 427.545265 -371.561455) (xy 427.561316 -371.643443)
			(xy 427.569379 -371.726598) (xy 427.569884 -371.76837) (xy 427.569379 -371.810142) (xy 427.561316 -371.893297)
			(xy 427.545265 -371.975285) (xy 427.521376 -372.055342) (xy 427.489871 -372.132719) (xy 427.451046 -372.206694)
			(xy 427.405263 -372.276577) (xy 427.352948 -372.341714) (xy 427.294591 -372.401499) (xy 427.230737 -372.455372)
			(xy 427.161981 -372.502831) (xy 427.088965 -372.543432) (xy 427.012372 -372.576797) (xy 426.932916 -372.602614)
			(xy 426.85134 -372.620642) (xy 426.768404 -372.630712) (xy 426.684884 -372.632731) (xy 426.601558 -372.626679)
			(xy 426.519206 -372.612614) (xy 426.438596 -372.590666) (xy 426.36048 -372.56104) (xy 426.285588 -372.524014)
			(xy 426.21462 -372.479933) (xy 426.148237 -372.429207) (xy 426.08706 -372.372312) (xy 426.031659 -372.309778)
			(xy 425.982553 -372.242189) (xy 425.940199 -372.170176) (xy 425.904993 -372.094411) (xy 425.877264 -372.015602)
			(xy 425.857271 -371.934485) (xy 425.845199 -371.851817) (xy 425.841163 -371.76837) (xy 425.095162 -371.76837)
			(xy 425.094658 -371.810718) (xy 425.086607 -371.895032) (xy 425.070578 -371.978198) (xy 425.046717 -372.059465)
			(xy 425.015238 -372.138095) (xy 424.976427 -372.213376) (xy 424.930637 -372.284628) (xy 424.878281 -372.351204)
			(xy 424.819833 -372.412502) (xy 424.755823 -372.467967) (xy 424.686831 -372.517096) (xy 424.613481 -372.559445)
			(xy 424.536438 -372.594629) (xy 424.456399 -372.622331) (xy 424.37409 -372.642299) (xy 424.290255 -372.654352)
			(xy 424.205654 -372.658383) (xy 424.121053 -372.654352) (xy 424.037218 -372.642299) (xy 423.954909 -372.622331)
			(xy 423.87487 -372.594629) (xy 423.797827 -372.559445) (xy 423.724477 -372.517096) (xy 423.655485 -372.467967)
			(xy 423.591475 -372.412502) (xy 423.533027 -372.351204) (xy 423.480671 -372.284628) (xy 423.434881 -372.213376)
			(xy 423.39607 -372.138095) (xy 423.364591 -372.059465) (xy 423.34073 -371.978198) (xy 423.324701 -371.895032)
			(xy 423.31665 -371.810718) (xy 422.235289 -371.810718) (xy 422.239526 -371.84005) (xy 422.239523 -371.894795)
			(xy 422.231691 -371.948976) (xy 422.21619 -372.00148) (xy 422.19334 -372.051227) (xy 422.163611 -372.097195)
			(xy 422.145968 -372.118128) (xy 422.136705 -372.129435) (xy 422.124535 -372.156001) (xy 422.120369 -372.184923)
			(xy 422.124548 -372.213843) (xy 422.136729 -372.240403) (xy 422.145968 -372.251732) (xy 422.163584 -372.272683)
			(xy 422.1933 -372.31865) (xy 422.216141 -372.368393) (xy 422.231638 -372.420889) (xy 422.239471 -372.475062)
			(xy 422.239948 -372.50243) (xy 422.23945 -372.52968) (xy 422.231691 -372.583625) (xy 422.216334 -372.635917)
			(xy 422.193692 -372.685492) (xy 422.164226 -372.73134) (xy 422.128536 -372.772529) (xy 422.087348 -372.80822)
			(xy 422.041501 -372.837687) (xy 421.991927 -372.86033) (xy 421.939635 -372.875689) (xy 421.88569 -372.88345)
			(xy 421.85844 -372.883938) (xy 421.829523 -372.883415) (xy 421.772351 -372.87469) (xy 421.717151 -372.857435)
			(xy 421.665189 -372.832044) (xy 421.617655 -372.7991) (xy 421.575639 -372.759358) (xy 421.55745 -372.736872)
			(xy 421.547553 -372.725067) (xy 421.522229 -372.707548) (xy 421.492836 -372.698372) (xy 421.462044 -372.698372)
			(xy 421.432651 -372.707548) (xy 421.407327 -372.725067) (xy 421.39743 -372.736872) (xy 421.379215 -372.759335)
			(xy 421.337201 -372.799073) (xy 421.289671 -372.832015) (xy 421.237715 -372.857407) (xy 421.182521 -372.874668)
			(xy 421.125355 -372.883401) (xy 421.09644 -372.883938) (xy 421.069189 -372.883408) (xy 421.015243 -372.875657)
			(xy 420.962948 -372.860307) (xy 420.91337 -372.837672) (xy 420.867518 -372.808211) (xy 420.826326 -372.772524)
			(xy 420.790631 -372.731338) (xy 420.761162 -372.685492) (xy 420.738517 -372.635918) (xy 420.723158 -372.583626)
			(xy 420.715397 -372.52968) (xy 420.714932 -372.50243) (xy 420.715408 -372.47506) (xy 420.723222 -372.420881)
			(xy 420.738708 -372.368378) (xy 420.761548 -372.318631) (xy 420.791271 -372.272664) (xy 420.808912 -372.251732)
			(xy 420.818119 -372.240383) (xy 420.830298 -372.213833) (xy 420.834476 -372.184923) (xy 420.830311 -372.156011)
			(xy 420.818144 -372.129455) (xy 420.808912 -372.118128) (xy 420.791301 -372.097171) (xy 420.761576 -372.051207)
			(xy 420.73873 -372.001465) (xy 420.723232 -371.948967) (xy 420.715401 -371.894792) (xy 420.715398 -371.840054)
			(xy 420.723223 -371.785878) (xy 420.738714 -371.733378) (xy 420.761555 -371.683632) (xy 420.791274 -371.637665)
			(xy 420.808912 -371.616732) (xy 420.818119 -371.605383) (xy 420.830298 -371.578833) (xy 420.834476 -371.549923)
			(xy 420.830311 -371.521011) (xy 420.818144 -371.494455) (xy 420.808912 -371.483128) (xy 420.791301 -371.462171)
			(xy 420.761576 -371.416207) (xy 420.73873 -371.366465) (xy 420.723232 -371.313967) (xy 420.715401 -371.259792)
			(xy 420.715398 -371.205054) (xy 420.723223 -371.150878) (xy 420.738714 -371.098378) (xy 420.761555 -371.048632)
			(xy 420.791274 -371.002665) (xy 420.808912 -370.981732) (xy 420.818119 -370.970383) (xy 420.830298 -370.943833)
			(xy 420.834476 -370.914923) (xy 420.830311 -370.886011) (xy 420.818144 -370.859455) (xy 420.808912 -370.848128)
			(xy 420.791274 -370.827195) (xy 420.761562 -370.781222) (xy 420.738726 -370.731475) (xy 420.723234 -370.678975)
			(xy 420.715406 -370.624799) (xy 420.714932 -370.59743) (xy 420.71516 -370.578375) (xy 420.718982 -370.540457)
			(xy 420.722552 -370.521738) (xy 420.724834 -370.508255) (xy 420.723002 -370.480984) (xy 420.713998 -370.455177)
			(xy 420.698467 -370.432685) (xy 420.677525 -370.41512) (xy 420.652672 -370.403744) (xy 420.625691 -370.399371)
			(xy 420.598517 -370.402315) (xy 420.585646 -370.40693) (xy 420.563174 -370.415447) (xy 420.516636 -370.42744)
			(xy 420.468959 -370.433487) (xy 420.44493 -370.433854) (xy 420.416013 -370.433332) (xy 420.358841 -370.424606)
			(xy 420.303642 -370.40735) (xy 420.25168 -370.381959) (xy 420.204146 -370.349015) (xy 420.16213 -370.309274)
			(xy 420.14394 -370.286788) (xy 420.134043 -370.274983) (xy 420.108719 -370.257464) (xy 420.079326 -370.248288)
			(xy 420.048534 -370.248288) (xy 420.019141 -370.257464) (xy 419.993817 -370.274983) (xy 419.98392 -370.286788)
			(xy 419.965715 -370.309259) (xy 419.923698 -370.348996) (xy 419.876166 -370.381937) (xy 419.824208 -370.407327)
			(xy 419.769013 -370.424586) (xy 419.711845 -370.433318) (xy 419.68293 -370.433854) (xy 419.655682 -370.433294)
			(xy 419.601739 -370.425543) (xy 419.549448 -370.410194) (xy 419.499874 -370.387559) (xy 419.454026 -370.358101)
			(xy 419.412837 -370.322417) (xy 419.377145 -370.281235) (xy 419.347677 -370.235392) (xy 419.325033 -370.185823)
			(xy 419.309673 -370.133535) (xy 419.301911 -370.079594) (xy 419.301422 -370.052346) (xy 417.669658 -370.052346)
			(xy 417.673779 -370.058759) (xy 417.696421 -370.108336) (xy 417.711776 -370.160631) (xy 417.719532 -370.214579)
			(xy 417.720018 -370.24183) (xy 417.71959 -370.269202) (xy 417.711766 -370.323383) (xy 417.696269 -370.375888)
			(xy 417.673418 -370.425634) (xy 417.643684 -370.471598) (xy 417.626038 -370.492528) (xy 417.616769 -370.503832)
			(xy 417.604591 -370.530398) (xy 417.600422 -370.559323) (xy 417.604604 -370.588246) (xy 417.616794 -370.614806)
			(xy 417.626038 -370.626132) (xy 417.64371 -370.64704) (xy 417.673436 -370.693011) (xy 417.696282 -370.742762)
			(xy 417.711777 -370.795268) (xy 417.719604 -370.84945) (xy 417.7196 -370.904195) (xy 417.711767 -370.958377)
			(xy 417.696266 -371.010881) (xy 417.673414 -371.060628) (xy 417.643682 -371.106596) (xy 417.626038 -371.127528)
			(xy 417.616769 -371.138832) (xy 417.604591 -371.165398) (xy 417.600422 -371.194323) (xy 417.604604 -371.223246)
			(xy 417.616794 -371.249806) (xy 417.626038 -371.261132) (xy 417.643665 -371.282074) (xy 417.673377 -371.328044)
			(xy 417.696215 -371.37779) (xy 417.711709 -371.430288) (xy 417.719542 -371.484462) (xy 417.720018 -371.51183)
			(xy 417.71948 -371.540747) (xy 417.71076 -371.597918) (xy 417.693508 -371.653118) (xy 417.66812 -371.705081)
			(xy 417.635178 -371.752615) (xy 417.595437 -371.794631) (xy 417.572952 -371.81282) (xy 417.561113 -371.822683)
			(xy 417.543589 -371.848014) (xy 417.534413 -371.877417) (xy 417.534419 -371.908219) (xy 417.543606 -371.937619)
			(xy 417.561139 -371.962944) (xy 417.572952 -371.97284) (xy 417.593764 -371.989558) (xy 417.630894 -372.027916)
			(xy 417.662314 -372.071075) (xy 417.687412 -372.118193) (xy 417.705696 -372.168349) (xy 417.716811 -372.220564)
			(xy 417.720538 -372.273818) (xy 417.716805 -372.327073) (xy 417.705686 -372.379287) (xy 417.687397 -372.429441)
			(xy 417.662295 -372.476556) (xy 417.63087 -372.519712) (xy 417.593737 -372.558066) (xy 417.572952 -372.57482)
			(xy 417.561113 -372.584683) (xy 417.543589 -372.610014) (xy 417.534413 -372.639417) (xy 417.534419 -372.670219)
			(xy 417.543606 -372.699619) (xy 417.561139 -372.724944) (xy 417.572952 -372.73484) (xy 417.595465 -372.752995)
			(xy 417.635196 -372.795024) (xy 417.66813 -372.842567) (xy 417.693513 -372.894535) (xy 417.710763 -372.949738)
			(xy 417.719486 -373.006912) (xy 417.720018 -373.03583) (xy 417.719532 -373.063081) (xy 417.711776 -373.117029)
			(xy 417.696421 -373.169324) (xy 417.673779 -373.218901) (xy 417.644313 -373.264751) (xy 417.608622 -373.305942)
			(xy 417.567431 -373.341633) (xy 417.521581 -373.371099) (xy 417.472004 -373.393741) (xy 417.419709 -373.409096)
			(xy 417.365761 -373.416852) (xy 417.311259 -373.416852) (xy 417.257311 -373.409096) (xy 417.205016 -373.393741)
			(xy 417.155439 -373.371099) (xy 417.109589 -373.341633) (xy 417.068398 -373.305942) (xy 417.032707 -373.264751)
			(xy 417.003241 -373.218901) (xy 416.980599 -373.169324) (xy 416.965244 -373.117029) (xy 416.957488 -373.063081)
			(xy 416.957002 -373.03583) (xy 416.957541 -373.006914) (xy 416.966266 -372.949744) (xy 416.98352 -372.894545)
			(xy 417.008907 -372.842583) (xy 417.041847 -372.795049) (xy 417.081584 -372.753031) (xy 417.104068 -372.73484)
			(xy 417.115845 -372.724911) (xy 417.133366 -372.699597) (xy 417.142547 -372.670211) (xy 417.142553 -372.639425)
			(xy 417.133383 -372.610036) (xy 417.11587 -372.584716) (xy 417.104068 -372.57482) (xy 417.083314 -372.558031)
			(xy 417.046184 -372.519683) (xy 417.014761 -372.476532) (xy 416.989661 -372.429423) (xy 416.971373 -372.379275)
			(xy 416.960254 -372.327067) (xy 416.956522 -372.273818) (xy 415.75026 -372.273818) (xy 415.752038 -372.299218)
			(xy 415.748305 -372.352473) (xy 415.737186 -372.404687) (xy 415.718897 -372.454841) (xy 415.693795 -372.501956)
			(xy 415.66237 -372.545112) (xy 415.625237 -372.583466) (xy 415.604452 -372.60022) (xy 415.592613 -372.610083)
			(xy 415.575089 -372.635414) (xy 415.565913 -372.664817) (xy 415.565919 -372.695619) (xy 415.575106 -372.725019)
			(xy 415.592639 -372.750344) (xy 415.604452 -372.76024) (xy 415.626965 -372.778395) (xy 415.666696 -372.820424)
			(xy 415.69963 -372.867967) (xy 415.725013 -372.919935) (xy 415.742263 -372.975138) (xy 415.750986 -373.032312)
			(xy 415.751518 -373.06123) (xy 415.75105 -373.088482) (xy 415.74329 -373.142429) (xy 415.727931 -373.194724)
			(xy 415.705287 -373.244301) (xy 415.675819 -373.29015) (xy 415.640126 -373.33134) (xy 415.598934 -373.367031)
			(xy 415.553083 -373.396497) (xy 415.503505 -373.419138) (xy 415.45121 -373.434494) (xy 415.397262 -373.442252)
			(xy 415.37001 -373.442738) (xy 415.341092 -373.442236) (xy 415.283919 -373.433507) (xy 415.228719 -373.416247)
			(xy 415.176757 -373.390853) (xy 415.129224 -373.357905) (xy 415.087209 -373.31816) (xy 415.06902 -373.295672)
			(xy 415.059123 -373.283867) (xy 415.033799 -373.266348) (xy 415.004406 -373.257172) (xy 414.973614 -373.257172)
			(xy 414.944221 -373.266348) (xy 414.918897 -373.283867) (xy 414.909 -373.295672) (xy 414.890802 -373.31815)
			(xy 414.848784 -373.357886) (xy 414.801251 -373.390827) (xy 414.749291 -373.416217) (xy 414.694095 -373.433474)
			(xy 414.636926 -373.442203) (xy 414.60801 -373.442738) (xy 414.580639 -373.442281) (xy 414.526459 -373.434463)
			(xy 414.473955 -373.418973) (xy 414.424209 -373.396129) (xy 414.378243 -373.366401) (xy 414.357312 -373.348758)
			(xy 414.345984 -373.339522) (xy 414.319427 -373.327346) (xy 414.29051 -373.323173) (xy 414.261593 -373.327346)
			(xy 414.235036 -373.339522) (xy 414.223708 -373.348758) (xy 414.202778 -373.3664) (xy 414.156806 -373.396113)
			(xy 414.107058 -373.418949) (xy 414.054556 -373.434439) (xy 414.000379 -373.442265) (xy 413.97301 -373.442738)
			(xy 413.94576 -373.442213) (xy 413.891816 -373.434458) (xy 413.839524 -373.419106) (xy 413.789948 -373.396468)
			(xy 413.744099 -373.367006) (xy 413.70291 -373.331318) (xy 413.667218 -373.290133) (xy 413.637751 -373.244287)
			(xy 413.615108 -373.194714) (xy 413.59975 -373.142423) (xy 413.59199 -373.08848) (xy 413.591502 -373.06123)
			(xy 413.592041 -373.032314) (xy 413.600766 -372.975144) (xy 413.61802 -372.919945) (xy 413.643407 -372.867983)
			(xy 413.676347 -372.820449) (xy 413.716084 -372.778431) (xy 413.738568 -372.76024) (xy 413.750345 -372.750311)
			(xy 413.767866 -372.724997) (xy 413.777047 -372.695611) (xy 413.777053 -372.664825) (xy 413.767883 -372.635436)
			(xy 413.75037 -372.610116) (xy 413.738568 -372.60022) (xy 413.717814 -372.583431) (xy 413.680684 -372.545083)
			(xy 413.649261 -372.501932) (xy 413.624161 -372.454823) (xy 413.605873 -372.404675) (xy 413.594754 -372.352467)
			(xy 413.591022 -372.299218) (xy 412.67253 -372.299218) (xy 412.67253 -373.962168) (xy 412.784098 -374.333052)
			(xy 416.088785 -374.333052) (xy 416.088785 -374.278548) (xy 416.096542 -374.224599) (xy 416.111899 -374.172302)
			(xy 416.134542 -374.122724) (xy 416.16401 -374.076873) (xy 416.199704 -374.035683) (xy 416.240897 -373.999992)
			(xy 416.286751 -373.970527) (xy 416.336331 -373.947888) (xy 416.388628 -373.932536) (xy 416.442578 -373.924783)
			(xy 416.46983 -373.924322) (xy 416.498745 -373.924882) (xy 416.555915 -373.933601) (xy 416.611113 -373.95085)
			(xy 416.663076 -373.976234) (xy 416.710611 -374.009171) (xy 416.752629 -374.048905) (xy 416.77082 -374.071388)
			(xy 416.780717 -374.083193) (xy 416.806041 -374.100712) (xy 416.835434 -374.109888) (xy 416.866226 -374.109888)
			(xy 416.895619 -374.100712) (xy 416.920943 -374.083193) (xy 416.93084 -374.071388) (xy 416.949005 -374.048883)
			(xy 416.991031 -374.00915) (xy 417.038571 -373.976213) (xy 417.090537 -373.950829) (xy 417.145739 -373.933577)
			(xy 417.202913 -373.924854) (xy 417.23183 -373.924322) (xy 417.259082 -373.92475) (xy 417.313031 -373.93251)
			(xy 417.365326 -373.947869) (xy 417.414903 -373.970514) (xy 417.460754 -373.999983) (xy 417.501943 -374.035678)
			(xy 417.537635 -374.07687) (xy 417.5671 -374.122723) (xy 417.589741 -374.172302) (xy 417.605096 -374.224599)
			(xy 417.612852 -374.278548) (xy 417.612852 -374.333052) (xy 417.605096 -374.387001) (xy 417.589741 -374.439298)
			(xy 417.5671 -374.488877) (xy 417.537635 -374.53473) (xy 417.501943 -374.575922) (xy 417.460754 -374.611617)
			(xy 417.414903 -374.641086) (xy 417.365326 -374.663731) (xy 417.313031 -374.67909) (xy 417.259082 -374.68685)
			(xy 417.23183 -374.687338) (xy 417.202913 -374.686822) (xy 417.14574 -374.678096) (xy 417.09054 -374.660839)
			(xy 417.038578 -374.635447) (xy 416.991045 -374.602502) (xy 416.949029 -374.562759) (xy 416.93084 -374.540272)
			(xy 416.920943 -374.528467) (xy 416.895619 -374.510948) (xy 416.866226 -374.501772) (xy 416.835434 -374.501772)
			(xy 416.806041 -374.510948) (xy 416.780717 -374.528467) (xy 416.77082 -374.540272) (xy 416.752611 -374.56274)
			(xy 416.710596 -374.602478) (xy 416.663065 -374.635419) (xy 416.611107 -374.66081) (xy 416.555912 -374.67807)
			(xy 416.498745 -374.686802) (xy 416.46983 -374.687338) (xy 416.442578 -374.686817) (xy 416.388628 -374.679064)
			(xy 416.336331 -374.663712) (xy 416.286751 -374.641073) (xy 416.240897 -374.611608) (xy 416.199704 -374.575917)
			(xy 416.16401 -374.534727) (xy 416.134542 -374.488876) (xy 416.111899 -374.439298) (xy 416.096542 -374.387001)
			(xy 416.088785 -374.333052) (xy 412.784098 -374.333052) (xy 413.468312 -376.607578) (xy 431.173382 -376.607578)
		)
		(stroke
			(width 0)
			(type solid)
		)
		(fill yes)
		(layer "In4.Cu")
		(net "GND")
	)
	(gr_poly
		(pts
			(xy 41.893998 -440.41187) (xy 41.907479 -440.411415) (xy 41.933484 -440.404282) (xy 41.956717 -440.390594)
			(xy 41.975558 -440.371303) (xy 41.988695 -440.347754) (xy 41.995212 -440.321588) (xy 41.994655 -440.294629)
			(xy 41.99128 -440.281568) (xy 41.984006 -440.255177) (xy 41.97623 -440.20099) (xy 41.975786 -440.173618)
			(xy 41.976272 -440.146367) (xy 41.984028 -440.092419) (xy 41.999383 -440.040124) (xy 42.022025 -439.990547)
			(xy 42.051491 -439.944697) (xy 42.087182 -439.903506) (xy 42.128373 -439.867815) (xy 42.174223 -439.838349)
			(xy 42.2238 -439.815707) (xy 42.276095 -439.800352) (xy 42.330043 -439.792596) (xy 42.384545 -439.792596)
			(xy 42.438493 -439.800352) (xy 42.490788 -439.815707) (xy 42.540365 -439.838349) (xy 42.586215 -439.867815)
			(xy 42.627406 -439.903506) (xy 42.663097 -439.944697) (xy 42.692563 -439.990547) (xy 42.715205 -440.040124)
			(xy 42.73056 -440.092419) (xy 42.738316 -440.146367) (xy 42.738802 -440.173618) (xy 42.738347 -440.200989)
			(xy 42.730569 -440.255174) (xy 42.723308 -440.281568) (xy 42.719892 -440.294625) (xy 42.719308 -440.321597)
			(xy 42.725815 -440.34778) (xy 42.738957 -440.371341) (xy 42.757816 -440.390634) (xy 42.781073 -440.404309)
			(xy 42.807101 -440.411409) (xy 42.82059 -440.41187) (xy 52.97805 -440.41187) (xy 54.258718 -439.131202)
			(xy 54.258718 -437.421782) (xy 54.258299 -437.4083) (xy 54.251235 -437.382277) (xy 54.237605 -437.359011)
			(xy 54.218359 -437.340125) (xy 54.19484 -437.326936) (xy 54.168689 -437.320364) (xy 54.141729 -437.320868)
			(xy 54.12867 -437.324246) (xy 54.102512 -437.331367) (xy 54.048842 -437.339012) (xy 54.021736 -437.339486)
			(xy 53.994483 -437.339025) (xy 53.940531 -437.331273) (xy 53.888232 -437.315921) (xy 53.83865 -437.293282)
			(xy 53.792795 -437.263816) (xy 53.751601 -437.228125) (xy 53.715905 -437.186933) (xy 53.686436 -437.141081)
			(xy 53.663792 -437.091502) (xy 53.648435 -437.039204) (xy 53.640677 -436.985253) (xy 53.640677 -436.930747)
			(xy 53.648435 -436.876796) (xy 53.663792 -436.824498) (xy 53.686436 -436.774919) (xy 53.715905 -436.729067)
			(xy 53.751601 -436.687875) (xy 53.792795 -436.652184) (xy 53.83865 -436.622718) (xy 53.888232 -436.600079)
			(xy 53.940531 -436.584727) (xy 53.994483 -436.576975) (xy 54.021736 -436.57647) (xy 54.048844 -436.576924)
			(xy 54.102516 -436.584569) (xy 54.12867 -436.59171) (xy 54.141728 -436.595083) (xy 54.168683 -436.595588)
			(xy 54.19483 -436.589016) (xy 54.218343 -436.575827) (xy 54.237582 -436.556941) (xy 54.251203 -436.533675)
			(xy 54.258257 -436.507654) (xy 54.258718 -436.494174) (xy 54.258718 -435.580282) (xy 54.229 -435.56682)
			(xy 54.204307 -435.555115) (xy 54.158262 -435.525688) (xy 54.116886 -435.489992) (xy 54.081025 -435.448759)
			(xy 54.051414 -435.402831) (xy 54.028658 -435.353149) (xy 54.013223 -435.300729) (xy 54.005424 -435.246643)
			(xy 54.005422 -435.191997) (xy 54.013215 -435.13791) (xy 54.028645 -435.085488) (xy 54.051395 -435.035803)
			(xy 54.081001 -434.989873) (xy 54.116857 -434.948636) (xy 54.15823 -434.912936) (xy 54.204272 -434.883504)
			(xy 54.229 -434.871876) (xy 54.258718 -434.858414) (xy 54.258718 -431.37328) (xy 53.907436 -431.021998)
			(xy 39.85895 -431.021998) (xy 39.83489 -431.038007) (xy 39.78296 -431.063359) (xy 39.727801 -431.080589)
			(xy 39.670674 -431.089304) (xy 39.612886 -431.089304) (xy 39.555759 -431.080589) (xy 39.5006 -431.063359)
			(xy 39.44867 -431.038007) (xy 39.42461 -431.021998) (xy 34.92627 -431.021998) (xy 33.58261 -429.678338)
			(xy 33.58261 -401.357338) (xy 36.005516 -398.934432) (xy 36.758372 -398.934432) (xy 36.769249 -398.928264)
			(xy 36.791617 -398.917083) (xy 36.803076 -398.91208) (xy 36.812607 -398.907416) (xy 36.827064 -398.891917)
			(xy 36.834029 -398.8719) (xy 36.832314 -398.850774) (xy 36.827714 -398.841214) (xy 36.813208 -398.813122)
			(xy 36.792688 -398.753324) (xy 36.782314 -398.690961) (xy 36.78174 -398.65935) (xy 36.782229 -398.632095)
			(xy 36.78999 -398.578139) (xy 36.805347 -398.525836) (xy 36.827987 -398.476249) (xy 36.857451 -398.430387)
			(xy 36.893139 -398.389182) (xy 36.934325 -398.353472) (xy 36.980171 -398.323984) (xy 37.029746 -398.301317)
			(xy 37.082041 -398.285933) (xy 37.135993 -398.278144) (xy 37.163248 -398.277588) (xy 38.026848 -398.277588)
			(xy 38.05411 -398.278055) (xy 38.108079 -398.285824) (xy 38.160391 -398.301197) (xy 38.209982 -398.323861)
			(xy 38.223802 -398.332749) (xy 47.218606 -398.332749) (xy 47.218606 -398.278251) (xy 47.226362 -398.224307)
			(xy 47.241716 -398.172016) (xy 47.264356 -398.122443) (xy 47.29382 -398.076596) (xy 47.329509 -398.035409)
			(xy 47.370696 -397.99972) (xy 47.416543 -397.970256) (xy 47.466116 -397.947616) (xy 47.518407 -397.932262)
			(xy 47.572351 -397.924506) (xy 47.5996 -397.92402) (xy 47.614652 -397.924192) (xy 47.644659 -397.926606)
			(xy 47.659544 -397.928846) (xy 47.673899 -397.930627) (xy 47.70258 -397.926951) (xy 47.729077 -397.915378)
			(xy 47.751265 -397.896837) (xy 47.76736 -397.872816) (xy 47.776071 -397.845245) (xy 47.776892 -397.830802)
			(xy 47.778042 -397.803997) (xy 47.786888 -397.751081) (xy 47.803056 -397.699925) (xy 47.826229 -397.651537)
			(xy 47.855949 -397.60687) (xy 47.89163 -397.566805) (xy 47.932571 -397.532132) (xy 47.977963 -397.503532)
			(xy 48.026912 -397.481571) (xy 48.078455 -397.466681) (xy 48.131575 -397.459154) (xy 48.1584 -397.458692)
			(xy 48.185651 -397.459178) (xy 48.239599 -397.466934) (xy 48.291894 -397.482289) (xy 48.341471 -397.504931)
			(xy 48.387321 -397.534397) (xy 48.428512 -397.570088) (xy 48.464203 -397.611279) (xy 48.493669 -397.657129)
			(xy 48.516311 -397.706706) (xy 48.531666 -397.759001) (xy 48.539422 -397.812949) (xy 48.539422 -397.867451)
			(xy 48.531666 -397.921399) (xy 48.516311 -397.973694) (xy 48.493669 -398.023271) (xy 48.464203 -398.069121)
			(xy 48.428512 -398.110312) (xy 48.387321 -398.146003) (xy 48.341471 -398.175469) (xy 48.291894 -398.198111)
			(xy 48.239599 -398.213466) (xy 48.185651 -398.221222) (xy 48.1584 -398.221708) (xy 48.143348 -398.221535)
			(xy 48.113341 -398.219122) (xy 48.098456 -398.216882) (xy 48.084096 -398.215171) (xy 48.055429 -398.218844)
			(xy 48.028942 -398.230408) (xy 48.006759 -398.248934) (xy 47.990661 -398.272937) (xy 47.981938 -398.30049)
			(xy 47.981108 -398.314926) (xy 47.979983 -398.341732) (xy 47.971134 -398.394649) (xy 47.954962 -398.445806)
			(xy 47.931786 -398.494194) (xy 47.902063 -398.53886) (xy 47.866379 -398.578924) (xy 47.825437 -398.613598)
			(xy 47.780043 -398.642196) (xy 47.731091 -398.664157) (xy 47.679547 -398.679048) (xy 47.626426 -398.686574)
			(xy 47.5996 -398.687036) (xy 47.572351 -398.686494) (xy 47.518407 -398.678738) (xy 47.466116 -398.663384)
			(xy 47.416543 -398.640744) (xy 47.370696 -398.61128) (xy 47.329509 -398.575591) (xy 47.29382 -398.534404)
			(xy 47.264356 -398.488557) (xy 47.241716 -398.438984) (xy 47.226362 -398.386693) (xy 47.218606 -398.332749)
			(xy 38.223802 -398.332749) (xy 38.255842 -398.353354) (xy 38.297036 -398.389075) (xy 38.332725 -398.430297)
			(xy 38.362182 -398.47618) (xy 38.384807 -398.525788) (xy 38.400139 -398.578113) (xy 38.407866 -398.632087)
			(xy 38.408356 -398.65935) (xy 38.407759 -398.69096) (xy 38.397388 -398.753321) (xy 38.376889 -398.813124)
			(xy 38.362382 -398.841214) (xy 38.357819 -398.85079) (xy 38.356117 -398.871909) (xy 38.363061 -398.891927)
			(xy 38.377478 -398.907454) (xy 38.38702 -398.91208) (xy 38.398486 -398.917068) (xy 38.420854 -398.928252)
			(xy 38.431724 -398.934432) (xy 40.083486 -398.934432) (xy 40.098258 -398.910114) (xy 40.133878 -398.865745)
			(xy 40.175692 -398.827159) (xy 40.222772 -398.79521) (xy 40.274075 -398.770607) (xy 40.328463 -398.753895)
			(xy 40.384729 -398.745446) (xy 40.441627 -398.745446) (xy 40.497893 -398.753895) (xy 40.552281 -398.770607)
			(xy 40.603584 -398.79521) (xy 40.650664 -398.827159) (xy 40.692478 -398.865745) (xy 40.728098 -398.910114)
			(xy 40.74287 -398.934432) (xy 42.006266 -398.934432) (xy 42.020647 -398.933928) (xy 42.048265 -398.925892)
			(xy 42.072548 -398.910475) (xy 42.091571 -398.888901) (xy 42.103826 -398.862878) (xy 42.108341 -398.834471)
			(xy 42.107104 -398.820132) (xy 42.10568 -398.808118) (xy 42.104157 -398.78397) (xy 42.104056 -398.771872)
			(xy 42.104544 -398.744621) (xy 42.112303 -398.690675) (xy 42.12766 -398.638381) (xy 42.150303 -398.588805)
			(xy 42.179769 -398.542956) (xy 42.21546 -398.501766) (xy 42.256649 -398.466074) (xy 42.302498 -398.436606)
			(xy 42.352074 -398.413963) (xy 42.404367 -398.398605) (xy 42.458313 -398.390844) (xy 42.485564 -398.390364)
			(xy 43.349164 -398.390364) (xy 43.376419 -398.390824) (xy 43.430376 -398.398577) (xy 43.482679 -398.41393)
			(xy 43.532266 -398.43657) (xy 43.578126 -398.466036) (xy 43.619325 -398.50173) (xy 43.655025 -398.542923)
			(xy 43.6845 -398.588778) (xy 43.707148 -398.63836) (xy 43.722509 -398.690662) (xy 43.730271 -398.744617)
			(xy 43.730672 -398.771872) (xy 43.730586 -398.78397) (xy 43.729058 -398.808119) (xy 43.727624 -398.820132)
			(xy 43.726323 -398.834466) (xy 43.73084 -398.862879) (xy 43.743106 -398.888903) (xy 43.762145 -398.910471)
			(xy 43.786445 -398.925872) (xy 43.814077 -398.933881) (xy 43.828462 -398.934432) (xy 49.047908 -398.934432)
			(xy 50.065432 -395.26337) (xy 50.065432 -387.886956) (xy 48.60925 -386.430774) (xy 43.248072 -386.430774)
			(xy 43.23282 -386.454092) (xy 43.197036 -386.496803) (xy 43.155853 -386.534334) (xy 43.110013 -386.56601)
			(xy 43.060343 -386.59126) (xy 43.007737 -386.609627) (xy 42.953146 -386.620782) (xy 42.897552 -386.624523)
			(xy 42.841958 -386.620782) (xy 42.787367 -386.609627) (xy 42.734761 -386.59126) (xy 42.685091 -386.56601)
			(xy 42.639251 -386.534334) (xy 42.598068 -386.496803) (xy 42.562284 -386.454092) (xy 42.547032 -386.430774)
			(xy 41.989248 -386.430774) (xy 41.973996 -386.454092) (xy 41.938212 -386.496803) (xy 41.897029 -386.534334)
			(xy 41.851189 -386.56601) (xy 41.801519 -386.59126) (xy 41.748913 -386.609627) (xy 41.694322 -386.620782)
			(xy 41.638728 -386.624523) (xy 41.583134 -386.620782) (xy 41.528543 -386.609627) (xy 41.475937 -386.59126)
			(xy 41.426267 -386.56601) (xy 41.380427 -386.534334) (xy 41.339244 -386.496803) (xy 41.30346 -386.454092)
			(xy 41.288208 -386.430774) (xy 40.646096 -386.430774) (xy 40.633904 -386.46354) (xy 40.623878 -386.48882)
			(xy 40.597695 -386.536484) (xy 40.56501 -386.579948) (xy 40.526485 -386.618331) (xy 40.4829 -386.650855)
			(xy 40.435139 -386.676861) (xy 40.38417 -386.695823) (xy 40.331024 -386.707356) (xy 40.27678 -386.711226)
			(xy 40.222536 -386.707356) (xy 40.16939 -386.695823) (xy 40.118421 -386.676861) (xy 40.07066 -386.650855)
			(xy 40.027075 -386.618331) (xy 39.98855 -386.579948) (xy 39.955865 -386.536484) (xy 39.929682 -386.48882)
			(xy 39.919656 -386.46354) (xy 39.907464 -386.430774) (xy 39.63289 -386.430774) (xy 39.620698 -386.46354)
			(xy 39.610672 -386.48882) (xy 39.584489 -386.536484) (xy 39.551804 -386.579948) (xy 39.513279 -386.618331)
			(xy 39.469694 -386.650855) (xy 39.421933 -386.676861) (xy 39.370964 -386.695823) (xy 39.317818 -386.707356)
			(xy 39.263574 -386.711226) (xy 39.20933 -386.707356) (xy 39.156184 -386.695823) (xy 39.105215 -386.676861)
			(xy 39.057454 -386.650855) (xy 39.013869 -386.618331) (xy 38.975344 -386.579948) (xy 38.942659 -386.536484)
			(xy 38.916476 -386.48882) (xy 38.90645 -386.46354) (xy 38.894258 -386.430774) (xy 30.779466 -386.430774)
			(xy 29.32684 -387.8834) (xy 25.480518 -387.8834) (xy 25.459273 -387.903145) (xy 25.411921 -387.936632)
			(xy 25.360046 -387.962567) (xy 25.304844 -387.980352) (xy 25.276302 -387.985508) (xy 25.260046 -387.988048)
			(xy 25.13584 -388.112508) (xy 25.105001 -388.142679) (xy 25.038905 -388.198136) (xy 24.968227 -388.247622)
			(xy 24.893506 -388.29076) (xy 24.815309 -388.327222) (xy 24.734232 -388.356732) (xy 24.650892 -388.379063)
			(xy 24.565923 -388.394047) (xy 24.479972 -388.401568) (xy 24.436832 -388.402068) (xy 22.28596 -388.402068)
			(xy 22.242818 -388.401613) (xy 22.156861 -388.394097) (xy 22.071886 -388.379118) (xy 21.988541 -388.356788)
			(xy 21.907459 -388.327279) (xy 21.829258 -388.290814) (xy 21.754533 -388.247672) (xy 21.683853 -388.19818)
			(xy 21.617756 -388.142716) (xy 21.586952 -388.112508) (xy 21.358098 -387.8834) (xy 15.621762 -387.8834)
			(xy 14.659864 -388.845298) (xy 14.695932 -388.881366) (xy 14.716868 -388.902983) (xy 14.752351 -388.951585)
			(xy 14.779766 -389.005154) (xy 14.798437 -389.06236) (xy 14.807899 -389.121788) (xy 14.808454 -389.151876)
			(xy 14.80797 -389.17913) (xy 14.800216 -389.233082) (xy 14.784864 -389.285383) (xy 14.762225 -389.334966)
			(xy 14.73276 -389.380822) (xy 14.697069 -389.422019) (xy 14.655879 -389.457718) (xy 14.610027 -389.487191)
			(xy 14.560448 -389.509839) (xy 14.508151 -389.525201) (xy 14.454199 -389.532965) (xy 14.426946 -389.533384)
			(xy 14.396856 -389.532821) (xy 14.337423 -389.523378) (xy 14.28021 -389.504717) (xy 14.226638 -389.477304)
			(xy 14.178036 -389.441817) (xy 14.156436 -389.420862) (xy 14.120368 -389.384794) (xy 13.132816 -390.372346)
			(xy 20.201634 -390.372346) (xy 20.205705 -390.316724) (xy 20.217831 -390.262287) (xy 20.237754 -390.210196)
			(xy 20.26505 -390.161561) (xy 20.299136 -390.117418) (xy 20.339285 -390.078709) (xy 20.384643 -390.046258)
			(xy 20.434243 -390.020757) (xy 20.487027 -390.00275) (xy 20.54187 -389.99262) (xy 20.597604 -389.990583)
			(xy 20.653041 -389.996683) (xy 20.706998 -390.010789) (xy 20.758327 -390.032601) (xy 20.805933 -390.061655)
			(xy 20.848801 -390.09733) (xy 20.886018 -390.138867) (xy 20.916791 -390.18538) (xy 20.940463 -390.235877)
			(xy 20.956531 -390.289284) (xy 20.957354 -390.294876) (xy 28.256228 -390.294876) (xy 28.260299 -390.239254)
			(xy 28.272425 -390.184817) (xy 28.292348 -390.132726) (xy 28.319644 -390.084091) (xy 28.35373 -390.039948)
			(xy 28.393879 -390.001239) (xy 28.439237 -389.968788) (xy 28.488837 -389.943287) (xy 28.541621 -389.92528)
			(xy 28.596464 -389.91515) (xy 28.652198 -389.913113) (xy 28.707635 -389.919213) (xy 28.761592 -389.933319)
			(xy 28.812921 -389.955131) (xy 28.860527 -389.984185) (xy 28.903395 -390.01986) (xy 28.940612 -390.061397)
			(xy 28.970895 -390.10717) (xy 31.968946 -390.10717) (xy 31.973017 -390.051548) (xy 31.985143 -389.997111)
			(xy 32.005066 -389.94502) (xy 32.032362 -389.896385) (xy 32.066448 -389.852242) (xy 32.106597 -389.813533)
			(xy 32.151955 -389.781082) (xy 32.201555 -389.755581) (xy 32.254339 -389.737574) (xy 32.309182 -389.727444)
			(xy 32.364916 -389.725407) (xy 32.420353 -389.731507) (xy 32.47431 -389.745613) (xy 32.525639 -389.767425)
			(xy 32.573245 -389.796479) (xy 32.616113 -389.832154) (xy 32.65333 -389.873691) (xy 32.684103 -389.920204)
			(xy 32.707775 -389.970701) (xy 32.718801 -390.007348) (xy 46.835312 -390.007348) (xy 46.839383 -389.951726)
			(xy 46.851509 -389.897289) (xy 46.871432 -389.845198) (xy 46.898728 -389.796563) (xy 46.932814 -389.75242)
			(xy 46.972963 -389.713711) (xy 47.018321 -389.68126) (xy 47.067921 -389.655759) (xy 47.120705 -389.637752)
			(xy 47.175548 -389.627622) (xy 47.231282 -389.625585) (xy 47.286719 -389.631685) (xy 47.340676 -389.645791)
			(xy 47.392005 -389.667603) (xy 47.439611 -389.696657) (xy 47.482479 -389.732332) (xy 47.519696 -389.773869)
			(xy 47.550469 -389.820382) (xy 47.574141 -389.870879) (xy 47.590209 -389.924286) (xy 47.598329 -389.979462)
			(xy 47.598838 -390.007348) (xy 47.598329 -390.035234) (xy 47.590209 -390.09041) (xy 47.574141 -390.143817)
			(xy 47.550469 -390.194314) (xy 47.519696 -390.240827) (xy 47.482479 -390.282364) (xy 47.439611 -390.318039)
			(xy 47.392005 -390.347093) (xy 47.340676 -390.368905) (xy 47.286719 -390.383011) (xy 47.231282 -390.389111)
			(xy 47.175548 -390.387074) (xy 47.120705 -390.376944) (xy 47.067921 -390.358937) (xy 47.018321 -390.333436)
			(xy 46.972963 -390.300985) (xy 46.932814 -390.262276) (xy 46.898728 -390.218133) (xy 46.871432 -390.169498)
			(xy 46.851509 -390.117407) (xy 46.839383 -390.06297) (xy 46.835312 -390.007348) (xy 32.718801 -390.007348)
			(xy 32.723843 -390.024108) (xy 32.731963 -390.079284) (xy 32.732472 -390.10717) (xy 32.731963 -390.135056)
			(xy 32.723843 -390.190232) (xy 32.707775 -390.243639) (xy 32.684103 -390.294136) (xy 32.65333 -390.340649)
			(xy 32.616113 -390.382186) (xy 32.573245 -390.417861) (xy 32.525639 -390.446915) (xy 32.47431 -390.468727)
			(xy 32.420353 -390.482833) (xy 32.364916 -390.488933) (xy 32.309182 -390.486896) (xy 32.254339 -390.476766)
			(xy 32.201555 -390.458759) (xy 32.151955 -390.433258) (xy 32.106597 -390.400807) (xy 32.066448 -390.362098)
			(xy 32.032362 -390.317955) (xy 32.005066 -390.26932) (xy 31.985143 -390.217229) (xy 31.973017 -390.162792)
			(xy 31.968946 -390.10717) (xy 28.970895 -390.10717) (xy 28.971385 -390.10791) (xy 28.995057 -390.158407)
			(xy 29.011125 -390.211814) (xy 29.019245 -390.26699) (xy 29.019754 -390.294876) (xy 29.019245 -390.322762)
			(xy 29.011125 -390.377938) (xy 28.995057 -390.431345) (xy 28.971385 -390.481842) (xy 28.940612 -390.528355)
			(xy 28.903395 -390.569892) (xy 28.860527 -390.605567) (xy 28.812921 -390.634621) (xy 28.761592 -390.656433)
			(xy 28.707635 -390.670539) (xy 28.652198 -390.676639) (xy 28.596464 -390.674602) (xy 28.541621 -390.664472)
			(xy 28.488837 -390.646465) (xy 28.439237 -390.620964) (xy 28.393879 -390.588513) (xy 28.35373 -390.549804)
			(xy 28.319644 -390.505661) (xy 28.292348 -390.457026) (xy 28.272425 -390.404935) (xy 28.260299 -390.350498)
			(xy 28.256228 -390.294876) (xy 20.957354 -390.294876) (xy 20.964651 -390.34446) (xy 20.96516 -390.372346)
			(xy 20.964651 -390.400232) (xy 20.956531 -390.455408) (xy 20.940463 -390.508815) (xy 20.916791 -390.559312)
			(xy 20.886018 -390.605825) (xy 20.848801 -390.647362) (xy 20.805933 -390.683037) (xy 20.758327 -390.712091)
			(xy 20.706998 -390.733903) (xy 20.653041 -390.748009) (xy 20.597604 -390.754109) (xy 20.54187 -390.752072)
			(xy 20.487027 -390.741942) (xy 20.434243 -390.723935) (xy 20.384643 -390.698434) (xy 20.339285 -390.665983)
			(xy 20.299136 -390.627274) (xy 20.26505 -390.583131) (xy 20.237754 -390.534496) (xy 20.217831 -390.482405)
			(xy 20.205705 -390.427968) (xy 20.201634 -390.372346) (xy 13.132816 -390.372346) (xy 12.497816 -391.007346)
			(xy 22.868634 -391.007346) (xy 22.872705 -390.951724) (xy 22.884831 -390.897287) (xy 22.904754 -390.845196)
			(xy 22.93205 -390.796561) (xy 22.966136 -390.752418) (xy 23.006285 -390.713709) (xy 23.051643 -390.681258)
			(xy 23.101243 -390.655757) (xy 23.154027 -390.63775) (xy 23.20887 -390.62762) (xy 23.264604 -390.625583)
			(xy 23.320041 -390.631683) (xy 23.373998 -390.645789) (xy 23.425327 -390.667601) (xy 23.472933 -390.696655)
			(xy 23.515801 -390.73233) (xy 23.553018 -390.773867) (xy 23.583791 -390.82038) (xy 23.607463 -390.870877)
			(xy 23.623531 -390.924284) (xy 23.631651 -390.97946) (xy 23.63216 -391.007346) (xy 23.631651 -391.035232)
			(xy 23.623531 -391.090408) (xy 23.607463 -391.143815) (xy 23.583791 -391.194312) (xy 23.553018 -391.240825)
			(xy 23.515801 -391.282362) (xy 23.481538 -391.310876) (xy 28.256228 -391.310876) (xy 28.260299 -391.255254)
			(xy 28.272425 -391.200817) (xy 28.292348 -391.148726) (xy 28.319644 -391.100091) (xy 28.35373 -391.055948)
			(xy 28.393879 -391.017239) (xy 28.439237 -390.984788) (xy 28.488837 -390.959287) (xy 28.541621 -390.94128)
			(xy 28.596464 -390.93115) (xy 28.652198 -390.929113) (xy 28.707635 -390.935213) (xy 28.761592 -390.949319)
			(xy 28.812921 -390.971131) (xy 28.860527 -391.000185) (xy 28.903395 -391.03586) (xy 28.940612 -391.077397)
			(xy 28.971385 -391.12391) (xy 28.995057 -391.174407) (xy 29.011125 -391.227814) (xy 29.019245 -391.28299)
			(xy 29.019754 -391.310876) (xy 29.019245 -391.338762) (xy 29.011125 -391.393938) (xy 28.995057 -391.447345)
			(xy 28.971385 -391.497842) (xy 28.940612 -391.544355) (xy 28.903395 -391.585892) (xy 28.860527 -391.621567)
			(xy 28.836885 -391.635996) (xy 31.968946 -391.635996) (xy 31.973017 -391.580374) (xy 31.985143 -391.525937)
			(xy 32.005066 -391.473846) (xy 32.032362 -391.425211) (xy 32.066448 -391.381068) (xy 32.106597 -391.342359)
			(xy 32.151955 -391.309908) (xy 32.201555 -391.284407) (xy 32.254339 -391.2664) (xy 32.309182 -391.25627)
			(xy 32.364916 -391.254233) (xy 32.420353 -391.260333) (xy 32.47431 -391.274439) (xy 32.525639 -391.296251)
			(xy 32.573245 -391.325305) (xy 32.616113 -391.36098) (xy 32.65333 -391.402517) (xy 32.654373 -391.404094)
			(xy 38.548816 -391.404094) (xy 38.552887 -391.348472) (xy 38.565013 -391.294035) (xy 38.584936 -391.241944)
			(xy 38.612232 -391.193309) (xy 38.646318 -391.149166) (xy 38.686467 -391.110457) (xy 38.731825 -391.078006)
			(xy 38.781425 -391.052505) (xy 38.834209 -391.034498) (xy 38.889052 -391.024368) (xy 38.944786 -391.022331)
			(xy 39.000223 -391.028431) (xy 39.05418 -391.042537) (xy 39.105509 -391.064349) (xy 39.153115 -391.093403)
			(xy 39.195983 -391.129078) (xy 39.2332 -391.170615) (xy 39.263973 -391.217128) (xy 39.287645 -391.267625)
			(xy 39.303713 -391.321032) (xy 39.311833 -391.376208) (xy 39.311864 -391.377932) (xy 40.593516 -391.377932)
			(xy 40.597587 -391.32231) (xy 40.609713 -391.267873) (xy 40.629636 -391.215782) (xy 40.656932 -391.167147)
			(xy 40.691018 -391.123004) (xy 40.731167 -391.084295) (xy 40.776525 -391.051844) (xy 40.826125 -391.026343)
			(xy 40.878909 -391.008336) (xy 40.933752 -390.998206) (xy 40.989486 -390.996169) (xy 41.044923 -391.002269)
			(xy 41.09888 -391.016375) (xy 41.150209 -391.038187) (xy 41.197815 -391.067241) (xy 41.224733 -391.089642)
			(xy 46.835312 -391.089642) (xy 46.839383 -391.03402) (xy 46.851509 -390.979583) (xy 46.871432 -390.927492)
			(xy 46.898728 -390.878857) (xy 46.932814 -390.834714) (xy 46.972963 -390.796005) (xy 47.018321 -390.763554)
			(xy 47.067921 -390.738053) (xy 47.120705 -390.720046) (xy 47.175548 -390.709916) (xy 47.231282 -390.707879)
			(xy 47.286719 -390.713979) (xy 47.340676 -390.728085) (xy 47.392005 -390.749897) (xy 47.439611 -390.778951)
			(xy 47.482479 -390.814626) (xy 47.519696 -390.856163) (xy 47.550469 -390.902676) (xy 47.574141 -390.953173)
			(xy 47.590209 -391.00658) (xy 47.598329 -391.061756) (xy 47.598838 -391.089642) (xy 47.598329 -391.117528)
			(xy 47.590209 -391.172704) (xy 47.574141 -391.226111) (xy 47.550469 -391.276608) (xy 47.519696 -391.323121)
			(xy 47.482479 -391.364658) (xy 47.439611 -391.400333) (xy 47.392005 -391.429387) (xy 47.340676 -391.451199)
			(xy 47.286719 -391.465305) (xy 47.231282 -391.471405) (xy 47.175548 -391.469368) (xy 47.120705 -391.459238)
			(xy 47.067921 -391.441231) (xy 47.018321 -391.41573) (xy 46.972963 -391.383279) (xy 46.932814 -391.34457)
			(xy 46.898728 -391.300427) (xy 46.871432 -391.251792) (xy 46.851509 -391.199701) (xy 46.839383 -391.145264)
			(xy 46.835312 -391.089642) (xy 41.224733 -391.089642) (xy 41.240683 -391.102916) (xy 41.2779 -391.144453)
			(xy 41.308673 -391.190966) (xy 41.332345 -391.241463) (xy 41.348413 -391.29487) (xy 41.356533 -391.350046)
			(xy 41.357042 -391.377932) (xy 41.356533 -391.405818) (xy 41.348413 -391.460994) (xy 41.332345 -391.514401)
			(xy 41.308673 -391.564898) (xy 41.2779 -391.611411) (xy 41.240683 -391.652948) (xy 41.197815 -391.688623)
			(xy 41.150209 -391.717677) (xy 41.09888 -391.739489) (xy 41.044923 -391.753595) (xy 40.989486 -391.759695)
			(xy 40.933752 -391.757658) (xy 40.878909 -391.747528) (xy 40.826125 -391.729521) (xy 40.776525 -391.70402)
			(xy 40.731167 -391.671569) (xy 40.691018 -391.63286) (xy 40.656932 -391.588717) (xy 40.629636 -391.540082)
			(xy 40.609713 -391.487991) (xy 40.597587 -391.433554) (xy 40.593516 -391.377932) (xy 39.311864 -391.377932)
			(xy 39.312342 -391.404094) (xy 39.311833 -391.43198) (xy 39.303713 -391.487156) (xy 39.287645 -391.540563)
			(xy 39.263973 -391.59106) (xy 39.2332 -391.637573) (xy 39.195983 -391.67911) (xy 39.153115 -391.714785)
			(xy 39.105509 -391.743839) (xy 39.05418 -391.765651) (xy 39.000223 -391.779757) (xy 38.944786 -391.785857)
			(xy 38.889052 -391.78382) (xy 38.834209 -391.77369) (xy 38.781425 -391.755683) (xy 38.731825 -391.730182)
			(xy 38.686467 -391.697731) (xy 38.646318 -391.659022) (xy 38.612232 -391.614879) (xy 38.584936 -391.566244)
			(xy 38.565013 -391.514153) (xy 38.552887 -391.459716) (xy 38.548816 -391.404094) (xy 32.654373 -391.404094)
			(xy 32.684103 -391.44903) (xy 32.707775 -391.499527) (xy 32.723843 -391.552934) (xy 32.731963 -391.60811)
			(xy 32.732472 -391.635996) (xy 32.731963 -391.663882) (xy 32.723843 -391.719058) (xy 32.707775 -391.772465)
			(xy 32.684103 -391.822962) (xy 32.65333 -391.869475) (xy 32.616113 -391.911012) (xy 32.573245 -391.946687)
			(xy 32.525639 -391.975741) (xy 32.47431 -391.997553) (xy 32.420353 -392.011659) (xy 32.364916 -392.017759)
			(xy 32.309182 -392.015722) (xy 32.254339 -392.005592) (xy 32.201555 -391.987585) (xy 32.151955 -391.962084)
			(xy 32.106597 -391.929633) (xy 32.066448 -391.890924) (xy 32.032362 -391.846781) (xy 32.005066 -391.798146)
			(xy 31.985143 -391.746055) (xy 31.973017 -391.691618) (xy 31.968946 -391.635996) (xy 28.836885 -391.635996)
			(xy 28.812921 -391.650621) (xy 28.761592 -391.672433) (xy 28.707635 -391.686539) (xy 28.652198 -391.692639)
			(xy 28.596464 -391.690602) (xy 28.541621 -391.680472) (xy 28.488837 -391.662465) (xy 28.439237 -391.636964)
			(xy 28.393879 -391.604513) (xy 28.35373 -391.565804) (xy 28.319644 -391.521661) (xy 28.292348 -391.473026)
			(xy 28.272425 -391.420935) (xy 28.260299 -391.366498) (xy 28.256228 -391.310876) (xy 23.481538 -391.310876)
			(xy 23.472933 -391.318037) (xy 23.425327 -391.347091) (xy 23.373998 -391.368903) (xy 23.320041 -391.383009)
			(xy 23.264604 -391.389109) (xy 23.20887 -391.387072) (xy 23.154027 -391.376942) (xy 23.101243 -391.358935)
			(xy 23.051643 -391.333434) (xy 23.006285 -391.300983) (xy 22.966136 -391.262274) (xy 22.93205 -391.218131)
			(xy 22.904754 -391.169496) (xy 22.884831 -391.117405) (xy 22.872705 -391.062968) (xy 22.868634 -391.007346)
			(xy 12.497816 -391.007346) (xy 11.305286 -392.199876) (xy 14.044928 -392.199876) (xy 14.048999 -392.144254)
			(xy 14.061125 -392.089817) (xy 14.081048 -392.037726) (xy 14.108344 -391.989091) (xy 14.14243 -391.944948)
			(xy 14.182579 -391.906239) (xy 14.227937 -391.873788) (xy 14.277537 -391.848287) (xy 14.330321 -391.83028)
			(xy 14.385164 -391.82015) (xy 14.440898 -391.818113) (xy 14.496335 -391.824213) (xy 14.550292 -391.838319)
			(xy 14.601621 -391.860131) (xy 14.649227 -391.889185) (xy 14.692095 -391.92486) (xy 14.729312 -391.966397)
			(xy 14.760085 -392.01291) (xy 14.783757 -392.063407) (xy 14.799825 -392.116814) (xy 14.807945 -392.17199)
			(xy 14.808454 -392.199876) (xy 14.807945 -392.227762) (xy 14.799825 -392.282938) (xy 14.786606 -392.326876)
			(xy 28.256228 -392.326876) (xy 28.260299 -392.271254) (xy 28.272425 -392.216817) (xy 28.292348 -392.164726)
			(xy 28.319644 -392.116091) (xy 28.35373 -392.071948) (xy 28.393879 -392.033239) (xy 28.439237 -392.000788)
			(xy 28.488837 -391.975287) (xy 28.541621 -391.95728) (xy 28.596464 -391.94715) (xy 28.652198 -391.945113)
			(xy 28.707635 -391.951213) (xy 28.761592 -391.965319) (xy 28.812921 -391.987131) (xy 28.860527 -392.016185)
			(xy 28.903395 -392.05186) (xy 28.940612 -392.093397) (xy 28.971385 -392.13991) (xy 28.991756 -392.183366)
			(xy 46.835312 -392.183366) (xy 46.839383 -392.127744) (xy 46.851509 -392.073307) (xy 46.871432 -392.021216)
			(xy 46.898728 -391.972581) (xy 46.932814 -391.928438) (xy 46.972963 -391.889729) (xy 47.018321 -391.857278)
			(xy 47.067921 -391.831777) (xy 47.120705 -391.81377) (xy 47.175548 -391.80364) (xy 47.231282 -391.801603)
			(xy 47.286719 -391.807703) (xy 47.340676 -391.821809) (xy 47.392005 -391.843621) (xy 47.439611 -391.872675)
			(xy 47.482479 -391.90835) (xy 47.519696 -391.949887) (xy 47.550469 -391.9964) (xy 47.574141 -392.046897)
			(xy 47.590209 -392.100304) (xy 47.598329 -392.15548) (xy 47.598838 -392.183366) (xy 47.598329 -392.211252)
			(xy 47.590209 -392.266428) (xy 47.574141 -392.319835) (xy 47.550469 -392.370332) (xy 47.519696 -392.416845)
			(xy 47.482479 -392.458382) (xy 47.439611 -392.494057) (xy 47.392005 -392.523111) (xy 47.340676 -392.544923)
			(xy 47.286719 -392.559029) (xy 47.231282 -392.565129) (xy 47.175548 -392.563092) (xy 47.120705 -392.552962)
			(xy 47.067921 -392.534955) (xy 47.018321 -392.509454) (xy 46.972963 -392.477003) (xy 46.932814 -392.438294)
			(xy 46.898728 -392.394151) (xy 46.871432 -392.345516) (xy 46.851509 -392.293425) (xy 46.839383 -392.238988)
			(xy 46.835312 -392.183366) (xy 28.991756 -392.183366) (xy 28.995057 -392.190407) (xy 29.011125 -392.243814)
			(xy 29.019245 -392.29899) (xy 29.019754 -392.326876) (xy 29.019245 -392.354762) (xy 29.011125 -392.409938)
			(xy 28.995057 -392.463345) (xy 28.971385 -392.513842) (xy 28.940612 -392.560355) (xy 28.903395 -392.601892)
			(xy 28.860527 -392.637567) (xy 28.812921 -392.666621) (xy 28.761592 -392.688433) (xy 28.707635 -392.702539)
			(xy 28.652198 -392.708639) (xy 28.596464 -392.706602) (xy 28.541621 -392.696472) (xy 28.488837 -392.678465)
			(xy 28.439237 -392.652964) (xy 28.393879 -392.620513) (xy 28.35373 -392.581804) (xy 28.319644 -392.537661)
			(xy 28.292348 -392.489026) (xy 28.272425 -392.436935) (xy 28.260299 -392.382498) (xy 28.256228 -392.326876)
			(xy 14.786606 -392.326876) (xy 14.783757 -392.336345) (xy 14.760085 -392.386842) (xy 14.729312 -392.433355)
			(xy 14.692095 -392.474892) (xy 14.649227 -392.510567) (xy 14.601621 -392.539621) (xy 14.550292 -392.561433)
			(xy 14.496335 -392.575539) (xy 14.440898 -392.581639) (xy 14.385164 -392.579602) (xy 14.330321 -392.569472)
			(xy 14.277537 -392.551465) (xy 14.227937 -392.525964) (xy 14.182579 -392.493513) (xy 14.14243 -392.454804)
			(xy 14.108344 -392.410661) (xy 14.081048 -392.362026) (xy 14.061125 -392.309935) (xy 14.048999 -392.255498)
			(xy 14.044928 -392.199876) (xy 11.305286 -392.199876) (xy 11.048492 -392.45667) (xy 11.048492 -393.215876)
			(xy 14.044928 -393.215876) (xy 14.048999 -393.160254) (xy 14.061125 -393.105817) (xy 14.081048 -393.053726)
			(xy 14.108344 -393.005091) (xy 14.14243 -392.960948) (xy 14.182579 -392.922239) (xy 14.227937 -392.889788)
			(xy 14.277537 -392.864287) (xy 14.330321 -392.84628) (xy 14.385164 -392.83615) (xy 14.440898 -392.834113)
			(xy 14.496335 -392.840213) (xy 14.550292 -392.854319) (xy 14.601621 -392.876131) (xy 14.649227 -392.905185)
			(xy 14.692095 -392.94086) (xy 14.729312 -392.982397) (xy 14.760085 -393.02891) (xy 14.783757 -393.079407)
			(xy 14.799825 -393.132814) (xy 14.807945 -393.18799) (xy 14.808454 -393.215876) (xy 14.807945 -393.243762)
			(xy 14.799825 -393.298938) (xy 14.783757 -393.352345) (xy 14.760085 -393.402842) (xy 14.729312 -393.449355)
			(xy 14.692095 -393.490892) (xy 14.649227 -393.526567) (xy 14.601621 -393.555621) (xy 14.550292 -393.577433)
			(xy 14.496335 -393.591539) (xy 14.440898 -393.597639) (xy 14.385164 -393.595602) (xy 14.330321 -393.585472)
			(xy 14.277537 -393.567465) (xy 14.227937 -393.541964) (xy 14.182579 -393.509513) (xy 14.14243 -393.470804)
			(xy 14.108344 -393.426661) (xy 14.081048 -393.378026) (xy 14.061125 -393.325935) (xy 14.048999 -393.271498)
			(xy 14.044928 -393.215876) (xy 11.048492 -393.215876) (xy 11.048492 -393.615926) (xy 18.102578 -393.615926)
			(xy 18.106649 -393.560304) (xy 18.118775 -393.505867) (xy 18.138698 -393.453776) (xy 18.165994 -393.405141)
			(xy 18.20008 -393.360998) (xy 18.240229 -393.322289) (xy 18.285587 -393.289838) (xy 18.335187 -393.264337)
			(xy 18.387971 -393.24633) (xy 18.442814 -393.2362) (xy 18.498548 -393.234163) (xy 18.553985 -393.240263)
			(xy 18.607942 -393.254369) (xy 18.659271 -393.276181) (xy 18.706877 -393.305235) (xy 18.749745 -393.34091)
			(xy 18.751507 -393.342876) (xy 28.256228 -393.342876) (xy 28.260299 -393.287254) (xy 28.272425 -393.232817)
			(xy 28.292348 -393.180726) (xy 28.319644 -393.132091) (xy 28.35373 -393.087948) (xy 28.393879 -393.049239)
			(xy 28.439237 -393.016788) (xy 28.488837 -392.991287) (xy 28.541621 -392.97328) (xy 28.596464 -392.96315)
			(xy 28.652198 -392.961113) (xy 28.707635 -392.967213) (xy 28.761592 -392.981319) (xy 28.812921 -393.003131)
			(xy 28.860527 -393.032185) (xy 28.903395 -393.06786) (xy 28.940612 -393.109397) (xy 28.971385 -393.15591)
			(xy 28.980564 -393.17549) (xy 31.968946 -393.17549) (xy 31.973017 -393.119868) (xy 31.985143 -393.065431)
			(xy 32.005066 -393.01334) (xy 32.032362 -392.964705) (xy 32.066448 -392.920562) (xy 32.106597 -392.881853)
			(xy 32.151955 -392.849402) (xy 32.201555 -392.823901) (xy 32.254339 -392.805894) (xy 32.309182 -392.795764)
			(xy 32.364916 -392.793727) (xy 32.420353 -392.799827) (xy 32.47431 -392.813933) (xy 32.525639 -392.835745)
			(xy 32.573245 -392.864799) (xy 32.616113 -392.900474) (xy 32.65333 -392.942011) (xy 32.684103 -392.988524)
			(xy 32.707775 -393.039021) (xy 32.723843 -393.092428) (xy 32.731963 -393.147604) (xy 32.732472 -393.17549)
			(xy 32.731963 -393.203376) (xy 32.723843 -393.258552) (xy 32.707775 -393.311959) (xy 32.684103 -393.362456)
			(xy 32.65333 -393.408969) (xy 32.616113 -393.450506) (xy 32.611761 -393.454128) (xy 38.515034 -393.454128)
			(xy 38.519105 -393.398506) (xy 38.531231 -393.344069) (xy 38.551154 -393.291978) (xy 38.57845 -393.243343)
			(xy 38.612536 -393.1992) (xy 38.652685 -393.160491) (xy 38.698043 -393.12804) (xy 38.747643 -393.102539)
			(xy 38.800427 -393.084532) (xy 38.85527 -393.074402) (xy 38.911004 -393.072365) (xy 38.966441 -393.078465)
			(xy 39.020398 -393.092571) (xy 39.071727 -393.114383) (xy 39.119333 -393.143437) (xy 39.162201 -393.179112)
			(xy 39.199418 -393.220649) (xy 39.230191 -393.267162) (xy 39.253863 -393.317659) (xy 39.269931 -393.371066)
			(xy 39.278051 -393.426242) (xy 39.27856 -393.454128) (xy 39.27837 -393.464542) (xy 40.606978 -393.464542)
			(xy 40.611049 -393.40892) (xy 40.623175 -393.354483) (xy 40.643098 -393.302392) (xy 40.670394 -393.253757)
			(xy 40.70448 -393.209614) (xy 40.744629 -393.170905) (xy 40.789987 -393.138454) (xy 40.839587 -393.112953)
			(xy 40.892371 -393.094946) (xy 40.947214 -393.084816) (xy 41.002948 -393.082779) (xy 41.058385 -393.088879)
			(xy 41.112342 -393.102985) (xy 41.163671 -393.124797) (xy 41.211277 -393.153851) (xy 41.254145 -393.189526)
			(xy 41.291362 -393.231063) (xy 41.322135 -393.277576) (xy 41.340006 -393.315698) (xy 46.835312 -393.315698)
			(xy 46.839383 -393.260076) (xy 46.851509 -393.205639) (xy 46.871432 -393.153548) (xy 46.898728 -393.104913)
			(xy 46.932814 -393.06077) (xy 46.972963 -393.022061) (xy 47.018321 -392.98961) (xy 47.067921 -392.964109)
			(xy 47.120705 -392.946102) (xy 47.175548 -392.935972) (xy 47.231282 -392.933935) (xy 47.286719 -392.940035)
			(xy 47.340676 -392.954141) (xy 47.392005 -392.975953) (xy 47.439611 -393.005007) (xy 47.482479 -393.040682)
			(xy 47.519696 -393.082219) (xy 47.550469 -393.128732) (xy 47.574141 -393.179229) (xy 47.590209 -393.232636)
			(xy 47.598329 -393.287812) (xy 47.598838 -393.315698) (xy 47.598329 -393.343584) (xy 47.590209 -393.39876)
			(xy 47.574141 -393.452167) (xy 47.550469 -393.502664) (xy 47.519696 -393.549177) (xy 47.482479 -393.590714)
			(xy 47.439611 -393.626389) (xy 47.392005 -393.655443) (xy 47.340676 -393.677255) (xy 47.286719 -393.691361)
			(xy 47.231282 -393.697461) (xy 47.175548 -393.695424) (xy 47.120705 -393.685294) (xy 47.067921 -393.667287)
			(xy 47.018321 -393.641786) (xy 46.972963 -393.609335) (xy 46.932814 -393.570626) (xy 46.898728 -393.526483)
			(xy 46.871432 -393.477848) (xy 46.851509 -393.425757) (xy 46.839383 -393.37132) (xy 46.835312 -393.315698)
			(xy 41.340006 -393.315698) (xy 41.345807 -393.328073) (xy 41.361875 -393.38148) (xy 41.369995 -393.436656)
			(xy 41.370504 -393.464542) (xy 41.369995 -393.492428) (xy 41.361875 -393.547604) (xy 41.345807 -393.601011)
			(xy 41.322135 -393.651508) (xy 41.291362 -393.698021) (xy 41.254145 -393.739558) (xy 41.211277 -393.775233)
			(xy 41.163671 -393.804287) (xy 41.112342 -393.826099) (xy 41.058385 -393.840205) (xy 41.002948 -393.846305)
			(xy 40.947214 -393.844268) (xy 40.892371 -393.834138) (xy 40.839587 -393.816131) (xy 40.789987 -393.79063)
			(xy 40.744629 -393.758179) (xy 40.70448 -393.71947) (xy 40.670394 -393.675327) (xy 40.643098 -393.626692)
			(xy 40.623175 -393.574601) (xy 40.611049 -393.520164) (xy 40.606978 -393.464542) (xy 39.27837 -393.464542)
			(xy 39.278051 -393.482014) (xy 39.269931 -393.53719) (xy 39.253863 -393.590597) (xy 39.230191 -393.641094)
			(xy 39.199418 -393.687607) (xy 39.162201 -393.729144) (xy 39.119333 -393.764819) (xy 39.071727 -393.793873)
			(xy 39.020398 -393.815685) (xy 38.966441 -393.829791) (xy 38.911004 -393.835891) (xy 38.85527 -393.833854)
			(xy 38.800427 -393.823724) (xy 38.747643 -393.805717) (xy 38.698043 -393.780216) (xy 38.652685 -393.747765)
			(xy 38.612536 -393.709056) (xy 38.57845 -393.664913) (xy 38.551154 -393.616278) (xy 38.531231 -393.564187)
			(xy 38.519105 -393.50975) (xy 38.515034 -393.454128) (xy 32.611761 -393.454128) (xy 32.573245 -393.486181)
			(xy 32.525639 -393.515235) (xy 32.47431 -393.537047) (xy 32.420353 -393.551153) (xy 32.364916 -393.557253)
			(xy 32.309182 -393.555216) (xy 32.254339 -393.545086) (xy 32.201555 -393.527079) (xy 32.151955 -393.501578)
			(xy 32.106597 -393.469127) (xy 32.066448 -393.430418) (xy 32.032362 -393.386275) (xy 32.005066 -393.33764)
			(xy 31.985143 -393.285549) (xy 31.973017 -393.231112) (xy 31.968946 -393.17549) (xy 28.980564 -393.17549)
			(xy 28.995057 -393.206407) (xy 29.011125 -393.259814) (xy 29.019245 -393.31499) (xy 29.019754 -393.342876)
			(xy 29.019245 -393.370762) (xy 29.011125 -393.425938) (xy 28.995057 -393.479345) (xy 28.971385 -393.529842)
			(xy 28.940612 -393.576355) (xy 28.903395 -393.617892) (xy 28.860527 -393.653567) (xy 28.812921 -393.682621)
			(xy 28.761592 -393.704433) (xy 28.707635 -393.718539) (xy 28.652198 -393.724639) (xy 28.596464 -393.722602)
			(xy 28.541621 -393.712472) (xy 28.488837 -393.694465) (xy 28.439237 -393.668964) (xy 28.393879 -393.636513)
			(xy 28.35373 -393.597804) (xy 28.319644 -393.553661) (xy 28.292348 -393.505026) (xy 28.272425 -393.452935)
			(xy 28.260299 -393.398498) (xy 28.256228 -393.342876) (xy 18.751507 -393.342876) (xy 18.786962 -393.382447)
			(xy 18.817735 -393.42896) (xy 18.841407 -393.479457) (xy 18.857475 -393.532864) (xy 18.865595 -393.58804)
			(xy 18.866104 -393.615926) (xy 18.865595 -393.643812) (xy 18.857475 -393.698988) (xy 18.841407 -393.752395)
			(xy 18.817735 -393.802892) (xy 18.786962 -393.849405) (xy 18.749745 -393.890942) (xy 18.706877 -393.926617)
			(xy 18.659271 -393.955671) (xy 18.607942 -393.977483) (xy 18.553985 -393.991589) (xy 18.498548 -393.997689)
			(xy 18.442814 -393.995652) (xy 18.387971 -393.985522) (xy 18.335187 -393.967515) (xy 18.285587 -393.942014)
			(xy 18.240229 -393.909563) (xy 18.20008 -393.870854) (xy 18.165994 -393.826711) (xy 18.138698 -393.778076)
			(xy 18.118775 -393.725985) (xy 18.106649 -393.671548) (xy 18.102578 -393.615926) (xy 11.048492 -393.615926)
			(xy 11.048492 -394.231876) (xy 14.044928 -394.231876) (xy 14.048999 -394.176254) (xy 14.061125 -394.121817)
			(xy 14.081048 -394.069726) (xy 14.108344 -394.021091) (xy 14.14243 -393.976948) (xy 14.182579 -393.938239)
			(xy 14.227937 -393.905788) (xy 14.277537 -393.880287) (xy 14.330321 -393.86228) (xy 14.385164 -393.85215)
			(xy 14.440898 -393.850113) (xy 14.496335 -393.856213) (xy 14.550292 -393.870319) (xy 14.601621 -393.892131)
			(xy 14.649227 -393.921185) (xy 14.692095 -393.95686) (xy 14.729312 -393.998397) (xy 14.760085 -394.04491)
			(xy 14.783757 -394.095407) (xy 14.799825 -394.148814) (xy 14.807945 -394.20399) (xy 14.808454 -394.231876)
			(xy 14.807945 -394.259762) (xy 14.799825 -394.314938) (xy 14.783757 -394.368345) (xy 14.760085 -394.418842)
			(xy 14.752537 -394.43025) (xy 46.835312 -394.43025) (xy 46.839383 -394.374628) (xy 46.851509 -394.320191)
			(xy 46.871432 -394.2681) (xy 46.898728 -394.219465) (xy 46.932814 -394.175322) (xy 46.972963 -394.136613)
			(xy 47.018321 -394.104162) (xy 47.067921 -394.078661) (xy 47.120705 -394.060654) (xy 47.175548 -394.050524)
			(xy 47.231282 -394.048487) (xy 47.286719 -394.054587) (xy 47.340676 -394.068693) (xy 47.392005 -394.090505)
			(xy 47.439611 -394.119559) (xy 47.482479 -394.155234) (xy 47.519696 -394.196771) (xy 47.550469 -394.243284)
			(xy 47.574141 -394.293781) (xy 47.590209 -394.347188) (xy 47.598329 -394.402364) (xy 47.598838 -394.43025)
			(xy 47.598329 -394.458136) (xy 47.590209 -394.513312) (xy 47.574141 -394.566719) (xy 47.550469 -394.617216)
			(xy 47.519696 -394.663729) (xy 47.482479 -394.705266) (xy 47.439611 -394.740941) (xy 47.392005 -394.769995)
			(xy 47.340676 -394.791807) (xy 47.286719 -394.805913) (xy 47.231282 -394.812013) (xy 47.175548 -394.809976)
			(xy 47.120705 -394.799846) (xy 47.067921 -394.781839) (xy 47.018321 -394.756338) (xy 46.972963 -394.723887)
			(xy 46.932814 -394.685178) (xy 46.898728 -394.641035) (xy 46.871432 -394.5924) (xy 46.851509 -394.540309)
			(xy 46.839383 -394.485872) (xy 46.835312 -394.43025) (xy 14.752537 -394.43025) (xy 14.729312 -394.465355)
			(xy 14.692095 -394.506892) (xy 14.649227 -394.542567) (xy 14.601621 -394.571621) (xy 14.550292 -394.593433)
			(xy 14.496335 -394.607539) (xy 14.440898 -394.613639) (xy 14.385164 -394.611602) (xy 14.330321 -394.601472)
			(xy 14.277537 -394.583465) (xy 14.227937 -394.557964) (xy 14.182579 -394.525513) (xy 14.14243 -394.486804)
			(xy 14.108344 -394.442661) (xy 14.081048 -394.394026) (xy 14.061125 -394.341935) (xy 14.048999 -394.287498)
			(xy 14.044928 -394.231876) (xy 11.048492 -394.231876) (xy 11.048492 -395.247876) (xy 14.044928 -395.247876)
			(xy 14.048999 -395.192254) (xy 14.061125 -395.137817) (xy 14.081048 -395.085726) (xy 14.108344 -395.037091)
			(xy 14.14243 -394.992948) (xy 14.182579 -394.954239) (xy 14.227937 -394.921788) (xy 14.277537 -394.896287)
			(xy 14.330321 -394.87828) (xy 14.385164 -394.86815) (xy 14.440898 -394.866113) (xy 14.496335 -394.872213)
			(xy 14.550292 -394.886319) (xy 14.601621 -394.908131) (xy 14.649227 -394.937185) (xy 14.692095 -394.97286)
			(xy 14.729312 -395.014397) (xy 14.760085 -395.06091) (xy 14.783757 -395.111407) (xy 14.799825 -395.164814)
			(xy 14.807945 -395.21999) (xy 14.808454 -395.247876) (xy 14.807945 -395.275762) (xy 14.799825 -395.330938)
			(xy 14.783757 -395.384345) (xy 14.760085 -395.434842) (xy 14.729312 -395.481355) (xy 14.692095 -395.522892)
			(xy 14.649227 -395.558567) (xy 14.601621 -395.587621) (xy 14.550292 -395.609433) (xy 14.496335 -395.623539)
			(xy 14.440898 -395.629639) (xy 14.385164 -395.627602) (xy 14.330321 -395.617472) (xy 14.277537 -395.599465)
			(xy 14.227937 -395.573964) (xy 14.182579 -395.541513) (xy 14.14243 -395.502804) (xy 14.108344 -395.458661)
			(xy 14.081048 -395.410026) (xy 14.061125 -395.357935) (xy 14.048999 -395.303498) (xy 14.044928 -395.247876)
			(xy 11.048492 -395.247876) (xy 11.048492 -397.477996) (xy 18.90268 -397.477996) (xy 18.903124 -397.450625)
			(xy 18.910944 -397.396444) (xy 18.926437 -397.34394) (xy 18.949285 -397.294193) (xy 18.979015 -397.248228)
			(xy 18.99666 -397.227298) (xy 19.005872 -397.215982) (xy 19.018052 -397.189482) (xy 19.02223 -397.160617)
			(xy 19.018062 -397.131751) (xy 19.005891 -397.105247) (xy 18.99666 -397.093948) (xy 18.979008 -397.072993)
			(xy 18.949266 -397.026978) (xy 18.926417 -396.97718) (xy 18.910933 -396.924623) (xy 18.903132 -396.870391)
			(xy 18.90268 -396.842996) (xy 18.90268 -395.979396) (xy 18.903129 -395.952002) (xy 18.910948 -395.897774)
			(xy 18.926439 -395.845222) (xy 18.949284 -395.795424) (xy 18.979014 -395.749403) (xy 18.99666 -395.728444)
			(xy 19.005924 -395.717167) (xy 19.018098 -395.690653) (xy 19.022265 -395.661777) (xy 19.018085 -395.632902)
			(xy 19.005898 -395.606394) (xy 18.99666 -395.595094) (xy 18.978998 -395.57418) (xy 18.949291 -395.528202)
			(xy 18.92646 -395.47845) (xy 18.910974 -395.425945) (xy 18.903151 -395.371766) (xy 18.90268 -395.344396)
			(xy 18.903166 -395.317145) (xy 18.910922 -395.263197) (xy 18.926277 -395.210902) (xy 18.948919 -395.161325)
			(xy 18.978385 -395.115475) (xy 19.014076 -395.074284) (xy 19.055267 -395.038593) (xy 19.101117 -395.009127)
			(xy 19.150694 -394.986485) (xy 19.202989 -394.97113) (xy 19.256937 -394.963374) (xy 19.311439 -394.963374)
			(xy 19.365387 -394.97113) (xy 19.417682 -394.986485) (xy 19.467259 -395.009127) (xy 19.513109 -395.038593)
			(xy 19.5543 -395.074284) (xy 19.589991 -395.115475) (xy 19.619457 -395.161325) (xy 19.642099 -395.210902)
			(xy 19.657454 -395.263197) (xy 19.66521 -395.317145) (xy 19.665696 -395.344396) (xy 19.665229 -395.371766)
			(xy 19.657411 -395.425945) (xy 19.641923 -395.478448) (xy 19.619081 -395.528195) (xy 19.589357 -395.574162)
			(xy 19.571716 -395.595094) (xy 19.56261 -395.606467) (xy 19.550523 -395.632956) (xy 19.546377 -395.661776)
			(xy 19.550509 -395.690599) (xy 19.554908 -395.70025) (xy 46.835312 -395.70025) (xy 46.839383 -395.644628)
			(xy 46.851509 -395.590191) (xy 46.871432 -395.5381) (xy 46.898728 -395.489465) (xy 46.932814 -395.445322)
			(xy 46.972963 -395.406613) (xy 47.018321 -395.374162) (xy 47.067921 -395.348661) (xy 47.120705 -395.330654)
			(xy 47.175548 -395.320524) (xy 47.231282 -395.318487) (xy 47.286719 -395.324587) (xy 47.340676 -395.338693)
			(xy 47.392005 -395.360505) (xy 47.439611 -395.389559) (xy 47.482479 -395.425234) (xy 47.519696 -395.466771)
			(xy 47.550469 -395.513284) (xy 47.574141 -395.563781) (xy 47.590209 -395.617188) (xy 47.598329 -395.672364)
			(xy 47.598838 -395.70025) (xy 47.598329 -395.728136) (xy 47.590209 -395.783312) (xy 47.574141 -395.836719)
			(xy 47.550469 -395.887216) (xy 47.519696 -395.933729) (xy 47.482479 -395.975266) (xy 47.439611 -396.010941)
			(xy 47.392005 -396.039995) (xy 47.340676 -396.061807) (xy 47.286719 -396.075913) (xy 47.231282 -396.082013)
			(xy 47.175548 -396.079976) (xy 47.120705 -396.069846) (xy 47.067921 -396.051839) (xy 47.018321 -396.026338)
			(xy 46.972963 -395.993887) (xy 46.932814 -395.955178) (xy 46.898728 -395.911035) (xy 46.871432 -395.8624)
			(xy 46.851509 -395.810309) (xy 46.839383 -395.755872) (xy 46.835312 -395.70025) (xy 19.554908 -395.70025)
			(xy 19.562585 -395.717093) (xy 19.571716 -395.728444) (xy 19.589361 -395.749405) (xy 19.619105 -395.795418)
			(xy 19.641955 -395.845215) (xy 19.657441 -395.89777) (xy 19.665243 -395.952001) (xy 19.665696 -395.979396)
			(xy 19.665696 -396.842996) (xy 19.665224 -396.870389) (xy 19.657408 -396.924615) (xy 19.641921 -396.977167)
			(xy 19.619081 -397.026965) (xy 19.589358 -397.072987) (xy 19.571716 -397.093948) (xy 19.562558 -397.105282)
			(xy 19.550477 -397.131786) (xy 19.546342 -397.160617) (xy 19.550487 -397.189448) (xy 19.562577 -397.215947)
			(xy 19.571716 -397.227298) (xy 19.58937 -397.248218) (xy 19.619079 -397.294194) (xy 19.641912 -397.343945)
			(xy 19.6574 -397.396448) (xy 19.665224 -397.450626) (xy 19.665696 -397.477996) (xy 19.66521 -397.505247)
			(xy 19.657454 -397.559195) (xy 19.642099 -397.61149) (xy 19.619457 -397.661067) (xy 19.589991 -397.706917)
			(xy 19.5543 -397.748108) (xy 19.513109 -397.783799) (xy 19.467259 -397.813265) (xy 19.417682 -397.835907)
			(xy 19.365387 -397.851262) (xy 19.311439 -397.859018) (xy 19.256937 -397.859018) (xy 19.202989 -397.851262)
			(xy 19.150694 -397.835907) (xy 19.101117 -397.813265) (xy 19.055267 -397.783799) (xy 19.014076 -397.748108)
			(xy 18.978385 -397.706917) (xy 18.948919 -397.661067) (xy 18.926277 -397.61149) (xy 18.910922 -397.559195)
			(xy 18.903166 -397.505247) (xy 18.90268 -397.477996) (xy 11.048492 -397.477996) (xy 11.048492 -398.241012)
			(xy 24.946356 -398.241012) (xy 24.946842 -398.213137) (xy 24.954955 -398.15798) (xy 24.971011 -398.104592)
			(xy 24.994667 -398.054109) (xy 25.02542 -398.007608) (xy 25.043638 -397.986504) (xy 25.053055 -397.975318)
			(xy 25.065605 -397.948919) (xy 25.070167 -397.920047) (xy 25.066367 -397.891065) (xy 25.054518 -397.864345)
			(xy 25.045416 -397.8529) (xy 25.028431 -397.832095) (xy 24.999802 -397.786655) (xy 24.977827 -397.737649)
			(xy 24.96294 -397.686046) (xy 24.955436 -397.632866) (xy 24.954992 -397.606012) (xy 24.954992 -396.742412)
			(xy 24.955447 -396.715018) (xy 24.963264 -396.660791) (xy 24.978754 -396.608238) (xy 25.001598 -396.55844)
			(xy 25.031327 -396.512419) (xy 25.048972 -396.49146) (xy 25.05822 -396.480171) (xy 25.070394 -396.453661)
			(xy 25.074564 -396.424789) (xy 25.070388 -396.395917) (xy 25.058207 -396.36941) (xy 25.048972 -396.35811)
			(xy 25.03132 -396.337189) (xy 25.001611 -396.291212) (xy 24.978778 -396.241462) (xy 24.96329 -396.188959)
			(xy 24.955465 -396.134782) (xy 24.954992 -396.107412) (xy 24.955478 -396.080161) (xy 24.963234 -396.026213)
			(xy 24.978589 -395.973918) (xy 25.001231 -395.924341) (xy 25.030697 -395.878491) (xy 25.066388 -395.8373)
			(xy 25.107579 -395.801609) (xy 25.153429 -395.772143) (xy 25.203006 -395.749501) (xy 25.255301 -395.734146)
			(xy 25.309249 -395.72639) (xy 25.363751 -395.72639) (xy 25.417699 -395.734146) (xy 25.469994 -395.749501)
			(xy 25.519571 -395.772143) (xy 25.565421 -395.801609) (xy 25.606612 -395.8373) (xy 25.642303 -395.878491)
			(xy 25.671769 -395.924341) (xy 25.694411 -395.973918) (xy 25.709766 -396.026213) (xy 25.717522 -396.080161)
			(xy 25.718008 -396.107412) (xy 25.717547 -396.134782) (xy 25.709728 -396.188962) (xy 25.694237 -396.241465)
			(xy 25.671395 -396.291211) (xy 25.641669 -396.337178) (xy 25.624028 -396.35811) (xy 25.614906 -396.369471)
			(xy 25.60514 -396.390876) (xy 28.256228 -396.390876) (xy 28.260299 -396.335254) (xy 28.272425 -396.280817)
			(xy 28.292348 -396.228726) (xy 28.319644 -396.180091) (xy 28.35373 -396.135948) (xy 28.393879 -396.097239)
			(xy 28.439237 -396.064788) (xy 28.488837 -396.039287) (xy 28.541621 -396.02128) (xy 28.596464 -396.01115)
			(xy 28.652198 -396.009113) (xy 28.707635 -396.015213) (xy 28.761592 -396.029319) (xy 28.812921 -396.051131)
			(xy 28.860527 -396.080185) (xy 28.903395 -396.11586) (xy 28.940612 -396.157397) (xy 28.971385 -396.20391)
			(xy 28.995057 -396.254407) (xy 29.001115 -396.274544) (xy 35.204398 -396.274544) (xy 35.208469 -396.218922)
			(xy 35.220595 -396.164485) (xy 35.240518 -396.112394) (xy 35.267814 -396.063759) (xy 35.3019 -396.019616)
			(xy 35.342049 -395.980907) (xy 35.387407 -395.948456) (xy 35.437007 -395.922955) (xy 35.489791 -395.904948)
			(xy 35.544634 -395.894818) (xy 35.600368 -395.892781) (xy 35.655805 -395.898881) (xy 35.709762 -395.912987)
			(xy 35.761091 -395.934799) (xy 35.808697 -395.963853) (xy 35.851565 -395.999528) (xy 35.888782 -396.041065)
			(xy 35.919555 -396.087578) (xy 35.943227 -396.138075) (xy 35.959295 -396.191482) (xy 35.967415 -396.246658)
			(xy 35.967924 -396.274544) (xy 35.967415 -396.30243) (xy 35.959295 -396.357606) (xy 35.943227 -396.411013)
			(xy 35.919555 -396.46151) (xy 35.888782 -396.508023) (xy 35.851565 -396.54956) (xy 35.808697 -396.585235)
			(xy 35.761091 -396.614289) (xy 35.709762 -396.636101) (xy 35.655805 -396.650207) (xy 35.600368 -396.656307)
			(xy 35.544634 -396.65427) (xy 35.489791 -396.64414) (xy 35.437007 -396.626133) (xy 35.387407 -396.600632)
			(xy 35.342049 -396.568181) (xy 35.3019 -396.529472) (xy 35.267814 -396.485329) (xy 35.240518 -396.436694)
			(xy 35.220595 -396.384603) (xy 35.208469 -396.330166) (xy 35.204398 -396.274544) (xy 29.001115 -396.274544)
			(xy 29.011125 -396.307814) (xy 29.019245 -396.36299) (xy 29.019754 -396.390876) (xy 29.019245 -396.418762)
			(xy 29.011125 -396.473938) (xy 28.995057 -396.527345) (xy 28.971385 -396.577842) (xy 28.940612 -396.624355)
			(xy 28.903395 -396.665892) (xy 28.860527 -396.701567) (xy 28.812921 -396.730621) (xy 28.761592 -396.752433)
			(xy 28.707635 -396.766539) (xy 28.652198 -396.772639) (xy 28.596464 -396.770602) (xy 28.541621 -396.760472)
			(xy 28.488837 -396.742465) (xy 28.439237 -396.716964) (xy 28.393879 -396.684513) (xy 28.35373 -396.645804)
			(xy 28.319644 -396.601661) (xy 28.292348 -396.553026) (xy 28.272425 -396.500935) (xy 28.260299 -396.446498)
			(xy 28.256228 -396.390876) (xy 25.60514 -396.390876) (xy 25.602819 -396.395964) (xy 25.598676 -396.424789)
			(xy 25.602812 -396.453614) (xy 25.614894 -396.48011) (xy 25.624028 -396.49146) (xy 25.641682 -396.512414)
			(xy 25.671424 -396.558428) (xy 25.694273 -396.608227) (xy 25.709756 -396.660784) (xy 25.717556 -396.715016)
			(xy 25.718008 -396.742412) (xy 25.718008 -397.406876) (xy 28.256228 -397.406876) (xy 28.260299 -397.351254)
			(xy 28.272425 -397.296817) (xy 28.292348 -397.244726) (xy 28.319644 -397.196091) (xy 28.35373 -397.151948)
			(xy 28.393879 -397.113239) (xy 28.439237 -397.080788) (xy 28.488837 -397.055287) (xy 28.541621 -397.03728)
			(xy 28.596464 -397.02715) (xy 28.652198 -397.025113) (xy 28.707635 -397.031213) (xy 28.751345 -397.04264)
			(xy 32.554162 -397.04264) (xy 32.558233 -396.987018) (xy 32.570359 -396.932581) (xy 32.590282 -396.88049)
			(xy 32.617578 -396.831855) (xy 32.651664 -396.787712) (xy 32.691813 -396.749003) (xy 32.737171 -396.716552)
			(xy 32.786771 -396.691051) (xy 32.839555 -396.673044) (xy 32.894398 -396.662914) (xy 32.950132 -396.660877)
			(xy 33.005569 -396.666977) (xy 33.059526 -396.681083) (xy 33.110855 -396.702895) (xy 33.158461 -396.731949)
			(xy 33.201329 -396.767624) (xy 33.238546 -396.809161) (xy 33.269319 -396.855674) (xy 33.292991 -396.906171)
			(xy 33.309059 -396.959578) (xy 33.317179 -397.014754) (xy 33.317688 -397.04264) (xy 33.317179 -397.070526)
			(xy 33.309059 -397.125702) (xy 33.292991 -397.179109) (xy 33.269319 -397.229606) (xy 33.238546 -397.276119)
			(xy 33.201329 -397.317656) (xy 33.158461 -397.353331) (xy 33.110855 -397.382385) (xy 33.059526 -397.404197)
			(xy 33.005569 -397.418303) (xy 32.950132 -397.424403) (xy 32.894398 -397.422366) (xy 32.839555 -397.412236)
			(xy 32.786771 -397.394229) (xy 32.737171 -397.368728) (xy 32.691813 -397.336277) (xy 32.651664 -397.297568)
			(xy 32.617578 -397.253425) (xy 32.590282 -397.20479) (xy 32.570359 -397.152699) (xy 32.558233 -397.098262)
			(xy 32.554162 -397.04264) (xy 28.751345 -397.04264) (xy 28.761592 -397.045319) (xy 28.812921 -397.067131)
			(xy 28.860527 -397.096185) (xy 28.903395 -397.13186) (xy 28.940612 -397.173397) (xy 28.971385 -397.21991)
			(xy 28.995057 -397.270407) (xy 29.011125 -397.323814) (xy 29.019245 -397.37899) (xy 29.019754 -397.406876)
			(xy 29.019245 -397.434762) (xy 29.011125 -397.489938) (xy 28.995057 -397.543345) (xy 28.971385 -397.593842)
			(xy 28.940612 -397.640355) (xy 28.903395 -397.681892) (xy 28.860527 -397.717567) (xy 28.812921 -397.746621)
			(xy 28.761592 -397.768433) (xy 28.707635 -397.782539) (xy 28.652198 -397.788639) (xy 28.596464 -397.786602)
			(xy 28.541621 -397.776472) (xy 28.488837 -397.758465) (xy 28.439237 -397.732964) (xy 28.393879 -397.700513)
			(xy 28.35373 -397.661804) (xy 28.319644 -397.617661) (xy 28.292348 -397.569026) (xy 28.272425 -397.516935)
			(xy 28.260299 -397.462498) (xy 28.256228 -397.406876) (xy 25.718008 -397.406876) (xy 25.718008 -397.606012)
			(xy 25.71756 -397.633915) (xy 25.70947 -397.68913) (xy 25.693422 -397.742577) (xy 25.669756 -397.793115)
			(xy 25.63898 -397.839665) (xy 25.620726 -397.860774) (xy 25.611333 -397.871977) (xy 25.598785 -397.898371)
			(xy 25.59422 -397.927236) (xy 25.598013 -397.956213) (xy 25.609852 -397.982932) (xy 25.618948 -397.994378)
			(xy 25.635949 -398.015138) (xy 25.664554 -398.060538) (xy 25.686515 -398.109498) (xy 25.701401 -398.161052)
			(xy 25.708917 -398.214182) (xy 25.709372 -398.241012) (xy 25.708886 -398.268263) (xy 25.70113 -398.322211)
			(xy 25.685775 -398.374506) (xy 25.663133 -398.424083) (xy 25.633667 -398.469933) (xy 25.597976 -398.511124)
			(xy 25.556785 -398.546815) (xy 25.510935 -398.576281) (xy 25.461358 -398.598923) (xy 25.409063 -398.614278)
			(xy 25.355115 -398.622034) (xy 25.300613 -398.622034) (xy 25.246665 -398.614278) (xy 25.19437 -398.598923)
			(xy 25.144793 -398.576281) (xy 25.098943 -398.546815) (xy 25.057752 -398.511124) (xy 25.022061 -398.469933)
			(xy 24.992595 -398.424083) (xy 24.969953 -398.374506) (xy 24.954598 -398.322211) (xy 24.946842 -398.268263)
			(xy 24.946356 -398.241012) (xy 11.048492 -398.241012) (xy 11.048492 -398.782032) (xy 18.269458 -398.782032)
			(xy 18.269944 -398.754781) (xy 18.2777 -398.700833) (xy 18.293055 -398.648538) (xy 18.315697 -398.598961)
			(xy 18.345163 -398.553111) (xy 18.380854 -398.51192) (xy 18.422045 -398.476229) (xy 18.467895 -398.446763)
			(xy 18.517472 -398.424121) (xy 18.569767 -398.408766) (xy 18.623715 -398.40101) (xy 18.678217 -398.40101)
			(xy 18.732165 -398.408766) (xy 18.78446 -398.424121) (xy 18.834037 -398.446763) (xy 18.879887 -398.476229)
			(xy 18.921078 -398.51192) (xy 18.956769 -398.553111) (xy 18.986235 -398.598961) (xy 19.008877 -398.648538)
			(xy 19.024232 -398.700833) (xy 19.031988 -398.754781) (xy 19.032474 -398.782032) (xy 19.031895 -398.812337)
			(xy 19.022331 -398.872186) (xy 19.013424 -398.901158) (xy 19.009518 -398.91433) (xy 19.0082 -398.941765)
			(xy 19.014244 -398.968558) (xy 19.027213 -398.992769) (xy 19.046168 -399.012647) (xy 19.069735 -399.026752)
			(xy 19.096211 -399.034063) (xy 19.109944 -399.034508) (xy 19.458432 -399.034508) (xy 19.472162 -399.034082)
			(xy 19.498626 -399.026757) (xy 19.522182 -399.012644) (xy 19.541125 -398.992765) (xy 19.554086 -398.968556)
			(xy 19.560128 -398.94177) (xy 19.558813 -398.914341) (xy 19.554952 -398.901158) (xy 19.546049 -398.872185)
			(xy 19.536483 -398.812336) (xy 19.535902 -398.782032) (xy 19.536388 -398.754781) (xy 19.544144 -398.700833)
			(xy 19.559499 -398.648538) (xy 19.582141 -398.598961) (xy 19.611607 -398.553111) (xy 19.647298 -398.51192)
			(xy 19.688489 -398.476229) (xy 19.734339 -398.446763) (xy 19.783916 -398.424121) (xy 19.836211 -398.408766)
			(xy 19.890159 -398.40101) (xy 19.944661 -398.40101) (xy 19.998609 -398.408766) (xy 20.050904 -398.424121)
			(xy 20.100481 -398.446763) (xy 20.146331 -398.476229) (xy 20.187522 -398.51192) (xy 20.223213 -398.553111)
			(xy 20.252679 -398.598961) (xy 20.275321 -398.648538) (xy 20.290676 -398.700833) (xy 20.298432 -398.754781)
			(xy 20.298918 -398.782032) (xy 20.298336 -398.811171) (xy 20.289474 -398.868772) (xy 20.271961 -398.924356)
			(xy 20.246204 -398.976634) (xy 20.212801 -399.024389) (xy 20.172528 -399.066514) (xy 20.126321 -399.102028)
			(xy 20.101052 -399.11655) (xy 20.08779 -399.124479) (xy 20.066418 -399.146774) (xy 20.052662 -399.174425)
			(xy 20.047774 -399.20492) (xy 20.052197 -399.235486) (xy 20.05838 -399.249646) (xy 20.070423 -399.275708)
			(xy 20.087414 -399.330545) (xy 20.095983 -399.387311) (xy 20.09648 -399.416016) (xy 20.09606 -399.443271)
			(xy 20.0883 -399.497225) (xy 20.072941 -399.549525) (xy 20.050294 -399.599107) (xy 20.020822 -399.644962)
			(xy 19.985124 -399.686155) (xy 19.943926 -399.721848) (xy 19.898068 -399.751315) (xy 19.848484 -399.773956)
			(xy 19.796181 -399.789309) (xy 19.742227 -399.797063) (xy 19.714972 -399.797524) (xy 18.851372 -399.797524)
			(xy 18.824121 -399.797048) (xy 18.770174 -399.789288) (xy 18.71788 -399.773931) (xy 18.668303 -399.751287)
			(xy 18.622454 -399.72182) (xy 18.581264 -399.686127) (xy 18.545573 -399.644937) (xy 18.516107 -399.599086)
			(xy 18.493465 -399.549509) (xy 18.478109 -399.497215) (xy 18.470351 -399.443267) (xy 18.469864 -399.416016)
			(xy 18.470394 -399.387219) (xy 18.479032 -399.330276) (xy 18.496116 -399.275274) (xy 18.508218 -399.249138)
			(xy 18.514442 -399.234981) (xy 18.519025 -399.204414) (xy 18.514272 -399.173874) (xy 18.500616 -399.146146)
			(xy 18.479304 -399.12376) (xy 18.466054 -399.115788) (xy 18.440928 -399.101229) (xy 18.394995 -399.065707)
			(xy 18.354972 -399.023636) (xy 18.321785 -398.975988) (xy 18.296199 -398.923862) (xy 18.278804 -398.868461)
			(xy 18.270003 -398.811065) (xy 18.269458 -398.782032) (xy 11.048492 -398.782032) (xy 11.048492 -399.974816)
			(xy 25.133046 -399.974816) (xy 25.133532 -399.947565) (xy 25.141288 -399.893617) (xy 25.156643 -399.841322)
			(xy 25.179285 -399.791745) (xy 25.208751 -399.745895) (xy 25.244442 -399.704704) (xy 25.285633 -399.669013)
			(xy 25.331483 -399.639547) (xy 25.38106 -399.616905) (xy 25.433355 -399.60155) (xy 25.487303 -399.593794)
			(xy 25.541805 -399.593794) (xy 25.595753 -399.60155) (xy 25.648048 -399.616905) (xy 25.697625 -399.639547)
			(xy 25.743475 -399.669013) (xy 25.784666 -399.704704) (xy 25.820357 -399.745895) (xy 25.849823 -399.791745)
			(xy 25.872465 -399.841322) (xy 25.88782 -399.893617) (xy 25.895576 -399.947565) (xy 25.896062 -399.974816)
			(xy 25.8953 -399.997422) (xy 25.895165 -400.008213) (xy 25.902896 -400.028344) (xy 25.918185 -400.043552)
			(xy 25.938356 -400.051177) (xy 25.949148 -400.051016) (xy 25.971754 -400.050508) (xy 26.835354 -400.050508)
			(xy 26.85796 -400.051016) (xy 26.868747 -400.051153) (xy 26.888907 -400.043529) (xy 26.904186 -400.028329)
			(xy 26.911912 -400.008209) (xy 26.911808 -399.997422) (xy 26.911046 -399.974816) (xy 26.911532 -399.947565)
			(xy 26.919288 -399.893617) (xy 26.934643 -399.841322) (xy 26.957285 -399.791745) (xy 26.986751 -399.745895)
			(xy 27.022442 -399.704704) (xy 27.063633 -399.669013) (xy 27.109483 -399.639547) (xy 27.15906 -399.616905)
			(xy 27.211355 -399.60155) (xy 27.265303 -399.593794) (xy 27.319805 -399.593794) (xy 27.373753 -399.60155)
			(xy 27.426048 -399.616905) (xy 27.475625 -399.639547) (xy 27.521475 -399.669013) (xy 27.562666 -399.704704)
			(xy 27.598357 -399.745895) (xy 27.627823 -399.791745) (xy 27.650465 -399.841322) (xy 27.66582 -399.893617)
			(xy 27.673576 -399.947565) (xy 27.674062 -399.974816) (xy 27.673509 -400.003792) (xy 27.664755 -400.061079)
			(xy 27.647437 -400.116382) (xy 27.621952 -400.16843) (xy 27.588887 -400.216023) (xy 27.549004 -400.258067)
			(xy 27.503219 -400.293594) (xy 27.452587 -400.321787) (xy 27.398273 -400.341996) (xy 27.341528 -400.353757)
			(xy 27.31262 -400.355816) (xy 27.297748 -400.357132) (xy 27.269664 -400.367216) (xy 27.245686 -400.384978)
			(xy 27.227856 -400.408904) (xy 27.21769 -400.436959) (xy 27.216354 -400.451828) (xy 27.214264 -400.480744)
			(xy 27.202528 -400.537514) (xy 27.182339 -400.591855) (xy 27.154161 -400.642516) (xy 27.118643 -400.688332)
			(xy 27.076603 -400.728246) (xy 27.029009 -400.761342) (xy 26.976955 -400.786856) (xy 26.921641 -400.804202)
			(xy 26.864339 -400.81298) (xy 26.835354 -400.813524) (xy 25.971754 -400.813524) (xy 25.942768 -400.812926)
			(xy 25.885464 -400.804163) (xy 25.830144 -400.786829) (xy 25.778085 -400.761325) (xy 25.730484 -400.728237)
			(xy 25.688438 -400.688328) (xy 25.652914 -400.642516) (xy 25.624731 -400.591857) (xy 25.604538 -400.537517)
			(xy 25.5928 -400.480746) (xy 25.590754 -400.451828) (xy 25.58934 -400.436969) (xy 25.579186 -400.408923)
			(xy 25.561374 -400.384998) (xy 25.537417 -400.367228) (xy 25.509353 -400.357124) (xy 25.494488 -400.355816)
			(xy 25.465581 -400.353758) (xy 25.408839 -400.341988) (xy 25.354529 -400.321772) (xy 25.303901 -400.293576)
			(xy 25.258119 -400.258049) (xy 25.218236 -400.216006) (xy 25.185169 -400.168416) (xy 25.159679 -400.116374)
			(xy 25.142351 -400.061074) (xy 25.133586 -400.003791) (xy 25.133046 -399.974816) (xy 11.048492 -399.974816)
			(xy 11.048492 -400.814032) (xy 20.966174 -400.814032) (xy 20.970245 -400.75841) (xy 20.982371 -400.703973)
			(xy 21.002294 -400.651882) (xy 21.02959 -400.603247) (xy 21.063676 -400.559104) (xy 21.103825 -400.520395)
			(xy 21.149183 -400.487944) (xy 21.198783 -400.462443) (xy 21.251567 -400.444436) (xy 21.30641 -400.434306)
			(xy 21.362144 -400.432269) (xy 21.417581 -400.438369) (xy 21.471538 -400.452475) (xy 21.522867 -400.474287)
			(xy 21.570473 -400.503341) (xy 21.613341 -400.539016) (xy 21.650558 -400.580553) (xy 21.681331 -400.627066)
			(xy 21.705003 -400.677563) (xy 21.709686 -400.693128) (xy 24.065736 -400.693128) (xy 24.069807 -400.637506)
			(xy 24.081933 -400.583069) (xy 24.101856 -400.530978) (xy 24.129152 -400.482343) (xy 24.163238 -400.4382)
			(xy 24.203387 -400.399491) (xy 24.248745 -400.36704) (xy 24.298345 -400.341539) (xy 24.351129 -400.323532)
			(xy 24.405972 -400.313402) (xy 24.461706 -400.311365) (xy 24.517143 -400.317465) (xy 24.5711 -400.331571)
			(xy 24.622429 -400.353383) (xy 24.670035 -400.382437) (xy 24.712903 -400.418112) (xy 24.75012 -400.459649)
			(xy 24.780893 -400.506162) (xy 24.804565 -400.556659) (xy 24.820633 -400.610066) (xy 24.828753 -400.665242)
			(xy 24.829262 -400.693128) (xy 24.828753 -400.721014) (xy 24.820633 -400.77619) (xy 24.804565 -400.829597)
			(xy 24.780893 -400.880094) (xy 24.75012 -400.926607) (xy 24.712903 -400.968144) (xy 24.670035 -401.003819)
			(xy 24.622429 -401.032873) (xy 24.5711 -401.054685) (xy 24.517143 -401.068791) (xy 24.461706 -401.074891)
			(xy 24.405972 -401.072854) (xy 24.351129 -401.062724) (xy 24.298345 -401.044717) (xy 24.248745 -401.019216)
			(xy 24.203387 -400.986765) (xy 24.163238 -400.948056) (xy 24.129152 -400.903913) (xy 24.101856 -400.855278)
			(xy 24.081933 -400.803187) (xy 24.069807 -400.74875) (xy 24.065736 -400.693128) (xy 21.709686 -400.693128)
			(xy 21.721071 -400.73097) (xy 21.729191 -400.786146) (xy 21.7297 -400.814032) (xy 21.729191 -400.841918)
			(xy 21.721071 -400.897094) (xy 21.705003 -400.950501) (xy 21.681331 -401.000998) (xy 21.650558 -401.047511)
			(xy 21.613341 -401.089048) (xy 21.570473 -401.124723) (xy 21.522867 -401.153777) (xy 21.471538 -401.175589)
			(xy 21.417581 -401.189695) (xy 21.362144 -401.195795) (xy 21.30641 -401.193758) (xy 21.251567 -401.183628)
			(xy 21.198783 -401.165621) (xy 21.149183 -401.14012) (xy 21.103825 -401.107669) (xy 21.063676 -401.06896)
			(xy 21.02959 -401.024817) (xy 21.002294 -400.976182) (xy 20.982371 -400.924091) (xy 20.970245 -400.869654)
			(xy 20.966174 -400.814032) (xy 11.048492 -400.814032) (xy 11.048492 -402.421598) (xy 26.00909 -402.421598)
			(xy 26.013161 -402.365976) (xy 26.025287 -402.311539) (xy 26.04521 -402.259448) (xy 26.072506 -402.210813)
			(xy 26.106592 -402.16667) (xy 26.146741 -402.127961) (xy 26.192099 -402.09551) (xy 26.241699 -402.070009)
			(xy 26.294483 -402.052002) (xy 26.349326 -402.041872) (xy 26.40506 -402.039835) (xy 26.460497 -402.045935)
			(xy 26.514454 -402.060041) (xy 26.565783 -402.081853) (xy 26.613389 -402.110907) (xy 26.656257 -402.146582)
			(xy 26.693474 -402.188119) (xy 26.724247 -402.234632) (xy 26.747919 -402.285129) (xy 26.763987 -402.338536)
			(xy 26.772107 -402.393712) (xy 26.772616 -402.421598) (xy 26.772107 -402.449484) (xy 26.763987 -402.50466)
			(xy 26.747919 -402.558067) (xy 26.724247 -402.608564) (xy 26.693474 -402.655077) (xy 26.656257 -402.696614)
			(xy 26.613389 -402.732289) (xy 26.565783 -402.761343) (xy 26.514454 -402.783155) (xy 26.460497 -402.797261)
			(xy 26.40506 -402.803361) (xy 26.349326 -402.801324) (xy 26.294483 -402.791194) (xy 26.241699 -402.773187)
			(xy 26.192099 -402.747686) (xy 26.146741 -402.715235) (xy 26.106592 -402.676526) (xy 26.072506 -402.632383)
			(xy 26.04521 -402.583748) (xy 26.025287 -402.531657) (xy 26.013161 -402.47722) (xy 26.00909 -402.421598)
			(xy 11.048492 -402.421598) (xy 11.048492 -402.806408) (xy 22.659084 -402.806408) (xy 22.663155 -402.750786)
			(xy 22.675281 -402.696349) (xy 22.695204 -402.644258) (xy 22.7225 -402.595623) (xy 22.756586 -402.55148)
			(xy 22.796735 -402.512771) (xy 22.842093 -402.48032) (xy 22.891693 -402.454819) (xy 22.944477 -402.436812)
			(xy 22.99932 -402.426682) (xy 23.055054 -402.424645) (xy 23.110491 -402.430745) (xy 23.164448 -402.444851)
			(xy 23.215777 -402.466663) (xy 23.263383 -402.495717) (xy 23.306251 -402.531392) (xy 23.343468 -402.572929)
			(xy 23.374241 -402.619442) (xy 23.397913 -402.669939) (xy 23.413981 -402.723346) (xy 23.422101 -402.778522)
			(xy 23.42261 -402.806408) (xy 23.422101 -402.834294) (xy 23.413981 -402.88947) (xy 23.397913 -402.942877)
			(xy 23.374241 -402.993374) (xy 23.343468 -403.039887) (xy 23.306251 -403.081424) (xy 23.263383 -403.117099)
			(xy 23.215777 -403.146153) (xy 23.164448 -403.167965) (xy 23.110491 -403.182071) (xy 23.055054 -403.188171)
			(xy 22.99932 -403.186134) (xy 22.944477 -403.176004) (xy 22.891693 -403.157997) (xy 22.842093 -403.132496)
			(xy 22.796735 -403.100045) (xy 22.756586 -403.061336) (xy 22.7225 -403.017193) (xy 22.695204 -402.968558)
			(xy 22.675281 -402.916467) (xy 22.663155 -402.86203) (xy 22.659084 -402.806408) (xy 11.048492 -402.806408)
			(xy 11.048492 -403.822408) (xy 22.659084 -403.822408) (xy 22.663155 -403.766786) (xy 22.675281 -403.712349)
			(xy 22.695204 -403.660258) (xy 22.7225 -403.611623) (xy 22.756586 -403.56748) (xy 22.796735 -403.528771)
			(xy 22.842093 -403.49632) (xy 22.891693 -403.470819) (xy 22.944477 -403.452812) (xy 22.99932 -403.442682)
			(xy 23.055054 -403.440645) (xy 23.110491 -403.446745) (xy 23.164448 -403.460851) (xy 23.215777 -403.482663)
			(xy 23.263383 -403.511717) (xy 23.306251 -403.547392) (xy 23.343468 -403.588929) (xy 23.374241 -403.635442)
			(xy 23.397913 -403.685939) (xy 23.413981 -403.739346) (xy 23.422101 -403.794522) (xy 23.42261 -403.822408)
			(xy 23.422101 -403.850294) (xy 23.413981 -403.90547) (xy 23.397913 -403.958877) (xy 23.374241 -404.009374)
			(xy 23.343468 -404.055887) (xy 23.306251 -404.097424) (xy 23.263383 -404.133099) (xy 23.215777 -404.162153)
			(xy 23.164448 -404.183965) (xy 23.110491 -404.198071) (xy 23.055054 -404.204171) (xy 22.99932 -404.202134)
			(xy 22.944477 -404.192004) (xy 22.891693 -404.173997) (xy 22.842093 -404.148496) (xy 22.796735 -404.116045)
			(xy 22.756586 -404.077336) (xy 22.7225 -404.033193) (xy 22.695204 -403.984558) (xy 22.675281 -403.932467)
			(xy 22.663155 -403.87803) (xy 22.659084 -403.822408) (xy 11.048492 -403.822408) (xy 11.048492 -404.445216)
			(xy 26.115264 -404.445216) (xy 26.115765 -404.416947) (xy 26.124095 -404.361026) (xy 26.140591 -404.306948)
			(xy 26.164891 -404.255898) (xy 26.196462 -404.208996) (xy 26.234611 -404.167269) (xy 26.256234 -404.149052)
			(xy 26.267538 -404.139112) (xy 26.284304 -404.114131) (xy 26.293067 -404.08535) (xy 26.293069 -404.055265)
			(xy 26.28431 -404.026483) (xy 26.267548 -404.001499) (xy 26.256234 -403.991572) (xy 26.234612 -403.973356)
			(xy 26.196476 -403.93162) (xy 26.164914 -403.884715) (xy 26.140618 -403.833667) (xy 26.124118 -403.779592)
			(xy 26.115776 -403.723676) (xy 26.115264 -403.695408) (xy 26.11575 -403.668157) (xy 26.123506 -403.614209)
			(xy 26.138861 -403.561914) (xy 26.161503 -403.512337) (xy 26.190969 -403.466487) (xy 26.22666 -403.425296)
			(xy 26.267851 -403.389605) (xy 26.313701 -403.360139) (xy 26.363278 -403.337497) (xy 26.415573 -403.322142)
			(xy 26.469521 -403.314386) (xy 26.524023 -403.314386) (xy 26.577971 -403.322142) (xy 26.630266 -403.337497)
			(xy 26.679843 -403.360139) (xy 26.725693 -403.389605) (xy 26.766884 -403.425296) (xy 26.802575 -403.466487)
			(xy 26.832041 -403.512337) (xy 26.854683 -403.561914) (xy 26.870038 -403.614209) (xy 26.877794 -403.668157)
			(xy 26.87828 -403.695408) (xy 29.285184 -403.695408) (xy 29.285709 -403.665612) (xy 29.294975 -403.606745)
			(xy 29.313282 -403.550035) (xy 29.340184 -403.496861) (xy 29.375028 -403.448517) (xy 29.416966 -403.40618)
			(xy 29.440632 -403.388068) (xy 29.45135 -403.379674) (xy 29.468218 -403.358317) (xy 29.478842 -403.333261)
			(xy 29.482467 -403.306288) (xy 29.478836 -403.279316) (xy 29.468206 -403.254263) (xy 29.451333 -403.232909)
			(xy 29.440632 -403.224492) (xy 29.416983 -403.206363) (xy 29.375061 -403.164021) (xy 29.340229 -403.115677)
			(xy 29.313334 -403.062507) (xy 29.29503 -403.005804) (xy 29.285761 -402.946944) (xy 29.285184 -402.917152)
			(xy 29.28567 -402.889901) (xy 29.293426 -402.835953) (xy 29.308781 -402.783658) (xy 29.331423 -402.734081)
			(xy 29.360889 -402.688231) (xy 29.39658 -402.64704) (xy 29.437771 -402.611349) (xy 29.483621 -402.581883)
			(xy 29.533198 -402.559241) (xy 29.585493 -402.543886) (xy 29.639441 -402.53613) (xy 29.693943 -402.53613)
			(xy 29.747891 -402.543886) (xy 29.800186 -402.559241) (xy 29.849763 -402.581883) (xy 29.895613 -402.611349)
			(xy 29.936804 -402.64704) (xy 29.972495 -402.688231) (xy 30.001961 -402.734081) (xy 30.024603 -402.783658)
			(xy 30.039958 -402.835953) (xy 30.047714 -402.889901) (xy 30.0482 -402.917152) (xy 30.047651 -402.946947)
			(xy 30.038392 -403.005814) (xy 30.02009 -403.062524) (xy 29.993192 -403.115698) (xy 29.958351 -403.164041)
			(xy 29.916416 -403.206379) (xy 29.892752 -403.224492) (xy 29.882075 -403.232933) (xy 29.86521 -403.254281)
			(xy 29.854585 -403.279326) (xy 29.850956 -403.306288) (xy 29.854579 -403.333251) (xy 29.865198 -403.358299)
			(xy 29.882058 -403.37965) (xy 29.892752 -403.388068) (xy 29.916426 -403.406166) (xy 29.958348 -403.448514)
			(xy 29.993177 -403.496864) (xy 30.020068 -403.55004) (xy 30.038366 -403.606749) (xy 30.047628 -403.665614)
			(xy 30.0482 -403.695408) (xy 30.047714 -403.722659) (xy 30.039958 -403.776607) (xy 30.024603 -403.828902)
			(xy 30.001961 -403.878479) (xy 29.972495 -403.924329) (xy 29.936804 -403.96552) (xy 29.895613 -404.001211)
			(xy 29.849763 -404.030677) (xy 29.800186 -404.053319) (xy 29.747891 -404.068674) (xy 29.693943 -404.07643)
			(xy 29.639441 -404.07643) (xy 29.585493 -404.068674) (xy 29.533198 -404.053319) (xy 29.483621 -404.030677)
			(xy 29.437771 -404.001211) (xy 29.39658 -403.96552) (xy 29.360889 -403.924329) (xy 29.331423 -403.878479)
			(xy 29.308781 -403.828902) (xy 29.293426 -403.776607) (xy 29.28567 -403.722659) (xy 29.285184 -403.695408)
			(xy 26.87828 -403.695408) (xy 26.87778 -403.723677) (xy 26.869447 -403.779597) (xy 26.85295 -403.833674)
			(xy 26.82865 -403.884724) (xy 26.79708 -403.931626) (xy 26.758932 -403.973354) (xy 26.73731 -403.991572)
			(xy 26.725987 -404.00149) (xy 26.709232 -404.02648) (xy 26.700476 -404.055264) (xy 26.700478 -404.085351)
			(xy 26.709238 -404.114134) (xy 26.725997 -404.139121) (xy 26.73731 -404.149052) (xy 26.758904 -404.167299)
			(xy 26.79704 -404.209029) (xy 26.828604 -404.255929) (xy 26.852905 -404.306971) (xy 26.869411 -404.361039)
			(xy 26.877762 -404.41695) (xy 26.87828 -404.445216) (xy 26.877794 -404.472467) (xy 26.870038 -404.526415)
			(xy 26.854683 -404.57871) (xy 26.832041 -404.628287) (xy 26.802575 -404.674137) (xy 26.766884 -404.715328)
			(xy 26.725693 -404.751019) (xy 26.679843 -404.780485) (xy 26.630266 -404.803127) (xy 26.577971 -404.818482)
			(xy 26.524023 -404.826238) (xy 26.469521 -404.826238) (xy 26.415573 -404.818482) (xy 26.363278 -404.803127)
			(xy 26.313701 -404.780485) (xy 26.267851 -404.751019) (xy 26.22666 -404.715328) (xy 26.190969 -404.674137)
			(xy 26.161503 -404.628287) (xy 26.138861 -404.57871) (xy 26.123506 -404.526415) (xy 26.11575 -404.472467)
			(xy 26.115264 -404.445216) (xy 11.048492 -404.445216) (xy 11.048492 -404.842218) (xy 22.659084 -404.842218)
			(xy 22.663155 -404.786596) (xy 22.675281 -404.732159) (xy 22.695204 -404.680068) (xy 22.7225 -404.631433)
			(xy 22.756586 -404.58729) (xy 22.796735 -404.548581) (xy 22.842093 -404.51613) (xy 22.891693 -404.490629)
			(xy 22.944477 -404.472622) (xy 22.99932 -404.462492) (xy 23.055054 -404.460455) (xy 23.110491 -404.466555)
			(xy 23.164448 -404.480661) (xy 23.215777 -404.502473) (xy 23.263383 -404.531527) (xy 23.306251 -404.567202)
			(xy 23.343468 -404.608739) (xy 23.374241 -404.655252) (xy 23.397913 -404.705749) (xy 23.413981 -404.759156)
			(xy 23.422101 -404.814332) (xy 23.42261 -404.842218) (xy 23.422101 -404.870104) (xy 23.413981 -404.92528)
			(xy 23.397913 -404.978687) (xy 23.374241 -405.029184) (xy 23.343468 -405.075697) (xy 23.306251 -405.117234)
			(xy 23.263383 -405.152909) (xy 23.215777 -405.181963) (xy 23.164448 -405.203775) (xy 23.110491 -405.217881)
			(xy 23.055054 -405.223981) (xy 22.99932 -405.221944) (xy 22.944477 -405.211814) (xy 22.891693 -405.193807)
			(xy 22.842093 -405.168306) (xy 22.796735 -405.135855) (xy 22.756586 -405.097146) (xy 22.7225 -405.053003)
			(xy 22.695204 -405.004368) (xy 22.675281 -404.952277) (xy 22.663155 -404.89784) (xy 22.659084 -404.842218)
			(xy 11.048492 -404.842218) (xy 11.048492 -405.477218) (xy 25.175462 -405.477218) (xy 25.179533 -405.421596)
			(xy 25.191659 -405.367159) (xy 25.211582 -405.315068) (xy 25.238878 -405.266433) (xy 25.272964 -405.22229)
			(xy 25.313113 -405.183581) (xy 25.358471 -405.15113) (xy 25.408071 -405.125629) (xy 25.460855 -405.107622)
			(xy 25.515698 -405.097492) (xy 25.571432 -405.095455) (xy 25.626869 -405.101555) (xy 25.680826 -405.115661)
			(xy 25.732155 -405.137473) (xy 25.779761 -405.166527) (xy 25.822629 -405.202202) (xy 25.859846 -405.243739)
			(xy 25.890619 -405.290252) (xy 25.914291 -405.340749) (xy 25.930359 -405.394156) (xy 25.938479 -405.449332)
			(xy 25.938988 -405.477218) (xy 25.938479 -405.505104) (xy 25.930359 -405.56028) (xy 25.914291 -405.613687)
			(xy 25.890619 -405.664184) (xy 25.859846 -405.710697) (xy 25.822629 -405.752234) (xy 25.779761 -405.787909)
			(xy 25.732155 -405.816963) (xy 25.680826 -405.838775) (xy 25.626869 -405.852881) (xy 25.571432 -405.858981)
			(xy 25.515698 -405.856944) (xy 25.460855 -405.846814) (xy 25.408071 -405.828807) (xy 25.358471 -405.803306)
			(xy 25.313113 -405.770855) (xy 25.272964 -405.732146) (xy 25.238878 -405.688003) (xy 25.211582 -405.639368)
			(xy 25.191659 -405.587277) (xy 25.179533 -405.53284) (xy 25.175462 -405.477218) (xy 11.048492 -405.477218)
			(xy 11.048492 -407.035508) (xy 15.978632 -407.035508) (xy 15.978632 -406.171908) (xy 15.979063 -406.144654)
			(xy 15.98682 -406.090699) (xy 16.002177 -406.038398) (xy 16.024821 -405.988816) (xy 16.054292 -405.942961)
			(xy 16.089989 -405.901767) (xy 16.131186 -405.866073) (xy 16.177044 -405.836606) (xy 16.226628 -405.813966)
			(xy 16.278931 -405.798613) (xy 16.332885 -405.790861) (xy 16.36014 -405.7904) (xy 16.389125 -405.790961)
			(xy 16.44643 -405.799715) (xy 16.501757 -405.817017) (xy 16.528034 -405.829262) (xy 16.542121 -405.835617)
			(xy 16.572658 -405.840299) (xy 16.603198 -405.835643) (xy 16.630952 -405.822073) (xy 16.653382 -405.80083)
			(xy 16.661384 -405.787606) (xy 16.675949 -405.762653) (xy 16.711506 -405.717112) (xy 16.753522 -405.677451)
			(xy 16.801036 -405.644577) (xy 16.852964 -405.619242) (xy 16.908117 -405.602025) (xy 16.965235 -405.593318)
			(xy 16.994124 -405.592788) (xy 17.021374 -405.593283) (xy 17.075318 -405.601043) (xy 17.12761 -405.6164)
			(xy 17.177183 -405.639042) (xy 17.22303 -405.668509) (xy 17.264217 -405.7042) (xy 17.299906 -405.745389)
			(xy 17.32937 -405.791238) (xy 17.352009 -405.840813) (xy 17.367362 -405.893105) (xy 17.375118 -405.94705)
			(xy 17.375118 -406.00155) (xy 17.36998 -406.037288) (xy 29.284674 -406.037288) (xy 29.288745 -405.981666)
			(xy 29.300871 -405.927229) (xy 29.320794 -405.875138) (xy 29.34809 -405.826503) (xy 29.382176 -405.78236)
			(xy 29.422325 -405.743651) (xy 29.467683 -405.7112) (xy 29.517283 -405.685699) (xy 29.570067 -405.667692)
			(xy 29.62491 -405.657562) (xy 29.680644 -405.655525) (xy 29.736081 -405.661625) (xy 29.790038 -405.675731)
			(xy 29.841367 -405.697543) (xy 29.888973 -405.726597) (xy 29.889337 -405.7269) (xy 30.918402 -405.7269)
			(xy 30.922473 -405.671278) (xy 30.934599 -405.616841) (xy 30.954522 -405.56475) (xy 30.981818 -405.516115)
			(xy 31.015904 -405.471972) (xy 31.056053 -405.433263) (xy 31.101411 -405.400812) (xy 31.151011 -405.375311)
			(xy 31.203795 -405.357304) (xy 31.258638 -405.347174) (xy 31.314372 -405.345137) (xy 31.369809 -405.351237)
			(xy 31.423766 -405.365343) (xy 31.475095 -405.387155) (xy 31.522701 -405.416209) (xy 31.565569 -405.451884)
			(xy 31.602786 -405.493421) (xy 31.633559 -405.539934) (xy 31.657231 -405.590431) (xy 31.673299 -405.643838)
			(xy 31.681419 -405.699014) (xy 31.681928 -405.7269) (xy 31.681419 -405.754786) (xy 31.673299 -405.809962)
			(xy 31.657231 -405.863369) (xy 31.633559 -405.913866) (xy 31.602786 -405.960379) (xy 31.565569 -406.001916)
			(xy 31.522701 -406.037591) (xy 31.475095 -406.066645) (xy 31.423766 -406.088457) (xy 31.369809 -406.102563)
			(xy 31.314372 -406.108663) (xy 31.258638 -406.106626) (xy 31.203795 -406.096496) (xy 31.151011 -406.078489)
			(xy 31.101411 -406.052988) (xy 31.056053 -406.020537) (xy 31.015904 -405.981828) (xy 30.981818 -405.937685)
			(xy 30.954522 -405.88905) (xy 30.934599 -405.836959) (xy 30.922473 -405.782522) (xy 30.918402 -405.7269)
			(xy 29.889337 -405.7269) (xy 29.931841 -405.762272) (xy 29.969058 -405.803809) (xy 29.999831 -405.850322)
			(xy 30.023503 -405.900819) (xy 30.039571 -405.954226) (xy 30.047691 -406.009402) (xy 30.0482 -406.037288)
			(xy 30.047691 -406.065174) (xy 30.039571 -406.12035) (xy 30.023503 -406.173757) (xy 29.999831 -406.224254)
			(xy 29.969058 -406.270767) (xy 29.931841 -406.312304) (xy 29.888973 -406.347979) (xy 29.841367 -406.377033)
			(xy 29.790038 -406.398845) (xy 29.736081 -406.412951) (xy 29.680644 -406.419051) (xy 29.62491 -406.417014)
			(xy 29.570067 -406.406884) (xy 29.517283 -406.388877) (xy 29.467683 -406.363376) (xy 29.422325 -406.330925)
			(xy 29.382176 -406.292216) (xy 29.34809 -406.248073) (xy 29.320794 -406.199438) (xy 29.300871 -406.147347)
			(xy 29.288745 -406.09291) (xy 29.284674 -406.037288) (xy 17.36998 -406.037288) (xy 17.367362 -406.055495)
			(xy 17.352009 -406.107787) (xy 17.32937 -406.157362) (xy 17.299906 -406.203211) (xy 17.264217 -406.2444)
			(xy 17.22303 -406.280091) (xy 17.177183 -406.309558) (xy 17.12761 -406.3322) (xy 17.075318 -406.347557)
			(xy 17.021374 -406.355317) (xy 16.994124 -406.355804) (xy 16.963819 -406.355234) (xy 16.90397 -406.345663)
			(xy 16.874998 -406.336754) (xy 16.861824 -406.332864) (xy 16.834396 -406.331559) (xy 16.807612 -406.337608)
			(xy 16.783407 -406.350575) (xy 16.763532 -406.369522) (xy 16.749423 -406.39308) (xy 16.742101 -406.419545)
			(xy 16.741648 -406.433274) (xy 16.741648 -406.679908) (xy 19.186142 -406.679908) (xy 19.190213 -406.624286)
			(xy 19.202339 -406.569849) (xy 19.222262 -406.517758) (xy 19.249558 -406.469123) (xy 19.283644 -406.42498)
			(xy 19.323793 -406.386271) (xy 19.369151 -406.35382) (xy 19.418751 -406.328319) (xy 19.471535 -406.310312)
			(xy 19.526378 -406.300182) (xy 19.582112 -406.298145) (xy 19.637549 -406.304245) (xy 19.691506 -406.318351)
			(xy 19.742835 -406.340163) (xy 19.790441 -406.369217) (xy 19.833309 -406.404892) (xy 19.870526 -406.446429)
			(xy 19.901299 -406.492942) (xy 19.924971 -406.543439) (xy 19.941039 -406.596846) (xy 19.949159 -406.652022)
			(xy 19.949668 -406.679908) (xy 19.949159 -406.707794) (xy 19.941039 -406.76297) (xy 19.924971 -406.816377)
			(xy 19.901299 -406.866874) (xy 19.870526 -406.913387) (xy 19.833309 -406.954924) (xy 19.790441 -406.990599)
			(xy 19.742835 -407.019653) (xy 19.691506 -407.041465) (xy 19.637549 -407.055571) (xy 19.582112 -407.061671)
			(xy 19.526378 -407.059634) (xy 19.471535 -407.049504) (xy 19.418751 -407.031497) (xy 19.369151 -407.005996)
			(xy 19.323793 -406.973545) (xy 19.283644 -406.934836) (xy 19.249558 -406.890693) (xy 19.222262 -406.842058)
			(xy 19.202339 -406.789967) (xy 19.190213 -406.73553) (xy 19.186142 -406.679908) (xy 16.741648 -406.679908)
			(xy 16.741648 -406.774142) (xy 16.742075 -406.787875) (xy 16.749385 -406.81435) (xy 16.763491 -406.837916)
			(xy 16.783372 -406.856867) (xy 16.807586 -406.869829) (xy 16.834381 -406.875864) (xy 16.861814 -406.874533)
			(xy 16.874998 -406.870662) (xy 16.903973 -406.861769) (xy 16.96382 -406.852197) (xy 16.994124 -406.851612)
			(xy 17.021376 -406.852059) (xy 17.075324 -406.859819) (xy 17.127618 -406.875177) (xy 17.177195 -406.897821)
			(xy 17.223045 -406.927289) (xy 17.264234 -406.962983) (xy 17.299925 -407.004175) (xy 17.329391 -407.050026)
			(xy 17.352031 -407.099604) (xy 17.367386 -407.1519) (xy 17.375142 -407.205848) (xy 17.375142 -407.260352)
			(xy 17.367386 -407.3143) (xy 17.360645 -407.33726) (xy 26.114754 -407.33726) (xy 26.118825 -407.281638)
			(xy 26.130951 -407.227201) (xy 26.150874 -407.17511) (xy 26.17817 -407.126475) (xy 26.212256 -407.082332)
			(xy 26.252405 -407.043623) (xy 26.297763 -407.011172) (xy 26.347363 -406.985671) (xy 26.400147 -406.967664)
			(xy 26.45499 -406.957534) (xy 26.510724 -406.955497) (xy 26.566161 -406.961597) (xy 26.620118 -406.975703)
			(xy 26.671447 -406.997515) (xy 26.719053 -407.026569) (xy 26.761921 -407.062244) (xy 26.799138 -407.103781)
			(xy 26.829911 -407.150294) (xy 26.853583 -407.200791) (xy 26.869651 -407.254198) (xy 26.877771 -407.309374)
			(xy 26.87828 -407.33726) (xy 26.877771 -407.365146) (xy 26.869651 -407.420322) (xy 26.853583 -407.473729)
			(xy 26.829911 -407.524226) (xy 26.799138 -407.570739) (xy 26.761921 -407.612276) (xy 26.719053 -407.647951)
			(xy 26.671447 -407.677005) (xy 26.620118 -407.698817) (xy 26.566161 -407.712923) (xy 26.510724 -407.719023)
			(xy 26.45499 -407.716986) (xy 26.400147 -407.706856) (xy 26.347363 -407.688849) (xy 26.297763 -407.663348)
			(xy 26.252405 -407.630897) (xy 26.212256 -407.592188) (xy 26.17817 -407.548045) (xy 26.150874 -407.49941)
			(xy 26.130951 -407.447319) (xy 26.118825 -407.392882) (xy 26.114754 -407.33726) (xy 17.360645 -407.33726)
			(xy 17.352031 -407.366596) (xy 17.329391 -407.416174) (xy 17.299925 -407.462025) (xy 17.264234 -407.503217)
			(xy 17.223045 -407.538911) (xy 17.177195 -407.568379) (xy 17.127618 -407.591023) (xy 17.075324 -407.606381)
			(xy 17.021376 -407.614141) (xy 16.994124 -407.614628) (xy 16.965237 -407.614064) (xy 16.908121 -407.605369)
			(xy 16.852969 -407.588158) (xy 16.801045 -407.562826) (xy 16.753535 -407.529952) (xy 16.711528 -407.490288)
			(xy 16.675983 -407.444742) (xy 16.661384 -407.41981) (xy 16.653339 -407.406619) (xy 16.630921 -407.385385)
			(xy 16.603182 -407.37182) (xy 16.572657 -407.367166) (xy 16.542136 -407.371846) (xy 16.528034 -407.378154)
			(xy 16.501766 -407.390425) (xy 16.446442 -407.407759) (xy 16.389128 -407.416499) (xy 16.36014 -407.417016)
			(xy 16.332888 -407.416508) (xy 16.27894 -407.408756) (xy 16.226643 -407.393406) (xy 16.177064 -407.370768)
			(xy 16.131211 -407.341305) (xy 16.090018 -407.305616) (xy 16.054324 -407.264428) (xy 16.024855 -407.218579)
			(xy 16.002211 -407.169002) (xy 15.986854 -407.116707) (xy 15.979096 -407.062759) (xy 15.978632 -407.035508)
			(xy 11.048492 -407.035508) (xy 11.048492 -407.507186) (xy 13.418564 -407.507186) (xy 13.422635 -407.451564)
			(xy 13.434761 -407.397127) (xy 13.454684 -407.345036) (xy 13.48198 -407.296401) (xy 13.516066 -407.252258)
			(xy 13.556215 -407.213549) (xy 13.601573 -407.181098) (xy 13.651173 -407.155597) (xy 13.703957 -407.13759)
			(xy 13.7588 -407.12746) (xy 13.814534 -407.125423) (xy 13.869971 -407.131523) (xy 13.923928 -407.145629)
			(xy 13.975257 -407.167441) (xy 14.022863 -407.196495) (xy 14.065731 -407.23217) (xy 14.102948 -407.273707)
			(xy 14.133721 -407.32022) (xy 14.157393 -407.370717) (xy 14.173461 -407.424124) (xy 14.181581 -407.4793)
			(xy 14.18209 -407.507186) (xy 14.181581 -407.535072) (xy 14.173461 -407.590248) (xy 14.157393 -407.643655)
			(xy 14.133721 -407.694152) (xy 14.102948 -407.740665) (xy 14.065731 -407.782202) (xy 14.022863 -407.817877)
			(xy 13.975257 -407.846931) (xy 13.923928 -407.868743) (xy 13.869971 -407.882849) (xy 13.814534 -407.888949)
			(xy 13.7588 -407.886912) (xy 13.703957 -407.876782) (xy 13.651173 -407.858775) (xy 13.601573 -407.833274)
			(xy 13.556215 -407.800823) (xy 13.516066 -407.762114) (xy 13.48198 -407.717971) (xy 13.454684 -407.669336)
			(xy 13.434761 -407.617245) (xy 13.422635 -407.562808) (xy 13.418564 -407.507186) (xy 11.048492 -407.507186)
			(xy 11.048492 -407.890218) (xy 22.678134 -407.890218) (xy 22.682205 -407.834596) (xy 22.694331 -407.780159)
			(xy 22.714254 -407.728068) (xy 22.74155 -407.679433) (xy 22.775636 -407.63529) (xy 22.815785 -407.596581)
			(xy 22.861143 -407.56413) (xy 22.910743 -407.538629) (xy 22.963527 -407.520622) (xy 23.01837 -407.510492)
			(xy 23.074104 -407.508455) (xy 23.129541 -407.514555) (xy 23.183498 -407.528661) (xy 23.234827 -407.550473)
			(xy 23.282433 -407.579527) (xy 23.325301 -407.615202) (xy 23.362518 -407.656739) (xy 23.393291 -407.703252)
			(xy 23.416963 -407.753749) (xy 23.433031 -407.807156) (xy 23.441151 -407.862332) (xy 23.44166 -407.890218)
			(xy 24.697434 -407.890218) (xy 24.701505 -407.834596) (xy 24.713631 -407.780159) (xy 24.733554 -407.728068)
			(xy 24.76085 -407.679433) (xy 24.794936 -407.63529) (xy 24.835085 -407.596581) (xy 24.880443 -407.56413)
			(xy 24.930043 -407.538629) (xy 24.982827 -407.520622) (xy 25.03767 -407.510492) (xy 25.093404 -407.508455)
			(xy 25.148841 -407.514555) (xy 25.202798 -407.528661) (xy 25.254127 -407.550473) (xy 25.301733 -407.579527)
			(xy 25.344601 -407.615202) (xy 25.381818 -407.656739) (xy 25.412591 -407.703252) (xy 25.420817 -407.7208)
			(xy 27.608782 -407.7208) (xy 27.612853 -407.665178) (xy 27.624979 -407.610741) (xy 27.644902 -407.55865)
			(xy 27.672198 -407.510015) (xy 27.706284 -407.465872) (xy 27.746433 -407.427163) (xy 27.791791 -407.394712)
			(xy 27.841391 -407.369211) (xy 27.894175 -407.351204) (xy 27.949018 -407.341074) (xy 28.004752 -407.339037)
			(xy 28.060189 -407.345137) (xy 28.114146 -407.359243) (xy 28.165475 -407.381055) (xy 28.213081 -407.410109)
			(xy 28.255949 -407.445784) (xy 28.293166 -407.487321) (xy 28.323939 -407.533834) (xy 28.347611 -407.584331)
			(xy 28.363679 -407.637738) (xy 28.371799 -407.692914) (xy 28.372308 -407.7208) (xy 28.371799 -407.748686)
			(xy 28.363679 -407.803862) (xy 28.347611 -407.857269) (xy 28.323939 -407.907766) (xy 28.293166 -407.954279)
			(xy 28.255949 -407.995816) (xy 28.213081 -408.031491) (xy 28.165475 -408.060545) (xy 28.114146 -408.082357)
			(xy 28.060189 -408.096463) (xy 28.004752 -408.102563) (xy 27.949018 -408.100526) (xy 27.894175 -408.090396)
			(xy 27.841391 -408.072389) (xy 27.791791 -408.046888) (xy 27.746433 -408.014437) (xy 27.706284 -407.975728)
			(xy 27.672198 -407.931585) (xy 27.644902 -407.88295) (xy 27.624979 -407.830859) (xy 27.612853 -407.776422)
			(xy 27.608782 -407.7208) (xy 25.420817 -407.7208) (xy 25.436263 -407.753749) (xy 25.452331 -407.807156)
			(xy 25.460451 -407.862332) (xy 25.46096 -407.890218) (xy 25.460451 -407.918104) (xy 25.452331 -407.97328)
			(xy 25.436263 -408.026687) (xy 25.412591 -408.077184) (xy 25.381818 -408.123697) (xy 25.344601 -408.165234)
			(xy 25.301733 -408.200909) (xy 25.254127 -408.229963) (xy 25.202798 -408.251775) (xy 25.148841 -408.265881)
			(xy 25.093404 -408.271981) (xy 25.03767 -408.269944) (xy 24.982827 -408.259814) (xy 24.930043 -408.241807)
			(xy 24.880443 -408.216306) (xy 24.835085 -408.183855) (xy 24.794936 -408.145146) (xy 24.76085 -408.101003)
			(xy 24.733554 -408.052368) (xy 24.713631 -408.000277) (xy 24.701505 -407.94584) (xy 24.697434 -407.890218)
			(xy 23.44166 -407.890218) (xy 23.441151 -407.918104) (xy 23.433031 -407.97328) (xy 23.416963 -408.026687)
			(xy 23.393291 -408.077184) (xy 23.362518 -408.123697) (xy 23.325301 -408.165234) (xy 23.282433 -408.200909)
			(xy 23.234827 -408.229963) (xy 23.183498 -408.251775) (xy 23.129541 -408.265881) (xy 23.074104 -408.271981)
			(xy 23.01837 -408.269944) (xy 22.963527 -408.259814) (xy 22.910743 -408.241807) (xy 22.861143 -408.216306)
			(xy 22.815785 -408.183855) (xy 22.775636 -408.145146) (xy 22.74155 -408.101003) (xy 22.714254 -408.052368)
			(xy 22.694331 -408.000277) (xy 22.682205 -407.94584) (xy 22.678134 -407.890218) (xy 11.048492 -407.890218)
			(xy 11.048492 -408.916886) (xy 16.158462 -408.916886) (xy 16.162533 -408.861264) (xy 16.174659 -408.806827)
			(xy 16.194582 -408.754736) (xy 16.221878 -408.706101) (xy 16.255964 -408.661958) (xy 16.296113 -408.623249)
			(xy 16.341471 -408.590798) (xy 16.391071 -408.565297) (xy 16.443855 -408.54729) (xy 16.498698 -408.53716)
			(xy 16.554432 -408.535123) (xy 16.609869 -408.541223) (xy 16.663826 -408.555329) (xy 16.715155 -408.577141)
			(xy 16.762761 -408.606195) (xy 16.805629 -408.64187) (xy 16.842846 -408.683407) (xy 16.873619 -408.72992)
			(xy 16.897291 -408.780417) (xy 16.913359 -408.833824) (xy 16.921479 -408.889) (xy 16.921988 -408.916886)
			(xy 16.921479 -408.944772) (xy 16.913359 -408.999948) (xy 16.897291 -409.053355) (xy 16.873619 -409.103852)
			(xy 16.842846 -409.150365) (xy 16.805629 -409.191902) (xy 16.762761 -409.227577) (xy 16.715155 -409.256631)
			(xy 16.663826 -409.278443) (xy 16.609869 -409.292549) (xy 16.554432 -409.298649) (xy 16.498698 -409.296612)
			(xy 16.443855 -409.286482) (xy 16.391071 -409.268475) (xy 16.341471 -409.242974) (xy 16.296113 -409.210523)
			(xy 16.255964 -409.171814) (xy 16.221878 -409.127671) (xy 16.194582 -409.079036) (xy 16.174659 -409.026945)
			(xy 16.162533 -408.972508) (xy 16.158462 -408.916886) (xy 11.048492 -408.916886) (xy 11.048492 -409.7782)
			(xy 18.439382 -409.7782) (xy 18.443453 -409.722578) (xy 18.455579 -409.668141) (xy 18.475502 -409.61605)
			(xy 18.502798 -409.567415) (xy 18.536884 -409.523272) (xy 18.577033 -409.484563) (xy 18.622391 -409.452112)
			(xy 18.671991 -409.426611) (xy 18.724775 -409.408604) (xy 18.779618 -409.398474) (xy 18.835352 -409.396437)
			(xy 18.890789 -409.402537) (xy 18.944746 -409.416643) (xy 18.996075 -409.438455) (xy 19.043681 -409.467509)
			(xy 19.086549 -409.503184) (xy 19.123766 -409.544721) (xy 19.154539 -409.591234) (xy 19.178211 -409.641731)
			(xy 19.194279 -409.695138) (xy 19.202399 -409.750314) (xy 19.202908 -409.7782) (xy 20.420582 -409.7782)
			(xy 20.424653 -409.722578) (xy 20.436779 -409.668141) (xy 20.456702 -409.61605) (xy 20.483998 -409.567415)
			(xy 20.518084 -409.523272) (xy 20.558233 -409.484563) (xy 20.603591 -409.452112) (xy 20.653191 -409.426611)
			(xy 20.705975 -409.408604) (xy 20.760818 -409.398474) (xy 20.816552 -409.396437) (xy 20.871989 -409.402537)
			(xy 20.925946 -409.416643) (xy 20.977275 -409.438455) (xy 21.024881 -409.467509) (xy 21.067749 -409.503184)
			(xy 21.104966 -409.544721) (xy 21.135739 -409.591234) (xy 21.159411 -409.641731) (xy 21.175479 -409.695138)
			(xy 21.183599 -409.750314) (xy 21.184108 -409.7782) (xy 21.411182 -409.7782) (xy 21.415253 -409.722578)
			(xy 21.427379 -409.668141) (xy 21.447302 -409.61605) (xy 21.474598 -409.567415) (xy 21.508684 -409.523272)
			(xy 21.548833 -409.484563) (xy 21.594191 -409.452112) (xy 21.643791 -409.426611) (xy 21.696575 -409.408604)
			(xy 21.751418 -409.398474) (xy 21.807152 -409.396437) (xy 21.862562 -409.402534) (xy 22.678134 -409.402534)
			(xy 22.682205 -409.346912) (xy 22.694331 -409.292475) (xy 22.714254 -409.240384) (xy 22.74155 -409.191749)
			(xy 22.775636 -409.147606) (xy 22.815785 -409.108897) (xy 22.861143 -409.076446) (xy 22.910743 -409.050945)
			(xy 22.963527 -409.032938) (xy 23.01837 -409.022808) (xy 23.074104 -409.020771) (xy 23.129541 -409.026871)
			(xy 23.183498 -409.040977) (xy 23.234827 -409.062789) (xy 23.282433 -409.091843) (xy 23.325301 -409.127518)
			(xy 23.362518 -409.169055) (xy 23.393291 -409.215568) (xy 23.416963 -409.266065) (xy 23.433031 -409.319472)
			(xy 23.441151 -409.374648) (xy 23.44166 -409.402534) (xy 23.441151 -409.43042) (xy 23.433031 -409.485596)
			(xy 23.416963 -409.539003) (xy 23.393291 -409.5895) (xy 23.362518 -409.636013) (xy 23.325301 -409.67755)
			(xy 23.282433 -409.713225) (xy 23.234827 -409.742279) (xy 23.183498 -409.764091) (xy 23.129541 -409.778197)
			(xy 23.074104 -409.784297) (xy 23.01837 -409.78226) (xy 22.963527 -409.77213) (xy 22.910743 -409.754123)
			(xy 22.861143 -409.728622) (xy 22.815785 -409.696171) (xy 22.775636 -409.657462) (xy 22.74155 -409.613319)
			(xy 22.714254 -409.564684) (xy 22.694331 -409.512593) (xy 22.682205 -409.458156) (xy 22.678134 -409.402534)
			(xy 21.862562 -409.402534) (xy 21.862589 -409.402537) (xy 21.916546 -409.416643) (xy 21.967875 -409.438455)
			(xy 22.015481 -409.467509) (xy 22.058349 -409.503184) (xy 22.095566 -409.544721) (xy 22.126339 -409.591234)
			(xy 22.150011 -409.641731) (xy 22.166079 -409.695138) (xy 22.174199 -409.750314) (xy 22.174708 -409.7782)
			(xy 22.174199 -409.806086) (xy 22.166079 -409.861262) (xy 22.150011 -409.914669) (xy 22.126339 -409.965166)
			(xy 22.095566 -410.011679) (xy 22.058349 -410.053216) (xy 22.015481 -410.088891) (xy 21.967875 -410.117945)
			(xy 21.916546 -410.139757) (xy 21.862589 -410.153863) (xy 21.807152 -410.159963) (xy 21.751418 -410.157926)
			(xy 21.696575 -410.147796) (xy 21.643791 -410.129789) (xy 21.594191 -410.104288) (xy 21.548833 -410.071837)
			(xy 21.508684 -410.033128) (xy 21.474598 -409.988985) (xy 21.447302 -409.94035) (xy 21.427379 -409.888259)
			(xy 21.415253 -409.833822) (xy 21.411182 -409.7782) (xy 21.184108 -409.7782) (xy 21.183599 -409.806086)
			(xy 21.175479 -409.861262) (xy 21.159411 -409.914669) (xy 21.135739 -409.965166) (xy 21.104966 -410.011679)
			(xy 21.067749 -410.053216) (xy 21.024881 -410.088891) (xy 20.977275 -410.117945) (xy 20.925946 -410.139757)
			(xy 20.871989 -410.153863) (xy 20.816552 -410.159963) (xy 20.760818 -410.157926) (xy 20.705975 -410.147796)
			(xy 20.653191 -410.129789) (xy 20.603591 -410.104288) (xy 20.558233 -410.071837) (xy 20.518084 -410.033128)
			(xy 20.483998 -409.988985) (xy 20.456702 -409.94035) (xy 20.436779 -409.888259) (xy 20.424653 -409.833822)
			(xy 20.420582 -409.7782) (xy 19.202908 -409.7782) (xy 19.202399 -409.806086) (xy 19.194279 -409.861262)
			(xy 19.178211 -409.914669) (xy 19.154539 -409.965166) (xy 19.123766 -410.011679) (xy 19.086549 -410.053216)
			(xy 19.043681 -410.088891) (xy 18.996075 -410.117945) (xy 18.944746 -410.139757) (xy 18.890789 -410.153863)
			(xy 18.835352 -410.159963) (xy 18.779618 -410.157926) (xy 18.724775 -410.147796) (xy 18.671991 -410.129789)
			(xy 18.622391 -410.104288) (xy 18.577033 -410.071837) (xy 18.536884 -410.033128) (xy 18.502798 -409.988985)
			(xy 18.475502 -409.94035) (xy 18.455579 -409.888259) (xy 18.443453 -409.833822) (xy 18.439382 -409.7782)
			(xy 11.048492 -409.7782) (xy 11.048492 -410.456888) (xy 16.260062 -410.456888) (xy 16.264133 -410.401266)
			(xy 16.276259 -410.346829) (xy 16.296182 -410.294738) (xy 16.323478 -410.246103) (xy 16.357564 -410.20196)
			(xy 16.397713 -410.163251) (xy 16.443071 -410.1308) (xy 16.492671 -410.105299) (xy 16.545455 -410.087292)
			(xy 16.600298 -410.077162) (xy 16.656032 -410.075125) (xy 16.711469 -410.081225) (xy 16.765426 -410.095331)
			(xy 16.816755 -410.117143) (xy 16.864361 -410.146197) (xy 16.907229 -410.181872) (xy 16.944446 -410.223409)
			(xy 16.975219 -410.269922) (xy 16.998891 -410.320419) (xy 17.014959 -410.373826) (xy 17.021538 -410.418534)
			(xy 25.023062 -410.418534) (xy 25.027133 -410.362912) (xy 25.039259 -410.308475) (xy 25.059182 -410.256384)
			(xy 25.086478 -410.207749) (xy 25.120564 -410.163606) (xy 25.160713 -410.124897) (xy 25.206071 -410.092446)
			(xy 25.255671 -410.066945) (xy 25.308455 -410.048938) (xy 25.363298 -410.038808) (xy 25.419032 -410.036771)
			(xy 25.474469 -410.042871) (xy 25.528426 -410.056977) (xy 25.579755 -410.078789) (xy 25.627361 -410.107843)
			(xy 25.670229 -410.143518) (xy 25.707446 -410.185055) (xy 25.738219 -410.231568) (xy 25.761891 -410.282065)
			(xy 25.777959 -410.335472) (xy 25.786079 -410.390648) (xy 25.786588 -410.418534) (xy 25.786079 -410.44642)
			(xy 25.777959 -410.501596) (xy 25.761891 -410.555003) (xy 25.738219 -410.6055) (xy 25.707446 -410.652013)
			(xy 25.670229 -410.69355) (xy 25.627361 -410.729225) (xy 25.579755 -410.758279) (xy 25.528426 -410.780091)
			(xy 25.511377 -410.784548) (xy 29.284674 -410.784548) (xy 29.288745 -410.728926) (xy 29.300871 -410.674489)
			(xy 29.320794 -410.622398) (xy 29.34809 -410.573763) (xy 29.382176 -410.52962) (xy 29.422325 -410.490911)
			(xy 29.467683 -410.45846) (xy 29.517283 -410.432959) (xy 29.570067 -410.414952) (xy 29.62491 -410.404822)
			(xy 29.680644 -410.402785) (xy 29.736081 -410.408885) (xy 29.790038 -410.422991) (xy 29.841367 -410.444803)
			(xy 29.888973 -410.473857) (xy 29.931841 -410.509532) (xy 29.969058 -410.551069) (xy 29.999831 -410.597582)
			(xy 30.023503 -410.648079) (xy 30.039571 -410.701486) (xy 30.047691 -410.756662) (xy 30.0482 -410.784548)
			(xy 30.047691 -410.812434) (xy 30.039571 -410.86761) (xy 30.023503 -410.921017) (xy 29.999831 -410.971514)
			(xy 29.969058 -411.018027) (xy 29.931841 -411.059564) (xy 29.888973 -411.095239) (xy 29.841367 -411.124293)
			(xy 29.790038 -411.146105) (xy 29.736081 -411.160211) (xy 29.680644 -411.166311) (xy 29.62491 -411.164274)
			(xy 29.570067 -411.154144) (xy 29.517283 -411.136137) (xy 29.467683 -411.110636) (xy 29.422325 -411.078185)
			(xy 29.382176 -411.039476) (xy 29.34809 -410.995333) (xy 29.320794 -410.946698) (xy 29.300871 -410.894607)
			(xy 29.288745 -410.84017) (xy 29.284674 -410.784548) (xy 25.511377 -410.784548) (xy 25.474469 -410.794197)
			(xy 25.419032 -410.800297) (xy 25.363298 -410.79826) (xy 25.308455 -410.78813) (xy 25.255671 -410.770123)
			(xy 25.206071 -410.744622) (xy 25.160713 -410.712171) (xy 25.120564 -410.673462) (xy 25.086478 -410.629319)
			(xy 25.059182 -410.580684) (xy 25.039259 -410.528593) (xy 25.027133 -410.474156) (xy 25.023062 -410.418534)
			(xy 17.021538 -410.418534) (xy 17.023079 -410.429002) (xy 17.023588 -410.456888) (xy 17.023079 -410.484774)
			(xy 17.014959 -410.53995) (xy 16.998891 -410.593357) (xy 16.975219 -410.643854) (xy 16.944446 -410.690367)
			(xy 16.907229 -410.731904) (xy 16.864361 -410.767579) (xy 16.816755 -410.796633) (xy 16.765426 -410.818445)
			(xy 16.711469 -410.832551) (xy 16.656032 -410.838651) (xy 16.600298 -410.836614) (xy 16.545455 -410.826484)
			(xy 16.492671 -410.808477) (xy 16.443071 -410.782976) (xy 16.397713 -410.750525) (xy 16.357564 -410.711816)
			(xy 16.323478 -410.667673) (xy 16.296182 -410.619038) (xy 16.276259 -410.566947) (xy 16.264133 -410.51251)
			(xy 16.260062 -410.456888) (xy 11.048492 -410.456888) (xy 11.048492 -412.450534) (xy 22.678134 -412.450534)
			(xy 22.682205 -412.394912) (xy 22.694331 -412.340475) (xy 22.714254 -412.288384) (xy 22.74155 -412.239749)
			(xy 22.775636 -412.195606) (xy 22.815785 -412.156897) (xy 22.861143 -412.124446) (xy 22.910743 -412.098945)
			(xy 22.963527 -412.080938) (xy 23.01837 -412.070808) (xy 23.074104 -412.068771) (xy 23.129541 -412.074871)
			(xy 23.166449 -412.08452) (xy 26.114754 -412.08452) (xy 26.118825 -412.028898) (xy 26.130951 -411.974461)
			(xy 26.150874 -411.92237) (xy 26.17817 -411.873735) (xy 26.212256 -411.829592) (xy 26.252405 -411.790883)
			(xy 26.297763 -411.758432) (xy 26.347363 -411.732931) (xy 26.400147 -411.714924) (xy 26.45499 -411.704794)
			(xy 26.510724 -411.702757) (xy 26.566161 -411.708857) (xy 26.620118 -411.722963) (xy 26.671447 -411.744775)
			(xy 26.719053 -411.773829) (xy 26.761921 -411.809504) (xy 26.799138 -411.851041) (xy 26.829911 -411.897554)
			(xy 26.853583 -411.948051) (xy 26.869651 -412.001458) (xy 26.877771 -412.056634) (xy 26.87828 -412.08452)
			(xy 29.970982 -412.08452) (xy 29.975053 -412.028898) (xy 29.987179 -411.974461) (xy 30.007102 -411.92237)
			(xy 30.034398 -411.873735) (xy 30.068484 -411.829592) (xy 30.108633 -411.790883) (xy 30.153991 -411.758432)
			(xy 30.203591 -411.732931) (xy 30.256375 -411.714924) (xy 30.311218 -411.704794) (xy 30.366952 -411.702757)
			(xy 30.422389 -411.708857) (xy 30.476346 -411.722963) (xy 30.527675 -411.744775) (xy 30.575281 -411.773829)
			(xy 30.618149 -411.809504) (xy 30.655366 -411.851041) (xy 30.686139 -411.897554) (xy 30.709811 -411.948051)
			(xy 30.725879 -412.001458) (xy 30.733999 -412.056634) (xy 30.734508 -412.08452) (xy 30.733999 -412.112406)
			(xy 30.725879 -412.167582) (xy 30.709811 -412.220989) (xy 30.686139 -412.271486) (xy 30.655366 -412.317999)
			(xy 30.618149 -412.359536) (xy 30.575281 -412.395211) (xy 30.527675 -412.424265) (xy 30.476346 -412.446077)
			(xy 30.422389 -412.460183) (xy 30.366952 -412.466283) (xy 30.311218 -412.464246) (xy 30.256375 -412.454116)
			(xy 30.203591 -412.436109) (xy 30.153991 -412.410608) (xy 30.108633 -412.378157) (xy 30.068484 -412.339448)
			(xy 30.034398 -412.295305) (xy 30.007102 -412.24667) (xy 29.987179 -412.194579) (xy 29.975053 -412.140142)
			(xy 29.970982 -412.08452) (xy 26.87828 -412.08452) (xy 26.877771 -412.112406) (xy 26.869651 -412.167582)
			(xy 26.853583 -412.220989) (xy 26.829911 -412.271486) (xy 26.799138 -412.317999) (xy 26.761921 -412.359536)
			(xy 26.719053 -412.395211) (xy 26.671447 -412.424265) (xy 26.620118 -412.446077) (xy 26.566161 -412.460183)
			(xy 26.510724 -412.466283) (xy 26.45499 -412.464246) (xy 26.400147 -412.454116) (xy 26.347363 -412.436109)
			(xy 26.297763 -412.410608) (xy 26.252405 -412.378157) (xy 26.212256 -412.339448) (xy 26.17817 -412.295305)
			(xy 26.150874 -412.24667) (xy 26.130951 -412.194579) (xy 26.118825 -412.140142) (xy 26.114754 -412.08452)
			(xy 23.166449 -412.08452) (xy 23.183498 -412.088977) (xy 23.234827 -412.110789) (xy 23.282433 -412.139843)
			(xy 23.325301 -412.175518) (xy 23.362518 -412.217055) (xy 23.393291 -412.263568) (xy 23.416963 -412.314065)
			(xy 23.433031 -412.367472) (xy 23.441151 -412.422648) (xy 23.44166 -412.450534) (xy 23.441151 -412.47842)
			(xy 23.433031 -412.533596) (xy 23.416963 -412.587003) (xy 23.393291 -412.6375) (xy 23.362518 -412.684013)
			(xy 23.325301 -412.72555) (xy 23.282433 -412.761225) (xy 23.234827 -412.790279) (xy 23.183498 -412.812091)
			(xy 23.129541 -412.826197) (xy 23.074104 -412.832297) (xy 23.01837 -412.83026) (xy 22.963527 -412.82013)
			(xy 22.910743 -412.802123) (xy 22.861143 -412.776622) (xy 22.815785 -412.744171) (xy 22.775636 -412.705462)
			(xy 22.74155 -412.661319) (xy 22.714254 -412.612684) (xy 22.694331 -412.560593) (xy 22.682205 -412.506156)
			(xy 22.678134 -412.450534) (xy 11.048492 -412.450534) (xy 11.048492 -413.258) (xy 21.131782 -413.258)
			(xy 21.135853 -413.202378) (xy 21.147979 -413.147941) (xy 21.167902 -413.09585) (xy 21.195198 -413.047215)
			(xy 21.229284 -413.003072) (xy 21.269433 -412.964363) (xy 21.314791 -412.931912) (xy 21.364391 -412.906411)
			(xy 21.417175 -412.888404) (xy 21.472018 -412.878274) (xy 21.527752 -412.876237) (xy 21.583189 -412.882337)
			(xy 21.637146 -412.896443) (xy 21.688475 -412.918255) (xy 21.736081 -412.947309) (xy 21.778949 -412.982984)
			(xy 21.816166 -413.024521) (xy 21.846939 -413.071034) (xy 21.870611 -413.121531) (xy 21.886679 -413.174938)
			(xy 21.894799 -413.230114) (xy 21.895308 -413.258) (xy 21.894799 -413.285886) (xy 21.886679 -413.341062)
			(xy 21.870611 -413.394469) (xy 21.846939 -413.444966) (xy 21.816166 -413.491479) (xy 21.795048 -413.515048)
			(xy 26.143202 -413.515048) (xy 26.147273 -413.459426) (xy 26.159399 -413.404989) (xy 26.179322 -413.352898)
			(xy 26.206618 -413.304263) (xy 26.240704 -413.26012) (xy 26.280853 -413.221411) (xy 26.326211 -413.18896)
			(xy 26.375811 -413.163459) (xy 26.428595 -413.145452) (xy 26.483438 -413.135322) (xy 26.539172 -413.133285)
			(xy 26.594609 -413.139385) (xy 26.648566 -413.153491) (xy 26.699895 -413.175303) (xy 26.747501 -413.204357)
			(xy 26.790369 -413.240032) (xy 26.827586 -413.281569) (xy 26.858359 -413.328082) (xy 26.882031 -413.378579)
			(xy 26.898099 -413.431986) (xy 26.906219 -413.487162) (xy 26.906728 -413.515048) (xy 26.906219 -413.542934)
			(xy 26.898099 -413.59811) (xy 26.882031 -413.651517) (xy 26.858359 -413.702014) (xy 26.827586 -413.748527)
			(xy 26.790369 -413.790064) (xy 26.747501 -413.825739) (xy 26.699895 -413.854793) (xy 26.648566 -413.876605)
			(xy 26.594609 -413.890711) (xy 26.539172 -413.896811) (xy 26.483438 -413.894774) (xy 26.428595 -413.884644)
			(xy 26.375811 -413.866637) (xy 26.326211 -413.841136) (xy 26.280853 -413.808685) (xy 26.240704 -413.769976)
			(xy 26.206618 -413.725833) (xy 26.179322 -413.677198) (xy 26.159399 -413.625107) (xy 26.147273 -413.57067)
			(xy 26.143202 -413.515048) (xy 21.795048 -413.515048) (xy 21.778949 -413.533016) (xy 21.736081 -413.568691)
			(xy 21.688475 -413.597745) (xy 21.637146 -413.619557) (xy 21.583189 -413.633663) (xy 21.527752 -413.639763)
			(xy 21.472018 -413.637726) (xy 21.417175 -413.627596) (xy 21.364391 -413.609589) (xy 21.314791 -413.584088)
			(xy 21.269433 -413.551637) (xy 21.229284 -413.512928) (xy 21.195198 -413.468785) (xy 21.167902 -413.42015)
			(xy 21.147979 -413.368059) (xy 21.135853 -413.313622) (xy 21.131782 -413.258) (xy 11.048492 -413.258)
			(xy 11.048492 -414.62579) (xy 26.135582 -414.62579) (xy 26.139653 -414.570168) (xy 26.151779 -414.515731)
			(xy 26.171702 -414.46364) (xy 26.198998 -414.415005) (xy 26.233084 -414.370862) (xy 26.273233 -414.332153)
			(xy 26.318591 -414.299702) (xy 26.368191 -414.274201) (xy 26.420975 -414.256194) (xy 26.475818 -414.246064)
			(xy 26.531552 -414.244027) (xy 26.586989 -414.250127) (xy 26.640946 -414.264233) (xy 26.692275 -414.286045)
			(xy 26.739881 -414.315099) (xy 26.782749 -414.350774) (xy 26.819966 -414.392311) (xy 26.850739 -414.438824)
			(xy 26.874411 -414.489321) (xy 26.890479 -414.542728) (xy 26.898599 -414.597904) (xy 26.899108 -414.62579)
			(xy 26.898599 -414.653676) (xy 26.890479 -414.708852) (xy 26.874411 -414.762259) (xy 26.850739 -414.812756)
			(xy 26.819966 -414.859269) (xy 26.782749 -414.900806) (xy 26.739881 -414.936481) (xy 26.692275 -414.965535)
			(xy 26.640946 -414.987347) (xy 26.586989 -415.001453) (xy 26.531552 -415.007553) (xy 26.475818 -415.005516)
			(xy 26.420975 -414.995386) (xy 26.368191 -414.977379) (xy 26.318591 -414.951878) (xy 26.273233 -414.919427)
			(xy 26.233084 -414.880718) (xy 26.198998 -414.836575) (xy 26.171702 -414.78794) (xy 26.151779 -414.735849)
			(xy 26.139653 -414.681412) (xy 26.135582 -414.62579) (xy 11.048492 -414.62579) (xy 11.048492 -415.127948)
			(xy 22.655274 -415.127948) (xy 22.659345 -415.072326) (xy 22.671471 -415.017889) (xy 22.691394 -414.965798)
			(xy 22.71869 -414.917163) (xy 22.752776 -414.87302) (xy 22.792925 -414.834311) (xy 22.838283 -414.80186)
			(xy 22.887883 -414.776359) (xy 22.940667 -414.758352) (xy 22.99551 -414.748222) (xy 23.051244 -414.746185)
			(xy 23.106681 -414.752285) (xy 23.160638 -414.766391) (xy 23.211967 -414.788203) (xy 23.259573 -414.817257)
			(xy 23.302441 -414.852932) (xy 23.339658 -414.894469) (xy 23.370431 -414.940982) (xy 23.394103 -414.991479)
			(xy 23.410171 -415.044886) (xy 23.418291 -415.100062) (xy 23.4188 -415.127948) (xy 23.418291 -415.155834)
			(xy 23.410171 -415.21101) (xy 23.394103 -415.264417) (xy 23.370431 -415.314914) (xy 23.339658 -415.361427)
			(xy 23.334699 -415.366962) (xy 29.284674 -415.366962) (xy 29.288745 -415.31134) (xy 29.300871 -415.256903)
			(xy 29.320794 -415.204812) (xy 29.34809 -415.156177) (xy 29.382176 -415.112034) (xy 29.422325 -415.073325)
			(xy 29.467683 -415.040874) (xy 29.517283 -415.015373) (xy 29.570067 -414.997366) (xy 29.62491 -414.987236)
			(xy 29.680644 -414.985199) (xy 29.736081 -414.991299) (xy 29.790038 -415.005405) (xy 29.841367 -415.027217)
			(xy 29.888973 -415.056271) (xy 29.931841 -415.091946) (xy 29.969058 -415.133483) (xy 29.999831 -415.179996)
			(xy 30.023503 -415.230493) (xy 30.039571 -415.2839) (xy 30.047691 -415.339076) (xy 30.0482 -415.366962)
			(xy 30.047691 -415.394848) (xy 30.039571 -415.450024) (xy 30.023503 -415.503431) (xy 29.999831 -415.553928)
			(xy 29.969058 -415.600441) (xy 29.931841 -415.641978) (xy 29.888973 -415.677653) (xy 29.841367 -415.706707)
			(xy 29.790038 -415.728519) (xy 29.736081 -415.742625) (xy 29.680644 -415.748725) (xy 29.62491 -415.746688)
			(xy 29.570067 -415.736558) (xy 29.517283 -415.718551) (xy 29.467683 -415.69305) (xy 29.422325 -415.660599)
			(xy 29.382176 -415.62189) (xy 29.34809 -415.577747) (xy 29.320794 -415.529112) (xy 29.300871 -415.477021)
			(xy 29.288745 -415.422584) (xy 29.284674 -415.366962) (xy 23.334699 -415.366962) (xy 23.302441 -415.402964)
			(xy 23.259573 -415.438639) (xy 23.211967 -415.467693) (xy 23.160638 -415.489505) (xy 23.106681 -415.503611)
			(xy 23.051244 -415.509711) (xy 22.99551 -415.507674) (xy 22.940667 -415.497544) (xy 22.887883 -415.479537)
			(xy 22.838283 -415.454036) (xy 22.792925 -415.421585) (xy 22.752776 -415.382876) (xy 22.71869 -415.338733)
			(xy 22.691394 -415.290098) (xy 22.671471 -415.238007) (xy 22.659345 -415.18357) (xy 22.655274 -415.127948)
			(xy 11.048492 -415.127948) (xy 11.048492 -416.143948) (xy 22.655274 -416.143948) (xy 22.659345 -416.088326)
			(xy 22.671471 -416.033889) (xy 22.691394 -415.981798) (xy 22.71869 -415.933163) (xy 22.752776 -415.88902)
			(xy 22.792925 -415.850311) (xy 22.838283 -415.81786) (xy 22.887883 -415.792359) (xy 22.940667 -415.774352)
			(xy 22.99551 -415.764222) (xy 23.051244 -415.762185) (xy 23.106681 -415.768285) (xy 23.160638 -415.782391)
			(xy 23.211967 -415.804203) (xy 23.259573 -415.833257) (xy 23.302441 -415.868932) (xy 23.339658 -415.910469)
			(xy 23.370431 -415.956982) (xy 23.394103 -416.007479) (xy 23.410171 -416.060886) (xy 23.418291 -416.116062)
			(xy 23.4188 -416.143948) (xy 23.418291 -416.171834) (xy 23.410171 -416.22701) (xy 23.394103 -416.280417)
			(xy 23.370431 -416.330914) (xy 23.339658 -416.377427) (xy 23.302441 -416.418964) (xy 23.259573 -416.454639)
			(xy 23.211967 -416.483693) (xy 23.160638 -416.505505) (xy 23.106681 -416.519611) (xy 23.051244 -416.525711)
			(xy 22.99551 -416.523674) (xy 22.940667 -416.513544) (xy 22.887883 -416.495537) (xy 22.838283 -416.470036)
			(xy 22.792925 -416.437585) (xy 22.752776 -416.398876) (xy 22.71869 -416.354733) (xy 22.691394 -416.306098)
			(xy 22.671471 -416.254007) (xy 22.659345 -416.19957) (xy 22.655274 -416.143948) (xy 11.048492 -416.143948)
			(xy 11.048492 -416.83305) (xy 26.115264 -416.83305) (xy 26.115755 -416.805622) (xy 26.123625 -416.751333)
			(xy 26.139181 -416.698728) (xy 26.162102 -416.64889) (xy 26.191919 -416.602844) (xy 26.228016 -416.561538)
			(xy 26.269651 -416.525821) (xy 26.292556 -416.510724) (xy 26.304663 -416.502508) (xy 26.323939 -416.48051)
			(xy 26.336177 -416.453945) (xy 26.340372 -416.424999) (xy 26.336177 -416.396054) (xy 26.323938 -416.369489)
			(xy 26.304662 -416.347492) (xy 26.292556 -416.339274) (xy 26.269645 -416.324181) (xy 26.22799 -416.288479)
			(xy 26.191878 -416.247179) (xy 26.162054 -416.201132) (xy 26.139132 -416.151289) (xy 26.123586 -416.098676)
			(xy 26.115736 -416.044379) (xy 26.115264 -416.016948) (xy 26.11575 -415.989697) (xy 26.123506 -415.935749)
			(xy 26.138861 -415.883454) (xy 26.161503 -415.833877) (xy 26.190969 -415.788027) (xy 26.22666 -415.746836)
			(xy 26.267851 -415.711145) (xy 26.313701 -415.681679) (xy 26.363278 -415.659037) (xy 26.415573 -415.643682)
			(xy 26.469521 -415.635926) (xy 26.524023 -415.635926) (xy 26.577971 -415.643682) (xy 26.630266 -415.659037)
			(xy 26.679843 -415.681679) (xy 26.725693 -415.711145) (xy 26.766884 -415.746836) (xy 26.802575 -415.788027)
			(xy 26.832041 -415.833877) (xy 26.854683 -415.883454) (xy 26.870038 -415.935749) (xy 26.877794 -415.989697)
			(xy 26.87828 -416.016948) (xy 26.877813 -416.044377) (xy 26.869942 -416.098669) (xy 26.854384 -416.151275)
			(xy 26.831459 -416.201114) (xy 26.801639 -416.24716) (xy 26.765536 -416.288465) (xy 26.723895 -416.324179)
			(xy 26.700988 -416.339274) (xy 26.688927 -416.347522) (xy 26.669737 -416.369542) (xy 26.657557 -416.396091)
			(xy 26.653384 -416.424999) (xy 26.657557 -416.453908) (xy 26.669736 -416.480457) (xy 26.688926 -416.502477)
			(xy 26.700988 -416.510724) (xy 26.723908 -416.525803) (xy 26.76556 -416.561509) (xy 26.80167 -416.602813)
			(xy 26.831493 -416.648862) (xy 26.854413 -416.698707) (xy 26.869958 -416.751321) (xy 26.877808 -416.805619)
			(xy 26.87828 -416.83305) (xy 26.877794 -416.860301) (xy 26.870038 -416.914249) (xy 26.854683 -416.966544)
			(xy 26.832041 -417.016121) (xy 26.802575 -417.061971) (xy 26.766884 -417.103162) (xy 26.725693 -417.138853)
			(xy 26.679843 -417.168319) (xy 26.630266 -417.190961) (xy 26.577971 -417.206316) (xy 26.524023 -417.214072)
			(xy 26.469521 -417.214072) (xy 26.415573 -417.206316) (xy 26.363278 -417.190961) (xy 26.313701 -417.168319)
			(xy 26.267851 -417.138853) (xy 26.22666 -417.103162) (xy 26.190969 -417.061971) (xy 26.161503 -417.016121)
			(xy 26.138861 -416.966544) (xy 26.123506 -416.914249) (xy 26.11575 -416.860301) (xy 26.115264 -416.83305)
			(xy 11.048492 -416.83305) (xy 11.048492 -420.794688) (xy 22.58136 -420.794688) (xy 22.585431 -420.739066)
			(xy 22.597557 -420.684629) (xy 22.61748 -420.632538) (xy 22.644776 -420.583903) (xy 22.678862 -420.53976)
			(xy 22.719011 -420.501051) (xy 22.764369 -420.4686) (xy 22.813969 -420.443099) (xy 22.866753 -420.425092)
			(xy 22.921596 -420.414962) (xy 22.97733 -420.412925) (xy 23.032767 -420.419025) (xy 23.086724 -420.433131)
			(xy 23.138053 -420.454943) (xy 23.185659 -420.483997) (xy 23.228527 -420.519672) (xy 23.265744 -420.561209)
			(xy 23.296517 -420.607722) (xy 23.320189 -420.658219) (xy 23.336257 -420.711626) (xy 23.344377 -420.766802)
			(xy 23.344886 -420.794688) (xy 23.344377 -420.822574) (xy 23.336257 -420.87775) (xy 23.320189 -420.931157)
			(xy 23.296517 -420.981654) (xy 23.265744 -421.028167) (xy 23.228527 -421.069704) (xy 23.185659 -421.105379)
			(xy 23.138053 -421.134433) (xy 23.086724 -421.156245) (xy 23.032767 -421.170351) (xy 22.97733 -421.176451)
			(xy 22.921596 -421.174414) (xy 22.866753 -421.164284) (xy 22.813969 -421.146277) (xy 22.764369 -421.120776)
			(xy 22.719011 -421.088325) (xy 22.678862 -421.049616) (xy 22.644776 -421.005473) (xy 22.61748 -420.956838)
			(xy 22.597557 -420.904747) (xy 22.585431 -420.85031) (xy 22.58136 -420.794688) (xy 11.048492 -420.794688)
			(xy 11.048492 -421.196262) (xy 11.049045 -421.211434) (xy 11.057945 -421.240443) (xy 11.074971 -421.265559)
			(xy 11.098623 -421.284568) (xy 11.126813 -421.295793) (xy 11.157058 -421.298245) (xy 11.186688 -421.291707)
			(xy 11.20013 -421.284654) (xy 11.221656 -421.272938) (xy 11.267071 -421.254514) (xy 11.314472 -421.24206)
			(xy 11.363077 -421.235779) (xy 11.387582 -421.235378) (xy 11.414837 -421.23584) (xy 11.468792 -421.243595)
			(xy 11.47541 -421.245538) (xy 13.469872 -421.245538) (xy 13.473943 -421.189916) (xy 13.486069 -421.135479)
			(xy 13.505992 -421.083388) (xy 13.533288 -421.034753) (xy 13.567374 -420.99061) (xy 13.607523 -420.951901)
			(xy 13.652881 -420.91945) (xy 13.702481 -420.893949) (xy 13.755265 -420.875942) (xy 13.810108 -420.865812)
			(xy 13.865842 -420.863775) (xy 13.921279 -420.869875) (xy 13.975236 -420.883981) (xy 14.026565 -420.905793)
			(xy 14.074171 -420.934847) (xy 14.117039 -420.970522) (xy 14.154256 -421.012059) (xy 14.185029 -421.058572)
			(xy 14.208701 -421.109069) (xy 14.224769 -421.162476) (xy 14.232889 -421.217652) (xy 14.233398 -421.245538)
			(xy 14.232889 -421.273424) (xy 14.224769 -421.3286) (xy 14.208701 -421.382007) (xy 14.185029 -421.432504)
			(xy 14.154256 -421.479017) (xy 14.117039 -421.520554) (xy 14.074171 -421.556229) (xy 14.026565 -421.585283)
			(xy 13.975236 -421.607095) (xy 13.921279 -421.621201) (xy 13.865842 -421.627301) (xy 13.810108 -421.625264)
			(xy 13.755265 -421.615134) (xy 13.702481 -421.597127) (xy 13.652881 -421.571626) (xy 13.607523 -421.539175)
			(xy 13.567374 -421.500466) (xy 13.533288 -421.456323) (xy 13.505992 -421.407688) (xy 13.486069 -421.355597)
			(xy 13.473943 -421.30116) (xy 13.469872 -421.245538) (xy 11.47541 -421.245538) (xy 11.521094 -421.25895)
			(xy 11.570678 -421.281592) (xy 11.616535 -421.311061) (xy 11.657731 -421.346756) (xy 11.693428 -421.387951)
			(xy 11.722899 -421.433806) (xy 11.745544 -421.483389) (xy 11.760901 -421.535691) (xy 11.768659 -421.589645)
			(xy 11.768659 -421.644155) (xy 11.760901 -421.698109) (xy 11.745544 -421.750411) (xy 11.722899 -421.799994)
			(xy 11.693428 -421.845849) (xy 11.657731 -421.887044) (xy 11.616535 -421.922739) (xy 11.570678 -421.952208)
			(xy 11.521094 -421.97485) (xy 11.507517 -421.978836) (xy 22.054564 -421.978836) (xy 22.058635 -421.923214)
			(xy 22.070761 -421.868777) (xy 22.090684 -421.816686) (xy 22.11798 -421.768051) (xy 22.152066 -421.723908)
			(xy 22.192215 -421.685199) (xy 22.237573 -421.652748) (xy 22.287173 -421.627247) (xy 22.339957 -421.60924)
			(xy 22.3948 -421.59911) (xy 22.450534 -421.597073) (xy 22.505971 -421.603173) (xy 22.559928 -421.617279)
			(xy 22.611257 -421.639091) (xy 22.658863 -421.668145) (xy 22.701731 -421.70382) (xy 22.738948 -421.745357)
			(xy 22.769721 -421.79187) (xy 22.793393 -421.842367) (xy 22.809461 -421.895774) (xy 22.817581 -421.95095)
			(xy 22.81809 -421.978836) (xy 22.817581 -422.006722) (xy 22.809461 -422.061898) (xy 22.793393 -422.115305)
			(xy 22.769721 -422.165802) (xy 22.738948 -422.212315) (xy 22.701731 -422.253852) (xy 22.658863 -422.289527)
			(xy 22.611257 -422.318581) (xy 22.559928 -422.340393) (xy 22.505971 -422.354499) (xy 22.450534 -422.360599)
			(xy 22.3948 -422.358562) (xy 22.339957 -422.348432) (xy 22.287173 -422.330425) (xy 22.237573 -422.304924)
			(xy 22.192215 -422.272473) (xy 22.152066 -422.233764) (xy 22.11798 -422.189621) (xy 22.090684 -422.140986)
			(xy 22.070761 -422.088895) (xy 22.058635 -422.034458) (xy 22.054564 -421.978836) (xy 11.507517 -421.978836)
			(xy 11.468792 -421.990205) (xy 11.414837 -421.99796) (xy 11.387582 -421.998394) (xy 11.363077 -421.998014)
			(xy 11.314471 -421.991728) (xy 11.267072 -421.979263) (xy 11.221662 -421.960825) (xy 11.20013 -421.949118)
			(xy 11.186661 -421.942135) (xy 11.15705 -421.935603) (xy 11.126826 -421.938054) (xy 11.098653 -421.949271)
			(xy 11.075016 -421.968264) (xy 11.057997 -421.993361) (xy 11.049097 -422.022348) (xy 11.048492 -422.03751)
			(xy 11.048492 -422.44391) (xy 11.554458 -422.44391) (xy 11.558529 -422.388288) (xy 11.570655 -422.333851)
			(xy 11.590578 -422.28176) (xy 11.617874 -422.233125) (xy 11.65196 -422.188982) (xy 11.692109 -422.150273)
			(xy 11.737467 -422.117822) (xy 11.787067 -422.092321) (xy 11.839851 -422.074314) (xy 11.894694 -422.064184)
			(xy 11.950428 -422.062147) (xy 12.005865 -422.068247) (xy 12.059822 -422.082353) (xy 12.111151 -422.104165)
			(xy 12.158757 -422.133219) (xy 12.201625 -422.168894) (xy 12.238842 -422.210431) (xy 12.269615 -422.256944)
			(xy 12.293287 -422.307441) (xy 12.309355 -422.360848) (xy 12.317475 -422.416024) (xy 12.317984 -422.44391)
			(xy 12.317475 -422.471796) (xy 12.309355 -422.526972) (xy 12.29583 -422.571926) (xy 13.455394 -422.571926)
			(xy 13.459465 -422.516304) (xy 13.471591 -422.461867) (xy 13.491514 -422.409776) (xy 13.51881 -422.361141)
			(xy 13.552896 -422.316998) (xy 13.593045 -422.278289) (xy 13.638403 -422.245838) (xy 13.688003 -422.220337)
			(xy 13.740787 -422.20233) (xy 13.79563 -422.1922) (xy 13.851364 -422.190163) (xy 13.906801 -422.196263)
			(xy 13.960758 -422.210369) (xy 14.012087 -422.232181) (xy 14.059693 -422.261235) (xy 14.102561 -422.29691)
			(xy 14.139778 -422.338447) (xy 14.170551 -422.38496) (xy 14.194223 -422.435457) (xy 14.20074 -422.457118)
			(xy 24.927812 -422.457118) (xy 24.931883 -422.401496) (xy 24.944009 -422.347059) (xy 24.963932 -422.294968)
			(xy 24.991228 -422.246333) (xy 25.025314 -422.20219) (xy 25.065463 -422.163481) (xy 25.110821 -422.13103)
			(xy 25.160421 -422.105529) (xy 25.213205 -422.087522) (xy 25.268048 -422.077392) (xy 25.323782 -422.075355)
			(xy 25.379219 -422.081455) (xy 25.433176 -422.095561) (xy 25.484505 -422.117373) (xy 25.532111 -422.146427)
			(xy 25.574979 -422.182102) (xy 25.612196 -422.223639) (xy 25.642969 -422.270152) (xy 25.666641 -422.320649)
			(xy 25.682709 -422.374056) (xy 25.690829 -422.429232) (xy 25.691338 -422.457118) (xy 25.690829 -422.485004)
			(xy 25.682709 -422.54018) (xy 25.666641 -422.593587) (xy 25.642969 -422.644084) (xy 25.612196 -422.690597)
			(xy 25.574979 -422.732134) (xy 25.532111 -422.767809) (xy 25.484505 -422.796863) (xy 25.433176 -422.818675)
			(xy 25.379219 -422.832781) (xy 25.323782 -422.838881) (xy 25.268048 -422.836844) (xy 25.213205 -422.826714)
			(xy 25.160421 -422.808707) (xy 25.110821 -422.783206) (xy 25.065463 -422.750755) (xy 25.025314 -422.712046)
			(xy 24.991228 -422.667903) (xy 24.963932 -422.619268) (xy 24.944009 -422.567177) (xy 24.931883 -422.51274)
			(xy 24.927812 -422.457118) (xy 14.20074 -422.457118) (xy 14.210291 -422.488864) (xy 14.218411 -422.54404)
			(xy 14.21892 -422.571926) (xy 14.218411 -422.599812) (xy 14.210291 -422.654988) (xy 14.194223 -422.708395)
			(xy 14.170551 -422.758892) (xy 14.139778 -422.805405) (xy 14.102561 -422.846942) (xy 14.059693 -422.882617)
			(xy 14.012087 -422.911671) (xy 13.960758 -422.933483) (xy 13.906801 -422.947589) (xy 13.851364 -422.953689)
			(xy 13.79563 -422.951652) (xy 13.740787 -422.941522) (xy 13.688003 -422.923515) (xy 13.638403 -422.898014)
			(xy 13.593045 -422.865563) (xy 13.552896 -422.826854) (xy 13.51881 -422.782711) (xy 13.491514 -422.734076)
			(xy 13.471591 -422.681985) (xy 13.459465 -422.627548) (xy 13.455394 -422.571926) (xy 12.29583 -422.571926)
			(xy 12.293287 -422.580379) (xy 12.269615 -422.630876) (xy 12.238842 -422.677389) (xy 12.201625 -422.718926)
			(xy 12.158757 -422.754601) (xy 12.111151 -422.783655) (xy 12.059822 -422.805467) (xy 12.005865 -422.819573)
			(xy 11.950428 -422.825673) (xy 11.894694 -422.823636) (xy 11.839851 -422.813506) (xy 11.787067 -422.795499)
			(xy 11.737467 -422.769998) (xy 11.692109 -422.737547) (xy 11.65196 -422.698838) (xy 11.617874 -422.654695)
			(xy 11.590578 -422.60606) (xy 11.570655 -422.553969) (xy 11.558529 -422.499532) (xy 11.554458 -422.44391)
			(xy 11.048492 -422.44391) (xy 11.048492 -423.756328) (xy 24.916382 -423.756328) (xy 24.920453 -423.700706)
			(xy 24.932579 -423.646269) (xy 24.952502 -423.594178) (xy 24.979798 -423.545543) (xy 25.013884 -423.5014)
			(xy 25.054033 -423.462691) (xy 25.099391 -423.43024) (xy 25.148991 -423.404739) (xy 25.201775 -423.386732)
			(xy 25.256618 -423.376602) (xy 25.312352 -423.374565) (xy 25.367789 -423.380665) (xy 25.421746 -423.394771)
			(xy 25.473075 -423.416583) (xy 25.520681 -423.445637) (xy 25.563549 -423.481312) (xy 25.600766 -423.522849)
			(xy 25.631539 -423.569362) (xy 25.655211 -423.619859) (xy 25.671279 -423.673266) (xy 25.679399 -423.728442)
			(xy 25.679908 -423.756328) (xy 25.679399 -423.784214) (xy 25.671279 -423.83939) (xy 25.655211 -423.892797)
			(xy 25.631539 -423.943294) (xy 25.600766 -423.989807) (xy 25.563549 -424.031344) (xy 25.520681 -424.067019)
			(xy 25.473075 -424.096073) (xy 25.421746 -424.117885) (xy 25.367789 -424.131991) (xy 25.312352 -424.138091)
			(xy 25.256618 -424.136054) (xy 25.201775 -424.125924) (xy 25.148991 -424.107917) (xy 25.099391 -424.082416)
			(xy 25.054033 -424.049965) (xy 25.013884 -424.011256) (xy 24.979798 -423.967113) (xy 24.952502 -423.918478)
			(xy 24.932579 -423.866387) (xy 24.920453 -423.81195) (xy 24.916382 -423.756328) (xy 11.048492 -423.756328)
			(xy 11.048492 -424.883834) (xy 11.878308 -424.883834) (xy 11.882379 -424.828212) (xy 11.894505 -424.773775)
			(xy 11.914428 -424.721684) (xy 11.941724 -424.673049) (xy 11.97581 -424.628906) (xy 12.015959 -424.590197)
			(xy 12.061317 -424.557746) (xy 12.110917 -424.532245) (xy 12.163701 -424.514238) (xy 12.218544 -424.504108)
			(xy 12.274278 -424.502071) (xy 12.329715 -424.508171) (xy 12.383672 -424.522277) (xy 12.435001 -424.544089)
			(xy 12.482607 -424.573143) (xy 12.525475 -424.608818) (xy 12.562692 -424.650355) (xy 12.564408 -424.652948)
			(xy 13.164564 -424.652948) (xy 13.168635 -424.597326) (xy 13.180761 -424.542889) (xy 13.200684 -424.490798)
			(xy 13.22798 -424.442163) (xy 13.262066 -424.39802) (xy 13.302215 -424.359311) (xy 13.347573 -424.32686)
			(xy 13.397173 -424.301359) (xy 13.449957 -424.283352) (xy 13.5048 -424.273222) (xy 13.560534 -424.271185)
			(xy 13.567468 -424.271948) (xy 31.925512 -424.271948) (xy 31.929583 -424.216326) (xy 31.941709 -424.161889)
			(xy 31.961632 -424.109798) (xy 31.988928 -424.061163) (xy 32.023014 -424.01702) (xy 32.063163 -423.978311)
			(xy 32.108521 -423.94586) (xy 32.158121 -423.920359) (xy 32.210905 -423.902352) (xy 32.265748 -423.892222)
			(xy 32.321482 -423.890185) (xy 32.376919 -423.896285) (xy 32.430876 -423.910391) (xy 32.482205 -423.932203)
			(xy 32.529811 -423.961257) (xy 32.572679 -423.996932) (xy 32.609896 -424.038469) (xy 32.640669 -424.084982)
			(xy 32.664341 -424.135479) (xy 32.680409 -424.188886) (xy 32.688529 -424.244062) (xy 32.689038 -424.271948)
			(xy 32.688529 -424.299834) (xy 32.680409 -424.35501) (xy 32.664341 -424.408417) (xy 32.640669 -424.458914)
			(xy 32.609896 -424.505427) (xy 32.572679 -424.546964) (xy 32.529811 -424.582639) (xy 32.482205 -424.611693)
			(xy 32.430876 -424.633505) (xy 32.376919 -424.647611) (xy 32.321482 -424.653711) (xy 32.265748 -424.651674)
			(xy 32.210905 -424.641544) (xy 32.158121 -424.623537) (xy 32.108521 -424.598036) (xy 32.063163 -424.565585)
			(xy 32.023014 -424.526876) (xy 31.988928 -424.482733) (xy 31.961632 -424.434098) (xy 31.941709 -424.382007)
			(xy 31.929583 -424.32757) (xy 31.925512 -424.271948) (xy 13.567468 -424.271948) (xy 13.615971 -424.277285)
			(xy 13.669928 -424.291391) (xy 13.721257 -424.313203) (xy 13.768863 -424.342257) (xy 13.811731 -424.377932)
			(xy 13.848948 -424.419469) (xy 13.879721 -424.465982) (xy 13.903393 -424.516479) (xy 13.919461 -424.569886)
			(xy 13.927581 -424.625062) (xy 13.92809 -424.652948) (xy 13.927581 -424.680834) (xy 13.919461 -424.73601)
			(xy 13.903393 -424.789417) (xy 13.879721 -424.839914) (xy 13.848948 -424.886427) (xy 13.811731 -424.927964)
			(xy 13.768863 -424.963639) (xy 13.721257 -424.992693) (xy 13.669928 -425.014505) (xy 13.615971 -425.028611)
			(xy 13.560534 -425.034711) (xy 13.5048 -425.032674) (xy 13.449957 -425.022544) (xy 13.397173 -425.004537)
			(xy 13.347573 -424.979036) (xy 13.302215 -424.946585) (xy 13.262066 -424.907876) (xy 13.22798 -424.863733)
			(xy 13.200684 -424.815098) (xy 13.180761 -424.763007) (xy 13.168635 -424.70857) (xy 13.164564 -424.652948)
			(xy 12.564408 -424.652948) (xy 12.593465 -424.696868) (xy 12.617137 -424.747365) (xy 12.633205 -424.800772)
			(xy 12.641325 -424.855948) (xy 12.641834 -424.883834) (xy 12.641325 -424.91172) (xy 12.633205 -424.966896)
			(xy 12.617137 -425.020303) (xy 12.593465 -425.0708) (xy 12.562692 -425.117313) (xy 12.525475 -425.15885)
			(xy 12.482607 -425.194525) (xy 12.435001 -425.223579) (xy 12.383672 -425.245391) (xy 12.329715 -425.259497)
			(xy 12.325071 -425.260008) (xy 18.371564 -425.260008) (xy 18.375635 -425.204386) (xy 18.387761 -425.149949)
			(xy 18.407684 -425.097858) (xy 18.43498 -425.049223) (xy 18.469066 -425.00508) (xy 18.509215 -424.966371)
			(xy 18.554573 -424.93392) (xy 18.604173 -424.908419) (xy 18.656957 -424.890412) (xy 18.7118 -424.880282)
			(xy 18.767534 -424.878245) (xy 18.822971 -424.884345) (xy 18.876928 -424.898451) (xy 18.928257 -424.920263)
			(xy 18.975863 -424.949317) (xy 19.018731 -424.984992) (xy 19.055948 -425.026529) (xy 19.086721 -425.073042)
			(xy 19.110393 -425.123539) (xy 19.126461 -425.176946) (xy 19.134581 -425.232122) (xy 19.13509 -425.260008)
			(xy 19.134581 -425.287894) (xy 19.128443 -425.329604) (xy 20.403564 -425.329604) (xy 20.407635 -425.273982)
			(xy 20.419761 -425.219545) (xy 20.439684 -425.167454) (xy 20.46698 -425.118819) (xy 20.501066 -425.074676)
			(xy 20.541215 -425.035967) (xy 20.586573 -425.003516) (xy 20.636173 -424.978015) (xy 20.688957 -424.960008)
			(xy 20.7438 -424.949878) (xy 20.799534 -424.947841) (xy 20.854971 -424.953941) (xy 20.908928 -424.968047)
			(xy 20.960257 -424.989859) (xy 21.007863 -425.018913) (xy 21.050731 -425.054588) (xy 21.087948 -425.096125)
			(xy 21.118721 -425.142638) (xy 21.142393 -425.193135) (xy 21.158461 -425.246542) (xy 21.164555 -425.287948)
			(xy 32.179512 -425.287948) (xy 32.183583 -425.232326) (xy 32.195709 -425.177889) (xy 32.215632 -425.125798)
			(xy 32.242928 -425.077163) (xy 32.277014 -425.03302) (xy 32.317163 -424.994311) (xy 32.362521 -424.96186)
			(xy 32.412121 -424.936359) (xy 32.464905 -424.918352) (xy 32.519748 -424.908222) (xy 32.575482 -424.906185)
			(xy 32.630919 -424.912285) (xy 32.684876 -424.926391) (xy 32.736205 -424.948203) (xy 32.783811 -424.977257)
			(xy 32.826679 -425.012932) (xy 32.863896 -425.054469) (xy 32.894669 -425.100982) (xy 32.918341 -425.151479)
			(xy 32.934409 -425.204886) (xy 32.942529 -425.260062) (xy 32.943038 -425.287948) (xy 32.942529 -425.315834)
			(xy 32.934409 -425.37101) (xy 32.918341 -425.424417) (xy 32.894669 -425.474914) (xy 32.863896 -425.521427)
			(xy 32.826679 -425.562964) (xy 32.783811 -425.598639) (xy 32.736205 -425.627693) (xy 32.684876 -425.649505)
			(xy 32.630919 -425.663611) (xy 32.575482 -425.669711) (xy 32.519748 -425.667674) (xy 32.464905 -425.657544)
			(xy 32.412121 -425.639537) (xy 32.362521 -425.614036) (xy 32.317163 -425.581585) (xy 32.277014 -425.542876)
			(xy 32.242928 -425.498733) (xy 32.215632 -425.450098) (xy 32.195709 -425.398007) (xy 32.183583 -425.34357)
			(xy 32.179512 -425.287948) (xy 21.164555 -425.287948) (xy 21.166581 -425.301718) (xy 21.16709 -425.329604)
			(xy 21.166581 -425.35749) (xy 21.158461 -425.412666) (xy 21.142393 -425.466073) (xy 21.118721 -425.51657)
			(xy 21.087948 -425.563083) (xy 21.050731 -425.60462) (xy 21.007863 -425.640295) (xy 20.960257 -425.669349)
			(xy 20.908928 -425.691161) (xy 20.854971 -425.705267) (xy 20.799534 -425.711367) (xy 20.7438 -425.70933)
			(xy 20.688957 -425.6992) (xy 20.636173 -425.681193) (xy 20.586573 -425.655692) (xy 20.541215 -425.623241)
			(xy 20.501066 -425.584532) (xy 20.46698 -425.540389) (xy 20.439684 -425.491754) (xy 20.419761 -425.439663)
			(xy 20.407635 -425.385226) (xy 20.403564 -425.329604) (xy 19.128443 -425.329604) (xy 19.126461 -425.34307)
			(xy 19.110393 -425.396477) (xy 19.086721 -425.446974) (xy 19.055948 -425.493487) (xy 19.018731 -425.535024)
			(xy 18.975863 -425.570699) (xy 18.928257 -425.599753) (xy 18.876928 -425.621565) (xy 18.822971 -425.635671)
			(xy 18.767534 -425.641771) (xy 18.7118 -425.639734) (xy 18.656957 -425.629604) (xy 18.604173 -425.611597)
			(xy 18.554573 -425.586096) (xy 18.509215 -425.553645) (xy 18.469066 -425.514936) (xy 18.43498 -425.470793)
			(xy 18.407684 -425.422158) (xy 18.387761 -425.370067) (xy 18.375635 -425.31563) (xy 18.371564 -425.260008)
			(xy 12.325071 -425.260008) (xy 12.274278 -425.265597) (xy 12.218544 -425.26356) (xy 12.163701 -425.25343)
			(xy 12.110917 -425.235423) (xy 12.061317 -425.209922) (xy 12.015959 -425.177471) (xy 11.97581 -425.138762)
			(xy 11.941724 -425.094619) (xy 11.914428 -425.045984) (xy 11.894505 -424.993893) (xy 11.882379 -424.939456)
			(xy 11.878308 -424.883834) (xy 11.048492 -424.883834) (xy 11.048492 -424.895518) (xy 12.37361 -426.220636)
			(xy 12.384521 -426.23083) (xy 12.41081 -426.24496) (xy 12.440061 -426.250888) (xy 12.469777 -426.248105)
			(xy 12.497419 -426.236851) (xy 12.520628 -426.218087) (xy 12.537421 -426.193414) (xy 12.546365 -426.16494)
			(xy 12.547092 -426.150024) (xy 12.547901 -426.122998) (xy 12.556206 -426.069572) (xy 12.571972 -426.017854)
			(xy 12.594883 -425.96888) (xy 12.62448 -425.923632) (xy 12.66017 -425.883018) (xy 12.701238 -425.84785)
			(xy 12.74686 -425.818833) (xy 12.796122 -425.79655) (xy 12.848038 -425.781447) (xy 12.901566 -425.773826)
			(xy 12.9286 -425.773342) (xy 12.955852 -425.773805) (xy 13.0098 -425.781563) (xy 13.062095 -425.796919)
			(xy 13.111672 -425.819562) (xy 13.157521 -425.849031) (xy 13.19871 -425.884726) (xy 13.234399 -425.925919)
			(xy 13.263862 -425.971772) (xy 13.286498 -426.021352) (xy 13.301848 -426.073649) (xy 13.309598 -426.127598)
			(xy 13.310108 -426.15485) (xy 13.309635 -426.181882) (xy 13.301997 -426.235405) (xy 13.286881 -426.287314)
			(xy 13.26459 -426.33657) (xy 13.235571 -426.382186) (xy 13.200403 -426.423251) (xy 13.159792 -426.45894)
			(xy 13.11455 -426.48854) (xy 13.065583 -426.511459) (xy 13.013871 -426.527236) (xy 12.96045 -426.535557)
			(xy 12.950565 -426.53585) (xy 14.432532 -426.53585) (xy 14.436603 -426.480228) (xy 14.448729 -426.425791)
			(xy 14.468652 -426.3737) (xy 14.495948 -426.325065) (xy 14.530034 -426.280922) (xy 14.570183 -426.242213)
			(xy 14.615541 -426.209762) (xy 14.665141 -426.184261) (xy 14.717925 -426.166254) (xy 14.772768 -426.156124)
			(xy 14.828502 -426.154087) (xy 14.883939 -426.160187) (xy 14.937896 -426.174293) (xy 14.989225 -426.196105)
			(xy 15.036831 -426.225159) (xy 15.079699 -426.260834) (xy 15.116916 -426.302371) (xy 15.147689 -426.348884)
			(xy 15.152819 -426.359828) (xy 17.355564 -426.359828) (xy 17.359635 -426.304206) (xy 17.371761 -426.249769)
			(xy 17.391684 -426.197678) (xy 17.41898 -426.149043) (xy 17.453066 -426.1049) (xy 17.493215 -426.066191)
			(xy 17.538573 -426.03374) (xy 17.588173 -426.008239) (xy 17.640957 -425.990232) (xy 17.6958 -425.980102)
			(xy 17.751534 -425.978065) (xy 17.806971 -425.984165) (xy 17.860928 -425.998271) (xy 17.912257 -426.020083)
			(xy 17.959863 -426.049137) (xy 18.002731 -426.084812) (xy 18.039948 -426.126349) (xy 18.070721 -426.172862)
			(xy 18.094393 -426.223359) (xy 18.110461 -426.276766) (xy 18.118581 -426.331942) (xy 18.11909 -426.359828)
			(xy 18.118581 -426.387714) (xy 18.110723 -426.441108) (xy 19.387564 -426.441108) (xy 19.391635 -426.385486)
			(xy 19.403761 -426.331049) (xy 19.423684 -426.278958) (xy 19.45098 -426.230323) (xy 19.485066 -426.18618)
			(xy 19.525215 -426.147471) (xy 19.570573 -426.11502) (xy 19.620173 -426.089519) (xy 19.672957 -426.071512)
			(xy 19.7278 -426.061382) (xy 19.783534 -426.059345) (xy 19.838971 -426.065445) (xy 19.892928 -426.079551)
			(xy 19.944257 -426.101363) (xy 19.991863 -426.130417) (xy 20.034731 -426.166092) (xy 20.071948 -426.207629)
			(xy 20.102721 -426.254142) (xy 20.126393 -426.304639) (xy 20.142461 -426.358046) (xy 20.150581 -426.413222)
			(xy 20.15109 -426.441108) (xy 20.150581 -426.468994) (xy 20.142461 -426.52417) (xy 20.126393 -426.577577)
			(xy 20.102721 -426.628074) (xy 20.071948 -426.674587) (xy 20.034731 -426.716124) (xy 19.991863 -426.751799)
			(xy 19.944257 -426.780853) (xy 19.915912 -426.792898) (xy 29.391862 -426.792898) (xy 29.395933 -426.737276)
			(xy 29.408059 -426.682839) (xy 29.427982 -426.630748) (xy 29.455278 -426.582113) (xy 29.489364 -426.53797)
			(xy 29.529513 -426.499261) (xy 29.574871 -426.46681) (xy 29.624471 -426.441309) (xy 29.677255 -426.423302)
			(xy 29.732098 -426.413172) (xy 29.787832 -426.411135) (xy 29.843269 -426.417235) (xy 29.897226 -426.431341)
			(xy 29.948555 -426.453153) (xy 29.996161 -426.482207) (xy 30.039029 -426.517882) (xy 30.076246 -426.559419)
			(xy 30.107019 -426.605932) (xy 30.130691 -426.656429) (xy 30.146759 -426.709836) (xy 30.154879 -426.765012)
			(xy 30.155388 -426.792898) (xy 30.154879 -426.820784) (xy 30.146759 -426.87596) (xy 30.130691 -426.929367)
			(xy 30.107019 -426.979864) (xy 30.076246 -427.026377) (xy 30.039029 -427.067914) (xy 29.996161 -427.103589)
			(xy 29.948555 -427.132643) (xy 29.897226 -427.154455) (xy 29.843269 -427.168561) (xy 29.787832 -427.174661)
			(xy 29.732098 -427.172624) (xy 29.677255 -427.162494) (xy 29.624471 -427.144487) (xy 29.574871 -427.118986)
			(xy 29.529513 -427.086535) (xy 29.489364 -427.047826) (xy 29.455278 -427.003683) (xy 29.427982 -426.955048)
			(xy 29.408059 -426.902957) (xy 29.395933 -426.84852) (xy 29.391862 -426.792898) (xy 19.915912 -426.792898)
			(xy 19.892928 -426.802665) (xy 19.838971 -426.816771) (xy 19.783534 -426.822871) (xy 19.7278 -426.820834)
			(xy 19.672957 -426.810704) (xy 19.620173 -426.792697) (xy 19.570573 -426.767196) (xy 19.525215 -426.734745)
			(xy 19.485066 -426.696036) (xy 19.45098 -426.651893) (xy 19.423684 -426.603258) (xy 19.403761 -426.551167)
			(xy 19.391635 -426.49673) (xy 19.387564 -426.441108) (xy 18.110723 -426.441108) (xy 18.110461 -426.44289)
			(xy 18.094393 -426.496297) (xy 18.070721 -426.546794) (xy 18.039948 -426.593307) (xy 18.002731 -426.634844)
			(xy 17.959863 -426.670519) (xy 17.912257 -426.699573) (xy 17.860928 -426.721385) (xy 17.806971 -426.735491)
			(xy 17.751534 -426.741591) (xy 17.6958 -426.739554) (xy 17.640957 -426.729424) (xy 17.588173 -426.711417)
			(xy 17.538573 -426.685916) (xy 17.493215 -426.653465) (xy 17.453066 -426.614756) (xy 17.41898 -426.570613)
			(xy 17.391684 -426.521978) (xy 17.371761 -426.469887) (xy 17.359635 -426.41545) (xy 17.355564 -426.359828)
			(xy 15.152819 -426.359828) (xy 15.171361 -426.399381) (xy 15.187429 -426.452788) (xy 15.195549 -426.507964)
			(xy 15.196058 -426.53585) (xy 15.195549 -426.563736) (xy 15.187429 -426.618912) (xy 15.171361 -426.672319)
			(xy 15.147689 -426.722816) (xy 15.116916 -426.769329) (xy 15.079699 -426.810866) (xy 15.036831 -426.846541)
			(xy 14.989225 -426.875595) (xy 14.937896 -426.897407) (xy 14.883939 -426.911513) (xy 14.828502 -426.917613)
			(xy 14.772768 -426.915576) (xy 14.717925 -426.905446) (xy 14.665141 -426.887439) (xy 14.615541 -426.861938)
			(xy 14.570183 -426.829487) (xy 14.530034 -426.790778) (xy 14.495948 -426.746635) (xy 14.468652 -426.698)
			(xy 14.448729 -426.645909) (xy 14.436603 -426.591472) (xy 14.432532 -426.53585) (xy 12.950565 -426.53585)
			(xy 12.933426 -426.536358) (xy 12.918493 -426.537026) (xy 12.889977 -426.545948) (xy 12.865265 -426.562741)
			(xy 12.846471 -426.585968) (xy 12.835203 -426.61364) (xy 12.832427 -426.643389) (xy 12.838381 -426.672669)
			(xy 12.852554 -426.698971) (xy 12.862814 -426.70984) (xy 13.355574 -427.2026) (xy 16.127982 -427.2026)
			(xy 16.132053 -427.146978) (xy 16.144179 -427.092541) (xy 16.164102 -427.04045) (xy 16.191398 -426.991815)
			(xy 16.225484 -426.947672) (xy 16.265633 -426.908963) (xy 16.310991 -426.876512) (xy 16.360591 -426.851011)
			(xy 16.413375 -426.833004) (xy 16.468218 -426.822874) (xy 16.523952 -426.820837) (xy 16.579389 -426.826937)
			(xy 16.633346 -426.841043) (xy 16.684675 -426.862855) (xy 16.732281 -426.891909) (xy 16.775149 -426.927584)
			(xy 16.812366 -426.969121) (xy 16.843139 -427.015634) (xy 16.866811 -427.066131) (xy 16.882879 -427.119538)
			(xy 16.890999 -427.174714) (xy 16.891508 -427.2026) (xy 16.890999 -427.230486) (xy 16.882879 -427.285662)
			(xy 16.866811 -427.339069) (xy 16.843139 -427.389566) (xy 16.812366 -427.436079) (xy 16.775149 -427.477616)
			(xy 16.741801 -427.505368) (xy 21.469602 -427.505368) (xy 21.473673 -427.449746) (xy 21.485799 -427.395309)
			(xy 21.505722 -427.343218) (xy 21.533018 -427.294583) (xy 21.567104 -427.25044) (xy 21.607253 -427.211731)
			(xy 21.652611 -427.17928) (xy 21.702211 -427.153779) (xy 21.754995 -427.135772) (xy 21.809838 -427.125642)
			(xy 21.865572 -427.123605) (xy 21.921009 -427.129705) (xy 21.974966 -427.143811) (xy 22.026295 -427.165623)
			(xy 22.064409 -427.188884) (xy 31.315912 -427.188884) (xy 31.319983 -427.133262) (xy 31.332109 -427.078825)
			(xy 31.352032 -427.026734) (xy 31.379328 -426.978099) (xy 31.413414 -426.933956) (xy 31.453563 -426.895247)
			(xy 31.498921 -426.862796) (xy 31.548521 -426.837295) (xy 31.601305 -426.819288) (xy 31.656148 -426.809158)
			(xy 31.711882 -426.807121) (xy 31.767319 -426.813221) (xy 31.821276 -426.827327) (xy 31.872605 -426.849139)
			(xy 31.920211 -426.878193) (xy 31.963079 -426.913868) (xy 32.000296 -426.955405) (xy 32.031069 -427.001918)
			(xy 32.054741 -427.052415) (xy 32.070809 -427.105822) (xy 32.078929 -427.160998) (xy 32.079438 -427.188884)
			(xy 32.078929 -427.21677) (xy 32.070809 -427.271946) (xy 32.054741 -427.325353) (xy 32.031069 -427.37585)
			(xy 32.000296 -427.422363) (xy 31.963079 -427.4639) (xy 31.920211 -427.499575) (xy 31.872605 -427.528629)
			(xy 31.821276 -427.550441) (xy 31.767319 -427.564547) (xy 31.711882 -427.570647) (xy 31.656148 -427.56861)
			(xy 31.601305 -427.55848) (xy 31.548521 -427.540473) (xy 31.498921 -427.514972) (xy 31.453563 -427.482521)
			(xy 31.413414 -427.443812) (xy 31.379328 -427.399669) (xy 31.352032 -427.351034) (xy 31.332109 -427.298943)
			(xy 31.319983 -427.244506) (xy 31.315912 -427.188884) (xy 22.064409 -427.188884) (xy 22.073901 -427.194677)
			(xy 22.116769 -427.230352) (xy 22.153986 -427.271889) (xy 22.184759 -427.318402) (xy 22.208431 -427.368899)
			(xy 22.224499 -427.422306) (xy 22.232619 -427.477482) (xy 22.233128 -427.505368) (xy 22.232619 -427.533254)
			(xy 22.224499 -427.58843) (xy 22.208431 -427.641837) (xy 22.184759 -427.692334) (xy 22.153986 -427.738847)
			(xy 22.116769 -427.780384) (xy 22.073901 -427.816059) (xy 22.026295 -427.845113) (xy 21.974966 -427.866925)
			(xy 21.921009 -427.881031) (xy 21.865572 -427.887131) (xy 21.809838 -427.885094) (xy 21.754995 -427.874964)
			(xy 21.702211 -427.856957) (xy 21.652611 -427.831456) (xy 21.607253 -427.799005) (xy 21.567104 -427.760296)
			(xy 21.533018 -427.716153) (xy 21.505722 -427.667518) (xy 21.485799 -427.615427) (xy 21.473673 -427.56099)
			(xy 21.469602 -427.505368) (xy 16.741801 -427.505368) (xy 16.732281 -427.513291) (xy 16.684675 -427.542345)
			(xy 16.633346 -427.564157) (xy 16.579389 -427.578263) (xy 16.523952 -427.584363) (xy 16.468218 -427.582326)
			(xy 16.413375 -427.572196) (xy 16.360591 -427.554189) (xy 16.310991 -427.528688) (xy 16.265633 -427.496237)
			(xy 16.225484 -427.457528) (xy 16.191398 -427.413385) (xy 16.164102 -427.36475) (xy 16.144179 -427.312659)
			(xy 16.132053 -427.258222) (xy 16.127982 -427.2026) (xy 13.355574 -427.2026) (xy 14.554962 -428.401988)
			(xy 23.549862 -428.401988) (xy 23.553933 -428.346366) (xy 23.566059 -428.291929) (xy 23.585982 -428.239838)
			(xy 23.613278 -428.191203) (xy 23.647364 -428.14706) (xy 23.687513 -428.108351) (xy 23.732871 -428.0759)
			(xy 23.782471 -428.050399) (xy 23.835255 -428.032392) (xy 23.890098 -428.022262) (xy 23.945832 -428.020225)
			(xy 24.001269 -428.026325) (xy 24.055226 -428.040431) (xy 24.106555 -428.062243) (xy 24.154161 -428.091297)
			(xy 24.197029 -428.126972) (xy 24.234246 -428.168509) (xy 24.265019 -428.215022) (xy 24.288691 -428.265519)
			(xy 24.304759 -428.318926) (xy 24.312879 -428.374102) (xy 24.313388 -428.401988) (xy 24.312879 -428.429874)
			(xy 24.304759 -428.48505) (xy 24.288691 -428.538457) (xy 24.265019 -428.588954) (xy 24.234246 -428.635467)
			(xy 24.197029 -428.677004) (xy 24.154161 -428.712679) (xy 24.122611 -428.731934) (xy 25.013412 -428.731934)
			(xy 25.013954 -428.703778) (xy 25.022247 -428.648078) (xy 25.038643 -428.594205) (xy 25.062786 -428.543329)
			(xy 25.094149 -428.496558) (xy 25.112726 -428.475394) (xy 25.122448 -428.463884) (xy 25.135404 -428.436707)
			(xy 25.139859 -428.40693) (xy 25.135422 -428.377151) (xy 25.122482 -428.349966) (xy 25.112726 -428.338488)
			(xy 25.094175 -428.317302) (xy 25.062819 -428.27053) (xy 25.038674 -428.219659) (xy 25.022262 -428.165794)
			(xy 25.01394 -428.110103) (xy 25.013412 -428.081948) (xy 25.013898 -428.054697) (xy 25.021654 -428.000749)
			(xy 25.037009 -427.948454) (xy 25.059651 -427.898877) (xy 25.089117 -427.853027) (xy 25.124808 -427.811836)
			(xy 25.165999 -427.776145) (xy 25.211849 -427.746679) (xy 25.261426 -427.724037) (xy 25.313721 -427.708682)
			(xy 25.367669 -427.700926) (xy 25.422171 -427.700926) (xy 25.476119 -427.708682) (xy 25.528414 -427.724037)
			(xy 25.577991 -427.746679) (xy 25.623841 -427.776145) (xy 25.665032 -427.811836) (xy 25.700723 -427.853027)
			(xy 25.730189 -427.898877) (xy 25.752831 -427.948454) (xy 25.768186 -428.000749) (xy 25.775942 -428.054697)
			(xy 25.776428 -428.081948) (xy 25.77595 -428.110107) (xy 25.767644 -428.16581) (xy 25.751234 -428.219684)
			(xy 25.727077 -428.270559) (xy 25.695699 -428.317326) (xy 25.677114 -428.338488) (xy 25.667366 -428.349959)
			(xy 25.654503 -428.377163) (xy 25.650095 -428.406931) (xy 25.654521 -428.436695) (xy 25.6674 -428.463892)
			(xy 25.677114 -428.475394) (xy 25.69571 -428.496542) (xy 25.727058 -428.543325) (xy 25.751194 -428.594205)
			(xy 25.767595 -428.648079) (xy 25.775906 -428.703777) (xy 25.776428 -428.731934) (xy 25.775942 -428.759185)
			(xy 25.768186 -428.813133) (xy 25.759138 -428.843948) (xy 31.925512 -428.843948) (xy 31.929583 -428.788326)
			(xy 31.941709 -428.733889) (xy 31.961632 -428.681798) (xy 31.988928 -428.633163) (xy 32.023014 -428.58902)
			(xy 32.063163 -428.550311) (xy 32.108521 -428.51786) (xy 32.158121 -428.492359) (xy 32.210905 -428.474352)
			(xy 32.265748 -428.464222) (xy 32.321482 -428.462185) (xy 32.376919 -428.468285) (xy 32.430876 -428.482391)
			(xy 32.482205 -428.504203) (xy 32.529811 -428.533257) (xy 32.572679 -428.568932) (xy 32.609896 -428.610469)
			(xy 32.640669 -428.656982) (xy 32.664341 -428.707479) (xy 32.680409 -428.760886) (xy 32.688529 -428.816062)
			(xy 32.689038 -428.843948) (xy 32.688529 -428.871834) (xy 32.680409 -428.92701) (xy 32.664341 -428.980417)
			(xy 32.640669 -429.030914) (xy 32.609896 -429.077427) (xy 32.572679 -429.118964) (xy 32.529811 -429.154639)
			(xy 32.482205 -429.183693) (xy 32.430876 -429.205505) (xy 32.376919 -429.219611) (xy 32.321482 -429.225711)
			(xy 32.265748 -429.223674) (xy 32.210905 -429.213544) (xy 32.158121 -429.195537) (xy 32.108521 -429.170036)
			(xy 32.063163 -429.137585) (xy 32.023014 -429.098876) (xy 31.988928 -429.054733) (xy 31.961632 -429.006098)
			(xy 31.941709 -428.954007) (xy 31.929583 -428.89957) (xy 31.925512 -428.843948) (xy 25.759138 -428.843948)
			(xy 25.752831 -428.865428) (xy 25.730189 -428.915005) (xy 25.700723 -428.960855) (xy 25.665032 -429.002046)
			(xy 25.623841 -429.037737) (xy 25.577991 -429.067203) (xy 25.528414 -429.089845) (xy 25.476119 -429.1052)
			(xy 25.422171 -429.112956) (xy 25.367669 -429.112956) (xy 25.313721 -429.1052) (xy 25.261426 -429.089845)
			(xy 25.211849 -429.067203) (xy 25.165999 -429.037737) (xy 25.124808 -429.002046) (xy 25.089117 -428.960855)
			(xy 25.059651 -428.915005) (xy 25.037009 -428.865428) (xy 25.021654 -428.813133) (xy 25.013898 -428.759185)
			(xy 25.013412 -428.731934) (xy 24.122611 -428.731934) (xy 24.106555 -428.741733) (xy 24.055226 -428.763545)
			(xy 24.001269 -428.777651) (xy 23.945832 -428.783751) (xy 23.890098 -428.781714) (xy 23.835255 -428.771584)
			(xy 23.782471 -428.753577) (xy 23.732871 -428.728076) (xy 23.687513 -428.695625) (xy 23.647364 -428.656916)
			(xy 23.613278 -428.612773) (xy 23.585982 -428.564138) (xy 23.566059 -428.512047) (xy 23.553933 -428.45761)
			(xy 23.549862 -428.401988) (xy 14.554962 -428.401988) (xy 15.250922 -429.097948) (xy 18.37131 -429.097948)
			(xy 18.375381 -429.042326) (xy 18.387507 -428.987889) (xy 18.40743 -428.935798) (xy 18.434726 -428.887163)
			(xy 18.468812 -428.84302) (xy 18.508961 -428.804311) (xy 18.554319 -428.77186) (xy 18.603919 -428.746359)
			(xy 18.656703 -428.728352) (xy 18.711546 -428.718222) (xy 18.76728 -428.716185) (xy 18.822717 -428.722285)
			(xy 18.876674 -428.736391) (xy 18.928003 -428.758203) (xy 18.975609 -428.787257) (xy 19.018477 -428.822932)
			(xy 19.055694 -428.864469) (xy 19.086467 -428.910982) (xy 19.110139 -428.961479) (xy 19.126207 -429.014886)
			(xy 19.130955 -429.047148) (xy 19.387564 -429.047148) (xy 19.391635 -428.991526) (xy 19.403761 -428.937089)
			(xy 19.423684 -428.884998) (xy 19.45098 -428.836363) (xy 19.485066 -428.79222) (xy 19.525215 -428.753511)
			(xy 19.570573 -428.72106) (xy 19.620173 -428.695559) (xy 19.672957 -428.677552) (xy 19.7278 -428.667422)
			(xy 19.783534 -428.665385) (xy 19.838971 -428.671485) (xy 19.892928 -428.685591) (xy 19.944257 -428.707403)
			(xy 19.991863 -428.736457) (xy 20.034731 -428.772132) (xy 20.071948 -428.813669) (xy 20.102721 -428.860182)
			(xy 20.126393 -428.910679) (xy 20.142461 -428.964086) (xy 20.150581 -429.019262) (xy 20.15109 -429.047148)
			(xy 20.403564 -429.047148) (xy 20.407635 -428.991526) (xy 20.419761 -428.937089) (xy 20.439684 -428.884998)
			(xy 20.46698 -428.836363) (xy 20.501066 -428.79222) (xy 20.541215 -428.753511) (xy 20.586573 -428.72106)
			(xy 20.636173 -428.695559) (xy 20.688957 -428.677552) (xy 20.7438 -428.667422) (xy 20.799534 -428.665385)
			(xy 20.854971 -428.671485) (xy 20.908928 -428.685591) (xy 20.960257 -428.707403) (xy 21.007863 -428.736457)
			(xy 21.050731 -428.772132) (xy 21.087948 -428.813669) (xy 21.118721 -428.860182) (xy 21.142393 -428.910679)
			(xy 21.158461 -428.964086) (xy 21.166581 -429.019262) (xy 21.16709 -429.047148) (xy 21.166581 -429.075034)
			(xy 21.158461 -429.13021) (xy 21.142393 -429.183617) (xy 21.118721 -429.234114) (xy 21.087948 -429.280627)
			(xy 21.050731 -429.322164) (xy 21.014942 -429.351948) (xy 21.524212 -429.351948) (xy 21.528283 -429.296326)
			(xy 21.540409 -429.241889) (xy 21.560332 -429.189798) (xy 21.587628 -429.141163) (xy 21.621714 -429.09702)
			(xy 21.661863 -429.058311) (xy 21.707221 -429.02586) (xy 21.756821 -429.000359) (xy 21.809605 -428.982352)
			(xy 21.864448 -428.972222) (xy 21.920182 -428.970185) (xy 21.975619 -428.976285) (xy 22.029576 -428.990391)
			(xy 22.080905 -429.012203) (xy 22.128511 -429.041257) (xy 22.171379 -429.076932) (xy 22.208596 -429.118469)
			(xy 22.239369 -429.164982) (xy 22.263041 -429.215479) (xy 22.279109 -429.268886) (xy 22.287229 -429.324062)
			(xy 22.287738 -429.351948) (xy 22.287229 -429.379834) (xy 22.279109 -429.43501) (xy 22.263041 -429.488417)
			(xy 22.239369 -429.538914) (xy 22.208596 -429.585427) (xy 22.171379 -429.626964) (xy 22.128511 -429.662639)
			(xy 22.080905 -429.691693) (xy 22.029576 -429.713505) (xy 21.975619 -429.727611) (xy 21.920182 -429.733711)
			(xy 21.864448 -429.731674) (xy 21.809605 -429.721544) (xy 21.756821 -429.703537) (xy 21.707221 -429.678036)
			(xy 21.661863 -429.645585) (xy 21.621714 -429.606876) (xy 21.587628 -429.562733) (xy 21.560332 -429.514098)
			(xy 21.540409 -429.462007) (xy 21.528283 -429.40757) (xy 21.524212 -429.351948) (xy 21.014942 -429.351948)
			(xy 21.007863 -429.357839) (xy 20.960257 -429.386893) (xy 20.908928 -429.408705) (xy 20.854971 -429.422811)
			(xy 20.799534 -429.428911) (xy 20.7438 -429.426874) (xy 20.688957 -429.416744) (xy 20.636173 -429.398737)
			(xy 20.586573 -429.373236) (xy 20.541215 -429.340785) (xy 20.501066 -429.302076) (xy 20.46698 -429.257933)
			(xy 20.439684 -429.209298) (xy 20.419761 -429.157207) (xy 20.407635 -429.10277) (xy 20.403564 -429.047148)
			(xy 20.15109 -429.047148) (xy 20.150581 -429.075034) (xy 20.142461 -429.13021) (xy 20.126393 -429.183617)
			(xy 20.102721 -429.234114) (xy 20.071948 -429.280627) (xy 20.034731 -429.322164) (xy 19.991863 -429.357839)
			(xy 19.944257 -429.386893) (xy 19.892928 -429.408705) (xy 19.838971 -429.422811) (xy 19.783534 -429.428911)
			(xy 19.7278 -429.426874) (xy 19.672957 -429.416744) (xy 19.620173 -429.398737) (xy 19.570573 -429.373236)
			(xy 19.525215 -429.340785) (xy 19.485066 -429.302076) (xy 19.45098 -429.257933) (xy 19.423684 -429.209298)
			(xy 19.403761 -429.157207) (xy 19.391635 -429.10277) (xy 19.387564 -429.047148) (xy 19.130955 -429.047148)
			(xy 19.134327 -429.070062) (xy 19.134836 -429.097948) (xy 19.134327 -429.125834) (xy 19.126207 -429.18101)
			(xy 19.110139 -429.234417) (xy 19.086467 -429.284914) (xy 19.055694 -429.331427) (xy 19.018477 -429.372964)
			(xy 18.975609 -429.408639) (xy 18.928003 -429.437693) (xy 18.876674 -429.459505) (xy 18.822717 -429.473611)
			(xy 18.76728 -429.479711) (xy 18.711546 -429.477674) (xy 18.656703 -429.467544) (xy 18.603919 -429.449537)
			(xy 18.554319 -429.424036) (xy 18.508961 -429.391585) (xy 18.468812 -429.352876) (xy 18.434726 -429.308733)
			(xy 18.40743 -429.260098) (xy 18.387507 -429.208007) (xy 18.375381 -429.15357) (xy 18.37131 -429.097948)
			(xy 15.250922 -429.097948) (xy 16.378936 -430.225962) (xy 24.108662 -430.225962) (xy 24.112733 -430.17034)
			(xy 24.124859 -430.115903) (xy 24.144782 -430.063812) (xy 24.172078 -430.015177) (xy 24.206164 -429.971034)
			(xy 24.246313 -429.932325) (xy 24.291671 -429.899874) (xy 24.341271 -429.874373) (xy 24.394055 -429.856366)
			(xy 24.448898 -429.846236) (xy 24.504632 -429.844199) (xy 24.560069 -429.850299) (xy 24.596977 -429.859948)
			(xy 31.925512 -429.859948) (xy 31.929583 -429.804326) (xy 31.941709 -429.749889) (xy 31.961632 -429.697798)
			(xy 31.988928 -429.649163) (xy 32.023014 -429.60502) (xy 32.063163 -429.566311) (xy 32.108521 -429.53386)
			(xy 32.158121 -429.508359) (xy 32.210905 -429.490352) (xy 32.265748 -429.480222) (xy 32.321482 -429.478185)
			(xy 32.376919 -429.484285) (xy 32.430876 -429.498391) (xy 32.482205 -429.520203) (xy 32.529811 -429.549257)
			(xy 32.572679 -429.584932) (xy 32.609896 -429.626469) (xy 32.640669 -429.672982) (xy 32.664341 -429.723479)
			(xy 32.680409 -429.776886) (xy 32.688529 -429.832062) (xy 32.689038 -429.859948) (xy 32.688529 -429.887834)
			(xy 32.680409 -429.94301) (xy 32.664341 -429.996417) (xy 32.640669 -430.046914) (xy 32.609896 -430.093427)
			(xy 32.572679 -430.134964) (xy 32.529811 -430.170639) (xy 32.482205 -430.199693) (xy 32.430876 -430.221505)
			(xy 32.376919 -430.235611) (xy 32.321482 -430.241711) (xy 32.265748 -430.239674) (xy 32.210905 -430.229544)
			(xy 32.158121 -430.211537) (xy 32.108521 -430.186036) (xy 32.063163 -430.153585) (xy 32.023014 -430.114876)
			(xy 31.988928 -430.070733) (xy 31.961632 -430.022098) (xy 31.941709 -429.970007) (xy 31.929583 -429.91557)
			(xy 31.925512 -429.859948) (xy 24.596977 -429.859948) (xy 24.614026 -429.864405) (xy 24.665355 -429.886217)
			(xy 24.712961 -429.915271) (xy 24.755829 -429.950946) (xy 24.793046 -429.992483) (xy 24.823819 -430.038996)
			(xy 24.847491 -430.089493) (xy 24.863559 -430.1429) (xy 24.871679 -430.198076) (xy 24.872188 -430.225962)
			(xy 24.871679 -430.253848) (xy 24.863559 -430.309024) (xy 24.847491 -430.362431) (xy 24.823819 -430.412928)
			(xy 24.793046 -430.459441) (xy 24.755829 -430.500978) (xy 24.712961 -430.536653) (xy 24.665355 -430.565707)
			(xy 24.614026 -430.587519) (xy 24.560069 -430.601625) (xy 24.504632 -430.607725) (xy 24.448898 -430.605688)
			(xy 24.394055 -430.595558) (xy 24.341271 -430.577551) (xy 24.291671 -430.55205) (xy 24.246313 -430.519599)
			(xy 24.206164 -430.48089) (xy 24.172078 -430.436747) (xy 24.144782 -430.388112) (xy 24.124859 -430.336021)
			(xy 24.112733 -430.281584) (xy 24.108662 -430.225962) (xy 16.378936 -430.225962) (xy 16.973804 -430.82083)
			(xy 25.011126 -430.82083) (xy 25.014174 -430.773332) (xy 25.016363 -430.746004) (xy 25.027591 -430.692344)
			(xy 25.046384 -430.640844) (xy 25.072355 -430.592564) (xy 25.10497 -430.548499) (xy 25.143557 -430.509556)
			(xy 25.18732 -430.476538) (xy 25.235359 -430.450124) (xy 25.286685 -430.430858) (xy 25.340239 -430.419138)
			(xy 25.39492 -430.415204) (xy 25.449601 -430.419138) (xy 25.503155 -430.430858) (xy 25.554481 -430.450124)
			(xy 25.60252 -430.476538) (xy 25.646283 -430.509556) (xy 25.68487 -430.548499) (xy 25.717485 -430.592564)
			(xy 25.743456 -430.640844) (xy 25.762249 -430.692344) (xy 25.773477 -430.746004) (xy 25.775666 -430.773332)
			(xy 25.778714 -430.82083) (xy 26.113486 -430.82083) (xy 26.803604 -431.510948) (xy 29.537912 -431.510948)
			(xy 29.541983 -431.455326) (xy 29.554109 -431.400889) (xy 29.574032 -431.348798) (xy 29.601328 -431.300163)
			(xy 29.635414 -431.25602) (xy 29.675563 -431.217311) (xy 29.720921 -431.18486) (xy 29.770521 -431.159359)
			(xy 29.823305 -431.141352) (xy 29.878148 -431.131222) (xy 29.933882 -431.129185) (xy 29.989319 -431.135285)
			(xy 30.043276 -431.149391) (xy 30.094605 -431.171203) (xy 30.142211 -431.200257) (xy 30.185079 -431.235932)
			(xy 30.222296 -431.277469) (xy 30.253069 -431.323982) (xy 30.276741 -431.374479) (xy 30.292809 -431.427886)
			(xy 30.300929 -431.483062) (xy 30.301438 -431.510948) (xy 30.300929 -431.538834) (xy 30.292809 -431.59401)
			(xy 30.276741 -431.647417) (xy 30.253069 -431.697914) (xy 30.222296 -431.744427) (xy 30.185079 -431.785964)
			(xy 30.142211 -431.821639) (xy 30.094605 -431.850693) (xy 30.043276 -431.872505) (xy 29.989319 -431.886611)
			(xy 29.940816 -431.891948) (xy 31.925512 -431.891948) (xy 31.929583 -431.836326) (xy 31.941709 -431.781889)
			(xy 31.961632 -431.729798) (xy 31.988928 -431.681163) (xy 32.023014 -431.63702) (xy 32.063163 -431.598311)
			(xy 32.108521 -431.56586) (xy 32.158121 -431.540359) (xy 32.210905 -431.522352) (xy 32.265748 -431.512222)
			(xy 32.321482 -431.510185) (xy 32.376919 -431.516285) (xy 32.430876 -431.530391) (xy 32.482205 -431.552203)
			(xy 32.529811 -431.581257) (xy 32.572679 -431.616932) (xy 32.609896 -431.658469) (xy 32.640669 -431.704982)
			(xy 32.664341 -431.755479) (xy 32.680409 -431.808886) (xy 32.688529 -431.864062) (xy 32.689038 -431.891948)
			(xy 32.688529 -431.919834) (xy 32.680409 -431.97501) (xy 32.664341 -432.028417) (xy 32.640669 -432.078914)
			(xy 32.609896 -432.125427) (xy 32.572679 -432.166964) (xy 32.529811 -432.202639) (xy 32.482205 -432.231693)
			(xy 32.430876 -432.253505) (xy 32.376919 -432.267611) (xy 32.321482 -432.273711) (xy 32.265748 -432.271674)
			(xy 32.210905 -432.261544) (xy 32.158121 -432.243537) (xy 32.108521 -432.218036) (xy 32.063163 -432.185585)
			(xy 32.023014 -432.146876) (xy 31.988928 -432.102733) (xy 31.961632 -432.054098) (xy 31.941709 -432.002007)
			(xy 31.929583 -431.94757) (xy 31.925512 -431.891948) (xy 29.940816 -431.891948) (xy 29.933882 -431.892711)
			(xy 29.878148 -431.890674) (xy 29.823305 -431.880544) (xy 29.770521 -431.862537) (xy 29.720921 -431.837036)
			(xy 29.675563 -431.804585) (xy 29.635414 -431.765876) (xy 29.601328 -431.721733) (xy 29.574032 -431.673098)
			(xy 29.554109 -431.621007) (xy 29.541983 -431.56657) (xy 29.537912 -431.510948) (xy 26.803604 -431.510948)
			(xy 27.569414 -432.276758) (xy 27.569414 -432.434053) (xy 36.411861 -432.434053) (xy 36.411861 -432.379547)
			(xy 36.419619 -432.325595) (xy 36.434975 -432.273297) (xy 36.457619 -432.223717) (xy 36.487088 -432.177863)
			(xy 36.522782 -432.136671) (xy 36.563976 -432.100978) (xy 36.609831 -432.071511) (xy 36.659412 -432.04887)
			(xy 36.711711 -432.033515) (xy 36.765663 -432.02576) (xy 36.792916 -432.025298) (xy 36.821831 -432.025877)
			(xy 36.878999 -432.034594) (xy 36.934197 -432.05184) (xy 36.986159 -432.07722) (xy 37.033694 -432.110153)
			(xy 37.075714 -432.149883) (xy 37.093906 -432.172364) (xy 37.102655 -432.182765) (xy 37.124399 -432.199044)
			(xy 37.149669 -432.209006) (xy 37.176672 -432.211943) (xy 37.203493 -432.207648) (xy 37.228228 -432.196424)
			(xy 37.249123 -432.179069) (xy 37.264696 -432.156813) (xy 37.269674 -432.14417) (xy 37.280062 -432.116809)
			(xy 37.308009 -432.065389) (xy 37.343477 -432.018838) (xy 37.385636 -431.978248) (xy 37.433498 -431.944568)
			(xy 37.48594 -431.91859) (xy 37.541732 -431.900921) (xy 37.599568 -431.891977) (xy 37.62883 -431.89144)
			(xy 37.656083 -431.891832) (xy 37.710035 -431.899593) (xy 37.762332 -431.914953) (xy 37.811912 -431.937598)
			(xy 37.857764 -431.967069) (xy 37.898956 -432.002765) (xy 37.914078 -432.020218) (xy 51.83581 -432.020218)
			(xy 51.839881 -431.964596) (xy 51.852007 -431.910159) (xy 51.87193 -431.858068) (xy 51.899226 -431.809433)
			(xy 51.933312 -431.76529) (xy 51.973461 -431.726581) (xy 52.018819 -431.69413) (xy 52.068419 -431.668629)
			(xy 52.121203 -431.650622) (xy 52.176046 -431.640492) (xy 52.23178 -431.638455) (xy 52.287217 -431.644555)
			(xy 52.341174 -431.658661) (xy 52.392503 -431.680473) (xy 52.440109 -431.709527) (xy 52.482977 -431.745202)
			(xy 52.520194 -431.786739) (xy 52.550967 -431.833252) (xy 52.574639 -431.883749) (xy 52.590707 -431.937156)
			(xy 52.598827 -431.992332) (xy 52.599336 -432.020218) (xy 52.598827 -432.048104) (xy 52.590707 -432.10328)
			(xy 52.574639 -432.156687) (xy 52.550967 -432.207184) (xy 52.520194 -432.253697) (xy 52.482977 -432.295234)
			(xy 52.440109 -432.330909) (xy 52.392503 -432.359963) (xy 52.341174 -432.381775) (xy 52.287217 -432.395881)
			(xy 52.23178 -432.401981) (xy 52.176046 -432.399944) (xy 52.121203 -432.389814) (xy 52.068419 -432.371807)
			(xy 52.018819 -432.346306) (xy 51.973461 -432.313855) (xy 51.933312 -432.275146) (xy 51.899226 -432.231003)
			(xy 51.87193 -432.182368) (xy 51.852007 -432.130277) (xy 51.839881 -432.07584) (xy 51.83581 -432.020218)
			(xy 37.914078 -432.020218) (xy 37.934649 -432.04396) (xy 37.964116 -432.089814) (xy 37.986758 -432.139396)
			(xy 38.002113 -432.191695) (xy 38.00987 -432.245647) (xy 38.00987 -432.300153) (xy 38.002113 -432.354105)
			(xy 37.986758 -432.406404) (xy 37.964116 -432.455986) (xy 37.934649 -432.50184) (xy 37.898956 -432.543035)
			(xy 37.857764 -432.578731) (xy 37.811912 -432.608202) (xy 37.762332 -432.630847) (xy 37.710035 -432.646207)
			(xy 37.656222 -432.653948) (xy 52.524912 -432.653948) (xy 52.528983 -432.598326) (xy 52.541109 -432.543889)
			(xy 52.561032 -432.491798) (xy 52.588328 -432.443163) (xy 52.622414 -432.39902) (xy 52.662563 -432.360311)
			(xy 52.707921 -432.32786) (xy 52.757521 -432.302359) (xy 52.810305 -432.284352) (xy 52.865148 -432.274222)
			(xy 52.920882 -432.272185) (xy 52.976319 -432.278285) (xy 53.030276 -432.292391) (xy 53.081605 -432.314203)
			(xy 53.129211 -432.343257) (xy 53.172079 -432.378932) (xy 53.209296 -432.420469) (xy 53.240069 -432.466982)
			(xy 53.263741 -432.517479) (xy 53.279809 -432.570886) (xy 53.287929 -432.626062) (xy 53.288438 -432.653948)
			(xy 53.287929 -432.681834) (xy 53.279809 -432.73701) (xy 53.263741 -432.790417) (xy 53.240069 -432.840914)
			(xy 53.209296 -432.887427) (xy 53.172079 -432.928964) (xy 53.129211 -432.964639) (xy 53.081605 -432.993693)
			(xy 53.030276 -433.015505) (xy 52.976319 -433.029611) (xy 52.920882 -433.035711) (xy 52.865148 -433.033674)
			(xy 52.810305 -433.023544) (xy 52.757521 -433.005537) (xy 52.707921 -432.980036) (xy 52.662563 -432.947585)
			(xy 52.622414 -432.908876) (xy 52.588328 -432.864733) (xy 52.561032 -432.816098) (xy 52.541109 -432.764007)
			(xy 52.528983 -432.70957) (xy 52.524912 -432.653948) (xy 37.656222 -432.653948) (xy 37.656083 -432.653968)
			(xy 37.62883 -432.654456) (xy 37.599913 -432.653933) (xy 37.542741 -432.645207) (xy 37.487542 -432.627951)
			(xy 37.43558 -432.602561) (xy 37.388046 -432.569617) (xy 37.34603 -432.529876) (xy 37.32784 -432.50739)
			(xy 37.319171 -432.496915) (xy 37.297413 -432.480624) (xy 37.272124 -432.470658) (xy 37.245102 -432.467724)
			(xy 37.218264 -432.472031) (xy 37.193516 -432.483271) (xy 37.172615 -432.500649) (xy 37.157045 -432.522929)
			(xy 37.152072 -432.535584) (xy 37.141705 -432.562954) (xy 37.113758 -432.614377) (xy 37.078289 -432.660931)
			(xy 37.036127 -432.701523) (xy 36.988262 -432.735202) (xy 36.935816 -432.761178) (xy 36.880019 -432.778843)
			(xy 36.822179 -432.787781) (xy 36.792916 -432.788314) (xy 36.765663 -432.78784) (xy 36.711711 -432.780085)
			(xy 36.659412 -432.76473) (xy 36.609831 -432.742089) (xy 36.563976 -432.712622) (xy 36.522782 -432.676929)
			(xy 36.487088 -432.635737) (xy 36.457619 -432.589883) (xy 36.434975 -432.540303) (xy 36.419619 -432.488005)
			(xy 36.411861 -432.434053) (xy 27.569414 -432.434053) (xy 27.569414 -432.907948) (xy 31.925512 -432.907948)
			(xy 31.929583 -432.852326) (xy 31.941709 -432.797889) (xy 31.961632 -432.745798) (xy 31.988928 -432.697163)
			(xy 32.023014 -432.65302) (xy 32.063163 -432.614311) (xy 32.108521 -432.58186) (xy 32.158121 -432.556359)
			(xy 32.210905 -432.538352) (xy 32.265748 -432.528222) (xy 32.321482 -432.526185) (xy 32.376919 -432.532285)
			(xy 32.430876 -432.546391) (xy 32.482205 -432.568203) (xy 32.529811 -432.597257) (xy 32.572679 -432.632932)
			(xy 32.609896 -432.674469) (xy 32.640669 -432.720982) (xy 32.664341 -432.771479) (xy 32.680409 -432.824886)
			(xy 32.688529 -432.880062) (xy 32.689038 -432.907948) (xy 32.688529 -432.935834) (xy 32.680409 -432.99101)
			(xy 32.664341 -433.044417) (xy 32.640669 -433.094914) (xy 32.609896 -433.141427) (xy 32.572679 -433.182964)
			(xy 32.529811 -433.218639) (xy 32.482205 -433.247693) (xy 32.430876 -433.269505) (xy 32.376919 -433.283611)
			(xy 32.321482 -433.289711) (xy 32.265748 -433.287674) (xy 32.210905 -433.277544) (xy 32.158121 -433.259537)
			(xy 32.108521 -433.234036) (xy 32.063163 -433.201585) (xy 32.023014 -433.162876) (xy 31.988928 -433.118733)
			(xy 31.961632 -433.070098) (xy 31.941709 -433.018007) (xy 31.929583 -432.96357) (xy 31.925512 -432.907948)
			(xy 27.569414 -432.907948) (xy 27.569414 -433.923948) (xy 31.925512 -433.923948) (xy 31.929583 -433.868326)
			(xy 31.941709 -433.813889) (xy 31.961632 -433.761798) (xy 31.988928 -433.713163) (xy 32.023014 -433.66902)
			(xy 32.063163 -433.630311) (xy 32.108521 -433.59786) (xy 32.158121 -433.572359) (xy 32.210905 -433.554352)
			(xy 32.265748 -433.544222) (xy 32.321482 -433.542185) (xy 32.376919 -433.548285) (xy 32.430876 -433.562391)
			(xy 32.482205 -433.584203) (xy 32.529811 -433.613257) (xy 32.572679 -433.648932) (xy 32.609896 -433.690469)
			(xy 32.640669 -433.736982) (xy 32.664341 -433.787479) (xy 32.680409 -433.840886) (xy 32.688529 -433.896062)
			(xy 32.689038 -433.923948) (xy 32.688529 -433.951834) (xy 32.686278 -433.967128) (xy 38.937944 -433.967128)
			(xy 38.942015 -433.911506) (xy 38.954141 -433.857069) (xy 38.974064 -433.804978) (xy 39.00136 -433.756343)
			(xy 39.035446 -433.7122) (xy 39.075595 -433.673491) (xy 39.120953 -433.64104) (xy 39.170553 -433.615539)
			(xy 39.223337 -433.597532) (xy 39.27818 -433.587402) (xy 39.333914 -433.585365) (xy 39.389351 -433.591465)
			(xy 39.443308 -433.605571) (xy 39.494637 -433.627383) (xy 39.542243 -433.656437) (xy 39.585111 -433.692112)
			(xy 39.622328 -433.733649) (xy 39.653101 -433.780162) (xy 39.676773 -433.830659) (xy 39.678858 -433.837588)
			(xy 40.590722 -433.837588) (xy 40.594793 -433.781966) (xy 40.606919 -433.727529) (xy 40.626842 -433.675438)
			(xy 40.654138 -433.626803) (xy 40.688224 -433.58266) (xy 40.728373 -433.543951) (xy 40.773731 -433.5115)
			(xy 40.823331 -433.485999) (xy 40.876115 -433.467992) (xy 40.930958 -433.457862) (xy 40.986692 -433.455825)
			(xy 41.042129 -433.461925) (xy 41.096086 -433.476031) (xy 41.147415 -433.497843) (xy 41.195021 -433.526897)
			(xy 41.237889 -433.562572) (xy 41.275106 -433.604109) (xy 41.305879 -433.650622) (xy 41.329551 -433.701119)
			(xy 41.344321 -433.750212) (xy 41.916348 -433.750212) (xy 41.920419 -433.69459) (xy 41.932545 -433.640153)
			(xy 41.952468 -433.588062) (xy 41.979764 -433.539427) (xy 42.01385 -433.495284) (xy 42.053999 -433.456575)
			(xy 42.099357 -433.424124) (xy 42.148957 -433.398623) (xy 42.201741 -433.380616) (xy 42.256584 -433.370486)
			(xy 42.312318 -433.368449) (xy 42.367755 -433.374549) (xy 42.421712 -433.388655) (xy 42.473041 -433.410467)
			(xy 42.520647 -433.439521) (xy 42.563515 -433.475196) (xy 42.600732 -433.516733) (xy 42.631505 -433.563246)
			(xy 42.655177 -433.613743) (xy 42.671245 -433.66715) (xy 42.679365 -433.722326) (xy 42.679874 -433.750212)
			(xy 42.679365 -433.778098) (xy 42.671245 -433.833274) (xy 42.655177 -433.886681) (xy 42.631505 -433.937178)
			(xy 42.600732 -433.983691) (xy 42.563515 -434.025228) (xy 42.520647 -434.060903) (xy 42.473041 -434.089957)
			(xy 42.472191 -434.090318) (xy 49.404522 -434.090318) (xy 49.408593 -434.034696) (xy 49.420719 -433.980259)
			(xy 49.440642 -433.928168) (xy 49.467938 -433.879533) (xy 49.502024 -433.83539) (xy 49.542173 -433.796681)
			(xy 49.587531 -433.76423) (xy 49.637131 -433.738729) (xy 49.689915 -433.720722) (xy 49.744758 -433.710592)
			(xy 49.800492 -433.708555) (xy 49.855929 -433.714655) (xy 49.909886 -433.728761) (xy 49.961215 -433.750573)
			(xy 50.008821 -433.779627) (xy 50.051689 -433.815302) (xy 50.088906 -433.856839) (xy 50.119679 -433.903352)
			(xy 50.143351 -433.953849) (xy 50.159419 -434.007256) (xy 50.167539 -434.062432) (xy 50.168048 -434.090318)
			(xy 50.167539 -434.118204) (xy 50.159419 -434.17338) (xy 50.143351 -434.226787) (xy 50.119679 -434.277284)
			(xy 50.088906 -434.323797) (xy 50.051689 -434.365334) (xy 50.008821 -434.401009) (xy 49.961215 -434.430063)
			(xy 49.909886 -434.451875) (xy 49.855929 -434.465981) (xy 49.800492 -434.472081) (xy 49.744758 -434.470044)
			(xy 49.689915 -434.459914) (xy 49.637131 -434.441907) (xy 49.587531 -434.416406) (xy 49.542173 -434.383955)
			(xy 49.502024 -434.345246) (xy 49.467938 -434.301103) (xy 49.440642 -434.252468) (xy 49.420719 -434.200377)
			(xy 49.408593 -434.14594) (xy 49.404522 -434.090318) (xy 42.472191 -434.090318) (xy 42.421712 -434.111769)
			(xy 42.367755 -434.125875) (xy 42.312318 -434.131975) (xy 42.256584 -434.129938) (xy 42.201741 -434.119808)
			(xy 42.148957 -434.101801) (xy 42.099357 -434.0763) (xy 42.053999 -434.043849) (xy 42.01385 -434.00514)
			(xy 41.979764 -433.960997) (xy 41.952468 -433.912362) (xy 41.932545 -433.860271) (xy 41.920419 -433.805834)
			(xy 41.916348 -433.750212) (xy 41.344321 -433.750212) (xy 41.345619 -433.754526) (xy 41.353739 -433.809702)
			(xy 41.354248 -433.837588) (xy 41.353739 -433.865474) (xy 41.345619 -433.92065) (xy 41.329551 -433.974057)
			(xy 41.305879 -434.024554) (xy 41.275106 -434.071067) (xy 41.237889 -434.112604) (xy 41.195021 -434.148279)
			(xy 41.147415 -434.177333) (xy 41.096086 -434.199145) (xy 41.042129 -434.213251) (xy 40.986692 -434.219351)
			(xy 40.930958 -434.217314) (xy 40.876115 -434.207184) (xy 40.823331 -434.189177) (xy 40.773731 -434.163676)
			(xy 40.728373 -434.131225) (xy 40.688224 -434.092516) (xy 40.654138 -434.048373) (xy 40.626842 -433.999738)
			(xy 40.606919 -433.947647) (xy 40.594793 -433.89321) (xy 40.590722 -433.837588) (xy 39.678858 -433.837588)
			(xy 39.692841 -433.884066) (xy 39.700961 -433.939242) (xy 39.70147 -433.967128) (xy 39.700961 -433.995014)
			(xy 39.692841 -434.05019) (xy 39.676773 -434.103597) (xy 39.653101 -434.154094) (xy 39.622328 -434.200607)
			(xy 39.585111 -434.242144) (xy 39.542243 -434.277819) (xy 39.494637 -434.306873) (xy 39.443308 -434.328685)
			(xy 39.389351 -434.342791) (xy 39.333914 -434.348891) (xy 39.27818 -434.346854) (xy 39.223337 -434.336724)
			(xy 39.170553 -434.318717) (xy 39.120953 -434.293216) (xy 39.075595 -434.260765) (xy 39.035446 -434.222056)
			(xy 39.00136 -434.177913) (xy 38.974064 -434.129278) (xy 38.954141 -434.077187) (xy 38.942015 -434.02275)
			(xy 38.937944 -433.967128) (xy 32.686278 -433.967128) (xy 32.680409 -434.00701) (xy 32.664341 -434.060417)
			(xy 32.640669 -434.110914) (xy 32.609896 -434.157427) (xy 32.572679 -434.198964) (xy 32.529811 -434.234639)
			(xy 32.482205 -434.263693) (xy 32.430876 -434.285505) (xy 32.376919 -434.299611) (xy 32.321482 -434.305711)
			(xy 32.265748 -434.303674) (xy 32.210905 -434.293544) (xy 32.158121 -434.275537) (xy 32.108521 -434.250036)
			(xy 32.063163 -434.217585) (xy 32.023014 -434.178876) (xy 31.988928 -434.134733) (xy 31.961632 -434.086098)
			(xy 31.941709 -434.034007) (xy 31.929583 -433.97957) (xy 31.925512 -433.923948) (xy 27.569414 -433.923948)
			(xy 27.569414 -435.233318) (xy 39.024812 -435.233318) (xy 39.028883 -435.177696) (xy 39.041009 -435.123259)
			(xy 39.060932 -435.071168) (xy 39.088228 -435.022533) (xy 39.122314 -434.97839) (xy 39.162463 -434.939681)
			(xy 39.207821 -434.90723) (xy 39.257421 -434.881729) (xy 39.310205 -434.863722) (xy 39.365048 -434.853592)
			(xy 39.420782 -434.851555) (xy 39.427716 -434.852318) (xy 41.507662 -434.852318) (xy 41.511733 -434.796696)
			(xy 41.523859 -434.742259) (xy 41.543782 -434.690168) (xy 41.571078 -434.641533) (xy 41.605164 -434.59739)
			(xy 41.645313 -434.558681) (xy 41.690671 -434.52623) (xy 41.740271 -434.500729) (xy 41.793055 -434.482722)
			(xy 41.847898 -434.472592) (xy 41.903632 -434.470555) (xy 41.959069 -434.476655) (xy 42.013026 -434.490761)
			(xy 42.064355 -434.512573) (xy 42.111961 -434.541627) (xy 42.154829 -434.577302) (xy 42.192046 -434.618839)
			(xy 42.222819 -434.665352) (xy 42.246491 -434.715849) (xy 42.256141 -434.747924) (xy 48.744122 -434.747924)
			(xy 48.748193 -434.692302) (xy 48.760319 -434.637865) (xy 48.780242 -434.585774) (xy 48.807538 -434.537139)
			(xy 48.841624 -434.492996) (xy 48.881773 -434.454287) (xy 48.927131 -434.421836) (xy 48.976731 -434.396335)
			(xy 49.029515 -434.378328) (xy 49.084358 -434.368198) (xy 49.140092 -434.366161) (xy 49.195529 -434.372261)
			(xy 49.249486 -434.386367) (xy 49.300815 -434.408179) (xy 49.348421 -434.437233) (xy 49.391289 -434.472908)
			(xy 49.428506 -434.514445) (xy 49.459279 -434.560958) (xy 49.482951 -434.611455) (xy 49.499019 -434.664862)
			(xy 49.507139 -434.720038) (xy 49.507648 -434.747924) (xy 49.507139 -434.77581) (xy 49.499019 -434.830986)
			(xy 49.482951 -434.884393) (xy 49.459279 -434.93489) (xy 49.428506 -434.981403) (xy 49.391289 -435.02294)
			(xy 49.348421 -435.058615) (xy 49.300815 -435.087669) (xy 49.249486 -435.109481) (xy 49.195529 -435.123587)
			(xy 49.140092 -435.129687) (xy 49.084358 -435.12765) (xy 49.029515 -435.11752) (xy 48.976731 -435.099513)
			(xy 48.927131 -435.074012) (xy 48.881773 -435.041561) (xy 48.841624 -435.002852) (xy 48.807538 -434.958709)
			(xy 48.780242 -434.910074) (xy 48.760319 -434.857983) (xy 48.748193 -434.803546) (xy 48.744122 -434.747924)
			(xy 42.256141 -434.747924) (xy 42.262559 -434.769256) (xy 42.270679 -434.824432) (xy 42.271188 -434.852318)
			(xy 42.270679 -434.880204) (xy 42.262559 -434.93538) (xy 42.246491 -434.988787) (xy 42.222819 -435.039284)
			(xy 42.192046 -435.085797) (xy 42.154829 -435.127334) (xy 42.111961 -435.163009) (xy 42.064355 -435.192063)
			(xy 42.013026 -435.213875) (xy 41.959069 -435.227981) (xy 41.903632 -435.234081) (xy 41.847898 -435.232044)
			(xy 41.793055 -435.221914) (xy 41.740271 -435.203907) (xy 41.690671 -435.178406) (xy 41.645313 -435.145955)
			(xy 41.605164 -435.107246) (xy 41.571078 -435.063103) (xy 41.543782 -435.014468) (xy 41.523859 -434.962377)
			(xy 41.511733 -434.90794) (xy 41.507662 -434.852318) (xy 39.427716 -434.852318) (xy 39.476219 -434.857655)
			(xy 39.530176 -434.871761) (xy 39.581505 -434.893573) (xy 39.629111 -434.922627) (xy 39.671979 -434.958302)
			(xy 39.709196 -434.999839) (xy 39.739969 -435.046352) (xy 39.763641 -435.096849) (xy 39.779709 -435.150256)
			(xy 39.787829 -435.205432) (xy 39.788338 -435.233318) (xy 39.787829 -435.261204) (xy 39.779709 -435.31638)
			(xy 39.763641 -435.369787) (xy 39.739969 -435.420284) (xy 39.709196 -435.466797) (xy 39.690809 -435.487318)
			(xy 49.297842 -435.487318) (xy 49.301913 -435.431696) (xy 49.314039 -435.377259) (xy 49.333962 -435.325168)
			(xy 49.361258 -435.276533) (xy 49.395344 -435.23239) (xy 49.435493 -435.193681) (xy 49.480851 -435.16123)
			(xy 49.530451 -435.135729) (xy 49.583235 -435.117722) (xy 49.638078 -435.107592) (xy 49.693812 -435.105555)
			(xy 49.749249 -435.111655) (xy 49.803206 -435.125761) (xy 49.854535 -435.147573) (xy 49.902141 -435.176627)
			(xy 49.945009 -435.212302) (xy 49.982226 -435.253839) (xy 50.012999 -435.300352) (xy 50.036671 -435.350849)
			(xy 50.052739 -435.404256) (xy 50.060859 -435.459432) (xy 50.061368 -435.487318) (xy 50.060859 -435.515204)
			(xy 50.052739 -435.57038) (xy 50.036671 -435.623787) (xy 50.012999 -435.674284) (xy 49.982226 -435.720797)
			(xy 49.945009 -435.762334) (xy 49.902141 -435.798009) (xy 49.854535 -435.827063) (xy 49.803206 -435.848875)
			(xy 49.749249 -435.862981) (xy 49.693812 -435.869081) (xy 49.638078 -435.867044) (xy 49.583235 -435.856914)
			(xy 49.530451 -435.838907) (xy 49.480851 -435.813406) (xy 49.435493 -435.780955) (xy 49.395344 -435.742246)
			(xy 49.361258 -435.698103) (xy 49.333962 -435.649468) (xy 49.314039 -435.597377) (xy 49.301913 -435.54294)
			(xy 49.297842 -435.487318) (xy 39.690809 -435.487318) (xy 39.671979 -435.508334) (xy 39.629111 -435.544009)
			(xy 39.581505 -435.573063) (xy 39.530176 -435.594875) (xy 39.476219 -435.608981) (xy 39.420782 -435.615081)
			(xy 39.365048 -435.613044) (xy 39.310205 -435.602914) (xy 39.257421 -435.584907) (xy 39.207821 -435.559406)
			(xy 39.162463 -435.526955) (xy 39.122314 -435.488246) (xy 39.088228 -435.444103) (xy 39.060932 -435.395468)
			(xy 39.041009 -435.343377) (xy 39.028883 -435.28894) (xy 39.024812 -435.233318) (xy 27.569414 -435.233318)
			(xy 27.569414 -436.268368) (xy 34.79495 -436.268368) (xy 34.799021 -436.212746) (xy 34.811147 -436.158309)
			(xy 34.83107 -436.106218) (xy 34.858366 -436.057583) (xy 34.892452 -436.01344) (xy 34.932601 -435.974731)
			(xy 34.977959 -435.94228) (xy 35.027559 -435.916779) (xy 35.080343 -435.898772) (xy 35.135186 -435.888642)
			(xy 35.19092 -435.886605) (xy 35.246357 -435.892705) (xy 35.300314 -435.906811) (xy 35.351643 -435.928623)
			(xy 35.399249 -435.957677) (xy 35.442117 -435.993352) (xy 35.479334 -436.034889) (xy 35.510107 -436.081402)
			(xy 35.533779 -436.131899) (xy 35.549847 -436.185306) (xy 35.557967 -436.240482) (xy 35.558337 -436.260748)
			(xy 36.326062 -436.260748) (xy 36.330133 -436.205126) (xy 36.342259 -436.150689) (xy 36.362182 -436.098598)
			(xy 36.389478 -436.049963) (xy 36.423564 -436.00582) (xy 36.463713 -435.967111) (xy 36.509071 -435.93466)
			(xy 36.558671 -435.909159) (xy 36.611455 -435.891152) (xy 36.666298 -435.881022) (xy 36.722032 -435.878985)
			(xy 36.777469 -435.885085) (xy 36.831426 -435.899191) (xy 36.882755 -435.921003) (xy 36.930361 -435.950057)
			(xy 36.973229 -435.985732) (xy 37.010446 -436.027269) (xy 37.041219 -436.073782) (xy 37.063972 -436.122318)
			(xy 41.035222 -436.122318) (xy 41.039293 -436.066696) (xy 41.051419 -436.012259) (xy 41.071342 -435.960168)
			(xy 41.098638 -435.911533) (xy 41.132724 -435.86739) (xy 41.172873 -435.828681) (xy 41.218231 -435.79623)
			(xy 41.267831 -435.770729) (xy 41.320615 -435.752722) (xy 41.375458 -435.742592) (xy 41.431192 -435.740555)
			(xy 41.486629 -435.746655) (xy 41.540586 -435.760761) (xy 41.591915 -435.782573) (xy 41.639521 -435.811627)
			(xy 41.682389 -435.847302) (xy 41.719606 -435.888839) (xy 41.750379 -435.935352) (xy 41.774051 -435.985849)
			(xy 41.790119 -436.039256) (xy 41.798239 -436.094432) (xy 41.798748 -436.122318) (xy 41.798239 -436.150204)
			(xy 41.790119 -436.20538) (xy 41.774051 -436.258787) (xy 41.750379 -436.309284) (xy 41.719606 -436.355797)
			(xy 41.682389 -436.397334) (xy 41.639521 -436.433009) (xy 41.591915 -436.462063) (xy 41.540586 -436.483875)
			(xy 41.486629 -436.497981) (xy 41.431192 -436.504081) (xy 41.375458 -436.502044) (xy 41.320615 -436.491914)
			(xy 41.267831 -436.473907) (xy 41.218231 -436.448406) (xy 41.172873 -436.415955) (xy 41.132724 -436.377246)
			(xy 41.098638 -436.333103) (xy 41.071342 -436.284468) (xy 41.051419 -436.232377) (xy 41.039293 -436.17794)
			(xy 41.035222 -436.122318) (xy 37.063972 -436.122318) (xy 37.064891 -436.124279) (xy 37.080959 -436.177686)
			(xy 37.089079 -436.232862) (xy 37.089588 -436.260748) (xy 37.089079 -436.288634) (xy 37.080959 -436.34381)
			(xy 37.064891 -436.397217) (xy 37.041219 -436.447714) (xy 37.010446 -436.494227) (xy 36.973229 -436.535764)
			(xy 36.930361 -436.571439) (xy 36.882755 -436.600493) (xy 36.831426 -436.622305) (xy 36.777469 -436.636411)
			(xy 36.722032 -436.642511) (xy 36.666298 -436.640474) (xy 36.611455 -436.630344) (xy 36.558671 -436.612337)
			(xy 36.509071 -436.586836) (xy 36.463713 -436.554385) (xy 36.423564 -436.515676) (xy 36.389478 -436.471533)
			(xy 36.362182 -436.422898) (xy 36.342259 -436.370807) (xy 36.330133 -436.31637) (xy 36.326062 -436.260748)
			(xy 35.558337 -436.260748) (xy 35.558476 -436.268368) (xy 35.557967 -436.296254) (xy 35.549847 -436.35143)
			(xy 35.533779 -436.404837) (xy 35.510107 -436.455334) (xy 35.479334 -436.501847) (xy 35.442117 -436.543384)
			(xy 35.399249 -436.579059) (xy 35.351643 -436.608113) (xy 35.300314 -436.629925) (xy 35.246357 -436.644031)
			(xy 35.19092 -436.650131) (xy 35.135186 -436.648094) (xy 35.080343 -436.637964) (xy 35.027559 -436.619957)
			(xy 34.977959 -436.594456) (xy 34.932601 -436.562005) (xy 34.892452 -436.523296) (xy 34.858366 -436.479153)
			(xy 34.83107 -436.430518) (xy 34.811147 -436.378427) (xy 34.799021 -436.32399) (xy 34.79495 -436.268368)
			(xy 27.569414 -436.268368) (xy 27.569414 -436.692548) (xy 31.550862 -436.692548) (xy 31.554933 -436.636926)
			(xy 31.567059 -436.582489) (xy 31.586982 -436.530398) (xy 31.614278 -436.481763) (xy 31.648364 -436.43762)
			(xy 31.688513 -436.398911) (xy 31.733871 -436.36646) (xy 31.783471 -436.340959) (xy 31.836255 -436.322952)
			(xy 31.891098 -436.312822) (xy 31.946832 -436.310785) (xy 32.002269 -436.316885) (xy 32.056226 -436.330991)
			(xy 32.107555 -436.352803) (xy 32.155161 -436.381857) (xy 32.198029 -436.417532) (xy 32.235246 -436.459069)
			(xy 32.266019 -436.505582) (xy 32.289691 -436.556079) (xy 32.305759 -436.609486) (xy 32.313879 -436.664662)
			(xy 32.314388 -436.692548) (xy 32.313879 -436.720434) (xy 32.305759 -436.77561) (xy 32.289691 -436.829017)
			(xy 32.266019 -436.879514) (xy 32.235246 -436.926027) (xy 32.198029 -436.967564) (xy 32.155161 -437.003239)
			(xy 32.107555 -437.032293) (xy 32.056226 -437.054105) (xy 32.002269 -437.068211) (xy 31.946832 -437.074311)
			(xy 31.891098 -437.072274) (xy 31.836255 -437.062144) (xy 31.783471 -437.044137) (xy 31.733871 -437.018636)
			(xy 31.688513 -436.986185) (xy 31.648364 -436.947476) (xy 31.614278 -436.903333) (xy 31.586982 -436.854698)
			(xy 31.567059 -436.802607) (xy 31.554933 -436.74817) (xy 31.550862 -436.692548) (xy 27.569414 -436.692548)
			(xy 27.569414 -437.187594) (xy 41.949876 -437.187594) (xy 41.953947 -437.131972) (xy 41.966073 -437.077535)
			(xy 41.985996 -437.025444) (xy 42.013292 -436.976809) (xy 42.047378 -436.932666) (xy 42.087527 -436.893957)
			(xy 42.132885 -436.861506) (xy 42.182485 -436.836005) (xy 42.235269 -436.817998) (xy 42.290112 -436.807868)
			(xy 42.345846 -436.805831) (xy 42.401283 -436.811931) (xy 42.45524 -436.826037) (xy 42.506569 -436.847849)
			(xy 42.554175 -436.876903) (xy 42.597043 -436.912578) (xy 42.63426 -436.954115) (xy 42.665033 -437.000628)
			(xy 42.688705 -437.051125) (xy 42.704773 -437.104532) (xy 42.712893 -437.159708) (xy 42.713402 -437.187594)
			(xy 42.713295 -437.193436) (xy 43.55033 -437.193436) (xy 43.554401 -437.137814) (xy 43.566527 -437.083377)
			(xy 43.58645 -437.031286) (xy 43.613746 -436.982651) (xy 43.647832 -436.938508) (xy 43.687981 -436.899799)
			(xy 43.733339 -436.867348) (xy 43.782939 -436.841847) (xy 43.835723 -436.82384) (xy 43.890566 -436.81371)
			(xy 43.9463 -436.811673) (xy 44.001737 -436.817773) (xy 44.055694 -436.831879) (xy 44.107023 -436.853691)
			(xy 44.154629 -436.882745) (xy 44.197497 -436.91842) (xy 44.234714 -436.959957) (xy 44.265487 -437.00647)
			(xy 44.283834 -437.045608) (xy 44.86605 -437.045608) (xy 44.870121 -436.989986) (xy 44.882247 -436.935549)
			(xy 44.90217 -436.883458) (xy 44.929466 -436.834823) (xy 44.963552 -436.79068) (xy 45.003701 -436.751971)
			(xy 45.049059 -436.71952) (xy 45.098659 -436.694019) (xy 45.151443 -436.676012) (xy 45.206286 -436.665882)
			(xy 45.26202 -436.663845) (xy 45.317457 -436.669945) (xy 45.371414 -436.684051) (xy 45.422743 -436.705863)
			(xy 45.470349 -436.734917) (xy 45.513217 -436.770592) (xy 45.550434 -436.812129) (xy 45.581207 -436.858642)
			(xy 45.604879 -436.909139) (xy 45.620947 -436.962546) (xy 45.628125 -437.011318) (xy 46.30877 -437.011318)
			(xy 46.312841 -436.955696) (xy 46.324967 -436.901259) (xy 46.34489 -436.849168) (xy 46.372186 -436.800533)
			(xy 46.406272 -436.75639) (xy 46.446421 -436.717681) (xy 46.491779 -436.68523) (xy 46.541379 -436.659729)
			(xy 46.594163 -436.641722) (xy 46.649006 -436.631592) (xy 46.70474 -436.629555) (xy 46.760177 -436.635655)
			(xy 46.814134 -436.649761) (xy 46.865463 -436.671573) (xy 46.913069 -436.700627) (xy 46.955937 -436.736302)
			(xy 46.993154 -436.777839) (xy 47.023927 -436.824352) (xy 47.047599 -436.874849) (xy 47.063667 -436.928256)
			(xy 47.071787 -436.983432) (xy 47.072296 -437.011318) (xy 47.071787 -437.039204) (xy 47.063667 -437.09438)
			(xy 47.047599 -437.147787) (xy 47.023927 -437.198284) (xy 46.993154 -437.244797) (xy 46.955937 -437.286334)
			(xy 46.913069 -437.322009) (xy 46.865463 -437.351063) (xy 46.814134 -437.372875) (xy 46.760177 -437.386981)
			(xy 46.70474 -437.393081) (xy 46.649006 -437.391044) (xy 46.594163 -437.380914) (xy 46.541379 -437.362907)
			(xy 46.491779 -437.337406) (xy 46.446421 -437.304955) (xy 46.406272 -437.266246) (xy 46.372186 -437.222103)
			(xy 46.34489 -437.173468) (xy 46.324967 -437.121377) (xy 46.312841 -437.06694) (xy 46.30877 -437.011318)
			(xy 45.628125 -437.011318) (xy 45.629067 -437.017722) (xy 45.629576 -437.045608) (xy 45.629067 -437.073494)
			(xy 45.620947 -437.12867) (xy 45.604879 -437.182077) (xy 45.581207 -437.232574) (xy 45.550434 -437.279087)
			(xy 45.513217 -437.320624) (xy 45.470349 -437.356299) (xy 45.422743 -437.385353) (xy 45.371414 -437.407165)
			(xy 45.317457 -437.421271) (xy 45.26202 -437.427371) (xy 45.206286 -437.425334) (xy 45.151443 -437.415204)
			(xy 45.098659 -437.397197) (xy 45.049059 -437.371696) (xy 45.003701 -437.339245) (xy 44.963552 -437.300536)
			(xy 44.929466 -437.256393) (xy 44.90217 -437.207758) (xy 44.882247 -437.155667) (xy 44.870121 -437.10123)
			(xy 44.86605 -437.045608) (xy 44.283834 -437.045608) (xy 44.289159 -437.056967) (xy 44.305227 -437.110374)
			(xy 44.313347 -437.16555) (xy 44.313856 -437.193436) (xy 44.313347 -437.221322) (xy 44.305227 -437.276498)
			(xy 44.289159 -437.329905) (xy 44.265487 -437.380402) (xy 44.234714 -437.426915) (xy 44.224748 -437.438038)
			(xy 49.514504 -437.438038) (xy 49.518575 -437.382416) (xy 49.530701 -437.327979) (xy 49.550624 -437.275888)
			(xy 49.57792 -437.227253) (xy 49.612006 -437.18311) (xy 49.652155 -437.144401) (xy 49.697513 -437.11195)
			(xy 49.747113 -437.086449) (xy 49.799897 -437.068442) (xy 49.85474 -437.058312) (xy 49.910474 -437.056275)
			(xy 49.965911 -437.062375) (xy 50.019868 -437.076481) (xy 50.071197 -437.098293) (xy 50.118803 -437.127347)
			(xy 50.161671 -437.163022) (xy 50.198888 -437.204559) (xy 50.229661 -437.251072) (xy 50.253333 -437.301569)
			(xy 50.269401 -437.354976) (xy 50.277521 -437.410152) (xy 50.27803 -437.438038) (xy 50.277521 -437.465924)
			(xy 50.269401 -437.5211) (xy 50.253333 -437.574507) (xy 50.229661 -437.625004) (xy 50.198888 -437.671517)
			(xy 50.161671 -437.713054) (xy 50.118803 -437.748729) (xy 50.071197 -437.777783) (xy 50.019868 -437.799595)
			(xy 49.965911 -437.813701) (xy 49.910474 -437.819801) (xy 49.85474 -437.817764) (xy 49.799897 -437.807634)
			(xy 49.747113 -437.789627) (xy 49.697513 -437.764126) (xy 49.652155 -437.731675) (xy 49.612006 -437.692966)
			(xy 49.57792 -437.648823) (xy 49.550624 -437.600188) (xy 49.530701 -437.548097) (xy 49.518575 -437.49366)
			(xy 49.514504 -437.438038) (xy 44.224748 -437.438038) (xy 44.197497 -437.468452) (xy 44.154629 -437.504127)
			(xy 44.107023 -437.533181) (xy 44.055694 -437.554993) (xy 44.001737 -437.569099) (xy 43.9463 -437.575199)
			(xy 43.890566 -437.573162) (xy 43.835723 -437.563032) (xy 43.782939 -437.545025) (xy 43.733339 -437.519524)
			(xy 43.687981 -437.487073) (xy 43.647832 -437.448364) (xy 43.613746 -437.404221) (xy 43.58645 -437.355586)
			(xy 43.566527 -437.303495) (xy 43.554401 -437.249058) (xy 43.55033 -437.193436) (xy 42.713295 -437.193436)
			(xy 42.712893 -437.21548) (xy 42.704773 -437.270656) (xy 42.688705 -437.324063) (xy 42.665033 -437.37456)
			(xy 42.63426 -437.421073) (xy 42.597043 -437.46261) (xy 42.554175 -437.498285) (xy 42.506569 -437.527339)
			(xy 42.45524 -437.549151) (xy 42.401283 -437.563257) (xy 42.345846 -437.569357) (xy 42.290112 -437.56732)
			(xy 42.235269 -437.55719) (xy 42.182485 -437.539183) (xy 42.132885 -437.513682) (xy 42.087527 -437.481231)
			(xy 42.047378 -437.442522) (xy 42.013292 -437.398379) (xy 41.985996 -437.349744) (xy 41.966073 -437.297653)
			(xy 41.953947 -437.243216) (xy 41.949876 -437.187594) (xy 27.569414 -437.187594) (xy 27.569414 -437.585612)
			(xy 33.79546 -437.585612) (xy 33.799531 -437.52999) (xy 33.811657 -437.475553) (xy 33.83158 -437.423462)
			(xy 33.858876 -437.374827) (xy 33.892962 -437.330684) (xy 33.933111 -437.291975) (xy 33.978469 -437.259524)
			(xy 34.028069 -437.234023) (xy 34.080853 -437.216016) (xy 34.135696 -437.205886) (xy 34.19143 -437.203849)
			(xy 34.246867 -437.209949) (xy 34.300824 -437.224055) (xy 34.352153 -437.245867) (xy 34.399759 -437.274921)
			(xy 34.442627 -437.310596) (xy 34.479844 -437.352133) (xy 34.510617 -437.398646) (xy 34.534289 -437.449143)
			(xy 34.550357 -437.50255) (xy 34.558477 -437.557726) (xy 34.558986 -437.585612) (xy 34.558477 -437.613498)
			(xy 34.550357 -437.668674) (xy 34.538361 -437.708548) (xy 39.013382 -437.708548) (xy 39.017453 -437.652926)
			(xy 39.029579 -437.598489) (xy 39.049502 -437.546398) (xy 39.076798 -437.497763) (xy 39.110884 -437.45362)
			(xy 39.151033 -437.414911) (xy 39.196391 -437.38246) (xy 39.245991 -437.356959) (xy 39.298775 -437.338952)
			(xy 39.353618 -437.328822) (xy 39.409352 -437.326785) (xy 39.464789 -437.332885) (xy 39.518746 -437.346991)
			(xy 39.570075 -437.368803) (xy 39.617681 -437.397857) (xy 39.660549 -437.433532) (xy 39.697766 -437.475069)
			(xy 39.728539 -437.521582) (xy 39.752211 -437.572079) (xy 39.768279 -437.625486) (xy 39.776399 -437.680662)
			(xy 39.776908 -437.708548) (xy 39.776399 -437.736434) (xy 39.768279 -437.79161) (xy 39.752211 -437.845017)
			(xy 39.728539 -437.895514) (xy 39.697766 -437.942027) (xy 39.660549 -437.983564) (xy 39.617681 -438.019239)
			(xy 39.570075 -438.048293) (xy 39.518746 -438.070105) (xy 39.464789 -438.084211) (xy 39.409352 -438.090311)
			(xy 39.353618 -438.088274) (xy 39.298775 -438.078144) (xy 39.245991 -438.060137) (xy 39.196391 -438.034636)
			(xy 39.151033 -438.002185) (xy 39.110884 -437.963476) (xy 39.076798 -437.919333) (xy 39.049502 -437.870698)
			(xy 39.029579 -437.818607) (xy 39.017453 -437.76417) (xy 39.013382 -437.708548) (xy 34.538361 -437.708548)
			(xy 34.534289 -437.722081) (xy 34.510617 -437.772578) (xy 34.479844 -437.819091) (xy 34.442627 -437.860628)
			(xy 34.399759 -437.896303) (xy 34.352153 -437.925357) (xy 34.300824 -437.947169) (xy 34.246867 -437.961275)
			(xy 34.19143 -437.967375) (xy 34.135696 -437.965338) (xy 34.080853 -437.955208) (xy 34.028069 -437.937201)
			(xy 33.978469 -437.9117) (xy 33.933111 -437.879249) (xy 33.892962 -437.84054) (xy 33.858876 -437.796397)
			(xy 33.83158 -437.747762) (xy 33.811657 -437.695671) (xy 33.799531 -437.641234) (xy 33.79546 -437.585612)
			(xy 27.569414 -437.585612) (xy 27.569414 -438.561988) (xy 29.444186 -438.561988) (xy 29.448257 -438.506366)
			(xy 29.460383 -438.451929) (xy 29.480306 -438.399838) (xy 29.507602 -438.351203) (xy 29.541688 -438.30706)
			(xy 29.581837 -438.268351) (xy 29.627195 -438.2359) (xy 29.676795 -438.210399) (xy 29.729579 -438.192392)
			(xy 29.784422 -438.182262) (xy 29.840156 -438.180225) (xy 29.895593 -438.186325) (xy 29.94955 -438.200431)
			(xy 30.000879 -438.222243) (xy 30.048485 -438.251297) (xy 30.091353 -438.286972) (xy 30.12857 -438.328509)
			(xy 30.159343 -438.375022) (xy 30.183015 -438.425519) (xy 30.199083 -438.478926) (xy 30.207203 -438.534102)
			(xy 30.20748 -438.549288) (xy 34.63239 -438.549288) (xy 34.636461 -438.493666) (xy 34.648587 -438.439229)
			(xy 34.66851 -438.387138) (xy 34.695806 -438.338503) (xy 34.729892 -438.29436) (xy 34.770041 -438.255651)
			(xy 34.815399 -438.2232) (xy 34.864999 -438.197699) (xy 34.917783 -438.179692) (xy 34.972626 -438.169562)
			(xy 35.02836 -438.167525) (xy 35.083797 -438.173625) (xy 35.137754 -438.187731) (xy 35.189083 -438.209543)
			(xy 35.236689 -438.238597) (xy 35.279557 -438.274272) (xy 35.316774 -438.315809) (xy 35.347547 -438.362322)
			(xy 35.371219 -438.412819) (xy 35.387287 -438.466226) (xy 35.395407 -438.521402) (xy 35.395661 -438.535318)
			(xy 42.74134 -438.535318) (xy 42.745411 -438.479696) (xy 42.757537 -438.425259) (xy 42.77746 -438.373168)
			(xy 42.804756 -438.324533) (xy 42.838842 -438.28039) (xy 42.878991 -438.241681) (xy 42.924349 -438.20923)
			(xy 42.973949 -438.183729) (xy 43.026733 -438.165722) (xy 43.081576 -438.155592) (xy 43.13731 -438.153555)
			(xy 43.192747 -438.159655) (xy 43.246704 -438.173761) (xy 43.298033 -438.195573) (xy 43.345639 -438.224627)
			(xy 43.388507 -438.260302) (xy 43.425724 -438.301839) (xy 43.456497 -438.348352) (xy 43.480169 -438.398849)
			(xy 43.496237 -438.452256) (xy 43.504357 -438.507432) (xy 43.504866 -438.535318) (xy 44.887386 -438.535318)
			(xy 44.891457 -438.479696) (xy 44.903583 -438.425259) (xy 44.923506 -438.373168) (xy 44.950802 -438.324533)
			(xy 44.984888 -438.28039) (xy 45.025037 -438.241681) (xy 45.070395 -438.20923) (xy 45.119995 -438.183729)
			(xy 45.172779 -438.165722) (xy 45.227622 -438.155592) (xy 45.283356 -438.153555) (xy 45.338793 -438.159655)
			(xy 45.391247 -438.173368) (xy 47.571658 -438.173368) (xy 47.575729 -438.117746) (xy 47.587855 -438.063309)
			(xy 47.607778 -438.011218) (xy 47.635074 -437.962583) (xy 47.66916 -437.91844) (xy 47.709309 -437.879731)
			(xy 47.754667 -437.84728) (xy 47.804267 -437.821779) (xy 47.857051 -437.803772) (xy 47.911894 -437.793642)
			(xy 47.967628 -437.791605) (xy 48.023065 -437.797705) (xy 48.077022 -437.811811) (xy 48.128351 -437.833623)
			(xy 48.175957 -437.862677) (xy 48.218825 -437.898352) (xy 48.256042 -437.939889) (xy 48.286815 -437.986402)
			(xy 48.310487 -438.036899) (xy 48.326555 -438.090306) (xy 48.334675 -438.145482) (xy 48.335184 -438.173368)
			(xy 48.334675 -438.201254) (xy 48.326555 -438.25643) (xy 48.310487 -438.309837) (xy 48.286815 -438.360334)
			(xy 48.256042 -438.406847) (xy 48.218825 -438.448384) (xy 48.175957 -438.484059) (xy 48.128351 -438.513113)
			(xy 48.127501 -438.513474) (xy 50.176682 -438.513474) (xy 50.180753 -438.457852) (xy 50.192879 -438.403415)
			(xy 50.212802 -438.351324) (xy 50.240098 -438.302689) (xy 50.274184 -438.258546) (xy 50.314333 -438.219837)
			(xy 50.359691 -438.187386) (xy 50.409291 -438.161885) (xy 50.462075 -438.143878) (xy 50.516918 -438.133748)
			(xy 50.572652 -438.131711) (xy 50.628089 -438.137811) (xy 50.682046 -438.151917) (xy 50.733375 -438.173729)
			(xy 50.780981 -438.202783) (xy 50.823849 -438.238458) (xy 50.861066 -438.279995) (xy 50.891839 -438.326508)
			(xy 50.915511 -438.377005) (xy 50.931579 -438.430412) (xy 50.939699 -438.485588) (xy 50.940208 -438.513474)
			(xy 50.939699 -438.54136) (xy 50.931579 -438.596536) (xy 50.915511 -438.649943) (xy 50.891839 -438.70044)
			(xy 50.861066 -438.746953) (xy 50.823849 -438.78849) (xy 50.780981 -438.824165) (xy 50.733375 -438.853219)
			(xy 50.682046 -438.875031) (xy 50.628089 -438.889137) (xy 50.572652 -438.895237) (xy 50.516918 -438.8932)
			(xy 50.462075 -438.88307) (xy 50.409291 -438.865063) (xy 50.359691 -438.839562) (xy 50.314333 -438.807111)
			(xy 50.274184 -438.768402) (xy 50.240098 -438.724259) (xy 50.212802 -438.675624) (xy 50.192879 -438.623533)
			(xy 50.180753 -438.569096) (xy 50.176682 -438.513474) (xy 48.127501 -438.513474) (xy 48.077022 -438.534925)
			(xy 48.023065 -438.549031) (xy 47.967628 -438.555131) (xy 47.911894 -438.553094) (xy 47.857051 -438.542964)
			(xy 47.804267 -438.524957) (xy 47.754667 -438.499456) (xy 47.709309 -438.467005) (xy 47.66916 -438.428296)
			(xy 47.635074 -438.384153) (xy 47.607778 -438.335518) (xy 47.587855 -438.283427) (xy 47.575729 -438.22899)
			(xy 47.571658 -438.173368) (xy 45.391247 -438.173368) (xy 45.39275 -438.173761) (xy 45.444079 -438.195573)
			(xy 45.491685 -438.224627) (xy 45.534553 -438.260302) (xy 45.57177 -438.301839) (xy 45.602543 -438.348352)
			(xy 45.626215 -438.398849) (xy 45.642283 -438.452256) (xy 45.650403 -438.507432) (xy 45.650912 -438.535318)
			(xy 45.650403 -438.563204) (xy 45.642283 -438.61838) (xy 45.626215 -438.671787) (xy 45.602543 -438.722284)
			(xy 45.57177 -438.768797) (xy 45.534553 -438.810334) (xy 45.491685 -438.846009) (xy 45.444079 -438.875063)
			(xy 45.39275 -438.896875) (xy 45.338793 -438.910981) (xy 45.283356 -438.917081) (xy 45.227622 -438.915044)
			(xy 45.172779 -438.904914) (xy 45.119995 -438.886907) (xy 45.070395 -438.861406) (xy 45.025037 -438.828955)
			(xy 44.984888 -438.790246) (xy 44.950802 -438.746103) (xy 44.923506 -438.697468) (xy 44.903583 -438.645377)
			(xy 44.891457 -438.59094) (xy 44.887386 -438.535318) (xy 43.504866 -438.535318) (xy 43.504357 -438.563204)
			(xy 43.496237 -438.61838) (xy 43.480169 -438.671787) (xy 43.456497 -438.722284) (xy 43.425724 -438.768797)
			(xy 43.388507 -438.810334) (xy 43.345639 -438.846009) (xy 43.298033 -438.875063) (xy 43.246704 -438.896875)
			(xy 43.192747 -438.910981) (xy 43.13731 -438.917081) (xy 43.081576 -438.915044) (xy 43.026733 -438.904914)
			(xy 42.973949 -438.886907) (xy 42.924349 -438.861406) (xy 42.878991 -438.828955) (xy 42.838842 -438.790246)
			(xy 42.804756 -438.746103) (xy 42.77746 -438.697468) (xy 42.757537 -438.645377) (xy 42.745411 -438.59094)
			(xy 42.74134 -438.535318) (xy 35.395661 -438.535318) (xy 35.395916 -438.549288) (xy 35.395407 -438.577174)
			(xy 35.387287 -438.63235) (xy 35.371219 -438.685757) (xy 35.347547 -438.736254) (xy 35.316774 -438.782767)
			(xy 35.279557 -438.824304) (xy 35.236689 -438.859979) (xy 35.189083 -438.889033) (xy 35.137754 -438.910845)
			(xy 35.083797 -438.924951) (xy 35.02836 -438.931051) (xy 34.972626 -438.929014) (xy 34.917783 -438.918884)
			(xy 34.864999 -438.900877) (xy 34.815399 -438.875376) (xy 34.770041 -438.842925) (xy 34.729892 -438.804216)
			(xy 34.695806 -438.760073) (xy 34.66851 -438.711438) (xy 34.648587 -438.659347) (xy 34.636461 -438.60491)
			(xy 34.63239 -438.549288) (xy 30.20748 -438.549288) (xy 30.207712 -438.561988) (xy 30.207203 -438.589874)
			(xy 30.199083 -438.64505) (xy 30.183015 -438.698457) (xy 30.159343 -438.748954) (xy 30.12857 -438.795467)
			(xy 30.091353 -438.837004) (xy 30.048485 -438.872679) (xy 30.000879 -438.901733) (xy 29.94955 -438.923545)
			(xy 29.895593 -438.937651) (xy 29.840156 -438.943751) (xy 29.784422 -438.941714) (xy 29.729579 -438.931584)
			(xy 29.676795 -438.913577) (xy 29.627195 -438.888076) (xy 29.581837 -438.855625) (xy 29.541688 -438.816916)
			(xy 29.507602 -438.772773) (xy 29.480306 -438.724138) (xy 29.460383 -438.672047) (xy 29.448257 -438.61761)
			(xy 29.444186 -438.561988) (xy 27.569414 -438.561988) (xy 27.569414 -439.527188) (xy 29.400752 -439.527188)
			(xy 29.404823 -439.471566) (xy 29.416949 -439.417129) (xy 29.436872 -439.365038) (xy 29.464168 -439.316403)
			(xy 29.498254 -439.27226) (xy 29.538403 -439.233551) (xy 29.583761 -439.2011) (xy 29.633361 -439.175599)
			(xy 29.686145 -439.157592) (xy 29.740988 -439.147462) (xy 29.796722 -439.145425) (xy 29.852159 -439.151525)
			(xy 29.856034 -439.152538) (xy 48.520348 -439.152538) (xy 48.524419 -439.096916) (xy 48.536545 -439.042479)
			(xy 48.556468 -438.990388) (xy 48.583764 -438.941753) (xy 48.61785 -438.89761) (xy 48.657999 -438.858901)
			(xy 48.703357 -438.82645) (xy 48.752957 -438.800949) (xy 48.805741 -438.782942) (xy 48.860584 -438.772812)
			(xy 48.916318 -438.770775) (xy 48.971755 -438.776875) (xy 49.025712 -438.790981) (xy 49.077041 -438.812793)
			(xy 49.124647 -438.841847) (xy 49.167515 -438.877522) (xy 49.204732 -438.919059) (xy 49.235505 -438.965572)
			(xy 49.259177 -439.016069) (xy 49.275245 -439.069476) (xy 49.283365 -439.124652) (xy 49.283874 -439.152538)
			(xy 49.283365 -439.180424) (xy 49.275245 -439.2356) (xy 49.259177 -439.289007) (xy 49.235505 -439.339504)
			(xy 49.204732 -439.386017) (xy 49.167515 -439.427554) (xy 49.124647 -439.463229) (xy 49.077041 -439.492283)
			(xy 49.025712 -439.514095) (xy 48.971755 -439.528201) (xy 48.916318 -439.534301) (xy 48.860584 -439.532264)
			(xy 48.805741 -439.522134) (xy 48.752957 -439.504127) (xy 48.703357 -439.478626) (xy 48.657999 -439.446175)
			(xy 48.61785 -439.407466) (xy 48.583764 -439.363323) (xy 48.556468 -439.314688) (xy 48.536545 -439.262597)
			(xy 48.524419 -439.20816) (xy 48.520348 -439.152538) (xy 29.856034 -439.152538) (xy 29.906116 -439.165631)
			(xy 29.957445 -439.187443) (xy 30.005051 -439.216497) (xy 30.047919 -439.252172) (xy 30.085136 -439.293709)
			(xy 30.115909 -439.340222) (xy 30.139581 -439.390719) (xy 30.155649 -439.444126) (xy 30.163769 -439.499302)
			(xy 30.164278 -439.527188) (xy 30.163769 -439.555074) (xy 30.155649 -439.61025) (xy 30.139581 -439.663657)
			(xy 30.115909 -439.714154) (xy 30.085136 -439.760667) (xy 30.072211 -439.775092) (xy 34.944302 -439.775092)
			(xy 34.948373 -439.71947) (xy 34.960499 -439.665033) (xy 34.980422 -439.612942) (xy 35.007718 -439.564307)
			(xy 35.041804 -439.520164) (xy 35.081953 -439.481455) (xy 35.127311 -439.449004) (xy 35.176911 -439.423503)
			(xy 35.229695 -439.405496) (xy 35.284538 -439.395366) (xy 35.340272 -439.393329) (xy 35.395709 -439.399429)
			(xy 35.449666 -439.413535) (xy 35.500995 -439.435347) (xy 35.548601 -439.464401) (xy 35.591469 -439.500076)
			(xy 35.628686 -439.541613) (xy 35.659459 -439.588126) (xy 35.683131 -439.638623) (xy 35.699199 -439.69203)
			(xy 35.707319 -439.747206) (xy 35.707828 -439.775092) (xy 35.707319 -439.802978) (xy 35.699199 -439.858154)
			(xy 35.683131 -439.911561) (xy 35.659459 -439.962058) (xy 35.628686 -440.008571) (xy 35.591469 -440.050108)
			(xy 35.548601 -440.085783) (xy 35.500995 -440.114837) (xy 35.449666 -440.136649) (xy 35.395709 -440.150755)
			(xy 35.340272 -440.156855) (xy 35.284538 -440.154818) (xy 35.229695 -440.144688) (xy 35.176911 -440.126681)
			(xy 35.127311 -440.10118) (xy 35.081953 -440.068729) (xy 35.041804 -440.03002) (xy 35.007718 -439.985877)
			(xy 34.980422 -439.937242) (xy 34.960499 -439.885151) (xy 34.948373 -439.830714) (xy 34.944302 -439.775092)
			(xy 30.072211 -439.775092) (xy 30.047919 -439.802204) (xy 30.005051 -439.837879) (xy 29.957445 -439.866933)
			(xy 29.906116 -439.888745) (xy 29.852159 -439.902851) (xy 29.796722 -439.908951) (xy 29.740988 -439.906914)
			(xy 29.686145 -439.896784) (xy 29.633361 -439.878777) (xy 29.583761 -439.853276) (xy 29.538403 -439.820825)
			(xy 29.498254 -439.782116) (xy 29.464168 -439.737973) (xy 29.436872 -439.689338) (xy 29.416949 -439.637247)
			(xy 29.404823 -439.58281) (xy 29.400752 -439.527188) (xy 27.569414 -439.527188) (xy 27.569414 -439.558176)
			(xy 28.423108 -440.41187)
		)
		(stroke
			(width 0)
			(type solid)
		)
		(fill yes)
		(layer "In4.Cu")
		(net "P3V3_AUX")
	)
	(gr_poly
		(pts
			(xy 432.741324 -185.397648) (xy 432.727405 -185.37001) (xy 432.707711 -185.311349) (xy 432.697738 -185.250279)
			(xy 432.697128 -185.21934) (xy 432.697614 -185.192071) (xy 432.705376 -185.138087) (xy 432.720741 -185.085757)
			(xy 432.743398 -185.036147) (xy 432.772884 -184.990266) (xy 432.808599 -184.949049) (xy 432.849816 -184.913334)
			(xy 432.895697 -184.883848) (xy 432.945307 -184.861191) (xy 432.997637 -184.845826) (xy 433.051621 -184.838064)
			(xy 433.106159 -184.838064) (xy 433.160143 -184.845826) (xy 433.212473 -184.861191) (xy 433.262083 -184.883848)
			(xy 433.307964 -184.913334) (xy 433.349181 -184.949049) (xy 433.384896 -184.990266) (xy 433.414382 -185.036147)
			(xy 433.437039 -185.085757) (xy 433.452404 -185.138087) (xy 433.460166 -185.192071) (xy 433.460652 -185.21934)
			(xy 433.46005 -185.250279) (xy 433.450066 -185.311347) (xy 433.430367 -185.370006) (xy 433.416456 -185.397648)
			(xy 434.861208 -185.397648) (xy 434.875937 -185.397153) (xy 434.904169 -185.388742) (xy 434.928825 -185.372622)
			(xy 434.947854 -185.350136) (xy 434.959673 -185.323153) (xy 434.963298 -185.293919) (xy 434.958428 -185.264866)
			(xy 434.945467 -185.238412) (xy 434.935884 -185.227214) (xy 434.93436 -185.225436) (xy 434.930042 -185.22061)
			(xy 434.912177 -185.199605) (xy 434.882054 -185.15342) (xy 434.858896 -185.103379) (xy 434.843184 -185.050524)
			(xy 434.835246 -184.995958) (xy 434.834792 -184.968388) (xy 434.834792 -184.959752) (xy 434.835932 -184.931624)
			(xy 434.84546 -184.876143) (xy 434.863035 -184.822663) (xy 434.888277 -184.772346) (xy 434.920637 -184.726283)
			(xy 434.959412 -184.685474) (xy 435.003763 -184.650804) (xy 435.052725 -184.623026) (xy 435.105237 -184.602743)
			(xy 435.16016 -184.590394) (xy 435.2163 -184.586247) (xy 435.27244 -184.590394) (xy 435.327363 -184.602743)
			(xy 435.379875 -184.623026) (xy 435.428837 -184.650804) (xy 435.473188 -184.685474) (xy 435.511963 -184.726283)
			(xy 435.544323 -184.772346) (xy 435.569565 -184.822663) (xy 435.58714 -184.876143) (xy 435.596668 -184.931624)
			(xy 435.597808 -184.959752) (xy 435.597808 -184.968388) (xy 435.597324 -184.995957) (xy 435.58939 -185.050522)
			(xy 435.573686 -185.103376) (xy 435.550538 -185.153421) (xy 435.520429 -185.199612) (xy 435.502558 -185.22061)
			(xy 435.49824 -185.225436) (xy 435.496716 -185.227214) (xy 435.487088 -185.238382) (xy 435.47412 -185.264849)
			(xy 435.469247 -185.293917) (xy 435.472874 -185.323167) (xy 435.484699 -185.350164) (xy 435.503739 -185.372663)
			(xy 435.528408 -185.388791) (xy 435.556655 -185.397207) (xy 435.571392 -185.397648) (xy 447.67754 -185.397648)
			(xy 448.9704 -184.104788) (xy 448.9704 -174.67453) (xy 448.946619 -174.661084) (xy 448.902819 -174.628433)
			(xy 448.864123 -174.589869) (xy 448.831322 -174.546181) (xy 448.805087 -174.498262) (xy 448.785954 -174.447091)
			(xy 448.774314 -174.393715) (xy 448.770405 -174.339224) (xy 448.774307 -174.284733) (xy 448.78594 -174.231355)
			(xy 448.805067 -174.180181) (xy 448.831296 -174.132259) (xy 448.864091 -174.088567) (xy 448.902782 -174.049998)
			(xy 448.946578 -174.017342) (xy 448.9704 -174.00397) (xy 448.9704 -169.255948) (xy 439.7502 -160.035748)
			(xy 439.711084 -160.035748) (xy 439.701224 -160.036209) (xy 439.682959 -160.043648) (xy 439.668845 -160.057422)
			(xy 439.660964 -160.0755) (xy 439.660478 -160.095215) (xy 439.663586 -160.104582) (xy 439.669682 -160.12033)
			(xy 439.67527 -160.126934) (xy 439.691812 -160.147027) (xy 439.719672 -160.190987) (xy 439.741076 -160.238426)
			(xy 439.755598 -160.288403) (xy 439.762949 -160.339926) (xy 439.763408 -160.365948) (xy 439.763408 -167.650668)
			(xy 439.762848 -167.679641) (xy 439.753737 -167.736866) (xy 439.735782 -167.791961) (xy 439.709427 -167.843567)
			(xy 439.675319 -167.890412) (xy 439.655204 -167.911272) (xy 431.969654 -175.597058) (xy 434.095902 -175.597058)
			(xy 434.099991 -175.541176) (xy 434.112174 -175.486486) (xy 434.13219 -175.434152) (xy 434.159613 -175.38529)
			(xy 434.193858 -175.340942) (xy 434.234194 -175.302052) (xy 434.279764 -175.26945) (xy 434.329595 -175.243831)
			(xy 434.382625 -175.225739) (xy 434.437723 -175.215562) (xy 434.493717 -175.213516) (xy 434.549412 -175.219644)
			(xy 434.603621 -175.233816) (xy 434.655189 -175.25573) (xy 434.703017 -175.284919) (xy 434.746085 -175.32076)
			(xy 434.783475 -175.36249) (xy 434.814391 -175.40922) (xy 434.838174 -175.459953) (xy 434.854316 -175.513609)
			(xy 434.862475 -175.569043) (xy 434.862986 -175.597058) (xy 434.862601 -175.61814) (xy 435.603902 -175.61814)
			(xy 435.607973 -175.562518) (xy 435.620099 -175.508081) (xy 435.640022 -175.45599) (xy 435.667318 -175.407355)
			(xy 435.701404 -175.363212) (xy 435.741553 -175.324503) (xy 435.786911 -175.292052) (xy 435.836511 -175.266551)
			(xy 435.889295 -175.248544) (xy 435.944138 -175.238414) (xy 435.999872 -175.236377) (xy 436.055309 -175.242477)
			(xy 436.109266 -175.256583) (xy 436.160595 -175.278395) (xy 436.208201 -175.307449) (xy 436.251069 -175.343124)
			(xy 436.288286 -175.384661) (xy 436.319059 -175.431174) (xy 436.342731 -175.481671) (xy 436.358799 -175.535078)
			(xy 436.366919 -175.590254) (xy 436.367428 -175.61814) (xy 436.366919 -175.646026) (xy 436.358799 -175.701202)
			(xy 436.342731 -175.754609) (xy 436.319059 -175.805106) (xy 436.288286 -175.851619) (xy 436.251069 -175.893156)
			(xy 436.208201 -175.928831) (xy 436.160595 -175.957885) (xy 436.109266 -175.979697) (xy 436.055309 -175.993803)
			(xy 435.999872 -175.999903) (xy 435.944138 -175.997866) (xy 435.889295 -175.987736) (xy 435.836511 -175.969729)
			(xy 435.786911 -175.944228) (xy 435.741553 -175.911777) (xy 435.701404 -175.873068) (xy 435.667318 -175.828925)
			(xy 435.640022 -175.78029) (xy 435.620099 -175.728199) (xy 435.607973 -175.673762) (xy 435.603902 -175.61814)
			(xy 434.862601 -175.61814) (xy 434.862475 -175.625073) (xy 434.854316 -175.680507) (xy 434.838174 -175.734163)
			(xy 434.814391 -175.784896) (xy 434.783475 -175.831626) (xy 434.746085 -175.873356) (xy 434.703017 -175.909197)
			(xy 434.655189 -175.938386) (xy 434.603621 -175.9603) (xy 434.549412 -175.974472) (xy 434.493717 -175.9806)
			(xy 434.437723 -175.978554) (xy 434.382625 -175.968377) (xy 434.329595 -175.950285) (xy 434.279764 -175.924666)
			(xy 434.234194 -175.892064) (xy 434.193858 -175.853174) (xy 434.159613 -175.808826) (xy 434.13219 -175.759964)
			(xy 434.112174 -175.70763) (xy 434.099991 -175.65294) (xy 434.095902 -175.597058) (xy 431.969654 -175.597058)
			(xy 431.547773 -176.018952) (xy 444.68161 -176.018952) (xy 444.682033 -175.991699) (xy 444.689797 -175.937748)
			(xy 444.705159 -175.885451) (xy 444.727807 -175.835872) (xy 444.75728 -175.790021) (xy 444.792978 -175.748831)
			(xy 444.834174 -175.71314) (xy 444.88003 -175.683675) (xy 444.929613 -175.661036) (xy 444.981912 -175.645683)
			(xy 445.035865 -175.637929) (xy 445.063118 -175.637444) (xy 445.08913 -175.637893) (xy 445.140672 -175.644964)
			(xy 445.190775 -175.658973) (xy 445.238509 -175.67966) (xy 445.28299 -175.706641) (xy 445.323393 -175.739415)
			(xy 445.341502 -175.758094) (xy 445.351381 -175.768042) (xy 445.37536 -175.78255) (xy 445.402382 -175.789987)
			(xy 445.430407 -175.789795) (xy 445.457324 -175.781987) (xy 445.481102 -175.767151) (xy 445.490854 -175.757078)
			(xy 445.509036 -175.737781) (xy 445.549776 -175.703855) (xy 445.594821 -175.675895) (xy 445.643302 -175.65444)
			(xy 445.694287 -175.639904) (xy 445.746794 -175.632565) (xy 445.773302 -175.63211) (xy 445.800556 -175.632554)
			(xy 445.854508 -175.640311) (xy 445.906808 -175.655668) (xy 445.956389 -175.678312) (xy 446.002243 -175.707782)
			(xy 446.043436 -175.743478) (xy 446.07913 -175.784673) (xy 446.108597 -175.830529) (xy 446.131239 -175.880111)
			(xy 446.146593 -175.932411) (xy 446.154348 -175.986364) (xy 446.15481 -176.013618) (xy 446.15429 -176.041314)
			(xy 446.146295 -176.096126) (xy 446.130461 -176.149206) (xy 446.10712 -176.19944) (xy 446.076763 -176.245773)
			(xy 446.040027 -176.28723) (xy 446.019174 -176.305464) (xy 446.012336 -176.311719) (xy 446.003266 -176.32786)
			(xy 446.000545 -176.346174) (xy 446.004531 -176.364255) (xy 446.014699 -176.379727) (xy 446.021968 -176.385474)
			(xy 446.049146 -176.407064) (xy 446.060474 -176.4163) (xy 446.087031 -176.428476) (xy 446.115948 -176.432649)
			(xy 446.144865 -176.428476) (xy 446.171422 -176.4163) (xy 446.18275 -176.407064) (xy 446.203685 -176.389429)
			(xy 446.249658 -176.359718) (xy 446.299405 -176.336882) (xy 446.351904 -176.32139) (xy 446.406079 -176.313559)
			(xy 446.433448 -176.313084) (xy 446.460696 -176.313589) (xy 446.514638 -176.321351) (xy 446.566926 -176.33671)
			(xy 446.616496 -176.359353) (xy 446.662339 -176.38882) (xy 446.703523 -176.424511) (xy 446.739209 -176.465699)
			(xy 446.76867 -176.511546) (xy 446.791307 -176.561119) (xy 446.806659 -176.613409) (xy 446.814414 -176.667352)
			(xy 446.814414 -176.721848) (xy 446.806659 -176.775791) (xy 446.791307 -176.828081) (xy 446.76867 -176.877654)
			(xy 446.739209 -176.923501) (xy 446.703523 -176.964689) (xy 446.662339 -177.00038) (xy 446.616496 -177.029847)
			(xy 446.566926 -177.05249) (xy 446.514638 -177.067849) (xy 446.460696 -177.075611) (xy 446.433448 -177.0761)
			(xy 446.406079 -177.075606) (xy 446.351901 -177.067795) (xy 446.299398 -177.052312) (xy 446.249651 -177.029477)
			(xy 446.203683 -176.999758) (xy 446.18275 -176.98212) (xy 446.171422 -176.972884) (xy 446.144865 -176.960708)
			(xy 446.115948 -176.956535) (xy 446.087031 -176.960708) (xy 446.060474 -176.972884) (xy 446.049146 -176.98212)
			(xy 446.02821 -176.999754) (xy 445.982238 -177.029466) (xy 445.932491 -177.052303) (xy 445.879992 -177.067795)
			(xy 445.825817 -177.075625) (xy 445.798448 -177.0761) (xy 445.772434 -177.075691) (xy 445.72089 -177.068614)
			(xy 445.670786 -177.054599) (xy 445.623051 -177.033904) (xy 445.578571 -177.006916) (xy 445.538171 -176.974133)
			(xy 445.520064 -176.95545) (xy 445.510219 -176.945464) (xy 445.486231 -176.930952) (xy 445.4592 -176.923515)
			(xy 445.431165 -176.923714) (xy 445.404242 -176.931534) (xy 445.380462 -176.946385) (xy 445.370712 -176.956466)
			(xy 445.352556 -176.975788) (xy 445.311809 -177.00971) (xy 445.266759 -177.037665) (xy 445.218272 -177.059116)
			(xy 445.167283 -177.073648) (xy 445.114774 -177.080982) (xy 445.088264 -177.081434) (xy 445.061013 -177.080956)
			(xy 445.007066 -177.073195) (xy 444.954773 -177.057837) (xy 444.905197 -177.035193) (xy 444.859349 -177.005726)
			(xy 444.818159 -176.970034) (xy 444.782468 -176.928843) (xy 444.753002 -176.882994) (xy 444.73036 -176.833417)
			(xy 444.715003 -176.781124) (xy 444.707244 -176.727177) (xy 444.706756 -176.699926) (xy 444.707283 -176.671461)
			(xy 444.715757 -176.615165) (xy 444.732506 -176.560755) (xy 444.757158 -176.509439) (xy 444.789165 -176.462358)
			(xy 444.808102 -176.4411) (xy 444.816772 -176.431026) (xy 444.829184 -176.407541) (xy 444.835101 -176.381646)
			(xy 444.834121 -176.3551) (xy 444.826309 -176.329712) (xy 444.812199 -176.307206) (xy 444.802768 -176.297844)
			(xy 444.784021 -176.279718) (xy 444.751106 -176.239272) (xy 444.724005 -176.194722) (xy 444.703222 -176.146895)
			(xy 444.689146 -176.096685) (xy 444.682038 -176.045025) (xy 444.68161 -176.018952) (xy 431.547773 -176.018952)
			(xy 431.381408 -176.185322) (xy 431.381408 -176.904904) (xy 434.675278 -176.904904) (xy 434.679349 -176.849282)
			(xy 434.691475 -176.794845) (xy 434.711398 -176.742754) (xy 434.738694 -176.694119) (xy 434.77278 -176.649976)
			(xy 434.812929 -176.611267) (xy 434.858287 -176.578816) (xy 434.907887 -176.553315) (xy 434.960671 -176.535308)
			(xy 435.015514 -176.525178) (xy 435.071248 -176.523141) (xy 435.126685 -176.529241) (xy 435.180642 -176.543347)
			(xy 435.231971 -176.565159) (xy 435.279577 -176.594213) (xy 435.322445 -176.629888) (xy 435.359662 -176.671425)
			(xy 435.390435 -176.717938) (xy 435.414107 -176.768435) (xy 435.430175 -176.821842) (xy 435.438295 -176.877018)
			(xy 435.438804 -176.904904) (xy 435.438295 -176.93279) (xy 435.430175 -176.987966) (xy 435.414107 -177.041373)
			(xy 435.390435 -177.09187) (xy 435.359662 -177.138383) (xy 435.322445 -177.17992) (xy 435.279577 -177.215595)
			(xy 435.231971 -177.244649) (xy 435.180642 -177.266461) (xy 435.126685 -177.280567) (xy 435.071248 -177.286667)
			(xy 435.015514 -177.28463) (xy 434.960671 -177.2745) (xy 434.907887 -177.256493) (xy 434.858287 -177.230992)
			(xy 434.812929 -177.198541) (xy 434.77278 -177.159832) (xy 434.738694 -177.115689) (xy 434.711398 -177.067054)
			(xy 434.691475 -177.014963) (xy 434.679349 -176.960526) (xy 434.675278 -176.904904) (xy 431.381408 -176.904904)
			(xy 431.381408 -178.044348) (xy 434.953662 -178.044348) (xy 434.957733 -177.988726) (xy 434.969859 -177.934289)
			(xy 434.989782 -177.882198) (xy 435.017078 -177.833563) (xy 435.051164 -177.78942) (xy 435.091313 -177.750711)
			(xy 435.136671 -177.71826) (xy 435.186271 -177.692759) (xy 435.239055 -177.674752) (xy 435.293898 -177.664622)
			(xy 435.349632 -177.662585) (xy 435.405069 -177.668685) (xy 435.459026 -177.682791) (xy 435.510355 -177.704603)
			(xy 435.557961 -177.733657) (xy 435.600829 -177.769332) (xy 435.638046 -177.810869) (xy 435.668819 -177.857382)
			(xy 435.692491 -177.907879) (xy 435.708559 -177.961286) (xy 435.716679 -178.016462) (xy 435.717188 -178.044348)
			(xy 435.716679 -178.072234) (xy 435.708559 -178.12741) (xy 435.692491 -178.180817) (xy 435.668819 -178.231314)
			(xy 435.638046 -178.277827) (xy 435.600829 -178.319364) (xy 435.557961 -178.355039) (xy 435.510355 -178.384093)
			(xy 435.459026 -178.405905) (xy 435.405069 -178.420011) (xy 435.349632 -178.426111) (xy 435.293898 -178.424074)
			(xy 435.239055 -178.413944) (xy 435.186271 -178.395937) (xy 435.136671 -178.370436) (xy 435.091313 -178.337985)
			(xy 435.051164 -178.299276) (xy 435.017078 -178.255133) (xy 434.989782 -178.206498) (xy 434.969859 -178.154407)
			(xy 434.957733 -178.09997) (xy 434.953662 -178.044348) (xy 431.381408 -178.044348) (xy 431.381408 -178.115214)
			(xy 431.488596 -178.222402) (xy 431.512971 -178.237158) (xy 431.557451 -178.272766) (xy 431.596141 -178.314592)
			(xy 431.62818 -178.361707) (xy 431.652857 -178.413063) (xy 431.669622 -178.467517) (xy 431.678103 -178.52386)
			(xy 431.678588 -178.552348) (xy 431.678031 -178.582365) (xy 431.668631 -178.641659) (xy 431.652483 -178.691286)
			(xy 433.98897 -178.691286) (xy 433.993041 -178.635664) (xy 434.005167 -178.581227) (xy 434.02509 -178.529136)
			(xy 434.052386 -178.480501) (xy 434.086472 -178.436358) (xy 434.126621 -178.397649) (xy 434.171979 -178.365198)
			(xy 434.221579 -178.339697) (xy 434.274363 -178.32169) (xy 434.329206 -178.31156) (xy 434.38494 -178.309523)
			(xy 434.440377 -178.315623) (xy 434.494334 -178.329729) (xy 434.545663 -178.351541) (xy 434.593269 -178.380595)
			(xy 434.636137 -178.41627) (xy 434.673354 -178.457807) (xy 434.704127 -178.50432) (xy 434.727799 -178.554817)
			(xy 434.743867 -178.608224) (xy 434.751987 -178.6634) (xy 434.752496 -178.691286) (xy 434.751987 -178.719172)
			(xy 434.743867 -178.774348) (xy 434.727799 -178.827755) (xy 434.72424 -178.835348) (xy 444.707304 -178.835348)
			(xy 444.707304 -178.780852) (xy 444.715059 -178.726911) (xy 444.730411 -178.674623) (xy 444.753048 -178.625052)
			(xy 444.782509 -178.579206) (xy 444.818194 -178.53802) (xy 444.859377 -178.502331) (xy 444.90522 -178.472866)
			(xy 444.954789 -178.450224) (xy 445.007076 -178.434867) (xy 445.061016 -178.427107) (xy 445.088264 -178.426618)
			(xy 445.114278 -178.427013) (xy 445.165823 -178.434092) (xy 445.215928 -178.44811) (xy 445.263663 -178.468807)
			(xy 445.308143 -178.495798) (xy 445.348542 -178.528584) (xy 445.366648 -178.547268) (xy 445.376576 -178.557164)
			(xy 445.40054 -178.571678) (xy 445.42755 -178.579125) (xy 445.455566 -178.578943) (xy 445.482476 -178.571145)
			(xy 445.506249 -178.55632) (xy 445.516 -178.546252) (xy 445.534154 -178.526928) (xy 445.574901 -178.493005)
			(xy 445.619952 -178.46505) (xy 445.668438 -178.4436) (xy 445.719428 -178.429068) (xy 445.771938 -178.421735)
			(xy 445.798448 -178.421284) (xy 445.825818 -178.42176) (xy 445.879998 -178.429572) (xy 445.932501 -178.445058)
			(xy 445.982249 -178.467898) (xy 446.028215 -178.497622) (xy 446.049146 -178.515264) (xy 446.060474 -178.5245)
			(xy 446.087031 -178.536676) (xy 446.115948 -178.540849) (xy 446.144865 -178.536676) (xy 446.171422 -178.5245)
			(xy 446.18275 -178.515264) (xy 446.203685 -178.497629) (xy 446.249658 -178.467918) (xy 446.299405 -178.445082)
			(xy 446.351904 -178.42959) (xy 446.406079 -178.421759) (xy 446.433448 -178.421284) (xy 446.460696 -178.421789)
			(xy 446.514638 -178.429551) (xy 446.566926 -178.44491) (xy 446.616496 -178.467553) (xy 446.662339 -178.49702)
			(xy 446.703523 -178.532711) (xy 446.739209 -178.573899) (xy 446.76867 -178.619746) (xy 446.791307 -178.669319)
			(xy 446.806659 -178.721609) (xy 446.814414 -178.775552) (xy 446.814414 -178.830048) (xy 446.806659 -178.883991)
			(xy 446.791307 -178.936281) (xy 446.76867 -178.985854) (xy 446.739209 -179.031701) (xy 446.703523 -179.072889)
			(xy 446.662339 -179.10858) (xy 446.616496 -179.138047) (xy 446.566926 -179.16069) (xy 446.514638 -179.176049)
			(xy 446.460696 -179.183811) (xy 446.433448 -179.1843) (xy 446.406079 -179.183806) (xy 446.351901 -179.175995)
			(xy 446.299398 -179.160512) (xy 446.249651 -179.137677) (xy 446.203683 -179.107958) (xy 446.18275 -179.09032)
			(xy 446.171422 -179.081084) (xy 446.144865 -179.068908) (xy 446.115948 -179.064735) (xy 446.087031 -179.068908)
			(xy 446.060474 -179.081084) (xy 446.049146 -179.09032) (xy 446.02821 -179.107954) (xy 445.982238 -179.137666)
			(xy 445.932491 -179.160503) (xy 445.879992 -179.175995) (xy 445.825817 -179.183825) (xy 445.798448 -179.1843)
			(xy 445.772434 -179.183891) (xy 445.72089 -179.176814) (xy 445.670786 -179.162799) (xy 445.623051 -179.142104)
			(xy 445.578571 -179.115116) (xy 445.538171 -179.082333) (xy 445.520064 -179.06365) (xy 445.510219 -179.053664)
			(xy 445.486231 -179.039152) (xy 445.4592 -179.031715) (xy 445.431165 -179.031914) (xy 445.404242 -179.039734)
			(xy 445.380462 -179.054585) (xy 445.370712 -179.064666) (xy 445.352556 -179.083988) (xy 445.311809 -179.11791)
			(xy 445.266759 -179.145865) (xy 445.218272 -179.167316) (xy 445.167283 -179.181848) (xy 445.114774 -179.189182)
			(xy 445.088264 -179.189634) (xy 445.061016 -179.189093) (xy 445.007076 -179.181333) (xy 444.954789 -179.165976)
			(xy 444.90522 -179.143334) (xy 444.859377 -179.113869) (xy 444.818194 -179.07818) (xy 444.782509 -179.036994)
			(xy 444.753048 -178.991148) (xy 444.730411 -178.941577) (xy 444.715059 -178.889289) (xy 444.707304 -178.835348)
			(xy 434.72424 -178.835348) (xy 434.704127 -178.878252) (xy 434.673354 -178.924765) (xy 434.636137 -178.966302)
			(xy 434.593269 -179.001977) (xy 434.545663 -179.031031) (xy 434.494334 -179.052843) (xy 434.440377 -179.066949)
			(xy 434.38494 -179.073049) (xy 434.329206 -179.071012) (xy 434.274363 -179.060882) (xy 434.221579 -179.042875)
			(xy 434.171979 -179.017374) (xy 434.126621 -178.984923) (xy 434.086472 -178.946214) (xy 434.052386 -178.902071)
			(xy 434.02509 -178.853436) (xy 434.005167 -178.801345) (xy 433.993041 -178.746908) (xy 433.98897 -178.691286)
			(xy 431.652483 -178.691286) (xy 431.650055 -178.698747) (xy 431.622763 -178.752219) (xy 431.587428 -178.800753)
			(xy 431.566574 -178.82235) (xy 431.557899 -178.832253) (xy 431.545461 -178.855444) (xy 431.539364 -178.881045)
			(xy 431.540013 -178.907354) (xy 431.547367 -178.932622) (xy 431.560934 -178.955172) (xy 431.57013 -178.96459)
			(xy 431.58827 -178.982779) (xy 431.619996 -179.023179) (xy 431.633376 -179.045108) (xy 431.641456 -179.057827)
			(xy 431.663594 -179.078248) (xy 431.69072 -179.091334) (xy 431.720482 -179.095949) (xy 431.750297 -179.091694)
			(xy 431.77758 -179.078937) (xy 431.799962 -179.058785) (xy 431.808128 -179.046124) (xy 431.822992 -179.022268)
			(xy 431.858628 -178.978803) (xy 431.90026 -178.941042) (xy 431.946986 -178.909804) (xy 431.997793 -178.885766)
			(xy 432.051578 -178.869449) (xy 432.107177 -178.861207) (xy 432.13528 -178.860704) (xy 432.162533 -178.861166)
			(xy 432.216484 -178.86892) (xy 432.268783 -178.884274) (xy 432.318364 -178.906915) (xy 432.364218 -178.936381)
			(xy 432.405412 -178.972074) (xy 432.441107 -179.013266) (xy 432.470576 -179.059118) (xy 432.493219 -179.108698)
			(xy 432.508575 -179.160996) (xy 432.516333 -179.214947) (xy 432.516333 -179.269453) (xy 432.508575 -179.323404)
			(xy 432.493219 -179.375702) (xy 432.470576 -179.425282) (xy 432.441107 -179.471134) (xy 432.405412 -179.512326)
			(xy 432.364218 -179.548019) (xy 432.318364 -179.577485) (xy 432.268783 -179.600126) (xy 432.216484 -179.61548)
			(xy 432.162533 -179.623234) (xy 432.13528 -179.62372) (xy 432.106912 -179.623199) (xy 432.050802 -179.614799)
			(xy 431.996554 -179.598186) (xy 431.945361 -179.573726) (xy 431.898354 -179.541959) (xy 431.856565 -179.503583)
			(xy 431.820918 -179.459446) (xy 431.806096 -179.435252) (xy 431.79802 -179.422531) (xy 431.775889 -179.402106)
			(xy 431.748765 -179.389018) (xy 431.719004 -179.384405) (xy 431.68919 -179.388666) (xy 431.661914 -179.401433)
			(xy 431.639542 -179.421595) (xy 431.631344 -179.434236) (xy 431.616481 -179.458093) (xy 431.580847 -179.501559)
			(xy 431.539215 -179.539321) (xy 431.492488 -179.570559) (xy 431.441681 -179.594596) (xy 431.387895 -179.610911)
			(xy 431.332295 -179.61915) (xy 431.304192 -179.619656) (xy 431.27694 -179.61917) (xy 431.22299 -179.611413)
			(xy 431.170694 -179.596057) (xy 431.121115 -179.573416) (xy 431.075262 -179.543951) (xy 431.034069 -179.50826)
			(xy 430.998373 -179.46707) (xy 430.968903 -179.42122) (xy 430.946257 -179.371644) (xy 430.930896 -179.319349)
			(xy 430.923133 -179.2654) (xy 430.922684 -179.238148) (xy 430.923241 -179.208131) (xy 430.932641 -179.148837)
			(xy 430.951216 -179.091748) (xy 430.978507 -179.038275) (xy 431.01384 -178.98974) (xy 431.034698 -178.968146)
			(xy 431.043374 -178.958244) (xy 431.055815 -178.935054) (xy 431.061913 -178.909453) (xy 431.061263 -178.883143)
			(xy 431.053907 -178.857875) (xy 431.040335 -178.835327) (xy 431.031142 -178.825906) (xy 431.030126 -178.82489)
			(xy 431.013055 -178.807644) (xy 430.982987 -178.769556) (xy 430.970182 -178.748944) (xy 430.96688 -178.74361)
			(xy 430.911762 -178.688492) (xy 430.751996 -178.528472) (xy 430.731871 -178.507622) (xy 430.697771 -178.460772)
			(xy 430.671421 -178.409163) (xy 430.653471 -178.354067) (xy 430.644362 -178.296841) (xy 430.643792 -178.267868)
			(xy 430.643792 -176.032668) (xy 430.64435 -176.003694) (xy 430.653455 -175.946465) (xy 430.671406 -175.891367)
			(xy 430.697758 -175.839758) (xy 430.731864 -175.792908) (xy 430.751996 -175.772064) (xy 439.025792 -167.498014)
			(xy 439.025792 -160.518602) (xy 435.019196 -156.511752) (xy 434.999073 -156.490901) (xy 434.964975 -156.444051)
			(xy 434.938627 -156.392442) (xy 434.92068 -156.337346) (xy 434.911575 -156.28012) (xy 434.910992 -156.251148)
			(xy 434.910992 -133.911848) (xy 434.911551 -133.882875) (xy 434.92066 -133.825648) (xy 434.938612 -133.770552)
			(xy 434.964967 -133.718944) (xy 434.999073 -133.672097) (xy 435.019196 -133.651244) (xy 442.752734 -125.917452)
			(xy 442.752734 -121.854214) (xy 438.451498 -117.552978) (xy 429.411892 -117.552978) (xy 429.403002 -117.592856)
			(xy 429.396666 -117.619327) (xy 429.377507 -117.670273) (xy 429.351307 -117.717982) (xy 429.318599 -117.761487)
			(xy 429.280044 -117.799907) (xy 429.236425 -117.832462) (xy 429.188625 -117.858494) (xy 429.137612 -117.877475)
			(xy 429.084421 -117.889019) (xy 429.03013 -117.892893) (xy 428.975839 -117.889019) (xy 428.922648 -117.877475)
			(xy 428.871635 -117.858494) (xy 428.823835 -117.832462) (xy 428.780216 -117.799907) (xy 428.741661 -117.761487)
			(xy 428.708953 -117.717982) (xy 428.682753 -117.670273) (xy 428.663594 -117.619327) (xy 428.657258 -117.592856)
			(xy 428.648368 -117.552978) (xy 428.356522 -117.552978) (xy 428.356522 -117.605048) (xy 428.356522 -117.60962)
			(xy 428.356036 -117.636889) (xy 428.348274 -117.690873) (xy 428.332909 -117.743203) (xy 428.310252 -117.792813)
			(xy 428.280766 -117.838694) (xy 428.245051 -117.879911) (xy 428.203834 -117.915626) (xy 428.157953 -117.945112)
			(xy 428.108343 -117.967769) (xy 428.056013 -117.983134) (xy 428.002029 -117.990896) (xy 427.947491 -117.990896)
			(xy 427.893507 -117.983134) (xy 427.841177 -117.967769) (xy 427.791567 -117.945112) (xy 427.745686 -117.915626)
			(xy 427.704469 -117.879911) (xy 427.668754 -117.838694) (xy 427.639268 -117.792813) (xy 427.616611 -117.743203)
			(xy 427.601246 -117.690873) (xy 427.593484 -117.636889) (xy 427.592998 -117.60962) (xy 427.592998 -117.605048)
			(xy 427.592998 -117.552978) (xy 416.563302 -117.552978) (xy 415.061654 -119.054626) (xy 431.95824 -119.054626)
			(xy 431.962311 -118.999004) (xy 431.974437 -118.944567) (xy 431.99436 -118.892476) (xy 432.021656 -118.843841)
			(xy 432.055742 -118.799698) (xy 432.095891 -118.760989) (xy 432.141249 -118.728538) (xy 432.190849 -118.703037)
			(xy 432.243633 -118.68503) (xy 432.298476 -118.6749) (xy 432.35421 -118.672863) (xy 432.409647 -118.678963)
			(xy 432.463604 -118.693069) (xy 432.514933 -118.714881) (xy 432.562539 -118.743935) (xy 432.605407 -118.77961)
			(xy 432.642624 -118.821147) (xy 432.673397 -118.86766) (xy 432.697069 -118.918157) (xy 432.713137 -118.971564)
			(xy 432.721257 -119.02674) (xy 432.721766 -119.054626) (xy 432.721257 -119.082512) (xy 432.713137 -119.137688)
			(xy 432.697069 -119.191095) (xy 432.696269 -119.192802) (xy 436.989726 -119.192802) (xy 436.993797 -119.13718)
			(xy 437.005923 -119.082743) (xy 437.025846 -119.030652) (xy 437.053142 -118.982017) (xy 437.087228 -118.937874)
			(xy 437.127377 -118.899165) (xy 437.172735 -118.866714) (xy 437.222335 -118.841213) (xy 437.275119 -118.823206)
			(xy 437.329962 -118.813076) (xy 437.385696 -118.811039) (xy 437.441133 -118.817139) (xy 437.49509 -118.831245)
			(xy 437.546419 -118.853057) (xy 437.594025 -118.882111) (xy 437.636893 -118.917786) (xy 437.67411 -118.959323)
			(xy 437.704883 -119.005836) (xy 437.728555 -119.056333) (xy 437.744623 -119.10974) (xy 437.752743 -119.164916)
			(xy 437.753252 -119.192802) (xy 437.752743 -119.220688) (xy 437.744623 -119.275864) (xy 437.728555 -119.329271)
			(xy 437.704883 -119.379768) (xy 437.67411 -119.426281) (xy 437.636893 -119.467818) (xy 437.594025 -119.503493)
			(xy 437.546419 -119.532547) (xy 437.49509 -119.554359) (xy 437.441133 -119.568465) (xy 437.385696 -119.574565)
			(xy 437.329962 -119.572528) (xy 437.275119 -119.562398) (xy 437.222335 -119.544391) (xy 437.172735 -119.51889)
			(xy 437.127377 -119.486439) (xy 437.087228 -119.44773) (xy 437.053142 -119.403587) (xy 437.025846 -119.354952)
			(xy 437.005923 -119.302861) (xy 436.993797 -119.248424) (xy 436.989726 -119.192802) (xy 432.696269 -119.192802)
			(xy 432.673397 -119.241592) (xy 432.642624 -119.288105) (xy 432.605407 -119.329642) (xy 432.562539 -119.365317)
			(xy 432.514933 -119.394371) (xy 432.463604 -119.416183) (xy 432.409647 -119.430289) (xy 432.35421 -119.436389)
			(xy 432.298476 -119.434352) (xy 432.243633 -119.424222) (xy 432.190849 -119.406215) (xy 432.141249 -119.380714)
			(xy 432.095891 -119.348263) (xy 432.055742 -119.309554) (xy 432.021656 -119.265411) (xy 431.99436 -119.216776)
			(xy 431.974437 -119.164685) (xy 431.962311 -119.110248) (xy 431.95824 -119.054626) (xy 415.061654 -119.054626)
			(xy 414.199832 -119.916448) (xy 422.520362 -119.916448) (xy 422.524433 -119.860826) (xy 422.536559 -119.806389)
			(xy 422.556482 -119.754298) (xy 422.583778 -119.705663) (xy 422.617864 -119.66152) (xy 422.658013 -119.622811)
			(xy 422.703371 -119.59036) (xy 422.752971 -119.564859) (xy 422.805755 -119.546852) (xy 422.860598 -119.536722)
			(xy 422.916332 -119.534685) (xy 422.971769 -119.540785) (xy 423.025726 -119.554891) (xy 423.077055 -119.576703)
			(xy 423.089365 -119.584216) (xy 433.69814 -119.584216) (xy 433.702211 -119.528594) (xy 433.714337 -119.474157)
			(xy 433.73426 -119.422066) (xy 433.761556 -119.373431) (xy 433.795642 -119.329288) (xy 433.835791 -119.290579)
			(xy 433.881149 -119.258128) (xy 433.930749 -119.232627) (xy 433.983533 -119.21462) (xy 434.038376 -119.20449)
			(xy 434.09411 -119.202453) (xy 434.149547 -119.208553) (xy 434.203504 -119.222659) (xy 434.254833 -119.244471)
			(xy 434.302439 -119.273525) (xy 434.345307 -119.3092) (xy 434.382524 -119.350737) (xy 434.413297 -119.39725)
			(xy 434.436969 -119.447747) (xy 434.453037 -119.501154) (xy 434.461157 -119.55633) (xy 434.461666 -119.584216)
			(xy 434.96814 -119.584216) (xy 434.972211 -119.528594) (xy 434.984337 -119.474157) (xy 435.00426 -119.422066)
			(xy 435.031556 -119.373431) (xy 435.065642 -119.329288) (xy 435.105791 -119.290579) (xy 435.151149 -119.258128)
			(xy 435.200749 -119.232627) (xy 435.253533 -119.21462) (xy 435.308376 -119.20449) (xy 435.36411 -119.202453)
			(xy 435.419547 -119.208553) (xy 435.473504 -119.222659) (xy 435.524833 -119.244471) (xy 435.572439 -119.273525)
			(xy 435.615307 -119.3092) (xy 435.652524 -119.350737) (xy 435.683297 -119.39725) (xy 435.706969 -119.447747)
			(xy 435.723037 -119.501154) (xy 435.731157 -119.55633) (xy 435.731666 -119.584216) (xy 435.731157 -119.612102)
			(xy 435.723037 -119.667278) (xy 435.706969 -119.720685) (xy 435.683297 -119.771182) (xy 435.652524 -119.817695)
			(xy 435.615307 -119.859232) (xy 435.572439 -119.894907) (xy 435.524833 -119.923961) (xy 435.473504 -119.945773)
			(xy 435.419547 -119.959879) (xy 435.36411 -119.965979) (xy 435.308376 -119.963942) (xy 435.253533 -119.953812)
			(xy 435.200749 -119.935805) (xy 435.151149 -119.910304) (xy 435.105791 -119.877853) (xy 435.065642 -119.839144)
			(xy 435.031556 -119.795001) (xy 435.00426 -119.746366) (xy 434.984337 -119.694275) (xy 434.972211 -119.639838)
			(xy 434.96814 -119.584216) (xy 434.461666 -119.584216) (xy 434.461157 -119.612102) (xy 434.453037 -119.667278)
			(xy 434.436969 -119.720685) (xy 434.413297 -119.771182) (xy 434.382524 -119.817695) (xy 434.345307 -119.859232)
			(xy 434.302439 -119.894907) (xy 434.254833 -119.923961) (xy 434.203504 -119.945773) (xy 434.149547 -119.959879)
			(xy 434.09411 -119.965979) (xy 434.038376 -119.963942) (xy 433.983533 -119.953812) (xy 433.930749 -119.935805)
			(xy 433.881149 -119.910304) (xy 433.835791 -119.877853) (xy 433.795642 -119.839144) (xy 433.761556 -119.795001)
			(xy 433.73426 -119.746366) (xy 433.714337 -119.694275) (xy 433.702211 -119.639838) (xy 433.69814 -119.584216)
			(xy 423.089365 -119.584216) (xy 423.124661 -119.605757) (xy 423.167529 -119.641432) (xy 423.204746 -119.682969)
			(xy 423.235519 -119.729482) (xy 423.259191 -119.779979) (xy 423.275259 -119.833386) (xy 423.283379 -119.888562)
			(xy 423.283888 -119.916448) (xy 423.283379 -119.944334) (xy 423.275259 -119.99951) (xy 423.259191 -120.052917)
			(xy 423.259105 -120.0531) (xy 429.699926 -120.0531) (xy 429.703997 -119.997478) (xy 429.716123 -119.943041)
			(xy 429.736046 -119.89095) (xy 429.763342 -119.842315) (xy 429.797428 -119.798172) (xy 429.837577 -119.759463)
			(xy 429.882935 -119.727012) (xy 429.932535 -119.701511) (xy 429.985319 -119.683504) (xy 430.040162 -119.673374)
			(xy 430.095896 -119.671337) (xy 430.151333 -119.677437) (xy 430.20529 -119.691543) (xy 430.256619 -119.713355)
			(xy 430.304225 -119.742409) (xy 430.347093 -119.778084) (xy 430.38431 -119.819621) (xy 430.415083 -119.866134)
			(xy 430.438755 -119.916631) (xy 430.454823 -119.970038) (xy 430.462943 -120.025214) (xy 430.463452 -120.0531)
			(xy 430.462943 -120.080986) (xy 430.454823 -120.136162) (xy 430.438755 -120.189569) (xy 430.415083 -120.240066)
			(xy 430.38431 -120.286579) (xy 430.347093 -120.328116) (xy 430.304225 -120.363791) (xy 430.256619 -120.392845)
			(xy 430.20529 -120.414657) (xy 430.151333 -120.428763) (xy 430.095896 -120.434863) (xy 430.040162 -120.432826)
			(xy 429.985319 -120.422696) (xy 429.932535 -120.404689) (xy 429.882935 -120.379188) (xy 429.837577 -120.346737)
			(xy 429.797428 -120.308028) (xy 429.763342 -120.263885) (xy 429.736046 -120.21525) (xy 429.716123 -120.163159)
			(xy 429.703997 -120.108722) (xy 429.699926 -120.0531) (xy 423.259105 -120.0531) (xy 423.235519 -120.103414)
			(xy 423.204746 -120.149927) (xy 423.167529 -120.191464) (xy 423.124661 -120.227139) (xy 423.077055 -120.256193)
			(xy 423.025726 -120.278005) (xy 422.971769 -120.292111) (xy 422.916332 -120.298211) (xy 422.860598 -120.296174)
			(xy 422.805755 -120.286044) (xy 422.752971 -120.268037) (xy 422.703371 -120.242536) (xy 422.658013 -120.210085)
			(xy 422.617864 -120.171376) (xy 422.583778 -120.127233) (xy 422.556482 -120.078598) (xy 422.536559 -120.026507)
			(xy 422.524433 -119.97207) (xy 422.520362 -119.916448) (xy 414.199832 -119.916448) (xy 413.618934 -120.497346)
			(xy 435.408576 -120.497346) (xy 435.412647 -120.441724) (xy 435.424773 -120.387287) (xy 435.444696 -120.335196)
			(xy 435.471992 -120.286561) (xy 435.506078 -120.242418) (xy 435.546227 -120.203709) (xy 435.591585 -120.171258)
			(xy 435.641185 -120.145757) (xy 435.693969 -120.12775) (xy 435.748812 -120.11762) (xy 435.804546 -120.115583)
			(xy 435.859983 -120.121683) (xy 435.91394 -120.135789) (xy 435.965269 -120.157601) (xy 436.012875 -120.186655)
			(xy 436.055743 -120.22233) (xy 436.09296 -120.263867) (xy 436.123733 -120.31038) (xy 436.147405 -120.360877)
			(xy 436.163473 -120.414284) (xy 436.171593 -120.46946) (xy 436.172102 -120.497346) (xy 436.171593 -120.525232)
			(xy 436.163473 -120.580408) (xy 436.147405 -120.633815) (xy 436.123733 -120.684312) (xy 436.09296 -120.730825)
			(xy 436.055743 -120.772362) (xy 436.012875 -120.808037) (xy 435.965269 -120.837091) (xy 435.91394 -120.858903)
			(xy 435.859983 -120.873009) (xy 435.804546 -120.879109) (xy 435.748812 -120.877072) (xy 435.693969 -120.866942)
			(xy 435.641185 -120.848935) (xy 435.591585 -120.823434) (xy 435.546227 -120.790983) (xy 435.506078 -120.752274)
			(xy 435.471992 -120.708131) (xy 435.444696 -120.659496) (xy 435.424773 -120.607405) (xy 435.412647 -120.552968)
			(xy 435.408576 -120.497346) (xy 413.618934 -120.497346) (xy 412.039054 -122.077226) (xy 421.87952 -122.077226)
			(xy 421.883591 -122.021604) (xy 421.895717 -121.967167) (xy 421.91564 -121.915076) (xy 421.942936 -121.866441)
			(xy 421.977022 -121.822298) (xy 422.017171 -121.783589) (xy 422.062529 -121.751138) (xy 422.112129 -121.725637)
			(xy 422.164913 -121.70763) (xy 422.219756 -121.6975) (xy 422.27549 -121.695463) (xy 422.330927 -121.701563)
			(xy 422.384884 -121.715669) (xy 422.436213 -121.737481) (xy 422.44561 -121.743216) (xy 428.864014 -121.743216)
			(xy 428.8645 -121.715965) (xy 428.872256 -121.662017) (xy 428.887611 -121.609722) (xy 428.910253 -121.560145)
			(xy 428.939719 -121.514295) (xy 428.97541 -121.473104) (xy 429.016601 -121.437413) (xy 429.062451 -121.407947)
			(xy 429.112028 -121.385305) (xy 429.164323 -121.36995) (xy 429.218271 -121.362194) (xy 429.272773 -121.362194)
			(xy 429.326721 -121.36995) (xy 429.379016 -121.385305) (xy 429.428593 -121.407947) (xy 429.474443 -121.437413)
			(xy 429.515634 -121.473104) (xy 429.551325 -121.514295) (xy 429.557897 -121.524522) (xy 435.516018 -121.524522)
			(xy 435.520089 -121.4689) (xy 435.532215 -121.414463) (xy 435.552138 -121.362372) (xy 435.579434 -121.313737)
			(xy 435.61352 -121.269594) (xy 435.653669 -121.230885) (xy 435.699027 -121.198434) (xy 435.748627 -121.172933)
			(xy 435.801411 -121.154926) (xy 435.856254 -121.144796) (xy 435.911988 -121.142759) (xy 435.967425 -121.148859)
			(xy 436.021382 -121.162965) (xy 436.072711 -121.184777) (xy 436.120317 -121.213831) (xy 436.163185 -121.249506)
			(xy 436.200402 -121.291043) (xy 436.231175 -121.337556) (xy 436.254847 -121.388053) (xy 436.26679 -121.427748)
			(xy 439.280298 -121.427748) (xy 439.284369 -121.372126) (xy 439.296495 -121.317689) (xy 439.316418 -121.265598)
			(xy 439.343714 -121.216963) (xy 439.3778 -121.17282) (xy 439.417949 -121.134111) (xy 439.463307 -121.10166)
			(xy 439.512907 -121.076159) (xy 439.565691 -121.058152) (xy 439.620534 -121.048022) (xy 439.676268 -121.045985)
			(xy 439.731705 -121.052085) (xy 439.785662 -121.066191) (xy 439.836991 -121.088003) (xy 439.884597 -121.117057)
			(xy 439.927465 -121.152732) (xy 439.964682 -121.194269) (xy 439.995455 -121.240782) (xy 440.019127 -121.291279)
			(xy 440.035195 -121.344686) (xy 440.043315 -121.399862) (xy 440.043824 -121.427748) (xy 440.043315 -121.455634)
			(xy 440.035195 -121.51081) (xy 440.019127 -121.564217) (xy 439.995455 -121.614714) (xy 439.964682 -121.661227)
			(xy 439.927465 -121.702764) (xy 439.884597 -121.738439) (xy 439.836991 -121.767493) (xy 439.785662 -121.789305)
			(xy 439.731705 -121.803411) (xy 439.676268 -121.809511) (xy 439.620534 -121.807474) (xy 439.565691 -121.797344)
			(xy 439.512907 -121.779337) (xy 439.463307 -121.753836) (xy 439.417949 -121.721385) (xy 439.3778 -121.682676)
			(xy 439.343714 -121.638533) (xy 439.316418 -121.589898) (xy 439.296495 -121.537807) (xy 439.284369 -121.48337)
			(xy 439.280298 -121.427748) (xy 436.26679 -121.427748) (xy 436.270915 -121.44146) (xy 436.279035 -121.496636)
			(xy 436.279544 -121.524522) (xy 436.279035 -121.552408) (xy 436.270915 -121.607584) (xy 436.254847 -121.660991)
			(xy 436.231175 -121.711488) (xy 436.200402 -121.758001) (xy 436.163185 -121.799538) (xy 436.120317 -121.835213)
			(xy 436.072711 -121.864267) (xy 436.021382 -121.886079) (xy 435.967425 -121.900185) (xy 435.911988 -121.906285)
			(xy 435.856254 -121.904248) (xy 435.801411 -121.894118) (xy 435.748627 -121.876111) (xy 435.699027 -121.85061)
			(xy 435.653669 -121.818159) (xy 435.61352 -121.77945) (xy 435.579434 -121.735307) (xy 435.552138 -121.686672)
			(xy 435.532215 -121.634581) (xy 435.520089 -121.580144) (xy 435.516018 -121.524522) (xy 429.557897 -121.524522)
			(xy 429.580791 -121.560145) (xy 429.603433 -121.609722) (xy 429.618788 -121.662017) (xy 429.626544 -121.715965)
			(xy 429.62703 -121.743216) (xy 429.626439 -121.773043) (xy 429.617165 -121.831972) (xy 429.598829 -121.888738)
			(xy 429.57188 -121.941957) (xy 429.554894 -121.966482) (xy 429.546539 -121.97895) (xy 429.536807 -122.007326)
			(xy 429.535742 -122.037306) (xy 429.543437 -122.066301) (xy 429.559226 -122.091808) (xy 429.570134 -122.102118)
			(xy 429.590087 -122.120342) (xy 429.622741 -122.158506) (xy 441.404246 -122.158506) (xy 441.408317 -122.102884)
			(xy 441.420443 -122.048447) (xy 441.440366 -121.996356) (xy 441.467662 -121.947721) (xy 441.501748 -121.903578)
			(xy 441.541897 -121.864869) (xy 441.587255 -121.832418) (xy 441.636855 -121.806917) (xy 441.689639 -121.78891)
			(xy 441.744482 -121.77878) (xy 441.800216 -121.776743) (xy 441.855653 -121.782843) (xy 441.90961 -121.796949)
			(xy 441.960939 -121.818761) (xy 442.008545 -121.847815) (xy 442.051413 -121.88349) (xy 442.08863 -121.925027)
			(xy 442.119403 -121.97154) (xy 442.143075 -122.022037) (xy 442.159143 -122.075444) (xy 442.167263 -122.13062)
			(xy 442.167772 -122.158506) (xy 442.167263 -122.186392) (xy 442.159143 -122.241568) (xy 442.143075 -122.294975)
			(xy 442.119403 -122.345472) (xy 442.08863 -122.391985) (xy 442.051413 -122.433522) (xy 442.008545 -122.469197)
			(xy 441.960939 -122.498251) (xy 441.90961 -122.520063) (xy 441.855653 -122.534169) (xy 441.800216 -122.540269)
			(xy 441.744482 -122.538232) (xy 441.689639 -122.528102) (xy 441.636855 -122.510095) (xy 441.587255 -122.484594)
			(xy 441.541897 -122.452143) (xy 441.501748 -122.413434) (xy 441.467662 -122.369291) (xy 441.440366 -122.320656)
			(xy 441.420443 -122.268565) (xy 441.408317 -122.214128) (xy 441.404246 -122.158506) (xy 429.622741 -122.158506)
			(xy 429.625216 -122.161399) (xy 429.654204 -122.207001) (xy 429.67647 -122.256236) (xy 429.691569 -122.308119)
			(xy 429.6992 -122.361612) (xy 429.699674 -122.38863) (xy 429.699188 -122.415881) (xy 429.691432 -122.469829)
			(xy 429.676077 -122.522124) (xy 429.653435 -122.571701) (xy 429.623969 -122.617551) (xy 429.588278 -122.658742)
			(xy 429.547087 -122.694433) (xy 429.501237 -122.723899) (xy 429.45166 -122.746541) (xy 429.399365 -122.761896)
			(xy 429.345417 -122.769652) (xy 429.290915 -122.769652) (xy 429.236967 -122.761896) (xy 429.184672 -122.746541)
			(xy 429.135095 -122.723899) (xy 429.089245 -122.694433) (xy 429.048054 -122.658742) (xy 429.012363 -122.617551)
			(xy 428.982897 -122.571701) (xy 428.960255 -122.522124) (xy 428.9449 -122.469829) (xy 428.937144 -122.415881)
			(xy 428.936658 -122.38863) (xy 428.937205 -122.358801) (xy 428.94649 -122.29987) (xy 428.964838 -122.243103)
			(xy 428.991801 -122.189886) (xy 429.008794 -122.165364) (xy 429.017104 -122.152868) (xy 429.026844 -122.124503)
			(xy 429.027919 -122.094532) (xy 429.020235 -122.065542) (xy 429.004456 -122.040038) (xy 428.993554 -122.029728)
			(xy 428.973573 -122.011534) (xy 428.938446 -121.97047) (xy 428.909463 -121.924862) (xy 428.887201 -121.875621)
			(xy 428.872108 -121.823733) (xy 428.864484 -121.770235) (xy 428.864014 -121.743216) (xy 422.44561 -121.743216)
			(xy 422.483819 -121.766535) (xy 422.526687 -121.80221) (xy 422.563904 -121.843747) (xy 422.594677 -121.89026)
			(xy 422.618349 -121.940757) (xy 422.634417 -121.994164) (xy 422.642537 -122.04934) (xy 422.643046 -122.077226)
			(xy 422.642537 -122.105112) (xy 422.634417 -122.160288) (xy 422.618349 -122.213695) (xy 422.594677 -122.264192)
			(xy 422.563904 -122.310705) (xy 422.526687 -122.352242) (xy 422.483819 -122.387917) (xy 422.436213 -122.416971)
			(xy 422.384884 -122.438783) (xy 422.330927 -122.452889) (xy 422.27549 -122.458989) (xy 422.219756 -122.456952)
			(xy 422.164913 -122.446822) (xy 422.112129 -122.428815) (xy 422.062529 -122.403314) (xy 422.017171 -122.370863)
			(xy 421.977022 -122.332154) (xy 421.942936 -122.288011) (xy 421.91564 -122.239376) (xy 421.895717 -122.187285)
			(xy 421.883591 -122.132848) (xy 421.87952 -122.077226) (xy 412.039054 -122.077226) (xy 411.2514 -122.86488)
			(xy 435.519574 -122.86488) (xy 435.523645 -122.809258) (xy 435.535771 -122.754821) (xy 435.555694 -122.70273)
			(xy 435.58299 -122.654095) (xy 435.617076 -122.609952) (xy 435.657225 -122.571243) (xy 435.702583 -122.538792)
			(xy 435.752183 -122.513291) (xy 435.804967 -122.495284) (xy 435.85981 -122.485154) (xy 435.915544 -122.483117)
			(xy 435.970981 -122.489217) (xy 436.024938 -122.503323) (xy 436.076267 -122.525135) (xy 436.123873 -122.554189)
			(xy 436.166741 -122.589864) (xy 436.203958 -122.631401) (xy 436.21542 -122.648726) (xy 437.90057 -122.648726)
			(xy 437.904641 -122.593104) (xy 437.916767 -122.538667) (xy 437.93669 -122.486576) (xy 437.963986 -122.437941)
			(xy 437.998072 -122.393798) (xy 438.038221 -122.355089) (xy 438.083579 -122.322638) (xy 438.133179 -122.297137)
			(xy 438.185963 -122.27913) (xy 438.240806 -122.269) (xy 438.29654 -122.266963) (xy 438.351977 -122.273063)
			(xy 438.405934 -122.287169) (xy 438.457263 -122.308981) (xy 438.504869 -122.338035) (xy 438.547737 -122.37371)
			(xy 438.584954 -122.415247) (xy 438.615727 -122.46176) (xy 438.639399 -122.512257) (xy 438.655467 -122.565664)
			(xy 438.663587 -122.62084) (xy 438.664096 -122.648726) (xy 438.663587 -122.676612) (xy 438.655467 -122.731788)
			(xy 438.639399 -122.785195) (xy 438.615727 -122.835692) (xy 438.584954 -122.882205) (xy 438.547737 -122.923742)
			(xy 438.504869 -122.959417) (xy 438.457263 -122.988471) (xy 438.405934 -123.010283) (xy 438.351977 -123.024389)
			(xy 438.29654 -123.030489) (xy 438.240806 -123.028452) (xy 438.185963 -123.018322) (xy 438.133179 -123.000315)
			(xy 438.083579 -122.974814) (xy 438.038221 -122.942363) (xy 437.998072 -122.903654) (xy 437.963986 -122.859511)
			(xy 437.93669 -122.810876) (xy 437.916767 -122.758785) (xy 437.904641 -122.704348) (xy 437.90057 -122.648726)
			(xy 436.21542 -122.648726) (xy 436.234731 -122.677914) (xy 436.258403 -122.728411) (xy 436.274471 -122.781818)
			(xy 436.282591 -122.836994) (xy 436.2831 -122.86488) (xy 436.282591 -122.892766) (xy 436.274471 -122.947942)
			(xy 436.258403 -123.001349) (xy 436.234731 -123.051846) (xy 436.203958 -123.098359) (xy 436.166741 -123.139896)
			(xy 436.123873 -123.175571) (xy 436.076267 -123.204625) (xy 436.024938 -123.226437) (xy 435.970981 -123.240543)
			(xy 435.915544 -123.246643) (xy 435.85981 -123.244606) (xy 435.804967 -123.234476) (xy 435.752183 -123.216469)
			(xy 435.702583 -123.190968) (xy 435.657225 -123.158517) (xy 435.617076 -123.119808) (xy 435.58299 -123.075665)
			(xy 435.555694 -123.02703) (xy 435.535771 -122.974939) (xy 435.523645 -122.920502) (xy 435.519574 -122.86488)
			(xy 411.2514 -122.86488) (xy 410.800296 -123.315984) (xy 428.176434 -123.315984) (xy 428.180505 -123.260362)
			(xy 428.192631 -123.205925) (xy 428.212554 -123.153834) (xy 428.23985 -123.105199) (xy 428.273936 -123.061056)
			(xy 428.314085 -123.022347) (xy 428.359443 -122.989896) (xy 428.409043 -122.964395) (xy 428.461827 -122.946388)
			(xy 428.51667 -122.936258) (xy 428.572404 -122.934221) (xy 428.627841 -122.940321) (xy 428.681798 -122.954427)
			(xy 428.733127 -122.976239) (xy 428.780733 -123.005293) (xy 428.823601 -123.040968) (xy 428.860818 -123.082505)
			(xy 428.891591 -123.129018) (xy 428.915263 -123.179515) (xy 428.931331 -123.232922) (xy 428.939451 -123.288098)
			(xy 428.93996 -123.315984) (xy 428.939451 -123.34387) (xy 428.931331 -123.399046) (xy 428.915263 -123.452453)
			(xy 428.891591 -123.50295) (xy 428.860818 -123.549463) (xy 428.823601 -123.591) (xy 428.780733 -123.626675)
			(xy 428.733127 -123.655729) (xy 428.681798 -123.677541) (xy 428.627841 -123.691647) (xy 428.572404 -123.697747)
			(xy 428.51667 -123.69571) (xy 428.461827 -123.68558) (xy 428.409043 -123.667573) (xy 428.359443 -123.642072)
			(xy 428.314085 -123.609621) (xy 428.273936 -123.570912) (xy 428.23985 -123.526769) (xy 428.212554 -123.478134)
			(xy 428.192631 -123.426043) (xy 428.180505 -123.371606) (xy 428.176434 -123.315984) (xy 410.800296 -123.315984)
			(xy 410.41574 -123.70054) (xy 410.41574 -123.87199) (xy 435.521606 -123.87199) (xy 435.525677 -123.816368)
			(xy 435.537803 -123.761931) (xy 435.557726 -123.70984) (xy 435.585022 -123.661205) (xy 435.619108 -123.617062)
			(xy 435.659257 -123.578353) (xy 435.704615 -123.545902) (xy 435.754215 -123.520401) (xy 435.806999 -123.502394)
			(xy 435.861842 -123.492264) (xy 435.917576 -123.490227) (xy 435.973013 -123.496327) (xy 436.02697 -123.510433)
			(xy 436.078299 -123.532245) (xy 436.125905 -123.561299) (xy 436.168773 -123.596974) (xy 436.20599 -123.638511)
			(xy 436.223334 -123.664726) (xy 439.889898 -123.664726) (xy 439.893969 -123.609104) (xy 439.906095 -123.554667)
			(xy 439.926018 -123.502576) (xy 439.953314 -123.453941) (xy 439.9874 -123.409798) (xy 440.027549 -123.371089)
			(xy 440.072907 -123.338638) (xy 440.122507 -123.313137) (xy 440.175291 -123.29513) (xy 440.230134 -123.285)
			(xy 440.285868 -123.282963) (xy 440.341305 -123.289063) (xy 440.395262 -123.303169) (xy 440.446591 -123.324981)
			(xy 440.494197 -123.354035) (xy 440.537065 -123.38971) (xy 440.574282 -123.431247) (xy 440.605055 -123.47776)
			(xy 440.628727 -123.528257) (xy 440.644795 -123.581664) (xy 440.652915 -123.63684) (xy 440.653424 -123.664726)
			(xy 440.652915 -123.692612) (xy 440.644795 -123.747788) (xy 440.628727 -123.801195) (xy 440.605055 -123.851692)
			(xy 440.574282 -123.898205) (xy 440.537065 -123.939742) (xy 440.494197 -123.975417) (xy 440.446591 -124.004471)
			(xy 440.395262 -124.026283) (xy 440.341305 -124.040389) (xy 440.285868 -124.046489) (xy 440.230134 -124.044452)
			(xy 440.175291 -124.034322) (xy 440.122507 -124.016315) (xy 440.072907 -123.990814) (xy 440.027549 -123.958363)
			(xy 439.9874 -123.919654) (xy 439.953314 -123.875511) (xy 439.926018 -123.826876) (xy 439.906095 -123.774785)
			(xy 439.893969 -123.720348) (xy 439.889898 -123.664726) (xy 436.223334 -123.664726) (xy 436.236763 -123.685024)
			(xy 436.260435 -123.735521) (xy 436.276503 -123.788928) (xy 436.284623 -123.844104) (xy 436.285132 -123.87199)
			(xy 436.284623 -123.899876) (xy 436.276503 -123.955052) (xy 436.260435 -124.008459) (xy 436.236763 -124.058956)
			(xy 436.20599 -124.105469) (xy 436.168773 -124.147006) (xy 436.125905 -124.182681) (xy 436.078299 -124.211735)
			(xy 436.02697 -124.233547) (xy 435.973013 -124.247653) (xy 435.917576 -124.253753) (xy 435.861842 -124.251716)
			(xy 435.806999 -124.241586) (xy 435.754215 -124.223579) (xy 435.704615 -124.198078) (xy 435.659257 -124.165627)
			(xy 435.619108 -124.126918) (xy 435.585022 -124.082775) (xy 435.557726 -124.03414) (xy 435.537803 -123.982049)
			(xy 435.525677 -123.927612) (xy 435.521606 -123.87199) (xy 410.41574 -123.87199) (xy 410.41574 -124.77242)
			(xy 427.805848 -124.77242) (xy 427.809919 -124.716798) (xy 427.822045 -124.662361) (xy 427.841968 -124.61027)
			(xy 427.869264 -124.561635) (xy 427.90335 -124.517492) (xy 427.943499 -124.478783) (xy 427.988857 -124.446332)
			(xy 428.038457 -124.420831) (xy 428.091241 -124.402824) (xy 428.146084 -124.392694) (xy 428.201818 -124.390657)
			(xy 428.257255 -124.396757) (xy 428.311212 -124.410863) (xy 428.362541 -124.432675) (xy 428.410147 -124.461729)
			(xy 428.453015 -124.497404) (xy 428.490232 -124.538941) (xy 428.521005 -124.585454) (xy 428.544677 -124.635951)
			(xy 428.560745 -124.689358) (xy 428.568865 -124.744534) (xy 428.569374 -124.77242) (xy 428.568865 -124.800306)
			(xy 428.560745 -124.855482) (xy 428.551652 -124.885704) (xy 435.552594 -124.885704) (xy 435.556665 -124.830082)
			(xy 435.568791 -124.775645) (xy 435.588714 -124.723554) (xy 435.61601 -124.674919) (xy 435.650096 -124.630776)
			(xy 435.690245 -124.592067) (xy 435.735603 -124.559616) (xy 435.785203 -124.534115) (xy 435.837987 -124.516108)
			(xy 435.89283 -124.505978) (xy 435.948564 -124.503941) (xy 436.004001 -124.510041) (xy 436.057958 -124.524147)
			(xy 436.109287 -124.545959) (xy 436.156893 -124.575013) (xy 436.199761 -124.610688) (xy 436.236978 -124.652225)
			(xy 436.255834 -124.680726) (xy 439.889898 -124.680726) (xy 439.893969 -124.625104) (xy 439.906095 -124.570667)
			(xy 439.926018 -124.518576) (xy 439.953314 -124.469941) (xy 439.9874 -124.425798) (xy 440.027549 -124.387089)
			(xy 440.072907 -124.354638) (xy 440.122507 -124.329137) (xy 440.175291 -124.31113) (xy 440.230134 -124.301)
			(xy 440.285868 -124.298963) (xy 440.341305 -124.305063) (xy 440.395262 -124.319169) (xy 440.446591 -124.340981)
			(xy 440.494197 -124.370035) (xy 440.537065 -124.40571) (xy 440.574282 -124.447247) (xy 440.605055 -124.49376)
			(xy 440.628727 -124.544257) (xy 440.644795 -124.597664) (xy 440.652915 -124.65284) (xy 440.653424 -124.680726)
			(xy 440.652915 -124.708612) (xy 440.644795 -124.763788) (xy 440.628727 -124.817195) (xy 440.605055 -124.867692)
			(xy 440.574282 -124.914205) (xy 440.537065 -124.955742) (xy 440.494197 -124.991417) (xy 440.446591 -125.020471)
			(xy 440.395262 -125.042283) (xy 440.341305 -125.056389) (xy 440.285868 -125.062489) (xy 440.230134 -125.060452)
			(xy 440.175291 -125.050322) (xy 440.122507 -125.032315) (xy 440.072907 -125.006814) (xy 440.027549 -124.974363)
			(xy 439.9874 -124.935654) (xy 439.953314 -124.891511) (xy 439.926018 -124.842876) (xy 439.906095 -124.790785)
			(xy 439.893969 -124.736348) (xy 439.889898 -124.680726) (xy 436.255834 -124.680726) (xy 436.267751 -124.698738)
			(xy 436.291423 -124.749235) (xy 436.307491 -124.802642) (xy 436.315611 -124.857818) (xy 436.31612 -124.885704)
			(xy 436.315611 -124.91359) (xy 436.307491 -124.968766) (xy 436.291423 -125.022173) (xy 436.267751 -125.07267)
			(xy 436.236978 -125.119183) (xy 436.199761 -125.16072) (xy 436.156893 -125.196395) (xy 436.109287 -125.225449)
			(xy 436.057958 -125.247261) (xy 436.004001 -125.261367) (xy 435.948564 -125.267467) (xy 435.89283 -125.26543)
			(xy 435.837987 -125.2553) (xy 435.785203 -125.237293) (xy 435.735603 -125.211792) (xy 435.690245 -125.179341)
			(xy 435.650096 -125.140632) (xy 435.61601 -125.096489) (xy 435.588714 -125.047854) (xy 435.568791 -124.995763)
			(xy 435.556665 -124.941326) (xy 435.552594 -124.885704) (xy 428.551652 -124.885704) (xy 428.544677 -124.908889)
			(xy 428.521005 -124.959386) (xy 428.490232 -125.005899) (xy 428.453015 -125.047436) (xy 428.410147 -125.083111)
			(xy 428.362541 -125.112165) (xy 428.311212 -125.133977) (xy 428.257255 -125.148083) (xy 428.201818 -125.154183)
			(xy 428.146084 -125.152146) (xy 428.091241 -125.142016) (xy 428.038457 -125.124009) (xy 427.988857 -125.098508)
			(xy 427.943499 -125.066057) (xy 427.90335 -125.027348) (xy 427.869264 -124.983205) (xy 427.841968 -124.93457)
			(xy 427.822045 -124.882479) (xy 427.809919 -124.828042) (xy 427.805848 -124.77242) (xy 410.41574 -124.77242)
			(xy 410.41574 -125.394212) (xy 429.170336 -125.394212) (xy 429.174407 -125.33859) (xy 429.186533 -125.284153)
			(xy 429.206456 -125.232062) (xy 429.233752 -125.183427) (xy 429.267838 -125.139284) (xy 429.307987 -125.100575)
			(xy 429.353345 -125.068124) (xy 429.402945 -125.042623) (xy 429.455729 -125.024616) (xy 429.510572 -125.014486)
			(xy 429.566306 -125.012449) (xy 429.621743 -125.018549) (xy 429.6757 -125.032655) (xy 429.727029 -125.054467)
			(xy 429.774635 -125.083521) (xy 429.817503 -125.119196) (xy 429.85472 -125.160733) (xy 429.885493 -125.207246)
			(xy 429.909165 -125.257743) (xy 429.925233 -125.31115) (xy 429.933353 -125.366326) (xy 429.933862 -125.394212)
			(xy 429.933353 -125.422098) (xy 429.925233 -125.477274) (xy 429.909165 -125.530681) (xy 429.885493 -125.581178)
			(xy 429.85472 -125.627691) (xy 429.817503 -125.669228) (xy 429.774635 -125.704903) (xy 429.727029 -125.733957)
			(xy 429.6757 -125.755769) (xy 429.621743 -125.769875) (xy 429.566306 -125.775975) (xy 429.510572 -125.773938)
			(xy 429.455729 -125.763808) (xy 429.402945 -125.745801) (xy 429.353345 -125.7203) (xy 429.307987 -125.687849)
			(xy 429.267838 -125.64914) (xy 429.233752 -125.604997) (xy 429.206456 -125.556362) (xy 429.186533 -125.504271)
			(xy 429.174407 -125.449834) (xy 429.170336 -125.394212) (xy 410.41574 -125.394212) (xy 410.41574 -125.80366)
			(xy 426.7995 -125.80366) (xy 426.803571 -125.748038) (xy 426.815697 -125.693601) (xy 426.83562 -125.64151)
			(xy 426.862916 -125.592875) (xy 426.897002 -125.548732) (xy 426.937151 -125.510023) (xy 426.982509 -125.477572)
			(xy 427.032109 -125.452071) (xy 427.084893 -125.434064) (xy 427.139736 -125.423934) (xy 427.19547 -125.421897)
			(xy 427.250907 -125.427997) (xy 427.304864 -125.442103) (xy 427.356193 -125.463915) (xy 427.403799 -125.492969)
			(xy 427.446667 -125.528644) (xy 427.483884 -125.570181) (xy 427.514657 -125.616694) (xy 427.538329 -125.667191)
			(xy 427.554397 -125.720598) (xy 427.562517 -125.775774) (xy 427.563026 -125.80366) (xy 427.562517 -125.831546)
			(xy 427.554397 -125.886722) (xy 427.55073 -125.89891) (xy 435.50408 -125.89891) (xy 435.508151 -125.843288)
			(xy 435.520277 -125.788851) (xy 435.5402 -125.73676) (xy 435.567496 -125.688125) (xy 435.601582 -125.643982)
			(xy 435.641731 -125.605273) (xy 435.687089 -125.572822) (xy 435.736689 -125.547321) (xy 435.789473 -125.529314)
			(xy 435.844316 -125.519184) (xy 435.90005 -125.517147) (xy 435.955487 -125.523247) (xy 436.009444 -125.537353)
			(xy 436.060773 -125.559165) (xy 436.108379 -125.588219) (xy 436.151247 -125.623894) (xy 436.188464 -125.665431)
			(xy 436.219237 -125.711944) (xy 436.242909 -125.762441) (xy 436.258977 -125.815848) (xy 436.267097 -125.871024)
			(xy 436.267606 -125.89891) (xy 436.267097 -125.926796) (xy 436.258977 -125.981972) (xy 436.242909 -126.035379)
			(xy 436.219237 -126.085876) (xy 436.188464 -126.132389) (xy 436.151247 -126.173926) (xy 436.108379 -126.209601)
			(xy 436.060773 -126.238655) (xy 436.009444 -126.260467) (xy 435.955487 -126.274573) (xy 435.90005 -126.280673)
			(xy 435.844316 -126.278636) (xy 435.789473 -126.268506) (xy 435.736689 -126.250499) (xy 435.687089 -126.224998)
			(xy 435.641731 -126.192547) (xy 435.601582 -126.153838) (xy 435.567496 -126.109695) (xy 435.5402 -126.06106)
			(xy 435.520277 -126.008969) (xy 435.508151 -125.954532) (xy 435.50408 -125.89891) (xy 427.55073 -125.89891)
			(xy 427.538329 -125.940129) (xy 427.514657 -125.990626) (xy 427.483884 -126.037139) (xy 427.446667 -126.078676)
			(xy 427.403799 -126.114351) (xy 427.356193 -126.143405) (xy 427.304864 -126.165217) (xy 427.250907 -126.179323)
			(xy 427.19547 -126.185423) (xy 427.139736 -126.183386) (xy 427.084893 -126.173256) (xy 427.032109 -126.155249)
			(xy 426.982509 -126.129748) (xy 426.937151 -126.097297) (xy 426.897002 -126.058588) (xy 426.862916 -126.014445)
			(xy 426.83562 -125.96581) (xy 426.815697 -125.913719) (xy 426.803571 -125.859282) (xy 426.7995 -125.80366)
			(xy 410.41574 -125.80366) (xy 410.41574 -127.458247) (xy 429.165816 -127.458247) (xy 429.165816 -127.403753)
			(xy 429.173571 -127.349814) (xy 429.188923 -127.297527) (xy 429.211559 -127.247957) (xy 429.241019 -127.202113)
			(xy 429.276704 -127.160928) (xy 429.317886 -127.12524) (xy 429.363727 -127.095775) (xy 429.413295 -127.073135)
			(xy 429.46558 -127.057778) (xy 429.519519 -127.050019) (xy 429.546766 -127.04953) (xy 429.576816 -127.050124)
			(xy 429.636173 -127.059554) (xy 429.693318 -127.078172) (xy 429.746838 -127.105515) (xy 429.795411 -127.14091)
			(xy 429.817022 -127.161798) (xy 429.827948 -127.171991) (xy 429.85427 -127.186102) (xy 429.883548 -127.192005)
			(xy 429.913282 -127.189196) (xy 429.940936 -127.177914) (xy 429.96415 -127.159121) (xy 429.972978 -127.147066)
			(xy 429.986745 -127.127393) (xy 430.018464 -127.091344) (xy 430.036224 -127.075184) (xy 430.045506 -127.066504)
			(xy 430.059824 -127.045517) (xy 430.068508 -127.021642) (xy 430.07102 -126.996361) (xy 430.069498 -126.983744)
			(xy 430.042506 -126.973126) (xy 429.991838 -126.944899) (xy 429.94602 -126.909337) (xy 429.906104 -126.867256)
			(xy 429.87301 -126.819624) (xy 429.847497 -126.767536) (xy 429.830153 -126.71219) (xy 429.821375 -126.654858)
			(xy 429.820832 -126.625858) (xy 429.821285 -126.598588) (xy 429.829053 -126.544603) (xy 429.844423 -126.492274)
			(xy 429.867084 -126.442664) (xy 429.896573 -126.396783) (xy 429.932292 -126.355566) (xy 429.973512 -126.319852)
			(xy 430.019395 -126.290366) (xy 430.069007 -126.26771) (xy 430.121339 -126.252345) (xy 430.175324 -126.244583)
			(xy 430.202594 -126.244096) (xy 430.220543 -126.244286) (xy 430.256289 -126.247591) (xy 430.273968 -126.2507)
			(xy 430.28362 -126.2507) (xy 430.310872 -126.251159) (xy 430.364821 -126.258919) (xy 430.417117 -126.274277)
			(xy 430.466695 -126.296921) (xy 430.512545 -126.32639) (xy 430.553736 -126.362084) (xy 430.589427 -126.403277)
			(xy 430.618893 -126.44913) (xy 430.641533 -126.498709) (xy 430.656887 -126.551006) (xy 430.664643 -126.604956)
			(xy 430.665128 -126.632208) (xy 430.664654 -126.659166) (xy 430.657062 -126.712545) (xy 430.642031 -126.764323)
			(xy 430.61986 -126.813469) (xy 430.59099 -126.859005) (xy 430.555998 -126.900022) (xy 430.536096 -126.918212)
			(xy 430.525502 -126.928164) (xy 430.509944 -126.952701) (xy 430.501935 -126.980629) (xy 430.502124 -127.009682)
			(xy 430.510495 -127.037504) (xy 430.52637 -127.061838) (xy 430.537112 -127.071628) (xy 430.544805 -127.078327)
			(xy 430.559545 -127.092432) (xy 430.566576 -127.099822) (xy 430.577044 -127.110092) (xy 430.602417 -127.124763)
			(xy 430.63091 -127.131636) (xy 430.660182 -127.130146) (xy 430.687829 -127.120415) (xy 430.711582 -127.103243)
			(xy 430.729488 -127.080039) (xy 430.735232 -127.066548) (xy 430.746045 -127.039951) (xy 430.774487 -126.990078)
			(xy 430.810079 -126.945029) (xy 430.852019 -126.90582) (xy 430.899358 -126.873337) (xy 430.95103 -126.848312)
			(xy 431.005868 -126.83131) (xy 431.062634 -126.822715) (xy 431.09134 -126.8222) (xy 431.091848 -126.8222)
			(xy 431.10222 -126.822278) (xy 431.122932 -126.823423) (xy 431.13325 -126.824486) (xy 431.146494 -126.82561)
			(xy 431.172767 -126.821628) (xy 431.197115 -126.810984) (xy 431.21788 -126.794402) (xy 431.233649 -126.773013)
			(xy 431.243346 -126.748272) (xy 431.246312 -126.721864) (xy 431.244756 -126.708662) (xy 431.242843 -126.694707)
			(xy 431.240806 -126.666612) (xy 431.240692 -126.652528) (xy 431.241181 -126.625276) (xy 431.248935 -126.571326)
			(xy 431.264287 -126.519028) (xy 431.286926 -126.469448) (xy 431.316391 -126.423595) (xy 431.352082 -126.382402)
			(xy 431.393273 -126.346708) (xy 431.439124 -126.31724) (xy 431.488702 -126.294597) (xy 431.540998 -126.27924)
			(xy 431.594948 -126.271483) (xy 431.6222 -126.27102) (xy 431.646145 -126.271364) (xy 431.693659 -126.277356)
			(xy 431.716942 -126.282958) (xy 431.730331 -126.285959) (xy 431.757756 -126.285459) (xy 431.784058 -126.277672)
			(xy 431.807335 -126.263162) (xy 431.825907 -126.242975) (xy 431.838431 -126.218572) (xy 431.841656 -126.205234)
			(xy 431.848089 -126.176987) (xy 431.868334 -126.122708) (xy 431.896552 -126.072114) (xy 431.932094 -126.026367)
			(xy 431.974143 -125.986519) (xy 432.021733 -125.953486) (xy 432.07377 -125.928026) (xy 432.129057 -125.910725)
			(xy 432.186324 -125.901981) (xy 432.21529 -125.90145) (xy 432.24254 -125.901997) (xy 432.296486 -125.909752)
			(xy 432.34878 -125.925105) (xy 432.398356 -125.947744) (xy 432.444205 -125.977209) (xy 432.485394 -126.012899)
			(xy 432.521085 -126.054087) (xy 432.550551 -126.099936) (xy 432.573192 -126.149511) (xy 432.588546 -126.201804)
			(xy 432.596303 -126.25575) (xy 432.596303 -126.31025) (xy 432.588546 -126.364196) (xy 432.573192 -126.416489)
			(xy 432.550551 -126.466064) (xy 432.521085 -126.511913) (xy 432.485394 -126.553101) (xy 432.444205 -126.588791)
			(xy 432.398356 -126.618256) (xy 432.34878 -126.640895) (xy 432.296486 -126.656248) (xy 432.24254 -126.664003)
			(xy 432.21529 -126.664466) (xy 432.191346 -126.664106) (xy 432.143832 -126.658124) (xy 432.120548 -126.652528)
			(xy 432.107159 -126.649527) (xy 432.079735 -126.65003) (xy 432.053435 -126.657818) (xy 432.030158 -126.672328)
			(xy 432.011586 -126.692513) (xy 431.99906 -126.716915) (xy 431.995834 -126.730252) (xy 431.994462 -126.736348)
			(xy 433.246782 -126.736348) (xy 433.250853 -126.680726) (xy 433.262979 -126.626289) (xy 433.282902 -126.574198)
			(xy 433.310198 -126.525563) (xy 433.344284 -126.48142) (xy 433.384433 -126.442711) (xy 433.429791 -126.41026)
			(xy 433.479391 -126.384759) (xy 433.532175 -126.366752) (xy 433.587018 -126.356622) (xy 433.642752 -126.354585)
			(xy 433.698189 -126.360685) (xy 433.752146 -126.374791) (xy 433.803475 -126.396603) (xy 433.851081 -126.425657)
			(xy 433.893949 -126.461332) (xy 433.931166 -126.502869) (xy 433.961939 -126.549382) (xy 433.985611 -126.599879)
			(xy 434.001679 -126.653286) (xy 434.009799 -126.708462) (xy 434.010308 -126.736348) (xy 434.009799 -126.764234)
			(xy 434.001679 -126.81941) (xy 433.985611 -126.872817) (xy 433.961939 -126.923314) (xy 433.931166 -126.969827)
			(xy 433.893949 -127.011364) (xy 433.851081 -127.047039) (xy 433.803475 -127.076093) (xy 433.752146 -127.097905)
			(xy 433.698189 -127.112011) (xy 433.642752 -127.118111) (xy 433.587018 -127.116074) (xy 433.532175 -127.105944)
			(xy 433.479391 -127.087937) (xy 433.429791 -127.062436) (xy 433.384433 -127.029985) (xy 433.344284 -126.991276)
			(xy 433.310198 -126.947133) (xy 433.282902 -126.898498) (xy 433.262979 -126.846407) (xy 433.250853 -126.79197)
			(xy 433.246782 -126.736348) (xy 431.994462 -126.736348) (xy 431.989471 -126.758516) (xy 431.969213 -126.812795)
			(xy 431.940984 -126.863387) (xy 431.905432 -126.909132) (xy 431.863374 -126.948978) (xy 431.815776 -126.982009)
			(xy 431.763733 -127.007466) (xy 431.70844 -127.024764) (xy 431.651168 -127.033506) (xy 431.6222 -127.034036)
			(xy 431.621692 -127.034036) (xy 431.61132 -127.033955) (xy 431.590608 -127.032812) (xy 431.58029 -127.03175)
			(xy 431.567042 -127.030739) (xy 431.540783 -127.034709) (xy 431.516446 -127.045337) (xy 431.495687 -127.0619)
			(xy 431.479918 -127.083269) (xy 431.470215 -127.107989) (xy 431.467237 -127.134379) (xy 431.468784 -127.147574)
			(xy 431.470701 -127.161528) (xy 431.472736 -127.189623) (xy 431.472848 -127.203708) (xy 431.47233 -127.230958)
			(xy 431.464573 -127.284902) (xy 431.44993 -127.334772) (xy 431.877976 -127.334772) (xy 431.882047 -127.27915)
			(xy 431.894173 -127.224713) (xy 431.914096 -127.172622) (xy 431.941392 -127.123987) (xy 431.975478 -127.079844)
			(xy 432.015627 -127.041135) (xy 432.060985 -127.008684) (xy 432.110585 -126.983183) (xy 432.163369 -126.965176)
			(xy 432.218212 -126.955046) (xy 432.273946 -126.953009) (xy 432.329383 -126.959109) (xy 432.38334 -126.973215)
			(xy 432.434669 -126.995027) (xy 432.482275 -127.024081) (xy 432.525143 -127.059756) (xy 432.56236 -127.101293)
			(xy 432.593133 -127.147806) (xy 432.616805 -127.198303) (xy 432.632873 -127.25171) (xy 432.640993 -127.306886)
			(xy 432.641502 -127.334772) (xy 432.640993 -127.362658) (xy 432.632873 -127.417834) (xy 432.616805 -127.471241)
			(xy 432.593133 -127.521738) (xy 432.56236 -127.568251) (xy 432.525143 -127.609788) (xy 432.482275 -127.645463)
			(xy 432.434669 -127.674517) (xy 432.38334 -127.696329) (xy 432.329383 -127.710435) (xy 432.273946 -127.716535)
			(xy 432.218212 -127.714498) (xy 432.163369 -127.704368) (xy 432.110585 -127.686361) (xy 432.060985 -127.66086)
			(xy 432.015627 -127.628409) (xy 431.975478 -127.5897) (xy 431.941392 -127.545557) (xy 431.914096 -127.496922)
			(xy 431.894173 -127.444831) (xy 431.882047 -127.390394) (xy 431.877976 -127.334772) (xy 431.44993 -127.334772)
			(xy 431.449219 -127.337194) (xy 431.42658 -127.386768) (xy 431.397117 -127.432617) (xy 431.361429 -127.473806)
			(xy 431.320242 -127.509497) (xy 431.274397 -127.538965) (xy 431.224824 -127.561608) (xy 431.172533 -127.576966)
			(xy 431.11859 -127.584727) (xy 431.09134 -127.585216) (xy 431.065389 -127.584758) (xy 431.013967 -127.577715)
			(xy 430.963974 -127.563767) (xy 430.916333 -127.543172) (xy 430.871923 -127.51631) (xy 430.831564 -127.483676)
			(xy 430.813464 -127.465074) (xy 430.803058 -127.454737) (xy 430.777668 -127.440069) (xy 430.74916 -127.433203)
			(xy 430.719876 -127.434703) (xy 430.69222 -127.444446) (xy 430.668461 -127.461632) (xy 430.650552 -127.48485)
			(xy 430.644808 -127.498348) (xy 430.634042 -127.524966) (xy 430.605595 -127.574841) (xy 430.569997 -127.619891)
			(xy 430.528051 -127.659099) (xy 430.480704 -127.69158) (xy 430.429025 -127.716602) (xy 430.37418 -127.733598)
			(xy 430.317409 -127.742185) (xy 430.2887 -127.742696) (xy 430.258649 -127.742116) (xy 430.199292 -127.732681)
			(xy 430.142148 -127.71406) (xy 430.088628 -127.686714) (xy 430.040055 -127.651317) (xy 430.018444 -127.630428)
			(xy 430.007554 -127.620193) (xy 429.981221 -127.60608) (xy 429.951932 -127.60018) (xy 429.922189 -127.602997)
			(xy 429.894529 -127.614291) (xy 429.871314 -127.633097) (xy 429.862488 -127.64516) (xy 429.847183 -127.666891)
			(xy 429.811542 -127.706322) (xy 429.77077 -127.740421) (xy 429.725659 -127.768527) (xy 429.677081 -127.790097)
			(xy 429.625978 -127.804711) (xy 429.573342 -127.812088) (xy 429.546766 -127.812546) (xy 429.519519 -127.811981)
			(xy 429.46558 -127.804222) (xy 429.413295 -127.788865) (xy 429.363727 -127.766225) (xy 429.317886 -127.73676)
			(xy 429.276704 -127.701072) (xy 429.241019 -127.659887) (xy 429.211559 -127.614043) (xy 429.188923 -127.564473)
			(xy 429.173571 -127.512186) (xy 429.165816 -127.458247) (xy 410.41574 -127.458247) (xy 410.41574 -136.098534)
			(xy 410.416271 -136.113204) (xy 410.42469 -136.141313) (xy 410.440739 -136.165877) (xy 410.463099 -136.184878)
			(xy 410.489932 -136.196752) (xy 410.519031 -136.200524) (xy 410.548005 -136.195883) (xy 410.57447 -136.183211)
			(xy 410.585666 -136.173718) (xy 417.992814 -128.766316) (xy 418.010911 -128.749064) (xy 418.052458 -128.721262)
			(xy 418.098629 -128.702095) (xy 418.147651 -128.692299) (xy 418.172646 -128.69164) (xy 430.231042 -128.69164)
			(xy 430.256039 -128.692276) (xy 430.305063 -128.702074) (xy 430.351235 -128.721247) (xy 430.392781 -128.749057)
			(xy 430.410874 -128.766316) (xy 430.666398 -129.02184) (xy 430.855374 -129.02184) (xy 431.274474 -128.848358)
			(xy 431.498756 -128.755394) (xy 432.125882 -128.128268) (xy 432.14396 -128.110989) (xy 432.185539 -128.083214)
			(xy 432.208432 -128.07315) (xy 432.808126 -127.824738) (xy 432.823874 -127.818642) (xy 432.846734 -127.812038)
			(xy 432.861191 -127.808836) (xy 432.890602 -127.805402) (xy 432.905408 -127.80518) (xy 433.3367 -127.80518)
			(xy 433.345336 -127.765048) (xy 433.351955 -127.737037) (xy 433.37248 -127.683267) (xy 433.400851 -127.633191)
			(xy 433.436422 -127.587945) (xy 433.478387 -127.548556) (xy 433.525794 -127.515919) (xy 433.577565 -127.490775)
			(xy 433.632527 -127.473693) (xy 433.689431 -127.465063) (xy 433.718208 -127.464566) (xy 433.74546 -127.465052)
			(xy 433.799408 -127.47281) (xy 433.851703 -127.488165) (xy 433.901281 -127.510806) (xy 433.947132 -127.540272)
			(xy 433.988324 -127.575964) (xy 434.024017 -127.617153) (xy 434.053485 -127.663003) (xy 434.076129 -127.71258)
			(xy 434.091487 -127.764875) (xy 434.099246 -127.818822) (xy 434.099716 -127.846074) (xy 434.099273 -127.872454)
			(xy 434.092012 -127.924712) (xy 434.077626 -127.975472) (xy 434.056387 -128.023768) (xy 434.028702 -128.06868)
			(xy 433.995096 -128.109352) (xy 433.956211 -128.145011) (xy 433.912786 -128.174975) (xy 433.889404 -128.187196)
			(xy 433.877045 -128.1939) (xy 433.856315 -128.21288) (xy 433.841552 -128.236797) (xy 433.833878 -128.263835)
			(xy 433.833875 -128.291942) (xy 433.841543 -128.318982) (xy 433.8563 -128.342902) (xy 433.877026 -128.361887)
			(xy 433.889404 -128.368552) (xy 433.912774 -128.380796) (xy 433.956201 -128.410753) (xy 433.995088 -128.446406)
			(xy 434.028695 -128.487075) (xy 434.056381 -128.531985) (xy 434.077618 -128.580279) (xy 434.092002 -128.631039)
			(xy 434.099257 -128.683295) (xy 434.099716 -128.709674) (xy 434.099254 -128.736928) (xy 434.091501 -128.790882)
			(xy 434.076147 -128.843184) (xy 434.053506 -128.892768) (xy 434.024039 -128.938625) (xy 433.988345 -128.979821)
			(xy 433.947152 -129.015518) (xy 433.901298 -129.04499) (xy 433.851716 -129.067635) (xy 433.799416 -129.082993)
			(xy 433.745462 -129.090752) (xy 433.718208 -129.091182) (xy 433.689833 -129.090655) (xy 433.633709 -129.082239)
			(xy 433.579451 -129.065605) (xy 433.528253 -129.04112) (xy 433.481246 -129.009325) (xy 433.439464 -128.97092)
			(xy 433.403829 -128.926751) (xy 433.375128 -128.877793) (xy 433.353992 -128.825125) (xy 433.340887 -128.769908)
			(xy 433.33797 -128.741678) (xy 433.33416 -128.695196) (xy 433.0319 -128.695196) (xy 432.826414 -128.780286)
			(xy 432.665632 -128.846834) (xy 432.038506 -129.47396) (xy 432.020426 -129.491237) (xy 431.978846 -129.519007)
			(xy 431.955956 -129.529078) (xy 431.079148 -129.892298) (xy 431.0634 -129.898394) (xy 431.04054 -129.904998)
			(xy 431.026084 -129.908204) (xy 430.996672 -129.911647) (xy 430.981866 -129.911856) (xy 430.402746 -129.911856)
			(xy 430.37775 -129.911219) (xy 430.328727 -129.901418) (xy 430.282556 -129.882244) (xy 430.241013 -129.854432)
			(xy 430.222914 -129.83718) (xy 429.96739 -129.581656) (xy 418.436298 -129.581656) (xy 417.512217 -130.505708)
			(xy 425.236638 -130.505708) (xy 425.240709 -130.450086) (xy 425.252835 -130.395649) (xy 425.272758 -130.343558)
			(xy 425.300054 -130.294923) (xy 425.33414 -130.25078) (xy 425.374289 -130.212071) (xy 425.419647 -130.17962)
			(xy 425.469247 -130.154119) (xy 425.522031 -130.136112) (xy 425.576874 -130.125982) (xy 425.632608 -130.123945)
			(xy 425.688045 -130.130045) (xy 425.742002 -130.144151) (xy 425.793331 -130.165963) (xy 425.840937 -130.195017)
			(xy 425.883805 -130.230692) (xy 425.921022 -130.272229) (xy 425.951795 -130.318742) (xy 425.956687 -130.329178)
			(xy 429.131728 -130.329178) (xy 429.135799 -130.273556) (xy 429.147925 -130.219119) (xy 429.167848 -130.167028)
			(xy 429.195144 -130.118393) (xy 429.22923 -130.07425) (xy 429.269379 -130.035541) (xy 429.314737 -130.00309)
			(xy 429.364337 -129.977589) (xy 429.417121 -129.959582) (xy 429.471964 -129.949452) (xy 429.527698 -129.947415)
			(xy 429.583135 -129.953515) (xy 429.637092 -129.967621) (xy 429.688421 -129.989433) (xy 429.736027 -130.018487)
			(xy 429.778895 -130.054162) (xy 429.816112 -130.095699) (xy 429.846885 -130.142212) (xy 429.870557 -130.192709)
			(xy 429.886625 -130.246116) (xy 429.894745 -130.301292) (xy 429.895254 -130.329178) (xy 431.304444 -130.329178)
			(xy 431.308515 -130.273556) (xy 431.320641 -130.219119) (xy 431.340564 -130.167028) (xy 431.36786 -130.118393)
			(xy 431.401946 -130.07425) (xy 431.442095 -130.035541) (xy 431.487453 -130.00309) (xy 431.537053 -129.977589)
			(xy 431.589837 -129.959582) (xy 431.64468 -129.949452) (xy 431.700414 -129.947415) (xy 431.755851 -129.953515)
			(xy 431.809808 -129.967621) (xy 431.861137 -129.989433) (xy 431.908743 -130.018487) (xy 431.951611 -130.054162)
			(xy 431.988828 -130.095699) (xy 432.019601 -130.142212) (xy 432.043273 -130.192709) (xy 432.059341 -130.246116)
			(xy 432.067461 -130.301292) (xy 432.06797 -130.329178) (xy 432.067461 -130.357064) (xy 432.059341 -130.41224)
			(xy 432.043273 -130.465647) (xy 432.040337 -130.471911) (xy 433.378888 -130.471911) (xy 433.378894 -130.41741)
			(xy 433.386656 -130.363464) (xy 433.402016 -130.311173) (xy 433.424662 -130.261599) (xy 433.454133 -130.215753)
			(xy 433.489828 -130.174568) (xy 433.531021 -130.138882) (xy 433.576873 -130.109422) (xy 433.626451 -130.086787)
			(xy 433.678746 -130.071438) (xy 433.732693 -130.063688) (xy 433.787194 -130.063694) (xy 433.84114 -130.071457)
			(xy 433.893431 -130.086818) (xy 433.943004 -130.109464) (xy 433.98885 -130.138935) (xy 434.030035 -130.174631)
			(xy 434.06572 -130.215824) (xy 434.09518 -130.261677) (xy 434.117814 -130.311255) (xy 434.133163 -130.36355)
			(xy 434.140912 -130.417497) (xy 434.141372 -130.444748) (xy 434.141021 -130.467824) (xy 434.135445 -130.513638)
			(xy 434.12437 -130.558442) (xy 434.11648 -130.58013) (xy 434.112148 -130.592902) (xy 434.109514 -130.61973)
			(xy 434.113997 -130.646312) (xy 434.125283 -130.670792) (xy 434.142586 -130.691463) (xy 434.164698 -130.706882)
			(xy 434.190076 -130.715973) (xy 434.216949 -130.718102) (xy 434.230272 -130.71602) (xy 434.247635 -130.712941)
			(xy 434.282744 -130.709636) (xy 434.300376 -130.709416) (xy 434.327631 -130.709829) (xy 434.381585 -130.717583)
			(xy 434.433888 -130.732937) (xy 434.483472 -130.755578) (xy 434.52933 -130.785045) (xy 434.570528 -130.820738)
			(xy 434.606226 -130.861931) (xy 434.635699 -130.907785) (xy 434.658346 -130.957367) (xy 434.673707 -131.009668)
			(xy 434.681467 -131.063621) (xy 434.681471 -131.118131) (xy 434.673717 -131.172085) (xy 434.658363 -131.224388)
			(xy 434.635722 -131.273972) (xy 434.606255 -131.31983) (xy 434.570562 -131.361028) (xy 434.529369 -131.396726)
			(xy 434.483515 -131.426199) (xy 434.433933 -131.448846) (xy 434.381632 -131.464207) (xy 434.327679 -131.471967)
			(xy 434.273169 -131.471971) (xy 434.219215 -131.464217) (xy 434.166912 -131.448863) (xy 434.117328 -131.426222)
			(xy 434.07147 -131.396755) (xy 434.030272 -131.361062) (xy 433.994574 -131.319869) (xy 433.965101 -131.274015)
			(xy 433.942454 -131.224433) (xy 433.927093 -131.172132) (xy 433.919333 -131.118179) (xy 433.918868 -131.090924)
			(xy 433.919209 -131.067847) (xy 433.924788 -131.022033) (xy 433.935868 -130.97723) (xy 433.94376 -130.955542)
			(xy 433.948192 -130.942799) (xy 433.950824 -130.915954) (xy 433.946334 -130.889357) (xy 433.935035 -130.864865)
			(xy 433.917716 -130.844186) (xy 433.895585 -130.828766) (xy 433.870188 -130.81968) (xy 433.843298 -130.817562)
			(xy 433.829968 -130.819652) (xy 433.812604 -130.822725) (xy 433.777496 -130.826034) (xy 433.759864 -130.826256)
			(xy 433.732614 -130.825706) (xy 433.678668 -130.817945) (xy 433.626376 -130.802585) (xy 433.576803 -130.77994)
			(xy 433.530957 -130.75047) (xy 433.489771 -130.714775) (xy 433.454085 -130.673583) (xy 433.424624 -130.62773)
			(xy 433.401988 -130.578152) (xy 433.386639 -130.525858) (xy 433.378888 -130.471911) (xy 432.040337 -130.471911)
			(xy 432.019601 -130.516144) (xy 431.988828 -130.562657) (xy 431.951611 -130.604194) (xy 431.908743 -130.639869)
			(xy 431.861137 -130.668923) (xy 431.809808 -130.690735) (xy 431.755851 -130.704841) (xy 431.700414 -130.710941)
			(xy 431.64468 -130.708904) (xy 431.589837 -130.698774) (xy 431.537053 -130.680767) (xy 431.487453 -130.655266)
			(xy 431.442095 -130.622815) (xy 431.401946 -130.584106) (xy 431.36786 -130.539963) (xy 431.340564 -130.491328)
			(xy 431.320641 -130.439237) (xy 431.308515 -130.3848) (xy 431.304444 -130.329178) (xy 429.895254 -130.329178)
			(xy 429.894745 -130.357064) (xy 429.886625 -130.41224) (xy 429.870557 -130.465647) (xy 429.846885 -130.516144)
			(xy 429.816112 -130.562657) (xy 429.778895 -130.604194) (xy 429.736027 -130.639869) (xy 429.688421 -130.668923)
			(xy 429.637092 -130.690735) (xy 429.583135 -130.704841) (xy 429.527698 -130.710941) (xy 429.471964 -130.708904)
			(xy 429.417121 -130.698774) (xy 429.364337 -130.680767) (xy 429.314737 -130.655266) (xy 429.269379 -130.622815)
			(xy 429.22923 -130.584106) (xy 429.195144 -130.539963) (xy 429.167848 -130.491328) (xy 429.147925 -130.439237)
			(xy 429.135799 -130.3848) (xy 429.131728 -130.329178) (xy 425.956687 -130.329178) (xy 425.975467 -130.369239)
			(xy 425.991535 -130.422646) (xy 425.999655 -130.477822) (xy 426.000164 -130.505708) (xy 425.999655 -130.533594)
			(xy 425.991535 -130.58877) (xy 425.975467 -130.642177) (xy 425.951795 -130.692674) (xy 425.926771 -130.730498)
			(xy 427.27829 -130.730498) (xy 427.282361 -130.674876) (xy 427.294487 -130.620439) (xy 427.31441 -130.568348)
			(xy 427.341706 -130.519713) (xy 427.375792 -130.47557) (xy 427.415941 -130.436861) (xy 427.461299 -130.40441)
			(xy 427.510899 -130.378909) (xy 427.563683 -130.360902) (xy 427.618526 -130.350772) (xy 427.67426 -130.348735)
			(xy 427.729697 -130.354835) (xy 427.783654 -130.368941) (xy 427.834983 -130.390753) (xy 427.882589 -130.419807)
			(xy 427.925457 -130.455482) (xy 427.962674 -130.497019) (xy 427.993447 -130.543532) (xy 428.017119 -130.594029)
			(xy 428.033187 -130.647436) (xy 428.041307 -130.702612) (xy 428.041816 -130.730498) (xy 428.041307 -130.758384)
			(xy 428.033187 -130.81356) (xy 428.017119 -130.866967) (xy 427.993447 -130.917464) (xy 427.962674 -130.963977)
			(xy 427.925457 -131.005514) (xy 427.882589 -131.041189) (xy 427.834983 -131.070243) (xy 427.783654 -131.092055)
			(xy 427.729697 -131.106161) (xy 427.67426 -131.112261) (xy 427.618526 -131.110224) (xy 427.563683 -131.100094)
			(xy 427.510899 -131.082087) (xy 427.461299 -131.056586) (xy 427.415941 -131.024135) (xy 427.375792 -130.985426)
			(xy 427.341706 -130.941283) (xy 427.31441 -130.892648) (xy 427.294487 -130.840557) (xy 427.282361 -130.78612)
			(xy 427.27829 -130.730498) (xy 425.926771 -130.730498) (xy 425.921022 -130.739187) (xy 425.883805 -130.780724)
			(xy 425.840937 -130.816399) (xy 425.793331 -130.845453) (xy 425.742002 -130.867265) (xy 425.688045 -130.881371)
			(xy 425.632608 -130.887471) (xy 425.576874 -130.885434) (xy 425.522031 -130.875304) (xy 425.469247 -130.857297)
			(xy 425.419647 -130.831796) (xy 425.374289 -130.799345) (xy 425.33414 -130.760636) (xy 425.300054 -130.716493)
			(xy 425.272758 -130.667858) (xy 425.252835 -130.615767) (xy 425.240709 -130.56133) (xy 425.236638 -130.505708)
			(xy 417.512217 -130.505708) (xy 410.41574 -137.60196) (xy 410.41574 -138.575288) (xy 419.00094 -138.575288)
			(xy 419.001346 -138.550391) (xy 419.007807 -138.501018) (xy 419.020631 -138.452903) (xy 419.039601 -138.406864)
			(xy 419.064394 -138.363681) (xy 419.079172 -138.34364) (xy 419.079172 -131.10464) (xy 426.565568 -131.10464)
			(xy 426.565568 -131.599178) (xy 428.565054 -131.599178) (xy 428.569125 -131.543556) (xy 428.581251 -131.489119)
			(xy 428.601174 -131.437028) (xy 428.62847 -131.388393) (xy 428.662556 -131.34425) (xy 428.702705 -131.305541)
			(xy 428.748063 -131.27309) (xy 428.797663 -131.247589) (xy 428.850447 -131.229582) (xy 428.90529 -131.219452)
			(xy 428.961024 -131.217415) (xy 429.016461 -131.223515) (xy 429.070418 -131.237621) (xy 429.121747 -131.259433)
			(xy 429.169353 -131.288487) (xy 429.212221 -131.324162) (xy 429.249438 -131.365699) (xy 429.280211 -131.412212)
			(xy 429.303883 -131.462709) (xy 429.319951 -131.516116) (xy 429.328071 -131.571292) (xy 429.32858 -131.599178)
			(xy 431.856386 -131.599178) (xy 431.860457 -131.543556) (xy 431.872583 -131.489119) (xy 431.892506 -131.437028)
			(xy 431.919802 -131.388393) (xy 431.953888 -131.34425) (xy 431.994037 -131.305541) (xy 432.039395 -131.27309)
			(xy 432.088995 -131.247589) (xy 432.141779 -131.229582) (xy 432.196622 -131.219452) (xy 432.252356 -131.217415)
			(xy 432.307793 -131.223515) (xy 432.36175 -131.237621) (xy 432.413079 -131.259433) (xy 432.460685 -131.288487)
			(xy 432.503553 -131.324162) (xy 432.54077 -131.365699) (xy 432.571543 -131.412212) (xy 432.595215 -131.462709)
			(xy 432.611283 -131.516116) (xy 432.619403 -131.571292) (xy 432.619912 -131.599178) (xy 432.619403 -131.627064)
			(xy 432.611283 -131.68224) (xy 432.595215 -131.735647) (xy 432.571543 -131.786144) (xy 432.54077 -131.832657)
			(xy 432.503553 -131.874194) (xy 432.460685 -131.909869) (xy 432.413079 -131.938923) (xy 432.36175 -131.960735)
			(xy 432.307793 -131.974841) (xy 432.252356 -131.980941) (xy 432.196622 -131.978904) (xy 432.141779 -131.968774)
			(xy 432.088995 -131.950767) (xy 432.039395 -131.925266) (xy 431.994037 -131.892815) (xy 431.953888 -131.854106)
			(xy 431.919802 -131.809963) (xy 431.892506 -131.761328) (xy 431.872583 -131.709237) (xy 431.860457 -131.6548)
			(xy 431.856386 -131.599178) (xy 429.32858 -131.599178) (xy 429.328071 -131.627064) (xy 429.319951 -131.68224)
			(xy 429.303883 -131.735647) (xy 429.280211 -131.786144) (xy 429.249438 -131.832657) (xy 429.212221 -131.874194)
			(xy 429.169353 -131.909869) (xy 429.121747 -131.938923) (xy 429.070418 -131.960735) (xy 429.016461 -131.974841)
			(xy 428.961024 -131.980941) (xy 428.90529 -131.978904) (xy 428.850447 -131.968774) (xy 428.797663 -131.950767)
			(xy 428.748063 -131.925266) (xy 428.702705 -131.892815) (xy 428.662556 -131.854106) (xy 428.62847 -131.809963)
			(xy 428.601174 -131.761328) (xy 428.581251 -131.709237) (xy 428.569125 -131.6548) (xy 428.565054 -131.599178)
			(xy 426.565568 -131.599178) (xy 426.565568 -132.462778) (xy 431.231292 -132.462778) (xy 431.235363 -132.407156)
			(xy 431.247489 -132.352719) (xy 431.267412 -132.300628) (xy 431.294708 -132.251993) (xy 431.328794 -132.20785)
			(xy 431.368943 -132.169141) (xy 431.414301 -132.13669) (xy 431.463901 -132.111189) (xy 431.516685 -132.093182)
			(xy 431.571528 -132.083052) (xy 431.627262 -132.081015) (xy 431.682699 -132.087115) (xy 431.736656 -132.101221)
			(xy 431.787985 -132.123033) (xy 431.835591 -132.152087) (xy 431.878459 -132.187762) (xy 431.915676 -132.229299)
			(xy 431.946449 -132.275812) (xy 431.970121 -132.326309) (xy 431.986189 -132.379716) (xy 431.994309 -132.434892)
			(xy 431.994818 -132.462778) (xy 431.994309 -132.490664) (xy 431.986189 -132.54584) (xy 431.970121 -132.599247)
			(xy 431.946449 -132.649744) (xy 431.915676 -132.696257) (xy 431.878459 -132.737794) (xy 431.835591 -132.773469)
			(xy 431.787985 -132.802523) (xy 431.736656 -132.824335) (xy 431.682699 -132.838441) (xy 431.627262 -132.844541)
			(xy 431.571528 -132.842504) (xy 431.516685 -132.832374) (xy 431.463901 -132.814367) (xy 431.414301 -132.788866)
			(xy 431.368943 -132.756415) (xy 431.328794 -132.717706) (xy 431.294708 -132.673563) (xy 431.267412 -132.624928)
			(xy 431.247489 -132.572837) (xy 431.235363 -132.5184) (xy 431.231292 -132.462778) (xy 426.565568 -132.462778)
			(xy 426.565568 -133.478778) (xy 429.131728 -133.478778) (xy 429.135799 -133.423156) (xy 429.147925 -133.368719)
			(xy 429.167848 -133.316628) (xy 429.195144 -133.267993) (xy 429.22923 -133.22385) (xy 429.269379 -133.185141)
			(xy 429.314737 -133.15269) (xy 429.364337 -133.127189) (xy 429.417121 -133.109182) (xy 429.471964 -133.099052)
			(xy 429.527698 -133.097015) (xy 429.583135 -133.103115) (xy 429.637092 -133.117221) (xy 429.688421 -133.139033)
			(xy 429.736027 -133.168087) (xy 429.778895 -133.203762) (xy 429.816112 -133.245299) (xy 429.846885 -133.291812)
			(xy 429.870557 -133.342309) (xy 429.886625 -133.395716) (xy 429.894745 -133.450892) (xy 429.895254 -133.478778)
			(xy 429.894745 -133.506664) (xy 429.886625 -133.56184) (xy 429.870557 -133.615247) (xy 429.863684 -133.629908)
			(xy 432.162202 -133.629908) (xy 432.166273 -133.574286) (xy 432.178399 -133.519849) (xy 432.198322 -133.467758)
			(xy 432.225618 -133.419123) (xy 432.259704 -133.37498) (xy 432.299853 -133.336271) (xy 432.345211 -133.30382)
			(xy 432.394811 -133.278319) (xy 432.447595 -133.260312) (xy 432.502438 -133.250182) (xy 432.558172 -133.248145)
			(xy 432.613609 -133.254245) (xy 432.667566 -133.268351) (xy 432.718895 -133.290163) (xy 432.766501 -133.319217)
			(xy 432.809369 -133.354892) (xy 432.846586 -133.396429) (xy 432.877359 -133.442942) (xy 432.901031 -133.493439)
			(xy 432.917099 -133.546846) (xy 432.925219 -133.602022) (xy 432.925728 -133.629908) (xy 432.925219 -133.657794)
			(xy 432.917099 -133.71297) (xy 432.901031 -133.766377) (xy 432.877359 -133.816874) (xy 432.846586 -133.863387)
			(xy 432.809369 -133.904924) (xy 432.766501 -133.940599) (xy 432.718895 -133.969653) (xy 432.667566 -133.991465)
			(xy 432.613609 -134.005571) (xy 432.558172 -134.011671) (xy 432.502438 -134.009634) (xy 432.447595 -133.999504)
			(xy 432.394811 -133.981497) (xy 432.345211 -133.955996) (xy 432.299853 -133.923545) (xy 432.259704 -133.884836)
			(xy 432.225618 -133.840693) (xy 432.198322 -133.792058) (xy 432.178399 -133.739967) (xy 432.166273 -133.68553)
			(xy 432.162202 -133.629908) (xy 429.863684 -133.629908) (xy 429.846885 -133.665744) (xy 429.816112 -133.712257)
			(xy 429.778895 -133.753794) (xy 429.736027 -133.789469) (xy 429.688421 -133.818523) (xy 429.637092 -133.840335)
			(xy 429.583135 -133.854441) (xy 429.527698 -133.860541) (xy 429.471964 -133.858504) (xy 429.417121 -133.848374)
			(xy 429.364337 -133.830367) (xy 429.314737 -133.804866) (xy 429.269379 -133.772415) (xy 429.22923 -133.733706)
			(xy 429.195144 -133.689563) (xy 429.167848 -133.640928) (xy 429.147925 -133.588837) (xy 429.135799 -133.5344)
			(xy 429.131728 -133.478778) (xy 426.565568 -133.478778) (xy 426.565568 -134.747762) (xy 429.158398 -134.747762)
			(xy 429.162469 -134.69214) (xy 429.174595 -134.637703) (xy 429.194518 -134.585612) (xy 429.221814 -134.536977)
			(xy 429.2559 -134.492834) (xy 429.296049 -134.454125) (xy 429.341407 -134.421674) (xy 429.391007 -134.396173)
			(xy 429.443791 -134.378166) (xy 429.498634 -134.368036) (xy 429.554368 -134.365999) (xy 429.609805 -134.372099)
			(xy 429.663762 -134.386205) (xy 429.715091 -134.408017) (xy 429.762697 -134.437071) (xy 429.805565 -134.472746)
			(xy 429.842782 -134.514283) (xy 429.873555 -134.560796) (xy 429.897227 -134.611293) (xy 429.913295 -134.6647)
			(xy 429.921415 -134.719876) (xy 429.921924 -134.747762) (xy 429.921415 -134.775648) (xy 429.913295 -134.830824)
			(xy 429.897227 -134.884231) (xy 429.873555 -134.934728) (xy 429.842782 -134.981241) (xy 429.805565 -135.022778)
			(xy 429.762697 -135.058453) (xy 429.715091 -135.087507) (xy 429.663762 -135.109319) (xy 429.609805 -135.123425)
			(xy 429.554368 -135.129525) (xy 429.498634 -135.127488) (xy 429.443791 -135.117358) (xy 429.391007 -135.099351)
			(xy 429.341407 -135.07385) (xy 429.296049 -135.041399) (xy 429.2559 -135.00269) (xy 429.221814 -134.958547)
			(xy 429.194518 -134.909912) (xy 429.174595 -134.857821) (xy 429.162469 -134.803384) (xy 429.158398 -134.747762)
			(xy 426.565568 -134.747762) (xy 426.565568 -137.130028) (xy 428.753016 -137.130028) (xy 428.753463 -137.103293)
			(xy 428.760925 -137.050348) (xy 428.775708 -136.998963) (xy 428.797521 -136.950146) (xy 428.825937 -136.904853)
			(xy 428.860399 -136.863971) (xy 428.880016 -136.845802) (xy 428.890822 -136.835406) (xy 428.906368 -136.809781)
			(xy 428.913789 -136.780743) (xy 428.912443 -136.750802) (xy 428.902446 -136.722547) (xy 428.893986 -136.710166)
			(xy 428.876517 -136.68545) (xy 428.848814 -136.631639) (xy 428.829949 -136.574132) (xy 428.820397 -136.514367)
			(xy 428.819818 -136.484106) (xy 428.82029 -136.455888) (xy 428.828576 -136.400063) (xy 428.844998 -136.34607)
			(xy 428.869197 -136.295085) (xy 428.900645 -136.248223) (xy 428.938655 -136.206507) (xy 428.982397 -136.170847)
			(xy 429.030917 -136.142022) (xy 429.083154 -136.120661) (xy 429.137969 -136.107232) (xy 429.16602 -136.104122)
			(xy 429.180402 -136.102296) (xy 429.207356 -136.091662) (xy 429.230235 -136.073881) (xy 429.247195 -136.050386)
			(xy 429.256869 -136.023073) (xy 429.258478 -135.994141) (xy 429.255682 -135.979916) (xy 429.250944 -135.958447)
			(xy 429.245847 -135.914777) (xy 429.245522 -135.892794) (xy 429.246008 -135.865543) (xy 429.253764 -135.811595)
			(xy 429.269119 -135.7593) (xy 429.291761 -135.709723) (xy 429.321227 -135.663873) (xy 429.356918 -135.622682)
			(xy 429.398109 -135.586991) (xy 429.443959 -135.557525) (xy 429.493536 -135.534883) (xy 429.545831 -135.519528)
			(xy 429.599779 -135.511772) (xy 429.654281 -135.511772) (xy 429.708229 -135.519528) (xy 429.760524 -135.534883)
			(xy 429.782825 -135.545068) (xy 431.227736 -135.545068) (xy 431.231807 -135.489446) (xy 431.243933 -135.435009)
			(xy 431.263856 -135.382918) (xy 431.291152 -135.334283) (xy 431.325238 -135.29014) (xy 431.365387 -135.251431)
			(xy 431.410745 -135.21898) (xy 431.460345 -135.193479) (xy 431.513129 -135.175472) (xy 431.567972 -135.165342)
			(xy 431.623706 -135.163305) (xy 431.679143 -135.169405) (xy 431.7331 -135.183511) (xy 431.784429 -135.205323)
			(xy 431.832035 -135.234377) (xy 431.874903 -135.270052) (xy 431.91212 -135.311589) (xy 431.942893 -135.358102)
			(xy 431.966565 -135.408599) (xy 431.982633 -135.462006) (xy 431.990753 -135.517182) (xy 431.991262 -135.545068)
			(xy 431.990753 -135.572954) (xy 431.982633 -135.62813) (xy 431.966565 -135.681537) (xy 431.942893 -135.732034)
			(xy 431.91212 -135.778547) (xy 431.887022 -135.806558) (xy 432.659911 -135.806558) (xy 432.659911 -135.752042)
			(xy 432.66767 -135.698081) (xy 432.68303 -135.645773) (xy 432.705678 -135.596185) (xy 432.735154 -135.550324)
			(xy 432.770857 -135.509125) (xy 432.812059 -135.473428) (xy 432.857923 -135.443957) (xy 432.907515 -135.421315)
			(xy 432.959824 -135.405961) (xy 433.013786 -135.398208) (xy 433.041044 -135.397748) (xy 433.071983 -135.398373)
			(xy 433.133051 -135.408358) (xy 433.191705 -135.428075) (xy 433.246404 -135.457005) (xy 433.271422 -135.475218)
			(xy 433.282668 -135.48321) (xy 433.308295 -135.493405) (xy 433.335716 -135.496354) (xy 433.362924 -135.491841)
			(xy 433.387925 -135.480197) (xy 433.408887 -135.462274) (xy 433.416964 -135.451088) (xy 433.432273 -135.429314)
			(xy 433.467904 -135.389775) (xy 433.508688 -135.355577) (xy 433.553832 -135.327383) (xy 433.602458 -135.305741)
			(xy 433.653621 -135.291072) (xy 433.706328 -135.283661) (xy 433.73294 -135.283194) (xy 433.76019 -135.283679)
			(xy 433.814133 -135.29144) (xy 433.866423 -135.306798) (xy 433.915996 -135.329442) (xy 433.961842 -135.358909)
			(xy 434.003027 -135.394601) (xy 434.038715 -135.435791) (xy 434.068177 -135.481639) (xy 434.090816 -135.531214)
			(xy 434.106169 -135.583506) (xy 434.113924 -135.63745) (xy 434.113924 -135.69195) (xy 434.106169 -135.745894)
			(xy 434.090816 -135.798186) (xy 434.068177 -135.847761) (xy 434.038715 -135.893609) (xy 434.003027 -135.934799)
			(xy 433.961842 -135.970491) (xy 433.915996 -135.999958) (xy 433.866423 -136.022602) (xy 433.814133 -136.03796)
			(xy 433.76019 -136.045721) (xy 433.73294 -136.04621) (xy 433.702 -136.045601) (xy 433.640931 -136.035612)
			(xy 433.582277 -136.015891) (xy 433.527579 -135.986955) (xy 433.502562 -135.96874) (xy 433.491321 -135.960741)
			(xy 433.465693 -135.950554) (xy 433.438271 -135.94761) (xy 433.411064 -135.952124) (xy 433.386063 -135.963767)
			(xy 433.365099 -135.981685) (xy 433.35702 -135.99287) (xy 433.341708 -136.014642) (xy 433.306079 -136.054183)
			(xy 433.265296 -136.088383) (xy 433.220153 -136.116578) (xy 433.171527 -136.13822) (xy 433.120363 -136.152888)
			(xy 433.067656 -136.160298) (xy 433.041044 -136.160764) (xy 433.013786 -136.160392) (xy 432.959824 -136.152639)
			(xy 432.907515 -136.137285) (xy 432.857923 -136.114643) (xy 432.812059 -136.085172) (xy 432.770857 -136.049475)
			(xy 432.735154 -136.008276) (xy 432.705678 -135.962415) (xy 432.68303 -135.912827) (xy 432.66767 -135.860519)
			(xy 432.659911 -135.806558) (xy 431.887022 -135.806558) (xy 431.874903 -135.820084) (xy 431.832035 -135.855759)
			(xy 431.784429 -135.884813) (xy 431.7331 -135.906625) (xy 431.679143 -135.920731) (xy 431.623706 -135.926831)
			(xy 431.567972 -135.924794) (xy 431.513129 -135.914664) (xy 431.460345 -135.896657) (xy 431.410745 -135.871156)
			(xy 431.365387 -135.838705) (xy 431.325238 -135.799996) (xy 431.291152 -135.755853) (xy 431.263856 -135.707218)
			(xy 431.243933 -135.655127) (xy 431.231807 -135.60069) (xy 431.227736 -135.545068) (xy 429.782825 -135.545068)
			(xy 429.810101 -135.557525) (xy 429.855951 -135.586991) (xy 429.897142 -135.622682) (xy 429.932833 -135.663873)
			(xy 429.962299 -135.709723) (xy 429.984941 -135.7593) (xy 430.000296 -135.811595) (xy 430.008052 -135.865543)
			(xy 430.008538 -135.892794) (xy 430.008015 -135.92101) (xy 429.999731 -135.97683) (xy 429.983312 -136.030819)
			(xy 429.959117 -136.081801) (xy 429.927675 -136.128661) (xy 429.889671 -136.170376) (xy 429.845935 -136.206037)
			(xy 429.797423 -136.234864) (xy 429.745192 -136.256229) (xy 429.690384 -136.269664) (xy 429.662336 -136.272778)
			(xy 429.64796 -136.274645) (xy 429.621005 -136.285266) (xy 429.598123 -136.303038) (xy 429.58116 -136.326525)
			(xy 429.571485 -136.353834) (xy 429.569877 -136.382761) (xy 429.572674 -136.396984) (xy 429.577413 -136.418453)
			(xy 429.582509 -136.462123) (xy 429.582834 -136.484106) (xy 429.582359 -136.51084) (xy 429.574905 -136.563785)
			(xy 429.560129 -136.61517) (xy 429.538321 -136.663988) (xy 429.509909 -136.709281) (xy 429.47545 -136.750163)
			(xy 429.455834 -136.768332) (xy 429.444998 -136.778702) (xy 429.429448 -136.804333) (xy 429.422029 -136.83338)
			(xy 429.423384 -136.863329) (xy 429.433395 -136.891588) (xy 429.441864 -136.903968) (xy 429.459298 -136.928708)
			(xy 429.487011 -136.982509) (xy 429.505885 -137.04001) (xy 429.515448 -137.099769) (xy 429.516032 -137.130028)
			(xy 429.515546 -137.157279) (xy 429.50779 -137.211227) (xy 429.492435 -137.263522) (xy 429.469793 -137.313099)
			(xy 429.440327 -137.358949) (xy 429.404636 -137.40014) (xy 429.363445 -137.435831) (xy 429.317595 -137.465297)
			(xy 429.268018 -137.487939) (xy 429.215723 -137.503294) (xy 429.161775 -137.51105) (xy 429.107273 -137.51105)
			(xy 429.053325 -137.503294) (xy 429.00103 -137.487939) (xy 428.951453 -137.465297) (xy 428.905603 -137.435831)
			(xy 428.864412 -137.40014) (xy 428.828721 -137.358949) (xy 428.799255 -137.313099) (xy 428.776613 -137.263522)
			(xy 428.761258 -137.211227) (xy 428.753502 -137.157279) (xy 428.753016 -137.130028) (xy 426.565568 -137.130028)
			(xy 426.565568 -137.542778) (xy 431.333146 -137.542778) (xy 431.337217 -137.487156) (xy 431.349343 -137.432719)
			(xy 431.369266 -137.380628) (xy 431.396562 -137.331993) (xy 431.430648 -137.28785) (xy 431.470797 -137.249141)
			(xy 431.516155 -137.21669) (xy 431.565755 -137.191189) (xy 431.618539 -137.173182) (xy 431.673382 -137.163052)
			(xy 431.729116 -137.161015) (xy 431.784553 -137.167115) (xy 431.83851 -137.181221) (xy 431.889839 -137.203033)
			(xy 431.937445 -137.232087) (xy 431.980313 -137.267762) (xy 432.01753 -137.309299) (xy 432.048303 -137.355812)
			(xy 432.071975 -137.406309) (xy 432.085293 -137.450576) (xy 433.794406 -137.450576) (xy 433.798477 -137.394954)
			(xy 433.810603 -137.340517) (xy 433.830526 -137.288426) (xy 433.857822 -137.239791) (xy 433.891908 -137.195648)
			(xy 433.932057 -137.156939) (xy 433.977415 -137.124488) (xy 434.027015 -137.098987) (xy 434.079799 -137.08098)
			(xy 434.134642 -137.07085) (xy 434.190376 -137.068813) (xy 434.245813 -137.074913) (xy 434.29977 -137.089019)
			(xy 434.351099 -137.110831) (xy 434.398705 -137.139885) (xy 434.441573 -137.17556) (xy 434.47879 -137.217097)
			(xy 434.509563 -137.26361) (xy 434.533235 -137.314107) (xy 434.549303 -137.367514) (xy 434.557423 -137.42269)
			(xy 434.557932 -137.450576) (xy 434.557423 -137.478462) (xy 434.549303 -137.533638) (xy 434.533235 -137.587045)
			(xy 434.509563 -137.637542) (xy 434.47879 -137.684055) (xy 434.441573 -137.725592) (xy 434.398705 -137.761267)
			(xy 434.351099 -137.790321) (xy 434.29977 -137.812133) (xy 434.245813 -137.826239) (xy 434.190376 -137.832339)
			(xy 434.134642 -137.830302) (xy 434.079799 -137.820172) (xy 434.027015 -137.802165) (xy 433.977415 -137.776664)
			(xy 433.932057 -137.744213) (xy 433.891908 -137.705504) (xy 433.857822 -137.661361) (xy 433.830526 -137.612726)
			(xy 433.810603 -137.560635) (xy 433.798477 -137.506198) (xy 433.794406 -137.450576) (xy 432.085293 -137.450576)
			(xy 432.088043 -137.459716) (xy 432.096163 -137.514892) (xy 432.096672 -137.542778) (xy 432.096163 -137.570664)
			(xy 432.088043 -137.62584) (xy 432.071975 -137.679247) (xy 432.048303 -137.729744) (xy 432.01753 -137.776257)
			(xy 431.980313 -137.817794) (xy 431.937445 -137.853469) (xy 431.889839 -137.882523) (xy 431.83851 -137.904335)
			(xy 431.784553 -137.918441) (xy 431.729116 -137.924541) (xy 431.673382 -137.922504) (xy 431.618539 -137.912374)
			(xy 431.565755 -137.894367) (xy 431.516155 -137.868866) (xy 431.470797 -137.836415) (xy 431.430648 -137.797706)
			(xy 431.396562 -137.753563) (xy 431.369266 -137.704928) (xy 431.349343 -137.652837) (xy 431.337217 -137.5984)
			(xy 431.333146 -137.542778) (xy 426.565568 -137.542778) (xy 426.565568 -138.143996) (xy 428.762158 -138.143996)
			(xy 428.766229 -138.088374) (xy 428.778355 -138.033937) (xy 428.798278 -137.981846) (xy 428.825574 -137.933211)
			(xy 428.85966 -137.889068) (xy 428.899809 -137.850359) (xy 428.945167 -137.817908) (xy 428.994767 -137.792407)
			(xy 429.047551 -137.7744) (xy 429.102394 -137.76427) (xy 429.158128 -137.762233) (xy 429.213565 -137.768333)
			(xy 429.267522 -137.782439) (xy 429.318851 -137.804251) (xy 429.366457 -137.833305) (xy 429.409325 -137.86898)
			(xy 429.446542 -137.910517) (xy 429.477315 -137.95703) (xy 429.500987 -138.007527) (xy 429.517055 -138.060934)
			(xy 429.525175 -138.11611) (xy 429.525684 -138.143996) (xy 429.525175 -138.171882) (xy 429.517055 -138.227058)
			(xy 429.500987 -138.280465) (xy 429.477315 -138.330962) (xy 429.446542 -138.377475) (xy 429.409325 -138.419012)
			(xy 429.366457 -138.454687) (xy 429.318851 -138.483741) (xy 429.267522 -138.505553) (xy 429.213565 -138.519659)
			(xy 429.158128 -138.525759) (xy 429.102394 -138.523722) (xy 429.047551 -138.513592) (xy 428.994767 -138.495585)
			(xy 428.945167 -138.470084) (xy 428.899809 -138.437633) (xy 428.85966 -138.398924) (xy 428.825574 -138.354781)
			(xy 428.798278 -138.306146) (xy 428.778355 -138.254055) (xy 428.766229 -138.199618) (xy 428.762158 -138.143996)
			(xy 426.565568 -138.143996) (xy 426.565568 -139.038756) (xy 433.284894 -139.038756) (xy 433.292649 -138.984811)
			(xy 433.308002 -138.932519) (xy 433.330641 -138.882945) (xy 433.360104 -138.837096) (xy 433.395793 -138.795908)
			(xy 433.436979 -138.760217) (xy 433.482826 -138.730751) (xy 433.532399 -138.70811) (xy 433.58469 -138.692754)
			(xy 433.638634 -138.684995) (xy 433.665884 -138.684508) (xy 433.688455 -138.684839) (xy 433.733278 -138.690182)
			(xy 433.755292 -138.695176) (xy 433.769008 -138.697889) (xy 433.796927 -138.696765) (xy 433.823496 -138.688112)
			(xy 433.846722 -138.672579) (xy 433.864866 -138.651329) (xy 433.876567 -138.625955) (xy 433.880949 -138.598359)
			(xy 433.879752 -138.584432) (xy 433.878541 -138.573296) (xy 433.87727 -138.550929) (xy 433.877212 -138.539728)
			(xy 433.877625 -138.512473) (xy 433.885379 -138.458517) (xy 433.900732 -138.406214) (xy 433.923373 -138.356628)
			(xy 433.95284 -138.31077) (xy 433.988533 -138.269571) (xy 434.029727 -138.233872) (xy 434.075582 -138.204398)
			(xy 434.125164 -138.181751) (xy 434.177465 -138.16639) (xy 434.23142 -138.158629) (xy 434.28593 -138.158625)
			(xy 434.339885 -138.166379) (xy 434.392188 -138.181733) (xy 434.441774 -138.204374) (xy 434.487633 -138.233841)
			(xy 434.528831 -138.269535) (xy 434.56453 -138.310729) (xy 434.594003 -138.356584) (xy 434.61665 -138.406167)
			(xy 434.632011 -138.458468) (xy 434.639771 -138.512422) (xy 434.639775 -138.566932) (xy 434.63202 -138.620888)
			(xy 434.616666 -138.673191) (xy 434.594025 -138.722776) (xy 434.564557 -138.768635) (xy 434.528863 -138.809833)
			(xy 434.487669 -138.845531) (xy 434.441814 -138.875004) (xy 434.392231 -138.897651) (xy 434.33993 -138.913011)
			(xy 434.285975 -138.920772) (xy 434.25872 -138.921236) (xy 434.236149 -138.920903) (xy 434.191326 -138.915561)
			(xy 434.169312 -138.910568) (xy 434.155602 -138.90781) (xy 434.127674 -138.908933) (xy 434.101098 -138.91759)
			(xy 434.077866 -138.93313) (xy 434.059721 -138.95439) (xy 434.048023 -138.979775) (xy 434.043649 -139.007382)
			(xy 434.044852 -139.021312) (xy 434.046067 -139.032448) (xy 434.047335 -139.054814) (xy 434.047392 -139.066016)
			(xy 434.046905 -139.093266) (xy 434.039146 -139.14721) (xy 434.02379 -139.199501) (xy 434.001149 -139.249074)
			(xy 433.971683 -139.294921) (xy 433.935992 -139.336107) (xy 433.894804 -139.371796) (xy 433.848955 -139.401259)
			(xy 433.799381 -139.423898) (xy 433.747089 -139.439251) (xy 433.693144 -139.447006) (xy 433.638645 -139.447005)
			(xy 433.584701 -139.439249) (xy 433.532409 -139.423894) (xy 433.482835 -139.401254) (xy 433.436988 -139.371789)
			(xy 433.3958 -139.3361) (xy 433.360111 -139.294912) (xy 433.330646 -139.249065) (xy 433.308006 -139.199491)
			(xy 433.292651 -139.147199) (xy 433.284895 -139.093255) (xy 433.284894 -139.038756) (xy 426.565568 -139.038756)
			(xy 426.565568 -139.716256) (xy 432.257706 -139.716256) (xy 432.261777 -139.660634) (xy 432.273903 -139.606197)
			(xy 432.293826 -139.554106) (xy 432.321122 -139.505471) (xy 432.355208 -139.461328) (xy 432.395357 -139.422619)
			(xy 432.440715 -139.390168) (xy 432.490315 -139.364667) (xy 432.543099 -139.34666) (xy 432.597942 -139.33653)
			(xy 432.653676 -139.334493) (xy 432.709113 -139.340593) (xy 432.76307 -139.354699) (xy 432.814399 -139.376511)
			(xy 432.862005 -139.405565) (xy 432.904873 -139.44124) (xy 432.94209 -139.482777) (xy 432.972863 -139.52929)
			(xy 432.996535 -139.579787) (xy 433.012603 -139.633194) (xy 433.020723 -139.68837) (xy 433.021232 -139.716256)
			(xy 433.020723 -139.744142) (xy 433.012603 -139.799318) (xy 432.996535 -139.852725) (xy 432.972863 -139.903222)
			(xy 432.94209 -139.949735) (xy 432.904873 -139.991272) (xy 432.862005 -140.026947) (xy 432.814399 -140.056001)
			(xy 432.76307 -140.077813) (xy 432.709113 -140.091919) (xy 432.653676 -140.098019) (xy 432.597942 -140.095982)
			(xy 432.543099 -140.085852) (xy 432.490315 -140.067845) (xy 432.440715 -140.042344) (xy 432.395357 -140.009893)
			(xy 432.355208 -139.971184) (xy 432.321122 -139.927041) (xy 432.293826 -139.878406) (xy 432.273903 -139.826315)
			(xy 432.261777 -139.771878) (xy 432.257706 -139.716256) (xy 426.565568 -139.716256) (xy 426.565568 -139.783058)
			(xy 426.565999 -139.797029) (xy 426.573618 -139.823913) (xy 426.588241 -139.847724) (xy 426.608772 -139.866678)
			(xy 426.633673 -139.879355) (xy 426.661079 -139.884805) (xy 426.675042 -139.88415) (xy 426.705014 -139.88288)
			(xy 426.732264 -139.883391) (xy 426.786208 -139.891149) (xy 426.8385 -139.906505) (xy 426.888073 -139.929146)
			(xy 426.933921 -139.958612) (xy 426.975108 -139.994302) (xy 427.010797 -140.035491) (xy 427.040261 -140.081339)
			(xy 427.0629 -140.130914) (xy 427.078254 -140.183206) (xy 427.08601 -140.23715) (xy 427.08601 -140.29165)
			(xy 427.078254 -140.345594) (xy 427.0629 -140.397886) (xy 427.040261 -140.447461) (xy 427.010797 -140.493309)
			(xy 426.975108 -140.534498) (xy 426.933921 -140.570188) (xy 426.888073 -140.599654) (xy 426.8385 -140.622295)
			(xy 426.786208 -140.637651) (xy 426.732264 -140.645409) (xy 426.705014 -140.645896) (xy 426.678278 -140.645487)
			(xy 426.625329 -140.638021) (xy 426.573942 -140.623233) (xy 426.525125 -140.601413) (xy 426.479833 -140.572989)
			(xy 426.438955 -140.538517) (xy 426.420788 -140.518896) (xy 426.38345 -140.518896) (xy 425.760388 -141.141958)
			(xy 425.760388 -141.415008) (xy 426.048422 -141.415008) (xy 426.052493 -141.359386) (xy 426.064619 -141.304949)
			(xy 426.084542 -141.252858) (xy 426.111838 -141.204223) (xy 426.145924 -141.16008) (xy 426.186073 -141.121371)
			(xy 426.231431 -141.08892) (xy 426.281031 -141.063419) (xy 426.333815 -141.045412) (xy 426.388658 -141.035282)
			(xy 426.444392 -141.033245) (xy 426.499829 -141.039345) (xy 426.553786 -141.053451) (xy 426.605115 -141.075263)
			(xy 426.652721 -141.104317) (xy 426.695589 -141.139992) (xy 426.721474 -141.168882) (xy 431.19116 -141.168882)
			(xy 431.195231 -141.11326) (xy 431.207357 -141.058823) (xy 431.22728 -141.006732) (xy 431.254576 -140.958097)
			(xy 431.288662 -140.913954) (xy 431.328811 -140.875245) (xy 431.374169 -140.842794) (xy 431.423769 -140.817293)
			(xy 431.476553 -140.799286) (xy 431.531396 -140.789156) (xy 431.58713 -140.787119) (xy 431.642567 -140.793219)
			(xy 431.696524 -140.807325) (xy 431.747853 -140.829137) (xy 431.795459 -140.858191) (xy 431.838327 -140.893866)
			(xy 431.875544 -140.935403) (xy 431.906317 -140.981916) (xy 431.929989 -141.032413) (xy 431.946057 -141.08582)
			(xy 431.954177 -141.140996) (xy 431.954686 -141.168882) (xy 431.954177 -141.196768) (xy 431.946057 -141.251944)
			(xy 431.929989 -141.305351) (xy 431.906317 -141.355848) (xy 431.875544 -141.402361) (xy 431.838327 -141.443898)
			(xy 431.795459 -141.479573) (xy 431.747853 -141.508627) (xy 431.696524 -141.530439) (xy 431.642567 -141.544545)
			(xy 431.58713 -141.550645) (xy 431.531396 -141.548608) (xy 431.476553 -141.538478) (xy 431.423769 -141.520471)
			(xy 431.374169 -141.49497) (xy 431.328811 -141.462519) (xy 431.288662 -141.42381) (xy 431.254576 -141.379667)
			(xy 431.22728 -141.331032) (xy 431.207357 -141.278941) (xy 431.195231 -141.224504) (xy 431.19116 -141.168882)
			(xy 426.721474 -141.168882) (xy 426.732806 -141.181529) (xy 426.763579 -141.228042) (xy 426.787251 -141.278539)
			(xy 426.803319 -141.331946) (xy 426.811439 -141.387122) (xy 426.811948 -141.415008) (xy 426.811439 -141.442894)
			(xy 426.803319 -141.49807) (xy 426.787251 -141.551477) (xy 426.763579 -141.601974) (xy 426.732806 -141.648487)
			(xy 426.695589 -141.690024) (xy 426.652721 -141.725699) (xy 426.605115 -141.754753) (xy 426.553786 -141.776565)
			(xy 426.499829 -141.790671) (xy 426.444392 -141.796771) (xy 426.388658 -141.794734) (xy 426.333815 -141.784604)
			(xy 426.281031 -141.766597) (xy 426.231431 -141.741096) (xy 426.186073 -141.708645) (xy 426.145924 -141.669936)
			(xy 426.111838 -141.625793) (xy 426.084542 -141.577158) (xy 426.064619 -141.525067) (xy 426.052493 -141.47063)
			(xy 426.048422 -141.415008) (xy 425.760388 -141.415008) (xy 425.760388 -142.963138) (xy 427.05909 -144.26184)
			(xy 427.266862 -144.26184) (xy 427.280692 -144.261445) (xy 427.307332 -144.254005) (xy 427.330997 -144.239686)
			(xy 427.349951 -144.21954) (xy 427.362801 -144.195046) (xy 427.368604 -144.168002) (xy 427.366935 -144.140392)
			(xy 427.357917 -144.114244) (xy 427.34221 -144.091476) (xy 427.331886 -144.082262) (xy 427.310736 -144.06405)
			(xy 427.273463 -144.022509) (xy 427.242641 -143.97598) (xy 427.218931 -143.925455) (xy 427.202837 -143.872014)
			(xy 427.194704 -143.816798) (xy 427.194218 -143.788892) (xy 427.194673 -143.762513) (xy 427.201927 -143.710255)
			(xy 427.21631 -143.659495) (xy 427.237546 -143.6112) (xy 427.265233 -143.566289) (xy 427.298841 -143.525621)
			(xy 427.33773 -143.489969) (xy 427.381159 -143.460013) (xy 427.40453 -143.44777) (xy 427.416899 -143.441083)
			(xy 427.437636 -143.422108) (xy 427.452403 -143.398191) (xy 427.460078 -143.371151) (xy 427.460077 -143.343042)
			(xy 427.4524 -143.316003) (xy 427.437631 -143.292087) (xy 427.416893 -143.273113) (xy 427.40453 -143.266414)
			(xy 427.38114 -143.254209) (xy 427.337718 -143.224239) (xy 427.298835 -143.188577) (xy 427.265232 -143.147902)
			(xy 427.237548 -143.102988) (xy 427.216311 -143.054691) (xy 427.201924 -143.00393) (xy 427.194662 -142.951672)
			(xy 427.194218 -142.925292) (xy 427.194704 -142.898041) (xy 427.20246 -142.844093) (xy 427.217815 -142.791798)
			(xy 427.240457 -142.742221) (xy 427.269923 -142.696371) (xy 427.305614 -142.65518) (xy 427.346805 -142.619489)
			(xy 427.392655 -142.590023) (xy 427.442232 -142.567381) (xy 427.494527 -142.552026) (xy 427.548475 -142.54427)
			(xy 427.602977 -142.54427) (xy 427.656925 -142.552026) (xy 427.70922 -142.567381) (xy 427.758797 -142.590023)
			(xy 427.804647 -142.619489) (xy 427.845838 -142.65518) (xy 427.881529 -142.696371) (xy 427.910995 -142.742221)
			(xy 427.933637 -142.791798) (xy 427.948992 -142.844093) (xy 427.956748 -142.898041) (xy 427.957234 -142.925292)
			(xy 427.956737 -142.95167) (xy 427.949487 -143.003924) (xy 427.935108 -143.054682) (xy 427.913877 -143.102976)
			(xy 427.886196 -143.147886) (xy 427.852595 -143.188555) (xy 427.813712 -143.224209) (xy 427.770289 -143.254169)
			(xy 427.746922 -143.266414) (xy 427.734572 -143.273128) (xy 427.713846 -143.292103) (xy 427.699087 -143.316014)
			(xy 427.691415 -143.343047) (xy 427.691415 -143.371146) (xy 427.699084 -143.398179) (xy 427.713841 -143.422092)
			(xy 427.734566 -143.441068) (xy 427.746922 -143.44777) (xy 427.770294 -143.460009) (xy 427.813717 -143.489972)
			(xy 427.852602 -143.525628) (xy 427.886208 -143.566298) (xy 427.913894 -143.611207) (xy 427.935135 -143.6595)
			(xy 427.949524 -143.710258) (xy 427.956788 -143.762513) (xy 427.957234 -143.788892) (xy 427.956735 -143.816797)
			(xy 427.948594 -143.872009) (xy 427.932497 -143.925447) (xy 427.90879 -143.97597) (xy 427.877976 -144.022502)
			(xy 427.840714 -144.06405) (xy 427.819566 -144.082262) (xy 427.809271 -144.091503) (xy 427.793564 -144.114257)
			(xy 427.784544 -144.140393) (xy 427.782873 -144.167992) (xy 427.788674 -144.195025) (xy 427.801522 -144.219508)
			(xy 427.820472 -144.239642) (xy 427.844133 -144.253948) (xy 427.870765 -144.261375) (xy 427.88459 -144.26184)
			(xy 431.419 -144.26184) (xy 431.443996 -144.262471) (xy 431.493019 -144.272276) (xy 431.53919 -144.291451)
			(xy 431.580736 -144.31926) (xy 431.598832 -144.336516) (xy 434.425852 -147.163536) (xy 434.44311 -147.18163)
			(xy 434.470922 -147.223175) (xy 434.490095 -147.269346) (xy 434.499893 -147.318371) (xy 434.500528 -147.343368)
			(xy 434.500528 -156.313124) (xy 438.212992 -160.025842) (xy 438.23026 -160.043927) (xy 438.258068 -160.085476)
			(xy 438.277238 -160.13165) (xy 438.287033 -160.180677) (xy 438.287668 -160.205674) (xy 438.287668 -166.522908)
			(xy 438.287039 -166.547904) (xy 438.277233 -166.596928) (xy 438.258057 -166.643098) (xy 438.230248 -166.684644)
			(xy 438.212992 -166.70274) (xy 430.140872 -174.77486) (xy 430.122776 -174.792116) (xy 430.081232 -174.819928)
			(xy 430.035061 -174.839101) (xy 429.986036 -174.8489) (xy 429.96104 -174.849536) (xy 426.173392 -174.849536)
			(xy 426.148395 -174.848917) (xy 426.099371 -174.839109) (xy 426.0532 -174.819931) (xy 426.011655 -174.792118)
			(xy 425.99356 -174.77486) (xy 424.254168 -173.035468) (xy 421.878252 -173.035468) (xy 421.169592 -173.744128)
			(xy 421.151498 -173.761386) (xy 421.109952 -173.789194) (xy 421.06378 -173.808367) (xy 421.014756 -173.818166)
			(xy 420.98976 -173.818804) (xy 420.032688 -173.818804) (xy 420.00769 -173.818196) (xy 419.958665 -173.808387)
			(xy 419.912494 -173.789205) (xy 419.87095 -173.761388) (xy 419.852856 -173.744128) (xy 419.649148 -173.54042)
			(xy 419.631916 -173.522302) (xy 419.6041 -173.480766) (xy 419.584919 -173.434601) (xy 419.575113 -173.385582)
			(xy 419.574472 -173.360588) (xy 419.574472 -173.134782) (xy 419.548895 -173.12039) (xy 419.502119 -173.084948)
			(xy 419.461322 -173.04276) (xy 419.427466 -172.994823) (xy 419.40135 -172.942268) (xy 419.38359 -172.886333)
			(xy 419.374604 -172.828338) (xy 419.374066 -172.798994) (xy 419.374572 -172.771744) (xy 419.382329 -172.717798)
			(xy 419.397683 -172.665505) (xy 419.420323 -172.61593) (xy 419.449788 -172.570081) (xy 419.485477 -172.528891)
			(xy 419.526665 -172.4932) (xy 419.572512 -172.463733) (xy 419.622087 -172.44109) (xy 419.674379 -172.425733)
			(xy 419.728324 -172.417974) (xy 419.755574 -172.417486) (xy 419.78151 -172.417935) (xy 419.832905 -172.42496)
			(xy 419.882874 -172.438884) (xy 419.930495 -172.459451) (xy 419.97489 -172.48628) (xy 420.015241 -172.518878)
			(xy 420.050803 -172.556642) (xy 420.066216 -172.577506) (xy 420.075441 -172.589618) (xy 420.099609 -172.608114)
			(xy 420.128159 -172.618654) (xy 420.158548 -172.620298) (xy 420.188068 -172.6129) (xy 420.201344 -172.605446)
			(xy 420.223766 -172.592408) (xy 420.271398 -172.571875) (xy 420.321372 -172.557986) (xy 420.372767 -172.550998)
			(xy 420.398702 -172.550582) (xy 420.426762 -172.551086) (xy 420.482278 -172.559289) (xy 420.535994 -172.575532)
			(xy 420.586754 -172.599465) (xy 420.633462 -172.630572) (xy 420.675112 -172.668184) (xy 420.693342 -172.68952)
			(xy 420.96563 -172.68952) (xy 421.435022 -172.220382) (xy 421.453115 -172.203141) (xy 421.494679 -172.175401)
			(xy 421.540855 -172.156299) (xy 421.589868 -172.146566) (xy 421.614854 -172.14596) (xy 424.517566 -172.14596)
			(xy 424.542551 -172.146547) (xy 424.59156 -172.156297) (xy 424.63773 -172.175412) (xy 424.679289 -172.203157)
			(xy 424.697398 -172.220382) (xy 424.973212 -172.496156) (xy 426.563024 -172.496156) (xy 426.563024 -172.41146)
			(xy 426.571075 -172.327146) (xy 426.587104 -172.24398) (xy 426.610965 -172.162713) (xy 426.642444 -172.084083)
			(xy 426.681255 -172.008802) (xy 426.727045 -171.93755) (xy 426.779401 -171.870974) (xy 426.837849 -171.809676)
			(xy 426.901859 -171.754211) (xy 426.970851 -171.705082) (xy 427.044201 -171.662733) (xy 427.121244 -171.627549)
			(xy 427.201283 -171.599847) (xy 427.283592 -171.579879) (xy 427.367427 -171.567826) (xy 427.452028 -171.563796)
			(xy 427.536629 -171.567826) (xy 427.620464 -171.579879) (xy 427.702773 -171.599847) (xy 427.782812 -171.627549)
			(xy 427.859855 -171.662733) (xy 427.933205 -171.705082) (xy 428.002197 -171.754211) (xy 428.066207 -171.809676)
			(xy 428.124655 -171.870974) (xy 428.177011 -171.93755) (xy 428.222801 -172.008802) (xy 428.261612 -172.084083)
			(xy 428.293091 -172.162713) (xy 428.316952 -172.24398) (xy 428.332981 -172.327146) (xy 428.341032 -172.41146)
			(xy 428.341536 -172.453808) (xy 428.341032 -172.496156) (xy 428.332981 -172.58047) (xy 428.316952 -172.663636)
			(xy 428.293091 -172.744903) (xy 428.261612 -172.823533) (xy 428.222801 -172.898814) (xy 428.177011 -172.970066)
			(xy 428.124655 -173.036642) (xy 428.066207 -173.09794) (xy 428.002197 -173.153405) (xy 427.933205 -173.202534)
			(xy 427.859855 -173.244883) (xy 427.782812 -173.280067) (xy 427.702773 -173.307769) (xy 427.620464 -173.327737)
			(xy 427.536629 -173.33979) (xy 427.452028 -173.343821) (xy 427.367427 -173.33979) (xy 427.283592 -173.327737)
			(xy 427.201283 -173.307769) (xy 427.121244 -173.280067) (xy 427.044201 -173.244883) (xy 426.970851 -173.202534)
			(xy 426.901859 -173.153405) (xy 426.837849 -173.09794) (xy 426.779401 -173.036642) (xy 426.727045 -172.970066)
			(xy 426.681255 -172.898814) (xy 426.642444 -172.823533) (xy 426.610965 -172.744903) (xy 426.587104 -172.663636)
			(xy 426.571075 -172.58047) (xy 426.563024 -172.496156) (xy 424.973212 -172.496156) (xy 426.43679 -173.95952)
			(xy 429.697642 -173.95952) (xy 437.397652 -166.25951) (xy 437.397652 -160.469326) (xy 433.685188 -156.756608)
			(xy 433.667941 -156.738505) (xy 433.640129 -156.696962) (xy 433.620954 -156.650793) (xy 433.611151 -156.601772)
			(xy 433.610512 -156.576776) (xy 433.610512 -147.606766) (xy 431.155602 -145.151856) (xy 426.795692 -145.151856)
			(xy 426.770695 -145.151231) (xy 426.721672 -145.141424) (xy 426.675501 -145.122247) (xy 426.633956 -145.094437)
			(xy 426.61586 -145.07718) (xy 424.945048 -143.406368) (xy 424.927792 -143.388272) (xy 424.89998 -143.346728)
			(xy 424.880806 -143.300557) (xy 424.871008 -143.251533) (xy 424.870372 -143.226536) (xy 424.870372 -140.858748)
			(xy 424.871024 -140.833753) (xy 424.880821 -140.78473) (xy 424.89999 -140.738559) (xy 424.927794 -140.697012)
			(xy 424.945048 -140.678916) (xy 425.327826 -140.295884) (xy 425.338071 -140.284965) (xy 425.352163 -140.25856)
			(xy 425.357995 -140.229203) (xy 425.355065 -140.199417) (xy 425.343624 -140.171759) (xy 425.324656 -140.148607)
			(xy 425.29979 -140.131948) (xy 425.271162 -140.123214) (xy 425.256198 -140.122656) (xy 422.02989 -140.122656)
			(xy 421.895016 -140.25753) (xy 421.895016 -141.026453) (xy 422.148465 -141.026453) (xy 422.148465 -140.971947)
			(xy 422.156222 -140.917997) (xy 422.171578 -140.8657) (xy 422.194221 -140.816121) (xy 422.223689 -140.770269)
			(xy 422.259382 -140.729077) (xy 422.300575 -140.693384) (xy 422.346428 -140.663917) (xy 422.396008 -140.641276)
			(xy 422.448305 -140.625921) (xy 422.502255 -140.618165) (xy 422.529508 -140.617702) (xy 422.555887 -140.618166)
			(xy 422.608144 -140.625419) (xy 422.658903 -140.639801) (xy 422.707198 -140.661037) (xy 422.752108 -140.688722)
			(xy 422.792777 -140.722329) (xy 422.82843 -140.761217) (xy 422.858387 -140.804644) (xy 422.87063 -140.828014)
			(xy 422.877332 -140.840373) (xy 422.896307 -140.861101) (xy 422.920221 -140.875863) (xy 422.947257 -140.883535)
			(xy 422.975359 -140.883535) (xy 423.002395 -140.875863) (xy 423.026309 -140.861101) (xy 423.045284 -140.840373)
			(xy 423.051986 -140.828014) (xy 423.064228 -140.804644) (xy 423.094189 -140.761219) (xy 423.129844 -140.722332)
			(xy 423.170513 -140.688725) (xy 423.215422 -140.661038) (xy 423.263715 -140.639798) (xy 423.314473 -140.62541)
			(xy 423.366729 -140.618147) (xy 423.393108 -140.617702) (xy 423.42036 -140.618168) (xy 423.474308 -140.625926)
			(xy 423.526603 -140.641282) (xy 423.576181 -140.663924) (xy 423.622031 -140.693392) (xy 423.663222 -140.729084)
			(xy 423.698913 -140.770275) (xy 423.728379 -140.816126) (xy 423.751021 -140.865704) (xy 423.766376 -140.918)
			(xy 423.774132 -140.971948) (xy 423.774132 -141.026452) (xy 423.766376 -141.0804) (xy 423.751021 -141.132696)
			(xy 423.728379 -141.182274) (xy 423.698913 -141.228125) (xy 423.663222 -141.269316) (xy 423.622031 -141.305008)
			(xy 423.576181 -141.334476) (xy 423.526603 -141.357118) (xy 423.474308 -141.372474) (xy 423.42036 -141.380232)
			(xy 423.393108 -141.380718) (xy 423.36673 -141.38023) (xy 423.314475 -141.372979) (xy 423.263716 -141.3586)
			(xy 423.215422 -141.337367) (xy 423.170512 -141.309686) (xy 423.129843 -141.276083) (xy 423.094189 -141.237198)
			(xy 423.06423 -141.193774) (xy 423.051986 -141.170406) (xy 423.045284 -141.158047) (xy 423.026309 -141.137319)
			(xy 423.002395 -141.122557) (xy 422.975359 -141.114885) (xy 422.947257 -141.114885) (xy 422.920221 -141.122557)
			(xy 422.896307 -141.137319) (xy 422.877332 -141.158047) (xy 422.87063 -141.170406) (xy 422.858385 -141.193774)
			(xy 422.828423 -141.237198) (xy 422.792768 -141.276084) (xy 422.752099 -141.30969) (xy 422.707191 -141.337377)
			(xy 422.658899 -141.358618) (xy 422.608141 -141.373008) (xy 422.555887 -141.380272) (xy 422.529508 -141.380718)
			(xy 422.502255 -141.380235) (xy 422.448305 -141.372479) (xy 422.396008 -141.357124) (xy 422.346428 -141.334483)
			(xy 422.300575 -141.305016) (xy 422.259382 -141.269323) (xy 422.223689 -141.228131) (xy 422.194221 -141.182279)
			(xy 422.171578 -141.1327) (xy 422.156222 -141.080403) (xy 422.148465 -141.026453) (xy 421.895016 -141.026453)
			(xy 421.895016 -144.659858) (xy 422.944798 -145.70964) (xy 425.201588 -145.70964) (xy 425.226584 -145.710278)
			(xy 425.275607 -145.720081) (xy 425.321777 -145.739254) (xy 425.363324 -145.767061) (xy 425.38142 -145.784316)
			(xy 427.001432 -147.404328) (xy 427.018714 -147.422403) (xy 427.046533 -147.463951) (xy 427.065711 -147.510128)
			(xy 427.075512 -147.55916) (xy 427.076108 -147.58416) (xy 427.076108 -153.667968) (xy 427.075472 -153.692964)
			(xy 427.065671 -153.741988) (xy 427.046497 -153.788159) (xy 427.018688 -153.829705) (xy 427.001432 -153.8478)
			(xy 425.626022 -155.22321) (xy 425.607909 -155.240429) (xy 425.566352 -155.268173) (xy 425.520183 -155.287282)
			(xy 425.471174 -155.297022) (xy 425.44619 -155.297632) (xy 423.46626 -155.297632) (xy 423.176192 -155.5877)
			(xy 423.158094 -155.604953) (xy 423.11655 -155.632764) (xy 423.070379 -155.651938) (xy 423.021356 -155.661738)
			(xy 422.99636 -155.662376) (xy 422.102026 -155.662376) (xy 422.077031 -155.661724) (xy 422.028009 -155.651925)
			(xy 421.981838 -155.632756) (xy 421.940291 -155.604953) (xy 421.922194 -155.5877) (xy 421.651684 -155.31719)
			(xy 421.634416 -155.299149) (xy 421.606656 -155.257642) (xy 421.587528 -155.211516) (xy 421.582088 -155.187142)
			(xy 421.561743 -155.16895) (xy 421.525942 -155.127759) (xy 421.496381 -155.081882) (xy 421.473664 -155.032259)
			(xy 421.458257 -154.979904) (xy 421.450475 -154.925886) (xy 421.450008 -154.898598) (xy 421.450454 -154.871344)
			(xy 421.458211 -154.817392) (xy 421.473568 -154.765093) (xy 421.496212 -154.715512) (xy 421.525682 -154.669658)
			(xy 421.561377 -154.628465) (xy 421.602572 -154.592771) (xy 421.648427 -154.563304) (xy 421.69801 -154.540662)
			(xy 421.75031 -154.525307) (xy 421.804262 -154.517552) (xy 421.831516 -154.51709) (xy 421.861892 -154.517675)
			(xy 421.921876 -154.527306) (xy 421.979575 -154.54632) (xy 422.033532 -154.574239) (xy 422.082383 -154.610355)
			(xy 422.104058 -154.631644) (xy 422.113809 -154.640955) (xy 422.137082 -154.65455) (xy 422.163099 -154.661592)
			(xy 422.190051 -154.661592) (xy 422.216068 -154.65455) (xy 422.239341 -154.640955) (xy 422.249092 -154.631644)
			(xy 422.267107 -154.613803) (xy 422.307074 -154.582602) (xy 422.350822 -154.55697) (xy 422.39758 -154.537359)
			(xy 422.446523 -154.524114) (xy 422.49679 -154.517469) (xy 422.522142 -154.51709) (xy 422.543478 -154.51709)
			(xy 422.578022 -154.482546) (xy 422.596109 -154.465299) (xy 422.637676 -154.437562) (xy 422.683853 -154.418462)
			(xy 422.732868 -154.40873) (xy 422.757854 -154.408124) (xy 425.182792 -154.408124) (xy 426.186092 -153.40457)
			(xy 426.186092 -147.847558) (xy 424.93819 -146.599656) (xy 422.6814 -146.599656) (xy 422.656404 -146.599026)
			(xy 422.60738 -146.589221) (xy 422.56121 -146.570045) (xy 422.519664 -146.542236) (xy 422.501568 -146.52498)
			(xy 421.079676 -145.103088) (xy 421.062417 -145.084995) (xy 421.034609 -145.043449) (xy 421.015437 -144.997277)
			(xy 421.005637 -144.948252) (xy 421.005 -144.923256) (xy 421.005 -140.122656) (xy 419.079172 -140.122656)
			(xy 419.079172 -138.806936) (xy 419.06438 -138.786903) (xy 419.039568 -138.743727) (xy 419.020589 -138.697686)
			(xy 419.007769 -138.649567) (xy 419.001324 -138.600187) (xy 419.00094 -138.575288) (xy 410.41574 -138.575288)
			(xy 410.41574 -139.48664) (xy 417.582602 -139.48664) (xy 417.586673 -139.431018) (xy 417.598799 -139.376581)
			(xy 417.618722 -139.32449) (xy 417.646018 -139.275855) (xy 417.680104 -139.231712) (xy 417.720253 -139.193003)
			(xy 417.765611 -139.160552) (xy 417.815211 -139.135051) (xy 417.867995 -139.117044) (xy 417.922838 -139.106914)
			(xy 417.978572 -139.104877) (xy 418.034009 -139.110977) (xy 418.087966 -139.125083) (xy 418.139295 -139.146895)
			(xy 418.186901 -139.175949) (xy 418.229769 -139.211624) (xy 418.266986 -139.253161) (xy 418.297759 -139.299674)
			(xy 418.321431 -139.350171) (xy 418.337499 -139.403578) (xy 418.345619 -139.458754) (xy 418.346128 -139.48664)
			(xy 418.345619 -139.514526) (xy 418.337499 -139.569702) (xy 418.321431 -139.623109) (xy 418.297759 -139.673606)
			(xy 418.266986 -139.720119) (xy 418.229769 -139.761656) (xy 418.186901 -139.797331) (xy 418.139295 -139.826385)
			(xy 418.087966 -139.848197) (xy 418.034009 -139.862303) (xy 417.978572 -139.868403) (xy 417.922838 -139.866366)
			(xy 417.867995 -139.856236) (xy 417.815211 -139.838229) (xy 417.765611 -139.812728) (xy 417.720253 -139.780277)
			(xy 417.680104 -139.741568) (xy 417.646018 -139.697425) (xy 417.618722 -139.64879) (xy 417.598799 -139.596699)
			(xy 417.586673 -139.542262) (xy 417.582602 -139.48664) (xy 410.41574 -139.48664) (xy 410.41574 -142.458948)
			(xy 416.868862 -142.458948) (xy 416.872933 -142.403326) (xy 416.885059 -142.348889) (xy 416.904982 -142.296798)
			(xy 416.932278 -142.248163) (xy 416.966364 -142.20402) (xy 417.006513 -142.165311) (xy 417.051871 -142.13286)
			(xy 417.101471 -142.107359) (xy 417.154255 -142.089352) (xy 417.209098 -142.079222) (xy 417.264832 -142.077185)
			(xy 417.320269 -142.083285) (xy 417.374226 -142.097391) (xy 417.425555 -142.119203) (xy 417.473161 -142.148257)
			(xy 417.516029 -142.183932) (xy 417.553246 -142.225469) (xy 417.584019 -142.271982) (xy 417.607691 -142.322479)
			(xy 417.623759 -142.375886) (xy 417.631879 -142.431062) (xy 417.632388 -142.458948) (xy 417.631879 -142.486834)
			(xy 417.623759 -142.54201) (xy 417.607691 -142.595417) (xy 417.584019 -142.645914) (xy 417.553246 -142.692427)
			(xy 417.516029 -142.733964) (xy 417.473161 -142.769639) (xy 417.425555 -142.798693) (xy 417.374226 -142.820505)
			(xy 417.320269 -142.834611) (xy 417.264832 -142.840711) (xy 417.209098 -142.838674) (xy 417.154255 -142.828544)
			(xy 417.101471 -142.810537) (xy 417.051871 -142.785036) (xy 417.006513 -142.752585) (xy 416.966364 -142.713876)
			(xy 416.932278 -142.669733) (xy 416.904982 -142.621098) (xy 416.885059 -142.569007) (xy 416.872933 -142.51457)
			(xy 416.868862 -142.458948) (xy 410.41574 -142.458948) (xy 410.41574 -147.992846) (xy 410.459936 -147.998688)
			(xy 410.486624 -148.002724) (xy 410.538448 -148.017802) (xy 410.587404 -148.040528) (xy 410.632369 -148.070382)
			(xy 410.672314 -148.106679) (xy 410.706324 -148.14859) (xy 410.733619 -148.195153) (xy 410.753574 -148.245302)
			(xy 410.765733 -148.297888) (xy 410.769816 -148.351706) (xy 410.765731 -148.405525) (xy 410.75357 -148.45811)
			(xy 410.733613 -148.508259) (xy 410.706316 -148.554821) (xy 410.672305 -148.59673) (xy 410.632359 -148.633026)
			(xy 410.587393 -148.662878) (xy 410.538437 -148.685603) (xy 410.486611 -148.700678) (xy 410.459936 -148.704808)
			(xy 410.41574 -148.71065) (xy 410.41574 -150.423949) (xy 420.30348 -150.423949) (xy 420.30348 -150.369451)
			(xy 420.311235 -150.315508) (xy 420.326587 -150.263217) (xy 420.349225 -150.213643) (xy 420.378687 -150.167796)
			(xy 420.414373 -150.126607) (xy 420.455557 -150.090915) (xy 420.501401 -150.061448) (xy 420.550972 -150.038804)
			(xy 420.603261 -150.023445) (xy 420.657203 -150.015683) (xy 420.684452 -150.015194) (xy 420.711821 -150.01569)
			(xy 420.765999 -150.023501) (xy 420.818502 -150.038983) (xy 420.868249 -150.061818) (xy 420.914217 -150.091536)
			(xy 420.93515 -150.109174) (xy 420.946478 -150.11841) (xy 420.973035 -150.130586) (xy 421.001952 -150.134759)
			(xy 421.030869 -150.130586) (xy 421.057426 -150.11841) (xy 421.068754 -150.109174) (xy 421.089687 -150.091533)
			(xy 421.135655 -150.061809) (xy 421.185401 -150.038963) (xy 421.237903 -150.023467) (xy 421.292081 -150.015638)
			(xy 421.346823 -150.015638) (xy 421.401001 -150.023467) (xy 421.453503 -150.038963) (xy 421.503249 -150.061809)
			(xy 421.549217 -150.091533) (xy 421.57015 -150.109174) (xy 421.581478 -150.11841) (xy 421.608035 -150.130586)
			(xy 421.636952 -150.134759) (xy 421.665869 -150.130586) (xy 421.692426 -150.11841) (xy 421.703754 -150.109174)
			(xy 421.724689 -150.091539) (xy 421.770662 -150.061827) (xy 421.820408 -150.038991) (xy 421.872908 -150.023499)
			(xy 421.927083 -150.015669) (xy 421.954452 -150.015194) (xy 421.981707 -150.01565) (xy 422.035664 -150.023402)
			(xy 422.087968 -150.038753) (xy 422.137554 -150.061393) (xy 422.183413 -150.09086) (xy 422.224612 -150.126554)
			(xy 422.260311 -150.167748) (xy 422.289784 -150.213604) (xy 422.31243 -150.263187) (xy 422.327788 -150.315489)
			(xy 422.335547 -150.369445) (xy 422.335547 -150.423955) (xy 422.327788 -150.477911) (xy 422.31243 -150.530213)
			(xy 422.289784 -150.579796) (xy 422.260311 -150.625652) (xy 422.224612 -150.666846) (xy 422.183413 -150.70254)
			(xy 422.137554 -150.732007) (xy 422.087968 -150.754647) (xy 422.035664 -150.769998) (xy 421.981707 -150.77775)
			(xy 421.954452 -150.77821) (xy 421.927083 -150.777711) (xy 421.872905 -150.769901) (xy 421.820403 -150.754419)
			(xy 421.770655 -150.731585) (xy 421.724687 -150.701868) (xy 421.703754 -150.68423) (xy 421.692426 -150.674994)
			(xy 421.665869 -150.662818) (xy 421.636952 -150.658645) (xy 421.608035 -150.662818) (xy 421.581478 -150.674994)
			(xy 421.57015 -150.68423) (xy 421.549217 -150.701871) (xy 421.503249 -150.731595) (xy 421.453503 -150.754441)
			(xy 421.401001 -150.769937) (xy 421.346823 -150.777766) (xy 421.292081 -150.777766) (xy 421.237903 -150.769937)
			(xy 421.185401 -150.754441) (xy 421.135655 -150.731595) (xy 421.089687 -150.701871) (xy 421.068754 -150.68423)
			(xy 421.057426 -150.674994) (xy 421.030869 -150.662818) (xy 421.001952 -150.658645) (xy 420.973035 -150.662818)
			(xy 420.946478 -150.674994) (xy 420.93515 -150.68423) (xy 420.914214 -150.701864) (xy 420.868242 -150.731575)
			(xy 420.818495 -150.754412) (xy 420.765996 -150.769904) (xy 420.711821 -150.777735) (xy 420.684452 -150.77821)
			(xy 420.657203 -150.777717) (xy 420.603261 -150.769955) (xy 420.550972 -150.754596) (xy 420.501401 -150.731952)
			(xy 420.455557 -150.702485) (xy 420.414373 -150.666793) (xy 420.378687 -150.625604) (xy 420.349225 -150.579757)
			(xy 420.326587 -150.530183) (xy 420.311235 -150.477892) (xy 420.30348 -150.423949) (xy 410.41574 -150.423949)
			(xy 410.41574 -151.116284) (xy 418.675564 -151.116284) (xy 418.679635 -151.060662) (xy 418.691761 -151.006225)
			(xy 418.711684 -150.954134) (xy 418.73898 -150.905499) (xy 418.773066 -150.861356) (xy 418.813215 -150.822647)
			(xy 418.858573 -150.790196) (xy 418.908173 -150.764695) (xy 418.960957 -150.746688) (xy 419.0158 -150.736558)
			(xy 419.071534 -150.734521) (xy 419.126971 -150.740621) (xy 419.180928 -150.754727) (xy 419.232257 -150.776539)
			(xy 419.279863 -150.805593) (xy 419.322731 -150.841268) (xy 419.359948 -150.882805) (xy 419.390721 -150.929318)
			(xy 419.414393 -150.979815) (xy 419.430461 -151.033222) (xy 419.438581 -151.088398) (xy 419.43909 -151.116284)
			(xy 419.439044 -151.118824) (xy 419.681658 -151.118824) (xy 419.685729 -151.063202) (xy 419.697855 -151.008765)
			(xy 419.717778 -150.956674) (xy 419.745074 -150.908039) (xy 419.77916 -150.863896) (xy 419.819309 -150.825187)
			(xy 419.864667 -150.792736) (xy 419.914267 -150.767235) (xy 419.967051 -150.749228) (xy 420.021894 -150.739098)
			(xy 420.077628 -150.737061) (xy 420.133065 -150.743161) (xy 420.187022 -150.757267) (xy 420.238351 -150.779079)
			(xy 420.285957 -150.808133) (xy 420.328825 -150.843808) (xy 420.366042 -150.885345) (xy 420.396815 -150.931858)
			(xy 420.420487 -150.982355) (xy 420.431436 -151.018748) (xy 423.976292 -151.018748) (xy 423.976778 -150.991497)
			(xy 423.984534 -150.937549) (xy 423.999889 -150.885254) (xy 424.022531 -150.835677) (xy 424.051997 -150.789827)
			(xy 424.087688 -150.748636) (xy 424.128879 -150.712945) (xy 424.174729 -150.683479) (xy 424.224306 -150.660837)
			(xy 424.276601 -150.645482) (xy 424.330549 -150.637726) (xy 424.385051 -150.637726) (xy 424.438999 -150.645482)
			(xy 424.491294 -150.660837) (xy 424.540871 -150.683479) (xy 424.586721 -150.712945) (xy 424.627912 -150.748636)
			(xy 424.663603 -150.789827) (xy 424.693069 -150.835677) (xy 424.715711 -150.885254) (xy 424.731066 -150.937549)
			(xy 424.738822 -150.991497) (xy 424.739308 -151.018748) (xy 424.739308 -151.019002) (xy 424.739877 -151.034449)
			(xy 424.749157 -151.063917) (xy 424.766809 -151.089273) (xy 424.791224 -151.108204) (xy 424.820177 -151.118986)
			(xy 424.835574 -151.120348) (xy 424.864452 -151.122457) (xy 424.921128 -151.134291) (xy 424.975366 -151.154551)
			(xy 425.025922 -151.182773) (xy 425.071634 -151.218307) (xy 425.111453 -151.26034) (xy 425.144465 -151.307905)
			(xy 425.169913 -151.359911) (xy 425.187213 -151.415165) (xy 425.195968 -151.472399) (xy 425.196508 -151.501348)
			(xy 425.196022 -151.528599) (xy 425.188266 -151.582547) (xy 425.172911 -151.634842) (xy 425.150269 -151.684419)
			(xy 425.120803 -151.730269) (xy 425.085112 -151.77146) (xy 425.043921 -151.807151) (xy 424.998071 -151.836617)
			(xy 424.948494 -151.859259) (xy 424.896199 -151.874614) (xy 424.842251 -151.88237) (xy 424.787749 -151.88237)
			(xy 424.733801 -151.874614) (xy 424.681506 -151.859259) (xy 424.631929 -151.836617) (xy 424.586079 -151.807151)
			(xy 424.544888 -151.77146) (xy 424.509197 -151.730269) (xy 424.479731 -151.684419) (xy 424.457089 -151.634842)
			(xy 424.441734 -151.582547) (xy 424.433978 -151.528599) (xy 424.433492 -151.501348) (xy 424.433492 -151.501094)
			(xy 424.432927 -151.485647) (xy 424.423646 -151.456178) (xy 424.405993 -151.430823) (xy 424.381577 -151.411891)
			(xy 424.352623 -151.40111) (xy 424.337226 -151.399748) (xy 424.308348 -151.397643) (xy 424.251671 -151.385809)
			(xy 424.197432 -151.365548) (xy 424.146877 -151.337326) (xy 424.101165 -151.301791) (xy 424.061346 -151.259758)
			(xy 424.028333 -151.212193) (xy 424.002885 -151.160186) (xy 423.985586 -151.104931) (xy 423.976832 -151.047698)
			(xy 423.976292 -151.018748) (xy 420.431436 -151.018748) (xy 420.436555 -151.035762) (xy 420.444675 -151.090938)
			(xy 420.445184 -151.118824) (xy 420.444675 -151.14671) (xy 420.436555 -151.201886) (xy 420.420487 -151.255293)
			(xy 420.396815 -151.30579) (xy 420.366042 -151.352303) (xy 420.328825 -151.39384) (xy 420.285957 -151.429515)
			(xy 420.238351 -151.458569) (xy 420.187022 -151.480381) (xy 420.133065 -151.494487) (xy 420.077628 -151.500587)
			(xy 420.021894 -151.49855) (xy 419.967051 -151.48842) (xy 419.914267 -151.470413) (xy 419.864667 -151.444912)
			(xy 419.819309 -151.412461) (xy 419.77916 -151.373752) (xy 419.745074 -151.329609) (xy 419.717778 -151.280974)
			(xy 419.697855 -151.228883) (xy 419.685729 -151.174446) (xy 419.681658 -151.118824) (xy 419.439044 -151.118824)
			(xy 419.438581 -151.14417) (xy 419.430461 -151.199346) (xy 419.414393 -151.252753) (xy 419.390721 -151.30325)
			(xy 419.359948 -151.349763) (xy 419.322731 -151.3913) (xy 419.279863 -151.426975) (xy 419.232257 -151.456029)
			(xy 419.180928 -151.477841) (xy 419.126971 -151.491947) (xy 419.071534 -151.498047) (xy 419.0158 -151.49601)
			(xy 418.960957 -151.48588) (xy 418.908173 -151.467873) (xy 418.858573 -151.442372) (xy 418.813215 -151.409921)
			(xy 418.773066 -151.371212) (xy 418.73898 -151.327069) (xy 418.711684 -151.278434) (xy 418.691761 -151.226343)
			(xy 418.679635 -151.171906) (xy 418.675564 -151.116284) (xy 410.41574 -151.116284) (xy 410.41574 -152.03297)
			(xy 418.678358 -152.03297) (xy 418.682429 -151.977348) (xy 418.694555 -151.922911) (xy 418.714478 -151.87082)
			(xy 418.741774 -151.822185) (xy 418.77586 -151.778042) (xy 418.816009 -151.739333) (xy 418.861367 -151.706882)
			(xy 418.910967 -151.681381) (xy 418.963751 -151.663374) (xy 419.018594 -151.653244) (xy 419.074328 -151.651207)
			(xy 419.129765 -151.657307) (xy 419.183722 -151.671413) (xy 419.235051 -151.693225) (xy 419.282657 -151.722279)
			(xy 419.325525 -151.757954) (xy 419.362742 -151.799491) (xy 419.393515 -151.846004) (xy 419.417187 -151.896501)
			(xy 419.433255 -151.949908) (xy 419.441375 -152.005084) (xy 419.441884 -152.03297) (xy 419.441787 -152.038304)
			(xy 419.676578 -152.038304) (xy 419.680649 -151.982682) (xy 419.692775 -151.928245) (xy 419.712698 -151.876154)
			(xy 419.739994 -151.827519) (xy 419.77408 -151.783376) (xy 419.814229 -151.744667) (xy 419.859587 -151.712216)
			(xy 419.909187 -151.686715) (xy 419.961971 -151.668708) (xy 420.016814 -151.658578) (xy 420.072548 -151.656541)
			(xy 420.127985 -151.662641) (xy 420.181942 -151.676747) (xy 420.233271 -151.698559) (xy 420.280877 -151.727613)
			(xy 420.323745 -151.763288) (xy 420.360962 -151.804825) (xy 420.391735 -151.851338) (xy 420.415407 -151.901835)
			(xy 420.431475 -151.955242) (xy 420.439595 -152.010418) (xy 420.440104 -152.038304) (xy 420.439595 -152.06619)
			(xy 420.431475 -152.121366) (xy 420.415407 -152.174773) (xy 420.391735 -152.22527) (xy 420.360962 -152.271783)
			(xy 420.323745 -152.31332) (xy 420.280877 -152.348995) (xy 420.233271 -152.378049) (xy 420.181942 -152.399861)
			(xy 420.127985 -152.413967) (xy 420.072548 -152.420067) (xy 420.016814 -152.41803) (xy 419.961971 -152.4079)
			(xy 419.909187 -152.389893) (xy 419.859587 -152.364392) (xy 419.814229 -152.331941) (xy 419.77408 -152.293232)
			(xy 419.739994 -152.249089) (xy 419.712698 -152.200454) (xy 419.692775 -152.148363) (xy 419.680649 -152.093926)
			(xy 419.676578 -152.038304) (xy 419.441787 -152.038304) (xy 419.441375 -152.060856) (xy 419.433255 -152.116032)
			(xy 419.417187 -152.169439) (xy 419.393515 -152.219936) (xy 419.362742 -152.266449) (xy 419.325525 -152.307986)
			(xy 419.282657 -152.343661) (xy 419.235051 -152.372715) (xy 419.183722 -152.394527) (xy 419.129765 -152.408633)
			(xy 419.074328 -152.414733) (xy 419.018594 -152.412696) (xy 418.963751 -152.402566) (xy 418.910967 -152.384559)
			(xy 418.861367 -152.359058) (xy 418.816009 -152.326607) (xy 418.77586 -152.287898) (xy 418.741774 -152.243755)
			(xy 418.714478 -152.19512) (xy 418.694555 -152.143029) (xy 418.682429 -152.088592) (xy 418.678358 -152.03297)
			(xy 410.41574 -152.03297) (xy 410.41574 -152.977342) (xy 421.425622 -152.977342) (xy 421.429693 -152.92172)
			(xy 421.441819 -152.867283) (xy 421.461742 -152.815192) (xy 421.489038 -152.766557) (xy 421.523124 -152.722414)
			(xy 421.563273 -152.683705) (xy 421.608631 -152.651254) (xy 421.658231 -152.625753) (xy 421.711015 -152.607746)
			(xy 421.765858 -152.597616) (xy 421.821592 -152.595579) (xy 421.877029 -152.601679) (xy 421.930986 -152.615785)
			(xy 421.982315 -152.637597) (xy 422.029921 -152.666651) (xy 422.072789 -152.702326) (xy 422.110006 -152.743863)
			(xy 422.140779 -152.790376) (xy 422.164451 -152.840873) (xy 422.180519 -152.89428) (xy 422.188639 -152.949456)
			(xy 422.188768 -152.956514) (xy 422.32402 -152.956514) (xy 422.328091 -152.900892) (xy 422.340217 -152.846455)
			(xy 422.36014 -152.794364) (xy 422.387436 -152.745729) (xy 422.421522 -152.701586) (xy 422.461671 -152.662877)
			(xy 422.507029 -152.630426) (xy 422.556629 -152.604925) (xy 422.609413 -152.586918) (xy 422.664256 -152.576788)
			(xy 422.71999 -152.574751) (xy 422.775427 -152.580851) (xy 422.829384 -152.594957) (xy 422.880713 -152.616769)
			(xy 422.928319 -152.645823) (xy 422.971187 -152.681498) (xy 423.008404 -152.723035) (xy 423.039177 -152.769548)
			(xy 423.062849 -152.820045) (xy 423.078917 -152.873452) (xy 423.087037 -152.928628) (xy 423.087546 -152.956514)
			(xy 423.087037 -152.9844) (xy 423.078917 -153.039576) (xy 423.062849 -153.092983) (xy 423.039177 -153.14348)
			(xy 423.008404 -153.189993) (xy 422.971187 -153.23153) (xy 422.928319 -153.267205) (xy 422.880713 -153.296259)
			(xy 422.829384 -153.318071) (xy 422.775427 -153.332177) (xy 422.71999 -153.338277) (xy 422.664256 -153.33624)
			(xy 422.609413 -153.32611) (xy 422.556629 -153.308103) (xy 422.507029 -153.282602) (xy 422.461671 -153.250151)
			(xy 422.421522 -153.211442) (xy 422.387436 -153.167299) (xy 422.36014 -153.118664) (xy 422.340217 -153.066573)
			(xy 422.328091 -153.012136) (xy 422.32402 -152.956514) (xy 422.188768 -152.956514) (xy 422.189148 -152.977342)
			(xy 422.188639 -153.005228) (xy 422.180519 -153.060404) (xy 422.164451 -153.113811) (xy 422.140779 -153.164308)
			(xy 422.110006 -153.210821) (xy 422.072789 -153.252358) (xy 422.029921 -153.288033) (xy 421.982315 -153.317087)
			(xy 421.930986 -153.338899) (xy 421.877029 -153.353005) (xy 421.821592 -153.359105) (xy 421.765858 -153.357068)
			(xy 421.711015 -153.346938) (xy 421.658231 -153.328931) (xy 421.608631 -153.30343) (xy 421.563273 -153.270979)
			(xy 421.523124 -153.23227) (xy 421.489038 -153.188127) (xy 421.461742 -153.139492) (xy 421.441819 -153.087401)
			(xy 421.429693 -153.032964) (xy 421.425622 -152.977342) (xy 410.41574 -152.977342) (xy 410.41574 -153.54046)
			(xy 423.60037 -153.54046) (xy 423.604441 -153.484838) (xy 423.616567 -153.430401) (xy 423.63649 -153.37831)
			(xy 423.663786 -153.329675) (xy 423.697872 -153.285532) (xy 423.738021 -153.246823) (xy 423.783379 -153.214372)
			(xy 423.832979 -153.188871) (xy 423.885763 -153.170864) (xy 423.940606 -153.160734) (xy 423.99634 -153.158697)
			(xy 424.051777 -153.164797) (xy 424.105734 -153.178903) (xy 424.157063 -153.200715) (xy 424.204669 -153.229769)
			(xy 424.247537 -153.265444) (xy 424.284754 -153.306981) (xy 424.315527 -153.353494) (xy 424.339199 -153.403991)
			(xy 424.355267 -153.457398) (xy 424.363387 -153.512574) (xy 424.363896 -153.54046) (xy 424.363387 -153.568346)
			(xy 424.355267 -153.623522) (xy 424.339199 -153.676929) (xy 424.315527 -153.727426) (xy 424.284754 -153.773939)
			(xy 424.247537 -153.815476) (xy 424.204669 -153.851151) (xy 424.157063 -153.880205) (xy 424.105734 -153.902017)
			(xy 424.051777 -153.916123) (xy 423.99634 -153.922223) (xy 423.940606 -153.920186) (xy 423.885763 -153.910056)
			(xy 423.832979 -153.892049) (xy 423.783379 -153.866548) (xy 423.738021 -153.834097) (xy 423.697872 -153.795388)
			(xy 423.663786 -153.751245) (xy 423.63649 -153.70261) (xy 423.616567 -153.650519) (xy 423.604441 -153.596082)
			(xy 423.60037 -153.54046) (xy 410.41574 -153.54046) (xy 410.41574 -155.499308) (xy 417.524182 -155.499308)
			(xy 417.528253 -155.443686) (xy 417.540379 -155.389249) (xy 417.560302 -155.337158) (xy 417.587598 -155.288523)
			(xy 417.621684 -155.24438) (xy 417.661833 -155.205671) (xy 417.707191 -155.17322) (xy 417.756791 -155.147719)
			(xy 417.809575 -155.129712) (xy 417.864418 -155.119582) (xy 417.920152 -155.117545) (xy 417.975589 -155.123645)
			(xy 418.029546 -155.137751) (xy 418.080875 -155.159563) (xy 418.128481 -155.188617) (xy 418.162419 -155.21686)
			(xy 420.484552 -155.21686) (xy 420.488623 -155.161238) (xy 420.500749 -155.106801) (xy 420.520672 -155.05471)
			(xy 420.547968 -155.006075) (xy 420.582054 -154.961932) (xy 420.622203 -154.923223) (xy 420.667561 -154.890772)
			(xy 420.717161 -154.865271) (xy 420.769945 -154.847264) (xy 420.824788 -154.837134) (xy 420.880522 -154.835097)
			(xy 420.935959 -154.841197) (xy 420.989916 -154.855303) (xy 421.041245 -154.877115) (xy 421.088851 -154.906169)
			(xy 421.131719 -154.941844) (xy 421.168936 -154.983381) (xy 421.199709 -155.029894) (xy 421.223381 -155.080391)
			(xy 421.239449 -155.133798) (xy 421.247569 -155.188974) (xy 421.248078 -155.21686) (xy 421.247569 -155.244746)
			(xy 421.239449 -155.299922) (xy 421.223381 -155.353329) (xy 421.199709 -155.403826) (xy 421.168936 -155.450339)
			(xy 421.131719 -155.491876) (xy 421.088851 -155.527551) (xy 421.041245 -155.556605) (xy 420.989916 -155.578417)
			(xy 420.935959 -155.592523) (xy 420.880522 -155.598623) (xy 420.824788 -155.596586) (xy 420.769945 -155.586456)
			(xy 420.717161 -155.568449) (xy 420.667561 -155.542948) (xy 420.622203 -155.510497) (xy 420.582054 -155.471788)
			(xy 420.547968 -155.427645) (xy 420.520672 -155.37901) (xy 420.500749 -155.326919) (xy 420.488623 -155.272482)
			(xy 420.484552 -155.21686) (xy 418.162419 -155.21686) (xy 418.171349 -155.224292) (xy 418.208566 -155.265829)
			(xy 418.239339 -155.312342) (xy 418.263011 -155.362839) (xy 418.279079 -155.416246) (xy 418.287199 -155.471422)
			(xy 418.287708 -155.499308) (xy 418.287199 -155.527194) (xy 418.279079 -155.58237) (xy 418.263011 -155.635777)
			(xy 418.239339 -155.686274) (xy 418.208566 -155.732787) (xy 418.171349 -155.774324) (xy 418.128481 -155.809999)
			(xy 418.080875 -155.839053) (xy 418.029546 -155.860865) (xy 417.975589 -155.874971) (xy 417.920152 -155.881071)
			(xy 417.864418 -155.879034) (xy 417.809575 -155.868904) (xy 417.756791 -155.850897) (xy 417.707191 -155.825396)
			(xy 417.661833 -155.792945) (xy 417.621684 -155.754236) (xy 417.587598 -155.710093) (xy 417.560302 -155.661458)
			(xy 417.540379 -155.609367) (xy 417.528253 -155.55493) (xy 417.524182 -155.499308) (xy 410.41574 -155.499308)
			(xy 410.41574 -155.972256) (xy 423.64482 -155.972256) (xy 423.648891 -155.916634) (xy 423.661017 -155.862197)
			(xy 423.68094 -155.810106) (xy 423.708236 -155.761471) (xy 423.742322 -155.717328) (xy 423.782471 -155.678619)
			(xy 423.827829 -155.646168) (xy 423.877429 -155.620667) (xy 423.930213 -155.60266) (xy 423.985056 -155.59253)
			(xy 424.04079 -155.590493) (xy 424.096227 -155.596593) (xy 424.150184 -155.610699) (xy 424.201513 -155.632511)
			(xy 424.249119 -155.661565) (xy 424.291987 -155.69724) (xy 424.329204 -155.738777) (xy 424.359977 -155.78529)
			(xy 424.383649 -155.835787) (xy 424.399717 -155.889194) (xy 424.407837 -155.94437) (xy 424.408346 -155.972256)
			(xy 424.407837 -156.000142) (xy 424.399717 -156.055318) (xy 424.383649 -156.108725) (xy 424.359977 -156.159222)
			(xy 424.329204 -156.205735) (xy 424.291987 -156.247272) (xy 424.249119 -156.282947) (xy 424.201513 -156.312001)
			(xy 424.150184 -156.333813) (xy 424.096227 -156.347919) (xy 424.04079 -156.354019) (xy 423.985056 -156.351982)
			(xy 423.930213 -156.341852) (xy 423.877429 -156.323845) (xy 423.827829 -156.298344) (xy 423.782471 -156.265893)
			(xy 423.742322 -156.227184) (xy 423.708236 -156.183041) (xy 423.68094 -156.134406) (xy 423.661017 -156.082315)
			(xy 423.648891 -156.027878) (xy 423.64482 -155.972256) (xy 410.41574 -155.972256) (xy 410.41574 -156.960062)
			(xy 422.378122 -156.960062) (xy 422.382193 -156.90444) (xy 422.394319 -156.850003) (xy 422.414242 -156.797912)
			(xy 422.441538 -156.749277) (xy 422.475624 -156.705134) (xy 422.515773 -156.666425) (xy 422.561131 -156.633974)
			(xy 422.610731 -156.608473) (xy 422.663515 -156.590466) (xy 422.718358 -156.580336) (xy 422.774092 -156.578299)
			(xy 422.829529 -156.584399) (xy 422.883486 -156.598505) (xy 422.934815 -156.620317) (xy 422.982421 -156.649371)
			(xy 423.025289 -156.685046) (xy 423.062506 -156.726583) (xy 423.093279 -156.773096) (xy 423.116951 -156.823593)
			(xy 423.133019 -156.877) (xy 423.133431 -156.879798) (xy 423.523662 -156.879798) (xy 423.527733 -156.824176)
			(xy 423.539859 -156.769739) (xy 423.559782 -156.717648) (xy 423.587078 -156.669013) (xy 423.621164 -156.62487)
			(xy 423.661313 -156.586161) (xy 423.706671 -156.55371) (xy 423.756271 -156.528209) (xy 423.809055 -156.510202)
			(xy 423.863898 -156.500072) (xy 423.919632 -156.498035) (xy 423.975069 -156.504135) (xy 424.029026 -156.518241)
			(xy 424.080355 -156.540053) (xy 424.127961 -156.569107) (xy 424.170829 -156.604782) (xy 424.208046 -156.646319)
			(xy 424.238819 -156.692832) (xy 424.262491 -156.743329) (xy 424.278559 -156.796736) (xy 424.286679 -156.851912)
			(xy 424.287188 -156.879798) (xy 424.286679 -156.907684) (xy 424.278559 -156.96286) (xy 424.262512 -157.016196)
			(xy 426.587415 -157.016196) (xy 426.591451 -156.932749) (xy 426.603523 -156.850081) (xy 426.623516 -156.768964)
			(xy 426.651245 -156.690155) (xy 426.686451 -156.61439) (xy 426.728805 -156.542377) (xy 426.777911 -156.474788)
			(xy 426.833312 -156.412254) (xy 426.894489 -156.355359) (xy 426.960872 -156.304633) (xy 427.03184 -156.260552)
			(xy 427.106732 -156.223526) (xy 427.184848 -156.1939) (xy 427.265458 -156.171952) (xy 427.34781 -156.157887)
			(xy 427.431136 -156.151835) (xy 427.514656 -156.153854) (xy 427.597592 -156.163924) (xy 427.679168 -156.181952)
			(xy 427.758624 -156.207769) (xy 427.835217 -156.241134) (xy 427.908233 -156.281735) (xy 427.976989 -156.329194)
			(xy 428.040843 -156.383067) (xy 428.0992 -156.442852) (xy 428.151515 -156.507989) (xy 428.197298 -156.577872)
			(xy 428.236123 -156.651847) (xy 428.267628 -156.729224) (xy 428.291517 -156.809281) (xy 428.307568 -156.891269)
			(xy 428.315631 -156.974424) (xy 428.316136 -157.016196) (xy 428.315631 -157.057968) (xy 428.307568 -157.141123)
			(xy 428.291517 -157.223111) (xy 428.267628 -157.303168) (xy 428.236123 -157.380545) (xy 428.197298 -157.45452)
			(xy 428.151515 -157.524403) (xy 428.0992 -157.58954) (xy 428.040843 -157.649325) (xy 427.976989 -157.703198)
			(xy 427.908233 -157.750657) (xy 427.835217 -157.791258) (xy 427.758624 -157.824623) (xy 427.679168 -157.85044)
			(xy 427.597592 -157.868468) (xy 427.514656 -157.878538) (xy 427.431136 -157.880557) (xy 427.34781 -157.874505)
			(xy 427.265458 -157.86044) (xy 427.184848 -157.838492) (xy 427.106732 -157.808866) (xy 427.03184 -157.77184)
			(xy 426.960872 -157.727759) (xy 426.894489 -157.677033) (xy 426.833312 -157.620138) (xy 426.777911 -157.557604)
			(xy 426.728805 -157.490015) (xy 426.686451 -157.418002) (xy 426.651245 -157.342237) (xy 426.623516 -157.263428)
			(xy 426.603523 -157.182311) (xy 426.591451 -157.099643) (xy 426.587415 -157.016196) (xy 424.262512 -157.016196)
			(xy 424.262491 -157.016267) (xy 424.238819 -157.066764) (xy 424.208046 -157.113277) (xy 424.170829 -157.154814)
			(xy 424.127961 -157.190489) (xy 424.080355 -157.219543) (xy 424.029026 -157.241355) (xy 423.975069 -157.255461)
			(xy 423.919632 -157.261561) (xy 423.863898 -157.259524) (xy 423.809055 -157.249394) (xy 423.756271 -157.231387)
			(xy 423.706671 -157.205886) (xy 423.661313 -157.173435) (xy 423.621164 -157.134726) (xy 423.587078 -157.090583)
			(xy 423.559782 -157.041948) (xy 423.539859 -156.989857) (xy 423.527733 -156.93542) (xy 423.523662 -156.879798)
			(xy 423.133431 -156.879798) (xy 423.141139 -156.932176) (xy 423.141648 -156.960062) (xy 423.141139 -156.987948)
			(xy 423.133019 -157.043124) (xy 423.116951 -157.096531) (xy 423.093279 -157.147028) (xy 423.062506 -157.193541)
			(xy 423.025289 -157.235078) (xy 422.982421 -157.270753) (xy 422.934815 -157.299807) (xy 422.883486 -157.321619)
			(xy 422.829529 -157.335725) (xy 422.774092 -157.341825) (xy 422.718358 -157.339788) (xy 422.663515 -157.329658)
			(xy 422.610731 -157.311651) (xy 422.561131 -157.28615) (xy 422.515773 -157.253699) (xy 422.475624 -157.21499)
			(xy 422.441538 -157.170847) (xy 422.414242 -157.122212) (xy 422.394319 -157.070121) (xy 422.382193 -157.015684)
			(xy 422.378122 -156.960062) (xy 410.41574 -156.960062) (xy 410.41574 -157.648148) (xy 419.535862 -157.648148)
			(xy 419.539933 -157.592526) (xy 419.552059 -157.538089) (xy 419.571982 -157.485998) (xy 419.599278 -157.437363)
			(xy 419.633364 -157.39322) (xy 419.673513 -157.354511) (xy 419.718871 -157.32206) (xy 419.768471 -157.296559)
			(xy 419.821255 -157.278552) (xy 419.876098 -157.268422) (xy 419.931832 -157.266385) (xy 419.987269 -157.272485)
			(xy 420.041226 -157.286591) (xy 420.092555 -157.308403) (xy 420.140161 -157.337457) (xy 420.183029 -157.373132)
			(xy 420.220246 -157.414669) (xy 420.251019 -157.461182) (xy 420.274691 -157.511679) (xy 420.290759 -157.565086)
			(xy 420.298879 -157.620262) (xy 420.299388 -157.648148) (xy 420.298879 -157.676034) (xy 420.290759 -157.73121)
			(xy 420.274691 -157.784617) (xy 420.251019 -157.835114) (xy 420.220246 -157.881627) (xy 420.183029 -157.923164)
			(xy 420.140161 -157.958839) (xy 420.092555 -157.987893) (xy 420.041226 -158.009705) (xy 419.987269 -158.023811)
			(xy 419.931832 -158.029911) (xy 419.876098 -158.027874) (xy 419.821255 -158.017744) (xy 419.768471 -157.999737)
			(xy 419.718871 -157.974236) (xy 419.673513 -157.941785) (xy 419.633364 -157.903076) (xy 419.599278 -157.858933)
			(xy 419.571982 -157.810298) (xy 419.552059 -157.758207) (xy 419.539933 -157.70377) (xy 419.535862 -157.648148)
			(xy 410.41574 -157.648148) (xy 410.41574 -161.520378) (xy 417.4998 -161.520378) (xy 417.500317 -161.493048)
			(xy 417.50828 -161.438971) (xy 417.524061 -161.386638) (xy 417.547322 -161.337175) (xy 417.577563 -161.291642)
			(xy 417.614133 -161.251018) (xy 417.656249 -161.216176) (xy 417.679378 -161.201608) (xy 417.691578 -161.19365)
			(xy 417.711251 -161.172189) (xy 417.724061 -161.146045) (xy 417.728962 -161.117347) (xy 417.725556 -161.088434)
			(xy 417.720272 -161.074862) (xy 417.710777 -161.051654) (xy 417.697428 -161.00332) (xy 417.690702 -160.95363)
			(xy 417.6903 -160.928558) (xy 417.690724 -160.903489) (xy 417.697474 -160.853806) (xy 417.710806 -160.805471)
			(xy 417.720272 -160.782254) (xy 417.725563 -160.768687) (xy 417.728937 -160.739773) (xy 417.724027 -160.711079)
			(xy 417.711231 -160.68493) (xy 417.691587 -160.663447) (xy 417.679378 -160.655508) (xy 417.656281 -160.640887)
			(xy 417.61416 -160.60605) (xy 417.57758 -160.565433) (xy 417.547327 -160.519907) (xy 417.52405 -160.470451)
			(xy 417.508247 -160.418124) (xy 417.500259 -160.36405) (xy 417.500256 -160.309389) (xy 417.508238 -160.255314)
			(xy 417.524036 -160.202986) (xy 417.547308 -160.153527) (xy 417.577556 -160.107998) (xy 417.614131 -160.067377)
			(xy 417.656249 -160.032536) (xy 417.679378 -160.017968) (xy 417.691605 -160.010048) (xy 417.711279 -159.988577)
			(xy 417.724084 -159.962423) (xy 417.728979 -159.933716) (xy 417.725563 -159.904796) (xy 417.720272 -159.891222)
			(xy 417.710796 -159.868007) (xy 417.69744 -159.819677) (xy 417.690706 -159.769989) (xy 417.6903 -159.744918)
			(xy 417.690766 -159.718075) (xy 417.698468 -159.664945) (xy 417.713716 -159.61347) (xy 417.736193 -159.564717)
			(xy 417.765435 -159.519694) (xy 417.800836 -159.479334) (xy 417.841662 -159.444472) (xy 417.887069 -159.415831)
			(xy 417.936117 -159.394002) (xy 417.961826 -159.38627) (xy 417.976329 -159.38162) (xy 418.0019 -159.365103)
			(xy 418.021469 -159.341785) (xy 418.033299 -159.313737) (xy 418.03634 -159.283448) (xy 418.030322 -159.253608)
			(xy 418.023548 -159.239966) (xy 418.00892 -159.211818) (xy 417.988191 -159.151868) (xy 417.977691 -159.08931)
			(xy 417.977066 -159.057594) (xy 417.977291 -159.039575) (xy 417.980722 -159.0037) (xy 417.983924 -158.985966)
			(xy 417.986322 -158.970764) (xy 417.982784 -158.940201) (xy 417.97031 -158.912077) (xy 417.95003 -158.888941)
			(xy 417.923782 -158.872889) (xy 417.908994 -158.868618) (xy 417.881967 -158.861164) (xy 417.830242 -158.839542)
			(xy 417.782237 -158.810585) (xy 417.738984 -158.774917) (xy 417.701416 -158.733305) (xy 417.670339 -158.686645)
			(xy 417.646423 -158.63594) (xy 417.630183 -158.582282) (xy 417.621967 -158.526825) (xy 417.621466 -158.498794)
			(xy 417.621972 -158.471544) (xy 417.629729 -158.417598) (xy 417.645083 -158.365305) (xy 417.667723 -158.31573)
			(xy 417.697188 -158.269881) (xy 417.732877 -158.228691) (xy 417.774065 -158.193) (xy 417.819912 -158.163533)
			(xy 417.869487 -158.14089) (xy 417.921779 -158.125533) (xy 417.975724 -158.117774) (xy 418.002974 -158.117286)
			(xy 418.030548 -158.117774) (xy 418.085119 -158.125723) (xy 418.137979 -158.141444) (xy 418.188024 -158.16461)
			(xy 418.234215 -158.194738) (xy 418.275587 -158.231201) (xy 418.293804 -158.251906) (xy 418.303702 -158.262804)
			(xy 418.328352 -158.278879) (xy 418.35656 -158.287263) (xy 418.385988 -158.287263) (xy 418.414196 -158.278879)
			(xy 418.438846 -158.262804) (xy 418.448744 -158.251906) (xy 418.466959 -158.2312) (xy 418.50833 -158.194735)
			(xy 418.55452 -158.164608) (xy 418.604567 -158.141445) (xy 418.657428 -158.125729) (xy 418.712 -158.117789)
			(xy 418.767148 -158.117789) (xy 418.82172 -158.125729) (xy 418.874581 -158.141445) (xy 418.924628 -158.164608)
			(xy 418.970818 -158.194735) (xy 419.012189 -158.2312) (xy 419.030404 -158.251906) (xy 419.040302 -158.262804)
			(xy 419.064952 -158.278879) (xy 419.09316 -158.287263) (xy 419.122588 -158.287263) (xy 419.150796 -158.278879)
			(xy 419.175446 -158.262804) (xy 419.185344 -158.251906) (xy 419.203582 -158.23122) (xy 419.244945 -158.194747)
			(xy 419.291129 -158.164612) (xy 419.341172 -158.141442) (xy 419.39403 -158.12572) (xy 419.448601 -158.117775)
			(xy 419.476174 -158.117286) (xy 419.503426 -158.117779) (xy 419.557375 -158.125533) (xy 419.609672 -158.140885)
			(xy 419.659252 -158.163524) (xy 419.705105 -158.192989) (xy 419.746298 -158.22868) (xy 419.781992 -158.269869)
			(xy 419.81146 -158.31572) (xy 419.834104 -158.365298) (xy 419.84946 -158.417593) (xy 419.857218 -158.471542)
			(xy 419.857682 -158.498794) (xy 419.857167 -158.52665) (xy 419.849043 -158.581766) (xy 419.832998 -158.635117)
			(xy 419.80937 -158.685571) (xy 419.778663 -158.732056) (xy 419.741526 -158.773585) (xy 419.69875 -158.809278)
			(xy 419.651241 -158.838376) (xy 419.600008 -158.860262) (xy 419.573202 -158.867856) (xy 419.559077 -158.872105)
			(xy 419.53393 -158.887501) (xy 419.514215 -158.909425) (xy 419.501566 -158.93606) (xy 419.497034 -158.965195)
			(xy 419.498526 -158.97987) (xy 419.5002 -158.992886) (xy 419.501977 -159.019071) (xy 419.502082 -159.032194)
			(xy 419.501988 -159.046343) (xy 419.499954 -159.074566) (xy 419.498018 -159.088582) (xy 419.496394 -159.101927)
			(xy 419.4995 -159.128623) (xy 419.509476 -159.153579) (xy 419.525629 -159.17506) (xy 419.546835 -159.191572)
			(xy 419.57162 -159.201966) (xy 419.584886 -159.204152) (xy 419.612039 -159.208237) (xy 419.664868 -159.223214)
			(xy 419.715004 -159.245609) (xy 419.761412 -159.274958) (xy 419.803135 -159.310656) (xy 419.839311 -159.351965)
			(xy 419.869192 -159.398033) (xy 419.892162 -159.447908) (xy 419.907746 -159.500561) (xy 419.915622 -159.554903)
			(xy 419.915688 -159.558666) (xy 426.563024 -159.558666) (xy 426.563024 -159.47397) (xy 426.571075 -159.389656)
			(xy 426.587104 -159.30649) (xy 426.610965 -159.225223) (xy 426.642444 -159.146593) (xy 426.681255 -159.071312)
			(xy 426.727045 -159.00006) (xy 426.779401 -158.933484) (xy 426.837849 -158.872186) (xy 426.901859 -158.816721)
			(xy 426.970851 -158.767592) (xy 427.044201 -158.725243) (xy 427.121244 -158.690059) (xy 427.201283 -158.662357)
			(xy 427.283592 -158.642389) (xy 427.367427 -158.630336) (xy 427.452028 -158.626306) (xy 427.536629 -158.630336)
			(xy 427.620464 -158.642389) (xy 427.702773 -158.662357) (xy 427.782812 -158.690059) (xy 427.859855 -158.725243)
			(xy 427.933205 -158.767592) (xy 428.002197 -158.816721) (xy 428.066207 -158.872186) (xy 428.124655 -158.933484)
			(xy 428.177011 -159.00006) (xy 428.222801 -159.071312) (xy 428.261612 -159.146593) (xy 428.293091 -159.225223)
			(xy 428.316952 -159.30649) (xy 428.332981 -159.389656) (xy 428.341032 -159.47397) (xy 428.341536 -159.516318)
			(xy 428.341032 -159.558666) (xy 428.332981 -159.64298) (xy 428.316952 -159.726146) (xy 428.293091 -159.807413)
			(xy 428.261612 -159.886043) (xy 428.222801 -159.961324) (xy 428.177011 -160.032576) (xy 428.124655 -160.099152)
			(xy 428.066207 -160.16045) (xy 428.002197 -160.215915) (xy 427.933205 -160.265044) (xy 427.859855 -160.307393)
			(xy 427.782812 -160.342577) (xy 427.702773 -160.370279) (xy 427.620464 -160.390247) (xy 427.536629 -160.4023)
			(xy 427.452028 -160.406331) (xy 427.367427 -160.4023) (xy 427.283592 -160.390247) (xy 427.201283 -160.370279)
			(xy 427.121244 -160.342577) (xy 427.044201 -160.307393) (xy 426.970851 -160.265044) (xy 426.901859 -160.215915)
			(xy 426.837849 -160.16045) (xy 426.779401 -160.099152) (xy 426.727045 -160.032576) (xy 426.681255 -159.961324)
			(xy 426.642444 -159.886043) (xy 426.610965 -159.807413) (xy 426.587104 -159.726146) (xy 426.571075 -159.64298)
			(xy 426.563024 -159.558666) (xy 419.915688 -159.558666) (xy 419.916102 -159.582358) (xy 419.915606 -159.60961)
			(xy 419.907854 -159.66356) (xy 419.892503 -159.715858) (xy 419.869865 -159.765438) (xy 419.840401 -159.811292)
			(xy 419.804711 -159.852485) (xy 419.763521 -159.888179) (xy 419.71767 -159.917648) (xy 419.668092 -159.940291)
			(xy 419.615795 -159.955647) (xy 419.561846 -159.963403) (xy 419.534594 -159.963866) (xy 419.507019 -159.963416)
			(xy 419.452445 -159.955462) (xy 419.399584 -159.939735) (xy 419.349538 -159.916562) (xy 419.303349 -159.886426)
			(xy 419.261979 -159.849955) (xy 419.243764 -159.829246) (xy 419.233866 -159.818348) (xy 419.209216 -159.802273)
			(xy 419.181008 -159.793889) (xy 419.15158 -159.793889) (xy 419.123372 -159.802273) (xy 419.098722 -159.818348)
			(xy 419.088824 -159.829246) (xy 419.070614 -159.849958) (xy 419.029244 -159.886426) (xy 418.983053 -159.916557)
			(xy 418.933005 -159.939722) (xy 418.880143 -159.955439) (xy 418.825569 -159.96338) (xy 418.797994 -159.963866)
			(xy 418.771493 -159.963405) (xy 418.719002 -159.956063) (xy 418.668034 -159.941521) (xy 418.619572 -159.920059)
			(xy 418.574549 -159.892091) (xy 418.5539 -159.875474) (xy 418.541717 -159.866082) (xy 418.51333 -159.854285)
			(xy 418.482719 -159.851451) (xy 418.452648 -159.857838) (xy 418.425831 -159.872868) (xy 418.404689 -159.895186)
			(xy 418.397436 -159.908748) (xy 418.385321 -159.93243) (xy 418.355402 -159.976413) (xy 418.319535 -160.015696)
			(xy 418.278448 -160.049482) (xy 418.255958 -160.063688) (xy 418.243751 -160.071635) (xy 418.224085 -160.093102)
			(xy 418.211281 -160.119249) (xy 418.206381 -160.147947) (xy 418.209783 -160.176861) (xy 418.215064 -160.190434)
			(xy 418.22456 -160.213641) (xy 418.237908 -160.261976) (xy 418.244633 -160.311666) (xy 418.245036 -160.336738)
			(xy 418.244615 -160.361807) (xy 418.237865 -160.411491) (xy 418.224531 -160.459825) (xy 418.215064 -160.483042)
			(xy 418.209854 -160.496631) (xy 418.206485 -160.525525) (xy 418.211389 -160.554198) (xy 418.224168 -160.58033)
			(xy 418.243789 -160.601805) (xy 418.255958 -160.609788) (xy 418.27905 -160.624416) (xy 418.321167 -160.659255)
			(xy 418.357742 -160.699872) (xy 418.387993 -160.745397) (xy 418.411268 -160.794852) (xy 418.427069 -160.847177)
			(xy 418.435057 -160.901249) (xy 418.43506 -160.955908) (xy 418.427078 -161.00998) (xy 418.411283 -161.062307)
			(xy 418.388014 -161.111765) (xy 418.357769 -161.157294) (xy 418.321198 -161.197915) (xy 418.279085 -161.232759)
			(xy 418.255958 -161.247328) (xy 418.243724 -161.255237) (xy 418.224058 -161.276714) (xy 418.211257 -161.302871)
			(xy 418.206364 -161.331578) (xy 418.209777 -161.360499) (xy 418.215064 -161.374074) (xy 418.224541 -161.397289)
			(xy 418.237896 -161.445619) (xy 418.244629 -161.495307) (xy 418.245036 -161.520378) (xy 418.244515 -161.548263)
			(xy 418.236203 -161.60341) (xy 418.219765 -161.656702) (xy 418.195567 -161.706948) (xy 418.164151 -161.753027)
			(xy 418.126218 -161.793909) (xy 418.082616 -161.828681) (xy 418.034318 -161.856566) (xy 417.982403 -161.876941)
			(xy 417.928032 -161.889351) (xy 417.872418 -161.893519) (xy 417.816804 -161.889351) (xy 417.762433 -161.876941)
			(xy 417.710518 -161.856566) (xy 417.66222 -161.828681) (xy 417.618618 -161.793909) (xy 417.580685 -161.753027)
			(xy 417.549269 -161.706948) (xy 417.525071 -161.656702) (xy 417.508633 -161.60341) (xy 417.500321 -161.548263)
			(xy 417.4998 -161.520378) (xy 410.41574 -161.520378) (xy 410.41574 -162.451542) (xy 419.315646 -162.451542)
			(xy 419.316217 -162.424294) (xy 419.323967 -162.370352) (xy 419.339314 -162.318061) (xy 419.361947 -162.268487)
			(xy 419.391405 -162.222639) (xy 419.427087 -162.18145) (xy 419.468269 -162.145757) (xy 419.51411 -162.116289)
			(xy 419.563679 -162.093645) (xy 419.615966 -162.078285) (xy 419.669906 -162.070523) (xy 419.697154 -162.070034)
			(xy 419.727059 -162.070571) (xy 419.786138 -162.079883) (xy 419.814756 -162.088576) (xy 419.82866 -162.09263)
			(xy 419.857597 -162.09354) (xy 419.885621 -162.086274) (xy 419.910469 -162.071418) (xy 419.930134 -162.050171)
			(xy 419.943028 -162.024251) (xy 419.946074 -162.01009) (xy 419.951204 -161.984008) (xy 419.967775 -161.933501)
			(xy 419.991201 -161.885784) (xy 420.021027 -161.841784) (xy 420.056674 -161.802352) (xy 420.097452 -161.768253)
			(xy 420.142571 -161.740148) (xy 420.191156 -161.718581) (xy 420.242265 -161.703971) (xy 420.294908 -161.696601)
			(xy 420.321486 -161.696146) (xy 420.348736 -161.6967) (xy 420.402682 -161.704455) (xy 420.454975 -161.719808)
			(xy 420.504551 -161.742447) (xy 420.550401 -161.771911) (xy 420.59159 -161.8076) (xy 420.627281 -161.848788)
			(xy 420.656747 -161.894636) (xy 420.679387 -161.944211) (xy 420.694742 -161.996504) (xy 420.702499 -162.05045)
			(xy 420.702499 -162.10495) (xy 420.694742 -162.158896) (xy 420.679387 -162.211189) (xy 420.656747 -162.260764)
			(xy 420.627281 -162.306612) (xy 420.59159 -162.3478) (xy 420.550401 -162.383489) (xy 420.504551 -162.412953)
			(xy 420.454975 -162.435592) (xy 420.402682 -162.450945) (xy 420.348736 -162.4587) (xy 420.321486 -162.459162)
			(xy 420.291581 -162.458639) (xy 420.232502 -162.449318) (xy 420.203884 -162.44062) (xy 420.189967 -162.436614)
			(xy 420.161038 -162.435695) (xy 420.133019 -162.442952) (xy 420.108173 -162.457799) (xy 420.088508 -162.479036)
			(xy 420.075613 -162.504949) (xy 420.072566 -162.519106) (xy 420.06599 -162.551947) (xy 420.042863 -162.614798)
			(xy 420.026592 -162.644074) (xy 420.019587 -162.657057) (xy 420.012541 -162.685688) (xy 420.013975 -162.715137)
			(xy 420.023771 -162.742948) (xy 420.04111 -162.766795) (xy 420.064544 -162.78469) (xy 420.078154 -162.790378)
			(xy 420.104942 -162.801047) (xy 420.155182 -162.829341) (xy 420.20059 -162.864876) (xy 420.240131 -162.906842)
			(xy 420.272903 -162.954283) (xy 420.298159 -163.006117) (xy 420.315323 -163.061162) (xy 420.324005 -163.118164)
			(xy 420.324534 -163.146994) (xy 420.324113 -163.170616) (xy 425.480988 -163.170616) (xy 425.48147 -163.143364)
			(xy 425.489225 -163.089414) (xy 425.504579 -163.037116) (xy 425.527219 -162.987537) (xy 425.556685 -162.941684)
			(xy 425.592377 -162.900491) (xy 425.633568 -162.864797) (xy 425.679419 -162.835329) (xy 425.728998 -162.812686)
			(xy 425.781294 -162.797329) (xy 425.835244 -162.789572) (xy 425.862496 -162.789108) (xy 425.890642 -162.789598)
			(xy 425.946324 -162.797875) (xy 426.000186 -162.814237) (xy 426.051064 -162.838327) (xy 426.097854 -162.869626)
			(xy 426.119036 -162.888168) (xy 426.130841 -162.8982) (xy 426.15893 -162.911235) (xy 426.189633 -162.915257)
			(xy 426.220131 -162.909897) (xy 426.247624 -162.895647) (xy 426.25899 -162.88512) (xy 426.280551 -162.864437)
			(xy 426.328964 -162.829427) (xy 426.382244 -162.802395) (xy 426.439087 -162.784001) (xy 426.498103 -162.774696)
			(xy 426.527976 -162.774122) (xy 426.556122 -162.77462) (xy 426.611803 -162.782895) (xy 426.665666 -162.799254)
			(xy 426.716544 -162.823343) (xy 426.763334 -162.85464) (xy 426.784516 -162.873182) (xy 426.796337 -162.883193)
			(xy 426.82442 -162.896228) (xy 426.855118 -162.900253) (xy 426.885612 -162.894899) (xy 426.913103 -162.880657)
			(xy 426.92447 -162.870134) (xy 426.946042 -162.849463) (xy 426.994452 -162.814451) (xy 427.047729 -162.787416)
			(xy 427.10457 -162.76902) (xy 427.163584 -162.759712) (xy 427.193456 -162.759136) (xy 427.22071 -162.759596)
			(xy 427.274663 -162.767348) (xy 427.326964 -162.782701) (xy 427.376547 -162.805342) (xy 427.422402 -162.834809)
			(xy 427.463596 -162.870504) (xy 427.499291 -162.911698) (xy 427.528758 -162.957553) (xy 427.551399 -163.007136)
			(xy 427.566752 -163.059437) (xy 427.574504 -163.11339) (xy 427.574964 -163.140644) (xy 427.57445 -163.169383)
			(xy 427.565822 -163.22621) (xy 427.548769 -163.2811) (xy 427.523676 -163.332812) (xy 427.49111 -163.380175)
			(xy 427.47184 -163.401502) (xy 427.461724 -163.413001) (xy 427.448385 -163.44056) (xy 427.443809 -163.470832)
			(xy 427.448405 -163.501102) (xy 427.461761 -163.528652) (xy 427.47184 -163.540186) (xy 427.491156 -163.561474)
			(xy 427.523723 -163.608842) (xy 427.548814 -163.66056) (xy 427.565863 -163.715457) (xy 427.574482 -163.77229)
			(xy 427.574477 -163.829774) (xy 427.565849 -163.886606) (xy 427.548791 -163.9415) (xy 427.52369 -163.993213)
			(xy 427.491116 -164.040576) (xy 427.47184 -164.061902) (xy 427.461724 -164.073401) (xy 427.448385 -164.10096)
			(xy 427.443809 -164.131232) (xy 427.448405 -164.161502) (xy 427.461761 -164.189052) (xy 427.47184 -164.200586)
			(xy 427.491156 -164.221874) (xy 427.523723 -164.269242) (xy 427.548814 -164.32096) (xy 427.565863 -164.375857)
			(xy 427.574482 -164.43269) (xy 427.574477 -164.490174) (xy 427.565849 -164.547006) (xy 427.548791 -164.6019)
			(xy 427.52369 -164.653613) (xy 427.491116 -164.700976) (xy 427.47184 -164.722302) (xy 427.461724 -164.733801)
			(xy 427.448385 -164.76136) (xy 427.443809 -164.791632) (xy 427.448405 -164.821902) (xy 427.461761 -164.849452)
			(xy 427.47184 -164.860986) (xy 427.491156 -164.882274) (xy 427.523723 -164.929642) (xy 427.548814 -164.98136)
			(xy 427.565863 -165.036257) (xy 427.574482 -165.09309) (xy 427.574477 -165.150574) (xy 427.565849 -165.207406)
			(xy 427.548791 -165.2623) (xy 427.52369 -165.314013) (xy 427.491116 -165.361376) (xy 427.47184 -165.382702)
			(xy 427.461724 -165.394201) (xy 427.448385 -165.42176) (xy 427.443809 -165.452032) (xy 427.448405 -165.482302)
			(xy 427.461761 -165.509852) (xy 427.47184 -165.521386) (xy 427.491156 -165.542674) (xy 427.523723 -165.590042)
			(xy 427.548814 -165.64176) (xy 427.565863 -165.696657) (xy 427.574482 -165.75349) (xy 427.574477 -165.810974)
			(xy 427.565849 -165.867806) (xy 427.548791 -165.9227) (xy 427.52369 -165.974413) (xy 427.491116 -166.021776)
			(xy 427.47184 -166.043102) (xy 427.461724 -166.054601) (xy 427.448385 -166.08216) (xy 427.443809 -166.112432)
			(xy 427.448405 -166.142702) (xy 427.461761 -166.170252) (xy 427.47184 -166.181786) (xy 427.491128 -166.203098)
			(xy 427.523693 -166.250464) (xy 427.548782 -166.302179) (xy 427.565829 -166.357073) (xy 427.574446 -166.413904)
			(xy 427.57457 -166.4208) (xy 430.96942 -166.4208) (xy 430.969965 -166.392062) (xy 430.978586 -166.335237)
			(xy 430.995632 -166.280347) (xy 431.020718 -166.228635) (xy 431.053277 -166.181271) (xy 431.072544 -166.159942)
			(xy 431.082618 -166.148409) (xy 431.095963 -166.120863) (xy 431.100549 -166.0906) (xy 431.095963 -166.060337)
			(xy 431.082618 -166.032791) (xy 431.072544 -166.021258) (xy 431.053272 -165.999932) (xy 431.020705 -165.95257)
			(xy 430.995612 -165.900858) (xy 430.978561 -165.845967) (xy 430.969938 -165.789139) (xy 430.969938 -165.731661)
			(xy 430.978561 -165.674833) (xy 430.995612 -165.619942) (xy 431.020705 -165.56823) (xy 431.053272 -165.520868)
			(xy 431.072544 -165.499542) (xy 431.082618 -165.488009) (xy 431.095963 -165.460463) (xy 431.100549 -165.4302)
			(xy 431.095963 -165.399937) (xy 431.082618 -165.372391) (xy 431.072544 -165.360858) (xy 431.053272 -165.339532)
			(xy 431.020705 -165.29217) (xy 430.995612 -165.240458) (xy 430.978561 -165.185567) (xy 430.969938 -165.128739)
			(xy 430.969938 -165.071261) (xy 430.978561 -165.014433) (xy 430.995612 -164.959542) (xy 431.020705 -164.90783)
			(xy 431.053272 -164.860468) (xy 431.072544 -164.839142) (xy 431.082618 -164.827609) (xy 431.095963 -164.800063)
			(xy 431.100549 -164.7698) (xy 431.095963 -164.739537) (xy 431.082618 -164.711991) (xy 431.072544 -164.700458)
			(xy 431.053272 -164.679132) (xy 431.020705 -164.63177) (xy 430.995612 -164.580058) (xy 430.978561 -164.525167)
			(xy 430.969938 -164.468339) (xy 430.969938 -164.410861) (xy 430.978561 -164.354033) (xy 430.995612 -164.299142)
			(xy 431.020705 -164.24743) (xy 431.053272 -164.200068) (xy 431.072544 -164.178742) (xy 431.082618 -164.167209)
			(xy 431.095963 -164.139663) (xy 431.100549 -164.1094) (xy 431.095963 -164.079137) (xy 431.082618 -164.051591)
			(xy 431.072544 -164.040058) (xy 431.053274 -164.01873) (xy 431.020708 -163.971368) (xy 430.995615 -163.919657)
			(xy 430.978564 -163.864766) (xy 430.969941 -163.807939) (xy 430.96942 -163.7792) (xy 430.96983 -163.753378)
			(xy 430.976782 -163.702204) (xy 430.990572 -163.652435) (xy 431.010949 -163.604981) (xy 431.037539 -163.560709)
			(xy 431.069858 -163.520427) (xy 431.088292 -163.50234) (xy 431.09798 -163.492559) (xy 431.112152 -163.468967)
			(xy 431.119503 -163.442447) (xy 431.1195 -163.414926) (xy 431.112141 -163.388407) (xy 431.097962 -163.36482)
			(xy 431.088292 -163.35502) (xy 431.069869 -163.336925) (xy 431.037565 -163.296636) (xy 431.010985 -163.252362)
			(xy 430.990611 -163.204911) (xy 430.976815 -163.155148) (xy 430.96985 -163.10398) (xy 430.96942 -163.07816)
			(xy 430.969941 -163.049421) (xy 430.978567 -162.992595) (xy 430.995619 -162.937705) (xy 431.020711 -162.885993)
			(xy 431.053274 -162.83863) (xy 431.072544 -162.817302) (xy 431.082657 -162.8058) (xy 431.095999 -162.778243)
			(xy 431.100577 -162.747971) (xy 431.095981 -162.717701) (xy 431.082624 -162.690151) (xy 431.072544 -162.678618)
			(xy 431.053255 -162.657306) (xy 431.020691 -162.60994) (xy 430.995602 -162.558225) (xy 430.978556 -162.503331)
			(xy 430.969938 -162.4465) (xy 430.96942 -162.41776) (xy 430.969841 -162.390506) (xy 430.977603 -162.336555)
			(xy 430.992965 -162.284257) (xy 431.015613 -162.234678) (xy 431.045086 -162.188827) (xy 431.080784 -162.147636)
			(xy 431.121981 -162.111945) (xy 431.167838 -162.08248) (xy 431.217421 -162.059841) (xy 431.269722 -162.044489)
			(xy 431.323674 -162.036736) (xy 431.350928 -162.036252) (xy 431.379073 -162.036771) (xy 431.434754 -162.04504)
			(xy 431.488617 -162.061394) (xy 431.539495 -162.085478) (xy 431.586286 -162.116772) (xy 431.607468 -162.135312)
			(xy 431.619251 -162.145371) (xy 431.647348 -162.158396) (xy 431.678057 -162.16241) (xy 431.708558 -162.157044)
			(xy 431.736054 -162.142792) (xy 431.747422 -162.132264) (xy 431.76902 -162.111621) (xy 431.817422 -162.076604)
			(xy 431.870692 -162.049563) (xy 431.927528 -162.031161) (xy 431.986538 -162.021846) (xy 432.016408 -162.021266)
			(xy 432.045147 -162.021794) (xy 432.101973 -162.030417) (xy 432.156864 -162.047466) (xy 432.208576 -162.072557)
			(xy 432.255939 -162.10512) (xy 432.277266 -162.12439) (xy 432.2888 -162.134462) (xy 432.316346 -162.147804)
			(xy 432.346608 -162.152389) (xy 432.37687 -162.147804) (xy 432.404416 -162.134462) (xy 432.41595 -162.12439)
			(xy 432.437282 -162.105124) (xy 432.484642 -162.072556) (xy 432.536352 -162.047461) (xy 432.591242 -162.03041)
			(xy 432.648069 -162.021787) (xy 432.676808 -162.021266) (xy 432.704058 -162.02177) (xy 432.758004 -162.029527)
			(xy 432.810297 -162.044882) (xy 432.859872 -162.067522) (xy 432.905721 -162.096987) (xy 432.946911 -162.132676)
			(xy 432.982602 -162.173864) (xy 433.012069 -162.219712) (xy 433.034712 -162.269286) (xy 433.050069 -162.321578)
			(xy 433.057828 -162.375524) (xy 433.058316 -162.402774) (xy 433.057772 -162.431512) (xy 433.049154 -162.488338)
			(xy 433.032108 -162.543229) (xy 433.007021 -162.594941) (xy 432.974461 -162.642304) (xy 432.955192 -162.663632)
			(xy 432.945149 -162.675188) (xy 432.931809 -162.702727) (xy 432.927221 -162.732981) (xy 432.931798 -162.763237)
			(xy 432.945127 -162.790781) (xy 432.955192 -162.802316) (xy 432.974455 -162.823649) (xy 433.007022 -162.87101)
			(xy 433.032115 -162.92272) (xy 433.049167 -162.977609) (xy 433.057793 -163.034436) (xy 433.058316 -163.063174)
			(xy 433.057878 -163.088995) (xy 433.05093 -163.140167) (xy 433.037145 -163.189935) (xy 433.016773 -163.237389)
			(xy 432.990188 -163.281662) (xy 432.957875 -163.321945) (xy 432.939444 -163.340034) (xy 432.92978 -163.349838)
			(xy 432.915601 -163.373422) (xy 432.908243 -163.399937) (xy 432.908242 -163.427455) (xy 432.915598 -163.453971)
			(xy 432.929774 -163.477556) (xy 432.939444 -163.487354) (xy 432.957891 -163.505427) (xy 432.990194 -163.545719)
			(xy 433.016773 -163.589997) (xy 433.037143 -163.637453) (xy 433.050933 -163.68722) (xy 433.05789 -163.738393)
			(xy 433.058316 -163.764214) (xy 433.057796 -163.792953) (xy 433.049172 -163.84978) (xy 433.032121 -163.904671)
			(xy 433.007029 -163.956383) (xy 432.974463 -164.003745) (xy 432.955192 -164.025072) (xy 432.94511 -164.036597)
			(xy 432.931774 -164.064147) (xy 432.927194 -164.09441) (xy 432.93178 -164.124673) (xy 432.945121 -164.15222)
			(xy 432.955192 -164.163756) (xy 432.974476 -164.185071) (xy 433.007039 -164.232436) (xy 433.032129 -164.28415)
			(xy 433.049177 -164.339042) (xy 433.057798 -164.395871) (xy 433.057797 -164.45335) (xy 433.049173 -164.510178)
			(xy 433.032122 -164.565069) (xy 433.007029 -164.616782) (xy 432.974463 -164.664145) (xy 432.955192 -164.685472)
			(xy 432.94511 -164.696997) (xy 432.931774 -164.724547) (xy 432.927194 -164.75481) (xy 432.93178 -164.785073)
			(xy 432.945121 -164.81262) (xy 432.955192 -164.824156) (xy 432.974476 -164.845471) (xy 433.007039 -164.892836)
			(xy 433.032129 -164.94455) (xy 433.049177 -164.999442) (xy 433.057798 -165.056271) (xy 433.057797 -165.11375)
			(xy 433.049173 -165.170578) (xy 433.032122 -165.225469) (xy 433.007029 -165.277182) (xy 432.974463 -165.324545)
			(xy 432.955192 -165.345872) (xy 432.94511 -165.357397) (xy 432.931774 -165.384947) (xy 432.927194 -165.41521)
			(xy 432.93178 -165.445473) (xy 432.945121 -165.47302) (xy 432.955192 -165.484556) (xy 432.974474 -165.505873)
			(xy 433.007038 -165.553238) (xy 433.032128 -165.604952) (xy 433.049176 -165.659845) (xy 433.057796 -165.716674)
			(xy 433.058316 -165.745414) (xy 433.057835 -165.772665) (xy 433.050077 -165.826613) (xy 433.034721 -165.878907)
			(xy 433.012078 -165.928484) (xy 432.982611 -165.974334) (xy 432.946919 -166.015524) (xy 432.905729 -166.051215)
			(xy 432.859879 -166.080681) (xy 432.810301 -166.103323) (xy 432.758007 -166.118678) (xy 432.704059 -166.126436)
			(xy 432.676808 -166.126922) (xy 432.649163 -166.126403) (xy 432.594453 -166.118406) (xy 432.541471 -166.102593)
			(xy 432.491328 -166.079296) (xy 432.445074 -166.049002) (xy 432.40368 -166.012347) (xy 432.38547 -165.99154)
			(xy 432.377861 -165.983437) (xy 432.35771 -165.974116) (xy 432.335506 -165.974116) (xy 432.315355 -165.983437)
			(xy 432.307746 -165.99154) (xy 432.294792 -166.006272) (xy 432.28471 -166.017797) (xy 432.271374 -166.045347)
			(xy 432.266794 -166.07561) (xy 432.27138 -166.105873) (xy 432.284721 -166.13342) (xy 432.294792 -166.144956)
			(xy 432.314074 -166.166273) (xy 432.346638 -166.213638) (xy 432.371728 -166.265352) (xy 432.388776 -166.320245)
			(xy 432.397396 -166.377074) (xy 432.397916 -166.405814) (xy 432.397371 -166.4341) (xy 432.389016 -166.490053)
			(xy 432.372492 -166.544159) (xy 432.34816 -166.595232) (xy 432.316555 -166.642153) (xy 432.29784 -166.66337)
			(xy 432.28775 -166.675307) (xy 432.274637 -166.703659) (xy 432.270696 -166.734646) (xy 432.276295 -166.765378)
			(xy 432.290912 -166.792984) (xy 432.30165 -166.80434) (xy 432.322827 -166.826023) (xy 432.358792 -166.874803)
			(xy 432.386591 -166.928657) (xy 432.405522 -166.98623) (xy 432.415111 -167.046071) (xy 432.415696 -167.076374)
			(xy 432.41522 -167.103627) (xy 432.407467 -167.157578) (xy 432.392113 -167.209876) (xy 432.369473 -167.259457)
			(xy 432.340007 -167.305311) (xy 432.304314 -167.346504) (xy 432.263122 -167.382198) (xy 432.217269 -167.411666)
			(xy 432.167689 -167.434308) (xy 432.115392 -167.449664) (xy 432.061441 -167.457419) (xy 432.034188 -167.457882)
			(xy 432.006043 -167.457345) (xy 431.950364 -167.449079) (xy 431.896502 -167.432729) (xy 431.845623 -167.408649)
			(xy 431.798831 -167.37736) (xy 431.777648 -167.358822) (xy 431.765855 -167.348775) (xy 431.737762 -167.335744)
			(xy 431.707055 -167.331725) (xy 431.676555 -167.337089) (xy 431.649061 -167.351341) (xy 431.637694 -167.36187)
			(xy 431.616095 -167.382511) (xy 431.567692 -167.417527) (xy 431.514422 -167.444567) (xy 431.457587 -167.462971)
			(xy 431.398578 -167.472287) (xy 431.368708 -167.472868) (xy 431.341454 -167.472437) (xy 431.287499 -167.46468)
			(xy 431.235198 -167.449323) (xy 431.185616 -167.426679) (xy 431.139761 -167.397208) (xy 431.098567 -167.361511)
			(xy 431.062873 -167.320314) (xy 431.033406 -167.274456) (xy 431.010766 -167.224872) (xy 430.995413 -167.172569)
			(xy 430.987661 -167.118615) (xy 430.9872 -167.09136) (xy 430.987726 -167.063073) (xy 430.996085 -167.007119)
			(xy 431.012613 -166.953013) (xy 431.036949 -166.90194) (xy 431.068559 -166.85502) (xy 431.087276 -166.833804)
			(xy 431.09739 -166.821886) (xy 431.110498 -166.793527) (xy 431.114434 -166.762534) (xy 431.108828 -166.7318)
			(xy 431.094206 -166.704191) (xy 431.083466 -166.692834) (xy 431.062279 -166.67116) (xy 431.026315 -166.622378)
			(xy 430.998518 -166.568521) (xy 430.979589 -166.510947) (xy 430.970003 -166.451103) (xy 430.96942 -166.4208)
			(xy 427.57457 -166.4208) (xy 427.574964 -166.442644) (xy 427.574563 -166.469898) (xy 427.566799 -166.523851)
			(xy 427.551436 -166.57615) (xy 427.528787 -166.625731) (xy 427.499312 -166.671583) (xy 427.463612 -166.712774)
			(xy 427.422412 -166.748465) (xy 427.376553 -166.777929) (xy 427.326968 -166.800567) (xy 427.274665 -166.815918)
			(xy 427.22071 -166.823669) (xy 427.193456 -166.824152) (xy 427.16531 -166.823641) (xy 427.10963 -166.815371)
			(xy 427.055766 -166.799015) (xy 427.004888 -166.774928) (xy 426.958098 -166.743633) (xy 426.936916 -166.725092)
			(xy 426.925069 -166.715116) (xy 426.896995 -166.702081) (xy 426.866306 -166.698051) (xy 426.835818 -166.703395)
			(xy 426.80833 -166.717624) (xy 426.796962 -166.72814) (xy 426.775372 -166.748791) (xy 426.726968 -166.783807)
			(xy 426.673695 -166.810846) (xy 426.616858 -166.829247) (xy 426.557847 -166.838559) (xy 426.527976 -166.839138)
			(xy 426.499237 -166.838619) (xy 426.44241 -166.829993) (xy 426.38752 -166.812942) (xy 426.335808 -166.78785)
			(xy 426.288445 -166.755284) (xy 426.267118 -166.736014) (xy 426.255584 -166.725942) (xy 426.228038 -166.7126)
			(xy 426.197776 -166.708015) (xy 426.167514 -166.7126) (xy 426.139968 -166.725942) (xy 426.128434 -166.736014)
			(xy 426.10711 -166.755288) (xy 426.059748 -166.787856) (xy 426.008036 -166.812948) (xy 425.953144 -166.829998)
			(xy 425.896315 -166.838619) (xy 425.867576 -166.839138) (xy 425.840326 -166.838645) (xy 425.78638 -166.830886)
			(xy 425.734087 -166.815529) (xy 425.684512 -166.792887) (xy 425.638663 -166.763421) (xy 425.597474 -166.727731)
			(xy 425.561782 -166.686542) (xy 425.532316 -166.640694) (xy 425.509673 -166.591119) (xy 425.494316 -166.538826)
			(xy 425.486556 -166.48488) (xy 425.486068 -166.45763) (xy 425.486619 -166.428892) (xy 425.495236 -166.372066)
			(xy 425.51228 -166.317176) (xy 425.537366 -166.265464) (xy 425.569924 -166.2181) (xy 425.589192 -166.196772)
			(xy 425.599232 -166.185214) (xy 425.612575 -166.157676) (xy 425.617164 -166.127422) (xy 425.612588 -166.097166)
			(xy 425.599257 -166.069623) (xy 425.589192 -166.058088) (xy 425.569952 -166.036735) (xy 425.537389 -165.989376)
			(xy 425.512298 -165.937668) (xy 425.495247 -165.882782) (xy 425.486622 -165.825959) (xy 425.486619 -165.768485)
			(xy 425.495237 -165.711661) (xy 425.512282 -165.656773) (xy 425.537367 -165.605062) (xy 425.569925 -165.557699)
			(xy 425.589192 -165.536372) (xy 425.599232 -165.524814) (xy 425.612575 -165.497276) (xy 425.617164 -165.467022)
			(xy 425.612588 -165.436766) (xy 425.599257 -165.409223) (xy 425.589192 -165.397688) (xy 425.569952 -165.376335)
			(xy 425.537389 -165.328976) (xy 425.512298 -165.277268) (xy 425.495247 -165.222382) (xy 425.486622 -165.165559)
			(xy 425.486619 -165.108085) (xy 425.495237 -165.051261) (xy 425.512282 -164.996373) (xy 425.537367 -164.944662)
			(xy 425.569925 -164.897299) (xy 425.589192 -164.875972) (xy 425.599232 -164.864414) (xy 425.612575 -164.836876)
			(xy 425.617164 -164.806622) (xy 425.612588 -164.776366) (xy 425.599257 -164.748823) (xy 425.589192 -164.737288)
			(xy 425.569952 -164.715935) (xy 425.537389 -164.668576) (xy 425.512298 -164.616868) (xy 425.495247 -164.561982)
			(xy 425.486622 -164.505159) (xy 425.486619 -164.447685) (xy 425.495237 -164.390861) (xy 425.512282 -164.335973)
			(xy 425.537367 -164.284262) (xy 425.569925 -164.236899) (xy 425.589192 -164.215572) (xy 425.599232 -164.204014)
			(xy 425.612575 -164.176476) (xy 425.617164 -164.146222) (xy 425.612588 -164.115966) (xy 425.599257 -164.088423)
			(xy 425.589192 -164.076888) (xy 425.569945 -164.05554) (xy 425.537373 -164.008185) (xy 425.512276 -163.956479)
			(xy 425.49522 -163.901592) (xy 425.486592 -163.844768) (xy 425.486068 -163.81603) (xy 425.486539 -163.788401)
			(xy 425.494478 -163.733716) (xy 425.510222 -163.680748) (xy 425.533443 -163.630605) (xy 425.563654 -163.584337)
			(xy 425.581572 -163.5633) (xy 425.590996 -163.551771) (xy 425.603448 -163.524742) (xy 425.607576 -163.495271)
			(xy 425.603028 -163.465862) (xy 425.590191 -163.439014) (xy 425.580556 -163.427664) (xy 425.561911 -163.406478)
			(xy 425.530459 -163.35962) (xy 425.506249 -163.308641) (xy 425.489809 -163.254654) (xy 425.481497 -163.198834)
			(xy 425.480988 -163.170616) (xy 420.324113 -163.170616) (xy 420.324048 -163.174245) (xy 420.316292 -163.228193)
			(xy 420.300937 -163.280488) (xy 420.278295 -163.330065) (xy 420.248829 -163.375915) (xy 420.213138 -163.417106)
			(xy 420.171947 -163.452797) (xy 420.126097 -163.482263) (xy 420.07652 -163.504905) (xy 420.024225 -163.52026)
			(xy 419.970277 -163.528016) (xy 419.915775 -163.528016) (xy 419.861827 -163.52026) (xy 419.809532 -163.504905)
			(xy 419.759955 -163.482263) (xy 419.714105 -163.452797) (xy 419.672914 -163.417106) (xy 419.637223 -163.375915)
			(xy 419.607757 -163.330065) (xy 419.585115 -163.280488) (xy 419.56976 -163.228193) (xy 419.562004 -163.174245)
			(xy 419.561518 -163.146994) (xy 419.56191 -163.121758) (xy 419.568529 -163.071724) (xy 419.581704 -163.023004)
			(xy 419.601202 -162.976452) (xy 419.613588 -162.954462) (xy 419.620627 -162.941499) (xy 419.627653 -162.912862)
			(xy 419.626205 -162.883412) (xy 419.616403 -162.855603) (xy 419.599064 -162.831754) (xy 419.575634 -162.813852)
			(xy 419.562026 -162.808158) (xy 419.535269 -162.797416) (xy 419.485027 -162.769136) (xy 419.439617 -162.733613)
			(xy 419.400072 -162.691658) (xy 419.367296 -162.644228) (xy 419.342035 -162.592402) (xy 419.324865 -162.537365)
			(xy 419.316178 -162.480369) (xy 419.315646 -162.451542) (xy 410.41574 -162.451542) (xy 410.41574 -164.19025)
			(xy 419.374572 -164.19025) (xy 419.374572 -164.13575) (xy 419.382328 -164.081803) (xy 419.397682 -164.02951)
			(xy 419.420321 -163.979933) (xy 419.449786 -163.934084) (xy 419.485475 -163.892893) (xy 419.526663 -163.857201)
			(xy 419.572511 -163.827734) (xy 419.622085 -163.805091) (xy 419.674378 -163.789733) (xy 419.728324 -163.781974)
			(xy 419.755574 -163.781486) (xy 419.785261 -163.782065) (xy 419.843919 -163.79126) (xy 419.900444 -163.809431)
			(xy 419.953471 -163.836139) (xy 420.001721 -163.870741) (xy 420.044027 -163.912399) (xy 420.062152 -163.935918)
			(xy 420.070578 -163.946525) (xy 420.091891 -163.963232) (xy 420.116845 -163.973751) (xy 420.143686 -163.977341)
			(xy 420.170527 -163.973751) (xy 420.195481 -163.963232) (xy 420.216794 -163.946525) (xy 420.22522 -163.935918)
			(xy 420.243349 -163.912402) (xy 420.285654 -163.870741) (xy 420.333902 -163.836136) (xy 420.386928 -163.809424)
			(xy 420.443453 -163.79125) (xy 420.502111 -163.782051) (xy 420.531798 -163.781486) (xy 420.559051 -163.781961)
			(xy 420.613001 -163.789718) (xy 420.665298 -163.805073) (xy 420.714878 -163.827715) (xy 420.76073 -163.857183)
			(xy 420.801923 -163.892876) (xy 420.837616 -163.934068) (xy 420.867084 -163.979921) (xy 420.889726 -164.0295)
			(xy 420.905082 -164.081797) (xy 420.912839 -164.135747) (xy 420.912839 -164.190253) (xy 420.905082 -164.244203)
			(xy 420.889726 -164.2965) (xy 420.867084 -164.346079) (xy 420.837616 -164.391932) (xy 420.801923 -164.433124)
			(xy 420.76073 -164.468817) (xy 420.714878 -164.498285) (xy 420.665298 -164.520927) (xy 420.613001 -164.536282)
			(xy 420.559051 -164.544039) (xy 420.531798 -164.544502) (xy 420.50211 -164.543948) (xy 420.443451 -164.534749)
			(xy 420.386925 -164.516573) (xy 420.333898 -164.48986) (xy 420.285649 -164.455254) (xy 420.243344 -164.413591)
			(xy 420.22522 -164.39007) (xy 420.216794 -164.379463) (xy 420.195481 -164.362756) (xy 420.170527 -164.352237)
			(xy 420.143686 -164.348647) (xy 420.116845 -164.352237) (xy 420.091891 -164.362756) (xy 420.070578 -164.379463)
			(xy 420.062152 -164.39007) (xy 420.044036 -164.413597) (xy 420.001729 -164.455258) (xy 419.953478 -164.489861)
			(xy 419.900449 -164.516572) (xy 419.843922 -164.534744) (xy 419.785262 -164.543939) (xy 419.755574 -164.544502)
			(xy 419.728324 -164.544026) (xy 419.674378 -164.536267) (xy 419.622085 -164.520909) (xy 419.572511 -164.498266)
			(xy 419.526663 -164.468799) (xy 419.485475 -164.433107) (xy 419.449786 -164.391916) (xy 419.420321 -164.346067)
			(xy 419.397682 -164.29649) (xy 419.382328 -164.244197) (xy 419.374572 -164.19025) (xy 410.41574 -164.19025)
			(xy 410.41574 -164.7698) (xy 410.452824 -164.780214) (xy 410.478928 -164.788017) (xy 410.528576 -164.810447)
			(xy 410.574231 -164.840175) (xy 410.614826 -164.876509) (xy 410.649416 -164.9186) (xy 410.663258 -164.941953)
			(xy 418.557175 -164.941953) (xy 418.564931 -164.888006) (xy 418.580286 -164.835711) (xy 418.602926 -164.786133)
			(xy 418.632392 -164.740282) (xy 418.668083 -164.699091) (xy 418.709272 -164.663399) (xy 418.755122 -164.633932)
			(xy 418.804699 -164.61129) (xy 418.856994 -164.595934) (xy 418.910941 -164.588176) (xy 418.965444 -164.588175)
			(xy 419.019392 -164.595931) (xy 419.071687 -164.611285) (xy 419.121265 -164.633925) (xy 419.167116 -164.66339)
			(xy 419.208307 -164.699081) (xy 419.243999 -164.74027) (xy 419.273467 -164.78612) (xy 419.296109 -164.835697)
			(xy 419.311466 -164.887991) (xy 419.319224 -164.941939) (xy 419.31971 -164.96919) (xy 419.319282 -164.994581)
			(xy 419.312524 -165.044913) (xy 419.306248 -165.06952) (xy 419.302808 -165.084167) (xy 419.303729 -165.114225)
			(xy 419.31336 -165.142715) (xy 419.330866 -165.167167) (xy 419.354731 -165.185465) (xy 419.38289 -165.196023)
			(xy 419.412902 -165.197929) (xy 419.42766 -165.194996) (xy 419.449255 -165.190239) (xy 419.49318 -165.18514)
			(xy 419.51529 -165.184836) (xy 419.542541 -165.185267) (xy 419.59649 -165.193022) (xy 419.648785 -165.208376)
			(xy 419.698364 -165.231015) (xy 419.744216 -165.26048) (xy 419.785408 -165.29617) (xy 419.821101 -165.337359)
			(xy 419.85057 -165.383209) (xy 419.873213 -165.432785) (xy 419.888571 -165.48508) (xy 419.896331 -165.539027)
			(xy 419.896334 -165.59353) (xy 419.88858 -165.647479) (xy 419.873228 -165.699775) (xy 419.85059 -165.749354)
			(xy 419.821127 -165.795207) (xy 419.785438 -165.8364) (xy 419.74425 -165.872094) (xy 419.698401 -165.901564)
			(xy 419.648825 -165.924209) (xy 419.596532 -165.939569) (xy 419.542584 -165.94733) (xy 419.488081 -165.947335)
			(xy 419.434132 -165.939583) (xy 419.381836 -165.924232) (xy 419.332256 -165.901596) (xy 419.286403 -165.872134)
			(xy 419.245208 -165.836446) (xy 419.209512 -165.795259) (xy 419.180041 -165.749411) (xy 419.157395 -165.699836)
			(xy 419.142034 -165.647543) (xy 419.134271 -165.593595) (xy 419.133782 -165.566344) (xy 419.134216 -165.540953)
			(xy 419.14097 -165.490622) (xy 419.147244 -165.466014) (xy 419.150657 -165.451361) (xy 419.149744 -165.421304)
			(xy 419.14012 -165.392815) (xy 419.122618 -165.368362) (xy 419.098755 -165.350064) (xy 419.070599 -165.339507)
			(xy 419.040588 -165.337604) (xy 419.025832 -165.340538) (xy 419.004238 -165.345297) (xy 418.960312 -165.350394)
			(xy 418.938202 -165.350698) (xy 418.910951 -165.350224) (xy 418.857003 -165.342468) (xy 418.804708 -165.327113)
			(xy 418.755131 -165.304473) (xy 418.70928 -165.275007) (xy 418.668089 -165.239315) (xy 418.632397 -165.198125)
			(xy 418.602931 -165.152275) (xy 418.580289 -165.102698) (xy 418.564933 -165.050404) (xy 418.557176 -164.996456)
			(xy 418.557175 -164.941953) (xy 410.663258 -164.941953) (xy 410.677194 -164.965466) (xy 410.697511 -165.016016)
			(xy 410.709895 -165.06907) (xy 410.714056 -165.123391) (xy 410.709898 -165.177713) (xy 410.697517 -165.230767)
			(xy 410.677201 -165.281318) (xy 410.649426 -165.328186) (xy 410.614838 -165.370279) (xy 410.574244 -165.406614)
			(xy 410.528591 -165.436345) (xy 410.478944 -165.458777) (xy 410.452824 -165.466522) (xy 410.41574 -165.476936)
			(xy 410.41574 -165.787957) (xy 416.453709 -165.787957) (xy 416.453709 -165.733443) (xy 416.461468 -165.679483)
			(xy 416.476827 -165.627176) (xy 416.499474 -165.577588) (xy 416.528948 -165.531728) (xy 416.56465 -165.49053)
			(xy 416.605851 -165.454832) (xy 416.651713 -165.425361) (xy 416.701302 -165.402717) (xy 416.75361 -165.387362)
			(xy 416.807571 -165.379607) (xy 416.834828 -165.379146) (xy 416.862199 -165.379584) (xy 416.91638 -165.387407)
			(xy 416.968884 -165.402902) (xy 417.01863 -165.42575) (xy 417.064596 -165.455481) (xy 417.085526 -165.473126)
			(xy 417.096854 -165.482362) (xy 417.123411 -165.494538) (xy 417.152328 -165.498711) (xy 417.181245 -165.494538)
			(xy 417.207802 -165.482362) (xy 417.21913 -165.473126) (xy 417.240081 -165.45551) (xy 417.286048 -165.425794)
			(xy 417.335791 -165.402953) (xy 417.388287 -165.387457) (xy 417.44246 -165.379623) (xy 417.469828 -165.379146)
			(xy 417.497075 -165.379726) (xy 417.551013 -165.387485) (xy 417.603298 -165.402841) (xy 417.652865 -165.425481)
			(xy 417.698707 -165.454944) (xy 417.739889 -165.490631) (xy 417.775573 -165.531816) (xy 417.805033 -165.577659)
			(xy 417.827669 -165.627228) (xy 417.843021 -165.679515) (xy 417.850776 -165.733453) (xy 417.850776 -165.787947)
			(xy 417.843021 -165.841885) (xy 417.827669 -165.894172) (xy 417.805033 -165.943741) (xy 417.775573 -165.989584)
			(xy 417.739889 -166.030769) (xy 417.698707 -166.066456) (xy 417.652865 -166.095919) (xy 417.603298 -166.118559)
			(xy 417.551013 -166.133915) (xy 417.497075 -166.141674) (xy 417.469828 -166.142162) (xy 417.442458 -166.141689)
			(xy 417.388279 -166.133874) (xy 417.335775 -166.118387) (xy 417.286028 -166.095547) (xy 417.240062 -166.065823)
			(xy 417.21913 -166.048182) (xy 417.207802 -166.038946) (xy 417.181245 -166.02677) (xy 417.152328 -166.022597)
			(xy 417.123411 -166.02677) (xy 417.096854 -166.038946) (xy 417.085526 -166.048182) (xy 417.064593 -166.06582)
			(xy 417.01862 -166.095532) (xy 416.968873 -166.118369) (xy 416.916373 -166.13386) (xy 416.862197 -166.141688)
			(xy 416.834828 -166.142162) (xy 416.807571 -166.141793) (xy 416.75361 -166.134038) (xy 416.701302 -166.118683)
			(xy 416.651713 -166.096039) (xy 416.605851 -166.066568) (xy 416.56465 -166.03087) (xy 416.528948 -165.989672)
			(xy 416.499474 -165.943812) (xy 416.476827 -165.894224) (xy 416.461468 -165.841917) (xy 416.453709 -165.787957)
			(xy 410.41574 -165.787957) (xy 410.41574 -166.71798) (xy 410.452824 -166.728394) (xy 410.477484 -166.735725)
			(xy 410.524547 -166.756504) (xy 410.56813 -166.78384) (xy 410.607324 -166.817164) (xy 410.641314 -166.855782)
			(xy 410.669391 -166.89889) (xy 410.690972 -166.945591) (xy 410.705606 -166.994912) (xy 410.71299 -167.045825)
			(xy 410.713428 -167.071548) (xy 410.712852 -167.100576) (xy 410.70343 -167.157861) (xy 410.684844 -167.212861)
			(xy 410.657586 -167.264119) (xy 410.622377 -167.310278) (xy 410.601668 -167.330628) (xy 410.592769 -167.34031)
			(xy 410.579793 -167.363172) (xy 410.573087 -167.38859) (xy 410.573096 -167.414878) (xy 410.579819 -167.440292)
			(xy 410.592811 -167.463145) (xy 410.601668 -167.472868) (xy 410.622395 -167.493202) (xy 410.657613 -167.53936)
			(xy 410.684874 -167.590621) (xy 410.703458 -167.645627) (xy 410.71287 -167.702918) (xy 410.713428 -167.731948)
			(xy 410.713332 -167.744691) (xy 410.711554 -167.770116) (xy 410.709872 -167.782748) (xy 410.705747 -167.808171)
			(xy 410.691131 -167.857556) (xy 410.669555 -167.904321) (xy 410.64147 -167.947491) (xy 410.60746 -167.986168)
			(xy 410.568236 -168.019543) (xy 410.524613 -168.046921) (xy 410.477503 -168.067733) (xy 410.452824 -168.075102)
			(xy 410.41574 -168.085516) (xy 410.41574 -170.156378) (xy 417.4998 -170.156378) (xy 417.500317 -170.129048)
			(xy 417.50828 -170.074971) (xy 417.524061 -170.022638) (xy 417.547322 -169.973175) (xy 417.577563 -169.927642)
			(xy 417.614133 -169.887018) (xy 417.656249 -169.852176) (xy 417.679378 -169.837608) (xy 417.691578 -169.82965)
			(xy 417.711251 -169.808189) (xy 417.724061 -169.782045) (xy 417.728962 -169.753347) (xy 417.725556 -169.724434)
			(xy 417.720272 -169.710862) (xy 417.710777 -169.687654) (xy 417.697428 -169.63932) (xy 417.690702 -169.58963)
			(xy 417.6903 -169.564558) (xy 417.690724 -169.539489) (xy 417.697474 -169.489806) (xy 417.710806 -169.441471)
			(xy 417.720272 -169.418254) (xy 417.725563 -169.404687) (xy 417.728937 -169.375773) (xy 417.724027 -169.347079)
			(xy 417.711231 -169.32093) (xy 417.691587 -169.299447) (xy 417.679378 -169.291508) (xy 417.656281 -169.276887)
			(xy 417.61416 -169.24205) (xy 417.57758 -169.201433) (xy 417.547327 -169.155907) (xy 417.52405 -169.106451)
			(xy 417.508247 -169.054124) (xy 417.500259 -169.00005) (xy 417.500256 -168.945389) (xy 417.508238 -168.891314)
			(xy 417.524036 -168.838986) (xy 417.547308 -168.789527) (xy 417.577556 -168.743998) (xy 417.614131 -168.703377)
			(xy 417.656249 -168.668536) (xy 417.679378 -168.653968) (xy 417.691605 -168.646048) (xy 417.711279 -168.624577)
			(xy 417.724084 -168.598423) (xy 417.728979 -168.569716) (xy 417.725563 -168.540796) (xy 417.720272 -168.527222)
			(xy 417.710796 -168.504007) (xy 417.69744 -168.455677) (xy 417.690706 -168.405989) (xy 417.6903 -168.380918)
			(xy 417.690766 -168.354075) (xy 417.698468 -168.300945) (xy 417.713716 -168.24947) (xy 417.736193 -168.200717)
			(xy 417.765435 -168.155694) (xy 417.800836 -168.115334) (xy 417.841662 -168.080472) (xy 417.887069 -168.051831)
			(xy 417.936117 -168.030002) (xy 417.961826 -168.02227) (xy 417.976329 -168.01762) (xy 418.0019 -168.001103)
			(xy 418.021469 -167.977785) (xy 418.033299 -167.949737) (xy 418.03634 -167.919448) (xy 418.030322 -167.889608)
			(xy 418.023548 -167.875966) (xy 418.00892 -167.847818) (xy 417.988191 -167.787868) (xy 417.977691 -167.72531)
			(xy 417.977066 -167.693594) (xy 417.977291 -167.675575) (xy 417.980722 -167.6397) (xy 417.983924 -167.621966)
			(xy 417.986322 -167.606764) (xy 417.982784 -167.576201) (xy 417.97031 -167.548077) (xy 417.95003 -167.524941)
			(xy 417.923782 -167.508889) (xy 417.908994 -167.504618) (xy 417.881967 -167.497164) (xy 417.830242 -167.475542)
			(xy 417.782237 -167.446585) (xy 417.738984 -167.410917) (xy 417.701416 -167.369305) (xy 417.670339 -167.322645)
			(xy 417.646423 -167.27194) (xy 417.630183 -167.218282) (xy 417.621967 -167.162825) (xy 417.621466 -167.134794)
			(xy 417.621972 -167.107544) (xy 417.629729 -167.053598) (xy 417.645083 -167.001305) (xy 417.667723 -166.95173)
			(xy 417.697188 -166.905881) (xy 417.732877 -166.864691) (xy 417.774065 -166.829) (xy 417.819912 -166.799533)
			(xy 417.869487 -166.77689) (xy 417.921779 -166.761533) (xy 417.975724 -166.753774) (xy 418.002974 -166.753286)
			(xy 418.030548 -166.753774) (xy 418.085119 -166.761723) (xy 418.137979 -166.777444) (xy 418.188024 -166.80061)
			(xy 418.234215 -166.830738) (xy 418.275587 -166.867201) (xy 418.293804 -166.887906) (xy 418.303702 -166.898804)
			(xy 418.328352 -166.914879) (xy 418.35656 -166.923263) (xy 418.385988 -166.923263) (xy 418.414196 -166.914879)
			(xy 418.438846 -166.898804) (xy 418.448744 -166.887906) (xy 418.466959 -166.8672) (xy 418.50833 -166.830735)
			(xy 418.55452 -166.800608) (xy 418.604567 -166.777445) (xy 418.657428 -166.761729) (xy 418.712 -166.753789)
			(xy 418.767148 -166.753789) (xy 418.82172 -166.761729) (xy 418.874581 -166.777445) (xy 418.924628 -166.800608)
			(xy 418.970818 -166.830735) (xy 419.012189 -166.8672) (xy 419.030404 -166.887906) (xy 419.040302 -166.898804)
			(xy 419.064952 -166.914879) (xy 419.09316 -166.923263) (xy 419.122588 -166.923263) (xy 419.150796 -166.914879)
			(xy 419.175446 -166.898804) (xy 419.185344 -166.887906) (xy 419.203582 -166.86722) (xy 419.244945 -166.830747)
			(xy 419.291129 -166.800612) (xy 419.341172 -166.777442) (xy 419.39403 -166.76172) (xy 419.448601 -166.753775)
			(xy 419.476174 -166.753286) (xy 419.503426 -166.753779) (xy 419.557375 -166.761533) (xy 419.609672 -166.776885)
			(xy 419.659252 -166.799524) (xy 419.705105 -166.828989) (xy 419.746298 -166.86468) (xy 419.781992 -166.905869)
			(xy 419.81146 -166.95172) (xy 419.834104 -167.001298) (xy 419.84946 -167.053593) (xy 419.857218 -167.107542)
			(xy 419.857682 -167.134794) (xy 419.857167 -167.16265) (xy 419.849043 -167.217766) (xy 419.832998 -167.271117)
			(xy 419.80937 -167.321571) (xy 419.778663 -167.368056) (xy 419.741526 -167.409585) (xy 419.69875 -167.445278)
			(xy 419.651241 -167.474376) (xy 419.600008 -167.496262) (xy 419.573202 -167.503856) (xy 419.559077 -167.508105)
			(xy 419.53393 -167.523501) (xy 419.514215 -167.545425) (xy 419.501566 -167.57206) (xy 419.497034 -167.601195)
			(xy 419.498526 -167.61587) (xy 419.5002 -167.628886) (xy 419.501977 -167.655071) (xy 419.502082 -167.668194)
			(xy 419.501988 -167.682343) (xy 419.499954 -167.710566) (xy 419.498018 -167.724582) (xy 419.496394 -167.737927)
			(xy 419.4995 -167.764623) (xy 419.509476 -167.789579) (xy 419.525629 -167.81106) (xy 419.546835 -167.827572)
			(xy 419.57162 -167.837966) (xy 419.584886 -167.840152) (xy 419.612039 -167.844237) (xy 419.664868 -167.859214)
			(xy 419.715004 -167.881609) (xy 419.761412 -167.910958) (xy 419.803135 -167.946656) (xy 419.839311 -167.987965)
			(xy 419.869192 -168.034033) (xy 419.892162 -168.083908) (xy 419.907746 -168.136561) (xy 419.915622 -168.190903)
			(xy 419.916102 -168.218358) (xy 419.915606 -168.24561) (xy 419.907854 -168.29956) (xy 419.892503 -168.351858)
			(xy 419.869865 -168.401438) (xy 419.840401 -168.447292) (xy 419.804711 -168.488485) (xy 419.763521 -168.524179)
			(xy 419.71767 -168.553648) (xy 419.668092 -168.576291) (xy 419.615795 -168.591647) (xy 419.561846 -168.599403)
			(xy 419.534594 -168.599866) (xy 419.507019 -168.599416) (xy 419.452445 -168.591462) (xy 419.399584 -168.575735)
			(xy 419.349538 -168.552562) (xy 419.303349 -168.522426) (xy 419.261979 -168.485955) (xy 419.243764 -168.465246)
			(xy 419.233866 -168.454348) (xy 419.209216 -168.438273) (xy 419.181008 -168.429889) (xy 419.15158 -168.429889)
			(xy 419.123372 -168.438273) (xy 419.098722 -168.454348) (xy 419.088824 -168.465246) (xy 419.070614 -168.485958)
			(xy 419.029244 -168.522426) (xy 418.983053 -168.552557) (xy 418.933005 -168.575722) (xy 418.880143 -168.591439)
			(xy 418.825569 -168.59938) (xy 418.797994 -168.599866) (xy 418.771493 -168.599405) (xy 418.719002 -168.592063)
			(xy 418.668034 -168.577521) (xy 418.619572 -168.556059) (xy 418.574549 -168.528091) (xy 418.5539 -168.511474)
			(xy 418.541717 -168.502082) (xy 418.51333 -168.490285) (xy 418.482719 -168.487451) (xy 418.452648 -168.493838)
			(xy 418.425831 -168.508868) (xy 418.404689 -168.531186) (xy 418.397436 -168.544748) (xy 418.385321 -168.56843)
			(xy 418.355402 -168.612413) (xy 418.319535 -168.651696) (xy 418.278448 -168.685482) (xy 418.255958 -168.699688)
			(xy 418.243751 -168.707635) (xy 418.224085 -168.729102) (xy 418.211281 -168.755249) (xy 418.206381 -168.783947)
			(xy 418.209783 -168.812861) (xy 418.215064 -168.826434) (xy 418.22456 -168.849641) (xy 418.237908 -168.897976)
			(xy 418.244633 -168.947666) (xy 418.245036 -168.972738) (xy 418.244615 -168.997807) (xy 418.237865 -169.047491)
			(xy 418.224531 -169.095825) (xy 418.215064 -169.119042) (xy 418.209854 -169.132631) (xy 418.206485 -169.161525)
			(xy 418.211389 -169.190198) (xy 418.224168 -169.21633) (xy 418.243789 -169.237805) (xy 418.255958 -169.245788)
			(xy 418.27905 -169.260416) (xy 418.321167 -169.295255) (xy 418.357742 -169.335872) (xy 418.387993 -169.381397)
			(xy 418.411268 -169.430852) (xy 418.427069 -169.483177) (xy 418.435057 -169.537249) (xy 418.43506 -169.591908)
			(xy 418.427078 -169.64598) (xy 418.411283 -169.698307) (xy 418.388014 -169.747765) (xy 418.357769 -169.793294)
			(xy 418.321198 -169.833915) (xy 418.279085 -169.868759) (xy 418.255958 -169.883328) (xy 418.243724 -169.891237)
			(xy 418.224058 -169.912714) (xy 418.211257 -169.938871) (xy 418.208732 -169.953686) (xy 426.587415 -169.953686)
			(xy 426.591451 -169.870239) (xy 426.603523 -169.787571) (xy 426.623516 -169.706454) (xy 426.651245 -169.627645)
			(xy 426.686451 -169.55188) (xy 426.728805 -169.479867) (xy 426.777911 -169.412278) (xy 426.833312 -169.349744)
			(xy 426.894489 -169.292849) (xy 426.960872 -169.242123) (xy 427.03184 -169.198042) (xy 427.106732 -169.161016)
			(xy 427.184848 -169.13139) (xy 427.265458 -169.109442) (xy 427.34781 -169.095377) (xy 427.431136 -169.089325)
			(xy 427.514656 -169.091344) (xy 427.597592 -169.101414) (xy 427.679168 -169.119442) (xy 427.758624 -169.145259)
			(xy 427.835217 -169.178624) (xy 427.908233 -169.219225) (xy 427.976989 -169.266684) (xy 428.040843 -169.320557)
			(xy 428.0992 -169.380342) (xy 428.151515 -169.445479) (xy 428.197298 -169.515362) (xy 428.236123 -169.589337)
			(xy 428.267628 -169.666714) (xy 428.291517 -169.746771) (xy 428.307568 -169.828759) (xy 428.315631 -169.911914)
			(xy 428.316136 -169.953686) (xy 428.315631 -169.995458) (xy 428.307568 -170.078613) (xy 428.291517 -170.160601)
			(xy 428.267628 -170.240658) (xy 428.236123 -170.318035) (xy 428.197298 -170.39201) (xy 428.151515 -170.461893)
			(xy 428.0992 -170.52703) (xy 428.040843 -170.586815) (xy 427.976989 -170.640688) (xy 427.908233 -170.688147)
			(xy 427.835217 -170.728748) (xy 427.758624 -170.762113) (xy 427.679168 -170.78793) (xy 427.597592 -170.805958)
			(xy 427.514656 -170.816028) (xy 427.431136 -170.818047) (xy 427.34781 -170.811995) (xy 427.265458 -170.79793)
			(xy 427.184848 -170.775982) (xy 427.106732 -170.746356) (xy 427.03184 -170.70933) (xy 426.960872 -170.665249)
			(xy 426.894489 -170.614523) (xy 426.833312 -170.557628) (xy 426.777911 -170.495094) (xy 426.728805 -170.427505)
			(xy 426.686451 -170.355492) (xy 426.651245 -170.279727) (xy 426.623516 -170.200918) (xy 426.603523 -170.119801)
			(xy 426.591451 -170.037133) (xy 426.587415 -169.953686) (xy 418.208732 -169.953686) (xy 418.206364 -169.967578)
			(xy 418.209777 -169.996499) (xy 418.215064 -170.010074) (xy 418.224541 -170.033289) (xy 418.237896 -170.081619)
			(xy 418.244629 -170.131307) (xy 418.245036 -170.156378) (xy 418.244515 -170.184263) (xy 418.236203 -170.23941)
			(xy 418.219765 -170.292702) (xy 418.195567 -170.342948) (xy 418.164151 -170.389027) (xy 418.126218 -170.429909)
			(xy 418.082616 -170.464681) (xy 418.034318 -170.492566) (xy 417.982403 -170.512941) (xy 417.928032 -170.525351)
			(xy 417.872418 -170.529519) (xy 417.816804 -170.525351) (xy 417.762433 -170.512941) (xy 417.710518 -170.492566)
			(xy 417.66222 -170.464681) (xy 417.618618 -170.429909) (xy 417.580685 -170.389027) (xy 417.549269 -170.342948)
			(xy 417.525071 -170.292702) (xy 417.508633 -170.23941) (xy 417.500321 -170.184263) (xy 417.4998 -170.156378)
			(xy 410.41574 -170.156378) (xy 410.41574 -171.087542) (xy 419.315646 -171.087542) (xy 419.316217 -171.060294)
			(xy 419.323967 -171.006352) (xy 419.339314 -170.954061) (xy 419.361947 -170.904487) (xy 419.391405 -170.858639)
			(xy 419.427087 -170.81745) (xy 419.468269 -170.781757) (xy 419.51411 -170.752289) (xy 419.563679 -170.729645)
			(xy 419.615966 -170.714285) (xy 419.669906 -170.706523) (xy 419.697154 -170.706034) (xy 419.727059 -170.706571)
			(xy 419.786138 -170.715883) (xy 419.814756 -170.724576) (xy 419.82866 -170.72863) (xy 419.857597 -170.72954)
			(xy 419.885621 -170.722274) (xy 419.910469 -170.707418) (xy 419.930134 -170.686171) (xy 419.943028 -170.660251)
			(xy 419.946074 -170.64609) (xy 419.951204 -170.620008) (xy 419.967775 -170.569501) (xy 419.991201 -170.521784)
			(xy 420.021027 -170.477784) (xy 420.056674 -170.438352) (xy 420.097452 -170.404253) (xy 420.142571 -170.376148)
			(xy 420.191156 -170.354581) (xy 420.242265 -170.339971) (xy 420.294908 -170.332601) (xy 420.321486 -170.332146)
			(xy 420.348736 -170.3327) (xy 420.402682 -170.340455) (xy 420.454975 -170.355808) (xy 420.504551 -170.378447)
			(xy 420.550401 -170.407911) (xy 420.59159 -170.4436) (xy 420.627281 -170.484788) (xy 420.656747 -170.530636)
			(xy 420.679387 -170.580211) (xy 420.694742 -170.632504) (xy 420.702499 -170.68645) (xy 420.702499 -170.74095)
			(xy 420.694742 -170.794896) (xy 420.679387 -170.847189) (xy 420.656747 -170.896764) (xy 420.627281 -170.942612)
			(xy 420.59159 -170.9838) (xy 420.550401 -171.019489) (xy 420.504551 -171.048953) (xy 420.454975 -171.071592)
			(xy 420.402682 -171.086945) (xy 420.348736 -171.0947) (xy 420.321486 -171.095162) (xy 420.291581 -171.094639)
			(xy 420.232502 -171.085318) (xy 420.203884 -171.07662) (xy 420.189967 -171.072614) (xy 420.161038 -171.071695)
			(xy 420.133019 -171.078952) (xy 420.108173 -171.093799) (xy 420.088508 -171.115036) (xy 420.075613 -171.140949)
			(xy 420.072566 -171.155106) (xy 420.06599 -171.187947) (xy 420.042863 -171.250798) (xy 420.026592 -171.280074)
			(xy 420.019587 -171.293057) (xy 420.012541 -171.321688) (xy 420.013975 -171.351137) (xy 420.023771 -171.378948)
			(xy 420.04111 -171.402795) (xy 420.064544 -171.42069) (xy 420.078154 -171.426378) (xy 420.104942 -171.437047)
			(xy 420.155182 -171.465341) (xy 420.20059 -171.500876) (xy 420.240131 -171.542842) (xy 420.272903 -171.590283)
			(xy 420.298159 -171.642117) (xy 420.315323 -171.697162) (xy 420.324005 -171.754164) (xy 420.324534 -171.782994)
			(xy 420.324048 -171.810245) (xy 420.316292 -171.864193) (xy 420.300937 -171.916488) (xy 420.278295 -171.966065)
			(xy 420.248829 -172.011915) (xy 420.213138 -172.053106) (xy 420.171947 -172.088797) (xy 420.126097 -172.118263)
			(xy 420.07652 -172.140905) (xy 420.024225 -172.15626) (xy 419.970277 -172.164016) (xy 419.915775 -172.164016)
			(xy 419.861827 -172.15626) (xy 419.809532 -172.140905) (xy 419.759955 -172.118263) (xy 419.714105 -172.088797)
			(xy 419.672914 -172.053106) (xy 419.637223 -172.011915) (xy 419.607757 -171.966065) (xy 419.585115 -171.916488)
			(xy 419.56976 -171.864193) (xy 419.562004 -171.810245) (xy 419.561518 -171.782994) (xy 419.56191 -171.757758)
			(xy 419.568529 -171.707724) (xy 419.581704 -171.659004) (xy 419.601202 -171.612452) (xy 419.613588 -171.590462)
			(xy 419.620627 -171.577499) (xy 419.627653 -171.548862) (xy 419.626205 -171.519412) (xy 419.616403 -171.491603)
			(xy 419.599064 -171.467754) (xy 419.575634 -171.449852) (xy 419.562026 -171.444158) (xy 419.535269 -171.433416)
			(xy 419.485027 -171.405136) (xy 419.439617 -171.369613) (xy 419.400072 -171.327658) (xy 419.367296 -171.280228)
			(xy 419.342035 -171.228402) (xy 419.324865 -171.173365) (xy 419.316178 -171.116369) (xy 419.315646 -171.087542)
			(xy 410.41574 -171.087542) (xy 410.41574 -173.4058) (xy 410.452824 -173.416214) (xy 410.478928 -173.424017)
			(xy 410.528576 -173.446447) (xy 410.574231 -173.476175) (xy 410.614826 -173.512509) (xy 410.649416 -173.5546)
			(xy 410.663258 -173.577953) (xy 418.557175 -173.577953) (xy 418.564931 -173.524006) (xy 418.580286 -173.471711)
			(xy 418.602926 -173.422133) (xy 418.632392 -173.376282) (xy 418.668083 -173.335091) (xy 418.709272 -173.299399)
			(xy 418.755122 -173.269932) (xy 418.804699 -173.24729) (xy 418.856994 -173.231934) (xy 418.910941 -173.224176)
			(xy 418.965444 -173.224175) (xy 419.019392 -173.231931) (xy 419.071687 -173.247285) (xy 419.121265 -173.269925)
			(xy 419.167116 -173.29939) (xy 419.208307 -173.335081) (xy 419.243999 -173.37627) (xy 419.273467 -173.42212)
			(xy 419.296109 -173.471697) (xy 419.311466 -173.523991) (xy 419.319224 -173.577939) (xy 419.31971 -173.60519)
			(xy 419.319282 -173.630581) (xy 419.312524 -173.680913) (xy 419.306248 -173.70552) (xy 419.302808 -173.720167)
			(xy 419.303729 -173.750225) (xy 419.31336 -173.778715) (xy 419.330866 -173.803167) (xy 419.354731 -173.821465)
			(xy 419.38289 -173.832023) (xy 419.412902 -173.833929) (xy 419.42766 -173.830996) (xy 419.449255 -173.826239)
			(xy 419.49318 -173.82114) (xy 419.51529 -173.820836) (xy 419.542541 -173.821267) (xy 419.59649 -173.829022)
			(xy 419.648785 -173.844376) (xy 419.698364 -173.867015) (xy 419.744216 -173.89648) (xy 419.785408 -173.93217)
			(xy 419.821101 -173.973359) (xy 419.85057 -174.019209) (xy 419.873213 -174.068785) (xy 419.888571 -174.12108)
			(xy 419.896331 -174.175027) (xy 419.896334 -174.22953) (xy 419.88858 -174.283479) (xy 419.873228 -174.335775)
			(xy 419.85059 -174.385354) (xy 419.821127 -174.431207) (xy 419.785438 -174.4724) (xy 419.74425 -174.508094)
			(xy 419.698401 -174.537564) (xy 419.648825 -174.560209) (xy 419.596532 -174.575569) (xy 419.542584 -174.58333)
			(xy 419.488081 -174.583335) (xy 419.434132 -174.575583) (xy 419.381836 -174.560232) (xy 419.332256 -174.537596)
			(xy 419.286403 -174.508134) (xy 419.245208 -174.472446) (xy 419.209512 -174.431259) (xy 419.180041 -174.385411)
			(xy 419.157395 -174.335836) (xy 419.142034 -174.283543) (xy 419.134271 -174.229595) (xy 419.133782 -174.202344)
			(xy 419.134216 -174.176953) (xy 419.14097 -174.126622) (xy 419.147244 -174.102014) (xy 419.150657 -174.087361)
			(xy 419.149744 -174.057304) (xy 419.14012 -174.028815) (xy 419.122618 -174.004362) (xy 419.098755 -173.986064)
			(xy 419.070599 -173.975507) (xy 419.040588 -173.973604) (xy 419.025832 -173.976538) (xy 419.004238 -173.981297)
			(xy 418.960312 -173.986394) (xy 418.938202 -173.986698) (xy 418.910951 -173.986224) (xy 418.857003 -173.978468)
			(xy 418.804708 -173.963113) (xy 418.755131 -173.940473) (xy 418.70928 -173.911007) (xy 418.668089 -173.875315)
			(xy 418.632397 -173.834125) (xy 418.602931 -173.788275) (xy 418.580289 -173.738698) (xy 418.564933 -173.686404)
			(xy 418.557176 -173.632456) (xy 418.557175 -173.577953) (xy 410.663258 -173.577953) (xy 410.677194 -173.601466)
			(xy 410.697511 -173.652016) (xy 410.709895 -173.70507) (xy 410.714056 -173.759391) (xy 410.709898 -173.813713)
			(xy 410.697517 -173.866767) (xy 410.677201 -173.917318) (xy 410.649426 -173.964186) (xy 410.614838 -174.006279)
			(xy 410.574244 -174.042614) (xy 410.528591 -174.072345) (xy 410.478944 -174.094777) (xy 410.452824 -174.102522)
			(xy 410.41574 -174.112936) (xy 410.41574 -174.423957) (xy 416.453709 -174.423957) (xy 416.453709 -174.369443)
			(xy 416.461468 -174.315483) (xy 416.476827 -174.263176) (xy 416.499474 -174.213588) (xy 416.528948 -174.167728)
			(xy 416.56465 -174.12653) (xy 416.605851 -174.090832) (xy 416.651713 -174.061361) (xy 416.701302 -174.038717)
			(xy 416.75361 -174.023362) (xy 416.807571 -174.015607) (xy 416.834828 -174.015146) (xy 416.862199 -174.015584)
			(xy 416.91638 -174.023407) (xy 416.968884 -174.038902) (xy 417.01863 -174.06175) (xy 417.064596 -174.091481)
			(xy 417.085526 -174.109126) (xy 417.096854 -174.118362) (xy 417.123411 -174.130538) (xy 417.152328 -174.134711)
			(xy 417.181245 -174.130538) (xy 417.207802 -174.118362) (xy 417.21913 -174.109126) (xy 417.240081 -174.09151)
			(xy 417.286048 -174.061794) (xy 417.335791 -174.038953) (xy 417.388287 -174.023457) (xy 417.44246 -174.015623)
			(xy 417.469828 -174.015146) (xy 417.497075 -174.015726) (xy 417.551013 -174.023485) (xy 417.603298 -174.038841)
			(xy 417.652865 -174.061481) (xy 417.698707 -174.090944) (xy 417.739889 -174.126631) (xy 417.775573 -174.167816)
			(xy 417.805033 -174.213659) (xy 417.827669 -174.263228) (xy 417.843021 -174.315515) (xy 417.850776 -174.369453)
			(xy 417.850776 -174.423947) (xy 417.843021 -174.477885) (xy 417.827669 -174.530172) (xy 417.805033 -174.579741)
			(xy 417.775573 -174.625584) (xy 417.739889 -174.666769) (xy 417.698707 -174.702456) (xy 417.652865 -174.731919)
			(xy 417.603298 -174.754559) (xy 417.551013 -174.769915) (xy 417.497075 -174.777674) (xy 417.469828 -174.778162)
			(xy 417.442458 -174.777689) (xy 417.388279 -174.769874) (xy 417.335775 -174.754387) (xy 417.286028 -174.731547)
			(xy 417.240062 -174.701823) (xy 417.21913 -174.684182) (xy 417.207802 -174.674946) (xy 417.181245 -174.66277)
			(xy 417.152328 -174.658597) (xy 417.123411 -174.66277) (xy 417.096854 -174.674946) (xy 417.085526 -174.684182)
			(xy 417.064593 -174.70182) (xy 417.01862 -174.731532) (xy 416.968873 -174.754369) (xy 416.916373 -174.76986)
			(xy 416.862197 -174.777688) (xy 416.834828 -174.778162) (xy 416.807571 -174.777793) (xy 416.75361 -174.770038)
			(xy 416.701302 -174.754683) (xy 416.651713 -174.732039) (xy 416.605851 -174.702568) (xy 416.56465 -174.66687)
			(xy 416.528948 -174.625672) (xy 416.499474 -174.579812) (xy 416.476827 -174.530224) (xy 416.461468 -174.477917)
			(xy 416.453709 -174.423957) (xy 410.41574 -174.423957) (xy 410.41574 -175.35398) (xy 410.452824 -175.364394)
			(xy 410.477484 -175.371725) (xy 410.524547 -175.392504) (xy 410.56813 -175.41984) (xy 410.607324 -175.453164)
			(xy 410.641314 -175.491782) (xy 410.669391 -175.53489) (xy 410.690972 -175.581591) (xy 410.705606 -175.630912)
			(xy 410.71299 -175.681825) (xy 410.713428 -175.707548) (xy 410.712852 -175.736576) (xy 410.70343 -175.793861)
			(xy 410.684844 -175.848861) (xy 410.657586 -175.900119) (xy 410.622377 -175.946278) (xy 410.601668 -175.966628)
			(xy 410.592769 -175.97631) (xy 410.579793 -175.999172) (xy 410.573087 -176.02459) (xy 410.573096 -176.050878)
			(xy 410.579819 -176.076292) (xy 410.592811 -176.099145) (xy 410.601668 -176.108868) (xy 410.622395 -176.129202)
			(xy 410.657613 -176.17536) (xy 410.684874 -176.226621) (xy 410.703458 -176.281627) (xy 410.71287 -176.338918)
			(xy 410.713428 -176.367948) (xy 410.713332 -176.380691) (xy 410.711554 -176.406116) (xy 410.709872 -176.418748)
			(xy 410.705747 -176.444171) (xy 410.691131 -176.493556) (xy 410.669555 -176.540321) (xy 410.64147 -176.583491)
			(xy 410.60746 -176.622168) (xy 410.568236 -176.655543) (xy 410.524613 -176.682921) (xy 410.477503 -176.703733)
			(xy 410.452824 -176.711102) (xy 410.41574 -176.721516) (xy 410.41574 -178.792378) (xy 417.4998 -178.792378)
			(xy 417.500317 -178.765048) (xy 417.50828 -178.710971) (xy 417.524061 -178.658638) (xy 417.547322 -178.609175)
			(xy 417.577563 -178.563642) (xy 417.614133 -178.523018) (xy 417.656249 -178.488176) (xy 417.679378 -178.473608)
			(xy 417.691578 -178.46565) (xy 417.711251 -178.444189) (xy 417.724061 -178.418045) (xy 417.728962 -178.389347)
			(xy 417.725556 -178.360434) (xy 417.720272 -178.346862) (xy 417.710777 -178.323654) (xy 417.697428 -178.27532)
			(xy 417.690702 -178.22563) (xy 417.6903 -178.200558) (xy 417.690724 -178.175489) (xy 417.697474 -178.125806)
			(xy 417.710806 -178.077471) (xy 417.720272 -178.054254) (xy 417.725563 -178.040687) (xy 417.728937 -178.011773)
			(xy 417.724027 -177.983079) (xy 417.711231 -177.95693) (xy 417.691587 -177.935447) (xy 417.679378 -177.927508)
			(xy 417.656281 -177.912887) (xy 417.61416 -177.87805) (xy 417.57758 -177.837433) (xy 417.547327 -177.791907)
			(xy 417.52405 -177.742451) (xy 417.508247 -177.690124) (xy 417.500259 -177.63605) (xy 417.500256 -177.581389)
			(xy 417.508238 -177.527314) (xy 417.524036 -177.474986) (xy 417.547308 -177.425527) (xy 417.577556 -177.379998)
			(xy 417.614131 -177.339377) (xy 417.656249 -177.304536) (xy 417.679378 -177.289968) (xy 417.691605 -177.282048)
			(xy 417.711279 -177.260577) (xy 417.724084 -177.234423) (xy 417.728979 -177.205716) (xy 417.725563 -177.176796)
			(xy 417.720272 -177.163222) (xy 417.710796 -177.140007) (xy 417.69744 -177.091677) (xy 417.690706 -177.041989)
			(xy 417.6903 -177.016918) (xy 417.690766 -176.990075) (xy 417.698468 -176.936945) (xy 417.713716 -176.88547)
			(xy 417.736193 -176.836717) (xy 417.765435 -176.791694) (xy 417.800836 -176.751334) (xy 417.841662 -176.716472)
			(xy 417.887069 -176.687831) (xy 417.936117 -176.666002) (xy 417.961826 -176.65827) (xy 417.976329 -176.65362)
			(xy 418.0019 -176.637103) (xy 418.021469 -176.613785) (xy 418.033299 -176.585737) (xy 418.03634 -176.555448)
			(xy 418.030322 -176.525608) (xy 418.023548 -176.511966) (xy 418.00892 -176.483818) (xy 417.988191 -176.423868)
			(xy 417.977691 -176.36131) (xy 417.977066 -176.329594) (xy 417.977291 -176.311575) (xy 417.980722 -176.2757)
			(xy 417.983924 -176.257966) (xy 417.986322 -176.242764) (xy 417.982784 -176.212201) (xy 417.97031 -176.184077)
			(xy 417.95003 -176.160941) (xy 417.923782 -176.144889) (xy 417.908994 -176.140618) (xy 417.881967 -176.133164)
			(xy 417.830242 -176.111542) (xy 417.782237 -176.082585) (xy 417.738984 -176.046917) (xy 417.701416 -176.005305)
			(xy 417.670339 -175.958645) (xy 417.646423 -175.90794) (xy 417.630183 -175.854282) (xy 417.621967 -175.798825)
			(xy 417.621466 -175.770794) (xy 417.621972 -175.743544) (xy 417.629729 -175.689598) (xy 417.645083 -175.637305)
			(xy 417.667723 -175.58773) (xy 417.697188 -175.541881) (xy 417.732877 -175.500691) (xy 417.774065 -175.465)
			(xy 417.819912 -175.435533) (xy 417.869487 -175.41289) (xy 417.921779 -175.397533) (xy 417.975724 -175.389774)
			(xy 418.002974 -175.389286) (xy 418.030548 -175.389774) (xy 418.085119 -175.397723) (xy 418.137979 -175.413444)
			(xy 418.188024 -175.43661) (xy 418.234215 -175.466738) (xy 418.275587 -175.503201) (xy 418.293804 -175.523906)
			(xy 418.303702 -175.534804) (xy 418.328352 -175.550879) (xy 418.35656 -175.559263) (xy 418.385988 -175.559263)
			(xy 418.414196 -175.550879) (xy 418.438846 -175.534804) (xy 418.448744 -175.523906) (xy 418.466959 -175.5032)
			(xy 418.50833 -175.466735) (xy 418.55452 -175.436608) (xy 418.604567 -175.413445) (xy 418.657428 -175.397729)
			(xy 418.712 -175.389789) (xy 418.767148 -175.389789) (xy 418.82172 -175.397729) (xy 418.874581 -175.413445)
			(xy 418.924628 -175.436608) (xy 418.970818 -175.466735) (xy 419.012189 -175.5032) (xy 419.030404 -175.523906)
			(xy 419.040302 -175.534804) (xy 419.064952 -175.550879) (xy 419.09316 -175.559263) (xy 419.122588 -175.559263)
			(xy 419.150796 -175.550879) (xy 419.175446 -175.534804) (xy 419.185344 -175.523906) (xy 419.203582 -175.50322)
			(xy 419.244945 -175.466747) (xy 419.291129 -175.436612) (xy 419.341172 -175.413442) (xy 419.39403 -175.39772)
			(xy 419.448601 -175.389775) (xy 419.476174 -175.389286) (xy 419.503426 -175.389779) (xy 419.557375 -175.397533)
			(xy 419.609672 -175.412885) (xy 419.659252 -175.435524) (xy 419.705105 -175.464989) (xy 419.746298 -175.50068)
			(xy 419.781992 -175.541869) (xy 419.81146 -175.58772) (xy 419.834104 -175.637298) (xy 419.84946 -175.689593)
			(xy 419.857218 -175.743542) (xy 419.857682 -175.770794) (xy 419.857167 -175.79865) (xy 419.849043 -175.853766)
			(xy 419.832998 -175.907117) (xy 419.80937 -175.957571) (xy 419.778663 -176.004056) (xy 419.741526 -176.045585)
			(xy 419.69875 -176.081278) (xy 419.651241 -176.110376) (xy 419.600008 -176.132262) (xy 419.573202 -176.139856)
			(xy 419.559077 -176.144105) (xy 419.53393 -176.159501) (xy 419.514215 -176.181425) (xy 419.501566 -176.20806)
			(xy 419.497034 -176.237195) (xy 419.498526 -176.25187) (xy 419.5002 -176.264886) (xy 419.501977 -176.291071)
			(xy 419.502082 -176.304194) (xy 419.501988 -176.318343) (xy 419.499954 -176.346566) (xy 419.498018 -176.360582)
			(xy 419.496394 -176.373927) (xy 419.4995 -176.400623) (xy 419.509476 -176.425579) (xy 419.525629 -176.44706)
			(xy 419.546835 -176.463572) (xy 419.57162 -176.473966) (xy 419.584886 -176.476152) (xy 419.612039 -176.480237)
			(xy 419.664868 -176.495214) (xy 419.715004 -176.517609) (xy 419.761412 -176.546958) (xy 419.803135 -176.582656)
			(xy 419.839311 -176.623965) (xy 419.869192 -176.670033) (xy 419.892162 -176.719908) (xy 419.907746 -176.772561)
			(xy 419.915622 -176.826903) (xy 419.916102 -176.854358) (xy 419.915606 -176.88161) (xy 419.907854 -176.93556)
			(xy 419.892503 -176.987858) (xy 419.869865 -177.037438) (xy 419.840401 -177.083292) (xy 419.804711 -177.124485)
			(xy 419.763521 -177.160179) (xy 419.71767 -177.189648) (xy 419.668092 -177.212291) (xy 419.615795 -177.227647)
			(xy 419.561846 -177.235403) (xy 419.534594 -177.235866) (xy 419.507019 -177.235416) (xy 419.452445 -177.227462)
			(xy 419.399584 -177.211735) (xy 419.349538 -177.188562) (xy 419.303349 -177.158426) (xy 419.261979 -177.121955)
			(xy 419.243764 -177.101246) (xy 419.233866 -177.090348) (xy 419.209216 -177.074273) (xy 419.181008 -177.065889)
			(xy 419.15158 -177.065889) (xy 419.123372 -177.074273) (xy 419.098722 -177.090348) (xy 419.088824 -177.101246)
			(xy 419.070614 -177.121958) (xy 419.029244 -177.158426) (xy 418.983053 -177.188557) (xy 418.933005 -177.211722)
			(xy 418.880143 -177.227439) (xy 418.825569 -177.23538) (xy 418.797994 -177.235866) (xy 418.771493 -177.235405)
			(xy 418.719002 -177.228063) (xy 418.668034 -177.213521) (xy 418.619572 -177.192059) (xy 418.574549 -177.164091)
			(xy 418.5539 -177.147474) (xy 418.541717 -177.138082) (xy 418.51333 -177.126285) (xy 418.482719 -177.123451)
			(xy 418.452648 -177.129838) (xy 418.425831 -177.144868) (xy 418.404689 -177.167186) (xy 418.397436 -177.180748)
			(xy 418.385321 -177.20443) (xy 418.355402 -177.248413) (xy 418.319535 -177.287696) (xy 418.278448 -177.321482)
			(xy 418.255958 -177.335688) (xy 418.243751 -177.343635) (xy 418.224085 -177.365102) (xy 418.211281 -177.391249)
			(xy 418.206381 -177.419947) (xy 418.209783 -177.448861) (xy 418.215064 -177.462434) (xy 418.22456 -177.485641)
			(xy 418.237908 -177.533976) (xy 418.244633 -177.583666) (xy 418.245036 -177.608738) (xy 418.244615 -177.633807)
			(xy 418.237865 -177.683491) (xy 418.224531 -177.731825) (xy 418.215064 -177.755042) (xy 418.209854 -177.768631)
			(xy 418.206485 -177.797525) (xy 418.211389 -177.826198) (xy 418.224168 -177.85233) (xy 418.243789 -177.873805)
			(xy 418.255958 -177.881788) (xy 418.27905 -177.896416) (xy 418.321167 -177.931255) (xy 418.357742 -177.971872)
			(xy 418.387993 -178.017397) (xy 418.411268 -178.066852) (xy 418.427069 -178.119177) (xy 418.435057 -178.173249)
			(xy 418.43506 -178.227908) (xy 418.427078 -178.28198) (xy 418.411283 -178.334307) (xy 418.388014 -178.383765)
			(xy 418.357769 -178.429294) (xy 418.321198 -178.469915) (xy 418.279085 -178.504759) (xy 418.255958 -178.519328)
			(xy 418.243724 -178.527237) (xy 418.224058 -178.548714) (xy 418.211257 -178.574871) (xy 418.206364 -178.603578)
			(xy 418.209777 -178.632499) (xy 418.215064 -178.646074) (xy 418.224541 -178.669289) (xy 418.237896 -178.717619)
			(xy 418.244629 -178.767307) (xy 418.245036 -178.792378) (xy 418.244515 -178.820263) (xy 418.236203 -178.87541)
			(xy 418.219765 -178.928702) (xy 418.195567 -178.978948) (xy 418.164151 -179.025027) (xy 418.126218 -179.065909)
			(xy 418.082616 -179.100681) (xy 418.034318 -179.128566) (xy 417.982403 -179.148941) (xy 417.928032 -179.161351)
			(xy 417.872418 -179.165519) (xy 417.816804 -179.161351) (xy 417.762433 -179.148941) (xy 417.710518 -179.128566)
			(xy 417.66222 -179.100681) (xy 417.618618 -179.065909) (xy 417.580685 -179.025027) (xy 417.549269 -178.978948)
			(xy 417.525071 -178.928702) (xy 417.508633 -178.87541) (xy 417.500321 -178.820263) (xy 417.4998 -178.792378)
			(xy 410.41574 -178.792378) (xy 410.41574 -179.723542) (xy 419.315646 -179.723542) (xy 419.316217 -179.696294)
			(xy 419.323967 -179.642352) (xy 419.339314 -179.590061) (xy 419.361947 -179.540487) (xy 419.391405 -179.494639)
			(xy 419.427087 -179.45345) (xy 419.468269 -179.417757) (xy 419.51411 -179.388289) (xy 419.563679 -179.365645)
			(xy 419.615966 -179.350285) (xy 419.669906 -179.342523) (xy 419.697154 -179.342034) (xy 419.727059 -179.342571)
			(xy 419.786138 -179.351883) (xy 419.814756 -179.360576) (xy 419.82866 -179.36463) (xy 419.857597 -179.36554)
			(xy 419.885621 -179.358274) (xy 419.910469 -179.343418) (xy 419.930134 -179.322171) (xy 419.943028 -179.296251)
			(xy 419.946074 -179.28209) (xy 419.951204 -179.256008) (xy 419.967775 -179.205501) (xy 419.991201 -179.157784)
			(xy 420.021027 -179.113784) (xy 420.056674 -179.074352) (xy 420.097452 -179.040253) (xy 420.142571 -179.012148)
			(xy 420.191156 -178.990581) (xy 420.242265 -178.975971) (xy 420.294908 -178.968601) (xy 420.321486 -178.968146)
			(xy 420.348736 -178.9687) (xy 420.402682 -178.976455) (xy 420.454975 -178.991808) (xy 420.504551 -179.014447)
			(xy 420.550401 -179.043911) (xy 420.59159 -179.0796) (xy 420.627281 -179.120788) (xy 420.656747 -179.166636)
			(xy 420.679387 -179.216211) (xy 420.694742 -179.268504) (xy 420.702499 -179.32245) (xy 420.702499 -179.37695)
			(xy 420.694742 -179.430896) (xy 420.679387 -179.483189) (xy 420.656747 -179.532764) (xy 420.627281 -179.578612)
			(xy 420.59159 -179.6198) (xy 420.550401 -179.655489) (xy 420.504551 -179.684953) (xy 420.454975 -179.707592)
			(xy 420.402682 -179.722945) (xy 420.348736 -179.7307) (xy 420.321486 -179.731162) (xy 420.291581 -179.730639)
			(xy 420.232502 -179.721318) (xy 420.203884 -179.71262) (xy 420.189967 -179.708614) (xy 420.161038 -179.707695)
			(xy 420.133019 -179.714952) (xy 420.108173 -179.729799) (xy 420.088508 -179.751036) (xy 420.075613 -179.776949)
			(xy 420.072566 -179.791106) (xy 420.06599 -179.823947) (xy 420.042863 -179.886798) (xy 420.026592 -179.916074)
			(xy 420.019587 -179.929057) (xy 420.012541 -179.957688) (xy 420.013975 -179.987137) (xy 420.023771 -180.014948)
			(xy 420.04111 -180.038795) (xy 420.064544 -180.05669) (xy 420.078154 -180.062378) (xy 420.104942 -180.073047)
			(xy 420.155182 -180.101341) (xy 420.20059 -180.136876) (xy 420.240131 -180.178842) (xy 420.269517 -180.221382)
			(xy 430.50409 -180.221382) (xy 430.508161 -180.16576) (xy 430.520287 -180.111323) (xy 430.54021 -180.059232)
			(xy 430.567506 -180.010597) (xy 430.601592 -179.966454) (xy 430.641741 -179.927745) (xy 430.687099 -179.895294)
			(xy 430.736699 -179.869793) (xy 430.789483 -179.851786) (xy 430.844326 -179.841656) (xy 430.90006 -179.839619)
			(xy 430.955497 -179.845719) (xy 431.009454 -179.859825) (xy 431.060783 -179.881637) (xy 431.108389 -179.910691)
			(xy 431.151257 -179.946366) (xy 431.188474 -179.987903) (xy 431.219247 -180.034416) (xy 431.242919 -180.084913)
			(xy 431.258987 -180.13832) (xy 431.267107 -180.193496) (xy 431.267616 -180.221382) (xy 431.267107 -180.249268)
			(xy 431.258987 -180.304444) (xy 431.242919 -180.357851) (xy 431.219247 -180.408348) (xy 431.188474 -180.454861)
			(xy 431.151257 -180.496398) (xy 431.108389 -180.532073) (xy 431.060783 -180.561127) (xy 431.009454 -180.582939)
			(xy 430.955497 -180.597045) (xy 430.90006 -180.603145) (xy 430.844326 -180.601108) (xy 430.789483 -180.590978)
			(xy 430.736699 -180.572971) (xy 430.687099 -180.54747) (xy 430.641741 -180.515019) (xy 430.601592 -180.47631)
			(xy 430.567506 -180.432167) (xy 430.54021 -180.383532) (xy 430.520287 -180.331441) (xy 430.508161 -180.277004)
			(xy 430.50409 -180.221382) (xy 420.269517 -180.221382) (xy 420.272903 -180.226283) (xy 420.298159 -180.278117)
			(xy 420.315323 -180.333162) (xy 420.324005 -180.390164) (xy 420.324534 -180.418994) (xy 420.324048 -180.446245)
			(xy 420.316292 -180.500193) (xy 420.300937 -180.552488) (xy 420.278295 -180.602065) (xy 420.248829 -180.647915)
			(xy 420.213138 -180.689106) (xy 420.171947 -180.724797) (xy 420.126097 -180.754263) (xy 420.07652 -180.776905)
			(xy 420.024225 -180.79226) (xy 419.970277 -180.800016) (xy 419.915775 -180.800016) (xy 419.861827 -180.79226)
			(xy 419.809532 -180.776905) (xy 419.759955 -180.754263) (xy 419.714105 -180.724797) (xy 419.672914 -180.689106)
			(xy 419.637223 -180.647915) (xy 419.607757 -180.602065) (xy 419.585115 -180.552488) (xy 419.56976 -180.500193)
			(xy 419.562004 -180.446245) (xy 419.561518 -180.418994) (xy 419.56191 -180.393758) (xy 419.568529 -180.343724)
			(xy 419.581704 -180.295004) (xy 419.601202 -180.248452) (xy 419.613588 -180.226462) (xy 419.620627 -180.213499)
			(xy 419.627653 -180.184862) (xy 419.626205 -180.155412) (xy 419.616403 -180.127603) (xy 419.599064 -180.103754)
			(xy 419.575634 -180.085852) (xy 419.562026 -180.080158) (xy 419.535269 -180.069416) (xy 419.485027 -180.041136)
			(xy 419.439617 -180.005613) (xy 419.400072 -179.963658) (xy 419.367296 -179.916228) (xy 419.342035 -179.864402)
			(xy 419.324865 -179.809365) (xy 419.316178 -179.752369) (xy 419.315646 -179.723542) (xy 410.41574 -179.723542)
			(xy 410.41574 -180.943548) (xy 444.707304 -180.943548) (xy 444.707304 -180.889052) (xy 444.715059 -180.835111)
			(xy 444.730411 -180.782823) (xy 444.753048 -180.733252) (xy 444.782509 -180.687406) (xy 444.818194 -180.64622)
			(xy 444.859377 -180.610531) (xy 444.90522 -180.581066) (xy 444.954789 -180.558424) (xy 445.007076 -180.543067)
			(xy 445.061016 -180.535307) (xy 445.088264 -180.534818) (xy 445.114278 -180.535213) (xy 445.165823 -180.542292)
			(xy 445.215928 -180.55631) (xy 445.263663 -180.577007) (xy 445.308143 -180.603998) (xy 445.348542 -180.636784)
			(xy 445.366648 -180.655468) (xy 445.376576 -180.665364) (xy 445.40054 -180.679878) (xy 445.42755 -180.687325)
			(xy 445.455566 -180.687143) (xy 445.482476 -180.679345) (xy 445.506249 -180.66452) (xy 445.516 -180.654452)
			(xy 445.534154 -180.635128) (xy 445.574901 -180.601205) (xy 445.619952 -180.57325) (xy 445.668438 -180.5518)
			(xy 445.719428 -180.537268) (xy 445.771938 -180.529935) (xy 445.798448 -180.529484) (xy 445.825818 -180.52996)
			(xy 445.879998 -180.537772) (xy 445.932501 -180.553258) (xy 445.982249 -180.576098) (xy 446.028215 -180.605822)
			(xy 446.049146 -180.623464) (xy 446.060474 -180.6327) (xy 446.087031 -180.644876) (xy 446.115948 -180.649049)
			(xy 446.144865 -180.644876) (xy 446.171422 -180.6327) (xy 446.18275 -180.623464) (xy 446.203685 -180.605829)
			(xy 446.249658 -180.576118) (xy 446.299405 -180.553282) (xy 446.351904 -180.53779) (xy 446.406079 -180.529959)
			(xy 446.433448 -180.529484) (xy 446.460696 -180.529989) (xy 446.514638 -180.537751) (xy 446.566926 -180.55311)
			(xy 446.616496 -180.575753) (xy 446.662339 -180.60522) (xy 446.703523 -180.640911) (xy 446.739209 -180.682099)
			(xy 446.76867 -180.727946) (xy 446.791307 -180.777519) (xy 446.806659 -180.829809) (xy 446.814414 -180.883752)
			(xy 446.814414 -180.938248) (xy 446.806659 -180.992191) (xy 446.791307 -181.044481) (xy 446.76867 -181.094054)
			(xy 446.739209 -181.139901) (xy 446.703523 -181.181089) (xy 446.662339 -181.21678) (xy 446.616496 -181.246247)
			(xy 446.566926 -181.26889) (xy 446.514638 -181.284249) (xy 446.460696 -181.292011) (xy 446.433448 -181.2925)
			(xy 446.406079 -181.292006) (xy 446.351901 -181.284195) (xy 446.299398 -181.268712) (xy 446.249651 -181.245877)
			(xy 446.203683 -181.216158) (xy 446.18275 -181.19852) (xy 446.171422 -181.189284) (xy 446.144865 -181.177108)
			(xy 446.115948 -181.172935) (xy 446.087031 -181.177108) (xy 446.060474 -181.189284) (xy 446.049146 -181.19852)
			(xy 446.02821 -181.216154) (xy 445.982238 -181.245866) (xy 445.932491 -181.268703) (xy 445.879992 -181.284195)
			(xy 445.825817 -181.292025) (xy 445.798448 -181.2925) (xy 445.772434 -181.292091) (xy 445.72089 -181.285014)
			(xy 445.670786 -181.270999) (xy 445.623051 -181.250304) (xy 445.578571 -181.223316) (xy 445.538171 -181.190533)
			(xy 445.520064 -181.17185) (xy 445.510219 -181.161864) (xy 445.486231 -181.147352) (xy 445.4592 -181.139915)
			(xy 445.431165 -181.140114) (xy 445.404242 -181.147934) (xy 445.380462 -181.162785) (xy 445.370712 -181.172866)
			(xy 445.352556 -181.192188) (xy 445.311809 -181.22611) (xy 445.266759 -181.254065) (xy 445.218272 -181.275516)
			(xy 445.167283 -181.290048) (xy 445.114774 -181.297382) (xy 445.088264 -181.297834) (xy 445.061016 -181.297293)
			(xy 445.007076 -181.289533) (xy 444.954789 -181.274176) (xy 444.90522 -181.251534) (xy 444.859377 -181.222069)
			(xy 444.818194 -181.18638) (xy 444.782509 -181.145194) (xy 444.753048 -181.099348) (xy 444.730411 -181.049777)
			(xy 444.715059 -180.997489) (xy 444.707304 -180.943548) (xy 410.41574 -180.943548) (xy 410.41574 -181.46225)
			(xy 419.374572 -181.46225) (xy 419.374572 -181.40775) (xy 419.382328 -181.353803) (xy 419.397682 -181.30151)
			(xy 419.420321 -181.251933) (xy 419.449786 -181.206084) (xy 419.485475 -181.164893) (xy 419.526663 -181.129201)
			(xy 419.572511 -181.099734) (xy 419.622085 -181.077091) (xy 419.674378 -181.061733) (xy 419.728324 -181.053974)
			(xy 419.755574 -181.053486) (xy 419.785261 -181.054065) (xy 419.843919 -181.06326) (xy 419.900444 -181.081431)
			(xy 419.953471 -181.108139) (xy 420.001721 -181.142741) (xy 420.044027 -181.184399) (xy 420.062152 -181.207918)
			(xy 420.070578 -181.218525) (xy 420.091891 -181.235232) (xy 420.116845 -181.245751) (xy 420.143686 -181.249341)
			(xy 420.170527 -181.245751) (xy 420.195481 -181.235232) (xy 420.216794 -181.218525) (xy 420.22522 -181.207918)
			(xy 420.243349 -181.184402) (xy 420.285654 -181.142741) (xy 420.333902 -181.108136) (xy 420.386928 -181.081424)
			(xy 420.443453 -181.06325) (xy 420.502111 -181.054051) (xy 420.531798 -181.053486) (xy 420.559051 -181.053961)
			(xy 420.613001 -181.061718) (xy 420.665298 -181.077073) (xy 420.714878 -181.099715) (xy 420.76073 -181.129183)
			(xy 420.801923 -181.164876) (xy 420.837616 -181.206068) (xy 420.867084 -181.251921) (xy 420.889726 -181.3015)
			(xy 420.905082 -181.353797) (xy 420.912839 -181.407747) (xy 420.912839 -181.462253) (xy 420.905082 -181.516203)
			(xy 420.889726 -181.5685) (xy 420.867084 -181.618079) (xy 420.837616 -181.663932) (xy 420.801923 -181.705124)
			(xy 420.76073 -181.740817) (xy 420.714878 -181.770285) (xy 420.665298 -181.792927) (xy 420.613001 -181.808282)
			(xy 420.559051 -181.816039) (xy 420.531798 -181.816502) (xy 420.50211 -181.815948) (xy 420.443451 -181.806749)
			(xy 420.386925 -181.788573) (xy 420.333898 -181.76186) (xy 420.285649 -181.727254) (xy 420.243344 -181.685591)
			(xy 420.22522 -181.66207) (xy 420.216794 -181.651463) (xy 420.195481 -181.634756) (xy 420.170527 -181.624237)
			(xy 420.143686 -181.620647) (xy 420.116845 -181.624237) (xy 420.091891 -181.634756) (xy 420.070578 -181.651463)
			(xy 420.062152 -181.66207) (xy 420.044036 -181.685597) (xy 420.001729 -181.727258) (xy 419.953478 -181.761861)
			(xy 419.900449 -181.788572) (xy 419.843922 -181.806744) (xy 419.785262 -181.815939) (xy 419.755574 -181.816502)
			(xy 419.728324 -181.816026) (xy 419.674378 -181.808267) (xy 419.622085 -181.792909) (xy 419.572511 -181.770266)
			(xy 419.526663 -181.740799) (xy 419.485475 -181.705107) (xy 419.449786 -181.663916) (xy 419.420321 -181.618067)
			(xy 419.397682 -181.56849) (xy 419.382328 -181.516197) (xy 419.374572 -181.46225) (xy 410.41574 -181.46225)
			(xy 410.41574 -182.0418) (xy 410.452824 -182.052214) (xy 410.478928 -182.060017) (xy 410.528576 -182.082447)
			(xy 410.574231 -182.112175) (xy 410.614826 -182.148509) (xy 410.649416 -182.1906) (xy 410.663258 -182.213953)
			(xy 418.557175 -182.213953) (xy 418.564931 -182.160006) (xy 418.580286 -182.107711) (xy 418.602926 -182.058133)
			(xy 418.632392 -182.012282) (xy 418.668083 -181.971091) (xy 418.709272 -181.935399) (xy 418.755122 -181.905932)
			(xy 418.804699 -181.88329) (xy 418.856994 -181.867934) (xy 418.910941 -181.860176) (xy 418.965444 -181.860175)
			(xy 419.019392 -181.867931) (xy 419.071687 -181.883285) (xy 419.121265 -181.905925) (xy 419.167116 -181.93539)
			(xy 419.208307 -181.971081) (xy 419.243999 -182.01227) (xy 419.273467 -182.05812) (xy 419.296109 -182.107697)
			(xy 419.311466 -182.159991) (xy 419.319224 -182.213939) (xy 419.31971 -182.24119) (xy 419.319282 -182.266581)
			(xy 419.312524 -182.316913) (xy 419.306248 -182.34152) (xy 419.302808 -182.356167) (xy 419.303729 -182.386225)
			(xy 419.31336 -182.414715) (xy 419.330866 -182.439167) (xy 419.354731 -182.457465) (xy 419.38289 -182.468023)
			(xy 419.412902 -182.469929) (xy 419.42766 -182.466996) (xy 419.449255 -182.462239) (xy 419.49318 -182.45714)
			(xy 419.51529 -182.456836) (xy 419.542541 -182.457267) (xy 419.59649 -182.465022) (xy 419.648785 -182.480376)
			(xy 419.698364 -182.503015) (xy 419.744216 -182.53248) (xy 419.785408 -182.56817) (xy 419.821101 -182.609359)
			(xy 419.85057 -182.655209) (xy 419.87006 -182.697882) (xy 433.914294 -182.697882) (xy 433.918365 -182.64226)
			(xy 433.930491 -182.587823) (xy 433.950414 -182.535732) (xy 433.97771 -182.487097) (xy 434.011796 -182.442954)
			(xy 434.051945 -182.404245) (xy 434.097303 -182.371794) (xy 434.146903 -182.346293) (xy 434.199687 -182.328286)
			(xy 434.25453 -182.318156) (xy 434.310264 -182.316119) (xy 434.365701 -182.322219) (xy 434.419658 -182.336325)
			(xy 434.470987 -182.358137) (xy 434.518593 -182.387191) (xy 434.561461 -182.422866) (xy 434.598678 -182.464403)
			(xy 434.629451 -182.510916) (xy 434.653123 -182.561413) (xy 434.669191 -182.61482) (xy 434.677311 -182.669996)
			(xy 434.67782 -182.697882) (xy 434.677311 -182.725768) (xy 434.669191 -182.780944) (xy 434.653123 -182.834351)
			(xy 434.629451 -182.884848) (xy 434.598678 -182.931361) (xy 434.561461 -182.972898) (xy 434.518593 -183.008573)
			(xy 434.470987 -183.037627) (xy 434.461508 -183.041655) (xy 444.697021 -183.041655) (xy 444.697021 -182.987145)
			(xy 444.704779 -182.933188) (xy 444.720136 -182.880885) (xy 444.742781 -182.831301) (xy 444.772252 -182.785443)
			(xy 444.80795 -182.744247) (xy 444.849146 -182.70855) (xy 444.895004 -182.679079) (xy 444.944589 -182.656435)
			(xy 444.996892 -182.641078) (xy 445.050849 -182.633321) (xy 445.078104 -182.632858) (xy 445.104116 -182.633312)
			(xy 445.155658 -182.640381) (xy 445.205761 -182.654389) (xy 445.253495 -182.675075) (xy 445.297977 -182.702055)
			(xy 445.338379 -182.734829) (xy 445.356488 -182.753508) (xy 445.366376 -182.76345) (xy 445.39035 -182.77797)
			(xy 445.417371 -182.785417) (xy 445.445399 -182.785227) (xy 445.472317 -182.777415) (xy 445.496092 -182.76257)
			(xy 445.50584 -182.752492) (xy 445.524031 -182.733205) (xy 445.564769 -182.699277) (xy 445.609812 -182.671316)
			(xy 445.658292 -182.649859) (xy 445.709275 -182.63532) (xy 445.76178 -182.62798) (xy 445.788288 -182.627524)
			(xy 445.815658 -182.627991) (xy 445.869838 -182.635808) (xy 445.922341 -182.651296) (xy 445.972088 -182.674138)
			(xy 446.018054 -182.703863) (xy 446.038986 -182.721504) (xy 446.050314 -182.73074) (xy 446.076871 -182.742916)
			(xy 446.105788 -182.747089) (xy 446.134705 -182.742916) (xy 446.161262 -182.73074) (xy 446.17259 -182.721504)
			(xy 446.193516 -182.703857) (xy 446.23949 -182.674146) (xy 446.289239 -182.651312) (xy 446.341741 -182.635822)
			(xy 446.395918 -182.627997) (xy 446.423288 -182.627524) (xy 446.450544 -182.627922) (xy 446.504501 -182.635678)
			(xy 446.556804 -182.651035) (xy 446.60639 -182.673678) (xy 446.652249 -182.703149) (xy 446.693446 -182.738845)
			(xy 446.729144 -182.780042) (xy 446.758616 -182.825899) (xy 446.781261 -182.875484) (xy 446.796619 -182.927788)
			(xy 446.804377 -182.981744) (xy 446.804377 -183.036256) (xy 446.796619 -183.090212) (xy 446.781261 -183.142516)
			(xy 446.758616 -183.192101) (xy 446.729144 -183.237958) (xy 446.693446 -183.279155) (xy 446.652249 -183.314851)
			(xy 446.60639 -183.344322) (xy 446.556804 -183.366965) (xy 446.504501 -183.382322) (xy 446.450544 -183.390078)
			(xy 446.423288 -183.39054) (xy 446.395917 -183.390096) (xy 446.341736 -183.382275) (xy 446.289232 -183.366781)
			(xy 446.239486 -183.343935) (xy 446.19352 -183.314204) (xy 446.17259 -183.29656) (xy 446.161262 -183.287324)
			(xy 446.134705 -183.275148) (xy 446.105788 -183.270975) (xy 446.076871 -183.275148) (xy 446.050314 -183.287324)
			(xy 446.038986 -183.29656) (xy 446.018027 -183.314166) (xy 445.972062 -183.343884) (xy 445.922322 -183.366727)
			(xy 445.869827 -183.382226) (xy 445.815655 -183.390062) (xy 445.788288 -183.39054) (xy 445.762276 -183.390092)
			(xy 445.710734 -183.383021) (xy 445.660631 -183.369013) (xy 445.612896 -183.348326) (xy 445.568415 -183.321344)
			(xy 445.528013 -183.288569) (xy 445.509904 -183.26989) (xy 445.500024 -183.25994) (xy 445.476048 -183.24542)
			(xy 445.449024 -183.237975) (xy 445.420995 -183.238166) (xy 445.394076 -183.24598) (xy 445.3703 -183.260827)
			(xy 445.360552 -183.270906) (xy 445.342364 -183.290197) (xy 445.301626 -183.324124) (xy 445.256582 -183.352085)
			(xy 445.208102 -183.373541) (xy 445.157118 -183.388079) (xy 445.104612 -183.395419) (xy 445.078104 -183.395874)
			(xy 445.050849 -183.395479) (xy 444.996892 -183.387722) (xy 444.944589 -183.372365) (xy 444.895004 -183.349721)
			(xy 444.849146 -183.32025) (xy 444.80795 -183.284553) (xy 444.772252 -183.243357) (xy 444.742781 -183.197499)
			(xy 444.720136 -183.147915) (xy 444.704779 -183.095612) (xy 444.697021 -183.041655) (xy 434.461508 -183.041655)
			(xy 434.419658 -183.059439) (xy 434.365701 -183.073545) (xy 434.310264 -183.079645) (xy 434.25453 -183.077608)
			(xy 434.199687 -183.067478) (xy 434.146903 -183.049471) (xy 434.097303 -183.02397) (xy 434.051945 -182.991519)
			(xy 434.011796 -182.95281) (xy 433.97771 -182.908667) (xy 433.950414 -182.860032) (xy 433.930491 -182.807941)
			(xy 433.918365 -182.753504) (xy 433.914294 -182.697882) (xy 419.87006 -182.697882) (xy 419.873213 -182.704785)
			(xy 419.888571 -182.75708) (xy 419.896331 -182.811027) (xy 419.896334 -182.86553) (xy 419.88858 -182.919479)
			(xy 419.873228 -182.971775) (xy 419.85059 -183.021354) (xy 419.821127 -183.067207) (xy 419.785438 -183.1084)
			(xy 419.74425 -183.144094) (xy 419.698401 -183.173564) (xy 419.648825 -183.196209) (xy 419.596532 -183.211569)
			(xy 419.542584 -183.21933) (xy 419.488081 -183.219335) (xy 419.434132 -183.211583) (xy 419.381836 -183.196232)
			(xy 419.332256 -183.173596) (xy 419.286403 -183.144134) (xy 419.245208 -183.108446) (xy 419.209512 -183.067259)
			(xy 419.180041 -183.021411) (xy 419.157395 -182.971836) (xy 419.142034 -182.919543) (xy 419.134271 -182.865595)
			(xy 419.133782 -182.838344) (xy 419.134216 -182.812953) (xy 419.14097 -182.762622) (xy 419.147244 -182.738014)
			(xy 419.150657 -182.723361) (xy 419.149744 -182.693304) (xy 419.14012 -182.664815) (xy 419.122618 -182.640362)
			(xy 419.098755 -182.622064) (xy 419.070599 -182.611507) (xy 419.040588 -182.609604) (xy 419.025832 -182.612538)
			(xy 419.004238 -182.617297) (xy 418.960312 -182.622394) (xy 418.938202 -182.622698) (xy 418.910951 -182.622224)
			(xy 418.857003 -182.614468) (xy 418.804708 -182.599113) (xy 418.755131 -182.576473) (xy 418.70928 -182.547007)
			(xy 418.668089 -182.511315) (xy 418.632397 -182.470125) (xy 418.602931 -182.424275) (xy 418.580289 -182.374698)
			(xy 418.564933 -182.322404) (xy 418.557176 -182.268456) (xy 418.557175 -182.213953) (xy 410.663258 -182.213953)
			(xy 410.677194 -182.237466) (xy 410.697511 -182.288016) (xy 410.709895 -182.34107) (xy 410.714056 -182.395391)
			(xy 410.709898 -182.449713) (xy 410.697517 -182.502767) (xy 410.677201 -182.553318) (xy 410.649426 -182.600186)
			(xy 410.614838 -182.642279) (xy 410.574244 -182.678614) (xy 410.528591 -182.708345) (xy 410.478944 -182.730777)
			(xy 410.452824 -182.738522) (xy 410.41574 -182.748936) (xy 410.41574 -183.059957) (xy 416.453709 -183.059957)
			(xy 416.453709 -183.005443) (xy 416.461468 -182.951483) (xy 416.476827 -182.899176) (xy 416.499474 -182.849588)
			(xy 416.528948 -182.803728) (xy 416.56465 -182.76253) (xy 416.605851 -182.726832) (xy 416.651713 -182.697361)
			(xy 416.701302 -182.674717) (xy 416.75361 -182.659362) (xy 416.807571 -182.651607) (xy 416.834828 -182.651146)
			(xy 416.862199 -182.651584) (xy 416.91638 -182.659407) (xy 416.968884 -182.674902) (xy 417.01863 -182.69775)
			(xy 417.064596 -182.727481) (xy 417.085526 -182.745126) (xy 417.096854 -182.754362) (xy 417.123411 -182.766538)
			(xy 417.152328 -182.770711) (xy 417.181245 -182.766538) (xy 417.207802 -182.754362) (xy 417.21913 -182.745126)
			(xy 417.240081 -182.72751) (xy 417.286048 -182.697794) (xy 417.335791 -182.674953) (xy 417.388287 -182.659457)
			(xy 417.44246 -182.651623) (xy 417.469828 -182.651146) (xy 417.497075 -182.651726) (xy 417.551013 -182.659485)
			(xy 417.603298 -182.674841) (xy 417.652865 -182.697481) (xy 417.698707 -182.726944) (xy 417.739889 -182.762631)
			(xy 417.775573 -182.803816) (xy 417.805033 -182.849659) (xy 417.827669 -182.899228) (xy 417.843021 -182.951515)
			(xy 417.850776 -183.005453) (xy 417.850776 -183.059947) (xy 417.843021 -183.113885) (xy 417.827669 -183.166172)
			(xy 417.805033 -183.215741) (xy 417.775573 -183.261584) (xy 417.739889 -183.302769) (xy 417.698707 -183.338456)
			(xy 417.652865 -183.367919) (xy 417.603298 -183.390559) (xy 417.551013 -183.405915) (xy 417.497075 -183.413674)
			(xy 417.469828 -183.414162) (xy 417.442458 -183.413689) (xy 417.388279 -183.405874) (xy 417.335775 -183.390387)
			(xy 417.286028 -183.367547) (xy 417.240062 -183.337823) (xy 417.21913 -183.320182) (xy 417.207802 -183.310946)
			(xy 417.181245 -183.29877) (xy 417.152328 -183.294597) (xy 417.123411 -183.29877) (xy 417.096854 -183.310946)
			(xy 417.085526 -183.320182) (xy 417.064593 -183.33782) (xy 417.01862 -183.367532) (xy 416.968873 -183.390369)
			(xy 416.916373 -183.40586) (xy 416.862197 -183.413688) (xy 416.834828 -183.414162) (xy 416.807571 -183.413793)
			(xy 416.75361 -183.406038) (xy 416.701302 -183.390683) (xy 416.651713 -183.368039) (xy 416.605851 -183.338568)
			(xy 416.56465 -183.30287) (xy 416.528948 -183.261672) (xy 416.499474 -183.215812) (xy 416.476827 -183.166224)
			(xy 416.461468 -183.113917) (xy 416.453709 -183.059957) (xy 410.41574 -183.059957) (xy 410.41574 -184.493408)
			(xy 410.45892 -184.536588) (xy 424.778422 -184.536588) (xy 424.782493 -184.480966) (xy 424.794619 -184.426529)
			(xy 424.814542 -184.374438) (xy 424.841838 -184.325803) (xy 424.875924 -184.28166) (xy 424.916073 -184.242951)
			(xy 424.961431 -184.2105) (xy 425.011031 -184.184999) (xy 425.063815 -184.166992) (xy 425.118658 -184.156862)
			(xy 425.174392 -184.154825) (xy 425.229829 -184.160925) (xy 425.283786 -184.175031) (xy 425.335115 -184.196843)
			(xy 425.382721 -184.225897) (xy 425.425589 -184.261572) (xy 425.462806 -184.303109) (xy 425.493579 -184.349622)
			(xy 425.517251 -184.400119) (xy 425.533319 -184.453526) (xy 425.541439 -184.508702) (xy 425.541948 -184.536588)
			(xy 425.541439 -184.564474) (xy 425.533319 -184.61965) (xy 425.517251 -184.673057) (xy 425.493579 -184.723554)
			(xy 425.462806 -184.770067) (xy 425.46035 -184.772808) (xy 431.191922 -184.772808) (xy 431.195993 -184.717186)
			(xy 431.208119 -184.662749) (xy 431.228042 -184.610658) (xy 431.255338 -184.562023) (xy 431.289424 -184.51788)
			(xy 431.329573 -184.479171) (xy 431.374931 -184.44672) (xy 431.424531 -184.421219) (xy 431.477315 -184.403212)
			(xy 431.532158 -184.393082) (xy 431.587892 -184.391045) (xy 431.643329 -184.397145) (xy 431.697286 -184.411251)
			(xy 431.748615 -184.433063) (xy 431.796221 -184.462117) (xy 431.839089 -184.497792) (xy 431.876306 -184.539329)
			(xy 431.907079 -184.585842) (xy 431.930751 -184.636339) (xy 431.946819 -184.689746) (xy 431.954939 -184.744922)
			(xy 431.955448 -184.772808) (xy 431.954939 -184.800694) (xy 431.946819 -184.85587) (xy 431.930751 -184.909277)
			(xy 431.907079 -184.959774) (xy 431.876306 -185.006287) (xy 431.839089 -185.047824) (xy 431.796221 -185.083499)
			(xy 431.748615 -185.112553) (xy 431.697286 -185.134365) (xy 431.643329 -185.148471) (xy 431.587892 -185.154571)
			(xy 431.532158 -185.152534) (xy 431.477315 -185.142404) (xy 431.424531 -185.124397) (xy 431.374931 -185.098896)
			(xy 431.329573 -185.066445) (xy 431.289424 -185.027736) (xy 431.255338 -184.983593) (xy 431.228042 -184.934958)
			(xy 431.208119 -184.882867) (xy 431.195993 -184.82843) (xy 431.191922 -184.772808) (xy 425.46035 -184.772808)
			(xy 425.425589 -184.811604) (xy 425.382721 -184.847279) (xy 425.335115 -184.876333) (xy 425.283786 -184.898145)
			(xy 425.229829 -184.912251) (xy 425.174392 -184.918351) (xy 425.118658 -184.916314) (xy 425.063815 -184.906184)
			(xy 425.011031 -184.888177) (xy 424.961431 -184.862676) (xy 424.916073 -184.830225) (xy 424.875924 -184.791516)
			(xy 424.841838 -184.747373) (xy 424.814542 -184.698738) (xy 424.794619 -184.646647) (xy 424.782493 -184.59221)
			(xy 424.778422 -184.536588) (xy 410.45892 -184.536588) (xy 411.31998 -185.397648)
		)
		(stroke
			(width 0)
			(type solid)
		)
		(fill yes)
		(layer "In4.Cu")
		(net "GND")
	)
	(gr_poly
		(pts
			(xy 238.9759 -407.2509) (xy 238.9759 -400.689572) (xy 237.668308 -399.38198) (xy 237.668308 -394.551662)
			(xy 232.288588 -389.171942) (xy 182.905908 -389.171942) (xy 177.847244 -394.23086) (xy 177.847244 -395.545564)
			(xy 177.846728 -395.570545) (xy 177.838868 -395.619888) (xy 177.823399 -395.667397) (xy 177.8007 -395.711907)
			(xy 177.771328 -395.752326) (xy 177.754026 -395.770354) (xy 176.79924 -396.72514) (xy 176.79924 -398.151096)
			(xy 176.799772 -398.166095) (xy 176.808477 -398.194801) (xy 176.825139 -398.219745) (xy 176.848324 -398.238779)
			(xy 176.876036 -398.250264) (xy 176.905888 -398.253212) (xy 176.93531 -398.247369) (xy 176.961771 -398.233238)
			(xy 176.972722 -398.222978) (xy 177.54854 -397.64716) (xy 177.567259 -397.629141) (xy 177.609271 -397.598575)
			(xy 177.655543 -397.574948) (xy 177.704938 -397.558841) (xy 177.756243 -397.550649) (xy 177.78222 -397.550132)
			(xy 178.99126 -397.550132) (xy 179.017242 -397.550629) (xy 179.068561 -397.558788) (xy 179.11797 -397.574882)
			(xy 179.16425 -397.598511) (xy 179.20626 -397.629095) (xy 179.22494 -397.64716) (xy 179.738528 -398.160748)
			(xy 179.756542 -398.17947) (xy 179.7871 -398.221484) (xy 179.810719 -398.267757) (xy 179.826821 -398.31715)
			(xy 179.835009 -398.368453) (xy 179.835556 -398.394428) (xy 179.835556 -400.751802) (xy 180.581046 -401.497292)
			(xy 180.658008 -401.497292) (xy 180.671835 -401.496879) (xy 180.698496 -401.489547) (xy 180.722202 -401.475314)
			(xy 180.741208 -401.455231) (xy 180.754113 -401.430776) (xy 180.759966 -401.403752) (xy 180.758336 -401.376149)
			(xy 180.754274 -401.362926) (xy 180.744681 -401.33297) (xy 180.734336 -401.27093) (xy 180.7337 -401.239482)
			(xy 180.734187 -401.212232) (xy 180.741946 -401.158286) (xy 180.757302 -401.105994) (xy 180.779945 -401.05642)
			(xy 180.809412 -401.010572) (xy 180.845103 -400.969385) (xy 180.886293 -400.933696) (xy 180.932143 -400.904232)
			(xy 180.981719 -400.881593) (xy 181.034012 -400.86624) (xy 181.087958 -400.858485) (xy 181.115208 -400.857974)
			(xy 181.127564 -400.858097) (xy 181.152222 -400.85975) (xy 181.164484 -400.861276) (xy 181.189376 -400.864324)
			(xy 181.24297 -400.81073) (xy 181.15534 -400.7231) (xy 181.137326 -400.704379) (xy 181.106769 -400.662365)
			(xy 181.083152 -400.616092) (xy 181.067055 -400.566698) (xy 181.058873 -400.515395) (xy 181.058312 -400.48942)
			(xy 181.058312 -400.363944) (xy 180.976016 -400.363944) (xy 180.962046 -400.392138) (xy 180.949895 -400.415737)
			(xy 180.920042 -400.459624) (xy 180.884395 -400.498952) (xy 180.843642 -400.53296) (xy 180.79857 -400.560992)
			(xy 180.750047 -400.582508) (xy 180.699012 -400.597091) (xy 180.646447 -400.604462) (xy 180.619908 -400.60499)
			(xy 180.592656 -400.604527) (xy 180.538707 -400.596772) (xy 180.48641 -400.581417) (xy 180.436832 -400.558776)
			(xy 180.39098 -400.52931) (xy 180.349788 -400.493618) (xy 180.314095 -400.452427) (xy 180.284628 -400.406575)
			(xy 180.261986 -400.356997) (xy 180.24663 -400.304701) (xy 180.238873 -400.250752) (xy 180.238873 -400.196248)
			(xy 180.24663 -400.142299) (xy 180.261986 -400.090003) (xy 180.284628 -400.040425) (xy 180.314095 -399.994573)
			(xy 180.349788 -399.953382) (xy 180.39098 -399.91769) (xy 180.436832 -399.888224) (xy 180.48641 -399.865583)
			(xy 180.538707 -399.850228) (xy 180.592656 -399.842473) (xy 180.619908 -399.841974) (xy 180.645036 -399.842375)
			(xy 180.694858 -399.848976) (xy 180.743381 -399.862063) (xy 180.789765 -399.881409) (xy 180.833207 -399.90668)
			(xy 180.853334 -399.92173) (xy 180.86442 -399.929754) (xy 180.889718 -399.940162) (xy 180.91687 -399.943486)
			(xy 180.943932 -399.939488) (xy 180.968963 -399.928454) (xy 180.990171 -399.911176) (xy 181.006036 -399.888891)
			(xy 181.01542 -399.863195) (xy 181.01691 -399.849594) (xy 181.019741 -399.82134) (xy 181.032695 -399.766056)
			(xy 181.053694 -399.7133) (xy 181.082272 -399.664235) (xy 181.117802 -399.619943) (xy 181.159498 -399.5814)
			(xy 181.206442 -399.549456) (xy 181.231794 -399.536666) (xy 181.243437 -399.530651) (xy 181.26341 -399.513702)
			(xy 181.278397 -399.492216) (xy 181.287405 -399.467618) (xy 181.289838 -399.441535) (xy 181.285535 -399.415695)
			(xy 181.280562 -399.40357) (xy 181.274322 -399.389152) (xy 181.26427 -399.359384) (xy 181.260496 -399.344134)
			(xy 181.256855 -399.33079) (xy 181.24349 -399.306588) (xy 181.224123 -399.286857) (xy 181.200172 -399.273045)
			(xy 181.173395 -399.266164) (xy 181.145753 -399.266717) (xy 181.119273 -399.274665) (xy 181.107334 -399.28165)
			(xy 181.084428 -399.29549) (xy 181.035568 -399.317323) (xy 180.984138 -399.33212) (xy 180.931146 -399.339591)
			(xy 180.904388 -399.34007) (xy 180.877137 -399.339606) (xy 180.823189 -399.331847) (xy 180.770895 -399.31649)
			(xy 180.721319 -399.293846) (xy 180.67547 -399.264377) (xy 180.634282 -399.228683) (xy 180.598593 -399.18749)
			(xy 180.56913 -399.141637) (xy 180.546493 -399.092058) (xy 180.531142 -399.039762) (xy 180.523391 -398.985813)
			(xy 180.52288 -398.958562) (xy 180.523331 -398.931752) (xy 180.530834 -398.878661) (xy 180.5457 -398.827144)
			(xy 180.567637 -398.778218) (xy 180.596211 -398.732847) (xy 180.630859 -398.691927) (xy 180.670898 -398.656264)
			(xy 180.715538 -398.626561) (xy 180.7639 -398.603405) (xy 180.815028 -398.587252) (xy 180.841396 -398.582388)
			(xy 180.857398 -398.579594) (xy 180.904896 -398.532096) (xy 180.812948 -398.440148) (xy 180.79493 -398.421428)
			(xy 180.764367 -398.379416) (xy 180.740742 -398.333143) (xy 180.724637 -398.283749) (xy 180.716448 -398.232444)
			(xy 180.71592 -398.206468) (xy 180.71592 -393.271502) (xy 180.71642 -393.245521) (xy 180.724584 -393.194205)
			(xy 180.740681 -393.1448) (xy 180.764314 -393.098523) (xy 180.794899 -393.056516) (xy 180.812948 -393.037822)
			(xy 183.261508 -390.589262) (xy 183.280212 -390.571238) (xy 183.322232 -390.540706) (xy 183.368513 -390.517126)
			(xy 183.417914 -390.501081) (xy 183.469217 -390.492966) (xy 183.495188 -390.492488) (xy 194.027044 -390.492488)
			(xy 194.053011 -390.493) (xy 194.104306 -390.501127) (xy 194.153698 -390.517175) (xy 194.199974 -390.540749)
			(xy 194.241995 -390.571268) (xy 194.260724 -390.589262) (xy 195.253356 -391.58164) (xy 196.289168 -390.546082)
			(xy 196.30787 -390.528054) (xy 196.349889 -390.497515) (xy 196.396169 -390.473929) (xy 196.445571 -390.457877)
			(xy 196.496876 -390.449755) (xy 196.522848 -390.449308) (xy 206.065628 -390.449308) (xy 206.091595 -390.449819)
			(xy 206.142891 -390.457945) (xy 206.192285 -390.473991) (xy 206.238562 -390.497564) (xy 206.280583 -390.528084)
			(xy 206.299308 -390.546082) (xy 207.175608 -391.422128) (xy 208.097628 -390.500362) (xy 208.116332 -390.482339)
			(xy 208.158353 -390.451809) (xy 208.204634 -390.428233) (xy 208.254035 -390.412191) (xy 208.305338 -390.404078)
			(xy 208.331308 -390.403588) (xy 216.878408 -390.403588) (xy 216.904376 -390.404097) (xy 216.955674 -390.41222)
			(xy 217.00507 -390.428263) (xy 217.05135 -390.451834) (xy 217.093375 -390.482351) (xy 217.112088 -390.500362)
			(xy 217.843608 -391.231628) (xy 218.661488 -390.414002) (xy 218.680193 -390.395979) (xy 218.722214 -390.36545)
			(xy 218.768495 -390.341873) (xy 218.817895 -390.325828) (xy 218.869198 -390.31771) (xy 218.895168 -390.317228)
			(xy 227.724208 -390.317228) (xy 227.750176 -390.317738) (xy 227.801473 -390.325861) (xy 227.850868 -390.341906)
			(xy 227.897146 -390.365478) (xy 227.939168 -390.395998) (xy 227.957888 -390.414002) (xy 228.745288 -391.201402)
			(xy 228.763301 -391.220124) (xy 228.793855 -391.262139) (xy 228.817469 -391.308412) (xy 228.833565 -391.357806)
			(xy 228.841746 -391.409108) (xy 228.842316 -391.435082) (xy 228.842316 -399.552922) (xy 228.854401 -399.574739)
			(xy 228.873426 -399.620841) (xy 228.886279 -399.669031) (xy 228.892739 -399.718485) (xy 228.893116 -399.743422)
			(xy 228.892653 -399.770341) (xy 228.885085 -399.823643) (xy 228.870103 -399.875354) (xy 228.848003 -399.924446)
			(xy 228.819225 -399.969946) (xy 228.784339 -400.010951) (xy 228.744038 -400.046648) (xy 228.699121 -400.076327)
			(xy 228.650479 -400.099401) (xy 228.599077 -400.115411) (xy 228.572568 -400.120104) (xy 228.558855 -400.122755)
			(xy 228.533525 -400.134501) (xy 228.512328 -400.152675) (xy 228.496854 -400.175916) (xy 228.48826 -400.202481)
			(xy 228.487191 -400.230382) (xy 228.493727 -400.257527) (xy 228.507378 -400.281883) (xy 228.516942 -400.292062)
			(xy 228.745288 -400.520662) (xy 228.762528 -400.538508) (xy 228.791992 -400.578429) (xy 228.803962 -400.600164)
			(xy 228.810678 -400.612017) (xy 228.829269 -400.631918) (xy 228.852465 -400.646187) (xy 228.878612 -400.653805)
			(xy 228.905842 -400.654229) (xy 228.932213 -400.647429) (xy 228.955842 -400.633889) (xy 228.96576 -400.624548)
			(xy 229.456742 -400.13382) (xy 229.475462 -400.115803) (xy 229.517475 -400.085241) (xy 229.563747 -400.061617)
			(xy 229.613142 -400.045512) (xy 229.664446 -400.037322) (xy 229.690422 -400.036792) (xy 229.988618 -400.036792)
			(xy 230.003082 -400.036322) (xy 230.030865 -400.028273) (xy 230.055267 -400.012742) (xy 230.074323 -399.990982)
			(xy 230.086498 -399.964743) (xy 230.090811 -399.936141) (xy 230.089456 -399.92173) (xy 230.087805 -399.908967)
			(xy 230.086029 -399.883291) (xy 230.0859 -399.870422) (xy 230.086432 -399.841505) (xy 230.095157 -399.784332)
			(xy 230.112408 -399.72913) (xy 230.137792 -399.677163) (xy 230.170728 -399.629623) (xy 230.21046 -399.587596)
			(xy 230.232966 -399.569432) (xy 230.244776 -399.559535) (xy 230.262304 -399.534211) (xy 230.271487 -399.504813)
			(xy 230.271491 -399.474014) (xy 230.262316 -399.444614) (xy 230.244795 -399.419284) (xy 230.232966 -399.409412)
			(xy 230.212181 -399.392659) (xy 230.175047 -399.354305) (xy 230.143622 -399.31115) (xy 230.11852 -399.264035)
			(xy 230.100231 -399.213881) (xy 230.089111 -399.161668) (xy 230.085379 -399.108414) (xy 230.089108 -399.055159)
			(xy 230.100223 -399.002945) (xy 230.118509 -398.952789) (xy 230.143608 -398.905673) (xy 230.17503 -398.862515)
			(xy 230.212161 -398.824159) (xy 230.232966 -398.807432) (xy 230.244776 -398.797535) (xy 230.262304 -398.772211)
			(xy 230.271487 -398.742813) (xy 230.271491 -398.712014) (xy 230.262316 -398.682614) (xy 230.244795 -398.657284)
			(xy 230.232966 -398.647412) (xy 230.212181 -398.630659) (xy 230.175047 -398.592305) (xy 230.143622 -398.54915)
			(xy 230.11852 -398.502035) (xy 230.100231 -398.451881) (xy 230.089111 -398.399668) (xy 230.085379 -398.346414)
			(xy 230.089108 -398.293159) (xy 230.100223 -398.240945) (xy 230.118509 -398.190789) (xy 230.143608 -398.143673)
			(xy 230.17503 -398.100515) (xy 230.212161 -398.062159) (xy 230.232966 -398.045432) (xy 230.244776 -398.035535)
			(xy 230.262304 -398.010211) (xy 230.271487 -397.980813) (xy 230.271491 -397.950014) (xy 230.262316 -397.920614)
			(xy 230.244795 -397.895284) (xy 230.232966 -397.885412) (xy 230.212181 -397.868659) (xy 230.175047 -397.830305)
			(xy 230.143622 -397.78715) (xy 230.11852 -397.740035) (xy 230.100231 -397.689881) (xy 230.089111 -397.637668)
			(xy 230.085379 -397.584414) (xy 230.089108 -397.531159) (xy 230.100223 -397.478945) (xy 230.118509 -397.428789)
			(xy 230.143608 -397.381673) (xy 230.17503 -397.338515) (xy 230.212161 -397.300159) (xy 230.232966 -397.283432)
			(xy 230.244776 -397.273535) (xy 230.262304 -397.248211) (xy 230.271487 -397.218813) (xy 230.271491 -397.188014)
			(xy 230.262316 -397.158614) (xy 230.244795 -397.133284) (xy 230.232966 -397.123412) (xy 230.212181 -397.106659)
			(xy 230.175047 -397.068305) (xy 230.143622 -397.02515) (xy 230.11852 -396.978035) (xy 230.100231 -396.927881)
			(xy 230.089111 -396.875668) (xy 230.085379 -396.822414) (xy 230.089108 -396.769159) (xy 230.100223 -396.716945)
			(xy 230.118509 -396.666789) (xy 230.143608 -396.619673) (xy 230.17503 -396.576515) (xy 230.212161 -396.538159)
			(xy 230.232966 -396.521432) (xy 230.244776 -396.511535) (xy 230.262304 -396.486211) (xy 230.271487 -396.456813)
			(xy 230.271491 -396.426014) (xy 230.262316 -396.396614) (xy 230.244795 -396.371284) (xy 230.232966 -396.361412)
			(xy 230.210485 -396.34322) (xy 230.170753 -396.301201) (xy 230.13782 -396.253665) (xy 230.112438 -396.201703)
			(xy 230.095192 -396.146505) (xy 230.086474 -396.089337) (xy 230.0859 -396.060422) (xy 230.086362 -396.033168)
			(xy 230.094116 -395.979215) (xy 230.109471 -395.926915) (xy 230.132112 -395.877333) (xy 230.161579 -395.831478)
			(xy 230.197273 -395.790283) (xy 230.238467 -395.754588) (xy 230.284321 -395.725119) (xy 230.333902 -395.702475)
			(xy 230.386202 -395.687119) (xy 230.440154 -395.679363) (xy 230.467408 -395.678914) (xy 230.496324 -395.679449)
			(xy 230.553494 -395.688177) (xy 230.608693 -395.705432) (xy 230.660655 -395.73082) (xy 230.708192 -395.763757)
			(xy 230.750213 -395.803491) (xy 230.768398 -395.82598) (xy 230.778295 -395.837785) (xy 230.803619 -395.855304)
			(xy 230.833012 -395.86448) (xy 230.863804 -395.86448) (xy 230.893197 -395.855304) (xy 230.918521 -395.837785)
			(xy 230.928418 -395.82598) (xy 230.945171 -395.805197) (xy 230.983525 -395.768067) (xy 231.026679 -395.736645)
			(xy 231.073793 -395.711546) (xy 231.123945 -395.69326) (xy 231.176156 -395.682143) (xy 231.229408 -395.678413)
			(xy 231.28266 -395.682143) (xy 231.334871 -395.69326) (xy 231.385023 -395.711546) (xy 231.432137 -395.736645)
			(xy 231.475291 -395.768067) (xy 231.513645 -395.805197) (xy 231.530398 -395.82598) (xy 231.540295 -395.837785)
			(xy 231.565619 -395.855304) (xy 231.595012 -395.86448) (xy 231.625804 -395.86448) (xy 231.655197 -395.855304)
			(xy 231.680521 -395.837785) (xy 231.690418 -395.82598) (xy 231.707171 -395.805197) (xy 231.745525 -395.768067)
			(xy 231.788679 -395.736645) (xy 231.835793 -395.711546) (xy 231.885945 -395.69326) (xy 231.938156 -395.682143)
			(xy 231.991408 -395.678413) (xy 232.04466 -395.682143) (xy 232.096871 -395.69326) (xy 232.147023 -395.711546)
			(xy 232.194137 -395.736645) (xy 232.237291 -395.768067) (xy 232.275645 -395.805197) (xy 232.292398 -395.82598)
			(xy 232.302295 -395.837785) (xy 232.327619 -395.855304) (xy 232.357012 -395.86448) (xy 232.387804 -395.86448)
			(xy 232.417197 -395.855304) (xy 232.442521 -395.837785) (xy 232.452418 -395.82598) (xy 232.469171 -395.805197)
			(xy 232.507525 -395.768067) (xy 232.550679 -395.736645) (xy 232.597793 -395.711546) (xy 232.647945 -395.69326)
			(xy 232.700156 -395.682143) (xy 232.753408 -395.678413) (xy 232.80666 -395.682143) (xy 232.858871 -395.69326)
			(xy 232.909023 -395.711546) (xy 232.956137 -395.736645) (xy 232.999291 -395.768067) (xy 233.037645 -395.805197)
			(xy 233.054398 -395.82598) (xy 233.064295 -395.837785) (xy 233.089619 -395.855304) (xy 233.119012 -395.86448)
			(xy 233.149804 -395.86448) (xy 233.179197 -395.855304) (xy 233.204521 -395.837785) (xy 233.214418 -395.82598)
			(xy 233.231171 -395.805197) (xy 233.269525 -395.768067) (xy 233.312679 -395.736645) (xy 233.359793 -395.711546)
			(xy 233.409945 -395.69326) (xy 233.462156 -395.682143) (xy 233.515408 -395.678413) (xy 233.56866 -395.682143)
			(xy 233.620871 -395.69326) (xy 233.671023 -395.711546) (xy 233.718137 -395.736645) (xy 233.761291 -395.768067)
			(xy 233.799645 -395.805197) (xy 233.816398 -395.82598) (xy 233.826295 -395.837785) (xy 233.851619 -395.855304)
			(xy 233.881012 -395.86448) (xy 233.911804 -395.86448) (xy 233.941197 -395.855304) (xy 233.966521 -395.837785)
			(xy 233.976418 -395.82598) (xy 233.993171 -395.805197) (xy 234.031525 -395.768067) (xy 234.074679 -395.736645)
			(xy 234.121793 -395.711546) (xy 234.171945 -395.69326) (xy 234.224156 -395.682143) (xy 234.277408 -395.678413)
			(xy 234.33066 -395.682143) (xy 234.382871 -395.69326) (xy 234.433023 -395.711546) (xy 234.480137 -395.736645)
			(xy 234.523291 -395.768067) (xy 234.561645 -395.805197) (xy 234.578398 -395.82598) (xy 234.588295 -395.837785)
			(xy 234.613619 -395.855304) (xy 234.643012 -395.86448) (xy 234.673804 -395.86448) (xy 234.703197 -395.855304)
			(xy 234.728521 -395.837785) (xy 234.738418 -395.82598) (xy 234.756608 -395.803495) (xy 234.798625 -395.763754)
			(xy 234.846159 -395.73081) (xy 234.898121 -395.705419) (xy 234.95332 -395.688161) (xy 235.010491 -395.679433)
			(xy 235.039408 -395.678914) (xy 235.06666 -395.679378) (xy 235.120609 -395.687136) (xy 235.172904 -395.702493)
			(xy 235.222482 -395.725136) (xy 235.268333 -395.754605) (xy 235.309523 -395.790299) (xy 235.345213 -395.831491)
			(xy 235.374678 -395.877344) (xy 235.397318 -395.926924) (xy 235.41267 -395.979221) (xy 235.420424 -396.03317)
			(xy 235.420916 -396.060422) (xy 235.42038 -396.089338) (xy 235.411651 -396.146508) (xy 235.394395 -396.201706)
			(xy 235.369008 -396.253668) (xy 235.336071 -396.301204) (xy 235.296338 -396.343227) (xy 235.27385 -396.361412)
			(xy 235.262045 -396.371307) (xy 235.244527 -396.396628) (xy 235.235353 -396.426019) (xy 235.235357 -396.456808)
			(xy 235.244539 -396.486197) (xy 235.262063 -396.511513) (xy 235.27385 -396.521432) (xy 235.294631 -396.538186)
			(xy 235.331758 -396.576539) (xy 235.363175 -396.619693) (xy 235.388271 -396.666805) (xy 235.406554 -396.716955)
			(xy 235.417668 -396.769165) (xy 235.421396 -396.822414) (xy 235.417664 -396.875662) (xy 235.406547 -396.927871)
			(xy 235.38826 -396.97802) (xy 235.363161 -397.02513) (xy 235.33174 -397.068282) (xy 235.294611 -397.106633)
			(xy 235.27385 -397.123412) (xy 235.262045 -397.133307) (xy 235.244527 -397.158628) (xy 235.235353 -397.188019)
			(xy 235.235357 -397.218808) (xy 235.244539 -397.248197) (xy 235.262063 -397.273513) (xy 235.27385 -397.283432)
			(xy 235.294631 -397.300186) (xy 235.331758 -397.338539) (xy 235.363175 -397.381693) (xy 235.388271 -397.428805)
			(xy 235.406554 -397.478955) (xy 235.417668 -397.531165) (xy 235.421396 -397.584414) (xy 235.417664 -397.637662)
			(xy 235.406547 -397.689871) (xy 235.38826 -397.74002) (xy 235.363161 -397.78713) (xy 235.33174 -397.830282)
			(xy 235.294611 -397.868633) (xy 235.27385 -397.885412) (xy 235.262045 -397.895307) (xy 235.244527 -397.920628)
			(xy 235.235353 -397.950019) (xy 235.235357 -397.980808) (xy 235.244539 -398.010197) (xy 235.262063 -398.035513)
			(xy 235.27385 -398.045432) (xy 235.294631 -398.062186) (xy 235.331758 -398.100539) (xy 235.363175 -398.143693)
			(xy 235.388271 -398.190805) (xy 235.406554 -398.240955) (xy 235.417668 -398.293165) (xy 235.421396 -398.346414)
			(xy 235.417664 -398.399662) (xy 235.406547 -398.451871) (xy 235.38826 -398.50202) (xy 235.363161 -398.54913)
			(xy 235.33174 -398.592282) (xy 235.294611 -398.630633) (xy 235.27385 -398.647412) (xy 235.262045 -398.657307)
			(xy 235.244527 -398.682628) (xy 235.235353 -398.712019) (xy 235.235357 -398.742808) (xy 235.244539 -398.772197)
			(xy 235.262063 -398.797513) (xy 235.27385 -398.807432) (xy 235.294631 -398.824186) (xy 235.331758 -398.862539)
			(xy 235.363175 -398.905693) (xy 235.388271 -398.952805) (xy 235.406554 -399.002955) (xy 235.417668 -399.055165)
			(xy 235.421396 -399.108414) (xy 235.417664 -399.161662) (xy 235.406547 -399.213871) (xy 235.38826 -399.26402)
			(xy 235.363161 -399.31113) (xy 235.33174 -399.354282) (xy 235.294611 -399.392633) (xy 235.27385 -399.409412)
			(xy 235.262045 -399.419307) (xy 235.244527 -399.444628) (xy 235.235353 -399.474019) (xy 235.235357 -399.504808)
			(xy 235.244539 -399.534197) (xy 235.262063 -399.559513) (xy 235.27385 -399.569432) (xy 235.296338 -399.58762)
			(xy 235.336084 -399.629635) (xy 235.369032 -399.677168) (xy 235.394427 -399.72913) (xy 235.411686 -399.784331)
			(xy 235.420414 -399.841504) (xy 235.420916 -399.870422) (xy 235.420783 -399.88329) (xy 235.419006 -399.908967)
			(xy 235.41736 -399.92173) (xy 235.415959 -399.936124) (xy 235.420336 -399.964698) (xy 235.432543 -399.990901)
			(xy 235.451602 -400.012636) (xy 235.475987 -400.02816) (xy 235.503744 -400.036232) (xy 235.518198 -400.036792)
			(xy 237.111286 -400.036792) (xy 237.137266 -400.037291) (xy 237.188582 -400.045455) (xy 237.237987 -400.061554)
			(xy 237.284262 -400.085189) (xy 237.326265 -400.115778) (xy 237.344966 -400.13382) (xy 238.516414 -401.305014)
			(xy 238.528606 -401.308824) (xy 238.554345 -401.317145) (xy 238.603354 -401.340038) (xy 238.648638 -401.369624)
			(xy 238.689289 -401.405311) (xy 238.724492 -401.446381) (xy 238.753539 -401.492013) (xy 238.77585 -401.54129)
			(xy 238.790976 -401.593225) (xy 238.798614 -401.646776) (xy 238.799116 -401.673822) (xy 238.798629 -401.701072)
			(xy 238.79087 -401.755018) (xy 238.775513 -401.807311) (xy 238.75287 -401.856886) (xy 238.723404 -401.902734)
			(xy 238.687712 -401.943922) (xy 238.646523 -401.979612) (xy 238.600673 -402.009077) (xy 238.551098 -402.031718)
			(xy 238.498805 -402.047073) (xy 238.444858 -402.05483) (xy 238.417608 -402.05533) (xy 238.39056 -402.054859)
			(xy 238.337005 -402.047219) (xy 238.285067 -402.032091) (xy 238.235786 -402.009778) (xy 238.190152 -401.980728)
			(xy 238.149078 -401.945523) (xy 238.113389 -401.904869) (xy 238.0838 -401.859582) (xy 238.060905 -401.810569)
			(xy 238.05261 -401.78482) (xy 238.0488 -401.772628) (xy 236.97438 -400.698208) (xy 229.827328 -400.698208)
			(xy 229.423468 -401.102068) (xy 229.423468 -401.419822) (xy 230.371648 -401.419822) (xy 230.375719 -401.3642)
			(xy 230.387845 -401.309763) (xy 230.407768 -401.257672) (xy 230.435064 -401.209037) (xy 230.46915 -401.164894)
			(xy 230.509299 -401.126185) (xy 230.554657 -401.093734) (xy 230.604257 -401.068233) (xy 230.657041 -401.050226)
			(xy 230.711884 -401.040096) (xy 230.767618 -401.038059) (xy 230.823055 -401.044159) (xy 230.877012 -401.058265)
			(xy 230.928341 -401.080077) (xy 230.975947 -401.109131) (xy 231.018815 -401.144806) (xy 231.056032 -401.186343)
			(xy 231.086805 -401.232856) (xy 231.110477 -401.283353) (xy 231.126545 -401.33676) (xy 231.134665 -401.391936)
			(xy 231.135174 -401.419822) (xy 231.794048 -401.419822) (xy 231.798119 -401.3642) (xy 231.810245 -401.309763)
			(xy 231.830168 -401.257672) (xy 231.857464 -401.209037) (xy 231.89155 -401.164894) (xy 231.931699 -401.126185)
			(xy 231.977057 -401.093734) (xy 232.026657 -401.068233) (xy 232.079441 -401.050226) (xy 232.134284 -401.040096)
			(xy 232.190018 -401.038059) (xy 232.245455 -401.044159) (xy 232.299412 -401.058265) (xy 232.350741 -401.080077)
			(xy 232.398347 -401.109131) (xy 232.441215 -401.144806) (xy 232.478432 -401.186343) (xy 232.509205 -401.232856)
			(xy 232.532877 -401.283353) (xy 232.548945 -401.33676) (xy 232.557065 -401.391936) (xy 232.557574 -401.419822)
			(xy 233.191048 -401.419822) (xy 233.195119 -401.3642) (xy 233.207245 -401.309763) (xy 233.227168 -401.257672)
			(xy 233.254464 -401.209037) (xy 233.28855 -401.164894) (xy 233.328699 -401.126185) (xy 233.374057 -401.093734)
			(xy 233.423657 -401.068233) (xy 233.476441 -401.050226) (xy 233.531284 -401.040096) (xy 233.587018 -401.038059)
			(xy 233.642455 -401.044159) (xy 233.696412 -401.058265) (xy 233.747741 -401.080077) (xy 233.795347 -401.109131)
			(xy 233.838215 -401.144806) (xy 233.875432 -401.186343) (xy 233.906205 -401.232856) (xy 233.929877 -401.283353)
			(xy 233.945945 -401.33676) (xy 233.954065 -401.391936) (xy 233.954574 -401.419822) (xy 233.954065 -401.447708)
			(xy 233.945945 -401.502884) (xy 233.929877 -401.556291) (xy 233.906205 -401.606788) (xy 233.875432 -401.653301)
			(xy 233.838215 -401.694838) (xy 233.795347 -401.730513) (xy 233.747741 -401.759567) (xy 233.696412 -401.781379)
			(xy 233.642455 -401.795485) (xy 233.587018 -401.801585) (xy 233.531284 -401.799548) (xy 233.476441 -401.789418)
			(xy 233.423657 -401.771411) (xy 233.374057 -401.74591) (xy 233.328699 -401.713459) (xy 233.28855 -401.67475)
			(xy 233.254464 -401.630607) (xy 233.227168 -401.581972) (xy 233.207245 -401.529881) (xy 233.195119 -401.475444)
			(xy 233.191048 -401.419822) (xy 232.557574 -401.419822) (xy 232.557065 -401.447708) (xy 232.548945 -401.502884)
			(xy 232.532877 -401.556291) (xy 232.509205 -401.606788) (xy 232.478432 -401.653301) (xy 232.441215 -401.694838)
			(xy 232.398347 -401.730513) (xy 232.350741 -401.759567) (xy 232.299412 -401.781379) (xy 232.245455 -401.795485)
			(xy 232.190018 -401.801585) (xy 232.134284 -401.799548) (xy 232.079441 -401.789418) (xy 232.026657 -401.771411)
			(xy 231.977057 -401.74591) (xy 231.931699 -401.713459) (xy 231.89155 -401.67475) (xy 231.857464 -401.630607)
			(xy 231.830168 -401.581972) (xy 231.810245 -401.529881) (xy 231.798119 -401.475444) (xy 231.794048 -401.419822)
			(xy 231.135174 -401.419822) (xy 231.134665 -401.447708) (xy 231.126545 -401.502884) (xy 231.110477 -401.556291)
			(xy 231.086805 -401.606788) (xy 231.056032 -401.653301) (xy 231.018815 -401.694838) (xy 230.975947 -401.730513)
			(xy 230.928341 -401.759567) (xy 230.877012 -401.781379) (xy 230.823055 -401.795485) (xy 230.767618 -401.801585)
			(xy 230.711884 -401.799548) (xy 230.657041 -401.789418) (xy 230.604257 -401.771411) (xy 230.554657 -401.74591)
			(xy 230.509299 -401.713459) (xy 230.46915 -401.67475) (xy 230.435064 -401.630607) (xy 230.407768 -401.581972)
			(xy 230.387845 -401.529881) (xy 230.375719 -401.475444) (xy 230.371648 -401.419822) (xy 229.423468 -401.419822)
			(xy 229.423468 -402.39442) (xy 229.422967 -402.4204) (xy 229.414799 -402.471714) (xy 229.398699 -402.521117)
			(xy 229.375064 -402.567391) (xy 229.344476 -402.609394) (xy 229.32644 -402.6281) (xy 229.24008 -402.71446)
			(xy 229.231372 -402.722842) (xy 230.371648 -402.722842) (xy 230.375719 -402.66722) (xy 230.387845 -402.612783)
			(xy 230.407768 -402.560692) (xy 230.435064 -402.512057) (xy 230.46915 -402.467914) (xy 230.509299 -402.429205)
			(xy 230.554657 -402.396754) (xy 230.604257 -402.371253) (xy 230.657041 -402.353246) (xy 230.711884 -402.343116)
			(xy 230.767618 -402.341079) (xy 230.823055 -402.347179) (xy 230.877012 -402.361285) (xy 230.928341 -402.383097)
			(xy 230.975947 -402.412151) (xy 231.018815 -402.447826) (xy 231.056032 -402.489363) (xy 231.086805 -402.535876)
			(xy 231.110477 -402.586373) (xy 231.126545 -402.63978) (xy 231.134665 -402.694956) (xy 231.135174 -402.722842)
			(xy 233.191048 -402.722842) (xy 233.195119 -402.66722) (xy 233.207245 -402.612783) (xy 233.227168 -402.560692)
			(xy 233.254464 -402.512057) (xy 233.28855 -402.467914) (xy 233.328699 -402.429205) (xy 233.374057 -402.396754)
			(xy 233.423657 -402.371253) (xy 233.476441 -402.353246) (xy 233.531284 -402.343116) (xy 233.587018 -402.341079)
			(xy 233.642455 -402.347179) (xy 233.696412 -402.361285) (xy 233.747741 -402.383097) (xy 233.795347 -402.412151)
			(xy 233.838215 -402.447826) (xy 233.860687 -402.472906) (xy 235.36859 -402.472906) (xy 235.372661 -402.417284)
			(xy 235.384787 -402.362847) (xy 235.40471 -402.310756) (xy 235.432006 -402.262121) (xy 235.466092 -402.217978)
			(xy 235.506241 -402.179269) (xy 235.551599 -402.146818) (xy 235.601199 -402.121317) (xy 235.653983 -402.10331)
			(xy 235.708826 -402.09318) (xy 235.76456 -402.091143) (xy 235.819997 -402.097243) (xy 235.873954 -402.111349)
			(xy 235.925283 -402.133161) (xy 235.972889 -402.162215) (xy 236.015757 -402.19789) (xy 236.052974 -402.239427)
			(xy 236.083747 -402.28594) (xy 236.107419 -402.336437) (xy 236.123487 -402.389844) (xy 236.131607 -402.44502)
			(xy 236.132116 -402.472906) (xy 236.131607 -402.500792) (xy 236.123487 -402.555968) (xy 236.107419 -402.609375)
			(xy 236.083747 -402.659872) (xy 236.052974 -402.706385) (xy 236.015757 -402.747922) (xy 235.972889 -402.783597)
			(xy 235.925283 -402.812651) (xy 235.873954 -402.834463) (xy 235.819997 -402.848569) (xy 235.76456 -402.854669)
			(xy 235.708826 -402.852632) (xy 235.653983 -402.842502) (xy 235.601199 -402.824495) (xy 235.551599 -402.798994)
			(xy 235.506241 -402.766543) (xy 235.466092 -402.727834) (xy 235.432006 -402.683691) (xy 235.40471 -402.635056)
			(xy 235.384787 -402.582965) (xy 235.372661 -402.528528) (xy 235.36859 -402.472906) (xy 233.860687 -402.472906)
			(xy 233.875432 -402.489363) (xy 233.906205 -402.535876) (xy 233.929877 -402.586373) (xy 233.945945 -402.63978)
			(xy 233.954065 -402.694956) (xy 233.954574 -402.722842) (xy 233.954065 -402.750728) (xy 233.945945 -402.805904)
			(xy 233.929877 -402.859311) (xy 233.906205 -402.909808) (xy 233.875432 -402.956321) (xy 233.838215 -402.997858)
			(xy 233.795347 -403.033533) (xy 233.747741 -403.062587) (xy 233.696412 -403.084399) (xy 233.642455 -403.098505)
			(xy 233.587018 -403.104605) (xy 233.531284 -403.102568) (xy 233.476441 -403.092438) (xy 233.423657 -403.074431)
			(xy 233.374057 -403.04893) (xy 233.328699 -403.016479) (xy 233.28855 -402.97777) (xy 233.254464 -402.933627)
			(xy 233.227168 -402.884992) (xy 233.207245 -402.832901) (xy 233.195119 -402.778464) (xy 233.191048 -402.722842)
			(xy 231.135174 -402.722842) (xy 231.134665 -402.750728) (xy 231.126545 -402.805904) (xy 231.110477 -402.859311)
			(xy 231.086805 -402.909808) (xy 231.056032 -402.956321) (xy 231.018815 -402.997858) (xy 230.975947 -403.033533)
			(xy 230.928341 -403.062587) (xy 230.877012 -403.084399) (xy 230.823055 -403.098505) (xy 230.767618 -403.104605)
			(xy 230.711884 -403.102568) (xy 230.657041 -403.092438) (xy 230.604257 -403.074431) (xy 230.554657 -403.04893)
			(xy 230.509299 -403.016479) (xy 230.46915 -402.97777) (xy 230.435064 -402.933627) (xy 230.407768 -402.884992)
			(xy 230.387845 -402.832901) (xy 230.375719 -402.778464) (xy 230.371648 -402.722842) (xy 229.231372 -402.722842)
			(xy 229.221361 -402.732479) (xy 229.179349 -402.763046) (xy 229.133077 -402.786674) (xy 229.083682 -402.802784)
			(xy 229.032377 -402.810978) (xy 229.0064 -402.811488) (xy 228.192838 -402.811488) (xy 228.178256 -402.811954)
			(xy 228.150276 -402.820182) (xy 228.12576 -402.835979) (xy 228.106705 -402.858058) (xy 228.094663 -402.88462)
			(xy 228.090615 -402.913502) (xy 228.09489 -402.942351) (xy 228.100636 -402.95576) (xy 228.111855 -402.981063)
			(xy 228.127687 -403.034099) (xy 228.135684 -403.088868) (xy 228.136196 -403.116542) (xy 228.13571 -403.143793)
			(xy 228.127954 -403.197741) (xy 228.112599 -403.250036) (xy 228.089957 -403.299613) (xy 228.060491 -403.345463)
			(xy 228.0248 -403.386654) (xy 227.983609 -403.422345) (xy 227.937759 -403.451811) (xy 227.888182 -403.474453)
			(xy 227.835887 -403.489808) (xy 227.781939 -403.497564) (xy 227.727437 -403.497564) (xy 227.673489 -403.489808)
			(xy 227.621194 -403.474453) (xy 227.571617 -403.451811) (xy 227.525767 -403.422345) (xy 227.484576 -403.386654)
			(xy 227.448885 -403.345463) (xy 227.419419 -403.299613) (xy 227.396777 -403.250036) (xy 227.381422 -403.197741)
			(xy 227.373666 -403.143793) (xy 227.37318 -403.116542) (xy 227.373616 -403.090282) (xy 227.380818 -403.038257)
			(xy 227.395092 -402.987714) (xy 227.416167 -402.939607) (xy 227.443645 -402.894848) (xy 227.477006 -402.854284)
			(xy 227.515618 -402.818682) (xy 227.558751 -402.788716) (xy 227.581968 -402.776436) (xy 227.594003 -402.769829)
			(xy 227.614288 -402.751345) (xy 227.628918 -402.728127) (xy 227.636835 -402.70185) (xy 227.637467 -402.674414)
			(xy 227.63077 -402.6478) (xy 227.617226 -402.623932) (xy 227.607876 -402.613876) (xy 227.515928 -402.521928)
			(xy 227.497913 -402.503207) (xy 227.467353 -402.461193) (xy 227.443733 -402.414921) (xy 227.427632 -402.365527)
			(xy 227.419446 -402.314223) (xy 227.4189 -402.288248) (xy 227.4189 -401.08251) (xy 227.385372 -401.070318)
			(xy 227.362782 -401.06167) (xy 227.320182 -401.03876) (xy 227.28137 -401.009895) (xy 227.26396 -400.993102)
			(xy 226.976432 -400.705828) (xy 219.438728 -400.705828) (xy 219.248228 -400.896328) (xy 219.248228 -401.419822)
			(xy 219.703648 -401.419822) (xy 219.707719 -401.3642) (xy 219.719845 -401.309763) (xy 219.739768 -401.257672)
			(xy 219.767064 -401.209037) (xy 219.80115 -401.164894) (xy 219.841299 -401.126185) (xy 219.886657 -401.093734)
			(xy 219.936257 -401.068233) (xy 219.989041 -401.050226) (xy 220.043884 -401.040096) (xy 220.099618 -401.038059)
			(xy 220.155055 -401.044159) (xy 220.209012 -401.058265) (xy 220.260341 -401.080077) (xy 220.307947 -401.109131)
			(xy 220.350815 -401.144806) (xy 220.388032 -401.186343) (xy 220.418805 -401.232856) (xy 220.442477 -401.283353)
			(xy 220.458545 -401.33676) (xy 220.466665 -401.391936) (xy 220.467174 -401.419822) (xy 221.126048 -401.419822)
			(xy 221.130119 -401.3642) (xy 221.142245 -401.309763) (xy 221.162168 -401.257672) (xy 221.189464 -401.209037)
			(xy 221.22355 -401.164894) (xy 221.263699 -401.126185) (xy 221.309057 -401.093734) (xy 221.358657 -401.068233)
			(xy 221.411441 -401.050226) (xy 221.466284 -401.040096) (xy 221.522018 -401.038059) (xy 221.577455 -401.044159)
			(xy 221.631412 -401.058265) (xy 221.682741 -401.080077) (xy 221.730347 -401.109131) (xy 221.773215 -401.144806)
			(xy 221.810432 -401.186343) (xy 221.841205 -401.232856) (xy 221.864877 -401.283353) (xy 221.880945 -401.33676)
			(xy 221.889065 -401.391936) (xy 221.889574 -401.419822) (xy 222.523048 -401.419822) (xy 222.527119 -401.3642)
			(xy 222.539245 -401.309763) (xy 222.559168 -401.257672) (xy 222.586464 -401.209037) (xy 222.62055 -401.164894)
			(xy 222.660699 -401.126185) (xy 222.706057 -401.093734) (xy 222.755657 -401.068233) (xy 222.808441 -401.050226)
			(xy 222.863284 -401.040096) (xy 222.919018 -401.038059) (xy 222.974455 -401.044159) (xy 223.028412 -401.058265)
			(xy 223.079741 -401.080077) (xy 223.127347 -401.109131) (xy 223.170215 -401.144806) (xy 223.207432 -401.186343)
			(xy 223.238205 -401.232856) (xy 223.261877 -401.283353) (xy 223.277945 -401.33676) (xy 223.286065 -401.391936)
			(xy 223.286574 -401.419822) (xy 223.286065 -401.447708) (xy 223.277945 -401.502884) (xy 223.261877 -401.556291)
			(xy 223.238205 -401.606788) (xy 223.207432 -401.653301) (xy 223.170215 -401.694838) (xy 223.127347 -401.730513)
			(xy 223.079741 -401.759567) (xy 223.028412 -401.781379) (xy 222.974455 -401.795485) (xy 222.919018 -401.801585)
			(xy 222.863284 -401.799548) (xy 222.808441 -401.789418) (xy 222.755657 -401.771411) (xy 222.706057 -401.74591)
			(xy 222.660699 -401.713459) (xy 222.62055 -401.67475) (xy 222.586464 -401.630607) (xy 222.559168 -401.581972)
			(xy 222.539245 -401.529881) (xy 222.527119 -401.475444) (xy 222.523048 -401.419822) (xy 221.889574 -401.419822)
			(xy 221.889065 -401.447708) (xy 221.880945 -401.502884) (xy 221.864877 -401.556291) (xy 221.841205 -401.606788)
			(xy 221.810432 -401.653301) (xy 221.773215 -401.694838) (xy 221.730347 -401.730513) (xy 221.682741 -401.759567)
			(xy 221.631412 -401.781379) (xy 221.577455 -401.795485) (xy 221.522018 -401.801585) (xy 221.466284 -401.799548)
			(xy 221.411441 -401.789418) (xy 221.358657 -401.771411) (xy 221.309057 -401.74591) (xy 221.263699 -401.713459)
			(xy 221.22355 -401.67475) (xy 221.189464 -401.630607) (xy 221.162168 -401.581972) (xy 221.142245 -401.529881)
			(xy 221.130119 -401.475444) (xy 221.126048 -401.419822) (xy 220.467174 -401.419822) (xy 220.466665 -401.447708)
			(xy 220.458545 -401.502884) (xy 220.442477 -401.556291) (xy 220.418805 -401.606788) (xy 220.388032 -401.653301)
			(xy 220.350815 -401.694838) (xy 220.307947 -401.730513) (xy 220.260341 -401.759567) (xy 220.209012 -401.781379)
			(xy 220.155055 -401.795485) (xy 220.099618 -401.801585) (xy 220.043884 -401.799548) (xy 219.989041 -401.789418)
			(xy 219.936257 -401.771411) (xy 219.886657 -401.74591) (xy 219.841299 -401.713459) (xy 219.80115 -401.67475)
			(xy 219.767064 -401.630607) (xy 219.739768 -401.581972) (xy 219.719845 -401.529881) (xy 219.707719 -401.475444)
			(xy 219.703648 -401.419822) (xy 219.248228 -401.419822) (xy 219.248228 -401.89912) (xy 219.247727 -401.925099)
			(xy 219.239558 -401.976413) (xy 219.223456 -402.025815) (xy 219.199819 -402.072087) (xy 219.169229 -402.114087)
			(xy 219.1512 -402.1328) (xy 218.561158 -402.722842) (xy 219.703648 -402.722842) (xy 219.707719 -402.66722)
			(xy 219.719845 -402.612783) (xy 219.739768 -402.560692) (xy 219.767064 -402.512057) (xy 219.80115 -402.467914)
			(xy 219.841299 -402.429205) (xy 219.886657 -402.396754) (xy 219.936257 -402.371253) (xy 219.989041 -402.353246)
			(xy 220.043884 -402.343116) (xy 220.099618 -402.341079) (xy 220.155055 -402.347179) (xy 220.209012 -402.361285)
			(xy 220.260341 -402.383097) (xy 220.307947 -402.412151) (xy 220.350815 -402.447826) (xy 220.388032 -402.489363)
			(xy 220.418805 -402.535876) (xy 220.442477 -402.586373) (xy 220.458545 -402.63978) (xy 220.466665 -402.694956)
			(xy 220.467174 -402.722842) (xy 222.523048 -402.722842) (xy 222.527119 -402.66722) (xy 222.539245 -402.612783)
			(xy 222.559168 -402.560692) (xy 222.586464 -402.512057) (xy 222.62055 -402.467914) (xy 222.660699 -402.429205)
			(xy 222.706057 -402.396754) (xy 222.755657 -402.371253) (xy 222.808441 -402.353246) (xy 222.863284 -402.343116)
			(xy 222.919018 -402.341079) (xy 222.974455 -402.347179) (xy 223.028412 -402.361285) (xy 223.079741 -402.383097)
			(xy 223.127347 -402.412151) (xy 223.170215 -402.447826) (xy 223.207432 -402.489363) (xy 223.238205 -402.535876)
			(xy 223.261877 -402.586373) (xy 223.277945 -402.63978) (xy 223.286065 -402.694956) (xy 223.286574 -402.722842)
			(xy 223.286065 -402.750728) (xy 223.277945 -402.805904) (xy 223.261877 -402.859311) (xy 223.238205 -402.909808)
			(xy 223.207432 -402.956321) (xy 223.170215 -402.997858) (xy 223.127347 -403.033533) (xy 223.079741 -403.062587)
			(xy 223.028412 -403.084399) (xy 222.974455 -403.098505) (xy 222.919018 -403.104605) (xy 222.863284 -403.102568)
			(xy 222.808441 -403.092438) (xy 222.755657 -403.074431) (xy 222.706057 -403.04893) (xy 222.660699 -403.016479)
			(xy 222.62055 -402.97777) (xy 222.586464 -402.933627) (xy 222.559168 -402.884992) (xy 222.539245 -402.832901)
			(xy 222.527119 -402.778464) (xy 222.523048 -402.722842) (xy 220.467174 -402.722842) (xy 220.466665 -402.750728)
			(xy 220.458545 -402.805904) (xy 220.442477 -402.859311) (xy 220.418805 -402.909808) (xy 220.388032 -402.956321)
			(xy 220.350815 -402.997858) (xy 220.307947 -403.033533) (xy 220.260341 -403.062587) (xy 220.209012 -403.084399)
			(xy 220.155055 -403.098505) (xy 220.099618 -403.104605) (xy 220.043884 -403.102568) (xy 219.989041 -403.092438)
			(xy 219.936257 -403.074431) (xy 219.886657 -403.04893) (xy 219.841299 -403.016479) (xy 219.80115 -402.97777)
			(xy 219.767064 -402.933627) (xy 219.739768 -402.884992) (xy 219.719845 -402.832901) (xy 219.707719 -402.778464)
			(xy 219.703648 -402.722842) (xy 218.561158 -402.722842) (xy 218.52636 -402.75764) (xy 218.507641 -402.775659)
			(xy 218.465629 -402.806225) (xy 218.419357 -402.829852) (xy 218.369962 -402.845959) (xy 218.318657 -402.854151)
			(xy 218.29268 -402.854668) (xy 217.57767 -402.854668) (xy 217.564203 -402.855035) (xy 217.538185 -402.861996)
			(xy 217.5149 -402.875528) (xy 217.495973 -402.894688) (xy 217.482725 -402.918136) (xy 217.476083 -402.944236)
			(xy 217.47651 -402.971165) (xy 217.47988 -402.984208) (xy 217.486882 -403.010061) (xy 217.494404 -403.063092)
			(xy 217.494866 -403.089872) (xy 217.49438 -403.117123) (xy 217.486624 -403.171071) (xy 217.471269 -403.223366)
			(xy 217.448627 -403.272943) (xy 217.419161 -403.318793) (xy 217.38347 -403.359984) (xy 217.342279 -403.395675)
			(xy 217.296429 -403.425141) (xy 217.246852 -403.447783) (xy 217.194557 -403.463138) (xy 217.140609 -403.470894)
			(xy 217.086107 -403.470894) (xy 217.032159 -403.463138) (xy 216.979864 -403.447783) (xy 216.930287 -403.425141)
			(xy 216.884437 -403.395675) (xy 216.843246 -403.359984) (xy 216.807555 -403.318793) (xy 216.778089 -403.272943)
			(xy 216.755447 -403.223366) (xy 216.740092 -403.171071) (xy 216.732336 -403.117123) (xy 216.73185 -403.089872)
			(xy 216.73231 -403.062598) (xy 216.740072 -403.008606) (xy 216.755447 -402.956271) (xy 216.778123 -402.90666)
			(xy 216.807635 -402.860786) (xy 216.843383 -402.819586) (xy 216.884636 -402.783899) (xy 216.907364 -402.768816)
			(xy 216.919832 -402.760165) (xy 216.939446 -402.73703) (xy 216.951411 -402.70916) (xy 216.954675 -402.679005)
			(xy 216.94895 -402.64922) (xy 216.934741 -402.622424) (xy 216.924382 -402.611336) (xy 216.847928 -402.534628)
			(xy 216.829913 -402.515907) (xy 216.799353 -402.473893) (xy 216.775733 -402.427621) (xy 216.759632 -402.378227)
			(xy 216.751446 -402.326923) (xy 216.7509 -402.300948) (xy 216.7509 -400.949922) (xy 216.740362 -400.930952)
			(xy 216.723179 -400.891102) (xy 216.71661 -400.87042) (xy 216.7128 -400.858228) (xy 216.57564 -400.721068)
			(xy 208.501488 -400.721068) (xy 208.501488 -401.419822) (xy 209.035648 -401.419822) (xy 209.039719 -401.3642)
			(xy 209.051845 -401.309763) (xy 209.071768 -401.257672) (xy 209.099064 -401.209037) (xy 209.13315 -401.164894)
			(xy 209.173299 -401.126185) (xy 209.218657 -401.093734) (xy 209.268257 -401.068233) (xy 209.321041 -401.050226)
			(xy 209.375884 -401.040096) (xy 209.431618 -401.038059) (xy 209.487055 -401.044159) (xy 209.541012 -401.058265)
			(xy 209.592341 -401.080077) (xy 209.639947 -401.109131) (xy 209.682815 -401.144806) (xy 209.720032 -401.186343)
			(xy 209.750805 -401.232856) (xy 209.774477 -401.283353) (xy 209.790545 -401.33676) (xy 209.798665 -401.391936)
			(xy 209.799174 -401.419822) (xy 210.458048 -401.419822) (xy 210.462119 -401.3642) (xy 210.474245 -401.309763)
			(xy 210.494168 -401.257672) (xy 210.521464 -401.209037) (xy 210.55555 -401.164894) (xy 210.595699 -401.126185)
			(xy 210.641057 -401.093734) (xy 210.690657 -401.068233) (xy 210.743441 -401.050226) (xy 210.798284 -401.040096)
			(xy 210.854018 -401.038059) (xy 210.909455 -401.044159) (xy 210.963412 -401.058265) (xy 211.014741 -401.080077)
			(xy 211.062347 -401.109131) (xy 211.105215 -401.144806) (xy 211.142432 -401.186343) (xy 211.173205 -401.232856)
			(xy 211.196877 -401.283353) (xy 211.212945 -401.33676) (xy 211.221065 -401.391936) (xy 211.221574 -401.419822)
			(xy 211.855048 -401.419822) (xy 211.859119 -401.3642) (xy 211.871245 -401.309763) (xy 211.891168 -401.257672)
			(xy 211.918464 -401.209037) (xy 211.95255 -401.164894) (xy 211.992699 -401.126185) (xy 212.038057 -401.093734)
			(xy 212.087657 -401.068233) (xy 212.140441 -401.050226) (xy 212.195284 -401.040096) (xy 212.251018 -401.038059)
			(xy 212.306455 -401.044159) (xy 212.360412 -401.058265) (xy 212.411741 -401.080077) (xy 212.459347 -401.109131)
			(xy 212.502215 -401.144806) (xy 212.539432 -401.186343) (xy 212.570205 -401.232856) (xy 212.593877 -401.283353)
			(xy 212.609945 -401.33676) (xy 212.618065 -401.391936) (xy 212.618574 -401.419822) (xy 212.618065 -401.447708)
			(xy 212.609945 -401.502884) (xy 212.593877 -401.556291) (xy 212.570205 -401.606788) (xy 212.539432 -401.653301)
			(xy 212.502215 -401.694838) (xy 212.459347 -401.730513) (xy 212.411741 -401.759567) (xy 212.360412 -401.781379)
			(xy 212.306455 -401.795485) (xy 212.251018 -401.801585) (xy 212.195284 -401.799548) (xy 212.140441 -401.789418)
			(xy 212.087657 -401.771411) (xy 212.038057 -401.74591) (xy 211.992699 -401.713459) (xy 211.95255 -401.67475)
			(xy 211.918464 -401.630607) (xy 211.891168 -401.581972) (xy 211.871245 -401.529881) (xy 211.859119 -401.475444)
			(xy 211.855048 -401.419822) (xy 211.221574 -401.419822) (xy 211.221065 -401.447708) (xy 211.212945 -401.502884)
			(xy 211.196877 -401.556291) (xy 211.173205 -401.606788) (xy 211.142432 -401.653301) (xy 211.105215 -401.694838)
			(xy 211.062347 -401.730513) (xy 211.014741 -401.759567) (xy 210.963412 -401.781379) (xy 210.909455 -401.795485)
			(xy 210.854018 -401.801585) (xy 210.798284 -401.799548) (xy 210.743441 -401.789418) (xy 210.690657 -401.771411)
			(xy 210.641057 -401.74591) (xy 210.595699 -401.713459) (xy 210.55555 -401.67475) (xy 210.521464 -401.630607)
			(xy 210.494168 -401.581972) (xy 210.474245 -401.529881) (xy 210.462119 -401.475444) (xy 210.458048 -401.419822)
			(xy 209.799174 -401.419822) (xy 209.798665 -401.447708) (xy 209.790545 -401.502884) (xy 209.774477 -401.556291)
			(xy 209.750805 -401.606788) (xy 209.720032 -401.653301) (xy 209.682815 -401.694838) (xy 209.639947 -401.730513)
			(xy 209.592341 -401.759567) (xy 209.541012 -401.781379) (xy 209.487055 -401.795485) (xy 209.431618 -401.801585)
			(xy 209.375884 -401.799548) (xy 209.321041 -401.789418) (xy 209.268257 -401.771411) (xy 209.218657 -401.74591)
			(xy 209.173299 -401.713459) (xy 209.13315 -401.67475) (xy 209.099064 -401.630607) (xy 209.071768 -401.581972)
			(xy 209.051845 -401.529881) (xy 209.039719 -401.475444) (xy 209.035648 -401.419822) (xy 208.501488 -401.419822)
			(xy 208.501488 -402.1582) (xy 208.500988 -402.184181) (xy 208.492823 -402.235497) (xy 208.476726 -402.284902)
			(xy 208.453094 -402.331179) (xy 208.422509 -402.373186) (xy 208.40446 -402.39188) (xy 208.073498 -402.722842)
			(xy 209.035648 -402.722842) (xy 209.039719 -402.66722) (xy 209.051845 -402.612783) (xy 209.071768 -402.560692)
			(xy 209.099064 -402.512057) (xy 209.13315 -402.467914) (xy 209.173299 -402.429205) (xy 209.218657 -402.396754)
			(xy 209.268257 -402.371253) (xy 209.321041 -402.353246) (xy 209.375884 -402.343116) (xy 209.431618 -402.341079)
			(xy 209.487055 -402.347179) (xy 209.541012 -402.361285) (xy 209.592341 -402.383097) (xy 209.639947 -402.412151)
			(xy 209.682815 -402.447826) (xy 209.720032 -402.489363) (xy 209.750805 -402.535876) (xy 209.774477 -402.586373)
			(xy 209.790545 -402.63978) (xy 209.798665 -402.694956) (xy 209.799174 -402.722842) (xy 211.855048 -402.722842)
			(xy 211.859119 -402.66722) (xy 211.871245 -402.612783) (xy 211.891168 -402.560692) (xy 211.918464 -402.512057)
			(xy 211.95255 -402.467914) (xy 211.992699 -402.429205) (xy 212.038057 -402.396754) (xy 212.087657 -402.371253)
			(xy 212.140441 -402.353246) (xy 212.195284 -402.343116) (xy 212.251018 -402.341079) (xy 212.306455 -402.347179)
			(xy 212.360412 -402.361285) (xy 212.411741 -402.383097) (xy 212.459347 -402.412151) (xy 212.502215 -402.447826)
			(xy 212.539432 -402.489363) (xy 212.570205 -402.535876) (xy 212.593877 -402.586373) (xy 212.609945 -402.63978)
			(xy 212.618065 -402.694956) (xy 212.618574 -402.722842) (xy 212.618065 -402.750728) (xy 212.609945 -402.805904)
			(xy 212.593877 -402.859311) (xy 212.570205 -402.909808) (xy 212.539432 -402.956321) (xy 212.502215 -402.997858)
			(xy 212.459347 -403.033533) (xy 212.411741 -403.062587) (xy 212.360412 -403.084399) (xy 212.306455 -403.098505)
			(xy 212.251018 -403.104605) (xy 212.195284 -403.102568) (xy 212.140441 -403.092438) (xy 212.087657 -403.074431)
			(xy 212.038057 -403.04893) (xy 211.992699 -403.016479) (xy 211.95255 -402.97777) (xy 211.918464 -402.933627)
			(xy 211.891168 -402.884992) (xy 211.871245 -402.832901) (xy 211.859119 -402.778464) (xy 211.855048 -402.722842)
			(xy 209.799174 -402.722842) (xy 209.798665 -402.750728) (xy 209.790545 -402.805904) (xy 209.774477 -402.859311)
			(xy 209.750805 -402.909808) (xy 209.720032 -402.956321) (xy 209.682815 -402.997858) (xy 209.639947 -403.033533)
			(xy 209.592341 -403.062587) (xy 209.541012 -403.084399) (xy 209.487055 -403.098505) (xy 209.431618 -403.104605)
			(xy 209.375884 -403.102568) (xy 209.321041 -403.092438) (xy 209.268257 -403.074431) (xy 209.218657 -403.04893)
			(xy 209.173299 -403.016479) (xy 209.13315 -402.97777) (xy 209.099064 -402.933627) (xy 209.071768 -402.884992)
			(xy 209.051845 -402.832901) (xy 209.039719 -402.778464) (xy 209.035648 -402.722842) (xy 208.073498 -402.722842)
			(xy 207.9371 -402.85924) (xy 207.918379 -402.877255) (xy 207.876366 -402.907814) (xy 207.830093 -402.931432)
			(xy 207.780698 -402.947531) (xy 207.729395 -402.955713) (xy 207.70342 -402.956268) (xy 206.905606 -402.956268)
			(xy 206.89137 -402.956754) (xy 206.864009 -402.96463) (xy 206.83988 -402.979745) (xy 206.820854 -403.000927)
			(xy 206.808407 -403.026534) (xy 206.803502 -403.054581) (xy 206.804514 -403.06879) (xy 206.80557 -403.079044)
			(xy 206.806713 -403.09963) (xy 206.8068 -403.109938) (xy 206.806314 -403.137189) (xy 206.798558 -403.191137)
			(xy 206.783203 -403.243432) (xy 206.760561 -403.293009) (xy 206.731095 -403.338859) (xy 206.695404 -403.38005)
			(xy 206.654213 -403.415741) (xy 206.608363 -403.445207) (xy 206.558786 -403.467849) (xy 206.506491 -403.483204)
			(xy 206.452543 -403.49096) (xy 206.398041 -403.49096) (xy 206.344093 -403.483204) (xy 206.291798 -403.467849)
			(xy 206.242221 -403.445207) (xy 206.196371 -403.415741) (xy 206.15518 -403.38005) (xy 206.119489 -403.338859)
			(xy 206.090023 -403.293009) (xy 206.067381 -403.243432) (xy 206.052026 -403.191137) (xy 206.04427 -403.137189)
			(xy 206.043784 -403.109938) (xy 206.044269 -403.082764) (xy 206.051993 -403.028967) (xy 206.067275 -402.976811)
			(xy 206.089805 -402.927352) (xy 206.119128 -402.881593) (xy 206.15465 -402.840459) (xy 206.195651 -402.804784)
			(xy 206.2413 -402.77529) (xy 206.26578 -402.763482) (xy 206.278335 -402.757234) (xy 206.299678 -402.73906)
			(xy 206.315279 -402.715769) (xy 206.323961 -402.689114) (xy 206.325071 -402.661103) (xy 206.318526 -402.633845)
			(xy 206.304819 -402.609392) (xy 206.295244 -402.599144) (xy 206.179928 -402.483828) (xy 206.161913 -402.465107)
			(xy 206.131353 -402.423093) (xy 206.107733 -402.376821) (xy 206.091632 -402.327427) (xy 206.083446 -402.276123)
			(xy 206.0829 -402.250148) (xy 206.0829 -400.949922) (xy 206.072362 -400.930952) (xy 206.055179 -400.891102)
			(xy 206.04861 -400.87042) (xy 206.0448 -400.858228) (xy 205.90256 -400.715988) (xy 198.190866 -400.715988)
			(xy 197.673468 -401.233386) (xy 197.673468 -401.419822) (xy 198.367648 -401.419822) (xy 198.371719 -401.3642)
			(xy 198.383845 -401.309763) (xy 198.403768 -401.257672) (xy 198.431064 -401.209037) (xy 198.46515 -401.164894)
			(xy 198.505299 -401.126185) (xy 198.550657 -401.093734) (xy 198.600257 -401.068233) (xy 198.653041 -401.050226)
			(xy 198.707884 -401.040096) (xy 198.763618 -401.038059) (xy 198.819055 -401.044159) (xy 198.873012 -401.058265)
			(xy 198.924341 -401.080077) (xy 198.971947 -401.109131) (xy 199.014815 -401.144806) (xy 199.052032 -401.186343)
			(xy 199.082805 -401.232856) (xy 199.106477 -401.283353) (xy 199.122545 -401.33676) (xy 199.130665 -401.391936)
			(xy 199.131174 -401.419822) (xy 199.790048 -401.419822) (xy 199.794119 -401.3642) (xy 199.806245 -401.309763)
			(xy 199.826168 -401.257672) (xy 199.853464 -401.209037) (xy 199.88755 -401.164894) (xy 199.927699 -401.126185)
			(xy 199.973057 -401.093734) (xy 200.022657 -401.068233) (xy 200.075441 -401.050226) (xy 200.130284 -401.040096)
			(xy 200.186018 -401.038059) (xy 200.241455 -401.044159) (xy 200.295412 -401.058265) (xy 200.346741 -401.080077)
			(xy 200.394347 -401.109131) (xy 200.437215 -401.144806) (xy 200.474432 -401.186343) (xy 200.505205 -401.232856)
			(xy 200.528877 -401.283353) (xy 200.544945 -401.33676) (xy 200.553065 -401.391936) (xy 200.553574 -401.419822)
			(xy 201.187048 -401.419822) (xy 201.191119 -401.3642) (xy 201.203245 -401.309763) (xy 201.223168 -401.257672)
			(xy 201.250464 -401.209037) (xy 201.28455 -401.164894) (xy 201.324699 -401.126185) (xy 201.370057 -401.093734)
			(xy 201.419657 -401.068233) (xy 201.472441 -401.050226) (xy 201.527284 -401.040096) (xy 201.583018 -401.038059)
			(xy 201.638455 -401.044159) (xy 201.692412 -401.058265) (xy 201.743741 -401.080077) (xy 201.791347 -401.109131)
			(xy 201.834215 -401.144806) (xy 201.871432 -401.186343) (xy 201.902205 -401.232856) (xy 201.925877 -401.283353)
			(xy 201.941945 -401.33676) (xy 201.950065 -401.391936) (xy 201.950574 -401.419822) (xy 201.950065 -401.447708)
			(xy 201.941945 -401.502884) (xy 201.925877 -401.556291) (xy 201.902205 -401.606788) (xy 201.871432 -401.653301)
			(xy 201.834215 -401.694838) (xy 201.791347 -401.730513) (xy 201.743741 -401.759567) (xy 201.692412 -401.781379)
			(xy 201.638455 -401.795485) (xy 201.583018 -401.801585) (xy 201.527284 -401.799548) (xy 201.472441 -401.789418)
			(xy 201.419657 -401.771411) (xy 201.370057 -401.74591) (xy 201.324699 -401.713459) (xy 201.28455 -401.67475)
			(xy 201.250464 -401.630607) (xy 201.223168 -401.581972) (xy 201.203245 -401.529881) (xy 201.191119 -401.475444)
			(xy 201.187048 -401.419822) (xy 200.553574 -401.419822) (xy 200.553065 -401.447708) (xy 200.544945 -401.502884)
			(xy 200.528877 -401.556291) (xy 200.505205 -401.606788) (xy 200.474432 -401.653301) (xy 200.437215 -401.694838)
			(xy 200.394347 -401.730513) (xy 200.346741 -401.759567) (xy 200.295412 -401.781379) (xy 200.241455 -401.795485)
			(xy 200.186018 -401.801585) (xy 200.130284 -401.799548) (xy 200.075441 -401.789418) (xy 200.022657 -401.771411)
			(xy 199.973057 -401.74591) (xy 199.927699 -401.713459) (xy 199.88755 -401.67475) (xy 199.853464 -401.630607)
			(xy 199.826168 -401.581972) (xy 199.806245 -401.529881) (xy 199.794119 -401.475444) (xy 199.790048 -401.419822)
			(xy 199.131174 -401.419822) (xy 199.130665 -401.447708) (xy 199.122545 -401.502884) (xy 199.106477 -401.556291)
			(xy 199.082805 -401.606788) (xy 199.052032 -401.653301) (xy 199.014815 -401.694838) (xy 198.971947 -401.730513)
			(xy 198.924341 -401.759567) (xy 198.873012 -401.781379) (xy 198.819055 -401.795485) (xy 198.763618 -401.801585)
			(xy 198.707884 -401.799548) (xy 198.653041 -401.789418) (xy 198.600257 -401.771411) (xy 198.550657 -401.74591)
			(xy 198.505299 -401.713459) (xy 198.46515 -401.67475) (xy 198.431064 -401.630607) (xy 198.403768 -401.581972)
			(xy 198.383845 -401.529881) (xy 198.371719 -401.475444) (xy 198.367648 -401.419822) (xy 197.673468 -401.419822)
			(xy 197.673468 -401.55876) (xy 197.672971 -401.584742) (xy 197.664812 -401.636061) (xy 197.648718 -401.68547)
			(xy 197.625089 -401.73175) (xy 197.594505 -401.77376) (xy 197.57644 -401.79244) (xy 197.08114 -402.28774)
			(xy 197.06242 -402.305757) (xy 197.020408 -402.336321) (xy 196.974135 -402.359945) (xy 196.924741 -402.376049)
			(xy 196.873436 -402.384238) (xy 196.84746 -402.384768) (xy 196.247258 -402.384768) (xy 196.221276 -402.384273)
			(xy 196.169955 -402.376115) (xy 196.120545 -402.360024) (xy 196.074262 -402.336396) (xy 196.03225 -402.305814)
			(xy 196.013578 -402.28774) (xy 194.282314 -400.556476) (xy 191.384174 -400.556476) (xy 190.88862 -401.052284)
			(xy 190.878443 -401.063262) (xy 190.864393 -401.08968) (xy 190.858604 -401.119037) (xy 190.861574 -401.148811)
			(xy 190.873046 -401.176445) (xy 190.892036 -401.199569) (xy 190.916913 -401.216194) (xy 190.945542 -401.224895)
			(xy 190.960502 -401.225512) (xy 192.487804 -401.225512) (xy 192.69964 -401.013676) (xy 192.70345 -401.001484)
			(xy 192.711771 -400.975743) (xy 192.734662 -400.926729) (xy 192.764248 -400.88144) (xy 192.799933 -400.840783)
			(xy 192.841003 -400.805574) (xy 192.886634 -400.776519) (xy 192.935911 -400.7542) (xy 192.987847 -400.739065)
			(xy 193.0414 -400.731417) (xy 193.068448 -400.730974) (xy 193.095697 -400.731463) (xy 193.149641 -400.739225)
			(xy 193.201931 -400.754584) (xy 193.251503 -400.777228) (xy 193.297349 -400.806695) (xy 193.338535 -400.842386)
			(xy 193.374223 -400.883575) (xy 193.403687 -400.929423) (xy 193.426326 -400.978997) (xy 193.441681 -401.031288)
			(xy 193.449439 -401.085232) (xy 193.449956 -401.112482) (xy 193.449485 -401.139529) (xy 193.441846 -401.193082)
			(xy 193.426717 -401.245018) (xy 193.404403 -401.294296) (xy 193.375351 -401.339927) (xy 193.340143 -401.380996)
			(xy 193.299487 -401.41668) (xy 193.254197 -401.446262) (xy 193.205183 -401.469149) (xy 193.179446 -401.47748)
			(xy 193.167254 -401.48129) (xy 192.99936 -401.649184) (xy 192.99936 -401.69719) (xy 192.999847 -401.707616)
			(xy 193.008133 -401.726749) (xy 193.023372 -401.74098) (xy 193.043025 -401.74794) (xy 193.053462 -401.747736)
			(xy 193.078608 -401.746974) (xy 193.105859 -401.74746) (xy 193.159807 -401.755218) (xy 193.212102 -401.770573)
			(xy 193.261679 -401.793215) (xy 193.30753 -401.822681) (xy 193.348721 -401.858372) (xy 193.384413 -401.899562)
			(xy 193.413881 -401.945412) (xy 193.436523 -401.994989) (xy 193.45188 -402.047283) (xy 193.459639 -402.101231)
			(xy 193.460116 -402.128482) (xy 193.459946 -402.146432) (xy 193.456638 -402.182179) (xy 193.453512 -402.199856)
			(xy 193.451274 -402.214574) (xy 193.454443 -402.244162) (xy 193.466 -402.271584) (xy 193.484967 -402.294513)
			(xy 193.509734 -402.311008) (xy 193.538203 -402.319669) (xy 193.55308 -402.320252) (xy 193.903346 -402.320252)
			(xy 193.929328 -402.320748) (xy 193.980648 -402.328906) (xy 194.030057 -402.344998) (xy 194.076338 -402.368628)
			(xy 194.118349 -402.399212) (xy 194.137026 -402.41728) (xy 194.155568 -402.435822) (xy 195.05879 -402.435822)
			(xy 195.062861 -402.3802) (xy 195.074987 -402.325763) (xy 195.09491 -402.273672) (xy 195.122206 -402.225037)
			(xy 195.156292 -402.180894) (xy 195.196441 -402.142185) (xy 195.241799 -402.109734) (xy 195.291399 -402.084233)
			(xy 195.344183 -402.066226) (xy 195.399026 -402.056096) (xy 195.45476 -402.054059) (xy 195.510197 -402.060159)
			(xy 195.564154 -402.074265) (xy 195.615483 -402.096077) (xy 195.663089 -402.125131) (xy 195.705957 -402.160806)
			(xy 195.743174 -402.202343) (xy 195.773947 -402.248856) (xy 195.797619 -402.299353) (xy 195.813687 -402.35276)
			(xy 195.821807 -402.407936) (xy 195.822316 -402.435822) (xy 195.821807 -402.463708) (xy 195.813687 -402.518884)
			(xy 195.797619 -402.572291) (xy 195.773947 -402.622788) (xy 195.743174 -402.669301) (xy 195.705957 -402.710838)
			(xy 195.691533 -402.722842) (xy 198.367648 -402.722842) (xy 198.371719 -402.66722) (xy 198.383845 -402.612783)
			(xy 198.403768 -402.560692) (xy 198.431064 -402.512057) (xy 198.46515 -402.467914) (xy 198.505299 -402.429205)
			(xy 198.550657 -402.396754) (xy 198.600257 -402.371253) (xy 198.653041 -402.353246) (xy 198.707884 -402.343116)
			(xy 198.763618 -402.341079) (xy 198.819055 -402.347179) (xy 198.873012 -402.361285) (xy 198.924341 -402.383097)
			(xy 198.971947 -402.412151) (xy 199.014815 -402.447826) (xy 199.052032 -402.489363) (xy 199.082805 -402.535876)
			(xy 199.106477 -402.586373) (xy 199.122545 -402.63978) (xy 199.130665 -402.694956) (xy 199.131174 -402.722842)
			(xy 201.187048 -402.722842) (xy 201.191119 -402.66722) (xy 201.203245 -402.612783) (xy 201.223168 -402.560692)
			(xy 201.250464 -402.512057) (xy 201.28455 -402.467914) (xy 201.324699 -402.429205) (xy 201.370057 -402.396754)
			(xy 201.419657 -402.371253) (xy 201.472441 -402.353246) (xy 201.527284 -402.343116) (xy 201.583018 -402.341079)
			(xy 201.638455 -402.347179) (xy 201.692412 -402.361285) (xy 201.743741 -402.383097) (xy 201.791347 -402.412151)
			(xy 201.834215 -402.447826) (xy 201.871432 -402.489363) (xy 201.902205 -402.535876) (xy 201.925877 -402.586373)
			(xy 201.941945 -402.63978) (xy 201.950065 -402.694956) (xy 201.950574 -402.722842) (xy 201.950065 -402.750728)
			(xy 201.941945 -402.805904) (xy 201.925877 -402.859311) (xy 201.902205 -402.909808) (xy 201.871432 -402.956321)
			(xy 201.834215 -402.997858) (xy 201.791347 -403.033533) (xy 201.743741 -403.062587) (xy 201.692412 -403.084399)
			(xy 201.638455 -403.098505) (xy 201.583018 -403.104605) (xy 201.527284 -403.102568) (xy 201.472441 -403.092438)
			(xy 201.419657 -403.074431) (xy 201.370057 -403.04893) (xy 201.324699 -403.016479) (xy 201.28455 -402.97777)
			(xy 201.250464 -402.933627) (xy 201.223168 -402.884992) (xy 201.203245 -402.832901) (xy 201.191119 -402.778464)
			(xy 201.187048 -402.722842) (xy 199.131174 -402.722842) (xy 199.130665 -402.750728) (xy 199.122545 -402.805904)
			(xy 199.106477 -402.859311) (xy 199.082805 -402.909808) (xy 199.052032 -402.956321) (xy 199.014815 -402.997858)
			(xy 198.971947 -403.033533) (xy 198.924341 -403.062587) (xy 198.873012 -403.084399) (xy 198.819055 -403.098505)
			(xy 198.763618 -403.104605) (xy 198.707884 -403.102568) (xy 198.653041 -403.092438) (xy 198.600257 -403.074431)
			(xy 198.550657 -403.04893) (xy 198.505299 -403.016479) (xy 198.46515 -402.97777) (xy 198.431064 -402.933627)
			(xy 198.403768 -402.884992) (xy 198.383845 -402.832901) (xy 198.371719 -402.778464) (xy 198.367648 -402.722842)
			(xy 195.691533 -402.722842) (xy 195.663089 -402.746513) (xy 195.615483 -402.775567) (xy 195.564154 -402.797379)
			(xy 195.510197 -402.811485) (xy 195.45476 -402.817585) (xy 195.399026 -402.815548) (xy 195.344183 -402.805418)
			(xy 195.291399 -402.787411) (xy 195.241799 -402.76191) (xy 195.196441 -402.729459) (xy 195.156292 -402.69075)
			(xy 195.122206 -402.646607) (xy 195.09491 -402.597972) (xy 195.074987 -402.545881) (xy 195.062861 -402.491444)
			(xy 195.05879 -402.435822) (xy 194.155568 -402.435822) (xy 195.681398 -403.961652) (xy 196.228177 -403.961652)
			(xy 196.228177 -403.907148) (xy 196.235934 -403.8532) (xy 196.25129 -403.800904) (xy 196.273931 -403.751327)
			(xy 196.303398 -403.705476) (xy 196.339091 -403.664285) (xy 196.380282 -403.628594) (xy 196.426134 -403.599128)
			(xy 196.475712 -403.576487) (xy 196.528008 -403.561132) (xy 196.581956 -403.553377) (xy 196.609208 -403.552914)
			(xy 196.638123 -403.553493) (xy 196.695291 -403.562209) (xy 196.750489 -403.579455) (xy 196.802451 -403.604835)
			(xy 196.849987 -403.637768) (xy 196.892006 -403.677499) (xy 196.910198 -403.69998) (xy 196.919481 -403.711159)
			(xy 196.943048 -403.728137) (xy 196.970445 -403.737787) (xy 196.99945 -403.739326) (xy 197.027714 -403.732631)
			(xy 197.052947 -403.718242) (xy 197.06336 -403.708108) (xy 197.081384 -403.68995) (xy 197.121487 -403.65818)
			(xy 197.165476 -403.632053) (xy 197.212562 -403.61204) (xy 197.261901 -403.598499) (xy 197.312606 -403.591674)
			(xy 197.338188 -403.591268) (xy 197.36544 -403.591778) (xy 197.419389 -403.599534) (xy 197.471685 -403.614888)
			(xy 197.521263 -403.637528) (xy 197.567115 -403.666994) (xy 197.608306 -403.702685) (xy 197.643999 -403.743876)
			(xy 197.673466 -403.789726) (xy 197.696108 -403.839304) (xy 197.711464 -403.8916) (xy 197.719221 -403.945548)
			(xy 197.719221 -404.000052) (xy 197.71551 -404.025862) (xy 198.367648 -404.025862) (xy 198.371719 -403.97024)
			(xy 198.383845 -403.915803) (xy 198.403768 -403.863712) (xy 198.431064 -403.815077) (xy 198.46515 -403.770934)
			(xy 198.505299 -403.732225) (xy 198.550657 -403.699774) (xy 198.600257 -403.674273) (xy 198.653041 -403.656266)
			(xy 198.707884 -403.646136) (xy 198.763618 -403.644099) (xy 198.819055 -403.650199) (xy 198.873012 -403.664305)
			(xy 198.924341 -403.686117) (xy 198.971947 -403.715171) (xy 199.014815 -403.750846) (xy 199.052032 -403.792383)
			(xy 199.082805 -403.838896) (xy 199.106477 -403.889393) (xy 199.122545 -403.9428) (xy 199.130665 -403.997976)
			(xy 199.131174 -404.025862) (xy 199.790048 -404.025862) (xy 199.794119 -403.97024) (xy 199.806245 -403.915803)
			(xy 199.826168 -403.863712) (xy 199.853464 -403.815077) (xy 199.88755 -403.770934) (xy 199.927699 -403.732225)
			(xy 199.973057 -403.699774) (xy 200.022657 -403.674273) (xy 200.075441 -403.656266) (xy 200.130284 -403.646136)
			(xy 200.186018 -403.644099) (xy 200.241455 -403.650199) (xy 200.295412 -403.664305) (xy 200.346741 -403.686117)
			(xy 200.394347 -403.715171) (xy 200.437215 -403.750846) (xy 200.474432 -403.792383) (xy 200.505205 -403.838896)
			(xy 200.528877 -403.889393) (xy 200.544945 -403.9428) (xy 200.553065 -403.997976) (xy 200.553574 -404.025862)
			(xy 201.187048 -404.025862) (xy 201.191119 -403.97024) (xy 201.203245 -403.915803) (xy 201.223168 -403.863712)
			(xy 201.250464 -403.815077) (xy 201.28455 -403.770934) (xy 201.324699 -403.732225) (xy 201.370057 -403.699774)
			(xy 201.419657 -403.674273) (xy 201.472441 -403.656266) (xy 201.527284 -403.646136) (xy 201.583018 -403.644099)
			(xy 201.638455 -403.650199) (xy 201.692412 -403.664305) (xy 201.743741 -403.686117) (xy 201.791347 -403.715171)
			(xy 201.834215 -403.750846) (xy 201.871432 -403.792383) (xy 201.902205 -403.838896) (xy 201.925877 -403.889393)
			(xy 201.941945 -403.9428) (xy 201.950065 -403.997976) (xy 201.950574 -404.025862) (xy 201.950065 -404.053748)
			(xy 201.941945 -404.108924) (xy 201.925877 -404.162331) (xy 201.902205 -404.212828) (xy 201.871432 -404.259341)
			(xy 201.834215 -404.300878) (xy 201.791347 -404.336553) (xy 201.743741 -404.365607) (xy 201.692412 -404.387419)
			(xy 201.638455 -404.401525) (xy 201.583018 -404.407625) (xy 201.527284 -404.405588) (xy 201.472441 -404.395458)
			(xy 201.419657 -404.377451) (xy 201.370057 -404.35195) (xy 201.324699 -404.319499) (xy 201.28455 -404.28079)
			(xy 201.250464 -404.236647) (xy 201.223168 -404.188012) (xy 201.203245 -404.135921) (xy 201.191119 -404.081484)
			(xy 201.187048 -404.025862) (xy 200.553574 -404.025862) (xy 200.553065 -404.053748) (xy 200.544945 -404.108924)
			(xy 200.528877 -404.162331) (xy 200.505205 -404.212828) (xy 200.474432 -404.259341) (xy 200.437215 -404.300878)
			(xy 200.394347 -404.336553) (xy 200.346741 -404.365607) (xy 200.295412 -404.387419) (xy 200.241455 -404.401525)
			(xy 200.186018 -404.407625) (xy 200.130284 -404.405588) (xy 200.075441 -404.395458) (xy 200.022657 -404.377451)
			(xy 199.973057 -404.35195) (xy 199.927699 -404.319499) (xy 199.88755 -404.28079) (xy 199.853464 -404.236647)
			(xy 199.826168 -404.188012) (xy 199.806245 -404.135921) (xy 199.794119 -404.081484) (xy 199.790048 -404.025862)
			(xy 199.131174 -404.025862) (xy 199.130665 -404.053748) (xy 199.122545 -404.108924) (xy 199.106477 -404.162331)
			(xy 199.082805 -404.212828) (xy 199.052032 -404.259341) (xy 199.014815 -404.300878) (xy 198.971947 -404.336553)
			(xy 198.924341 -404.365607) (xy 198.873012 -404.387419) (xy 198.819055 -404.401525) (xy 198.763618 -404.407625)
			(xy 198.707884 -404.405588) (xy 198.653041 -404.395458) (xy 198.600257 -404.377451) (xy 198.550657 -404.35195)
			(xy 198.505299 -404.319499) (xy 198.46515 -404.28079) (xy 198.431064 -404.236647) (xy 198.403768 -404.188012)
			(xy 198.383845 -404.135921) (xy 198.371719 -404.081484) (xy 198.367648 -404.025862) (xy 197.71551 -404.025862)
			(xy 197.711464 -404.054) (xy 197.696108 -404.106296) (xy 197.673466 -404.155874) (xy 197.643999 -404.201724)
			(xy 197.608306 -404.242915) (xy 197.567115 -404.278606) (xy 197.521263 -404.308072) (xy 197.471685 -404.330712)
			(xy 197.419389 -404.346066) (xy 197.36544 -404.353822) (xy 197.338188 -404.354284) (xy 197.309273 -404.353709)
			(xy 197.252104 -404.344992) (xy 197.196906 -404.327746) (xy 197.144944 -404.302365) (xy 197.097409 -404.269431)
			(xy 197.05539 -404.229699) (xy 197.037198 -404.207218) (xy 197.02792 -404.196035) (xy 197.004351 -404.179057)
			(xy 196.976953 -404.169408) (xy 196.947947 -404.16787) (xy 196.919682 -404.174566) (xy 196.894449 -404.188955)
			(xy 196.884036 -404.19909) (xy 196.866014 -404.217249) (xy 196.82591 -404.24902) (xy 196.781921 -404.275146)
			(xy 196.734834 -404.295159) (xy 196.685495 -404.308699) (xy 196.63479 -404.315525) (xy 196.609208 -404.31593)
			(xy 196.581956 -404.315423) (xy 196.528008 -404.307668) (xy 196.475712 -404.292313) (xy 196.426134 -404.269672)
			(xy 196.380282 -404.240206) (xy 196.339091 -404.204515) (xy 196.303398 -404.163324) (xy 196.273931 -404.117473)
			(xy 196.25129 -404.067896) (xy 196.235934 -404.0156) (xy 196.228177 -403.961652) (xy 195.681398 -403.961652)
			(xy 196.263514 -404.543768) (xy 201.953622 -404.543768) (xy 202.6539 -403.843236) (xy 202.6539 -403.163278)
			(xy 202.641815 -403.141461) (xy 202.622789 -403.095359) (xy 202.609935 -403.047169) (xy 202.603475 -402.997715)
			(xy 202.6031 -402.972778) (xy 202.603587 -402.945528) (xy 202.611346 -402.891583) (xy 202.626704 -402.839291)
			(xy 202.649346 -402.789717) (xy 202.678813 -402.74387) (xy 202.714505 -402.702683) (xy 202.755694 -402.666995)
			(xy 202.801544 -402.637532) (xy 202.85112 -402.614893) (xy 202.903412 -402.59954) (xy 202.957358 -402.591785)
			(xy 202.984608 -402.59127) (xy 203.015515 -402.591873) (xy 203.076522 -402.601835) (xy 203.10602 -402.611082)
			(xy 203.119833 -402.615167) (xy 203.148603 -402.616299) (xy 203.176547 -402.609365) (xy 203.20145 -402.594915)
			(xy 203.221336 -402.574093) (xy 203.234627 -402.548553) (xy 203.24027 -402.520319) (xy 203.239624 -402.505926)
			(xy 203.2381 -402.472906) (xy 203.238585 -402.445655) (xy 203.246341 -402.391709) (xy 203.261695 -402.339415)
			(xy 203.284335 -402.289838) (xy 203.313799 -402.243988) (xy 203.34949 -402.202799) (xy 203.390678 -402.167107)
			(xy 203.436527 -402.137641) (xy 203.486103 -402.114999) (xy 203.538396 -402.099644) (xy 203.592343 -402.091886)
			(xy 203.646844 -402.091885) (xy 203.700791 -402.099641) (xy 203.753085 -402.114995) (xy 203.802661 -402.137634)
			(xy 203.848511 -402.167099) (xy 203.889701 -402.202789) (xy 203.925393 -402.243978) (xy 203.954859 -402.289827)
			(xy 203.977501 -402.339402) (xy 203.992856 -402.391696) (xy 204.000614 -402.445642) (xy 204.000615 -402.500143)
			(xy 203.992859 -402.55409) (xy 203.977506 -402.606384) (xy 203.954866 -402.65596) (xy 203.925401 -402.70181)
			(xy 203.889711 -402.743001) (xy 203.848523 -402.778692) (xy 203.802674 -402.808159) (xy 203.753098 -402.8308)
			(xy 203.700805 -402.846156) (xy 203.646859 -402.853914) (xy 203.619608 -402.854414) (xy 203.593819 -402.85399)
			(xy 203.542711 -402.847047) (xy 203.493002 -402.833288) (xy 203.445598 -402.812962) (xy 203.423266 -402.800058)
			(xy 203.414226 -402.795172) (xy 203.393894 -402.792333) (xy 203.374073 -402.797684) (xy 203.357931 -402.810368)
			(xy 203.348046 -402.828361) (xy 203.345996 -402.848788) (xy 203.34859 -402.858732) (xy 203.349606 -402.86178)
			(xy 203.353416 -402.873972) (xy 203.473558 -402.994368) (xy 204.584808 -402.994368) (xy 204.610776 -402.994878)
			(xy 204.662071 -403.003002) (xy 204.711465 -403.019048) (xy 204.757742 -403.042623) (xy 204.799762 -403.073144)
			(xy 204.818488 -403.091142) (xy 205.700122 -403.972776) (xy 207.55559 -403.972776) (xy 207.559661 -403.917154)
			(xy 207.571787 -403.862717) (xy 207.59171 -403.810626) (xy 207.619006 -403.761991) (xy 207.653092 -403.717848)
			(xy 207.693241 -403.679139) (xy 207.738599 -403.646688) (xy 207.788199 -403.621187) (xy 207.840983 -403.60318)
			(xy 207.895826 -403.59305) (xy 207.95156 -403.591013) (xy 208.006997 -403.597113) (xy 208.060954 -403.611219)
			(xy 208.112283 -403.633031) (xy 208.159889 -403.662085) (xy 208.202757 -403.69776) (xy 208.239974 -403.739297)
			(xy 208.270747 -403.78581) (xy 208.294419 -403.836307) (xy 208.310487 -403.889714) (xy 208.318607 -403.94489)
			(xy 208.319116 -403.972776) (xy 208.318607 -404.000662) (xy 208.314898 -404.025862) (xy 209.035648 -404.025862)
			(xy 209.039719 -403.97024) (xy 209.051845 -403.915803) (xy 209.071768 -403.863712) (xy 209.099064 -403.815077)
			(xy 209.13315 -403.770934) (xy 209.173299 -403.732225) (xy 209.218657 -403.699774) (xy 209.268257 -403.674273)
			(xy 209.321041 -403.656266) (xy 209.375884 -403.646136) (xy 209.431618 -403.644099) (xy 209.487055 -403.650199)
			(xy 209.541012 -403.664305) (xy 209.592341 -403.686117) (xy 209.639947 -403.715171) (xy 209.682815 -403.750846)
			(xy 209.720032 -403.792383) (xy 209.750805 -403.838896) (xy 209.774477 -403.889393) (xy 209.790545 -403.9428)
			(xy 209.798665 -403.997976) (xy 209.799174 -404.025862) (xy 210.458048 -404.025862) (xy 210.462119 -403.97024)
			(xy 210.474245 -403.915803) (xy 210.494168 -403.863712) (xy 210.521464 -403.815077) (xy 210.55555 -403.770934)
			(xy 210.595699 -403.732225) (xy 210.641057 -403.699774) (xy 210.690657 -403.674273) (xy 210.743441 -403.656266)
			(xy 210.798284 -403.646136) (xy 210.854018 -403.644099) (xy 210.909455 -403.650199) (xy 210.963412 -403.664305)
			(xy 211.014741 -403.686117) (xy 211.062347 -403.715171) (xy 211.105215 -403.750846) (xy 211.142432 -403.792383)
			(xy 211.173205 -403.838896) (xy 211.196877 -403.889393) (xy 211.212945 -403.9428) (xy 211.221065 -403.997976)
			(xy 211.221574 -404.025862) (xy 211.855048 -404.025862) (xy 211.859119 -403.97024) (xy 211.871245 -403.915803)
			(xy 211.891168 -403.863712) (xy 211.918464 -403.815077) (xy 211.95255 -403.770934) (xy 211.992699 -403.732225)
			(xy 212.038057 -403.699774) (xy 212.087657 -403.674273) (xy 212.140441 -403.656266) (xy 212.195284 -403.646136)
			(xy 212.251018 -403.644099) (xy 212.306455 -403.650199) (xy 212.360412 -403.664305) (xy 212.411741 -403.686117)
			(xy 212.459347 -403.715171) (xy 212.502215 -403.750846) (xy 212.539432 -403.792383) (xy 212.570205 -403.838896)
			(xy 212.593877 -403.889393) (xy 212.609945 -403.9428) (xy 212.618065 -403.997976) (xy 212.618574 -404.025862)
			(xy 212.618065 -404.053748) (xy 212.609945 -404.108924) (xy 212.593877 -404.162331) (xy 212.570205 -404.212828)
			(xy 212.539432 -404.259341) (xy 212.502215 -404.300878) (xy 212.459347 -404.336553) (xy 212.411741 -404.365607)
			(xy 212.360412 -404.387419) (xy 212.306455 -404.401525) (xy 212.251018 -404.407625) (xy 212.195284 -404.405588)
			(xy 212.140441 -404.395458) (xy 212.087657 -404.377451) (xy 212.038057 -404.35195) (xy 211.992699 -404.319499)
			(xy 211.95255 -404.28079) (xy 211.918464 -404.236647) (xy 211.891168 -404.188012) (xy 211.871245 -404.135921)
			(xy 211.859119 -404.081484) (xy 211.855048 -404.025862) (xy 211.221574 -404.025862) (xy 211.221065 -404.053748)
			(xy 211.212945 -404.108924) (xy 211.196877 -404.162331) (xy 211.173205 -404.212828) (xy 211.142432 -404.259341)
			(xy 211.105215 -404.300878) (xy 211.062347 -404.336553) (xy 211.014741 -404.365607) (xy 210.963412 -404.387419)
			(xy 210.909455 -404.401525) (xy 210.854018 -404.407625) (xy 210.798284 -404.405588) (xy 210.743441 -404.395458)
			(xy 210.690657 -404.377451) (xy 210.641057 -404.35195) (xy 210.595699 -404.319499) (xy 210.55555 -404.28079)
			(xy 210.521464 -404.236647) (xy 210.494168 -404.188012) (xy 210.474245 -404.135921) (xy 210.462119 -404.081484)
			(xy 210.458048 -404.025862) (xy 209.799174 -404.025862) (xy 209.798665 -404.053748) (xy 209.790545 -404.108924)
			(xy 209.774477 -404.162331) (xy 209.750805 -404.212828) (xy 209.720032 -404.259341) (xy 209.682815 -404.300878)
			(xy 209.639947 -404.336553) (xy 209.592341 -404.365607) (xy 209.541012 -404.387419) (xy 209.487055 -404.401525)
			(xy 209.431618 -404.407625) (xy 209.375884 -404.405588) (xy 209.321041 -404.395458) (xy 209.268257 -404.377451)
			(xy 209.218657 -404.35195) (xy 209.173299 -404.319499) (xy 209.13315 -404.28079) (xy 209.099064 -404.236647)
			(xy 209.071768 -404.188012) (xy 209.051845 -404.135921) (xy 209.039719 -404.081484) (xy 209.035648 -404.025862)
			(xy 208.314898 -404.025862) (xy 208.310487 -404.055838) (xy 208.294419 -404.109245) (xy 208.270747 -404.159742)
			(xy 208.239974 -404.206255) (xy 208.202757 -404.247792) (xy 208.159889 -404.283467) (xy 208.112283 -404.312521)
			(xy 208.060954 -404.334333) (xy 208.006997 -404.348439) (xy 207.95156 -404.354539) (xy 207.895826 -404.352502)
			(xy 207.840983 -404.342372) (xy 207.788199 -404.324365) (xy 207.738599 -404.298864) (xy 207.693241 -404.266413)
			(xy 207.653092 -404.227704) (xy 207.619006 -404.183561) (xy 207.59171 -404.134926) (xy 207.571787 -404.082835)
			(xy 207.559661 -404.028398) (xy 207.55559 -403.972776) (xy 205.700122 -403.972776) (xy 205.936088 -404.208742)
			(xy 205.954104 -404.227462) (xy 205.984666 -404.269476) (xy 206.008289 -404.315748) (xy 206.024394 -404.365142)
			(xy 206.032584 -404.416446) (xy 206.033116 -404.442422) (xy 206.033116 -404.686516) (xy 206.321914 -404.975568)
			(xy 206.669386 -404.975568) (xy 206.683607 -404.975098) (xy 206.71095 -404.967262) (xy 206.735073 -404.952194)
			(xy 206.754109 -404.931061) (xy 206.766582 -404.905499) (xy 206.771527 -404.877489) (xy 206.770478 -404.8633)
			(xy 206.76951 -404.853359) (xy 206.768491 -404.83341) (xy 206.768446 -404.823422) (xy 206.76893 -404.796169)
			(xy 206.776684 -404.742216) (xy 206.792037 -404.689916) (xy 206.814676 -404.640333) (xy 206.844141 -404.594477)
			(xy 206.879832 -404.55328) (xy 206.921022 -404.517582) (xy 206.966873 -404.488109) (xy 207.016452 -404.465461)
			(xy 207.068749 -404.450098) (xy 207.122701 -404.442335) (xy 207.149954 -404.441914) (xy 207.178172 -404.442427)
			(xy 207.23399 -404.450749) (xy 207.287974 -404.467204) (xy 207.338944 -404.491432) (xy 207.385788 -404.522906)
			(xy 207.427484 -404.560937) (xy 207.463123 -404.604696) (xy 207.491926 -404.653228) (xy 207.513264 -404.705474)
			(xy 207.52054 -404.732744) (xy 207.524171 -404.745693) (xy 207.537222 -404.769196) (xy 207.555954 -404.788479)
			(xy 207.57907 -404.802206) (xy 207.604966 -404.809424) (xy 207.631849 -404.809635) (xy 207.657855 -404.802822)
			(xy 207.681183 -404.78946) (xy 207.690974 -404.780242) (xy 207.830928 -404.640542) (xy 207.849633 -404.62252)
			(xy 207.891654 -404.591992) (xy 207.937935 -404.568417) (xy 207.987336 -404.552376) (xy 208.038638 -404.544264)
			(xy 208.064608 -404.543768) (xy 212.672422 -404.543768) (xy 213.3219 -403.894036) (xy 213.3219 -403.163278)
			(xy 213.309815 -403.141461) (xy 213.290789 -403.095359) (xy 213.277935 -403.047169) (xy 213.271475 -402.997715)
			(xy 213.2711 -402.972778) (xy 213.271587 -402.945528) (xy 213.279346 -402.891583) (xy 213.294704 -402.839291)
			(xy 213.317346 -402.789717) (xy 213.346813 -402.74387) (xy 213.382505 -402.702683) (xy 213.423694 -402.666995)
			(xy 213.469544 -402.637532) (xy 213.51912 -402.614893) (xy 213.571412 -402.59954) (xy 213.625358 -402.591785)
			(xy 213.652608 -402.59127) (xy 213.683515 -402.591873) (xy 213.744522 -402.601835) (xy 213.77402 -402.611082)
			(xy 213.787833 -402.615167) (xy 213.816603 -402.616299) (xy 213.844547 -402.609365) (xy 213.86945 -402.594915)
			(xy 213.889336 -402.574093) (xy 213.902627 -402.548553) (xy 213.90827 -402.520319) (xy 213.907624 -402.505926)
			(xy 213.9061 -402.472906) (xy 213.906585 -402.445655) (xy 213.914341 -402.391709) (xy 213.929695 -402.339415)
			(xy 213.952335 -402.289838) (xy 213.981799 -402.243988) (xy 214.01749 -402.202799) (xy 214.058678 -402.167107)
			(xy 214.104527 -402.137641) (xy 214.154103 -402.114999) (xy 214.206396 -402.099644) (xy 214.260343 -402.091886)
			(xy 214.314844 -402.091885) (xy 214.368791 -402.099641) (xy 214.421085 -402.114995) (xy 214.470661 -402.137634)
			(xy 214.516511 -402.167099) (xy 214.557701 -402.202789) (xy 214.593393 -402.243978) (xy 214.622859 -402.289827)
			(xy 214.645501 -402.339402) (xy 214.660856 -402.391696) (xy 214.668614 -402.445642) (xy 214.668615 -402.500143)
			(xy 214.660859 -402.55409) (xy 214.645506 -402.606384) (xy 214.622866 -402.65596) (xy 214.593401 -402.70181)
			(xy 214.557711 -402.743001) (xy 214.516523 -402.778692) (xy 214.470674 -402.808159) (xy 214.421098 -402.8308)
			(xy 214.368805 -402.846156) (xy 214.314859 -402.853914) (xy 214.287608 -402.854414) (xy 214.261819 -402.85399)
			(xy 214.210711 -402.847047) (xy 214.161002 -402.833288) (xy 214.113598 -402.812962) (xy 214.091266 -402.800058)
			(xy 214.082226 -402.795172) (xy 214.061894 -402.792333) (xy 214.042073 -402.797684) (xy 214.025931 -402.810368)
			(xy 214.016046 -402.828361) (xy 214.013996 -402.848788) (xy 214.01659 -402.858732) (xy 214.017606 -402.86178)
			(xy 214.021416 -402.873972) (xy 214.141558 -402.994368) (xy 215.506808 -402.994368) (xy 215.532776 -402.994878)
			(xy 215.584071 -403.003002) (xy 215.633465 -403.019048) (xy 215.679742 -403.042623) (xy 215.721762 -403.073144)
			(xy 215.740488 -403.091142) (xy 216.622122 -403.972776) (xy 218.22359 -403.972776) (xy 218.227661 -403.917154)
			(xy 218.239787 -403.862717) (xy 218.25971 -403.810626) (xy 218.287006 -403.761991) (xy 218.321092 -403.717848)
			(xy 218.361241 -403.679139) (xy 218.406599 -403.646688) (xy 218.456199 -403.621187) (xy 218.508983 -403.60318)
			(xy 218.563826 -403.59305) (xy 218.61956 -403.591013) (xy 218.674997 -403.597113) (xy 218.728954 -403.611219)
			(xy 218.780283 -403.633031) (xy 218.827889 -403.662085) (xy 218.870757 -403.69776) (xy 218.907974 -403.739297)
			(xy 218.938747 -403.78581) (xy 218.962419 -403.836307) (xy 218.978487 -403.889714) (xy 218.986607 -403.94489)
			(xy 218.987116 -403.972776) (xy 218.986607 -404.000662) (xy 218.982898 -404.025862) (xy 219.703648 -404.025862)
			(xy 219.707719 -403.97024) (xy 219.719845 -403.915803) (xy 219.739768 -403.863712) (xy 219.767064 -403.815077)
			(xy 219.80115 -403.770934) (xy 219.841299 -403.732225) (xy 219.886657 -403.699774) (xy 219.936257 -403.674273)
			(xy 219.989041 -403.656266) (xy 220.043884 -403.646136) (xy 220.099618 -403.644099) (xy 220.155055 -403.650199)
			(xy 220.209012 -403.664305) (xy 220.260341 -403.686117) (xy 220.307947 -403.715171) (xy 220.350815 -403.750846)
			(xy 220.388032 -403.792383) (xy 220.418805 -403.838896) (xy 220.442477 -403.889393) (xy 220.458545 -403.9428)
			(xy 220.466665 -403.997976) (xy 220.467174 -404.025862) (xy 221.126048 -404.025862) (xy 221.130119 -403.97024)
			(xy 221.142245 -403.915803) (xy 221.162168 -403.863712) (xy 221.189464 -403.815077) (xy 221.22355 -403.770934)
			(xy 221.263699 -403.732225) (xy 221.309057 -403.699774) (xy 221.358657 -403.674273) (xy 221.411441 -403.656266)
			(xy 221.466284 -403.646136) (xy 221.522018 -403.644099) (xy 221.577455 -403.650199) (xy 221.631412 -403.664305)
			(xy 221.682741 -403.686117) (xy 221.730347 -403.715171) (xy 221.773215 -403.750846) (xy 221.810432 -403.792383)
			(xy 221.841205 -403.838896) (xy 221.864877 -403.889393) (xy 221.880945 -403.9428) (xy 221.889065 -403.997976)
			(xy 221.889574 -404.025862) (xy 222.523048 -404.025862) (xy 222.527119 -403.97024) (xy 222.539245 -403.915803)
			(xy 222.559168 -403.863712) (xy 222.586464 -403.815077) (xy 222.62055 -403.770934) (xy 222.660699 -403.732225)
			(xy 222.706057 -403.699774) (xy 222.755657 -403.674273) (xy 222.808441 -403.656266) (xy 222.863284 -403.646136)
			(xy 222.919018 -403.644099) (xy 222.974455 -403.650199) (xy 223.028412 -403.664305) (xy 223.079741 -403.686117)
			(xy 223.127347 -403.715171) (xy 223.170215 -403.750846) (xy 223.207432 -403.792383) (xy 223.238205 -403.838896)
			(xy 223.261877 -403.889393) (xy 223.277945 -403.9428) (xy 223.286065 -403.997976) (xy 223.286574 -404.025862)
			(xy 223.286065 -404.053748) (xy 223.277945 -404.108924) (xy 223.261877 -404.162331) (xy 223.238205 -404.212828)
			(xy 223.207432 -404.259341) (xy 223.170215 -404.300878) (xy 223.127347 -404.336553) (xy 223.079741 -404.365607)
			(xy 223.028412 -404.387419) (xy 222.974455 -404.401525) (xy 222.919018 -404.407625) (xy 222.863284 -404.405588)
			(xy 222.808441 -404.395458) (xy 222.755657 -404.377451) (xy 222.706057 -404.35195) (xy 222.660699 -404.319499)
			(xy 222.62055 -404.28079) (xy 222.586464 -404.236647) (xy 222.559168 -404.188012) (xy 222.539245 -404.135921)
			(xy 222.527119 -404.081484) (xy 222.523048 -404.025862) (xy 221.889574 -404.025862) (xy 221.889065 -404.053748)
			(xy 221.880945 -404.108924) (xy 221.864877 -404.162331) (xy 221.841205 -404.212828) (xy 221.810432 -404.259341)
			(xy 221.773215 -404.300878) (xy 221.730347 -404.336553) (xy 221.682741 -404.365607) (xy 221.631412 -404.387419)
			(xy 221.577455 -404.401525) (xy 221.522018 -404.407625) (xy 221.466284 -404.405588) (xy 221.411441 -404.395458)
			(xy 221.358657 -404.377451) (xy 221.309057 -404.35195) (xy 221.263699 -404.319499) (xy 221.22355 -404.28079)
			(xy 221.189464 -404.236647) (xy 221.162168 -404.188012) (xy 221.142245 -404.135921) (xy 221.130119 -404.081484)
			(xy 221.126048 -404.025862) (xy 220.467174 -404.025862) (xy 220.466665 -404.053748) (xy 220.458545 -404.108924)
			(xy 220.442477 -404.162331) (xy 220.418805 -404.212828) (xy 220.388032 -404.259341) (xy 220.350815 -404.300878)
			(xy 220.307947 -404.336553) (xy 220.260341 -404.365607) (xy 220.209012 -404.387419) (xy 220.155055 -404.401525)
			(xy 220.099618 -404.407625) (xy 220.043884 -404.405588) (xy 219.989041 -404.395458) (xy 219.936257 -404.377451)
			(xy 219.886657 -404.35195) (xy 219.841299 -404.319499) (xy 219.80115 -404.28079) (xy 219.767064 -404.236647)
			(xy 219.739768 -404.188012) (xy 219.719845 -404.135921) (xy 219.707719 -404.081484) (xy 219.703648 -404.025862)
			(xy 218.982898 -404.025862) (xy 218.978487 -404.055838) (xy 218.962419 -404.109245) (xy 218.938747 -404.159742)
			(xy 218.907974 -404.206255) (xy 218.870757 -404.247792) (xy 218.827889 -404.283467) (xy 218.780283 -404.312521)
			(xy 218.728954 -404.334333) (xy 218.674997 -404.348439) (xy 218.61956 -404.354539) (xy 218.563826 -404.352502)
			(xy 218.508983 -404.342372) (xy 218.456199 -404.324365) (xy 218.406599 -404.298864) (xy 218.361241 -404.266413)
			(xy 218.321092 -404.227704) (xy 218.287006 -404.183561) (xy 218.25971 -404.134926) (xy 218.239787 -404.082835)
			(xy 218.227661 -404.028398) (xy 218.22359 -403.972776) (xy 216.622122 -403.972776) (xy 216.680288 -404.030942)
			(xy 216.698304 -404.049662) (xy 216.728866 -404.091676) (xy 216.752489 -404.137948) (xy 216.768594 -404.187342)
			(xy 216.776784 -404.238646) (xy 216.777316 -404.264622) (xy 216.777316 -404.864316) (xy 216.939114 -405.026368)
			(xy 217.345514 -405.026368) (xy 217.360631 -405.025815) (xy 217.389539 -405.01696) (xy 217.414589 -405.00003)
			(xy 217.433585 -404.976509) (xy 217.444864 -404.948458) (xy 217.447437 -404.918334) (xy 217.444828 -404.903432)
			(xy 217.440882 -404.883666) (xy 217.436678 -404.843577) (xy 217.436446 -404.823422) (xy 217.43693 -404.796169)
			(xy 217.444684 -404.742216) (xy 217.460037 -404.689916) (xy 217.482676 -404.640333) (xy 217.512141 -404.594477)
			(xy 217.547832 -404.55328) (xy 217.589022 -404.517582) (xy 217.634873 -404.488109) (xy 217.684452 -404.465461)
			(xy 217.736749 -404.450098) (xy 217.790701 -404.442335) (xy 217.817954 -404.441914) (xy 217.845048 -404.442392)
			(xy 217.898689 -404.450066) (xy 217.950706 -404.46525) (xy 218.000051 -404.487641) (xy 218.045733 -404.516788)
			(xy 218.086831 -404.552103) (xy 218.122521 -404.592878) (xy 218.152083 -404.638292) (xy 218.174923 -404.687431)
			(xy 218.190582 -404.739307) (xy 218.195144 -404.766018) (xy 218.197697 -404.779813) (xy 218.209305 -404.805341)
			(xy 218.227418 -404.826751) (xy 218.250671 -404.842427) (xy 218.277311 -404.851189) (xy 218.305329 -404.852375)
			(xy 218.332614 -404.845897) (xy 218.357109 -404.832242) (xy 218.367356 -404.82266) (xy 218.559888 -404.630382)
			(xy 218.578591 -404.612355) (xy 218.62061 -404.581819) (xy 218.666891 -404.558236) (xy 218.716292 -404.542187)
			(xy 218.767596 -404.534067) (xy 218.793568 -404.533608) (xy 223.330262 -404.533608) (xy 223.9899 -403.873716)
			(xy 223.9899 -403.163278) (xy 223.977815 -403.141461) (xy 223.958789 -403.095359) (xy 223.945935 -403.047169)
			(xy 223.939475 -402.997715) (xy 223.9391 -402.972778) (xy 223.939587 -402.945528) (xy 223.947346 -402.891583)
			(xy 223.962704 -402.839291) (xy 223.985346 -402.789717) (xy 224.014813 -402.74387) (xy 224.050505 -402.702683)
			(xy 224.091694 -402.666995) (xy 224.137544 -402.637532) (xy 224.18712 -402.614893) (xy 224.239412 -402.59954)
			(xy 224.293358 -402.591785) (xy 224.320608 -402.59127) (xy 224.351515 -402.591873) (xy 224.412522 -402.601835)
			(xy 224.44202 -402.611082) (xy 224.455833 -402.615167) (xy 224.484603 -402.616299) (xy 224.512547 -402.609365)
			(xy 224.53745 -402.594915) (xy 224.557336 -402.574093) (xy 224.570627 -402.548553) (xy 224.57627 -402.520319)
			(xy 224.575624 -402.505926) (xy 224.5741 -402.472906) (xy 224.574585 -402.445655) (xy 224.582341 -402.391709)
			(xy 224.597695 -402.339415) (xy 224.620335 -402.289838) (xy 224.649799 -402.243988) (xy 224.68549 -402.202799)
			(xy 224.726678 -402.167107) (xy 224.772527 -402.137641) (xy 224.822103 -402.114999) (xy 224.874396 -402.099644)
			(xy 224.928343 -402.091886) (xy 224.982844 -402.091885) (xy 225.036791 -402.099641) (xy 225.089085 -402.114995)
			(xy 225.138661 -402.137634) (xy 225.184511 -402.167099) (xy 225.225701 -402.202789) (xy 225.261393 -402.243978)
			(xy 225.290859 -402.289827) (xy 225.313501 -402.339402) (xy 225.328856 -402.391696) (xy 225.336614 -402.445642)
			(xy 225.336615 -402.500143) (xy 225.328859 -402.55409) (xy 225.313506 -402.606384) (xy 225.290866 -402.65596)
			(xy 225.261401 -402.70181) (xy 225.225711 -402.743001) (xy 225.184523 -402.778692) (xy 225.138674 -402.808159)
			(xy 225.089098 -402.8308) (xy 225.036805 -402.846156) (xy 224.982859 -402.853914) (xy 224.955608 -402.854414)
			(xy 224.929819 -402.85399) (xy 224.878711 -402.847047) (xy 224.829002 -402.833288) (xy 224.781598 -402.812962)
			(xy 224.759266 -402.800058) (xy 224.750226 -402.795172) (xy 224.729894 -402.792333) (xy 224.710073 -402.797684)
			(xy 224.693931 -402.810368) (xy 224.684046 -402.828361) (xy 224.681996 -402.848788) (xy 224.68459 -402.858732)
			(xy 224.685606 -402.86178) (xy 224.689416 -402.873972) (xy 224.809558 -402.994368) (xy 226.174808 -402.994368)
			(xy 226.200776 -402.994878) (xy 226.252071 -403.003002) (xy 226.301465 -403.019048) (xy 226.347742 -403.042623)
			(xy 226.389762 -403.073144) (xy 226.408488 -403.091142) (xy 226.891088 -403.573742) (xy 226.909104 -403.592462)
			(xy 226.939666 -403.634476) (xy 226.963289 -403.680748) (xy 226.979394 -403.730142) (xy 226.987584 -403.781446)
			(xy 226.988116 -403.807422) (xy 226.988116 -404.508716) (xy 227.454714 -404.975568) (xy 228.005386 -404.975568)
			(xy 228.019607 -404.975098) (xy 228.04695 -404.967262) (xy 228.071073 -404.952194) (xy 228.090109 -404.931061)
			(xy 228.102582 -404.905499) (xy 228.107527 -404.877489) (xy 228.106478 -404.8633) (xy 228.10551 -404.853359)
			(xy 228.104491 -404.83341) (xy 228.104446 -404.823422) (xy 228.10493 -404.796169) (xy 228.112684 -404.742216)
			(xy 228.128037 -404.689916) (xy 228.150676 -404.640333) (xy 228.180141 -404.594477) (xy 228.215832 -404.55328)
			(xy 228.257022 -404.517582) (xy 228.302873 -404.488109) (xy 228.352452 -404.465461) (xy 228.404749 -404.450098)
			(xy 228.458701 -404.442335) (xy 228.485954 -404.441914) (xy 228.512362 -404.44236) (xy 228.564675 -404.449641)
			(xy 228.615482 -404.464072) (xy 228.663812 -404.485375) (xy 228.70874 -404.513143) (xy 228.749407 -404.546845)
			(xy 228.785034 -404.585836) (xy 228.81494 -404.62937) (xy 228.838553 -404.676614) (xy 228.847396 -404.701502)
			(xy 228.852602 -404.715328) (xy 228.869671 -404.739428) (xy 228.892916 -404.757643) (xy 228.920397 -404.768456)
			(xy 228.949822 -404.770963) (xy 228.978736 -404.764957) (xy 229.004728 -404.750937) (xy 229.015544 -404.740872)
			(xy 229.240334 -404.516082) (xy 229.249655 -404.506168) (xy 229.263148 -404.48255) (xy 229.269921 -404.456205)
			(xy 229.269492 -404.429008) (xy 229.261892 -404.40289) (xy 229.247662 -404.379708) (xy 229.227812 -404.36111)
			(xy 229.203754 -404.348418) (xy 229.19055 -404.34514) (xy 229.162693 -404.338399) (xy 229.10925 -404.317694)
			(xy 229.059506 -404.289228) (xy 229.01458 -404.253641) (xy 228.975482 -404.211733) (xy 228.943094 -404.164449)
			(xy 228.918144 -404.112851) (xy 228.901193 -404.058102) (xy 228.892623 -404.001433) (xy 228.8921 -403.972776)
			(xy 228.892586 -403.945525) (xy 228.900342 -403.891577) (xy 228.915697 -403.839282) (xy 228.938339 -403.789705)
			(xy 228.967805 -403.743855) (xy 229.003496 -403.702664) (xy 229.044687 -403.666973) (xy 229.090537 -403.637507)
			(xy 229.140114 -403.614865) (xy 229.192409 -403.59951) (xy 229.246357 -403.591754) (xy 229.300859 -403.591754)
			(xy 229.354807 -403.59951) (xy 229.407102 -403.614865) (xy 229.456679 -403.637507) (xy 229.502529 -403.666973)
			(xy 229.54372 -403.702664) (xy 229.579411 -403.743855) (xy 229.608877 -403.789705) (xy 229.631519 -403.839282)
			(xy 229.646874 -403.891577) (xy 229.65463 -403.945525) (xy 229.655116 -403.972776) (xy 229.654615 -404.000593)
			(xy 229.646542 -404.055639) (xy 229.630564 -404.108929) (xy 229.607019 -404.159336) (xy 229.592124 -404.182834)
			(xy 229.584911 -404.194522) (xy 229.576381 -404.220619) (xy 229.575114 -404.248045) (xy 229.581202 -404.274817)
			(xy 229.594204 -404.298998) (xy 229.61318 -404.31884) (xy 229.636758 -404.332907) (xy 229.663232 -404.340182)
			(xy 229.67696 -404.340568) (xy 230.320088 -404.340568) (xy 230.334839 -404.340059) (xy 230.363107 -404.331611)
			(xy 230.387785 -404.315442) (xy 230.406819 -404.2929) (xy 230.418623 -404.265861) (xy 230.422216 -404.236577)
			(xy 230.417297 -404.207487) (xy 230.411274 -404.19401) (xy 230.398967 -404.167704) (xy 230.381559 -404.112299)
			(xy 230.372726 -404.054899) (xy 230.372158 -404.025862) (xy 230.372644 -403.998611) (xy 230.3804 -403.944663)
			(xy 230.395755 -403.892368) (xy 230.418397 -403.842791) (xy 230.447863 -403.796941) (xy 230.483554 -403.75575)
			(xy 230.524745 -403.720059) (xy 230.570595 -403.690593) (xy 230.620172 -403.667951) (xy 230.672467 -403.652596)
			(xy 230.726415 -403.64484) (xy 230.780917 -403.64484) (xy 230.834865 -403.652596) (xy 230.88716 -403.667951)
			(xy 230.936737 -403.690593) (xy 230.982587 -403.720059) (xy 231.023778 -403.75575) (xy 231.059469 -403.796941)
			(xy 231.088935 -403.842791) (xy 231.111577 -403.892368) (xy 231.126932 -403.944663) (xy 231.134688 -403.998611)
			(xy 231.135174 -404.025862) (xy 231.134636 -404.054903) (xy 231.125829 -404.112313) (xy 231.108399 -404.167717)
			(xy 231.096058 -404.19401) (xy 231.089968 -404.207473) (xy 231.085013 -404.236589) (xy 231.08859 -404.265907)
			(xy 231.1004 -404.292979) (xy 231.119457 -404.315543) (xy 231.14417 -404.331717) (xy 231.172476 -404.340149)
			(xy 231.187244 -404.340568) (xy 231.742488 -404.340568) (xy 231.757239 -404.340059) (xy 231.785507 -404.331611)
			(xy 231.810185 -404.315442) (xy 231.829219 -404.2929) (xy 231.841023 -404.265861) (xy 231.844616 -404.236577)
			(xy 231.839697 -404.207487) (xy 231.833674 -404.19401) (xy 231.821367 -404.167704) (xy 231.803959 -404.112299)
			(xy 231.795126 -404.054899) (xy 231.794558 -404.025862) (xy 231.795044 -403.998611) (xy 231.8028 -403.944663)
			(xy 231.818155 -403.892368) (xy 231.840797 -403.842791) (xy 231.870263 -403.796941) (xy 231.905954 -403.75575)
			(xy 231.947145 -403.720059) (xy 231.992995 -403.690593) (xy 232.042572 -403.667951) (xy 232.094867 -403.652596)
			(xy 232.148815 -403.64484) (xy 232.203317 -403.64484) (xy 232.257265 -403.652596) (xy 232.30956 -403.667951)
			(xy 232.359137 -403.690593) (xy 232.404987 -403.720059) (xy 232.446178 -403.75575) (xy 232.481869 -403.796941)
			(xy 232.511335 -403.842791) (xy 232.533977 -403.892368) (xy 232.549332 -403.944663) (xy 232.557088 -403.998611)
			(xy 232.557574 -404.025862) (xy 232.557036 -404.054903) (xy 232.548229 -404.112313) (xy 232.530799 -404.167717)
			(xy 232.518458 -404.19401) (xy 232.512368 -404.207473) (xy 232.507413 -404.236589) (xy 232.51099 -404.265907)
			(xy 232.5228 -404.292979) (xy 232.541857 -404.315543) (xy 232.56657 -404.331717) (xy 232.594876 -404.340149)
			(xy 232.609644 -404.340568) (xy 233.139488 -404.340568) (xy 233.154239 -404.340059) (xy 233.182507 -404.331611)
			(xy 233.207185 -404.315442) (xy 233.226219 -404.2929) (xy 233.238023 -404.265861) (xy 233.241616 -404.236577)
			(xy 233.236697 -404.207487) (xy 233.230674 -404.19401) (xy 233.218367 -404.167704) (xy 233.200959 -404.112299)
			(xy 233.192126 -404.054899) (xy 233.191558 -404.025862) (xy 233.192046 -403.998612) (xy 233.199807 -403.944666)
			(xy 233.215165 -403.892374) (xy 233.237808 -403.842799) (xy 233.267275 -403.796951) (xy 233.302966 -403.755763)
			(xy 233.344155 -403.720072) (xy 233.390003 -403.690606) (xy 233.439578 -403.667964) (xy 233.49187 -403.652606)
			(xy 233.545816 -403.644846) (xy 233.573066 -403.644354) (xy 233.600014 -403.644824) (xy 233.653371 -403.652419)
			(xy 233.705128 -403.667449) (xy 233.754254 -403.689616) (xy 233.79977 -403.718476) (xy 233.840771 -403.753456)
			(xy 233.876441 -403.793859) (xy 233.906067 -403.838881) (xy 233.917998 -403.863048) (xy 233.924343 -403.875458)
			(xy 233.942613 -403.896494) (xy 233.965888 -403.911812) (xy 233.992435 -403.920274) (xy 234.02028 -403.921249)
			(xy 234.047354 -403.914665) (xy 234.071643 -403.901013) (xy 234.081828 -403.891496) (xy 234.6579 -403.31517)
			(xy 234.6579 -403.163532) (xy 234.652058 -403.152356) (xy 234.637929 -403.124552) (xy 234.617905 -403.065489)
			(xy 234.607735 -403.00396) (xy 234.6071 -402.972778) (xy 234.607586 -402.945527) (xy 234.615342 -402.891579)
			(xy 234.630697 -402.839284) (xy 234.653339 -402.789707) (xy 234.682805 -402.743857) (xy 234.718496 -402.702666)
			(xy 234.759687 -402.666975) (xy 234.805537 -402.637509) (xy 234.855114 -402.614867) (xy 234.907409 -402.599512)
			(xy 234.961357 -402.591756) (xy 235.015859 -402.591756) (xy 235.069807 -402.599512) (xy 235.122102 -402.614867)
			(xy 235.171679 -402.637509) (xy 235.217529 -402.666975) (xy 235.25872 -402.702666) (xy 235.294411 -402.743857)
			(xy 235.323877 -402.789707) (xy 235.346519 -402.839284) (xy 235.361874 -402.891579) (xy 235.36963 -402.945527)
			(xy 235.370116 -402.972778) (xy 235.369726 -402.997714) (xy 235.363259 -403.047165) (xy 235.350408 -403.095353)
			(xy 235.33139 -403.141456) (xy 235.319316 -403.163278) (xy 235.319316 -403.452076) (xy 235.318818 -403.478057)
			(xy 235.310655 -403.529374) (xy 235.294558 -403.578779) (xy 235.270924 -403.625056) (xy 235.240336 -403.667061)
			(xy 235.222288 -403.685756) (xy 234.003342 -404.904702) (xy 233.984638 -404.922726) (xy 233.942617 -404.953259)
			(xy 233.896337 -404.97684) (xy 233.846936 -404.99289) (xy 233.795633 -405.001011) (xy 233.769662 -405.001476)
			(xy 229.689914 -405.001476) (xy 229.151688 -405.539702) (xy 229.132983 -405.557723) (xy 229.09096 -405.588249)
			(xy 229.044679 -405.611823) (xy 228.995279 -405.627864) (xy 228.943978 -405.635977) (xy 228.918008 -405.636476)
			(xy 227.317808 -405.636476) (xy 227.29184 -405.635968) (xy 227.240542 -405.627847) (xy 227.191145 -405.611804)
			(xy 227.144865 -405.588233) (xy 227.10284 -405.557715) (xy 227.084128 -405.539702) (xy 226.423728 -404.879302)
			(xy 226.405714 -404.860581) (xy 226.375158 -404.818566) (xy 226.351542 -404.772293) (xy 226.335445 -404.722899)
			(xy 226.327263 -404.671597) (xy 226.3267 -404.645622) (xy 226.3267 -403.944328) (xy 226.25304 -403.870668)
			(xy 226.241998 -403.860446) (xy 226.215421 -403.846365) (xy 226.185896 -403.840633) (xy 226.155981 -403.843747)
			(xy 226.128269 -403.855436) (xy 226.105162 -403.874688) (xy 226.088662 -403.899834) (xy 226.083876 -403.914102)
			(xy 226.074327 -403.944585) (xy 226.046505 -404.002082) (xy 226.009493 -404.054141) (xy 225.987356 -404.07717)
			(xy 224.524316 -405.54021) (xy 224.50272 -405.561) (xy 224.454207 -405.596209) (xy 224.400779 -405.623387)
			(xy 224.343755 -405.641863) (xy 224.28454 -405.651183) (xy 224.254568 -405.651716) (xy 223.504506 -405.651716)
			(xy 223.490103 -405.652226) (xy 223.462449 -405.66029) (xy 223.438142 -405.675749) (xy 223.419115 -405.697377)
			(xy 223.406878 -405.723455) (xy 223.402404 -405.751911) (xy 223.403668 -405.76627) (xy 223.405077 -405.778158)
			(xy 223.4066 -405.802051) (xy 223.406716 -405.814022) (xy 223.40618 -405.842938) (xy 223.397451 -405.900108)
			(xy 223.380195 -405.955306) (xy 223.354808 -406.007268) (xy 223.321871 -406.054804) (xy 223.282138 -406.096827)
			(xy 223.25965 -406.115012) (xy 223.247845 -406.124907) (xy 223.230327 -406.150228) (xy 223.221153 -406.179619)
			(xy 223.221157 -406.210408) (xy 223.230339 -406.239797) (xy 223.247863 -406.265113) (xy 223.25965 -406.275032)
			(xy 223.280431 -406.291786) (xy 223.317558 -406.330139) (xy 223.348975 -406.373293) (xy 223.374071 -406.420405)
			(xy 223.392354 -406.470555) (xy 223.403468 -406.522765) (xy 223.407196 -406.576014) (xy 223.403464 -406.629262)
			(xy 223.392347 -406.681471) (xy 223.37406 -406.73162) (xy 223.348961 -406.77873) (xy 223.31754 -406.821882)
			(xy 223.280411 -406.860233) (xy 223.25965 -406.877012) (xy 223.247845 -406.886907) (xy 223.230327 -406.912228)
			(xy 223.221153 -406.941619) (xy 223.221157 -406.972408) (xy 223.230339 -407.001797) (xy 223.247863 -407.027113)
			(xy 223.25965 -407.037032) (xy 223.282138 -407.05522) (xy 223.321884 -407.097235) (xy 223.354832 -407.144768)
			(xy 223.380227 -407.19673) (xy 223.397486 -407.251931) (xy 223.406214 -407.309104) (xy 223.406716 -407.338022)
			(xy 223.406229 -407.365272) (xy 223.39847 -407.419218) (xy 223.383113 -407.471511) (xy 223.36047 -407.521086)
			(xy 223.331004 -407.566934) (xy 223.295312 -407.608122) (xy 223.254123 -407.643812) (xy 223.208273 -407.673277)
			(xy 223.158698 -407.695918) (xy 223.106405 -407.711273) (xy 223.052458 -407.71903) (xy 223.025208 -407.71953)
			(xy 222.996292 -407.718996) (xy 222.939122 -407.710269) (xy 222.883923 -407.693014) (xy 222.831962 -407.667625)
			(xy 222.784427 -407.634685) (xy 222.742408 -407.594949) (xy 222.724218 -407.572464) (xy 222.714321 -407.560659)
			(xy 222.688997 -407.54314) (xy 222.659604 -407.533964) (xy 222.628812 -407.533964) (xy 222.599419 -407.54314)
			(xy 222.574095 -407.560659) (xy 222.564198 -407.572464) (xy 222.547445 -407.593247) (xy 222.509091 -407.630377)
			(xy 222.465937 -407.661799) (xy 222.418823 -407.686898) (xy 222.368671 -407.705184) (xy 222.31646 -407.716301)
			(xy 222.263208 -407.720031) (xy 222.209956 -407.716301) (xy 222.157745 -407.705184) (xy 222.107593 -407.686898)
			(xy 222.060479 -407.661799) (xy 222.017325 -407.630377) (xy 221.978971 -407.593247) (xy 221.962218 -407.572464)
			(xy 221.952321 -407.560659) (xy 221.926997 -407.54314) (xy 221.897604 -407.533964) (xy 221.866812 -407.533964)
			(xy 221.837419 -407.54314) (xy 221.812095 -407.560659) (xy 221.802198 -407.572464) (xy 221.785445 -407.593247)
			(xy 221.747091 -407.630377) (xy 221.703937 -407.661799) (xy 221.656823 -407.686898) (xy 221.606671 -407.705184)
			(xy 221.55446 -407.716301) (xy 221.501208 -407.720031) (xy 221.447956 -407.716301) (xy 221.395745 -407.705184)
			(xy 221.345593 -407.686898) (xy 221.298479 -407.661799) (xy 221.255325 -407.630377) (xy 221.216971 -407.593247)
			(xy 221.200218 -407.572464) (xy 221.190321 -407.560659) (xy 221.164997 -407.54314) (xy 221.135604 -407.533964)
			(xy 221.104812 -407.533964) (xy 221.075419 -407.54314) (xy 221.050095 -407.560659) (xy 221.040198 -407.572464)
			(xy 221.023445 -407.593247) (xy 220.985091 -407.630377) (xy 220.941937 -407.661799) (xy 220.894823 -407.686898)
			(xy 220.844671 -407.705184) (xy 220.79246 -407.716301) (xy 220.739208 -407.720031) (xy 220.685956 -407.716301)
			(xy 220.633745 -407.705184) (xy 220.583593 -407.686898) (xy 220.536479 -407.661799) (xy 220.493325 -407.630377)
			(xy 220.454971 -407.593247) (xy 220.438218 -407.572464) (xy 220.428321 -407.560659) (xy 220.402997 -407.54314)
			(xy 220.373604 -407.533964) (xy 220.342812 -407.533964) (xy 220.313419 -407.54314) (xy 220.288095 -407.560659)
			(xy 220.278198 -407.572464) (xy 220.260008 -407.594948) (xy 220.217991 -407.634685) (xy 220.170456 -407.667623)
			(xy 220.118493 -407.693007) (xy 220.063294 -407.710255) (xy 220.006124 -407.718972) (xy 219.977208 -407.71953)
			(xy 219.949956 -407.719045) (xy 219.896006 -407.711289) (xy 219.843709 -407.695935) (xy 219.794129 -407.673295)
			(xy 219.748276 -407.643829) (xy 219.707083 -407.608138) (xy 219.671389 -407.566948) (xy 219.64192 -407.521097)
			(xy 219.619275 -407.471519) (xy 219.603917 -407.419223) (xy 219.596157 -407.365274) (xy 219.5957 -407.338022)
			(xy 219.596232 -407.309105) (xy 219.604957 -407.251932) (xy 219.622208 -407.19673) (xy 219.647592 -407.144763)
			(xy 219.680528 -407.097223) (xy 219.72026 -407.055196) (xy 219.742766 -407.037032) (xy 219.754576 -407.027135)
			(xy 219.772104 -407.001811) (xy 219.781287 -406.972413) (xy 219.781291 -406.941614) (xy 219.772116 -406.912214)
			(xy 219.754595 -406.886884) (xy 219.742766 -406.877012) (xy 219.721981 -406.860259) (xy 219.684847 -406.821905)
			(xy 219.653422 -406.77875) (xy 219.62832 -406.731635) (xy 219.610031 -406.681481) (xy 219.598911 -406.629268)
			(xy 219.595179 -406.576014) (xy 219.598908 -406.522759) (xy 219.610023 -406.470545) (xy 219.628309 -406.420389)
			(xy 219.653408 -406.373273) (xy 219.68483 -406.330115) (xy 219.721961 -406.291759) (xy 219.742766 -406.275032)
			(xy 219.754576 -406.265135) (xy 219.772104 -406.239811) (xy 219.781287 -406.210413) (xy 219.781291 -406.179614)
			(xy 219.772116 -406.150214) (xy 219.754595 -406.124884) (xy 219.742766 -406.115012) (xy 219.720285 -406.09682)
			(xy 219.680553 -406.054801) (xy 219.64762 -406.007265) (xy 219.622238 -405.955303) (xy 219.604992 -405.900105)
			(xy 219.596274 -405.842937) (xy 219.5957 -405.814022) (xy 219.5958 -405.802051) (xy 219.597328 -405.778157)
			(xy 219.598748 -405.76627) (xy 219.600092 -405.75191) (xy 219.595635 -405.72343) (xy 219.583394 -405.69733)
			(xy 219.564346 -405.675692) (xy 219.54001 -405.660241) (xy 219.512324 -405.652208) (xy 219.49791 -405.651716)
			(xy 219.180156 -405.651716) (xy 218.595956 -406.23617) (xy 218.574362 -406.256965) (xy 218.525851 -406.292182)
			(xy 218.472424 -406.319368) (xy 218.415398 -406.337853) (xy 218.356182 -406.347179) (xy 218.326208 -406.347676)
			(xy 216.268808 -406.347676) (xy 216.23884 -406.347106) (xy 216.179636 -406.337767) (xy 216.122621 -406.319287)
			(xy 216.069196 -406.29212) (xy 216.020676 -406.256934) (xy 215.99906 -406.23617) (xy 215.36406 -405.60117)
			(xy 215.343281 -405.579555) (xy 215.308042 -405.531049) (xy 215.280821 -405.477631) (xy 215.262286 -405.420613)
			(xy 215.252893 -405.361399) (xy 215.2523 -405.331422) (xy 215.2523 -404.54961) (xy 215.049608 -404.346664)
			(xy 213.846156 -405.55037) (xy 213.824562 -405.571165) (xy 213.776051 -405.606382) (xy 213.722624 -405.633568)
			(xy 213.665598 -405.652053) (xy 213.606382 -405.661379) (xy 213.576408 -405.661876) (xy 212.837776 -405.661876)
			(xy 212.823555 -405.66235) (xy 212.796215 -405.670192) (xy 212.772093 -405.685261) (xy 212.753055 -405.706392)
			(xy 212.740575 -405.73195) (xy 212.735618 -405.759957) (xy 212.736684 -405.774144) (xy 212.737651 -405.784085)
			(xy 212.738668 -405.804034) (xy 212.738716 -405.814022) (xy 212.73818 -405.842938) (xy 212.729451 -405.900108)
			(xy 212.712195 -405.955306) (xy 212.686808 -406.007268) (xy 212.653871 -406.054804) (xy 212.614138 -406.096827)
			(xy 212.59165 -406.115012) (xy 212.579845 -406.124907) (xy 212.562327 -406.150228) (xy 212.553153 -406.179619)
			(xy 212.553157 -406.210408) (xy 212.562339 -406.239797) (xy 212.579863 -406.265113) (xy 212.59165 -406.275032)
			(xy 212.612431 -406.291786) (xy 212.649558 -406.330139) (xy 212.680975 -406.373293) (xy 212.706071 -406.420405)
			(xy 212.724354 -406.470555) (xy 212.735468 -406.522765) (xy 212.739196 -406.576014) (xy 212.735464 -406.629262)
			(xy 212.724347 -406.681471) (xy 212.70606 -406.73162) (xy 212.680961 -406.77873) (xy 212.64954 -406.821882)
			(xy 212.612411 -406.860233) (xy 212.59165 -406.877012) (xy 212.579845 -406.886907) (xy 212.562327 -406.912228)
			(xy 212.553153 -406.941619) (xy 212.553157 -406.972408) (xy 212.562339 -407.001797) (xy 212.579863 -407.027113)
			(xy 212.59165 -407.037032) (xy 212.614138 -407.05522) (xy 212.653884 -407.097235) (xy 212.686832 -407.144768)
			(xy 212.712227 -407.19673) (xy 212.729486 -407.251931) (xy 212.738214 -407.309104) (xy 212.738716 -407.338022)
			(xy 212.738229 -407.365272) (xy 212.73047 -407.419218) (xy 212.715113 -407.471511) (xy 212.69247 -407.521086)
			(xy 212.663004 -407.566934) (xy 212.627312 -407.608122) (xy 212.586123 -407.643812) (xy 212.540273 -407.673277)
			(xy 212.490698 -407.695918) (xy 212.438405 -407.711273) (xy 212.384458 -407.71903) (xy 212.357208 -407.71953)
			(xy 212.328292 -407.718996) (xy 212.271122 -407.710269) (xy 212.215923 -407.693014) (xy 212.163962 -407.667625)
			(xy 212.116427 -407.634685) (xy 212.074408 -407.594949) (xy 212.056218 -407.572464) (xy 212.046321 -407.560659)
			(xy 212.020997 -407.54314) (xy 211.991604 -407.533964) (xy 211.960812 -407.533964) (xy 211.931419 -407.54314)
			(xy 211.906095 -407.560659) (xy 211.896198 -407.572464) (xy 211.879445 -407.593247) (xy 211.841091 -407.630377)
			(xy 211.797937 -407.661799) (xy 211.750823 -407.686898) (xy 211.700671 -407.705184) (xy 211.64846 -407.716301)
			(xy 211.595208 -407.720031) (xy 211.541956 -407.716301) (xy 211.489745 -407.705184) (xy 211.439593 -407.686898)
			(xy 211.392479 -407.661799) (xy 211.349325 -407.630377) (xy 211.310971 -407.593247) (xy 211.294218 -407.572464)
			(xy 211.284321 -407.560659) (xy 211.258997 -407.54314) (xy 211.229604 -407.533964) (xy 211.198812 -407.533964)
			(xy 211.169419 -407.54314) (xy 211.144095 -407.560659) (xy 211.134198 -407.572464) (xy 211.117445 -407.593247)
			(xy 211.079091 -407.630377) (xy 211.035937 -407.661799) (xy 210.988823 -407.686898) (xy 210.938671 -407.705184)
			(xy 210.88646 -407.716301) (xy 210.833208 -407.720031) (xy 210.779956 -407.716301) (xy 210.727745 -407.705184)
			(xy 210.677593 -407.686898) (xy 210.630479 -407.661799) (xy 210.587325 -407.630377) (xy 210.548971 -407.593247)
			(xy 210.532218 -407.572464) (xy 210.522321 -407.560659) (xy 210.496997 -407.54314) (xy 210.467604 -407.533964)
			(xy 210.436812 -407.533964) (xy 210.407419 -407.54314) (xy 210.382095 -407.560659) (xy 210.372198 -407.572464)
			(xy 210.355445 -407.593247) (xy 210.317091 -407.630377) (xy 210.273937 -407.661799) (xy 210.226823 -407.686898)
			(xy 210.176671 -407.705184) (xy 210.12446 -407.716301) (xy 210.071208 -407.720031) (xy 210.017956 -407.716301)
			(xy 209.965745 -407.705184) (xy 209.915593 -407.686898) (xy 209.868479 -407.661799) (xy 209.825325 -407.630377)
			(xy 209.786971 -407.593247) (xy 209.770218 -407.572464) (xy 209.760321 -407.560659) (xy 209.734997 -407.54314)
			(xy 209.705604 -407.533964) (xy 209.674812 -407.533964) (xy 209.645419 -407.54314) (xy 209.620095 -407.560659)
			(xy 209.610198 -407.572464) (xy 209.592008 -407.594948) (xy 209.549991 -407.634685) (xy 209.502456 -407.667623)
			(xy 209.450493 -407.693007) (xy 209.395294 -407.710255) (xy 209.338124 -407.718972) (xy 209.309208 -407.71953)
			(xy 209.281956 -407.719045) (xy 209.228006 -407.711289) (xy 209.175709 -407.695935) (xy 209.126129 -407.673295)
			(xy 209.080276 -407.643829) (xy 209.039083 -407.608138) (xy 209.003389 -407.566948) (xy 208.97392 -407.521097)
			(xy 208.951275 -407.471519) (xy 208.935917 -407.419223) (xy 208.928157 -407.365274) (xy 208.9277 -407.338022)
			(xy 208.928232 -407.309105) (xy 208.936957 -407.251932) (xy 208.954208 -407.19673) (xy 208.979592 -407.144763)
			(xy 209.012528 -407.097223) (xy 209.05226 -407.055196) (xy 209.074766 -407.037032) (xy 209.086576 -407.027135)
			(xy 209.104104 -407.001811) (xy 209.113287 -406.972413) (xy 209.113291 -406.941614) (xy 209.104116 -406.912214)
			(xy 209.086595 -406.886884) (xy 209.074766 -406.877012) (xy 209.053981 -406.860259) (xy 209.016847 -406.821905)
			(xy 208.985422 -406.77875) (xy 208.96032 -406.731635) (xy 208.942031 -406.681481) (xy 208.930911 -406.629268)
			(xy 208.927179 -406.576014) (xy 208.930908 -406.522759) (xy 208.942023 -406.470545) (xy 208.960309 -406.420389)
			(xy 208.985408 -406.373273) (xy 209.01683 -406.330115) (xy 209.053961 -406.291759) (xy 209.074766 -406.275032)
			(xy 209.086576 -406.265135) (xy 209.104104 -406.239811) (xy 209.113287 -406.210413) (xy 209.113291 -406.179614)
			(xy 209.104116 -406.150214) (xy 209.086595 -406.124884) (xy 209.074766 -406.115012) (xy 209.052285 -406.09682)
			(xy 209.012553 -406.054801) (xy 208.97962 -406.007265) (xy 208.954238 -405.955303) (xy 208.936992 -405.900105)
			(xy 208.928274 -405.842937) (xy 208.9277 -405.814022) (xy 208.927751 -405.804034) (xy 208.928765 -405.784085)
			(xy 208.929732 -405.774144) (xy 208.930766 -405.759945) (xy 208.92585 -405.731917) (xy 208.913391 -405.706333)
			(xy 208.894357 -405.685179) (xy 208.870225 -405.670099) (xy 208.842868 -405.662263) (xy 208.82864 -405.661876)
			(xy 208.806796 -405.661876) (xy 208.410556 -406.05837) (xy 208.388962 -406.079165) (xy 208.340451 -406.114382)
			(xy 208.287024 -406.141568) (xy 208.229998 -406.160053) (xy 208.170782 -406.169379) (xy 208.140808 -406.169876)
			(xy 205.524608 -406.169876) (xy 205.49464 -406.169306) (xy 205.435436 -406.159967) (xy 205.378421 -406.141487)
			(xy 205.324996 -406.11432) (xy 205.276476 -406.079134) (xy 205.25486 -406.05837) (xy 204.11186 -404.91537)
			(xy 204.096642 -404.899698) (xy 204.069522 -404.86545) (xy 204.057758 -404.847044) (xy 204.049253 -404.834331)
			(xy 204.026165 -404.81429) (xy 203.998186 -404.801966) (xy 203.967815 -404.79846) (xy 203.937764 -404.804085)
			(xy 203.910717 -404.818339) (xy 203.899516 -404.828756) (xy 203.178156 -405.55037) (xy 203.156562 -405.571165)
			(xy 203.108051 -405.606382) (xy 203.054624 -405.633568) (xy 202.997598 -405.652053) (xy 202.938382 -405.661379)
			(xy 202.908408 -405.661876) (xy 202.169776 -405.661876) (xy 202.155555 -405.66235) (xy 202.128215 -405.670192)
			(xy 202.104093 -405.685261) (xy 202.085055 -405.706392) (xy 202.072575 -405.73195) (xy 202.067618 -405.759957)
			(xy 202.068684 -405.774144) (xy 202.069651 -405.784085) (xy 202.070668 -405.804034) (xy 202.070716 -405.814022)
			(xy 202.07018 -405.842938) (xy 202.061451 -405.900108) (xy 202.044195 -405.955306) (xy 202.018808 -406.007268)
			(xy 201.985871 -406.054804) (xy 201.946138 -406.096827) (xy 201.92365 -406.115012) (xy 201.911845 -406.124907)
			(xy 201.894327 -406.150228) (xy 201.885153 -406.179619) (xy 201.885157 -406.210408) (xy 201.894339 -406.239797)
			(xy 201.911863 -406.265113) (xy 201.92365 -406.275032) (xy 201.944431 -406.291786) (xy 201.981558 -406.330139)
			(xy 202.012975 -406.373293) (xy 202.038071 -406.420405) (xy 202.056354 -406.470555) (xy 202.067468 -406.522765)
			(xy 202.071196 -406.576014) (xy 202.067464 -406.629262) (xy 202.056347 -406.681471) (xy 202.03806 -406.73162)
			(xy 202.012961 -406.77873) (xy 201.98154 -406.821882) (xy 201.944411 -406.860233) (xy 201.92365 -406.877012)
			(xy 201.911845 -406.886907) (xy 201.894327 -406.912228) (xy 201.885153 -406.941619) (xy 201.885157 -406.972408)
			(xy 201.894339 -407.001797) (xy 201.911863 -407.027113) (xy 201.92365 -407.037032) (xy 201.946138 -407.05522)
			(xy 201.985884 -407.097235) (xy 202.018832 -407.144768) (xy 202.044227 -407.19673) (xy 202.061486 -407.251931)
			(xy 202.070214 -407.309104) (xy 202.070716 -407.338022) (xy 202.070229 -407.365272) (xy 202.06247 -407.419218)
			(xy 202.047113 -407.471511) (xy 202.02447 -407.521086) (xy 201.995004 -407.566934) (xy 201.959312 -407.608122)
			(xy 201.918123 -407.643812) (xy 201.872273 -407.673277) (xy 201.822698 -407.695918) (xy 201.770405 -407.711273)
			(xy 201.716458 -407.71903) (xy 201.689208 -407.71953) (xy 201.660292 -407.718996) (xy 201.603122 -407.710269)
			(xy 201.547923 -407.693014) (xy 201.495962 -407.667625) (xy 201.448427 -407.634685) (xy 201.406408 -407.594949)
			(xy 201.388218 -407.572464) (xy 201.378321 -407.560659) (xy 201.352997 -407.54314) (xy 201.323604 -407.533964)
			(xy 201.292812 -407.533964) (xy 201.263419 -407.54314) (xy 201.238095 -407.560659) (xy 201.228198 -407.572464)
			(xy 201.211445 -407.593247) (xy 201.173091 -407.630377) (xy 201.129937 -407.661799) (xy 201.082823 -407.686898)
			(xy 201.032671 -407.705184) (xy 200.98046 -407.716301) (xy 200.927208 -407.720031) (xy 200.873956 -407.716301)
			(xy 200.821745 -407.705184) (xy 200.771593 -407.686898) (xy 200.724479 -407.661799) (xy 200.681325 -407.630377)
			(xy 200.642971 -407.593247) (xy 200.626218 -407.572464) (xy 200.616321 -407.560659) (xy 200.590997 -407.54314)
			(xy 200.561604 -407.533964) (xy 200.530812 -407.533964) (xy 200.501419 -407.54314) (xy 200.476095 -407.560659)
			(xy 200.466198 -407.572464) (xy 200.449445 -407.593247) (xy 200.411091 -407.630377) (xy 200.367937 -407.661799)
			(xy 200.320823 -407.686898) (xy 200.270671 -407.705184) (xy 200.21846 -407.716301) (xy 200.165208 -407.720031)
			(xy 200.111956 -407.716301) (xy 200.059745 -407.705184) (xy 200.009593 -407.686898) (xy 199.962479 -407.661799)
			(xy 199.919325 -407.630377) (xy 199.880971 -407.593247) (xy 199.864218 -407.572464) (xy 199.854321 -407.560659)
			(xy 199.828997 -407.54314) (xy 199.799604 -407.533964) (xy 199.768812 -407.533964) (xy 199.739419 -407.54314)
			(xy 199.714095 -407.560659) (xy 199.704198 -407.572464) (xy 199.687445 -407.593247) (xy 199.649091 -407.630377)
			(xy 199.605937 -407.661799) (xy 199.558823 -407.686898) (xy 199.508671 -407.705184) (xy 199.45646 -407.716301)
			(xy 199.403208 -407.720031) (xy 199.349956 -407.716301) (xy 199.297745 -407.705184) (xy 199.247593 -407.686898)
			(xy 199.200479 -407.661799) (xy 199.157325 -407.630377) (xy 199.118971 -407.593247) (xy 199.102218 -407.572464)
			(xy 199.092321 -407.560659) (xy 199.066997 -407.54314) (xy 199.037604 -407.533964) (xy 199.006812 -407.533964)
			(xy 198.977419 -407.54314) (xy 198.952095 -407.560659) (xy 198.942198 -407.572464) (xy 198.924008 -407.594948)
			(xy 198.881991 -407.634685) (xy 198.834456 -407.667623) (xy 198.782493 -407.693007) (xy 198.727294 -407.710255)
			(xy 198.670124 -407.718972) (xy 198.641208 -407.71953) (xy 198.613956 -407.719045) (xy 198.560006 -407.711289)
			(xy 198.507709 -407.695935) (xy 198.458129 -407.673295) (xy 198.412276 -407.643829) (xy 198.371083 -407.608138)
			(xy 198.335389 -407.566948) (xy 198.30592 -407.521097) (xy 198.283275 -407.471519) (xy 198.267917 -407.419223)
			(xy 198.260157 -407.365274) (xy 198.2597 -407.338022) (xy 198.260232 -407.309105) (xy 198.268957 -407.251932)
			(xy 198.286208 -407.19673) (xy 198.311592 -407.144763) (xy 198.344528 -407.097223) (xy 198.38426 -407.055196)
			(xy 198.406766 -407.037032) (xy 198.418576 -407.027135) (xy 198.436104 -407.001811) (xy 198.445287 -406.972413)
			(xy 198.445291 -406.941614) (xy 198.436116 -406.912214) (xy 198.418595 -406.886884) (xy 198.406766 -406.877012)
			(xy 198.385981 -406.860259) (xy 198.348847 -406.821905) (xy 198.317422 -406.77875) (xy 198.29232 -406.731635)
			(xy 198.274031 -406.681481) (xy 198.262911 -406.629268) (xy 198.259179 -406.576014) (xy 198.262908 -406.522759)
			(xy 198.274023 -406.470545) (xy 198.292309 -406.420389) (xy 198.317408 -406.373273) (xy 198.34883 -406.330115)
			(xy 198.385961 -406.291759) (xy 198.406766 -406.275032) (xy 198.418576 -406.265135) (xy 198.436104 -406.239811)
			(xy 198.445287 -406.210413) (xy 198.445291 -406.179614) (xy 198.436116 -406.150214) (xy 198.418595 -406.124884)
			(xy 198.406766 -406.115012) (xy 198.384285 -406.09682) (xy 198.344553 -406.054801) (xy 198.31162 -406.007265)
			(xy 198.286238 -405.955303) (xy 198.268992 -405.900105) (xy 198.260274 -405.842937) (xy 198.2597 -405.814022)
			(xy 198.259751 -405.804034) (xy 198.260765 -405.784085) (xy 198.261732 -405.774144) (xy 198.262766 -405.759945)
			(xy 198.25785 -405.731917) (xy 198.245391 -405.706333) (xy 198.226357 -405.685179) (xy 198.202225 -405.670099)
			(xy 198.174868 -405.662263) (xy 198.16064 -405.661876) (xy 195.923408 -405.661876) (xy 195.89344 -405.661306)
			(xy 195.834236 -405.651967) (xy 195.777221 -405.633487) (xy 195.723796 -405.60632) (xy 195.675276 -405.571134)
			(xy 195.65366 -405.55037) (xy 194.02044 -403.916896) (xy 193.639694 -403.916896) (xy 193.467736 -404.089108)
			(xy 193.446121 -404.109887) (xy 193.397615 -404.145124) (xy 193.344197 -404.172343) (xy 193.287179 -404.190874)
			(xy 193.227965 -404.200262) (xy 193.197988 -404.200868) (xy 192.66916 -404.200868) (xy 192.639648 -404.200294)
			(xy 192.581332 -404.191172) (xy 192.525111 -404.173196) (xy 192.498472 -404.160482) (xy 192.487804 -404.155148)
			(xy 191.518794 -404.155148) (xy 191.488814 -404.15459) (xy 191.429593 -404.145205) (xy 191.37257 -404.126669)
			(xy 191.31915 -404.099438) (xy 191.27065 -404.064182) (xy 191.249046 -404.043388) (xy 191.071246 -403.865588)
			(xy 190.77559 -403.865588) (xy 190.77559 -403.924008) (xy 190.77813 -403.931628) (xy 190.779146 -403.935184)
			(xy 190.782956 -403.947376) (xy 191.886332 -405.050752) (xy 192.677034 -405.050752) (xy 193.341498 -404.386542)
			(xy 193.360202 -404.368518) (xy 193.402223 -404.337987) (xy 193.448503 -404.314407) (xy 193.497904 -404.298362)
			(xy 193.549207 -404.290245) (xy 193.575178 -404.289768) (xy 194.04076 -404.289768) (xy 194.066726 -404.290282)
			(xy 194.118018 -404.298413) (xy 194.167407 -404.314465) (xy 194.213677 -404.338044) (xy 194.255691 -404.368569)
			(xy 194.27444 -404.386542) (xy 194.6783 -404.790402) (xy 194.696312 -404.809124) (xy 194.726865 -404.851139)
			(xy 194.750479 -404.897412) (xy 194.766574 -404.946806) (xy 194.774755 -404.998108) (xy 194.775328 -405.024082)
			(xy 194.775328 -408.406652) (xy 197.498177 -408.406652) (xy 197.498177 -408.352148) (xy 197.505934 -408.2982)
			(xy 197.52129 -408.245904) (xy 197.543931 -408.196327) (xy 197.573398 -408.150476) (xy 197.609091 -408.109285)
			(xy 197.650282 -408.073594) (xy 197.696134 -408.044128) (xy 197.745712 -408.021487) (xy 197.798008 -408.006132)
			(xy 197.851956 -407.998377) (xy 197.879208 -407.997914) (xy 197.908123 -407.998493) (xy 197.965291 -408.007209)
			(xy 198.020489 -408.024455) (xy 198.072451 -408.049835) (xy 198.119987 -408.082768) (xy 198.162006 -408.122499)
			(xy 198.180198 -408.14498) (xy 198.190095 -408.156785) (xy 198.215419 -408.174304) (xy 198.244812 -408.18348)
			(xy 198.275604 -408.18348) (xy 198.304997 -408.174304) (xy 198.330321 -408.156785) (xy 198.340218 -408.14498)
			(xy 198.356971 -408.124197) (xy 198.395325 -408.087067) (xy 198.438479 -408.055645) (xy 198.485593 -408.030546)
			(xy 198.535745 -408.01226) (xy 198.587956 -408.001143) (xy 198.641208 -407.997413) (xy 198.69446 -408.001143)
			(xy 198.746671 -408.01226) (xy 198.796823 -408.030546) (xy 198.843937 -408.055645) (xy 198.887091 -408.087067)
			(xy 198.925445 -408.124197) (xy 198.942198 -408.14498) (xy 198.952095 -408.156785) (xy 198.977419 -408.174304)
			(xy 199.006812 -408.18348) (xy 199.037604 -408.18348) (xy 199.066997 -408.174304) (xy 199.092321 -408.156785)
			(xy 199.102218 -408.14498) (xy 199.118971 -408.124197) (xy 199.157325 -408.087067) (xy 199.200479 -408.055645)
			(xy 199.247593 -408.030546) (xy 199.297745 -408.01226) (xy 199.349956 -408.001143) (xy 199.403208 -407.997413)
			(xy 199.45646 -408.001143) (xy 199.508671 -408.01226) (xy 199.558823 -408.030546) (xy 199.605937 -408.055645)
			(xy 199.649091 -408.087067) (xy 199.687445 -408.124197) (xy 199.704198 -408.14498) (xy 199.714095 -408.156785)
			(xy 199.739419 -408.174304) (xy 199.768812 -408.18348) (xy 199.799604 -408.18348) (xy 199.828997 -408.174304)
			(xy 199.854321 -408.156785) (xy 199.864218 -408.14498) (xy 199.880971 -408.124197) (xy 199.919325 -408.087067)
			(xy 199.962479 -408.055645) (xy 200.009593 -408.030546) (xy 200.059745 -408.01226) (xy 200.111956 -408.001143)
			(xy 200.165208 -407.997413) (xy 200.21846 -408.001143) (xy 200.270671 -408.01226) (xy 200.320823 -408.030546)
			(xy 200.367937 -408.055645) (xy 200.411091 -408.087067) (xy 200.449445 -408.124197) (xy 200.466198 -408.14498)
			(xy 200.476095 -408.156785) (xy 200.501419 -408.174304) (xy 200.530812 -408.18348) (xy 200.561604 -408.18348)
			(xy 200.590997 -408.174304) (xy 200.616321 -408.156785) (xy 200.626218 -408.14498) (xy 200.642971 -408.124197)
			(xy 200.681325 -408.087067) (xy 200.724479 -408.055645) (xy 200.771593 -408.030546) (xy 200.821745 -408.01226)
			(xy 200.873956 -408.001143) (xy 200.927208 -407.997413) (xy 200.98046 -408.001143) (xy 201.032671 -408.01226)
			(xy 201.082823 -408.030546) (xy 201.129937 -408.055645) (xy 201.173091 -408.087067) (xy 201.211445 -408.124197)
			(xy 201.228198 -408.14498) (xy 201.238095 -408.156785) (xy 201.263419 -408.174304) (xy 201.292812 -408.18348)
			(xy 201.323604 -408.18348) (xy 201.352997 -408.174304) (xy 201.378321 -408.156785) (xy 201.388218 -408.14498)
			(xy 201.404971 -408.124197) (xy 201.443325 -408.087067) (xy 201.486479 -408.055645) (xy 201.533593 -408.030546)
			(xy 201.583745 -408.01226) (xy 201.635956 -408.001143) (xy 201.689208 -407.997413) (xy 201.74246 -408.001143)
			(xy 201.794671 -408.01226) (xy 201.844823 -408.030546) (xy 201.891937 -408.055645) (xy 201.935091 -408.087067)
			(xy 201.973445 -408.124197) (xy 201.990198 -408.14498) (xy 202.000095 -408.156785) (xy 202.025419 -408.174304)
			(xy 202.054812 -408.18348) (xy 202.085604 -408.18348) (xy 202.114997 -408.174304) (xy 202.140321 -408.156785)
			(xy 202.150218 -408.14498) (xy 202.168394 -408.122484) (xy 202.210417 -408.08275) (xy 202.257956 -408.049813)
			(xy 202.30992 -408.024427) (xy 202.36512 -408.007174) (xy 202.422291 -407.998448) (xy 202.451208 -407.997914)
			(xy 202.47846 -407.998356) (xy 202.53241 -408.006114) (xy 202.584707 -408.021471) (xy 202.634286 -408.044114)
			(xy 202.680138 -408.073582) (xy 202.72133 -408.109276) (xy 202.757023 -408.150468) (xy 202.78649 -408.196321)
			(xy 202.809132 -408.2459) (xy 202.824487 -408.298197) (xy 202.832244 -408.352148) (xy 202.832244 -408.406652)
			(xy 202.824487 -408.460603) (xy 202.809132 -408.5129) (xy 202.78649 -408.562479) (xy 202.757023 -408.608332)
			(xy 202.72133 -408.649524) (xy 202.680138 -408.685218) (xy 202.634286 -408.714686) (xy 202.584707 -408.737329)
			(xy 202.53241 -408.752686) (xy 202.47846 -408.760444) (xy 202.451208 -408.76093) (xy 202.42229 -408.760432)
			(xy 202.365117 -408.751703) (xy 202.309916 -408.734443) (xy 202.257954 -408.709047) (xy 202.210421 -408.676099)
			(xy 202.168406 -408.636352) (xy 202.150218 -408.613864) (xy 202.140321 -408.602059) (xy 202.114997 -408.58454)
			(xy 202.085604 -408.575364) (xy 202.054812 -408.575364) (xy 202.025419 -408.58454) (xy 202.000095 -408.602059)
			(xy 201.990198 -408.613864) (xy 201.973445 -408.634647) (xy 201.935091 -408.671777) (xy 201.891937 -408.703199)
			(xy 201.844823 -408.728298) (xy 201.794671 -408.746584) (xy 201.74246 -408.757701) (xy 201.689208 -408.761431)
			(xy 201.635956 -408.757701) (xy 201.583745 -408.746584) (xy 201.533593 -408.728298) (xy 201.486479 -408.703199)
			(xy 201.443325 -408.671777) (xy 201.404971 -408.634647) (xy 201.388218 -408.613864) (xy 201.378321 -408.602059)
			(xy 201.352997 -408.58454) (xy 201.323604 -408.575364) (xy 201.292812 -408.575364) (xy 201.263419 -408.58454)
			(xy 201.238095 -408.602059) (xy 201.228198 -408.613864) (xy 201.211445 -408.634647) (xy 201.173091 -408.671777)
			(xy 201.129937 -408.703199) (xy 201.082823 -408.728298) (xy 201.032671 -408.746584) (xy 200.98046 -408.757701)
			(xy 200.927208 -408.761431) (xy 200.873956 -408.757701) (xy 200.821745 -408.746584) (xy 200.771593 -408.728298)
			(xy 200.724479 -408.703199) (xy 200.681325 -408.671777) (xy 200.642971 -408.634647) (xy 200.626218 -408.613864)
			(xy 200.616321 -408.602059) (xy 200.590997 -408.58454) (xy 200.561604 -408.575364) (xy 200.530812 -408.575364)
			(xy 200.501419 -408.58454) (xy 200.476095 -408.602059) (xy 200.466198 -408.613864) (xy 200.449445 -408.634647)
			(xy 200.411091 -408.671777) (xy 200.367937 -408.703199) (xy 200.320823 -408.728298) (xy 200.270671 -408.746584)
			(xy 200.21846 -408.757701) (xy 200.165208 -408.761431) (xy 200.111956 -408.757701) (xy 200.059745 -408.746584)
			(xy 200.009593 -408.728298) (xy 199.962479 -408.703199) (xy 199.919325 -408.671777) (xy 199.880971 -408.634647)
			(xy 199.864218 -408.613864) (xy 199.854321 -408.602059) (xy 199.828997 -408.58454) (xy 199.799604 -408.575364)
			(xy 199.768812 -408.575364) (xy 199.739419 -408.58454) (xy 199.714095 -408.602059) (xy 199.704198 -408.613864)
			(xy 199.687445 -408.634647) (xy 199.649091 -408.671777) (xy 199.605937 -408.703199) (xy 199.558823 -408.728298)
			(xy 199.508671 -408.746584) (xy 199.45646 -408.757701) (xy 199.403208 -408.761431) (xy 199.349956 -408.757701)
			(xy 199.297745 -408.746584) (xy 199.247593 -408.728298) (xy 199.200479 -408.703199) (xy 199.157325 -408.671777)
			(xy 199.118971 -408.634647) (xy 199.102218 -408.613864) (xy 199.092321 -408.602059) (xy 199.066997 -408.58454)
			(xy 199.037604 -408.575364) (xy 199.006812 -408.575364) (xy 198.977419 -408.58454) (xy 198.952095 -408.602059)
			(xy 198.942198 -408.613864) (xy 198.925445 -408.634647) (xy 198.887091 -408.671777) (xy 198.843937 -408.703199)
			(xy 198.796823 -408.728298) (xy 198.746671 -408.746584) (xy 198.69446 -408.757701) (xy 198.641208 -408.761431)
			(xy 198.587956 -408.757701) (xy 198.535745 -408.746584) (xy 198.485593 -408.728298) (xy 198.438479 -408.703199)
			(xy 198.395325 -408.671777) (xy 198.356971 -408.634647) (xy 198.340218 -408.613864) (xy 198.330321 -408.602059)
			(xy 198.304997 -408.58454) (xy 198.275604 -408.575364) (xy 198.244812 -408.575364) (xy 198.215419 -408.58454)
			(xy 198.190095 -408.602059) (xy 198.180198 -408.613864) (xy 198.161999 -408.636341) (xy 198.119982 -408.676078)
			(xy 198.072449 -408.709019) (xy 198.020489 -408.734409) (xy 197.965293 -408.751666) (xy 197.908124 -408.760395)
			(xy 197.879208 -408.76093) (xy 197.851956 -408.760423) (xy 197.798008 -408.752668) (xy 197.745712 -408.737313)
			(xy 197.696134 -408.714672) (xy 197.650282 -408.685206) (xy 197.609091 -408.649515) (xy 197.573398 -408.608324)
			(xy 197.543931 -408.562473) (xy 197.52129 -408.512896) (xy 197.505934 -408.4606) (xy 197.498177 -408.406652)
			(xy 194.775328 -408.406652) (xy 194.775328 -409.448052) (xy 196.736177 -409.448052) (xy 196.736177 -409.393548)
			(xy 196.743934 -409.3396) (xy 196.75929 -409.287304) (xy 196.781931 -409.237727) (xy 196.811398 -409.191876)
			(xy 196.847091 -409.150685) (xy 196.888282 -409.114994) (xy 196.934134 -409.085528) (xy 196.983712 -409.062887)
			(xy 197.036008 -409.047532) (xy 197.089956 -409.039777) (xy 197.117208 -409.039314) (xy 197.146123 -409.039893)
			(xy 197.203291 -409.048609) (xy 197.258489 -409.065855) (xy 197.310451 -409.091235) (xy 197.357987 -409.124168)
			(xy 197.400006 -409.163899) (xy 197.418198 -409.18638) (xy 197.428095 -409.198185) (xy 197.453419 -409.215704)
			(xy 197.482812 -409.22488) (xy 197.513604 -409.22488) (xy 197.542997 -409.215704) (xy 197.568321 -409.198185)
			(xy 197.578218 -409.18638) (xy 197.594971 -409.165597) (xy 197.633325 -409.128467) (xy 197.676479 -409.097045)
			(xy 197.723593 -409.071946) (xy 197.773745 -409.05366) (xy 197.825956 -409.042543) (xy 197.879208 -409.038813)
			(xy 197.93246 -409.042543) (xy 197.984671 -409.05366) (xy 198.034823 -409.071946) (xy 198.081937 -409.097045)
			(xy 198.125091 -409.128467) (xy 198.163445 -409.165597) (xy 198.180198 -409.18638) (xy 198.190095 -409.198185)
			(xy 198.215419 -409.215704) (xy 198.244812 -409.22488) (xy 198.275604 -409.22488) (xy 198.304997 -409.215704)
			(xy 198.330321 -409.198185) (xy 198.340218 -409.18638) (xy 198.356971 -409.165597) (xy 198.395325 -409.128467)
			(xy 198.438479 -409.097045) (xy 198.485593 -409.071946) (xy 198.535745 -409.05366) (xy 198.587956 -409.042543)
			(xy 198.641208 -409.038813) (xy 198.69446 -409.042543) (xy 198.746671 -409.05366) (xy 198.796823 -409.071946)
			(xy 198.843937 -409.097045) (xy 198.887091 -409.128467) (xy 198.925445 -409.165597) (xy 198.942198 -409.18638)
			(xy 198.952095 -409.198185) (xy 198.977419 -409.215704) (xy 199.006812 -409.22488) (xy 199.037604 -409.22488)
			(xy 199.066997 -409.215704) (xy 199.092321 -409.198185) (xy 199.102218 -409.18638) (xy 199.118971 -409.165597)
			(xy 199.157325 -409.128467) (xy 199.200479 -409.097045) (xy 199.247593 -409.071946) (xy 199.297745 -409.05366)
			(xy 199.349956 -409.042543) (xy 199.403208 -409.038813) (xy 199.45646 -409.042543) (xy 199.508671 -409.05366)
			(xy 199.558823 -409.071946) (xy 199.605937 -409.097045) (xy 199.649091 -409.128467) (xy 199.687445 -409.165597)
			(xy 199.704198 -409.18638) (xy 199.714095 -409.198185) (xy 199.739419 -409.215704) (xy 199.768812 -409.22488)
			(xy 199.799604 -409.22488) (xy 199.828997 -409.215704) (xy 199.854321 -409.198185) (xy 199.864218 -409.18638)
			(xy 199.880971 -409.165597) (xy 199.919325 -409.128467) (xy 199.962479 -409.097045) (xy 200.009593 -409.071946)
			(xy 200.059745 -409.05366) (xy 200.111956 -409.042543) (xy 200.165208 -409.038813) (xy 200.21846 -409.042543)
			(xy 200.270671 -409.05366) (xy 200.320823 -409.071946) (xy 200.367937 -409.097045) (xy 200.411091 -409.128467)
			(xy 200.449445 -409.165597) (xy 200.466198 -409.18638) (xy 200.476095 -409.198185) (xy 200.501419 -409.215704)
			(xy 200.530812 -409.22488) (xy 200.561604 -409.22488) (xy 200.590997 -409.215704) (xy 200.616321 -409.198185)
			(xy 200.626218 -409.18638) (xy 200.642971 -409.165597) (xy 200.681325 -409.128467) (xy 200.724479 -409.097045)
			(xy 200.771593 -409.071946) (xy 200.821745 -409.05366) (xy 200.873956 -409.042543) (xy 200.927208 -409.038813)
			(xy 200.98046 -409.042543) (xy 201.032671 -409.05366) (xy 201.082823 -409.071946) (xy 201.129937 -409.097045)
			(xy 201.173091 -409.128467) (xy 201.211445 -409.165597) (xy 201.228198 -409.18638) (xy 201.238095 -409.198185)
			(xy 201.263419 -409.215704) (xy 201.292812 -409.22488) (xy 201.323604 -409.22488) (xy 201.352997 -409.215704)
			(xy 201.378321 -409.198185) (xy 201.388218 -409.18638) (xy 201.404971 -409.165597) (xy 201.443325 -409.128467)
			(xy 201.486479 -409.097045) (xy 201.533593 -409.071946) (xy 201.583745 -409.05366) (xy 201.635956 -409.042543)
			(xy 201.689208 -409.038813) (xy 201.74246 -409.042543) (xy 201.794671 -409.05366) (xy 201.844823 -409.071946)
			(xy 201.891937 -409.097045) (xy 201.935091 -409.128467) (xy 201.973445 -409.165597) (xy 201.990198 -409.18638)
			(xy 202.000095 -409.198185) (xy 202.025419 -409.215704) (xy 202.054812 -409.22488) (xy 202.085604 -409.22488)
			(xy 202.114997 -409.215704) (xy 202.140321 -409.198185) (xy 202.150218 -409.18638) (xy 202.168394 -409.163884)
			(xy 202.210417 -409.12415) (xy 202.257956 -409.091213) (xy 202.30992 -409.065827) (xy 202.36512 -409.048574)
			(xy 202.422291 -409.039848) (xy 202.451208 -409.039314) (xy 202.47846 -409.039756) (xy 202.53241 -409.047514)
			(xy 202.584707 -409.062871) (xy 202.634286 -409.085514) (xy 202.680138 -409.114982) (xy 202.72133 -409.150676)
			(xy 202.757023 -409.191868) (xy 202.78649 -409.237721) (xy 202.809132 -409.2873) (xy 202.824487 -409.339597)
			(xy 202.832244 -409.393548) (xy 202.832244 -409.448052) (xy 202.824487 -409.502003) (xy 202.809132 -409.5543)
			(xy 202.78649 -409.603879) (xy 202.757023 -409.649732) (xy 202.72133 -409.690924) (xy 202.680138 -409.726618)
			(xy 202.634286 -409.756086) (xy 202.584707 -409.778729) (xy 202.53241 -409.794086) (xy 202.47846 -409.801844)
			(xy 202.451208 -409.80233) (xy 202.42229 -409.801832) (xy 202.365117 -409.793103) (xy 202.309916 -409.775843)
			(xy 202.257954 -409.750447) (xy 202.210421 -409.717499) (xy 202.168406 -409.677752) (xy 202.150218 -409.655264)
			(xy 202.140321 -409.643459) (xy 202.114997 -409.62594) (xy 202.085604 -409.616764) (xy 202.054812 -409.616764)
			(xy 202.025419 -409.62594) (xy 202.000095 -409.643459) (xy 201.990198 -409.655264) (xy 201.973445 -409.676047)
			(xy 201.935091 -409.713177) (xy 201.891937 -409.744599) (xy 201.844823 -409.769698) (xy 201.794671 -409.787984)
			(xy 201.74246 -409.799101) (xy 201.689208 -409.802831) (xy 201.635956 -409.799101) (xy 201.583745 -409.787984)
			(xy 201.533593 -409.769698) (xy 201.486479 -409.744599) (xy 201.443325 -409.713177) (xy 201.404971 -409.676047)
			(xy 201.388218 -409.655264) (xy 201.378321 -409.643459) (xy 201.352997 -409.62594) (xy 201.323604 -409.616764)
			(xy 201.292812 -409.616764) (xy 201.263419 -409.62594) (xy 201.238095 -409.643459) (xy 201.228198 -409.655264)
			(xy 201.211445 -409.676047) (xy 201.173091 -409.713177) (xy 201.129937 -409.744599) (xy 201.082823 -409.769698)
			(xy 201.032671 -409.787984) (xy 200.98046 -409.799101) (xy 200.927208 -409.802831) (xy 200.873956 -409.799101)
			(xy 200.821745 -409.787984) (xy 200.771593 -409.769698) (xy 200.724479 -409.744599) (xy 200.681325 -409.713177)
			(xy 200.642971 -409.676047) (xy 200.626218 -409.655264) (xy 200.616321 -409.643459) (xy 200.590997 -409.62594)
			(xy 200.561604 -409.616764) (xy 200.530812 -409.616764) (xy 200.501419 -409.62594) (xy 200.476095 -409.643459)
			(xy 200.466198 -409.655264) (xy 200.449445 -409.676047) (xy 200.411091 -409.713177) (xy 200.367937 -409.744599)
			(xy 200.320823 -409.769698) (xy 200.270671 -409.787984) (xy 200.21846 -409.799101) (xy 200.165208 -409.802831)
			(xy 200.111956 -409.799101) (xy 200.059745 -409.787984) (xy 200.009593 -409.769698) (xy 199.962479 -409.744599)
			(xy 199.919325 -409.713177) (xy 199.880971 -409.676047) (xy 199.864218 -409.655264) (xy 199.854321 -409.643459)
			(xy 199.828997 -409.62594) (xy 199.799604 -409.616764) (xy 199.768812 -409.616764) (xy 199.739419 -409.62594)
			(xy 199.714095 -409.643459) (xy 199.704198 -409.655264) (xy 199.687445 -409.676047) (xy 199.649091 -409.713177)
			(xy 199.605937 -409.744599) (xy 199.558823 -409.769698) (xy 199.508671 -409.787984) (xy 199.45646 -409.799101)
			(xy 199.403208 -409.802831) (xy 199.349956 -409.799101) (xy 199.297745 -409.787984) (xy 199.247593 -409.769698)
			(xy 199.200479 -409.744599) (xy 199.157325 -409.713177) (xy 199.118971 -409.676047) (xy 199.102218 -409.655264)
			(xy 199.092321 -409.643459) (xy 199.066997 -409.62594) (xy 199.037604 -409.616764) (xy 199.006812 -409.616764)
			(xy 198.977419 -409.62594) (xy 198.952095 -409.643459) (xy 198.942198 -409.655264) (xy 198.925445 -409.676047)
			(xy 198.887091 -409.713177) (xy 198.843937 -409.744599) (xy 198.796823 -409.769698) (xy 198.746671 -409.787984)
			(xy 198.69446 -409.799101) (xy 198.641208 -409.802831) (xy 198.587956 -409.799101) (xy 198.535745 -409.787984)
			(xy 198.485593 -409.769698) (xy 198.438479 -409.744599) (xy 198.395325 -409.713177) (xy 198.356971 -409.676047)
			(xy 198.340218 -409.655264) (xy 198.330321 -409.643459) (xy 198.304997 -409.62594) (xy 198.275604 -409.616764)
			(xy 198.244812 -409.616764) (xy 198.215419 -409.62594) (xy 198.190095 -409.643459) (xy 198.180198 -409.655264)
			(xy 198.163445 -409.676047) (xy 198.125091 -409.713177) (xy 198.081937 -409.744599) (xy 198.034823 -409.769698)
			(xy 197.984671 -409.787984) (xy 197.93246 -409.799101) (xy 197.879208 -409.802831) (xy 197.825956 -409.799101)
			(xy 197.773745 -409.787984) (xy 197.723593 -409.769698) (xy 197.676479 -409.744599) (xy 197.633325 -409.713177)
			(xy 197.594971 -409.676047) (xy 197.578218 -409.655264) (xy 197.568321 -409.643459) (xy 197.542997 -409.62594)
			(xy 197.513604 -409.616764) (xy 197.482812 -409.616764) (xy 197.453419 -409.62594) (xy 197.428095 -409.643459)
			(xy 197.418198 -409.655264) (xy 197.399999 -409.677741) (xy 197.357982 -409.717478) (xy 197.310449 -409.750419)
			(xy 197.258489 -409.775809) (xy 197.203293 -409.793066) (xy 197.146124 -409.801795) (xy 197.117208 -409.80233)
			(xy 197.089956 -409.801823) (xy 197.036008 -409.794068) (xy 196.983712 -409.778713) (xy 196.934134 -409.756072)
			(xy 196.888282 -409.726606) (xy 196.847091 -409.690915) (xy 196.811398 -409.649724) (xy 196.781931 -409.603873)
			(xy 196.75929 -409.554296) (xy 196.743934 -409.502) (xy 196.736177 -409.448052) (xy 194.775328 -409.448052)
			(xy 194.775328 -410.79928) (xy 195.542662 -411.566868) (xy 202.922378 -411.566868) (xy 203.31938 -411.169612)
			(xy 203.31938 -408.407362) (xy 203.319875 -408.38138) (xy 203.328033 -408.33006) (xy 203.344125 -408.28065)
			(xy 203.367756 -408.23437) (xy 203.398341 -408.19236) (xy 203.416408 -408.173682) (xy 204.968348 -406.621742)
			(xy 204.987051 -406.603715) (xy 205.02907 -406.573177) (xy 205.07535 -406.549591) (xy 205.124751 -406.533538)
			(xy 205.176056 -406.525414) (xy 205.202028 -406.524968) (xy 206.223108 -406.524968) (xy 206.244906 -406.512827)
			(xy 206.290999 -406.493724) (xy 206.339192 -406.480804) (xy 206.38866 -406.474288) (xy 206.413608 -406.473914)
			(xy 206.440655 -406.474386) (xy 206.494206 -406.482029) (xy 206.546141 -406.497159) (xy 206.595417 -406.519474)
			(xy 206.641047 -406.548527) (xy 206.682116 -406.583733) (xy 206.717799 -406.624388) (xy 206.747382 -406.669676)
			(xy 206.77027 -406.718689) (xy 206.778606 -406.744424) (xy 206.782416 -406.756616) (xy 207.129888 -407.104342)
			(xy 207.147904 -407.123062) (xy 207.178466 -407.165076) (xy 207.202089 -407.211348) (xy 207.218194 -407.260742)
			(xy 207.226384 -407.312046) (xy 207.226916 -407.338022) (xy 207.226916 -408.406652) (xy 208.166177 -408.406652)
			(xy 208.166177 -408.352148) (xy 208.173934 -408.2982) (xy 208.18929 -408.245904) (xy 208.211931 -408.196327)
			(xy 208.241398 -408.150476) (xy 208.277091 -408.109285) (xy 208.318282 -408.073594) (xy 208.364134 -408.044128)
			(xy 208.413712 -408.021487) (xy 208.466008 -408.006132) (xy 208.519956 -407.998377) (xy 208.547208 -407.997914)
			(xy 208.576123 -407.998493) (xy 208.633291 -408.007209) (xy 208.688489 -408.024455) (xy 208.740451 -408.049835)
			(xy 208.787987 -408.082768) (xy 208.830006 -408.122499) (xy 208.848198 -408.14498) (xy 208.858095 -408.156785)
			(xy 208.883419 -408.174304) (xy 208.912812 -408.18348) (xy 208.943604 -408.18348) (xy 208.972997 -408.174304)
			(xy 208.998321 -408.156785) (xy 209.008218 -408.14498) (xy 209.024971 -408.124197) (xy 209.063325 -408.087067)
			(xy 209.106479 -408.055645) (xy 209.153593 -408.030546) (xy 209.203745 -408.01226) (xy 209.255956 -408.001143)
			(xy 209.309208 -407.997413) (xy 209.36246 -408.001143) (xy 209.414671 -408.01226) (xy 209.464823 -408.030546)
			(xy 209.511937 -408.055645) (xy 209.555091 -408.087067) (xy 209.593445 -408.124197) (xy 209.610198 -408.14498)
			(xy 209.620095 -408.156785) (xy 209.645419 -408.174304) (xy 209.674812 -408.18348) (xy 209.705604 -408.18348)
			(xy 209.734997 -408.174304) (xy 209.760321 -408.156785) (xy 209.770218 -408.14498) (xy 209.786971 -408.124197)
			(xy 209.825325 -408.087067) (xy 209.868479 -408.055645) (xy 209.915593 -408.030546) (xy 209.965745 -408.01226)
			(xy 210.017956 -408.001143) (xy 210.071208 -407.997413) (xy 210.12446 -408.001143) (xy 210.176671 -408.01226)
			(xy 210.226823 -408.030546) (xy 210.273937 -408.055645) (xy 210.317091 -408.087067) (xy 210.355445 -408.124197)
			(xy 210.372198 -408.14498) (xy 210.382095 -408.156785) (xy 210.407419 -408.174304) (xy 210.436812 -408.18348)
			(xy 210.467604 -408.18348) (xy 210.496997 -408.174304) (xy 210.522321 -408.156785) (xy 210.532218 -408.14498)
			(xy 210.548971 -408.124197) (xy 210.587325 -408.087067) (xy 210.630479 -408.055645) (xy 210.677593 -408.030546)
			(xy 210.727745 -408.01226) (xy 210.779956 -408.001143) (xy 210.833208 -407.997413) (xy 210.88646 -408.001143)
			(xy 210.938671 -408.01226) (xy 210.988823 -408.030546) (xy 211.035937 -408.055645) (xy 211.079091 -408.087067)
			(xy 211.117445 -408.124197) (xy 211.134198 -408.14498) (xy 211.144095 -408.156785) (xy 211.169419 -408.174304)
			(xy 211.198812 -408.18348) (xy 211.229604 -408.18348) (xy 211.258997 -408.174304) (xy 211.284321 -408.156785)
			(xy 211.294218 -408.14498) (xy 211.310971 -408.124197) (xy 211.349325 -408.087067) (xy 211.392479 -408.055645)
			(xy 211.439593 -408.030546) (xy 211.489745 -408.01226) (xy 211.541956 -408.001143) (xy 211.595208 -407.997413)
			(xy 211.64846 -408.001143) (xy 211.700671 -408.01226) (xy 211.750823 -408.030546) (xy 211.797937 -408.055645)
			(xy 211.841091 -408.087067) (xy 211.879445 -408.124197) (xy 211.896198 -408.14498) (xy 211.906095 -408.156785)
			(xy 211.931419 -408.174304) (xy 211.960812 -408.18348) (xy 211.991604 -408.18348) (xy 212.020997 -408.174304)
			(xy 212.046321 -408.156785) (xy 212.056218 -408.14498) (xy 212.072971 -408.124197) (xy 212.111325 -408.087067)
			(xy 212.154479 -408.055645) (xy 212.201593 -408.030546) (xy 212.251745 -408.01226) (xy 212.303956 -408.001143)
			(xy 212.357208 -407.997413) (xy 212.41046 -408.001143) (xy 212.462671 -408.01226) (xy 212.512823 -408.030546)
			(xy 212.559937 -408.055645) (xy 212.603091 -408.087067) (xy 212.641445 -408.124197) (xy 212.658198 -408.14498)
			(xy 212.668095 -408.156785) (xy 212.693419 -408.174304) (xy 212.722812 -408.18348) (xy 212.753604 -408.18348)
			(xy 212.782997 -408.174304) (xy 212.808321 -408.156785) (xy 212.818218 -408.14498) (xy 212.836394 -408.122484)
			(xy 212.878417 -408.08275) (xy 212.925956 -408.049813) (xy 212.97792 -408.024427) (xy 213.03312 -408.007174)
			(xy 213.090291 -407.998448) (xy 213.119208 -407.997914) (xy 213.14646 -407.998356) (xy 213.20041 -408.006114)
			(xy 213.252707 -408.021471) (xy 213.302286 -408.044114) (xy 213.348138 -408.073582) (xy 213.38933 -408.109276)
			(xy 213.425023 -408.150468) (xy 213.45449 -408.196321) (xy 213.477132 -408.2459) (xy 213.492487 -408.298197)
			(xy 213.500244 -408.352148) (xy 213.500244 -408.406652) (xy 213.492487 -408.460603) (xy 213.477132 -408.5129)
			(xy 213.45449 -408.562479) (xy 213.425023 -408.608332) (xy 213.38933 -408.649524) (xy 213.348138 -408.685218)
			(xy 213.302286 -408.714686) (xy 213.252707 -408.737329) (xy 213.20041 -408.752686) (xy 213.14646 -408.760444)
			(xy 213.119208 -408.76093) (xy 213.09029 -408.760432) (xy 213.033117 -408.751703) (xy 212.977916 -408.734443)
			(xy 212.925954 -408.709047) (xy 212.878421 -408.676099) (xy 212.836406 -408.636352) (xy 212.818218 -408.613864)
			(xy 212.808321 -408.602059) (xy 212.782997 -408.58454) (xy 212.753604 -408.575364) (xy 212.722812 -408.575364)
			(xy 212.693419 -408.58454) (xy 212.668095 -408.602059) (xy 212.658198 -408.613864) (xy 212.641445 -408.634647)
			(xy 212.603091 -408.671777) (xy 212.559937 -408.703199) (xy 212.512823 -408.728298) (xy 212.462671 -408.746584)
			(xy 212.41046 -408.757701) (xy 212.357208 -408.761431) (xy 212.303956 -408.757701) (xy 212.251745 -408.746584)
			(xy 212.201593 -408.728298) (xy 212.154479 -408.703199) (xy 212.111325 -408.671777) (xy 212.072971 -408.634647)
			(xy 212.056218 -408.613864) (xy 212.046321 -408.602059) (xy 212.020997 -408.58454) (xy 211.991604 -408.575364)
			(xy 211.960812 -408.575364) (xy 211.931419 -408.58454) (xy 211.906095 -408.602059) (xy 211.896198 -408.613864)
			(xy 211.879445 -408.634647) (xy 211.841091 -408.671777) (xy 211.797937 -408.703199) (xy 211.750823 -408.728298)
			(xy 211.700671 -408.746584) (xy 211.64846 -408.757701) (xy 211.595208 -408.761431) (xy 211.541956 -408.757701)
			(xy 211.489745 -408.746584) (xy 211.439593 -408.728298) (xy 211.392479 -408.703199) (xy 211.349325 -408.671777)
			(xy 211.310971 -408.634647) (xy 211.294218 -408.613864) (xy 211.284321 -408.602059) (xy 211.258997 -408.58454)
			(xy 211.229604 -408.575364) (xy 211.198812 -408.575364) (xy 211.169419 -408.58454) (xy 211.144095 -408.602059)
			(xy 211.134198 -408.613864) (xy 211.117445 -408.634647) (xy 211.079091 -408.671777) (xy 211.035937 -408.703199)
			(xy 210.988823 -408.728298) (xy 210.938671 -408.746584) (xy 210.88646 -408.757701) (xy 210.833208 -408.761431)
			(xy 210.779956 -408.757701) (xy 210.727745 -408.746584) (xy 210.677593 -408.728298) (xy 210.630479 -408.703199)
			(xy 210.587325 -408.671777) (xy 210.548971 -408.634647) (xy 210.532218 -408.613864) (xy 210.522321 -408.602059)
			(xy 210.496997 -408.58454) (xy 210.467604 -408.575364) (xy 210.436812 -408.575364) (xy 210.407419 -408.58454)
			(xy 210.382095 -408.602059) (xy 210.372198 -408.613864) (xy 210.355445 -408.634647) (xy 210.317091 -408.671777)
			(xy 210.273937 -408.703199) (xy 210.226823 -408.728298) (xy 210.176671 -408.746584) (xy 210.12446 -408.757701)
			(xy 210.071208 -408.761431) (xy 210.017956 -408.757701) (xy 209.965745 -408.746584) (xy 209.915593 -408.728298)
			(xy 209.868479 -408.703199) (xy 209.825325 -408.671777) (xy 209.786971 -408.634647) (xy 209.770218 -408.613864)
			(xy 209.760321 -408.602059) (xy 209.734997 -408.58454) (xy 209.705604 -408.575364) (xy 209.674812 -408.575364)
			(xy 209.645419 -408.58454) (xy 209.620095 -408.602059) (xy 209.610198 -408.613864) (xy 209.593445 -408.634647)
			(xy 209.555091 -408.671777) (xy 209.511937 -408.703199) (xy 209.464823 -408.728298) (xy 209.414671 -408.746584)
			(xy 209.36246 -408.757701) (xy 209.309208 -408.761431) (xy 209.255956 -408.757701) (xy 209.203745 -408.746584)
			(xy 209.153593 -408.728298) (xy 209.106479 -408.703199) (xy 209.063325 -408.671777) (xy 209.024971 -408.634647)
			(xy 209.008218 -408.613864) (xy 208.998321 -408.602059) (xy 208.972997 -408.58454) (xy 208.943604 -408.575364)
			(xy 208.912812 -408.575364) (xy 208.883419 -408.58454) (xy 208.858095 -408.602059) (xy 208.848198 -408.613864)
			(xy 208.829999 -408.636341) (xy 208.787982 -408.676078) (xy 208.740449 -408.709019) (xy 208.688489 -408.734409)
			(xy 208.633293 -408.751666) (xy 208.576124 -408.760395) (xy 208.547208 -408.76093) (xy 208.519956 -408.760423)
			(xy 208.466008 -408.752668) (xy 208.413712 -408.737313) (xy 208.364134 -408.714672) (xy 208.318282 -408.685206)
			(xy 208.277091 -408.649515) (xy 208.241398 -408.608324) (xy 208.211931 -408.562473) (xy 208.18929 -408.512896)
			(xy 208.173934 -408.4606) (xy 208.166177 -408.406652) (xy 207.226916 -408.406652) (xy 207.226916 -409.448052)
			(xy 207.404177 -409.448052) (xy 207.404177 -409.393548) (xy 207.411934 -409.3396) (xy 207.42729 -409.287304)
			(xy 207.449931 -409.237727) (xy 207.479398 -409.191876) (xy 207.515091 -409.150685) (xy 207.556282 -409.114994)
			(xy 207.602134 -409.085528) (xy 207.651712 -409.062887) (xy 207.704008 -409.047532) (xy 207.757956 -409.039777)
			(xy 207.785208 -409.039314) (xy 207.814123 -409.039893) (xy 207.871291 -409.048609) (xy 207.926489 -409.065855)
			(xy 207.978451 -409.091235) (xy 208.025987 -409.124168) (xy 208.068006 -409.163899) (xy 208.086198 -409.18638)
			(xy 208.096095 -409.198185) (xy 208.121419 -409.215704) (xy 208.150812 -409.22488) (xy 208.181604 -409.22488)
			(xy 208.210997 -409.215704) (xy 208.236321 -409.198185) (xy 208.246218 -409.18638) (xy 208.262971 -409.165597)
			(xy 208.301325 -409.128467) (xy 208.344479 -409.097045) (xy 208.391593 -409.071946) (xy 208.441745 -409.05366)
			(xy 208.493956 -409.042543) (xy 208.547208 -409.038813) (xy 208.60046 -409.042543) (xy 208.652671 -409.05366)
			(xy 208.702823 -409.071946) (xy 208.749937 -409.097045) (xy 208.793091 -409.128467) (xy 208.831445 -409.165597)
			(xy 208.848198 -409.18638) (xy 208.858095 -409.198185) (xy 208.883419 -409.215704) (xy 208.912812 -409.22488)
			(xy 208.943604 -409.22488) (xy 208.972997 -409.215704) (xy 208.998321 -409.198185) (xy 209.008218 -409.18638)
			(xy 209.024971 -409.165597) (xy 209.063325 -409.128467) (xy 209.106479 -409.097045) (xy 209.153593 -409.071946)
			(xy 209.203745 -409.05366) (xy 209.255956 -409.042543) (xy 209.309208 -409.038813) (xy 209.36246 -409.042543)
			(xy 209.414671 -409.05366) (xy 209.464823 -409.071946) (xy 209.511937 -409.097045) (xy 209.555091 -409.128467)
			(xy 209.593445 -409.165597) (xy 209.610198 -409.18638) (xy 209.620095 -409.198185) (xy 209.645419 -409.215704)
			(xy 209.674812 -409.22488) (xy 209.705604 -409.22488) (xy 209.734997 -409.215704) (xy 209.760321 -409.198185)
			(xy 209.770218 -409.18638) (xy 209.786971 -409.165597) (xy 209.825325 -409.128467) (xy 209.868479 -409.097045)
			(xy 209.915593 -409.071946) (xy 209.965745 -409.05366) (xy 210.017956 -409.042543) (xy 210.071208 -409.038813)
			(xy 210.12446 -409.042543) (xy 210.176671 -409.05366) (xy 210.226823 -409.071946) (xy 210.273937 -409.097045)
			(xy 210.317091 -409.128467) (xy 210.355445 -409.165597) (xy 210.372198 -409.18638) (xy 210.382095 -409.198185)
			(xy 210.407419 -409.215704) (xy 210.436812 -409.22488) (xy 210.467604 -409.22488) (xy 210.496997 -409.215704)
			(xy 210.522321 -409.198185) (xy 210.532218 -409.18638) (xy 210.548971 -409.165597) (xy 210.587325 -409.128467)
			(xy 210.630479 -409.097045) (xy 210.677593 -409.071946) (xy 210.727745 -409.05366) (xy 210.779956 -409.042543)
			(xy 210.833208 -409.038813) (xy 210.88646 -409.042543) (xy 210.938671 -409.05366) (xy 210.988823 -409.071946)
			(xy 211.035937 -409.097045) (xy 211.079091 -409.128467) (xy 211.117445 -409.165597) (xy 211.134198 -409.18638)
			(xy 211.144095 -409.198185) (xy 211.169419 -409.215704) (xy 211.198812 -409.22488) (xy 211.229604 -409.22488)
			(xy 211.258997 -409.215704) (xy 211.284321 -409.198185) (xy 211.294218 -409.18638) (xy 211.310971 -409.165597)
			(xy 211.349325 -409.128467) (xy 211.392479 -409.097045) (xy 211.439593 -409.071946) (xy 211.489745 -409.05366)
			(xy 211.541956 -409.042543) (xy 211.595208 -409.038813) (xy 211.64846 -409.042543) (xy 211.700671 -409.05366)
			(xy 211.750823 -409.071946) (xy 211.797937 -409.097045) (xy 211.841091 -409.128467) (xy 211.879445 -409.165597)
			(xy 211.896198 -409.18638) (xy 211.906095 -409.198185) (xy 211.931419 -409.215704) (xy 211.960812 -409.22488)
			(xy 211.991604 -409.22488) (xy 212.020997 -409.215704) (xy 212.046321 -409.198185) (xy 212.056218 -409.18638)
			(xy 212.072971 -409.165597) (xy 212.111325 -409.128467) (xy 212.154479 -409.097045) (xy 212.201593 -409.071946)
			(xy 212.251745 -409.05366) (xy 212.303956 -409.042543) (xy 212.357208 -409.038813) (xy 212.41046 -409.042543)
			(xy 212.462671 -409.05366) (xy 212.512823 -409.071946) (xy 212.559937 -409.097045) (xy 212.603091 -409.128467)
			(xy 212.641445 -409.165597) (xy 212.658198 -409.18638) (xy 212.668095 -409.198185) (xy 212.693419 -409.215704)
			(xy 212.722812 -409.22488) (xy 212.753604 -409.22488) (xy 212.782997 -409.215704) (xy 212.808321 -409.198185)
			(xy 212.818218 -409.18638) (xy 212.836394 -409.163884) (xy 212.878417 -409.12415) (xy 212.925956 -409.091213)
			(xy 212.97792 -409.065827) (xy 213.03312 -409.048574) (xy 213.090291 -409.039848) (xy 213.119208 -409.039314)
			(xy 213.14646 -409.039756) (xy 213.20041 -409.047514) (xy 213.252707 -409.062871) (xy 213.302286 -409.085514)
			(xy 213.348138 -409.114982) (xy 213.38933 -409.150676) (xy 213.425023 -409.191868) (xy 213.45449 -409.237721)
			(xy 213.477132 -409.2873) (xy 213.492487 -409.339597) (xy 213.500244 -409.393548) (xy 213.500244 -409.448052)
			(xy 213.492487 -409.502003) (xy 213.477132 -409.5543) (xy 213.45449 -409.603879) (xy 213.425023 -409.649732)
			(xy 213.38933 -409.690924) (xy 213.348138 -409.726618) (xy 213.302286 -409.756086) (xy 213.252707 -409.778729)
			(xy 213.20041 -409.794086) (xy 213.14646 -409.801844) (xy 213.119208 -409.80233) (xy 213.09029 -409.801832)
			(xy 213.033117 -409.793103) (xy 212.977916 -409.775843) (xy 212.925954 -409.750447) (xy 212.878421 -409.717499)
			(xy 212.836406 -409.677752) (xy 212.818218 -409.655264) (xy 212.808321 -409.643459) (xy 212.782997 -409.62594)
			(xy 212.753604 -409.616764) (xy 212.722812 -409.616764) (xy 212.693419 -409.62594) (xy 212.668095 -409.643459)
			(xy 212.658198 -409.655264) (xy 212.641445 -409.676047) (xy 212.603091 -409.713177) (xy 212.559937 -409.744599)
			(xy 212.512823 -409.769698) (xy 212.462671 -409.787984) (xy 212.41046 -409.799101) (xy 212.357208 -409.802831)
			(xy 212.303956 -409.799101) (xy 212.251745 -409.787984) (xy 212.201593 -409.769698) (xy 212.154479 -409.744599)
			(xy 212.111325 -409.713177) (xy 212.072971 -409.676047) (xy 212.056218 -409.655264) (xy 212.046321 -409.643459)
			(xy 212.020997 -409.62594) (xy 211.991604 -409.616764) (xy 211.960812 -409.616764) (xy 211.931419 -409.62594)
			(xy 211.906095 -409.643459) (xy 211.896198 -409.655264) (xy 211.879445 -409.676047) (xy 211.841091 -409.713177)
			(xy 211.797937 -409.744599) (xy 211.750823 -409.769698) (xy 211.700671 -409.787984) (xy 211.64846 -409.799101)
			(xy 211.595208 -409.802831) (xy 211.541956 -409.799101) (xy 211.489745 -409.787984) (xy 211.439593 -409.769698)
			(xy 211.392479 -409.744599) (xy 211.349325 -409.713177) (xy 211.310971 -409.676047) (xy 211.294218 -409.655264)
			(xy 211.284321 -409.643459) (xy 211.258997 -409.62594) (xy 211.229604 -409.616764) (xy 211.198812 -409.616764)
			(xy 211.169419 -409.62594) (xy 211.144095 -409.643459) (xy 211.134198 -409.655264) (xy 211.117445 -409.676047)
			(xy 211.079091 -409.713177) (xy 211.035937 -409.744599) (xy 210.988823 -409.769698) (xy 210.938671 -409.787984)
			(xy 210.88646 -409.799101) (xy 210.833208 -409.802831) (xy 210.779956 -409.799101) (xy 210.727745 -409.787984)
			(xy 210.677593 -409.769698) (xy 210.630479 -409.744599) (xy 210.587325 -409.713177) (xy 210.548971 -409.676047)
			(xy 210.532218 -409.655264) (xy 210.522321 -409.643459) (xy 210.496997 -409.62594) (xy 210.467604 -409.616764)
			(xy 210.436812 -409.616764) (xy 210.407419 -409.62594) (xy 210.382095 -409.643459) (xy 210.372198 -409.655264)
			(xy 210.355445 -409.676047) (xy 210.317091 -409.713177) (xy 210.273937 -409.744599) (xy 210.226823 -409.769698)
			(xy 210.176671 -409.787984) (xy 210.12446 -409.799101) (xy 210.071208 -409.802831) (xy 210.017956 -409.799101)
			(xy 209.965745 -409.787984) (xy 209.915593 -409.769698) (xy 209.868479 -409.744599) (xy 209.825325 -409.713177)
			(xy 209.786971 -409.676047) (xy 209.770218 -409.655264) (xy 209.760321 -409.643459) (xy 209.734997 -409.62594)
			(xy 209.705604 -409.616764) (xy 209.674812 -409.616764) (xy 209.645419 -409.62594) (xy 209.620095 -409.643459)
			(xy 209.610198 -409.655264) (xy 209.593445 -409.676047) (xy 209.555091 -409.713177) (xy 209.511937 -409.744599)
			(xy 209.464823 -409.769698) (xy 209.414671 -409.787984) (xy 209.36246 -409.799101) (xy 209.309208 -409.802831)
			(xy 209.255956 -409.799101) (xy 209.203745 -409.787984) (xy 209.153593 -409.769698) (xy 209.106479 -409.744599)
			(xy 209.063325 -409.713177) (xy 209.024971 -409.676047) (xy 209.008218 -409.655264) (xy 208.998321 -409.643459)
			(xy 208.972997 -409.62594) (xy 208.943604 -409.616764) (xy 208.912812 -409.616764) (xy 208.883419 -409.62594)
			(xy 208.858095 -409.643459) (xy 208.848198 -409.655264) (xy 208.831445 -409.676047) (xy 208.793091 -409.713177)
			(xy 208.749937 -409.744599) (xy 208.702823 -409.769698) (xy 208.652671 -409.787984) (xy 208.60046 -409.799101)
			(xy 208.547208 -409.802831) (xy 208.493956 -409.799101) (xy 208.441745 -409.787984) (xy 208.391593 -409.769698)
			(xy 208.344479 -409.744599) (xy 208.301325 -409.713177) (xy 208.262971 -409.676047) (xy 208.246218 -409.655264)
			(xy 208.236321 -409.643459) (xy 208.210997 -409.62594) (xy 208.181604 -409.616764) (xy 208.150812 -409.616764)
			(xy 208.121419 -409.62594) (xy 208.096095 -409.643459) (xy 208.086198 -409.655264) (xy 208.067999 -409.677741)
			(xy 208.025982 -409.717478) (xy 207.978449 -409.750419) (xy 207.926489 -409.775809) (xy 207.871293 -409.793066)
			(xy 207.814124 -409.801795) (xy 207.785208 -409.80233) (xy 207.757956 -409.801823) (xy 207.704008 -409.794068)
			(xy 207.651712 -409.778713) (xy 207.602134 -409.756072) (xy 207.556282 -409.726606) (xy 207.515091 -409.690915)
			(xy 207.479398 -409.649724) (xy 207.449931 -409.603873) (xy 207.42729 -409.554296) (xy 207.411934 -409.502)
			(xy 207.404177 -409.448052) (xy 207.226916 -409.448052) (xy 207.226916 -411.171136) (xy 207.703674 -411.648148)
			(xy 213.795102 -411.648148) (xy 214.17534 -411.267656) (xy 214.17534 -408.359102) (xy 214.17584 -408.333122)
			(xy 214.184005 -408.281806) (xy 214.200103 -408.232401) (xy 214.223736 -408.186125) (xy 214.254323 -408.14412)
			(xy 214.272368 -408.125422) (xy 215.776048 -406.621742) (xy 215.794751 -406.603715) (xy 215.83677 -406.573177)
			(xy 215.88305 -406.549591) (xy 215.932451 -406.533538) (xy 215.983756 -406.525414) (xy 216.009728 -406.524968)
			(xy 216.891108 -406.524968) (xy 216.912906 -406.512827) (xy 216.958999 -406.493724) (xy 217.007192 -406.480804)
			(xy 217.05666 -406.474288) (xy 217.081608 -406.473914) (xy 217.108655 -406.474386) (xy 217.162206 -406.482029)
			(xy 217.214141 -406.497159) (xy 217.263417 -406.519474) (xy 217.309047 -406.548527) (xy 217.350116 -406.583733)
			(xy 217.385799 -406.624388) (xy 217.415382 -406.669676) (xy 217.43827 -406.718689) (xy 217.446606 -406.744424)
			(xy 217.450416 -406.756616) (xy 217.797888 -407.104342) (xy 217.815904 -407.123062) (xy 217.846466 -407.165076)
			(xy 217.870089 -407.211348) (xy 217.886194 -407.260742) (xy 217.894384 -407.312046) (xy 217.894916 -407.338022)
			(xy 217.894916 -408.406652) (xy 218.834177 -408.406652) (xy 218.834177 -408.352148) (xy 218.841934 -408.2982)
			(xy 218.85729 -408.245904) (xy 218.879931 -408.196327) (xy 218.909398 -408.150476) (xy 218.945091 -408.109285)
			(xy 218.986282 -408.073594) (xy 219.032134 -408.044128) (xy 219.081712 -408.021487) (xy 219.134008 -408.006132)
			(xy 219.187956 -407.998377) (xy 219.215208 -407.997914) (xy 219.244123 -407.998493) (xy 219.301291 -408.007209)
			(xy 219.356489 -408.024455) (xy 219.408451 -408.049835) (xy 219.455987 -408.082768) (xy 219.498006 -408.122499)
			(xy 219.516198 -408.14498) (xy 219.526095 -408.156785) (xy 219.551419 -408.174304) (xy 219.580812 -408.18348)
			(xy 219.611604 -408.18348) (xy 219.640997 -408.174304) (xy 219.666321 -408.156785) (xy 219.676218 -408.14498)
			(xy 219.692971 -408.124197) (xy 219.731325 -408.087067) (xy 219.774479 -408.055645) (xy 219.821593 -408.030546)
			(xy 219.871745 -408.01226) (xy 219.923956 -408.001143) (xy 219.977208 -407.997413) (xy 220.03046 -408.001143)
			(xy 220.082671 -408.01226) (xy 220.132823 -408.030546) (xy 220.179937 -408.055645) (xy 220.223091 -408.087067)
			(xy 220.261445 -408.124197) (xy 220.278198 -408.14498) (xy 220.288095 -408.156785) (xy 220.313419 -408.174304)
			(xy 220.342812 -408.18348) (xy 220.373604 -408.18348) (xy 220.402997 -408.174304) (xy 220.428321 -408.156785)
			(xy 220.438218 -408.14498) (xy 220.454971 -408.124197) (xy 220.493325 -408.087067) (xy 220.536479 -408.055645)
			(xy 220.583593 -408.030546) (xy 220.633745 -408.01226) (xy 220.685956 -408.001143) (xy 220.739208 -407.997413)
			(xy 220.79246 -408.001143) (xy 220.844671 -408.01226) (xy 220.894823 -408.030546) (xy 220.941937 -408.055645)
			(xy 220.985091 -408.087067) (xy 221.023445 -408.124197) (xy 221.040198 -408.14498) (xy 221.050095 -408.156785)
			(xy 221.075419 -408.174304) (xy 221.104812 -408.18348) (xy 221.135604 -408.18348) (xy 221.164997 -408.174304)
			(xy 221.190321 -408.156785) (xy 221.200218 -408.14498) (xy 221.216971 -408.124197) (xy 221.255325 -408.087067)
			(xy 221.298479 -408.055645) (xy 221.345593 -408.030546) (xy 221.395745 -408.01226) (xy 221.447956 -408.001143)
			(xy 221.501208 -407.997413) (xy 221.55446 -408.001143) (xy 221.606671 -408.01226) (xy 221.656823 -408.030546)
			(xy 221.703937 -408.055645) (xy 221.747091 -408.087067) (xy 221.785445 -408.124197) (xy 221.802198 -408.14498)
			(xy 221.812095 -408.156785) (xy 221.837419 -408.174304) (xy 221.866812 -408.18348) (xy 221.897604 -408.18348)
			(xy 221.926997 -408.174304) (xy 221.952321 -408.156785) (xy 221.962218 -408.14498) (xy 221.978971 -408.124197)
			(xy 222.017325 -408.087067) (xy 222.060479 -408.055645) (xy 222.107593 -408.030546) (xy 222.157745 -408.01226)
			(xy 222.209956 -408.001143) (xy 222.263208 -407.997413) (xy 222.31646 -408.001143) (xy 222.368671 -408.01226)
			(xy 222.418823 -408.030546) (xy 222.465937 -408.055645) (xy 222.509091 -408.087067) (xy 222.547445 -408.124197)
			(xy 222.564198 -408.14498) (xy 222.574095 -408.156785) (xy 222.599419 -408.174304) (xy 222.628812 -408.18348)
			(xy 222.659604 -408.18348) (xy 222.688997 -408.174304) (xy 222.714321 -408.156785) (xy 222.724218 -408.14498)
			(xy 222.740971 -408.124197) (xy 222.779325 -408.087067) (xy 222.822479 -408.055645) (xy 222.869593 -408.030546)
			(xy 222.919745 -408.01226) (xy 222.971956 -408.001143) (xy 223.025208 -407.997413) (xy 223.07846 -408.001143)
			(xy 223.130671 -408.01226) (xy 223.180823 -408.030546) (xy 223.227937 -408.055645) (xy 223.271091 -408.087067)
			(xy 223.309445 -408.124197) (xy 223.326198 -408.14498) (xy 223.336095 -408.156785) (xy 223.361419 -408.174304)
			(xy 223.390812 -408.18348) (xy 223.421604 -408.18348) (xy 223.450997 -408.174304) (xy 223.476321 -408.156785)
			(xy 223.486218 -408.14498) (xy 223.504394 -408.122484) (xy 223.546417 -408.08275) (xy 223.593956 -408.049813)
			(xy 223.64592 -408.024427) (xy 223.70112 -408.007174) (xy 223.758291 -407.998448) (xy 223.787208 -407.997914)
			(xy 223.81446 -407.998356) (xy 223.86841 -408.006114) (xy 223.920707 -408.021471) (xy 223.970286 -408.044114)
			(xy 224.016138 -408.073582) (xy 224.05733 -408.109276) (xy 224.093023 -408.150468) (xy 224.12249 -408.196321)
			(xy 224.145132 -408.2459) (xy 224.160487 -408.298197) (xy 224.168244 -408.352148) (xy 224.168244 -408.406652)
			(xy 224.160487 -408.460603) (xy 224.145132 -408.5129) (xy 224.12249 -408.562479) (xy 224.093023 -408.608332)
			(xy 224.05733 -408.649524) (xy 224.016138 -408.685218) (xy 223.970286 -408.714686) (xy 223.920707 -408.737329)
			(xy 223.86841 -408.752686) (xy 223.81446 -408.760444) (xy 223.787208 -408.76093) (xy 223.75829 -408.760432)
			(xy 223.701117 -408.751703) (xy 223.645916 -408.734443) (xy 223.593954 -408.709047) (xy 223.546421 -408.676099)
			(xy 223.504406 -408.636352) (xy 223.486218 -408.613864) (xy 223.476321 -408.602059) (xy 223.450997 -408.58454)
			(xy 223.421604 -408.575364) (xy 223.390812 -408.575364) (xy 223.361419 -408.58454) (xy 223.336095 -408.602059)
			(xy 223.326198 -408.613864) (xy 223.309445 -408.634647) (xy 223.271091 -408.671777) (xy 223.227937 -408.703199)
			(xy 223.180823 -408.728298) (xy 223.130671 -408.746584) (xy 223.07846 -408.757701) (xy 223.025208 -408.761431)
			(xy 222.971956 -408.757701) (xy 222.919745 -408.746584) (xy 222.869593 -408.728298) (xy 222.822479 -408.703199)
			(xy 222.779325 -408.671777) (xy 222.740971 -408.634647) (xy 222.724218 -408.613864) (xy 222.714321 -408.602059)
			(xy 222.688997 -408.58454) (xy 222.659604 -408.575364) (xy 222.628812 -408.575364) (xy 222.599419 -408.58454)
			(xy 222.574095 -408.602059) (xy 222.564198 -408.613864) (xy 222.547445 -408.634647) (xy 222.509091 -408.671777)
			(xy 222.465937 -408.703199) (xy 222.418823 -408.728298) (xy 222.368671 -408.746584) (xy 222.31646 -408.757701)
			(xy 222.263208 -408.761431) (xy 222.209956 -408.757701) (xy 222.157745 -408.746584) (xy 222.107593 -408.728298)
			(xy 222.060479 -408.703199) (xy 222.017325 -408.671777) (xy 221.978971 -408.634647) (xy 221.962218 -408.613864)
			(xy 221.952321 -408.602059) (xy 221.926997 -408.58454) (xy 221.897604 -408.575364) (xy 221.866812 -408.575364)
			(xy 221.837419 -408.58454) (xy 221.812095 -408.602059) (xy 221.802198 -408.613864) (xy 221.785445 -408.634647)
			(xy 221.747091 -408.671777) (xy 221.703937 -408.703199) (xy 221.656823 -408.728298) (xy 221.606671 -408.746584)
			(xy 221.55446 -408.757701) (xy 221.501208 -408.761431) (xy 221.447956 -408.757701) (xy 221.395745 -408.746584)
			(xy 221.345593 -408.728298) (xy 221.298479 -408.703199) (xy 221.255325 -408.671777) (xy 221.216971 -408.634647)
			(xy 221.200218 -408.613864) (xy 221.190321 -408.602059) (xy 221.164997 -408.58454) (xy 221.135604 -408.575364)
			(xy 221.104812 -408.575364) (xy 221.075419 -408.58454) (xy 221.050095 -408.602059) (xy 221.040198 -408.613864)
			(xy 221.023445 -408.634647) (xy 220.985091 -408.671777) (xy 220.941937 -408.703199) (xy 220.894823 -408.728298)
			(xy 220.844671 -408.746584) (xy 220.79246 -408.757701) (xy 220.739208 -408.761431) (xy 220.685956 -408.757701)
			(xy 220.633745 -408.746584) (xy 220.583593 -408.728298) (xy 220.536479 -408.703199) (xy 220.493325 -408.671777)
			(xy 220.454971 -408.634647) (xy 220.438218 -408.613864) (xy 220.428321 -408.602059) (xy 220.402997 -408.58454)
			(xy 220.373604 -408.575364) (xy 220.342812 -408.575364) (xy 220.313419 -408.58454) (xy 220.288095 -408.602059)
			(xy 220.278198 -408.613864) (xy 220.261445 -408.634647) (xy 220.223091 -408.671777) (xy 220.179937 -408.703199)
			(xy 220.132823 -408.728298) (xy 220.082671 -408.746584) (xy 220.03046 -408.757701) (xy 219.977208 -408.761431)
			(xy 219.923956 -408.757701) (xy 219.871745 -408.746584) (xy 219.821593 -408.728298) (xy 219.774479 -408.703199)
			(xy 219.731325 -408.671777) (xy 219.692971 -408.634647) (xy 219.676218 -408.613864) (xy 219.666321 -408.602059)
			(xy 219.640997 -408.58454) (xy 219.611604 -408.575364) (xy 219.580812 -408.575364) (xy 219.551419 -408.58454)
			(xy 219.526095 -408.602059) (xy 219.516198 -408.613864) (xy 219.497999 -408.636341) (xy 219.455982 -408.676078)
			(xy 219.408449 -408.709019) (xy 219.356489 -408.734409) (xy 219.301293 -408.751666) (xy 219.244124 -408.760395)
			(xy 219.215208 -408.76093) (xy 219.187956 -408.760423) (xy 219.134008 -408.752668) (xy 219.081712 -408.737313)
			(xy 219.032134 -408.714672) (xy 218.986282 -408.685206) (xy 218.945091 -408.649515) (xy 218.909398 -408.608324)
			(xy 218.879931 -408.562473) (xy 218.85729 -408.512896) (xy 218.841934 -408.4606) (xy 218.834177 -408.406652)
			(xy 217.894916 -408.406652) (xy 217.894916 -409.448052) (xy 218.072177 -409.448052) (xy 218.072177 -409.393548)
			(xy 218.079934 -409.3396) (xy 218.09529 -409.287304) (xy 218.117931 -409.237727) (xy 218.147398 -409.191876)
			(xy 218.183091 -409.150685) (xy 218.224282 -409.114994) (xy 218.270134 -409.085528) (xy 218.319712 -409.062887)
			(xy 218.372008 -409.047532) (xy 218.425956 -409.039777) (xy 218.453208 -409.039314) (xy 218.482123 -409.039893)
			(xy 218.539291 -409.048609) (xy 218.594489 -409.065855) (xy 218.646451 -409.091235) (xy 218.693987 -409.124168)
			(xy 218.736006 -409.163899) (xy 218.754198 -409.18638) (xy 218.764095 -409.198185) (xy 218.789419 -409.215704)
			(xy 218.818812 -409.22488) (xy 218.849604 -409.22488) (xy 218.878997 -409.215704) (xy 218.904321 -409.198185)
			(xy 218.914218 -409.18638) (xy 218.930971 -409.165597) (xy 218.969325 -409.128467) (xy 219.012479 -409.097045)
			(xy 219.059593 -409.071946) (xy 219.109745 -409.05366) (xy 219.161956 -409.042543) (xy 219.215208 -409.038813)
			(xy 219.26846 -409.042543) (xy 219.320671 -409.05366) (xy 219.370823 -409.071946) (xy 219.417937 -409.097045)
			(xy 219.461091 -409.128467) (xy 219.499445 -409.165597) (xy 219.516198 -409.18638) (xy 219.526095 -409.198185)
			(xy 219.551419 -409.215704) (xy 219.580812 -409.22488) (xy 219.611604 -409.22488) (xy 219.640997 -409.215704)
			(xy 219.666321 -409.198185) (xy 219.676218 -409.18638) (xy 219.692971 -409.165597) (xy 219.731325 -409.128467)
			(xy 219.774479 -409.097045) (xy 219.821593 -409.071946) (xy 219.871745 -409.05366) (xy 219.923956 -409.042543)
			(xy 219.977208 -409.038813) (xy 220.03046 -409.042543) (xy 220.082671 -409.05366) (xy 220.132823 -409.071946)
			(xy 220.179937 -409.097045) (xy 220.223091 -409.128467) (xy 220.261445 -409.165597) (xy 220.278198 -409.18638)
			(xy 220.288095 -409.198185) (xy 220.313419 -409.215704) (xy 220.342812 -409.22488) (xy 220.373604 -409.22488)
			(xy 220.402997 -409.215704) (xy 220.428321 -409.198185) (xy 220.438218 -409.18638) (xy 220.454971 -409.165597)
			(xy 220.493325 -409.128467) (xy 220.536479 -409.097045) (xy 220.583593 -409.071946) (xy 220.633745 -409.05366)
			(xy 220.685956 -409.042543) (xy 220.739208 -409.038813) (xy 220.79246 -409.042543) (xy 220.844671 -409.05366)
			(xy 220.894823 -409.071946) (xy 220.941937 -409.097045) (xy 220.985091 -409.128467) (xy 221.023445 -409.165597)
			(xy 221.040198 -409.18638) (xy 221.050095 -409.198185) (xy 221.075419 -409.215704) (xy 221.104812 -409.22488)
			(xy 221.135604 -409.22488) (xy 221.164997 -409.215704) (xy 221.190321 -409.198185) (xy 221.200218 -409.18638)
			(xy 221.216971 -409.165597) (xy 221.255325 -409.128467) (xy 221.298479 -409.097045) (xy 221.345593 -409.071946)
			(xy 221.395745 -409.05366) (xy 221.447956 -409.042543) (xy 221.501208 -409.038813) (xy 221.55446 -409.042543)
			(xy 221.606671 -409.05366) (xy 221.656823 -409.071946) (xy 221.703937 -409.097045) (xy 221.747091 -409.128467)
			(xy 221.785445 -409.165597) (xy 221.802198 -409.18638) (xy 221.812095 -409.198185) (xy 221.837419 -409.215704)
			(xy 221.866812 -409.22488) (xy 221.897604 -409.22488) (xy 221.926997 -409.215704) (xy 221.952321 -409.198185)
			(xy 221.962218 -409.18638) (xy 221.978971 -409.165597) (xy 222.017325 -409.128467) (xy 222.060479 -409.097045)
			(xy 222.107593 -409.071946) (xy 222.157745 -409.05366) (xy 222.209956 -409.042543) (xy 222.263208 -409.038813)
			(xy 222.31646 -409.042543) (xy 222.368671 -409.05366) (xy 222.418823 -409.071946) (xy 222.465937 -409.097045)
			(xy 222.509091 -409.128467) (xy 222.547445 -409.165597) (xy 222.564198 -409.18638) (xy 222.574095 -409.198185)
			(xy 222.599419 -409.215704) (xy 222.628812 -409.22488) (xy 222.659604 -409.22488) (xy 222.688997 -409.215704)
			(xy 222.714321 -409.198185) (xy 222.724218 -409.18638) (xy 222.740971 -409.165597) (xy 222.779325 -409.128467)
			(xy 222.822479 -409.097045) (xy 222.869593 -409.071946) (xy 222.919745 -409.05366) (xy 222.971956 -409.042543)
			(xy 223.025208 -409.038813) (xy 223.07846 -409.042543) (xy 223.130671 -409.05366) (xy 223.180823 -409.071946)
			(xy 223.227937 -409.097045) (xy 223.271091 -409.128467) (xy 223.309445 -409.165597) (xy 223.326198 -409.18638)
			(xy 223.336095 -409.198185) (xy 223.361419 -409.215704) (xy 223.390812 -409.22488) (xy 223.421604 -409.22488)
			(xy 223.450997 -409.215704) (xy 223.476321 -409.198185) (xy 223.486218 -409.18638) (xy 223.504394 -409.163884)
			(xy 223.546417 -409.12415) (xy 223.593956 -409.091213) (xy 223.64592 -409.065827) (xy 223.70112 -409.048574)
			(xy 223.758291 -409.039848) (xy 223.787208 -409.039314) (xy 223.81446 -409.039756) (xy 223.86841 -409.047514)
			(xy 223.920707 -409.062871) (xy 223.970286 -409.085514) (xy 224.016138 -409.114982) (xy 224.05733 -409.150676)
			(xy 224.093023 -409.191868) (xy 224.12249 -409.237721) (xy 224.145132 -409.2873) (xy 224.160487 -409.339597)
			(xy 224.168244 -409.393548) (xy 224.168244 -409.448052) (xy 224.160487 -409.502003) (xy 224.145132 -409.5543)
			(xy 224.12249 -409.603879) (xy 224.093023 -409.649732) (xy 224.05733 -409.690924) (xy 224.016138 -409.726618)
			(xy 223.970286 -409.756086) (xy 223.920707 -409.778729) (xy 223.86841 -409.794086) (xy 223.81446 -409.801844)
			(xy 223.787208 -409.80233) (xy 223.75829 -409.801832) (xy 223.701117 -409.793103) (xy 223.645916 -409.775843)
			(xy 223.593954 -409.750447) (xy 223.546421 -409.717499) (xy 223.504406 -409.677752) (xy 223.486218 -409.655264)
			(xy 223.476321 -409.643459) (xy 223.450997 -409.62594) (xy 223.421604 -409.616764) (xy 223.390812 -409.616764)
			(xy 223.361419 -409.62594) (xy 223.336095 -409.643459) (xy 223.326198 -409.655264) (xy 223.309445 -409.676047)
			(xy 223.271091 -409.713177) (xy 223.227937 -409.744599) (xy 223.180823 -409.769698) (xy 223.130671 -409.787984)
			(xy 223.07846 -409.799101) (xy 223.025208 -409.802831) (xy 222.971956 -409.799101) (xy 222.919745 -409.787984)
			(xy 222.869593 -409.769698) (xy 222.822479 -409.744599) (xy 222.779325 -409.713177) (xy 222.740971 -409.676047)
			(xy 222.724218 -409.655264) (xy 222.714321 -409.643459) (xy 222.688997 -409.62594) (xy 222.659604 -409.616764)
			(xy 222.628812 -409.616764) (xy 222.599419 -409.62594) (xy 222.574095 -409.643459) (xy 222.564198 -409.655264)
			(xy 222.547445 -409.676047) (xy 222.509091 -409.713177) (xy 222.465937 -409.744599) (xy 222.418823 -409.769698)
			(xy 222.368671 -409.787984) (xy 222.31646 -409.799101) (xy 222.263208 -409.802831) (xy 222.209956 -409.799101)
			(xy 222.157745 -409.787984) (xy 222.107593 -409.769698) (xy 222.060479 -409.744599) (xy 222.017325 -409.713177)
			(xy 221.978971 -409.676047) (xy 221.962218 -409.655264) (xy 221.952321 -409.643459) (xy 221.926997 -409.62594)
			(xy 221.897604 -409.616764) (xy 221.866812 -409.616764) (xy 221.837419 -409.62594) (xy 221.812095 -409.643459)
			(xy 221.802198 -409.655264) (xy 221.785445 -409.676047) (xy 221.747091 -409.713177) (xy 221.703937 -409.744599)
			(xy 221.656823 -409.769698) (xy 221.606671 -409.787984) (xy 221.55446 -409.799101) (xy 221.501208 -409.802831)
			(xy 221.447956 -409.799101) (xy 221.395745 -409.787984) (xy 221.345593 -409.769698) (xy 221.298479 -409.744599)
			(xy 221.255325 -409.713177) (xy 221.216971 -409.676047) (xy 221.200218 -409.655264) (xy 221.190321 -409.643459)
			(xy 221.164997 -409.62594) (xy 221.135604 -409.616764) (xy 221.104812 -409.616764) (xy 221.075419 -409.62594)
			(xy 221.050095 -409.643459) (xy 221.040198 -409.655264) (xy 221.023445 -409.676047) (xy 220.985091 -409.713177)
			(xy 220.941937 -409.744599) (xy 220.894823 -409.769698) (xy 220.844671 -409.787984) (xy 220.79246 -409.799101)
			(xy 220.739208 -409.802831) (xy 220.685956 -409.799101) (xy 220.633745 -409.787984) (xy 220.583593 -409.769698)
			(xy 220.536479 -409.744599) (xy 220.493325 -409.713177) (xy 220.454971 -409.676047) (xy 220.438218 -409.655264)
			(xy 220.428321 -409.643459) (xy 220.402997 -409.62594) (xy 220.373604 -409.616764) (xy 220.342812 -409.616764)
			(xy 220.313419 -409.62594) (xy 220.288095 -409.643459) (xy 220.278198 -409.655264) (xy 220.261445 -409.676047)
			(xy 220.223091 -409.713177) (xy 220.179937 -409.744599) (xy 220.132823 -409.769698) (xy 220.082671 -409.787984)
			(xy 220.03046 -409.799101) (xy 219.977208 -409.802831) (xy 219.923956 -409.799101) (xy 219.871745 -409.787984)
			(xy 219.821593 -409.769698) (xy 219.774479 -409.744599) (xy 219.731325 -409.713177) (xy 219.692971 -409.676047)
			(xy 219.676218 -409.655264) (xy 219.666321 -409.643459) (xy 219.640997 -409.62594) (xy 219.611604 -409.616764)
			(xy 219.580812 -409.616764) (xy 219.551419 -409.62594) (xy 219.526095 -409.643459) (xy 219.516198 -409.655264)
			(xy 219.499445 -409.676047) (xy 219.461091 -409.713177) (xy 219.417937 -409.744599) (xy 219.370823 -409.769698)
			(xy 219.320671 -409.787984) (xy 219.26846 -409.799101) (xy 219.215208 -409.802831) (xy 219.161956 -409.799101)
			(xy 219.109745 -409.787984) (xy 219.059593 -409.769698) (xy 219.012479 -409.744599) (xy 218.969325 -409.713177)
			(xy 218.930971 -409.676047) (xy 218.914218 -409.655264) (xy 218.904321 -409.643459) (xy 218.878997 -409.62594)
			(xy 218.849604 -409.616764) (xy 218.818812 -409.616764) (xy 218.789419 -409.62594) (xy 218.764095 -409.643459)
			(xy 218.754198 -409.655264) (xy 218.735999 -409.677741) (xy 218.693982 -409.717478) (xy 218.646449 -409.750419)
			(xy 218.594489 -409.775809) (xy 218.539293 -409.793066) (xy 218.482124 -409.801795) (xy 218.453208 -409.80233)
			(xy 218.425956 -409.801823) (xy 218.372008 -409.794068) (xy 218.319712 -409.778713) (xy 218.270134 -409.756072)
			(xy 218.224282 -409.726606) (xy 218.183091 -409.690915) (xy 218.147398 -409.649724) (xy 218.117931 -409.603873)
			(xy 218.09529 -409.554296) (xy 218.079934 -409.502) (xy 218.072177 -409.448052) (xy 217.894916 -409.448052)
			(xy 217.894916 -411.199076) (xy 218.412314 -411.716728) (xy 224.417382 -411.716728) (xy 224.7138 -411.420056)
			(xy 224.7138 -408.458162) (xy 224.714295 -408.432179) (xy 224.722451 -408.380858) (xy 224.738541 -408.331446)
			(xy 224.762167 -408.285162) (xy 224.792747 -408.243147) (xy 224.810828 -408.224482) (xy 226.413568 -406.621742)
			(xy 226.432271 -406.603716) (xy 226.474291 -406.573181) (xy 226.520572 -406.549598) (xy 226.569973 -406.533548)
			(xy 226.621277 -406.525426) (xy 226.647248 -406.524968) (xy 227.559108 -406.524968) (xy 227.580906 -406.512827)
			(xy 227.626999 -406.493724) (xy 227.675192 -406.480804) (xy 227.72466 -406.474288) (xy 227.749608 -406.473914)
			(xy 227.77686 -406.474378) (xy 227.830809 -406.482136) (xy 227.883104 -406.497493) (xy 227.932682 -406.520136)
			(xy 227.978533 -406.549605) (xy 228.009008 -406.576014) (xy 230.263215 -406.576014) (xy 230.266942 -406.522764)
			(xy 230.278057 -406.470554) (xy 230.296341 -406.420404) (xy 230.321438 -406.373292) (xy 230.352857 -406.330138)
			(xy 230.389985 -406.291785) (xy 230.410766 -406.275032) (xy 230.422551 -406.265112) (xy 230.440073 -406.239795)
			(xy 230.449253 -406.210408) (xy 230.449257 -406.179619) (xy 230.440085 -406.150229) (xy 230.42257 -406.124908)
			(xy 230.410766 -406.115012) (xy 230.388281 -406.096823) (xy 230.348548 -406.054802) (xy 230.31561 -406.007266)
			(xy 230.290222 -405.955305) (xy 230.272966 -405.900107) (xy 230.264236 -405.842938) (xy 230.2637 -405.814022)
			(xy 230.264176 -405.786769) (xy 230.27193 -405.732818) (xy 230.287284 -405.68052) (xy 230.309924 -405.63094)
			(xy 230.339391 -405.585086) (xy 230.375083 -405.543893) (xy 230.416275 -405.508199) (xy 230.462127 -405.478731)
			(xy 230.511707 -405.456089) (xy 230.564005 -405.440733) (xy 230.617955 -405.432977) (xy 230.645208 -405.432514)
			(xy 230.674123 -405.433093) (xy 230.731291 -405.441809) (xy 230.786489 -405.459055) (xy 230.838451 -405.484435)
			(xy 230.885987 -405.517368) (xy 230.928006 -405.557099) (xy 230.946198 -405.57958) (xy 230.956095 -405.591385)
			(xy 230.981419 -405.608904) (xy 231.010812 -405.61808) (xy 231.041604 -405.61808) (xy 231.070997 -405.608904)
			(xy 231.096321 -405.591385) (xy 231.106218 -405.57958) (xy 231.122971 -405.558797) (xy 231.161325 -405.521667)
			(xy 231.204479 -405.490245) (xy 231.251593 -405.465146) (xy 231.301745 -405.44686) (xy 231.353956 -405.435743)
			(xy 231.407208 -405.432013) (xy 231.46046 -405.435743) (xy 231.512671 -405.44686) (xy 231.562823 -405.465146)
			(xy 231.609937 -405.490245) (xy 231.653091 -405.521667) (xy 231.691445 -405.558797) (xy 231.708198 -405.57958)
			(xy 231.718095 -405.591385) (xy 231.743419 -405.608904) (xy 231.772812 -405.61808) (xy 231.803604 -405.61808)
			(xy 231.832997 -405.608904) (xy 231.858321 -405.591385) (xy 231.868218 -405.57958) (xy 231.884971 -405.558797)
			(xy 231.923325 -405.521667) (xy 231.966479 -405.490245) (xy 232.013593 -405.465146) (xy 232.063745 -405.44686)
			(xy 232.115956 -405.435743) (xy 232.169208 -405.432013) (xy 232.22246 -405.435743) (xy 232.274671 -405.44686)
			(xy 232.324823 -405.465146) (xy 232.371937 -405.490245) (xy 232.415091 -405.521667) (xy 232.453445 -405.558797)
			(xy 232.470198 -405.57958) (xy 232.480095 -405.591385) (xy 232.505419 -405.608904) (xy 232.534812 -405.61808)
			(xy 232.565604 -405.61808) (xy 232.594997 -405.608904) (xy 232.620321 -405.591385) (xy 232.630218 -405.57958)
			(xy 232.646971 -405.558797) (xy 232.685325 -405.521667) (xy 232.728479 -405.490245) (xy 232.775593 -405.465146)
			(xy 232.825745 -405.44686) (xy 232.877956 -405.435743) (xy 232.931208 -405.432013) (xy 232.98446 -405.435743)
			(xy 233.036671 -405.44686) (xy 233.086823 -405.465146) (xy 233.133937 -405.490245) (xy 233.177091 -405.521667)
			(xy 233.215445 -405.558797) (xy 233.232198 -405.57958) (xy 233.242095 -405.591385) (xy 233.267419 -405.608904)
			(xy 233.296812 -405.61808) (xy 233.327604 -405.61808) (xy 233.356997 -405.608904) (xy 233.382321 -405.591385)
			(xy 233.392218 -405.57958) (xy 233.410394 -405.557084) (xy 233.452417 -405.51735) (xy 233.499956 -405.484413)
			(xy 233.55192 -405.459027) (xy 233.60712 -405.441774) (xy 233.664291 -405.433048) (xy 233.693208 -405.432514)
			(xy 233.720462 -405.432948) (xy 233.774415 -405.440707) (xy 233.826715 -405.456065) (xy 233.876297 -405.47871)
			(xy 233.922151 -405.508181) (xy 233.963344 -405.543877) (xy 233.999037 -405.585073) (xy 234.028505 -405.63093)
			(xy 234.051146 -405.680513) (xy 234.0665 -405.732814) (xy 234.074254 -405.786768) (xy 234.074716 -405.814022)
			(xy 234.074173 -405.842938) (xy 234.065454 -405.90011) (xy 234.048203 -405.95531) (xy 234.022816 -406.007272)
			(xy 233.989875 -406.054806) (xy 233.950135 -406.096822) (xy 233.92765 -406.115012) (xy 233.915819 -406.124883)
			(xy 233.898296 -406.150212) (xy 233.889119 -406.179613) (xy 233.889123 -406.210413) (xy 233.898308 -406.239812)
			(xy 233.915838 -406.265136) (xy 233.92765 -406.275032) (xy 233.948454 -406.29176) (xy 233.985584 -406.330116)
			(xy 234.017005 -406.373274) (xy 234.042103 -406.420391) (xy 234.060387 -406.470546) (xy 234.071502 -406.52276)
			(xy 234.07523 -406.576014) (xy 234.071499 -406.629267) (xy 234.06038 -406.68148) (xy 234.042092 -406.731634)
			(xy 234.01699 -406.778749) (xy 233.985567 -406.821904) (xy 233.948434 -406.860258) (xy 233.92765 -406.877012)
			(xy 233.915819 -406.886883) (xy 233.898296 -406.912212) (xy 233.889119 -406.941613) (xy 233.889123 -406.972413)
			(xy 233.898308 -407.001812) (xy 233.915838 -407.027136) (xy 233.92765 -407.037032) (xy 233.950159 -407.055192)
			(xy 233.989891 -407.09722) (xy 234.022825 -407.144762) (xy 234.048209 -407.196729) (xy 234.06546 -407.251931)
			(xy 234.074184 -407.309104) (xy 234.074716 -407.338022) (xy 234.074243 -407.365273) (xy 234.066483 -407.419221)
			(xy 234.051126 -407.471516) (xy 234.028483 -407.521092) (xy 233.999015 -407.566942) (xy 233.963322 -407.608132)
			(xy 233.922131 -407.643823) (xy 233.87628 -407.673289) (xy 233.826703 -407.695931) (xy 233.774407 -407.711286)
			(xy 233.720459 -407.719044) (xy 233.693208 -407.71953) (xy 233.66429 -407.719032) (xy 233.607117 -407.710303)
			(xy 233.551916 -407.693043) (xy 233.499954 -407.667647) (xy 233.452421 -407.634699) (xy 233.410406 -407.594952)
			(xy 233.392218 -407.572464) (xy 233.382321 -407.560659) (xy 233.356997 -407.54314) (xy 233.327604 -407.533964)
			(xy 233.296812 -407.533964) (xy 233.267419 -407.54314) (xy 233.242095 -407.560659) (xy 233.232198 -407.572464)
			(xy 233.215445 -407.593247) (xy 233.177091 -407.630377) (xy 233.133937 -407.661799) (xy 233.086823 -407.686898)
			(xy 233.036671 -407.705184) (xy 232.98446 -407.716301) (xy 232.931208 -407.720031) (xy 232.877956 -407.716301)
			(xy 232.825745 -407.705184) (xy 232.775593 -407.686898) (xy 232.728479 -407.661799) (xy 232.685325 -407.630377)
			(xy 232.646971 -407.593247) (xy 232.630218 -407.572464) (xy 232.620321 -407.560659) (xy 232.594997 -407.54314)
			(xy 232.565604 -407.533964) (xy 232.534812 -407.533964) (xy 232.505419 -407.54314) (xy 232.480095 -407.560659)
			(xy 232.470198 -407.572464) (xy 232.453445 -407.593247) (xy 232.415091 -407.630377) (xy 232.371937 -407.661799)
			(xy 232.324823 -407.686898) (xy 232.274671 -407.705184) (xy 232.22246 -407.716301) (xy 232.169208 -407.720031)
			(xy 232.115956 -407.716301) (xy 232.063745 -407.705184) (xy 232.013593 -407.686898) (xy 231.966479 -407.661799)
			(xy 231.923325 -407.630377) (xy 231.884971 -407.593247) (xy 231.868218 -407.572464) (xy 231.858321 -407.560659)
			(xy 231.832997 -407.54314) (xy 231.803604 -407.533964) (xy 231.772812 -407.533964) (xy 231.743419 -407.54314)
			(xy 231.718095 -407.560659) (xy 231.708198 -407.572464) (xy 231.691445 -407.593247) (xy 231.653091 -407.630377)
			(xy 231.609937 -407.661799) (xy 231.562823 -407.686898) (xy 231.512671 -407.705184) (xy 231.46046 -407.716301)
			(xy 231.407208 -407.720031) (xy 231.353956 -407.716301) (xy 231.301745 -407.705184) (xy 231.251593 -407.686898)
			(xy 231.204479 -407.661799) (xy 231.161325 -407.630377) (xy 231.122971 -407.593247) (xy 231.106218 -407.572464)
			(xy 231.096321 -407.560659) (xy 231.070997 -407.54314) (xy 231.041604 -407.533964) (xy 231.010812 -407.533964)
			(xy 230.981419 -407.54314) (xy 230.956095 -407.560659) (xy 230.946198 -407.572464) (xy 230.927999 -407.594941)
			(xy 230.885982 -407.634678) (xy 230.838449 -407.667619) (xy 230.786489 -407.693009) (xy 230.731293 -407.710266)
			(xy 230.674124 -407.718995) (xy 230.645208 -407.71953) (xy 230.617958 -407.719015) (xy 230.564012 -407.71126)
			(xy 230.51172 -407.695907) (xy 230.462144 -407.673268) (xy 230.416294 -407.643805) (xy 230.375105 -407.608117)
			(xy 230.339413 -407.56693) (xy 230.309946 -407.521083) (xy 230.287304 -407.471509) (xy 230.271946 -407.419217)
			(xy 230.264187 -407.365272) (xy 230.2637 -407.338022) (xy 230.264234 -407.309106) (xy 230.27296 -407.251935)
			(xy 230.290215 -407.196737) (xy 230.315603 -407.144775) (xy 230.348544 -407.097241) (xy 230.388282 -407.055223)
			(xy 230.410766 -407.037032) (xy 230.422551 -407.027112) (xy 230.440073 -407.001795) (xy 230.449253 -406.972408)
			(xy 230.449257 -406.941619) (xy 230.440085 -406.912229) (xy 230.42257 -406.886908) (xy 230.410766 -406.877012)
			(xy 230.390005 -406.860233) (xy 230.352874 -406.821883) (xy 230.321452 -406.778731) (xy 230.296352 -406.731621)
			(xy 230.278064 -406.681472) (xy 230.266946 -406.629263) (xy 230.263215 -406.576014) (xy 228.009008 -406.576014)
			(xy 228.019723 -406.585299) (xy 228.055413 -406.626491) (xy 228.084878 -406.672344) (xy 228.107518 -406.721924)
			(xy 228.12287 -406.774221) (xy 228.130624 -406.82817) (xy 228.131116 -406.855422) (xy 228.130643 -406.882469)
			(xy 228.122999 -406.93602) (xy 228.107868 -406.987954) (xy 228.085553 -407.037231) (xy 228.056501 -407.082861)
			(xy 228.021295 -407.12393) (xy 227.980641 -407.159615) (xy 227.935354 -407.189199) (xy 227.886343 -407.21209)
			(xy 227.860606 -407.22042) (xy 227.848414 -407.22423) (xy 227.546916 -407.525728) (xy 227.546916 -408.406652)
			(xy 229.502177 -408.406652) (xy 229.502177 -408.352148) (xy 229.509934 -408.2982) (xy 229.52529 -408.245904)
			(xy 229.547931 -408.196327) (xy 229.577398 -408.150476) (xy 229.613091 -408.109285) (xy 229.654282 -408.073594)
			(xy 229.700134 -408.044128) (xy 229.749712 -408.021487) (xy 229.802008 -408.006132) (xy 229.855956 -407.998377)
			(xy 229.883208 -407.997914) (xy 229.912123 -407.998493) (xy 229.969291 -408.007209) (xy 230.024489 -408.024455)
			(xy 230.076451 -408.049835) (xy 230.123987 -408.082768) (xy 230.166006 -408.122499) (xy 230.184198 -408.14498)
			(xy 230.194095 -408.156785) (xy 230.219419 -408.174304) (xy 230.248812 -408.18348) (xy 230.279604 -408.18348)
			(xy 230.308997 -408.174304) (xy 230.334321 -408.156785) (xy 230.344218 -408.14498) (xy 230.360971 -408.124197)
			(xy 230.399325 -408.087067) (xy 230.442479 -408.055645) (xy 230.489593 -408.030546) (xy 230.539745 -408.01226)
			(xy 230.591956 -408.001143) (xy 230.645208 -407.997413) (xy 230.69846 -408.001143) (xy 230.750671 -408.01226)
			(xy 230.800823 -408.030546) (xy 230.847937 -408.055645) (xy 230.891091 -408.087067) (xy 230.929445 -408.124197)
			(xy 230.946198 -408.14498) (xy 230.956095 -408.156785) (xy 230.981419 -408.174304) (xy 231.010812 -408.18348)
			(xy 231.041604 -408.18348) (xy 231.070997 -408.174304) (xy 231.096321 -408.156785) (xy 231.106218 -408.14498)
			(xy 231.122971 -408.124197) (xy 231.161325 -408.087067) (xy 231.204479 -408.055645) (xy 231.251593 -408.030546)
			(xy 231.301745 -408.01226) (xy 231.353956 -408.001143) (xy 231.407208 -407.997413) (xy 231.46046 -408.001143)
			(xy 231.512671 -408.01226) (xy 231.562823 -408.030546) (xy 231.609937 -408.055645) (xy 231.653091 -408.087067)
			(xy 231.691445 -408.124197) (xy 231.708198 -408.14498) (xy 231.718095 -408.156785) (xy 231.743419 -408.174304)
			(xy 231.772812 -408.18348) (xy 231.803604 -408.18348) (xy 231.832997 -408.174304) (xy 231.858321 -408.156785)
			(xy 231.868218 -408.14498) (xy 231.884971 -408.124197) (xy 231.923325 -408.087067) (xy 231.966479 -408.055645)
			(xy 232.013593 -408.030546) (xy 232.063745 -408.01226) (xy 232.115956 -408.001143) (xy 232.169208 -407.997413)
			(xy 232.22246 -408.001143) (xy 232.274671 -408.01226) (xy 232.324823 -408.030546) (xy 232.371937 -408.055645)
			(xy 232.415091 -408.087067) (xy 232.453445 -408.124197) (xy 232.470198 -408.14498) (xy 232.480095 -408.156785)
			(xy 232.505419 -408.174304) (xy 232.534812 -408.18348) (xy 232.565604 -408.18348) (xy 232.594997 -408.174304)
			(xy 232.620321 -408.156785) (xy 232.630218 -408.14498) (xy 232.646971 -408.124197) (xy 232.685325 -408.087067)
			(xy 232.728479 -408.055645) (xy 232.775593 -408.030546) (xy 232.825745 -408.01226) (xy 232.877956 -408.001143)
			(xy 232.931208 -407.997413) (xy 232.98446 -408.001143) (xy 233.036671 -408.01226) (xy 233.086823 -408.030546)
			(xy 233.133937 -408.055645) (xy 233.177091 -408.087067) (xy 233.215445 -408.124197) (xy 233.232198 -408.14498)
			(xy 233.242095 -408.156785) (xy 233.267419 -408.174304) (xy 233.296812 -408.18348) (xy 233.327604 -408.18348)
			(xy 233.356997 -408.174304) (xy 233.382321 -408.156785) (xy 233.392218 -408.14498) (xy 233.408971 -408.124197)
			(xy 233.447325 -408.087067) (xy 233.490479 -408.055645) (xy 233.537593 -408.030546) (xy 233.587745 -408.01226)
			(xy 233.639956 -408.001143) (xy 233.693208 -407.997413) (xy 233.74646 -408.001143) (xy 233.798671 -408.01226)
			(xy 233.848823 -408.030546) (xy 233.895937 -408.055645) (xy 233.939091 -408.087067) (xy 233.977445 -408.124197)
			(xy 233.994198 -408.14498) (xy 234.004095 -408.156785) (xy 234.029419 -408.174304) (xy 234.058812 -408.18348)
			(xy 234.089604 -408.18348) (xy 234.118997 -408.174304) (xy 234.144321 -408.156785) (xy 234.154218 -408.14498)
			(xy 234.172394 -408.122484) (xy 234.214417 -408.08275) (xy 234.261956 -408.049813) (xy 234.31392 -408.024427)
			(xy 234.36912 -408.007174) (xy 234.426291 -407.998448) (xy 234.455208 -407.997914) (xy 234.48246 -407.998356)
			(xy 234.53641 -408.006114) (xy 234.588707 -408.021471) (xy 234.638286 -408.044114) (xy 234.684138 -408.073582)
			(xy 234.72533 -408.109276) (xy 234.761023 -408.150468) (xy 234.79049 -408.196321) (xy 234.813132 -408.2459)
			(xy 234.828487 -408.298197) (xy 234.836244 -408.352148) (xy 234.836244 -408.406652) (xy 234.828487 -408.460603)
			(xy 234.813132 -408.5129) (xy 234.79049 -408.562479) (xy 234.761023 -408.608332) (xy 234.72533 -408.649524)
			(xy 234.684138 -408.685218) (xy 234.638286 -408.714686) (xy 234.588707 -408.737329) (xy 234.53641 -408.752686)
			(xy 234.48246 -408.760444) (xy 234.455208 -408.76093) (xy 234.42629 -408.760432) (xy 234.369117 -408.751703)
			(xy 234.313916 -408.734443) (xy 234.261954 -408.709047) (xy 234.214421 -408.676099) (xy 234.172406 -408.636352)
			(xy 234.154218 -408.613864) (xy 234.144321 -408.602059) (xy 234.118997 -408.58454) (xy 234.089604 -408.575364)
			(xy 234.058812 -408.575364) (xy 234.029419 -408.58454) (xy 234.004095 -408.602059) (xy 233.994198 -408.613864)
			(xy 233.977445 -408.634647) (xy 233.939091 -408.671777) (xy 233.895937 -408.703199) (xy 233.848823 -408.728298)
			(xy 233.798671 -408.746584) (xy 233.74646 -408.757701) (xy 233.693208 -408.761431) (xy 233.639956 -408.757701)
			(xy 233.587745 -408.746584) (xy 233.537593 -408.728298) (xy 233.490479 -408.703199) (xy 233.447325 -408.671777)
			(xy 233.408971 -408.634647) (xy 233.392218 -408.613864) (xy 233.382321 -408.602059) (xy 233.356997 -408.58454)
			(xy 233.327604 -408.575364) (xy 233.296812 -408.575364) (xy 233.267419 -408.58454) (xy 233.242095 -408.602059)
			(xy 233.232198 -408.613864) (xy 233.215445 -408.634647) (xy 233.177091 -408.671777) (xy 233.133937 -408.703199)
			(xy 233.086823 -408.728298) (xy 233.036671 -408.746584) (xy 232.98446 -408.757701) (xy 232.931208 -408.761431)
			(xy 232.877956 -408.757701) (xy 232.825745 -408.746584) (xy 232.775593 -408.728298) (xy 232.728479 -408.703199)
			(xy 232.685325 -408.671777) (xy 232.646971 -408.634647) (xy 232.630218 -408.613864) (xy 232.620321 -408.602059)
			(xy 232.594997 -408.58454) (xy 232.565604 -408.575364) (xy 232.534812 -408.575364) (xy 232.505419 -408.58454)
			(xy 232.480095 -408.602059) (xy 232.470198 -408.613864) (xy 232.453445 -408.634647) (xy 232.415091 -408.671777)
			(xy 232.371937 -408.703199) (xy 232.324823 -408.728298) (xy 232.274671 -408.746584) (xy 232.22246 -408.757701)
			(xy 232.169208 -408.761431) (xy 232.115956 -408.757701) (xy 232.063745 -408.746584) (xy 232.013593 -408.728298)
			(xy 231.966479 -408.703199) (xy 231.923325 -408.671777) (xy 231.884971 -408.634647) (xy 231.868218 -408.613864)
			(xy 231.858321 -408.602059) (xy 231.832997 -408.58454) (xy 231.803604 -408.575364) (xy 231.772812 -408.575364)
			(xy 231.743419 -408.58454) (xy 231.718095 -408.602059) (xy 231.708198 -408.613864) (xy 231.691445 -408.634647)
			(xy 231.653091 -408.671777) (xy 231.609937 -408.703199) (xy 231.562823 -408.728298) (xy 231.512671 -408.746584)
			(xy 231.46046 -408.757701) (xy 231.407208 -408.761431) (xy 231.353956 -408.757701) (xy 231.301745 -408.746584)
			(xy 231.251593 -408.728298) (xy 231.204479 -408.703199) (xy 231.161325 -408.671777) (xy 231.122971 -408.634647)
			(xy 231.106218 -408.613864) (xy 231.096321 -408.602059) (xy 231.070997 -408.58454) (xy 231.041604 -408.575364)
			(xy 231.010812 -408.575364) (xy 230.981419 -408.58454) (xy 230.956095 -408.602059) (xy 230.946198 -408.613864)
			(xy 230.929445 -408.634647) (xy 230.891091 -408.671777) (xy 230.847937 -408.703199) (xy 230.800823 -408.728298)
			(xy 230.750671 -408.746584) (xy 230.69846 -408.757701) (xy 230.645208 -408.761431) (xy 230.591956 -408.757701)
			(xy 230.539745 -408.746584) (xy 230.489593 -408.728298) (xy 230.442479 -408.703199) (xy 230.399325 -408.671777)
			(xy 230.360971 -408.634647) (xy 230.344218 -408.613864) (xy 230.334321 -408.602059) (xy 230.308997 -408.58454)
			(xy 230.279604 -408.575364) (xy 230.248812 -408.575364) (xy 230.219419 -408.58454) (xy 230.194095 -408.602059)
			(xy 230.184198 -408.613864) (xy 230.165999 -408.636341) (xy 230.123982 -408.676078) (xy 230.076449 -408.709019)
			(xy 230.024489 -408.734409) (xy 229.969293 -408.751666) (xy 229.912124 -408.760395) (xy 229.883208 -408.76093)
			(xy 229.855956 -408.760423) (xy 229.802008 -408.752668) (xy 229.749712 -408.737313) (xy 229.700134 -408.714672)
			(xy 229.654282 -408.685206) (xy 229.613091 -408.649515) (xy 229.577398 -408.608324) (xy 229.547931 -408.562473)
			(xy 229.52529 -408.512896) (xy 229.509934 -408.4606) (xy 229.502177 -408.406652) (xy 227.546916 -408.406652)
			(xy 227.546916 -409.583128) (xy 228.70668 -410.742892) (xy 233.418888 -410.742892) (xy 234.263946 -409.897834)
			(xy 234.27425 -409.886779) (xy 234.288454 -409.860122) (xy 234.294231 -409.830475) (xy 234.291074 -409.800435)
			(xy 234.279261 -409.772636) (xy 234.259826 -409.749514) (xy 234.247436 -409.740862) (xy 234.2211 -409.723013)
			(xy 234.174239 -409.679989) (xy 234.154218 -409.655264) (xy 234.144321 -409.643459) (xy 234.118997 -409.62594)
			(xy 234.089604 -409.616764) (xy 234.058812 -409.616764) (xy 234.029419 -409.62594) (xy 234.004095 -409.643459)
			(xy 233.994198 -409.655264) (xy 233.977445 -409.676047) (xy 233.939091 -409.713177) (xy 233.895937 -409.744599)
			(xy 233.848823 -409.769698) (xy 233.798671 -409.787984) (xy 233.74646 -409.799101) (xy 233.693208 -409.802831)
			(xy 233.639956 -409.799101) (xy 233.587745 -409.787984) (xy 233.537593 -409.769698) (xy 233.490479 -409.744599)
			(xy 233.447325 -409.713177) (xy 233.408971 -409.676047) (xy 233.392218 -409.655264) (xy 233.382321 -409.643459)
			(xy 233.356997 -409.62594) (xy 233.327604 -409.616764) (xy 233.296812 -409.616764) (xy 233.267419 -409.62594)
			(xy 233.242095 -409.643459) (xy 233.232198 -409.655264) (xy 233.215445 -409.676047) (xy 233.177091 -409.713177)
			(xy 233.133937 -409.744599) (xy 233.086823 -409.769698) (xy 233.036671 -409.787984) (xy 232.98446 -409.799101)
			(xy 232.931208 -409.802831) (xy 232.877956 -409.799101) (xy 232.825745 -409.787984) (xy 232.775593 -409.769698)
			(xy 232.728479 -409.744599) (xy 232.685325 -409.713177) (xy 232.646971 -409.676047) (xy 232.630218 -409.655264)
			(xy 232.620321 -409.643459) (xy 232.594997 -409.62594) (xy 232.565604 -409.616764) (xy 232.534812 -409.616764)
			(xy 232.505419 -409.62594) (xy 232.480095 -409.643459) (xy 232.470198 -409.655264) (xy 232.453445 -409.676047)
			(xy 232.415091 -409.713177) (xy 232.371937 -409.744599) (xy 232.324823 -409.769698) (xy 232.274671 -409.787984)
			(xy 232.22246 -409.799101) (xy 232.169208 -409.802831) (xy 232.115956 -409.799101) (xy 232.063745 -409.787984)
			(xy 232.013593 -409.769698) (xy 231.966479 -409.744599) (xy 231.923325 -409.713177) (xy 231.884971 -409.676047)
			(xy 231.868218 -409.655264) (xy 231.858321 -409.643459) (xy 231.832997 -409.62594) (xy 231.803604 -409.616764)
			(xy 231.772812 -409.616764) (xy 231.743419 -409.62594) (xy 231.718095 -409.643459) (xy 231.708198 -409.655264)
			(xy 231.691445 -409.676047) (xy 231.653091 -409.713177) (xy 231.609937 -409.744599) (xy 231.562823 -409.769698)
			(xy 231.512671 -409.787984) (xy 231.46046 -409.799101) (xy 231.407208 -409.802831) (xy 231.353956 -409.799101)
			(xy 231.301745 -409.787984) (xy 231.251593 -409.769698) (xy 231.204479 -409.744599) (xy 231.161325 -409.713177)
			(xy 231.122971 -409.676047) (xy 231.106218 -409.655264) (xy 231.096321 -409.643459) (xy 231.070997 -409.62594)
			(xy 231.041604 -409.616764) (xy 231.010812 -409.616764) (xy 230.981419 -409.62594) (xy 230.956095 -409.643459)
			(xy 230.946198 -409.655264) (xy 230.929445 -409.676047) (xy 230.891091 -409.713177) (xy 230.847937 -409.744599)
			(xy 230.800823 -409.769698) (xy 230.750671 -409.787984) (xy 230.69846 -409.799101) (xy 230.645208 -409.802831)
			(xy 230.591956 -409.799101) (xy 230.539745 -409.787984) (xy 230.489593 -409.769698) (xy 230.442479 -409.744599)
			(xy 230.399325 -409.713177) (xy 230.360971 -409.676047) (xy 230.344218 -409.655264) (xy 230.334321 -409.643459)
			(xy 230.308997 -409.62594) (xy 230.279604 -409.616764) (xy 230.248812 -409.616764) (xy 230.219419 -409.62594)
			(xy 230.194095 -409.643459) (xy 230.184198 -409.655264) (xy 230.167445 -409.676047) (xy 230.129091 -409.713177)
			(xy 230.085937 -409.744599) (xy 230.038823 -409.769698) (xy 229.988671 -409.787984) (xy 229.93646 -409.799101)
			(xy 229.883208 -409.802831) (xy 229.829956 -409.799101) (xy 229.777745 -409.787984) (xy 229.727593 -409.769698)
			(xy 229.680479 -409.744599) (xy 229.637325 -409.713177) (xy 229.598971 -409.676047) (xy 229.582218 -409.655264)
			(xy 229.572321 -409.643459) (xy 229.546997 -409.62594) (xy 229.517604 -409.616764) (xy 229.486812 -409.616764)
			(xy 229.457419 -409.62594) (xy 229.432095 -409.643459) (xy 229.422198 -409.655264) (xy 229.404008 -409.677748)
			(xy 229.361991 -409.717485) (xy 229.314456 -409.750423) (xy 229.262493 -409.775807) (xy 229.207294 -409.793055)
			(xy 229.150124 -409.801772) (xy 229.121208 -409.80233) (xy 229.093953 -409.801868) (xy 229.039998 -409.794111)
			(xy 228.987696 -409.778755) (xy 228.938112 -409.756112) (xy 228.892255 -409.726642) (xy 228.851059 -409.690946)
			(xy 228.815363 -409.649751) (xy 228.785892 -409.603895) (xy 228.763248 -409.554311) (xy 228.747891 -409.50201)
			(xy 228.740133 -409.448055) (xy 228.740133 -409.393545) (xy 228.747891 -409.33959) (xy 228.763248 -409.287289)
			(xy 228.785892 -409.237705) (xy 228.815363 -409.191849) (xy 228.851059 -409.150654) (xy 228.892255 -409.114958)
			(xy 228.938112 -409.085488) (xy 228.987696 -409.062845) (xy 229.039998 -409.047489) (xy 229.093953 -409.039732)
			(xy 229.121208 -409.039314) (xy 229.150124 -409.039849) (xy 229.207294 -409.048577) (xy 229.262493 -409.065832)
			(xy 229.314455 -409.09122) (xy 229.361992 -409.124157) (xy 229.404013 -409.163891) (xy 229.422198 -409.18638)
			(xy 229.432095 -409.198185) (xy 229.457419 -409.215704) (xy 229.486812 -409.22488) (xy 229.517604 -409.22488)
			(xy 229.546997 -409.215704) (xy 229.572321 -409.198185) (xy 229.582218 -409.18638) (xy 229.598971 -409.165597)
			(xy 229.637325 -409.128467) (xy 229.680479 -409.097045) (xy 229.727593 -409.071946) (xy 229.777745 -409.05366)
			(xy 229.829956 -409.042543) (xy 229.883208 -409.038813) (xy 229.93646 -409.042543) (xy 229.988671 -409.05366)
			(xy 230.038823 -409.071946) (xy 230.085937 -409.097045) (xy 230.129091 -409.128467) (xy 230.167445 -409.165597)
			(xy 230.184198 -409.18638) (xy 230.194095 -409.198185) (xy 230.219419 -409.215704) (xy 230.248812 -409.22488)
			(xy 230.279604 -409.22488) (xy 230.308997 -409.215704) (xy 230.334321 -409.198185) (xy 230.344218 -409.18638)
			(xy 230.360971 -409.165597) (xy 230.399325 -409.128467) (xy 230.442479 -409.097045) (xy 230.489593 -409.071946)
			(xy 230.539745 -409.05366) (xy 230.591956 -409.042543) (xy 230.645208 -409.038813) (xy 230.69846 -409.042543)
			(xy 230.750671 -409.05366) (xy 230.800823 -409.071946) (xy 230.847937 -409.097045) (xy 230.891091 -409.128467)
			(xy 230.929445 -409.165597) (xy 230.946198 -409.18638) (xy 230.956095 -409.198185) (xy 230.981419 -409.215704)
			(xy 231.010812 -409.22488) (xy 231.041604 -409.22488) (xy 231.070997 -409.215704) (xy 231.096321 -409.198185)
			(xy 231.106218 -409.18638) (xy 231.122971 -409.165597) (xy 231.161325 -409.128467) (xy 231.204479 -409.097045)
			(xy 231.251593 -409.071946) (xy 231.301745 -409.05366) (xy 231.353956 -409.042543) (xy 231.407208 -409.038813)
			(xy 231.46046 -409.042543) (xy 231.512671 -409.05366) (xy 231.562823 -409.071946) (xy 231.609937 -409.097045)
			(xy 231.653091 -409.128467) (xy 231.691445 -409.165597) (xy 231.708198 -409.18638) (xy 231.718095 -409.198185)
			(xy 231.743419 -409.215704) (xy 231.772812 -409.22488) (xy 231.803604 -409.22488) (xy 231.832997 -409.215704)
			(xy 231.858321 -409.198185) (xy 231.868218 -409.18638) (xy 231.884971 -409.165597) (xy 231.923325 -409.128467)
			(xy 231.966479 -409.097045) (xy 232.013593 -409.071946) (xy 232.063745 -409.05366) (xy 232.115956 -409.042543)
			(xy 232.169208 -409.038813) (xy 232.22246 -409.042543) (xy 232.274671 -409.05366) (xy 232.324823 -409.071946)
			(xy 232.371937 -409.097045) (xy 232.415091 -409.128467) (xy 232.453445 -409.165597) (xy 232.470198 -409.18638)
			(xy 232.480095 -409.198185) (xy 232.505419 -409.215704) (xy 232.534812 -409.22488) (xy 232.565604 -409.22488)
			(xy 232.594997 -409.215704) (xy 232.620321 -409.198185) (xy 232.630218 -409.18638) (xy 232.646971 -409.165597)
			(xy 232.685325 -409.128467) (xy 232.728479 -409.097045) (xy 232.775593 -409.071946) (xy 232.825745 -409.05366)
			(xy 232.877956 -409.042543) (xy 232.931208 -409.038813) (xy 232.98446 -409.042543) (xy 233.036671 -409.05366)
			(xy 233.086823 -409.071946) (xy 233.133937 -409.097045) (xy 233.177091 -409.128467) (xy 233.215445 -409.165597)
			(xy 233.232198 -409.18638) (xy 233.242095 -409.198185) (xy 233.267419 -409.215704) (xy 233.296812 -409.22488)
			(xy 233.327604 -409.22488) (xy 233.356997 -409.215704) (xy 233.382321 -409.198185) (xy 233.392218 -409.18638)
			(xy 233.408971 -409.165597) (xy 233.447325 -409.128467) (xy 233.490479 -409.097045) (xy 233.537593 -409.071946)
			(xy 233.587745 -409.05366) (xy 233.639956 -409.042543) (xy 233.693208 -409.038813) (xy 233.74646 -409.042543)
			(xy 233.798671 -409.05366) (xy 233.848823 -409.071946) (xy 233.895937 -409.097045) (xy 233.939091 -409.128467)
			(xy 233.977445 -409.165597) (xy 233.994198 -409.18638) (xy 234.004095 -409.198185) (xy 234.029419 -409.215704)
			(xy 234.058812 -409.22488) (xy 234.089604 -409.22488) (xy 234.118997 -409.215704) (xy 234.144321 -409.198185)
			(xy 234.154218 -409.18638) (xy 234.172408 -409.163895) (xy 234.214425 -409.124154) (xy 234.261959 -409.09121)
			(xy 234.313921 -409.065819) (xy 234.36912 -409.048561) (xy 234.426291 -409.039833) (xy 234.455208 -409.039314)
			(xy 234.482338 -409.039784) (xy 234.536051 -409.047457) (xy 234.588136 -409.062662) (xy 234.637542 -409.085091)
			(xy 234.683273 -409.114292) (xy 234.724406 -409.149677) (xy 234.760112 -409.190531) (xy 234.775248 -409.21305)
			(xy 234.783944 -409.225383) (xy 234.807077 -409.244738) (xy 234.834851 -409.2565) (xy 234.864849 -409.259647)
			(xy 234.894459 -409.253904) (xy 234.921105 -409.239771) (xy 234.93222 -409.22956) (xy 235.84662 -408.31516)
			(xy 235.84662 -405.946102) (xy 235.84712 -405.920121) (xy 235.855284 -405.868805) (xy 235.871381 -405.8194)
			(xy 235.895014 -405.773123) (xy 235.925599 -405.731116) (xy 235.943648 -405.712422) (xy 238.0488 -403.607016)
			(xy 238.05261 -403.594824) (xy 238.06093 -403.569083) (xy 238.08382 -403.520069) (xy 238.113404 -403.474781)
			(xy 238.149089 -403.434125) (xy 238.19016 -403.398919) (xy 238.235792 -403.369867) (xy 238.285071 -403.347553)
			(xy 238.337007 -403.332424) (xy 238.39056 -403.324783) (xy 238.417608 -403.324314) (xy 238.44486 -403.324778)
			(xy 238.498809 -403.332536) (xy 238.551104 -403.347893) (xy 238.600682 -403.370536) (xy 238.646533 -403.400005)
			(xy 238.687723 -403.435699) (xy 238.723413 -403.476891) (xy 238.752878 -403.522744) (xy 238.775518 -403.572324)
			(xy 238.79087 -403.624621) (xy 238.798624 -403.67857) (xy 238.799116 -403.705822) (xy 238.798643 -403.732869)
			(xy 238.790999 -403.78642) (xy 238.775868 -403.838354) (xy 238.753553 -403.887631) (xy 238.724501 -403.933261)
			(xy 238.689295 -403.97433) (xy 238.648641 -404.010015) (xy 238.603354 -404.039599) (xy 238.554343 -404.06249)
			(xy 238.528606 -404.07082) (xy 238.516414 -404.07463) (xy 236.508036 -406.083008) (xy 236.508036 -408.452066)
			(xy 236.507539 -408.478047) (xy 236.499378 -408.529365) (xy 236.483282 -408.578773) (xy 236.459651 -408.625051)
			(xy 236.429065 -408.667058) (xy 236.411008 -408.685746) (xy 233.789474 -411.30728) (xy 233.770754 -411.325298)
			(xy 233.728741 -411.355862) (xy 233.682469 -411.379488) (xy 233.633075 -411.395596) (xy 233.58177 -411.403789)
			(xy 233.555794 -411.404308) (xy 228.569774 -411.404308) (xy 228.543795 -411.403806) (xy 228.492482 -411.395636)
			(xy 228.443082 -411.379533) (xy 228.396811 -411.355894) (xy 228.354813 -411.325303) (xy 228.336094 -411.30728)
			(xy 226.982528 -409.953714) (xy 226.964514 -409.934993) (xy 226.933956 -409.892979) (xy 226.910338 -409.846706)
			(xy 226.894239 -409.797312) (xy 226.886055 -409.746009) (xy 226.8855 -409.720034) (xy 226.8855 -407.388822)
			(xy 226.885868 -407.366212) (xy 226.892031 -407.321413) (xy 226.904243 -407.277873) (xy 226.912932 -407.256996)
			(xy 226.91725 -407.247344) (xy 226.91725 -407.185876) (xy 226.784154 -407.185876) (xy 225.637598 -408.332432)
			(xy 225.627298 -408.3435) (xy 225.613104 -408.370176) (xy 225.607334 -408.399838) (xy 225.610493 -408.42989)
			(xy 225.622305 -408.457703) (xy 225.641737 -408.480845) (xy 225.667088 -408.49729) (xy 225.696141 -408.505599)
			(xy 225.711258 -408.505914) (xy 225.717608 -408.505914) (xy 225.74486 -408.506378) (xy 225.798809 -408.514136)
			(xy 225.851104 -408.529493) (xy 225.900682 -408.552136) (xy 225.946533 -408.581605) (xy 225.987723 -408.617299)
			(xy 226.023413 -408.658491) (xy 226.052878 -408.704344) (xy 226.075518 -408.753924) (xy 226.09087 -408.806221)
			(xy 226.098624 -408.86017) (xy 226.099116 -408.887422) (xy 226.098723 -408.912357) (xy 226.092251 -408.961806)
			(xy 226.079395 -409.009991) (xy 226.060373 -409.056091) (xy 226.048316 -409.077922) (xy 226.048316 -411.716982)
			(xy 226.047818 -411.742963) (xy 226.039654 -411.794279) (xy 226.023556 -411.843684) (xy 225.999922 -411.88996)
			(xy 225.969333 -411.931964) (xy 225.951288 -411.950662) (xy 225.135948 -412.766002) (xy 225.117244 -412.784027)
			(xy 225.075223 -412.81456) (xy 225.028943 -412.838142) (xy 224.979542 -412.854192) (xy 224.928239 -412.862315)
			(xy 224.902268 -412.862776) (xy 215.826848 -412.862776) (xy 215.800881 -412.862263) (xy 215.749588 -412.854134)
			(xy 215.700197 -412.838084) (xy 215.653924 -412.814508) (xy 215.611906 -412.783986) (xy 215.593168 -412.766002)
			(xy 215.049608 -412.222696) (xy 214.528908 -412.743142) (xy 214.510204 -412.761167) (xy 214.468185 -412.791701)
			(xy 214.421904 -412.815282) (xy 214.372503 -412.831329) (xy 214.321199 -412.839447) (xy 214.295228 -412.839916)
			(xy 205.362048 -412.839916) (xy 205.336081 -412.839403) (xy 205.284787 -412.831275) (xy 205.235395 -412.815226)
			(xy 205.18912 -412.791653) (xy 205.1471 -412.761133) (xy 205.128368 -412.743142) (xy 204.381608 -411.996636)
			(xy 203.609448 -412.768542) (xy 203.590745 -412.786569) (xy 203.548727 -412.817108) (xy 203.502446 -412.840695)
			(xy 203.453045 -412.856748) (xy 203.40174 -412.864872) (xy 203.375768 -412.865316) (xy 195.326508 -412.865316)
			(xy 195.300539 -412.864808) (xy 195.249241 -412.856688) (xy 195.199843 -412.840646) (xy 195.153561 -412.817077)
			(xy 195.111533 -412.786562) (xy 195.092828 -412.768542) (xy 193.606928 -411.282642) (xy 193.588912 -411.263922)
			(xy 193.558351 -411.221908) (xy 193.534728 -411.175636) (xy 193.518626 -411.126242) (xy 193.510437 -411.074938)
			(xy 193.5099 -411.048962) (xy 193.5099 -405.293322) (xy 193.494914 -405.264366) (xy 193.491104 -405.256238)
			(xy 193.44894 -405.214074) (xy 193.04762 -405.61514) (xy 193.0289 -405.633156) (xy 192.986887 -405.663717)
			(xy 192.940614 -405.687339) (xy 192.89122 -405.70344) (xy 192.839916 -405.711626) (xy 192.81394 -405.712168)
			(xy 191.749426 -405.712168) (xy 191.723445 -405.71167) (xy 191.672127 -405.703509) (xy 191.622719 -405.687414)
			(xy 191.576441 -405.663783) (xy 191.534432 -405.633198) (xy 191.515746 -405.61514) (xy 190.95085 -405.050498)
			(xy 190.94063 -405.040888) (xy 190.916165 -405.027181) (xy 190.888893 -405.020652) (xy 190.860873 -405.021794)
			(xy 190.834223 -405.030522) (xy 190.810955 -405.046175) (xy 190.792828 -405.067572) (xy 190.781211 -405.093095)
			(xy 190.778638 -405.106886) (xy 190.774092 -405.133602) (xy 190.758441 -405.185483) (xy 190.735605 -405.234627)
			(xy 190.706044 -405.280046) (xy 190.670353 -405.320823) (xy 190.62925 -405.35614) (xy 190.583564 -405.385284)
			(xy 190.534213 -405.40767) (xy 190.48219 -405.422846) (xy 190.428544 -405.430507) (xy 190.401448 -405.43099)
			(xy 190.374193 -405.43053) (xy 190.320238 -405.422778) (xy 190.267936 -405.407426) (xy 190.218351 -405.384786)
			(xy 190.172493 -405.355319) (xy 190.131296 -405.319625) (xy 190.095599 -405.278431) (xy 190.066128 -405.232576)
			(xy 190.043484 -405.182993) (xy 190.028128 -405.130691) (xy 190.020372 -405.076737) (xy 190.01994 -405.049482)
			(xy 190.020416 -405.022387) (xy 190.028085 -404.968743) (xy 190.043267 -404.916724) (xy 190.065656 -404.867375)
			(xy 190.094802 -404.821691) (xy 190.130118 -404.78059) (xy 190.170894 -404.7449) (xy 190.21631 -404.715337)
			(xy 190.265451 -404.692497) (xy 190.317329 -404.67684) (xy 190.344044 -404.672292) (xy 190.357829 -404.669712)
			(xy 190.383328 -404.65806) (xy 190.404702 -404.639918) (xy 190.420343 -404.616652) (xy 190.429075 -404.590011)
			(xy 190.430239 -404.562) (xy 190.423749 -404.534726) (xy 190.410093 -404.510242) (xy 190.400432 -404.50008)
			(xy 190.315342 -404.41499) (xy 190.30315 -404.41118) (xy 190.27557 -404.402238) (xy 190.223289 -404.377177)
			(xy 190.175411 -404.344481) (xy 190.133042 -404.304905) (xy 190.097162 -404.259364) (xy 190.082424 -404.234396)
			(xy 190.075481 -404.222935) (xy 190.056682 -404.203851) (xy 190.033561 -404.190324) (xy 190.007713 -404.183289)
			(xy 189.980926 -404.183231) (xy 189.955048 -404.190154) (xy 189.931868 -404.20358) (xy 189.92215 -404.212806)
			(xy 188.938408 -405.196548) (xy 188.916794 -405.217328) (xy 188.868289 -405.252567) (xy 188.81487 -405.279786)
			(xy 188.757852 -405.298317) (xy 188.698637 -405.307702) (xy 188.66866 -405.308308) (xy 188.529722 -405.308308)
			(xy 188.529722 -405.386286) (xy 188.552582 -405.401272) (xy 188.578068 -405.418893) (xy 188.623507 -405.461012)
			(xy 188.643006 -405.485092) (xy 188.652903 -405.496897) (xy 188.678227 -405.514416) (xy 188.70762 -405.523592)
			(xy 188.738412 -405.523592) (xy 188.767805 -405.514416) (xy 188.793129 -405.496897) (xy 188.803026 -405.485092)
			(xy 188.821216 -405.462606) (xy 188.863232 -405.422865) (xy 188.910766 -405.389922) (xy 188.962728 -405.36453)
			(xy 189.017927 -405.347273) (xy 189.075099 -405.338546) (xy 189.104016 -405.338026) (xy 189.131267 -405.33849)
			(xy 189.185215 -405.346249) (xy 189.237509 -405.361607) (xy 189.287085 -405.384251) (xy 189.332933 -405.41372)
			(xy 189.374121 -405.449414) (xy 189.40981 -405.490607) (xy 189.439273 -405.536459) (xy 189.46191 -405.586038)
			(xy 189.477261 -405.638334) (xy 189.485013 -405.692283) (xy 189.485524 -405.719534) (xy 189.484987 -405.748449)
			(xy 189.476255 -405.805615) (xy 189.458994 -405.860809) (xy 189.433602 -405.912766) (xy 189.40066 -405.960295)
			(xy 189.360921 -406.002309) (xy 189.338458 -406.020524) (xy 189.326654 -406.030419) (xy 189.309138 -406.055738)
			(xy 189.299966 -406.085127) (xy 189.299973 -406.115914) (xy 189.309156 -406.1453) (xy 189.326682 -406.170612)
			(xy 189.338458 -406.180544) (xy 189.356856 -406.195324) (xy 189.390223 -406.228697) (xy 189.405006 -406.247092)
			(xy 189.414903 -406.258897) (xy 189.440227 -406.276416) (xy 189.46962 -406.285592) (xy 189.500412 -406.285592)
			(xy 189.529805 -406.276416) (xy 189.555129 -406.258897) (xy 189.565026 -406.247092) (xy 189.583216 -406.224606)
			(xy 189.625232 -406.184865) (xy 189.672766 -406.151922) (xy 189.724728 -406.12653) (xy 189.779927 -406.109273)
			(xy 189.837099 -406.100546) (xy 189.866016 -406.100026) (xy 189.893267 -406.10049) (xy 189.947215 -406.108249)
			(xy 189.999509 -406.123607) (xy 190.049085 -406.146251) (xy 190.094933 -406.17572) (xy 190.136121 -406.211414)
			(xy 190.17181 -406.252607) (xy 190.201273 -406.298459) (xy 190.22391 -406.348038) (xy 190.239261 -406.400334)
			(xy 190.247013 -406.454283) (xy 190.247524 -406.481534) (xy 190.246987 -406.510449) (xy 190.238255 -406.567615)
			(xy 190.220994 -406.622809) (xy 190.195602 -406.674766) (xy 190.16266 -406.722295) (xy 190.122921 -406.764309)
			(xy 190.100458 -406.782524) (xy 190.088654 -406.792419) (xy 190.071138 -406.817738) (xy 190.061966 -406.847127)
			(xy 190.061973 -406.877914) (xy 190.071156 -406.9073) (xy 190.088682 -406.932612) (xy 190.100458 -406.942544)
			(xy 190.121238 -406.959298) (xy 190.158362 -406.997651) (xy 190.189777 -407.040805) (xy 190.214871 -407.087916)
			(xy 190.233152 -407.138065) (xy 190.244265 -407.190274) (xy 190.247991 -407.243521) (xy 190.244259 -407.296768)
			(xy 190.233141 -407.348975) (xy 190.214854 -407.399122) (xy 190.189755 -407.446231) (xy 190.158335 -407.489381)
			(xy 190.121207 -407.52773) (xy 190.100458 -407.544524) (xy 190.088654 -407.554419) (xy 190.071138 -407.579738)
			(xy 190.061966 -407.609127) (xy 190.061973 -407.639914) (xy 190.071156 -407.6693) (xy 190.088682 -407.694612)
			(xy 190.100458 -407.704544) (xy 190.122945 -407.722733) (xy 190.162689 -407.764748) (xy 190.195635 -407.812281)
			(xy 190.221027 -407.864244) (xy 190.238284 -407.919444) (xy 190.24701 -407.976617) (xy 190.247524 -408.005534)
			(xy 190.247066 -408.032795) (xy 190.239315 -408.086764) (xy 190.223964 -408.139081) (xy 190.201323 -408.18868)
			(xy 190.171853 -408.234553) (xy 190.136156 -408.275764) (xy 190.094956 -408.311476) (xy 190.072264 -408.32659)
			(xy 190.060305 -408.334831) (xy 190.041297 -408.356773) (xy 190.02924 -408.383182) (xy 190.025114 -408.411918)
			(xy 190.029251 -408.440653) (xy 190.041316 -408.467058) (xy 190.060333 -408.488994) (xy 190.072264 -408.497278)
			(xy 190.099029 -408.515308) (xy 190.14666 -408.558843) (xy 190.167006 -408.583892) (xy 190.176903 -408.595697)
			(xy 190.202227 -408.613216) (xy 190.23162 -408.622392) (xy 190.262412 -408.622392) (xy 190.291805 -408.613216)
			(xy 190.317129 -408.595697) (xy 190.327026 -408.583892) (xy 190.345216 -408.561406) (xy 190.387232 -408.521665)
			(xy 190.434766 -408.488722) (xy 190.486728 -408.46333) (xy 190.541927 -408.446073) (xy 190.599099 -408.437346)
			(xy 190.628016 -408.436826) (xy 190.655267 -408.43729) (xy 190.709215 -408.445049) (xy 190.761509 -408.460407)
			(xy 190.811085 -408.483051) (xy 190.856933 -408.51252) (xy 190.898121 -408.548214) (xy 190.93381 -408.589407)
			(xy 190.963273 -408.635259) (xy 190.98591 -408.684838) (xy 191.001261 -408.737134) (xy 191.009013 -408.791083)
			(xy 191.009524 -408.818334) (xy 191.008987 -408.847249) (xy 191.000255 -408.904415) (xy 190.982994 -408.959609)
			(xy 190.957602 -409.011566) (xy 190.92466 -409.059095) (xy 190.884921 -409.101109) (xy 190.862458 -409.119324)
			(xy 190.850654 -409.129219) (xy 190.833138 -409.154538) (xy 190.823966 -409.183927) (xy 190.823973 -409.214714)
			(xy 190.833156 -409.2441) (xy 190.850682 -409.269412) (xy 190.862458 -409.279344) (xy 190.884945 -409.297533)
			(xy 190.924689 -409.339548) (xy 190.957635 -409.387081) (xy 190.983027 -409.439044) (xy 191.000284 -409.494244)
			(xy 191.00901 -409.551417) (xy 191.009524 -409.580334) (xy 191.009036 -409.607584) (xy 191.001276 -409.661529)
			(xy 190.985918 -409.713821) (xy 190.963275 -409.763395) (xy 190.933808 -409.809242) (xy 190.898117 -409.850429)
			(xy 190.856927 -409.886119) (xy 190.811079 -409.915583) (xy 190.761504 -409.938224) (xy 190.709211 -409.953579)
			(xy 190.655266 -409.961337) (xy 190.628016 -409.961842) (xy 190.599099 -409.961309) (xy 190.541928 -409.952583)
			(xy 190.486729 -409.935329) (xy 190.434766 -409.909942) (xy 190.387229 -409.877003) (xy 190.345208 -409.837267)
			(xy 190.327026 -409.814776) (xy 190.317129 -409.802971) (xy 190.291805 -409.785452) (xy 190.262412 -409.776276)
			(xy 190.23162 -409.776276) (xy 190.202227 -409.785452) (xy 190.176903 -409.802971) (xy 190.167006 -409.814776)
			(xy 190.150253 -409.835559) (xy 190.111899 -409.872689) (xy 190.068745 -409.904111) (xy 190.021631 -409.92921)
			(xy 189.971479 -409.947496) (xy 189.919268 -409.958613) (xy 189.866016 -409.962343) (xy 189.812764 -409.958613)
			(xy 189.760553 -409.947496) (xy 189.710401 -409.92921) (xy 189.663287 -409.904111) (xy 189.620133 -409.872689)
			(xy 189.581779 -409.835559) (xy 189.565026 -409.814776) (xy 189.555129 -409.802971) (xy 189.529805 -409.785452)
			(xy 189.500412 -409.776276) (xy 189.46962 -409.776276) (xy 189.440227 -409.785452) (xy 189.414903 -409.802971)
			(xy 189.405006 -409.814776) (xy 189.388253 -409.835559) (xy 189.349899 -409.872689) (xy 189.306745 -409.904111)
			(xy 189.259631 -409.92921) (xy 189.209479 -409.947496) (xy 189.157268 -409.958613) (xy 189.104016 -409.962343)
			(xy 189.050764 -409.958613) (xy 188.998553 -409.947496) (xy 188.948401 -409.92921) (xy 188.901287 -409.904111)
			(xy 188.858133 -409.872689) (xy 188.819779 -409.835559) (xy 188.803026 -409.814776) (xy 188.793129 -409.802971)
			(xy 188.767805 -409.785452) (xy 188.738412 -409.776276) (xy 188.70762 -409.776276) (xy 188.678227 -409.785452)
			(xy 188.652903 -409.802971) (xy 188.643006 -409.814776) (xy 188.626253 -409.835559) (xy 188.587899 -409.872689)
			(xy 188.544745 -409.904111) (xy 188.497631 -409.92921) (xy 188.447479 -409.947496) (xy 188.395268 -409.958613)
			(xy 188.342016 -409.962343) (xy 188.288764 -409.958613) (xy 188.236553 -409.947496) (xy 188.186401 -409.92921)
			(xy 188.139287 -409.904111) (xy 188.096133 -409.872689) (xy 188.057779 -409.835559) (xy 188.041026 -409.814776)
			(xy 188.031129 -409.802971) (xy 188.005805 -409.785452) (xy 187.976412 -409.776276) (xy 187.94562 -409.776276)
			(xy 187.916227 -409.785452) (xy 187.890903 -409.802971) (xy 187.881006 -409.814776) (xy 187.864253 -409.835559)
			(xy 187.825899 -409.872689) (xy 187.782745 -409.904111) (xy 187.735631 -409.92921) (xy 187.685479 -409.947496)
			(xy 187.633268 -409.958613) (xy 187.580016 -409.962343) (xy 187.526764 -409.958613) (xy 187.474553 -409.947496)
			(xy 187.424401 -409.92921) (xy 187.377287 -409.904111) (xy 187.334133 -409.872689) (xy 187.295779 -409.835559)
			(xy 187.279026 -409.814776) (xy 187.269129 -409.802971) (xy 187.243805 -409.785452) (xy 187.214412 -409.776276)
			(xy 187.18362 -409.776276) (xy 187.154227 -409.785452) (xy 187.128903 -409.802971) (xy 187.119006 -409.814776)
			(xy 187.100815 -409.837259) (xy 187.058798 -409.876996) (xy 187.011263 -409.909934) (xy 186.959301 -409.935318)
			(xy 186.904102 -409.952567) (xy 186.846932 -409.961285) (xy 186.818016 -409.961842) (xy 186.790763 -409.961357)
			(xy 186.736812 -409.953603) (xy 186.684513 -409.938249) (xy 186.634932 -409.91561) (xy 186.589077 -409.886144)
			(xy 186.547882 -409.850453) (xy 186.512186 -409.809263) (xy 186.482714 -409.763412) (xy 186.460068 -409.713834)
			(xy 186.444708 -409.661537) (xy 186.436946 -409.607587) (xy 186.436508 -409.580334) (xy 186.43704 -409.551416)
			(xy 186.445762 -409.494242) (xy 186.463013 -409.43904) (xy 186.488397 -409.387072) (xy 186.521332 -409.339531)
			(xy 186.561064 -409.297504) (xy 186.583574 -409.279344) (xy 186.595386 -409.269447) (xy 186.612915 -409.244121)
			(xy 186.622101 -409.214721) (xy 186.622107 -409.18392) (xy 186.612934 -409.154517) (xy 186.595415 -409.129183)
			(xy 186.583574 -409.119324) (xy 186.561092 -409.101133) (xy 186.521358 -409.059114) (xy 186.488422 -409.011579)
			(xy 186.463039 -408.959617) (xy 186.44579 -408.904419) (xy 186.437071 -408.847249) (xy 186.436508 -408.818334)
			(xy 186.436991 -408.791075) (xy 186.444744 -408.73711) (xy 186.460096 -408.684797) (xy 186.482736 -408.635202)
			(xy 186.512202 -408.589332) (xy 186.547895 -408.548121) (xy 186.589089 -408.512409) (xy 186.611768 -408.497278)
			(xy 186.6237 -408.488997) (xy 186.642712 -408.467058) (xy 186.654774 -408.440653) (xy 186.65891 -408.411918)
			(xy 186.654785 -408.383183) (xy 186.642732 -408.356773) (xy 186.623728 -408.334828) (xy 186.611768 -408.32659)
			(xy 186.585007 -408.308555) (xy 186.537386 -408.265013) (xy 186.517026 -408.239976) (xy 186.507129 -408.228171)
			(xy 186.481805 -408.210652) (xy 186.452412 -408.201476) (xy 186.42162 -408.201476) (xy 186.392227 -408.210652)
			(xy 186.366903 -408.228171) (xy 186.357006 -408.239976) (xy 186.338815 -408.262459) (xy 186.296798 -408.302196)
			(xy 186.249263 -408.335134) (xy 186.197301 -408.360518) (xy 186.142102 -408.377767) (xy 186.084932 -408.386485)
			(xy 186.056016 -408.387042) (xy 186.028763 -408.386557) (xy 185.974812 -408.378803) (xy 185.922513 -408.363449)
			(xy 185.872932 -408.34081) (xy 185.827077 -408.311344) (xy 185.785882 -408.275653) (xy 185.750186 -408.234463)
			(xy 185.720714 -408.188612) (xy 185.698068 -408.139034) (xy 185.682708 -408.086737) (xy 185.674946 -408.032787)
			(xy 185.674508 -408.005534) (xy 185.67504 -407.976616) (xy 185.683762 -407.919442) (xy 185.701013 -407.86424)
			(xy 185.726397 -407.812272) (xy 185.759332 -407.764731) (xy 185.799064 -407.722704) (xy 185.821574 -407.704544)
			(xy 185.833386 -407.694647) (xy 185.850915 -407.669321) (xy 185.860101 -407.639921) (xy 185.860107 -407.60912)
			(xy 185.850934 -407.579717) (xy 185.833415 -407.554383) (xy 185.821574 -407.544524) (xy 185.800788 -407.527771)
			(xy 185.763651 -407.489418) (xy 185.732224 -407.446262) (xy 185.70712 -407.399147) (xy 185.688829 -407.348992)
			(xy 185.677708 -407.296776) (xy 185.673975 -407.243521) (xy 185.677702 -407.190265) (xy 185.688817 -407.138049)
			(xy 185.707103 -407.087892) (xy 185.732202 -407.040773) (xy 185.763625 -406.997614) (xy 185.800757 -406.959257)
			(xy 185.821574 -406.942544) (xy 185.833386 -406.932647) (xy 185.850915 -406.907321) (xy 185.860101 -406.877921)
			(xy 185.860107 -406.84712) (xy 185.850934 -406.817717) (xy 185.833415 -406.792383) (xy 185.821574 -406.782524)
			(xy 185.800788 -406.765771) (xy 185.763651 -406.727418) (xy 185.732224 -406.684262) (xy 185.70712 -406.637147)
			(xy 185.688829 -406.586992) (xy 185.677708 -406.534776) (xy 185.673975 -406.481521) (xy 185.677702 -406.428265)
			(xy 185.688817 -406.376049) (xy 185.707103 -406.325892) (xy 185.732202 -406.278773) (xy 185.763625 -406.235614)
			(xy 185.800757 -406.197257) (xy 185.821574 -406.180544) (xy 185.833386 -406.170647) (xy 185.850915 -406.145321)
			(xy 185.860101 -406.115921) (xy 185.860107 -406.08512) (xy 185.850934 -406.055717) (xy 185.833415 -406.030383)
			(xy 185.821574 -406.020524) (xy 185.799092 -406.002333) (xy 185.759358 -405.960314) (xy 185.726422 -405.912779)
			(xy 185.701039 -405.860817) (xy 185.68379 -405.805619) (xy 185.675071 -405.748449) (xy 185.674508 -405.719534)
			(xy 185.674963 -405.692974) (xy 185.682323 -405.640365) (xy 185.696904 -405.589285) (xy 185.718427 -405.540719)
			(xy 185.746473 -405.495606) (xy 185.763154 -405.474932) (xy 185.771992 -405.463545) (xy 185.783518 -405.437139)
			(xy 185.787209 -405.408565) (xy 185.782772 -405.380097) (xy 185.77056 -405.354001) (xy 185.751545 -405.332356)
			(xy 185.72724 -405.316883) (xy 185.699581 -405.308814) (xy 185.685176 -405.308308) (xy 181.457346 -405.308308)
			(xy 181.442977 -405.308795) (xy 181.415373 -405.31679) (xy 181.391091 -405.332159) (xy 181.372052 -405.353685)
			(xy 181.359765 -405.379664) (xy 181.355202 -405.408037) (xy 181.356508 -405.422354) (xy 181.357912 -405.434179)
			(xy 181.359435 -405.457945) (xy 181.359556 -405.469852) (xy 181.35907 -405.497103) (xy 181.351314 -405.551051)
			(xy 181.335959 -405.603346) (xy 181.313317 -405.652923) (xy 181.283851 -405.698773) (xy 181.24816 -405.739964)
			(xy 181.206969 -405.775655) (xy 181.161119 -405.805121) (xy 181.111542 -405.827763) (xy 181.059247 -405.843118)
			(xy 181.005299 -405.850874) (xy 180.950797 -405.850874) (xy 180.896849 -405.843118) (xy 180.844554 -405.827763)
			(xy 180.794977 -405.805121) (xy 180.749127 -405.775655) (xy 180.707936 -405.739964) (xy 180.672245 -405.698773)
			(xy 180.642779 -405.652923) (xy 180.620137 -405.603346) (xy 180.604782 -405.551051) (xy 180.597026 -405.497103)
			(xy 180.59654 -405.469852) (xy 180.596934 -405.444209) (xy 180.603768 -405.393382) (xy 180.617358 -405.34393)
			(xy 180.63746 -405.296749) (xy 180.66371 -405.252692) (xy 180.679344 -405.232362) (xy 180.687851 -405.220896)
			(xy 180.698743 -405.194517) (xy 180.701913 -405.166155) (xy 180.697114 -405.138023) (xy 180.68472 -405.112316)
			(xy 180.665698 -405.091041) (xy 180.641533 -405.075858) (xy 180.614111 -405.067952) (xy 180.599842 -405.067516)
			(xy 179.111656 -405.067516) (xy 178.606196 -405.57323) (xy 178.584602 -405.594023) (xy 178.53609 -405.629236)
			(xy 178.482662 -405.656417) (xy 178.425637 -405.674894) (xy 178.366421 -405.684213) (xy 178.336448 -405.684736)
			(xy 178.309205 -405.684254) (xy 178.255273 -405.67651) (xy 178.202991 -405.661172) (xy 178.153423 -405.638553)
			(xy 178.107577 -405.609112) (xy 178.066385 -405.573448) (xy 178.030686 -405.532287) (xy 178.001206 -405.486467)
			(xy 177.978543 -405.436918) (xy 177.96316 -405.38465) (xy 177.955369 -405.330724) (xy 177.95494 -405.303482)
			(xy 177.955492 -405.273499) (xy 177.964863 -405.214271) (xy 177.983389 -405.157239) (xy 178.010612 -405.103809)
			(xy 178.045862 -405.055298) (xy 178.0667 -405.033734) (xy 178.68392 -404.416514) (xy 178.705516 -404.395725)
			(xy 178.75403 -404.360519) (xy 178.807458 -404.333344) (xy 178.864482 -404.314872) (xy 178.923696 -404.305558)
			(xy 178.953668 -404.305008) (xy 180.227224 -404.305008) (xy 180.241108 -404.304546) (xy 180.267851 -404.297076)
			(xy 180.291589 -404.28267) (xy 180.310561 -404.262395) (xy 180.323361 -404.237754) (xy 180.329039 -404.210574)
			(xy 180.327176 -404.182869) (xy 180.322982 -404.169626) (xy 180.312912 -404.138912) (xy 180.302066 -404.075196)
			(xy 180.301392 -404.04288) (xy 180.301879 -404.01563) (xy 180.309638 -403.961684) (xy 180.324995 -403.909392)
			(xy 180.347637 -403.859817) (xy 180.377104 -403.813969) (xy 180.412795 -403.772781) (xy 180.453985 -403.737092)
			(xy 180.499835 -403.707628) (xy 180.549411 -403.684988) (xy 180.601704 -403.669634) (xy 180.65565 -403.661878)
			(xy 180.6829 -403.661372) (xy 180.710305 -403.661847) (xy 180.76455 -403.669694) (xy 180.817113 -403.685227)
			(xy 180.86691 -403.708125) (xy 180.912916 -403.737917) (xy 180.933852 -403.755606) (xy 180.944701 -403.764472)
			(xy 180.970022 -403.776443) (xy 180.997643 -403.781086) (xy 181.025487 -403.77805) (xy 181.051458 -403.767564)
			(xy 181.073605 -403.750418) (xy 181.090261 -403.7279) (xy 181.09565 -403.714966) (xy 181.106344 -403.688162)
			(xy 181.13464 -403.637867) (xy 181.170188 -403.592408) (xy 181.212178 -403.552822) (xy 181.259652 -403.520012)
			(xy 181.311525 -403.494727) (xy 181.366616 -403.477544) (xy 181.423666 -403.468855) (xy 181.45252 -403.468332)
			(xy 181.479767 -403.46882) (xy 181.533707 -403.476578) (xy 181.585994 -403.491933) (xy 181.635564 -403.514573)
			(xy 181.681407 -403.544036) (xy 181.72259 -403.579724) (xy 181.758276 -403.620909) (xy 181.787737 -403.666754)
			(xy 181.810374 -403.716325) (xy 181.825727 -403.768612) (xy 181.833482 -403.822553) (xy 181.833482 -403.877047)
			(xy 181.825727 -403.930988) (xy 181.810374 -403.983275) (xy 181.791158 -404.025354) (xy 185.10961 -404.025354)
			(xy 185.113681 -403.969732) (xy 185.125807 -403.915295) (xy 185.14573 -403.863204) (xy 185.173026 -403.814569)
			(xy 185.207112 -403.770426) (xy 185.247261 -403.731717) (xy 185.292619 -403.699266) (xy 185.342219 -403.673765)
			(xy 185.395003 -403.655758) (xy 185.449846 -403.645628) (xy 185.50558 -403.643591) (xy 185.561017 -403.649691)
			(xy 185.614974 -403.663797) (xy 185.666303 -403.685609) (xy 185.713909 -403.714663) (xy 185.756777 -403.750338)
			(xy 185.793994 -403.791875) (xy 185.824767 -403.838388) (xy 185.848439 -403.888885) (xy 185.864507 -403.942292)
			(xy 185.872627 -403.997468) (xy 185.873136 -404.025354) (xy 186.53201 -404.025354) (xy 186.536081 -403.969732)
			(xy 186.548207 -403.915295) (xy 186.56813 -403.863204) (xy 186.595426 -403.814569) (xy 186.629512 -403.770426)
			(xy 186.669661 -403.731717) (xy 186.715019 -403.699266) (xy 186.764619 -403.673765) (xy 186.817403 -403.655758)
			(xy 186.872246 -403.645628) (xy 186.92798 -403.643591) (xy 186.983417 -403.649691) (xy 187.037374 -403.663797)
			(xy 187.088703 -403.685609) (xy 187.136309 -403.714663) (xy 187.179177 -403.750338) (xy 187.216394 -403.791875)
			(xy 187.247167 -403.838388) (xy 187.270839 -403.888885) (xy 187.286907 -403.942292) (xy 187.295027 -403.997468)
			(xy 187.295536 -404.025354) (xy 187.295351 -404.035514) (xy 187.92901 -404.035514) (xy 187.933081 -403.979892)
			(xy 187.945207 -403.925455) (xy 187.96513 -403.873364) (xy 187.992426 -403.824729) (xy 188.026512 -403.780586)
			(xy 188.066661 -403.741877) (xy 188.112019 -403.709426) (xy 188.161619 -403.683925) (xy 188.214403 -403.665918)
			(xy 188.269246 -403.655788) (xy 188.32498 -403.653751) (xy 188.380417 -403.659851) (xy 188.434374 -403.673957)
			(xy 188.485703 -403.695769) (xy 188.533309 -403.724823) (xy 188.576177 -403.760498) (xy 188.613394 -403.802035)
			(xy 188.644167 -403.848548) (xy 188.667839 -403.899045) (xy 188.683907 -403.952452) (xy 188.692027 -404.007628)
			(xy 188.692536 -404.035514) (xy 188.692027 -404.0634) (xy 188.683907 -404.118576) (xy 188.667839 -404.171983)
			(xy 188.644167 -404.22248) (xy 188.613394 -404.268993) (xy 188.576177 -404.31053) (xy 188.533309 -404.346205)
			(xy 188.485703 -404.375259) (xy 188.434374 -404.397071) (xy 188.380417 -404.411177) (xy 188.32498 -404.417277)
			(xy 188.269246 -404.41524) (xy 188.214403 -404.40511) (xy 188.161619 -404.387103) (xy 188.112019 -404.361602)
			(xy 188.066661 -404.329151) (xy 188.026512 -404.290442) (xy 187.992426 -404.246299) (xy 187.96513 -404.197664)
			(xy 187.945207 -404.145573) (xy 187.933081 -404.091136) (xy 187.92901 -404.035514) (xy 187.295351 -404.035514)
			(xy 187.295027 -404.05324) (xy 187.286907 -404.108416) (xy 187.270839 -404.161823) (xy 187.247167 -404.21232)
			(xy 187.216394 -404.258833) (xy 187.179177 -404.30037) (xy 187.136309 -404.336045) (xy 187.088703 -404.365099)
			(xy 187.037374 -404.386911) (xy 186.983417 -404.401017) (xy 186.92798 -404.407117) (xy 186.872246 -404.40508)
			(xy 186.817403 -404.39495) (xy 186.764619 -404.376943) (xy 186.715019 -404.351442) (xy 186.669661 -404.318991)
			(xy 186.629512 -404.280282) (xy 186.595426 -404.236139) (xy 186.56813 -404.187504) (xy 186.548207 -404.135413)
			(xy 186.536081 -404.080976) (xy 186.53201 -404.025354) (xy 185.873136 -404.025354) (xy 185.872627 -404.05324)
			(xy 185.864507 -404.108416) (xy 185.848439 -404.161823) (xy 185.824767 -404.21232) (xy 185.793994 -404.258833)
			(xy 185.756777 -404.30037) (xy 185.713909 -404.336045) (xy 185.666303 -404.365099) (xy 185.614974 -404.386911)
			(xy 185.561017 -404.401017) (xy 185.50558 -404.407117) (xy 185.449846 -404.40508) (xy 185.395003 -404.39495)
			(xy 185.342219 -404.376943) (xy 185.292619 -404.351442) (xy 185.247261 -404.318991) (xy 185.207112 -404.280282)
			(xy 185.173026 -404.236139) (xy 185.14573 -404.187504) (xy 185.125807 -404.135413) (xy 185.113681 -404.080976)
			(xy 185.10961 -404.025354) (xy 181.791158 -404.025354) (xy 181.787737 -404.032846) (xy 181.758276 -404.078691)
			(xy 181.72259 -404.119876) (xy 181.681407 -404.155564) (xy 181.635564 -404.185027) (xy 181.585994 -404.207667)
			(xy 181.533707 -404.223022) (xy 181.479767 -404.23078) (xy 181.45252 -404.231348) (xy 181.425115 -404.230875)
			(xy 181.37087 -404.223029) (xy 181.318307 -404.207495) (xy 181.268511 -404.184595) (xy 181.222507 -404.1548)
			(xy 181.201568 -404.137114) (xy 181.190719 -404.128243) (xy 181.165396 -404.116264) (xy 181.137771 -404.111617)
			(xy 181.109922 -404.11465) (xy 181.083945 -404.125136) (xy 181.061794 -404.142286) (xy 181.045137 -404.164809)
			(xy 181.03977 -404.177754) (xy 181.032658 -404.195026) (xy 181.027577 -404.207752) (xy 181.023674 -404.234865)
			(xy 181.027132 -404.262038) (xy 181.037701 -404.287309) (xy 181.054619 -404.308852) (xy 181.076662 -404.325113)
			(xy 181.0893 -404.330408) (xy 181.113921 -404.340362) (xy 181.160365 -404.366114) (xy 181.202778 -404.398073)
			(xy 181.221888 -404.416514) (xy 181.350666 -404.545292) (xy 188.510672 -404.545292) (xy 189.841632 -403.214332)
			(xy 189.85931 -403.197227) (xy 189.898301 -403.167237) (xy 189.940822 -403.142503) (xy 189.986168 -403.123437)
			(xy 190.00978 -403.116542) (xy 190.019432 -403.113444) (xy 190.035381 -403.100956) (xy 190.045253 -403.083269)
			(xy 190.04751 -403.06314) (xy 190.045086 -403.053296) (xy 190.038077 -403.02738) (xy 190.030557 -402.974222)
			(xy 190.0301 -402.947378) (xy 190.030573 -402.920331) (xy 190.038217 -402.866781) (xy 190.053348 -402.814847)
			(xy 190.075664 -402.765572) (xy 190.104716 -402.719942) (xy 190.139923 -402.678874) (xy 190.180577 -402.643191)
			(xy 190.225865 -402.613608) (xy 190.274876 -402.590719) (xy 190.30061 -402.58238) (xy 190.312802 -402.57857)
			(xy 190.381128 -402.510244) (xy 190.3349 -402.463762) (xy 190.320168 -402.460714) (xy 190.292185 -402.454057)
			(xy 190.238477 -402.433472) (xy 190.188464 -402.405065) (xy 190.143277 -402.369478) (xy 190.103939 -402.327516)
			(xy 190.07134 -402.280129) (xy 190.046217 -402.228388) (xy 190.029138 -402.173464) (xy 190.02049 -402.116601)
			(xy 190.01994 -402.087842) (xy 190.020176 -402.068075) (xy 190.02425 -402.028752) (xy 190.028068 -402.009356)
			(xy 190.030614 -401.994503) (xy 190.027903 -401.964506) (xy 190.016565 -401.936602) (xy 189.997585 -401.913216)
			(xy 189.972611 -401.896379) (xy 189.943813 -401.887554) (xy 189.928754 -401.886928) (xy 189.91834 -401.886928)
			(xy 189.892359 -401.886431) (xy 189.84104 -401.878271) (xy 189.791633 -401.862176) (xy 189.745354 -401.838544)
			(xy 189.703346 -401.807958) (xy 189.68466 -401.7899) (xy 188.836554 -400.942048) (xy 188.6839 -400.942048)
			(xy 188.669535 -400.942542) (xy 188.641943 -400.950548) (xy 188.617675 -400.965925) (xy 188.598654 -400.987456)
			(xy 188.586385 -401.013434) (xy 188.581842 -401.041802) (xy 188.585383 -401.070313) (xy 188.596729 -401.096707)
			(xy 188.605414 -401.108164) (xy 188.621807 -401.128738) (xy 188.649377 -401.17354) (xy 188.670525 -401.221707)
			(xy 188.684849 -401.272325) (xy 188.692078 -401.324431) (xy 188.692536 -401.350734) (xy 188.69205 -401.377985)
			(xy 188.684294 -401.431933) (xy 188.668939 -401.484228) (xy 188.646297 -401.533805) (xy 188.616831 -401.579655)
			(xy 188.58114 -401.620846) (xy 188.539949 -401.656537) (xy 188.494099 -401.686003) (xy 188.444522 -401.708645)
			(xy 188.392227 -401.724) (xy 188.338279 -401.731756) (xy 188.283777 -401.731756) (xy 188.229829 -401.724)
			(xy 188.177534 -401.708645) (xy 188.127957 -401.686003) (xy 188.082107 -401.656537) (xy 188.040916 -401.620846)
			(xy 188.005225 -401.579655) (xy 187.975759 -401.533805) (xy 187.953117 -401.484228) (xy 187.937762 -401.431933)
			(xy 187.930006 -401.377985) (xy 187.92952 -401.350734) (xy 187.929959 -401.32443) (xy 187.937188 -401.27232)
			(xy 187.951511 -401.221699) (xy 187.972658 -401.173528) (xy 188.000227 -401.128722) (xy 188.016642 -401.108164)
			(xy 188.025396 -401.09675) (xy 188.036755 -401.070339) (xy 188.040302 -401.041807) (xy 188.035756 -401.013418)
			(xy 188.023476 -400.987421) (xy 188.004437 -400.965877) (xy 187.980147 -400.950495) (xy 187.952532 -400.942493)
			(xy 187.938156 -400.942048) (xy 187.217558 -400.942048) (xy 187.203629 -400.942473) (xy 187.176805 -400.949989)
			(xy 187.153013 -400.964477) (xy 187.134023 -400.984858) (xy 187.12125 -401.009614) (xy 187.115646 -401.036901)
			(xy 187.117628 -401.064688) (xy 187.127048 -401.090903) (xy 187.143206 -401.113596) (xy 187.153804 -401.122642)
			(xy 187.175531 -401.140849) (xy 187.213877 -401.182595) (xy 187.245618 -401.229559) (xy 187.270052 -401.280707)
			(xy 187.286642 -401.33491) (xy 187.29502 -401.390972) (xy 187.295536 -401.419314) (xy 187.29505 -401.446565)
			(xy 187.287294 -401.500513) (xy 187.271939 -401.552808) (xy 187.249297 -401.602385) (xy 187.219831 -401.648235)
			(xy 187.18414 -401.689426) (xy 187.142949 -401.725117) (xy 187.097099 -401.754583) (xy 187.047522 -401.777225)
			(xy 186.995227 -401.79258) (xy 186.941279 -401.800336) (xy 186.886777 -401.800336) (xy 186.832829 -401.79258)
			(xy 186.780534 -401.777225) (xy 186.730957 -401.754583) (xy 186.685107 -401.725117) (xy 186.643916 -401.689426)
			(xy 186.608225 -401.648235) (xy 186.578759 -401.602385) (xy 186.556117 -401.552808) (xy 186.540762 -401.500513)
			(xy 186.533006 -401.446565) (xy 186.53252 -401.419314) (xy 186.533044 -401.390974) (xy 186.541443 -401.334921)
			(xy 186.558043 -401.280727) (xy 186.582479 -401.229585) (xy 186.614214 -401.182622) (xy 186.652547 -401.140872)
			(xy 186.674252 -401.122642) (xy 186.68481 -401.113559) (xy 186.700939 -401.090864) (xy 186.710339 -401.064656)
			(xy 186.712312 -401.036884) (xy 186.706712 -401.009611) (xy 186.693954 -400.984863) (xy 186.674986 -400.964481)
			(xy 186.651219 -400.949979) (xy 186.624419 -400.942434) (xy 186.610498 -400.942048) (xy 185.795158 -400.942048)
			(xy 185.781229 -400.942473) (xy 185.754405 -400.949989) (xy 185.730613 -400.964477) (xy 185.711623 -400.984858)
			(xy 185.69885 -401.009614) (xy 185.693246 -401.036901) (xy 185.695228 -401.064688) (xy 185.704648 -401.090903)
			(xy 185.720806 -401.113596) (xy 185.731404 -401.122642) (xy 185.753131 -401.140849) (xy 185.791477 -401.182595)
			(xy 185.823218 -401.229559) (xy 185.847652 -401.280707) (xy 185.864242 -401.33491) (xy 185.87262 -401.390972)
			(xy 185.873136 -401.419314) (xy 185.87265 -401.446565) (xy 185.864894 -401.500513) (xy 185.849539 -401.552808)
			(xy 185.826897 -401.602385) (xy 185.797431 -401.648235) (xy 185.76174 -401.689426) (xy 185.720549 -401.725117)
			(xy 185.674699 -401.754583) (xy 185.625122 -401.777225) (xy 185.572827 -401.79258) (xy 185.518879 -401.800336)
			(xy 185.464377 -401.800336) (xy 185.410429 -401.79258) (xy 185.358134 -401.777225) (xy 185.308557 -401.754583)
			(xy 185.262707 -401.725117) (xy 185.221516 -401.689426) (xy 185.185825 -401.648235) (xy 185.156359 -401.602385)
			(xy 185.133717 -401.552808) (xy 185.118362 -401.500513) (xy 185.110606 -401.446565) (xy 185.11012 -401.419314)
			(xy 185.110644 -401.390974) (xy 185.119043 -401.334921) (xy 185.135643 -401.280727) (xy 185.160079 -401.229585)
			(xy 185.191814 -401.182622) (xy 185.230147 -401.140872) (xy 185.251852 -401.122642) (xy 185.26241 -401.113559)
			(xy 185.278539 -401.090864) (xy 185.287939 -401.064656) (xy 185.289912 -401.036884) (xy 185.284312 -401.009611)
			(xy 185.271554 -400.984863) (xy 185.252586 -400.964481) (xy 185.228819 -400.949979) (xy 185.202019 -400.942434)
			(xy 185.188098 -400.942048) (xy 184.392824 -400.942048) (xy 184.378569 -400.94251) (xy 184.351164 -400.950369)
			(xy 184.327005 -400.965508) (xy 184.307982 -400.986742) (xy 184.29558 -401.012413) (xy 184.29077 -401.040514)
			(xy 184.293927 -401.068848) (xy 184.304804 -401.095201) (xy 184.313322 -401.10664) (xy 184.328856 -401.126928)
			(xy 184.354932 -401.17087) (xy 184.374907 -401.217901) (xy 184.388422 -401.267179) (xy 184.395237 -401.317819)
			(xy 184.395618 -401.343368) (xy 184.39511 -401.363688) (xy 184.394837 -401.377894) (xy 184.401226 -401.405568)
			(xy 184.414993 -401.430409) (xy 184.435074 -401.450494) (xy 184.459913 -401.464267) (xy 184.487585 -401.470661)
			(xy 184.50179 -401.470368) (xy 184.52211 -401.46986) (xy 184.549365 -401.470324) (xy 184.603321 -401.478083)
			(xy 184.655624 -401.493442) (xy 184.705208 -401.516088) (xy 184.751065 -401.545561) (xy 184.79226 -401.581259)
			(xy 184.827956 -401.622457) (xy 184.857425 -401.668316) (xy 184.880068 -401.717902) (xy 184.895423 -401.770205)
			(xy 184.903178 -401.824162) (xy 184.903176 -401.878673) (xy 184.895416 -401.932629) (xy 184.880055 -401.984931)
			(xy 184.857408 -402.034515) (xy 184.827935 -402.080371) (xy 184.792236 -402.121565) (xy 184.751037 -402.15726)
			(xy 184.705178 -402.186728) (xy 184.655591 -402.20937) (xy 184.603288 -402.224724) (xy 184.549331 -402.232479)
			(xy 184.49482 -402.232475) (xy 184.440864 -402.224714) (xy 184.388562 -402.209353) (xy 184.338979 -402.186705)
			(xy 184.293123 -402.157231) (xy 184.251929 -402.12153) (xy 184.216235 -402.080331) (xy 184.186768 -402.034471)
			(xy 184.164127 -401.984885) (xy 184.148774 -401.93258) (xy 184.141021 -401.878624) (xy 184.140602 -401.851368)
			(xy 184.14111 -401.831048) (xy 184.141387 -401.816843) (xy 184.135005 -401.789169) (xy 184.121238 -401.76433)
			(xy 184.101154 -401.74425) (xy 184.076311 -401.730488) (xy 184.048636 -401.724111) (xy 184.03443 -401.724368)
			(xy 184.01411 -401.724876) (xy 183.99379 -401.724368) (xy 183.979589 -401.724099) (xy 183.951927 -401.730491)
			(xy 183.927099 -401.744262) (xy 183.907029 -401.764343) (xy 183.893272 -401.789178) (xy 183.886894 -401.816844)
			(xy 183.88711 -401.831048) (xy 183.887618 -401.851368) (xy 183.887157 -401.878622) (xy 183.879404 -401.932577)
			(xy 183.864052 -401.984878) (xy 183.841412 -402.034463) (xy 183.811945 -402.08032) (xy 183.776253 -402.121517)
			(xy 183.73506 -402.157215) (xy 183.689207 -402.186688) (xy 183.639625 -402.209334) (xy 183.587325 -402.224694)
			(xy 183.533372 -402.232454) (xy 183.478864 -402.232456) (xy 183.42491 -402.224701) (xy 183.372609 -402.209347)
			(xy 183.323025 -402.186705) (xy 183.277169 -402.157237) (xy 183.235973 -402.121543) (xy 183.200276 -402.080349)
			(xy 183.170806 -402.034494) (xy 183.148161 -401.984912) (xy 183.132803 -401.932612) (xy 183.125045 -401.878658)
			(xy 183.125045 -401.82415) (xy 183.132802 -401.770196) (xy 183.148158 -401.717895) (xy 183.170802 -401.668313)
			(xy 183.200271 -401.622457) (xy 183.235967 -401.581263) (xy 183.277162 -401.545568) (xy 183.323018 -401.516099)
			(xy 183.372601 -401.493456) (xy 183.424902 -401.4781) (xy 183.478856 -401.470344) (xy 183.50611 -401.46986)
			(xy 183.52643 -401.470368) (xy 183.54064 -401.470648) (xy 183.568325 -401.46427) (xy 183.593178 -401.450506)
			(xy 183.613273 -401.430422) (xy 183.627051 -401.405577) (xy 183.633444 -401.377895) (xy 183.63311 -401.363688)
			(xy 183.632602 -401.343368) (xy 183.633013 -401.317821) (xy 183.639833 -401.267185) (xy 183.653347 -401.217912)
			(xy 183.673314 -401.170881) (xy 183.699376 -401.126935) (xy 183.714898 -401.10664) (xy 183.72336 -401.095176)
			(xy 183.734174 -401.068828) (xy 183.737292 -401.040518) (xy 183.732472 -401.012447) (xy 183.720088 -400.986799)
			(xy 183.701103 -400.965568) (xy 183.676995 -400.950404) (xy 183.649636 -400.942487) (xy 183.635396 -400.942048)
			(xy 183.443626 -400.942048) (xy 182.32374 -402.06168) (xy 182.305019 -402.079696) (xy 182.263006 -402.110256)
			(xy 182.216733 -402.133877) (xy 182.167339 -402.149979) (xy 182.116036 -402.158167) (xy 182.09006 -402.158708)
			(xy 181.382162 -402.158708) (xy 181.368079 -402.159167) (xy 181.340986 -402.166872) (xy 181.317029 -402.181686)
			(xy 181.298031 -402.202482) (xy 181.285437 -402.227676) (xy 181.280205 -402.255353) (xy 181.282734 -402.283407)
			(xy 181.292831 -402.309702) (xy 181.300882 -402.321268) (xy 181.31883 -402.346189) (xy 181.347367 -402.400564)
			(xy 181.366827 -402.458809) (xy 181.376707 -402.519418) (xy 181.377336 -402.550122) (xy 181.37685 -402.577373)
			(xy 181.369094 -402.631321) (xy 181.353739 -402.683616) (xy 181.336056 -402.722334) (xy 185.10961 -402.722334)
			(xy 185.113681 -402.666712) (xy 185.125807 -402.612275) (xy 185.14573 -402.560184) (xy 185.173026 -402.511549)
			(xy 185.207112 -402.467406) (xy 185.247261 -402.428697) (xy 185.292619 -402.396246) (xy 185.342219 -402.370745)
			(xy 185.395003 -402.352738) (xy 185.449846 -402.342608) (xy 185.50558 -402.340571) (xy 185.561017 -402.346671)
			(xy 185.614974 -402.360777) (xy 185.666303 -402.382589) (xy 185.713909 -402.411643) (xy 185.756777 -402.447318)
			(xy 185.793994 -402.488855) (xy 185.824767 -402.535368) (xy 185.848439 -402.585865) (xy 185.864507 -402.639272)
			(xy 185.866638 -402.653754) (xy 187.92901 -402.653754) (xy 187.933081 -402.598132) (xy 187.945207 -402.543695)
			(xy 187.96513 -402.491604) (xy 187.992426 -402.442969) (xy 188.026512 -402.398826) (xy 188.066661 -402.360117)
			(xy 188.112019 -402.327666) (xy 188.161619 -402.302165) (xy 188.214403 -402.284158) (xy 188.269246 -402.274028)
			(xy 188.32498 -402.271991) (xy 188.380417 -402.278091) (xy 188.434374 -402.292197) (xy 188.485703 -402.314009)
			(xy 188.533309 -402.343063) (xy 188.576177 -402.378738) (xy 188.613394 -402.420275) (xy 188.644167 -402.466788)
			(xy 188.667839 -402.517285) (xy 188.683907 -402.570692) (xy 188.692027 -402.625868) (xy 188.692536 -402.653754)
			(xy 188.692027 -402.68164) (xy 188.683907 -402.736816) (xy 188.667839 -402.790223) (xy 188.644167 -402.84072)
			(xy 188.613394 -402.887233) (xy 188.576177 -402.92877) (xy 188.533309 -402.964445) (xy 188.485703 -402.993499)
			(xy 188.434374 -403.015311) (xy 188.380417 -403.029417) (xy 188.32498 -403.035517) (xy 188.269246 -403.03348)
			(xy 188.214403 -403.02335) (xy 188.161619 -403.005343) (xy 188.112019 -402.979842) (xy 188.066661 -402.947391)
			(xy 188.026512 -402.908682) (xy 187.992426 -402.864539) (xy 187.96513 -402.815904) (xy 187.945207 -402.763813)
			(xy 187.933081 -402.709376) (xy 187.92901 -402.653754) (xy 185.866638 -402.653754) (xy 185.872627 -402.694448)
			(xy 185.873136 -402.722334) (xy 185.872627 -402.75022) (xy 185.864507 -402.805396) (xy 185.848439 -402.858803)
			(xy 185.824767 -402.9093) (xy 185.793994 -402.955813) (xy 185.756777 -402.99735) (xy 185.713909 -403.033025)
			(xy 185.666303 -403.062079) (xy 185.614974 -403.083891) (xy 185.561017 -403.097997) (xy 185.50558 -403.104097)
			(xy 185.449846 -403.10206) (xy 185.395003 -403.09193) (xy 185.342219 -403.073923) (xy 185.292619 -403.048422)
			(xy 185.247261 -403.015971) (xy 185.207112 -402.977262) (xy 185.173026 -402.933119) (xy 185.14573 -402.884484)
			(xy 185.125807 -402.832393) (xy 185.113681 -402.777956) (xy 185.10961 -402.722334) (xy 181.336056 -402.722334)
			(xy 181.331097 -402.733193) (xy 181.301631 -402.779043) (xy 181.26594 -402.820234) (xy 181.224749 -402.855925)
			(xy 181.178899 -402.885391) (xy 181.129322 -402.908033) (xy 181.077027 -402.923388) (xy 181.023079 -402.931144)
			(xy 180.968577 -402.931144) (xy 180.914629 -402.923388) (xy 180.862334 -402.908033) (xy 180.812757 -402.885391)
			(xy 180.766907 -402.855925) (xy 180.725716 -402.820234) (xy 180.690025 -402.779043) (xy 180.660559 -402.733193)
			(xy 180.637917 -402.683616) (xy 180.622562 -402.631321) (xy 180.614806 -402.577373) (xy 180.61432 -402.550122)
			(xy 180.614957 -402.519419) (xy 180.624838 -402.458812) (xy 180.644301 -402.40057) (xy 180.672841 -402.346198)
			(xy 180.690774 -402.321268) (xy 180.698865 -402.309725) (xy 180.708971 -402.283421) (xy 180.711503 -402.255357)
			(xy 180.706269 -402.22767) (xy 180.693668 -402.202466) (xy 180.674659 -402.181666) (xy 180.650689 -402.166852)
			(xy 180.623583 -402.159153) (xy 180.609494 -402.158708) (xy 180.44414 -402.158708) (xy 180.418159 -402.158211)
			(xy 180.366841 -402.15005) (xy 180.317434 -402.133955) (xy 180.271156 -402.110322) (xy 180.22915 -402.079735)
			(xy 180.21046 -402.06168) (xy 179.271168 -401.122388) (xy 179.253153 -401.103667) (xy 179.222596 -401.061653)
			(xy 179.198978 -401.015381) (xy 179.182881 -400.965986) (xy 179.1747 -400.914683) (xy 179.17414 -400.888708)
			(xy 179.17414 -398.531334) (xy 178.854354 -398.211548) (xy 177.919126 -398.211548) (xy 176.79924 -399.331434)
			(xy 176.79924 -402.255482) (xy 177.95443 -402.255482) (xy 177.958501 -402.19986) (xy 177.970627 -402.145423)
			(xy 177.99055 -402.093332) (xy 178.017846 -402.044697) (xy 178.051932 -402.000554) (xy 178.092081 -401.961845)
			(xy 178.137439 -401.929394) (xy 178.187039 -401.903893) (xy 178.239823 -401.885886) (xy 178.294666 -401.875756)
			(xy 178.3504 -401.873719) (xy 178.405837 -401.879819) (xy 178.459794 -401.893925) (xy 178.511123 -401.915737)
			(xy 178.558729 -401.944791) (xy 178.601597 -401.980466) (xy 178.638814 -402.022003) (xy 178.669587 -402.068516)
			(xy 178.693259 -402.119013) (xy 178.709327 -402.17242) (xy 178.717447 -402.227596) (xy 178.717956 -402.255482)
			(xy 178.717447 -402.283368) (xy 178.709327 -402.338544) (xy 178.693259 -402.391951) (xy 178.669587 -402.442448)
			(xy 178.638814 -402.488961) (xy 178.601597 -402.530498) (xy 178.558729 -402.566173) (xy 178.511123 -402.595227)
			(xy 178.459794 -402.617039) (xy 178.405837 -402.631145) (xy 178.3504 -402.637245) (xy 178.294666 -402.635208)
			(xy 178.239823 -402.625078) (xy 178.187039 -402.607071) (xy 178.137439 -402.58157) (xy 178.092081 -402.549119)
			(xy 178.051932 -402.51041) (xy 178.017846 -402.466267) (xy 177.99055 -402.417632) (xy 177.970627 -402.365541)
			(xy 177.958501 -402.311104) (xy 177.95443 -402.255482) (xy 176.79924 -402.255482) (xy 176.79924 -406.054814)
			(xy 176.871875 -406.127458) (xy 178.56022 -406.127458) (xy 178.564291 -406.071836) (xy 178.576417 -406.017399)
			(xy 178.59634 -405.965308) (xy 178.623636 -405.916673) (xy 178.657722 -405.87253) (xy 178.697871 -405.833821)
			(xy 178.743229 -405.80137) (xy 178.792829 -405.775869) (xy 178.845613 -405.757862) (xy 178.900456 -405.747732)
			(xy 178.95619 -405.745695) (xy 179.011627 -405.751795) (xy 179.065584 -405.765901) (xy 179.116913 -405.787713)
			(xy 179.164519 -405.816767) (xy 179.207387 -405.852442) (xy 179.244604 -405.893979) (xy 179.275377 -405.940492)
			(xy 179.299049 -405.990989) (xy 179.315117 -406.044396) (xy 179.323237 -406.099572) (xy 179.323746 -406.127458)
			(xy 179.323237 -406.155344) (xy 179.319704 -406.179349) (xy 181.425874 -406.179349) (xy 181.425874 -406.124851)
			(xy 181.433629 -406.070907) (xy 181.448982 -406.018616) (xy 181.471619 -405.969041) (xy 181.501081 -405.923193)
			(xy 181.536768 -405.882003) (xy 181.577953 -405.846311) (xy 181.623797 -405.816843) (xy 181.673369 -405.794199)
			(xy 181.725658 -405.77884) (xy 181.779601 -405.771077) (xy 181.80685 -405.770588) (xy 181.835046 -405.771058)
			(xy 181.890822 -405.779374) (xy 181.944769 -405.795802) (xy 181.995713 -405.819986) (xy 182.042546 -405.851399)
			(xy 182.08425 -405.889358) (xy 182.119917 -405.933038) (xy 182.148773 -405.981489) (xy 182.17019 -406.033656)
			(xy 182.177436 -406.06091) (xy 182.181212 -406.074447) (xy 182.195036 -406.098903) (xy 182.215011 -406.118655)
			(xy 182.23962 -406.132203) (xy 182.266993 -406.138518) (xy 182.29505 -406.137121) (xy 182.3085 -406.133046)
			(xy 182.338106 -406.123683) (xy 182.399375 -406.113607) (xy 182.43042 -406.11298) (xy 182.457708 -406.113458)
			(xy 182.511729 -406.121226) (xy 182.56409 -406.136614) (xy 182.613724 -406.159309) (xy 182.636922 -406.173686)
			(xy 182.649389 -406.18114) (xy 182.677243 -406.189344) (xy 182.706279 -406.189384) (xy 182.734154 -406.181257)
			(xy 182.758619 -406.165618) (xy 182.777699 -406.14373) (xy 182.784242 -406.13076) (xy 182.795994 -406.106252)
			(xy 182.825496 -406.060601) (xy 182.861179 -406.019601) (xy 182.902321 -405.984082) (xy 182.948089 -405.954762)
			(xy 182.997555 -405.932237) (xy 183.049718 -405.916961) (xy 183.103521 -405.909245) (xy 183.130698 -405.908764)
			(xy 183.157949 -405.909283) (xy 183.211896 -405.917039) (xy 183.26419 -405.932394) (xy 183.313767 -405.955035)
			(xy 183.359617 -405.984501) (xy 183.394448 -406.014682) (xy 184.04535 -406.014682) (xy 184.049421 -405.95906)
			(xy 184.061547 -405.904623) (xy 184.08147 -405.852532) (xy 184.108766 -405.803897) (xy 184.142852 -405.759754)
			(xy 184.183001 -405.721045) (xy 184.228359 -405.688594) (xy 184.277959 -405.663093) (xy 184.330743 -405.645086)
			(xy 184.385586 -405.634956) (xy 184.44132 -405.632919) (xy 184.496757 -405.639019) (xy 184.550714 -405.653125)
			(xy 184.602043 -405.674937) (xy 184.649649 -405.703991) (xy 184.692517 -405.739666) (xy 184.729734 -405.781203)
			(xy 184.760507 -405.827716) (xy 184.784179 -405.878213) (xy 184.800247 -405.93162) (xy 184.808367 -405.986796)
			(xy 184.808876 -406.014682) (xy 184.808367 -406.042568) (xy 184.800247 -406.097744) (xy 184.784179 -406.151151)
			(xy 184.760507 -406.201648) (xy 184.729734 -406.248161) (xy 184.692517 -406.289698) (xy 184.649649 -406.325373)
			(xy 184.602043 -406.354427) (xy 184.550714 -406.376239) (xy 184.496757 -406.390345) (xy 184.44132 -406.396445)
			(xy 184.385586 -406.394408) (xy 184.330743 -406.384278) (xy 184.277959 -406.366271) (xy 184.228359 -406.34077)
			(xy 184.183001 -406.308319) (xy 184.142852 -406.26961) (xy 184.108766 -406.225467) (xy 184.08147 -406.176832)
			(xy 184.061547 -406.124741) (xy 184.049421 -406.070304) (xy 184.04535 -406.014682) (xy 183.394448 -406.014682)
			(xy 183.400807 -406.020192) (xy 183.436498 -406.061381) (xy 183.465964 -406.107231) (xy 183.488605 -406.156808)
			(xy 183.50396 -406.209102) (xy 183.511717 -406.263049) (xy 183.511717 -406.317551) (xy 183.50396 -406.371498)
			(xy 183.488605 -406.423792) (xy 183.465964 -406.473369) (xy 183.436498 -406.519219) (xy 183.400807 -406.560408)
			(xy 183.359617 -406.596099) (xy 183.313767 -406.625565) (xy 183.26419 -406.648206) (xy 183.211896 -406.663561)
			(xy 183.157949 -406.671317) (xy 183.130698 -406.67178) (xy 183.10341 -406.671299) (xy 183.049389 -406.663533)
			(xy 182.997028 -406.648146) (xy 182.947394 -406.625451) (xy 182.924196 -406.611074) (xy 182.911729 -406.603615)
			(xy 182.883875 -406.595401) (xy 182.854835 -406.595356) (xy 182.826956 -406.603484) (xy 182.80249 -406.619129)
			(xy 182.783415 -406.641026) (xy 182.776876 -406.654) (xy 182.765091 -406.678492) (xy 182.735596 -406.724143)
			(xy 182.699918 -406.765145) (xy 182.658781 -406.800667) (xy 182.613018 -406.829988) (xy 182.563555 -406.852517)
			(xy 182.511396 -406.867795) (xy 182.457596 -406.875513) (xy 182.43042 -406.875996) (xy 182.402225 -406.875475)
			(xy 182.346451 -406.867169) (xy 182.292505 -406.850749) (xy 182.241561 -406.826573) (xy 182.194727 -406.795167)
			(xy 182.153022 -406.757213) (xy 182.117353 -406.713538) (xy 182.088497 -406.665091) (xy 182.06708 -406.612926)
			(xy 182.059834 -406.585674) (xy 182.056103 -406.572122) (xy 182.04227 -406.547664) (xy 182.022285 -406.527912)
			(xy 181.997667 -406.514366) (xy 181.970286 -406.508055) (xy 181.942222 -406.509459) (xy 181.92877 -406.513538)
			(xy 181.899159 -406.522884) (xy 181.837894 -406.532971) (xy 181.80685 -406.533604) (xy 181.779601 -406.533123)
			(xy 181.725658 -406.52536) (xy 181.673369 -406.510001) (xy 181.623797 -406.487357) (xy 181.577953 -406.457889)
			(xy 181.536768 -406.422197) (xy 181.501081 -406.381007) (xy 181.471619 -406.335159) (xy 181.448982 -406.285584)
			(xy 181.433629 -406.233293) (xy 181.425874 -406.179349) (xy 179.319704 -406.179349) (xy 179.315117 -406.21052)
			(xy 179.299049 -406.263927) (xy 179.275377 -406.314424) (xy 179.244604 -406.360937) (xy 179.207387 -406.402474)
			(xy 179.164519 -406.438149) (xy 179.116913 -406.467203) (xy 179.065584 -406.489015) (xy 179.011627 -406.503121)
			(xy 178.95619 -406.509221) (xy 178.900456 -406.507184) (xy 178.845613 -406.497054) (xy 178.792829 -406.479047)
			(xy 178.743229 -406.453546) (xy 178.697871 -406.421095) (xy 178.657722 -406.382386) (xy 178.623636 -406.338243)
			(xy 178.59634 -406.289608) (xy 178.576417 -406.237517) (xy 178.564291 -406.18308) (xy 178.56022 -406.127458)
			(xy 176.871875 -406.127458) (xy 177.476318 -406.731978) (xy 180.74589 -406.731978) (xy 180.749961 -406.676356)
			(xy 180.762087 -406.621919) (xy 180.78201 -406.569828) (xy 180.809306 -406.521193) (xy 180.843392 -406.47705)
			(xy 180.883541 -406.438341) (xy 180.928899 -406.40589) (xy 180.978499 -406.380389) (xy 181.031283 -406.362382)
			(xy 181.086126 -406.352252) (xy 181.14186 -406.350215) (xy 181.197297 -406.356315) (xy 181.251254 -406.370421)
			(xy 181.302583 -406.392233) (xy 181.350189 -406.421287) (xy 181.393057 -406.456962) (xy 181.430274 -406.498499)
			(xy 181.461047 -406.545012) (xy 181.484719 -406.595509) (xy 181.500787 -406.648916) (xy 181.508907 -406.704092)
			(xy 181.509416 -406.731978) (xy 181.508907 -406.759864) (xy 181.500787 -406.81504) (xy 181.484719 -406.868447)
			(xy 181.461047 -406.918944) (xy 181.430274 -406.965457) (xy 181.393057 -407.006994) (xy 181.35391 -407.039572)
			(xy 184.79719 -407.039572) (xy 184.801261 -406.98395) (xy 184.813387 -406.929513) (xy 184.83331 -406.877422)
			(xy 184.860606 -406.828787) (xy 184.894692 -406.784644) (xy 184.934841 -406.745935) (xy 184.980199 -406.713484)
			(xy 185.029799 -406.687983) (xy 185.082583 -406.669976) (xy 185.137426 -406.659846) (xy 185.19316 -406.657809)
			(xy 185.248597 -406.663909) (xy 185.302554 -406.678015) (xy 185.353883 -406.699827) (xy 185.401489 -406.728881)
			(xy 185.444357 -406.764556) (xy 185.481574 -406.806093) (xy 185.512347 -406.852606) (xy 185.536019 -406.903103)
			(xy 185.552087 -406.95651) (xy 185.560207 -407.011686) (xy 185.560716 -407.039572) (xy 185.560207 -407.067458)
			(xy 185.552087 -407.122634) (xy 185.536019 -407.176041) (xy 185.512347 -407.226538) (xy 185.481574 -407.273051)
			(xy 185.444357 -407.314588) (xy 185.401489 -407.350263) (xy 185.353883 -407.379317) (xy 185.302554 -407.401129)
			(xy 185.248597 -407.415235) (xy 185.19316 -407.421335) (xy 185.137426 -407.419298) (xy 185.082583 -407.409168)
			(xy 185.029799 -407.391161) (xy 184.980199 -407.36566) (xy 184.934841 -407.333209) (xy 184.894692 -407.2945)
			(xy 184.860606 -407.250357) (xy 184.83331 -407.201722) (xy 184.813387 -407.149631) (xy 184.801261 -407.095194)
			(xy 184.79719 -407.039572) (xy 181.35391 -407.039572) (xy 181.350189 -407.042669) (xy 181.302583 -407.071723)
			(xy 181.251254 -407.093535) (xy 181.197297 -407.107641) (xy 181.14186 -407.113741) (xy 181.086126 -407.111704)
			(xy 181.031283 -407.101574) (xy 180.978499 -407.083567) (xy 180.928899 -407.058066) (xy 180.883541 -407.025615)
			(xy 180.843392 -406.986906) (xy 180.809306 -406.942763) (xy 180.78201 -406.894128) (xy 180.762087 -406.842037)
			(xy 180.749961 -406.7876) (xy 180.74589 -406.731978) (xy 177.476318 -406.731978) (xy 178.792632 -408.04846)
			(xy 180.32984 -408.04846) (xy 180.917596 -408.636216) (xy 181.827678 -408.636216) (xy 181.851248 -408.621141)
			(xy 181.901869 -408.597313) (xy 181.955429 -408.581141) (xy 182.010778 -408.572971) (xy 182.038752 -408.572462)
			(xy 182.066008 -408.572922) (xy 182.119966 -408.580673) (xy 182.172271 -408.596024) (xy 182.221859 -408.618664)
			(xy 182.267721 -408.64813) (xy 182.308921 -408.683823) (xy 182.344623 -408.725017) (xy 182.374099 -408.770872)
			(xy 182.396748 -408.820456) (xy 182.412111 -408.872758) (xy 182.419873 -408.926714) (xy 182.42026 -408.95397)
			(xy 182.41899 -408.984196) (xy 182.41833 -408.998473) (xy 182.424022 -409.02647) (xy 182.437237 -409.051799)
			(xy 182.456943 -409.072484) (xy 182.481602 -409.08691) (xy 182.509291 -409.093951) (xy 182.537846 -409.093057)
			(xy 182.551578 -409.089098) (xy 182.580079 -409.080459) (xy 182.638897 -409.071138) (xy 182.668672 -409.070556)
			(xy 182.697708 -409.071097) (xy 182.755109 -409.079896) (xy 182.782972 -409.088082) (xy 182.797441 -409.092081)
			(xy 182.827443 -409.092395) (xy 182.856243 -409.083979) (xy 182.881355 -409.067559) (xy 182.900613 -409.04455)
			(xy 182.906924 -409.030932) (xy 182.918256 -409.005443) (xy 182.947276 -408.957806) (xy 182.982929 -408.914907)
			(xy 183.024454 -408.877662) (xy 183.070962 -408.846866) (xy 183.121462 -408.823177) (xy 183.174876 -408.8071)
			(xy 183.230062 -408.798978) (xy 183.257952 -408.798522) (xy 183.286547 -408.799029) (xy 183.343097 -408.807558)
			(xy 183.39774 -408.824434) (xy 183.449251 -408.849278) (xy 183.496477 -408.881533) (xy 183.538359 -408.920475)
			(xy 183.573958 -408.965234) (xy 183.602478 -409.014805) (xy 183.623278 -409.068078) (xy 183.635892 -409.123859)
			(xy 183.638444 -409.152344) (xy 183.639852 -409.165671) (xy 183.648737 -409.190945) (xy 183.663883 -409.213043)
			(xy 183.684251 -409.230447) (xy 183.708441 -409.241961) (xy 183.734791 -409.246794) (xy 183.748172 -409.24607)
			(xy 183.779668 -409.2448) (xy 183.808644 -409.245336) (xy 183.86593 -409.254097) (xy 183.921232 -409.27142)
			(xy 183.973278 -409.296909) (xy 184.02087 -409.329976) (xy 184.062913 -409.36986) (xy 184.09844 -409.415645)
			(xy 184.126634 -409.466276) (xy 184.146846 -409.520589) (xy 184.158611 -409.577334) (xy 184.160668 -409.606242)
			(xy 184.162022 -409.621305) (xy 184.172384 -409.6497) (xy 184.190589 -409.673831) (xy 184.215047 -409.691592)
			(xy 184.243627 -409.701435) (xy 184.258712 -409.702508) (xy 184.285354 -409.703841) (xy 184.337901 -409.713028)
			(xy 184.388656 -409.729446) (xy 184.436629 -409.752774) (xy 184.480884 -409.782558) (xy 184.520559 -409.818216)
			(xy 184.554879 -409.859053) (xy 184.583176 -409.904274) (xy 184.604897 -409.952995) (xy 184.61962 -410.004267)
			(xy 184.627056 -410.05709) (xy 184.62752 -410.083762) (xy 184.62706 -410.111017) (xy 184.619307 -410.164973)
			(xy 184.603955 -410.217276) (xy 184.581314 -410.266862) (xy 184.551848 -410.31272) (xy 184.516154 -410.353919)
			(xy 184.47496 -410.389618) (xy 184.429106 -410.41909) (xy 184.379523 -410.441737) (xy 184.327222 -410.457097)
			(xy 184.273267 -410.464856) (xy 184.246012 -410.46527) (xy 184.217035 -410.464732) (xy 184.159748 -410.45597)
			(xy 184.104444 -410.438646) (xy 184.052396 -410.413157) (xy 184.004802 -410.380091) (xy 183.962755 -410.340208)
			(xy 183.927222 -410.294425) (xy 183.899022 -410.243796) (xy 183.878802 -410.189484) (xy 183.867028 -410.132739)
			(xy 183.865012 -410.103828) (xy 183.863653 -410.088769) (xy 183.853286 -410.060384) (xy 183.83508 -410.036264)
			(xy 183.810623 -410.018513) (xy 183.782048 -410.00868) (xy 183.766968 -410.007562) (xy 183.739045 -410.006141)
			(xy 183.684036 -409.996141) (xy 183.631075 -409.97822) (xy 183.581297 -409.952763) (xy 183.535766 -409.920315)
			(xy 183.495457 -409.88157) (xy 183.461234 -409.837357) (xy 183.43383 -409.788623) (xy 183.41383 -409.736413)
			(xy 183.401663 -409.681842) (xy 183.399176 -409.653994) (xy 183.397761 -409.640672) (xy 183.388867 -409.615409)
			(xy 183.373719 -409.593322) (xy 183.353354 -409.575927) (xy 183.32917 -409.564417) (xy 183.302828 -409.559582)
			(xy 183.289448 -409.560268) (xy 183.257952 -409.561538) (xy 183.228917 -409.560991) (xy 183.171519 -409.552182)
			(xy 183.143652 -409.544012) (xy 183.129187 -409.540025) (xy 183.0992 -409.53973) (xy 183.070419 -409.548157)
			(xy 183.045327 -409.56458) (xy 183.026086 -409.587584) (xy 183.0197 -409.601162) (xy 183.014501 -409.613129)
			(xy 183.002683 -409.636392) (xy 182.996078 -409.647644) (xy 182.988563 -409.661393) (xy 182.981431 -409.691887)
			(xy 182.983843 -409.723111) (xy 182.995573 -409.752148) (xy 183.015525 -409.776286) (xy 183.028336 -409.785312)
			(xy 183.050947 -409.80045) (xy 183.092037 -409.836119) (xy 183.127636 -409.877269) (xy 183.15702 -409.923065)
			(xy 183.179592 -409.972575) (xy 183.194891 -410.024792) (xy 183.202608 -410.078654) (xy 183.203088 -410.10586)
			(xy 183.202615 -410.132968) (xy 183.194944 -410.186639) (xy 183.179753 -410.238684) (xy 183.157346 -410.288053)
			(xy 183.128174 -410.333753) (xy 183.092827 -410.374863) (xy 183.052015 -410.410553) (xy 183.006562 -410.440107)
			(xy 182.957382 -410.462927) (xy 182.905466 -410.478554) (xy 182.87873 -410.48305) (xy 182.862474 -410.48559)
			(xy 182.814722 -410.533342) (xy 182.896002 -410.614622) (xy 191.024002 -410.614622) (xy 193.7639 -413.35452)
			(xy 232.87228 -413.35452)
		)
		(stroke
			(width 0)
			(type solid)
		)
		(fill yes)
		(layer "In4.Cu")
		(net "AGND_HSC")
	)
	(gr_poly
		(pts
			(xy 47.239428 -180.800502) (xy 55.908448 -180.800502) (xy 59.39663 -177.31232) (xy 59.39663 -144.272762)
			(xy 42.46118 -127.337312) (xy 42.451054 -127.327883) (xy 42.426935 -127.314347) (xy 42.400069 -127.307782)
			(xy 42.372426 -127.308672) (xy 42.346036 -127.31695) (xy 42.322839 -127.33201) (xy 42.304535 -127.352744)
			(xy 42.298112 -127.364998) (xy 42.286047 -127.388832) (xy 42.25625 -127.433169) (xy 42.220567 -127.472922)
			(xy 42.179692 -127.507315) (xy 42.134424 -127.535678) (xy 42.085645 -127.557456) (xy 42.034308 -127.572225)
			(xy 41.981413 -127.579696) (xy 41.954704 -127.580136) (xy 41.927452 -127.579651) (xy 41.873502 -127.571895)
			(xy 41.821205 -127.55654) (xy 41.771626 -127.5339) (xy 41.725773 -127.504434) (xy 41.68458 -127.468743)
			(xy 41.648885 -127.427553) (xy 41.619416 -127.381702) (xy 41.596771 -127.332125) (xy 41.581412 -127.279829)
			(xy 41.573652 -127.22588) (xy 41.573196 -127.198628) (xy 41.573718 -127.169846) (xy 41.582362 -127.112934)
			(xy 41.599458 -127.057968) (xy 41.624619 -127.006193) (xy 41.657272 -126.958786) (xy 41.696677 -126.916823)
			(xy 41.741939 -126.881257) (xy 41.766744 -126.86665) (xy 41.767252 -126.866396) (xy 41.810432 -126.840488)
			(xy 41.820665 -126.831068) (xy 41.836002 -126.807876) (xy 41.844511 -126.781406) (xy 41.845559 -126.753622)
			(xy 41.839071 -126.726586) (xy 41.825526 -126.702304) (xy 41.81602 -126.692152) (xy 37.664644 -122.540776)
			(xy 37.540946 -122.664474) (xy 37.51072 -122.694446) (xy 37.486844 -122.718322) (xy 37.486844 -124.075698)
			(xy 37.74643 -124.075698) (xy 37.750503 -124.020039) (xy 37.762638 -123.965566) (xy 37.782574 -123.91344)
			(xy 37.809888 -123.864772) (xy 37.843996 -123.8206) (xy 37.884173 -123.781865) (xy 37.929561 -123.749393)
			(xy 37.979193 -123.723875) (xy 38.032013 -123.705856) (xy 38.086892 -123.695719) (xy 38.142663 -123.693681)
			(xy 38.198137 -123.699784) (xy 38.25213 -123.7139) (xy 38.303493 -123.735727) (xy 38.351131 -123.7648)
			(xy 38.394027 -123.800499) (xy 38.431269 -123.842063) (xy 38.462063 -123.888607) (xy 38.485751 -123.939138)
			(xy 38.501829 -123.99258) (xy 38.509955 -124.047794) (xy 38.510464 -124.075698) (xy 38.509955 -124.103602)
			(xy 38.501829 -124.158816) (xy 38.485751 -124.212258) (xy 38.462063 -124.262789) (xy 38.431269 -124.309333)
			(xy 38.394027 -124.350897) (xy 38.351131 -124.386596) (xy 38.303493 -124.415669) (xy 38.25213 -124.437496)
			(xy 38.198137 -124.451612) (xy 38.142663 -124.457715) (xy 38.086892 -124.455677) (xy 38.032013 -124.44554)
			(xy 37.979193 -124.427521) (xy 37.929561 -124.402003) (xy 37.884173 -124.369531) (xy 37.843996 -124.330796)
			(xy 37.809888 -124.286624) (xy 37.782574 -124.237956) (xy 37.762638 -124.18583) (xy 37.750503 -124.131357)
			(xy 37.74643 -124.075698) (xy 37.486844 -124.075698) (xy 37.486844 -124.74067) (xy 37.930582 -125.184408)
			(xy 37.996114 -125.184408) (xy 38.025241 -125.185631) (xy 38.082639 -125.195818) (xy 38.137822 -125.21461)
			(xy 38.189508 -125.241571) (xy 38.236496 -125.276073) (xy 38.277695 -125.317316) (xy 38.312147 -125.364342)
			(xy 38.339052 -125.416057) (xy 38.34892 -125.443488) (xy 38.352476 -125.45441) (xy 38.352984 -125.456188)
			(xy 38.356794 -125.469302) (xy 38.370331 -125.493009) (xy 38.389667 -125.51228) (xy 38.413419 -125.525736)
			(xy 38.439889 -125.532414) (xy 38.467182 -125.531838) (xy 38.493346 -125.524048) (xy 38.50513 -125.517148)
			(xy 38.529581 -125.500334) (xy 38.582591 -125.473671) (xy 38.639088 -125.455529) (xy 38.697711 -125.446346)
			(xy 38.72738 -125.445774) (xy 38.754635 -125.446236) (xy 38.808591 -125.453991) (xy 38.860894 -125.469346)
			(xy 38.910479 -125.491988) (xy 38.956336 -125.521457) (xy 38.997534 -125.557152) (xy 39.033231 -125.598347)
			(xy 39.062702 -125.644204) (xy 39.085347 -125.693788) (xy 39.100705 -125.74609) (xy 39.108463 -125.800045)
			(xy 39.108463 -125.854555) (xy 39.100705 -125.90851) (xy 39.085347 -125.960812) (xy 39.062702 -126.010396)
			(xy 39.033231 -126.056253) (xy 38.997534 -126.097448) (xy 38.956336 -126.133143) (xy 38.910479 -126.162612)
			(xy 38.860894 -126.185254) (xy 38.808591 -126.200609) (xy 38.754635 -126.208364) (xy 38.72738 -126.20879)
			(xy 38.699809 -126.208304) (xy 38.645242 -126.200368) (xy 38.592385 -126.184665) (xy 38.542335 -126.161522)
			(xy 38.496136 -126.131419) (xy 38.454748 -126.094983) (xy 38.419033 -126.052972) (xy 38.389732 -126.00626)
			(xy 38.367456 -125.955819) (xy 38.359588 -125.92939) (xy 38.354952 -125.916953) (xy 38.340286 -125.894844)
			(xy 38.320405 -125.877275) (xy 38.29666 -125.865439) (xy 38.270663 -125.86014) (xy 38.24418 -125.861738)
			(xy 38.219008 -125.870124) (xy 38.207696 -125.877066) (xy 38.199822 -125.88367) (xy 38.177724 -125.89637)
			(xy 38.161468 -125.905006) (xy 38.143434 -125.913642) (xy 38.142418 -125.91415) (xy 38.14064 -125.914912)
			(xy 38.125324 -125.921446) (xy 38.093782 -125.932128) (xy 38.077648 -125.936248) (xy 38.062916 -125.939804)
			(xy 37.466524 -126.536196) (xy 37.466524 -127.798322) (xy 40.5798 -127.798322) (xy 40.583871 -127.7427)
			(xy 40.595997 -127.688263) (xy 40.61592 -127.636172) (xy 40.643216 -127.587537) (xy 40.677302 -127.543394)
			(xy 40.717451 -127.504685) (xy 40.762809 -127.472234) (xy 40.812409 -127.446733) (xy 40.865193 -127.428726)
			(xy 40.920036 -127.418596) (xy 40.97577 -127.416559) (xy 41.031207 -127.422659) (xy 41.085164 -127.436765)
			(xy 41.136493 -127.458577) (xy 41.184099 -127.487631) (xy 41.226967 -127.523306) (xy 41.264184 -127.564843)
			(xy 41.294957 -127.611356) (xy 41.318629 -127.661853) (xy 41.334697 -127.71526) (xy 41.342817 -127.770436)
			(xy 41.343326 -127.798322) (xy 41.342817 -127.826208) (xy 41.334697 -127.881384) (xy 41.318629 -127.934791)
			(xy 41.294957 -127.985288) (xy 41.264184 -128.031801) (xy 41.226967 -128.073338) (xy 41.184099 -128.109013)
			(xy 41.136493 -128.138067) (xy 41.085164 -128.159879) (xy 41.031207 -128.173985) (xy 40.97577 -128.180085)
			(xy 40.920036 -128.178048) (xy 40.865193 -128.167918) (xy 40.812409 -128.149911) (xy 40.762809 -128.12441)
			(xy 40.717451 -128.091959) (xy 40.677302 -128.05325) (xy 40.643216 -128.009107) (xy 40.61592 -127.960472)
			(xy 40.595997 -127.908381) (xy 40.583871 -127.853944) (xy 40.5798 -127.798322) (xy 37.466524 -127.798322)
			(xy 37.466524 -128.081532) (xy 37.779706 -128.394714) (xy 37.81171 -128.380744) (xy 37.836101 -128.370473)
			(xy 37.887008 -128.356) (xy 37.939426 -128.348699) (xy 37.965888 -128.348232) (xy 37.99314 -128.348695)
			(xy 38.04709 -128.35645) (xy 38.099387 -128.371806) (xy 38.148967 -128.394448) (xy 38.194818 -128.423916)
			(xy 38.236009 -128.459611) (xy 38.2717 -128.500804) (xy 38.301165 -128.546658) (xy 38.323804 -128.596239)
			(xy 38.339156 -128.648537) (xy 38.346907 -128.702488) (xy 38.347396 -128.72974) (xy 38.346878 -128.758044)
			(xy 38.338507 -128.81403) (xy 38.321955 -128.868164) (xy 38.297586 -128.919258) (xy 38.265934 -128.96619)
			(xy 38.227694 -129.00793) (xy 38.183706 -129.04356) (xy 38.134936 -129.0723) (xy 38.082454 -129.093517)
			(xy 38.055042 -129.10058) (xy 38.041072 -129.104136) (xy 37.97681 -129.168398) (xy 37.750496 -129.394458)
			(xy 37.750496 -129.553208) (xy 40.257982 -129.553208) (xy 40.262053 -129.497586) (xy 40.274179 -129.443149)
			(xy 40.294102 -129.391058) (xy 40.321398 -129.342423) (xy 40.355484 -129.29828) (xy 40.395633 -129.259571)
			(xy 40.440991 -129.22712) (xy 40.490591 -129.201619) (xy 40.543375 -129.183612) (xy 40.598218 -129.173482)
			(xy 40.653952 -129.171445) (xy 40.709389 -129.177545) (xy 40.763346 -129.191651) (xy 40.814675 -129.213463)
			(xy 40.862281 -129.242517) (xy 40.905149 -129.278192) (xy 40.942366 -129.319729) (xy 40.973139 -129.366242)
			(xy 40.996811 -129.416739) (xy 41.012879 -129.470146) (xy 41.020999 -129.525322) (xy 41.021508 -129.553208)
			(xy 41.020999 -129.581094) (xy 41.012879 -129.63627) (xy 40.996811 -129.689677) (xy 40.973139 -129.740174)
			(xy 40.942366 -129.786687) (xy 40.905149 -129.828224) (xy 40.862281 -129.863899) (xy 40.814675 -129.892953)
			(xy 40.763346 -129.914765) (xy 40.709389 -129.928871) (xy 40.653952 -129.934971) (xy 40.598218 -129.932934)
			(xy 40.543375 -129.922804) (xy 40.490591 -129.904797) (xy 40.440991 -129.879296) (xy 40.395633 -129.846845)
			(xy 40.355484 -129.808136) (xy 40.321398 -129.763993) (xy 40.294102 -129.715358) (xy 40.274179 -129.663267)
			(xy 40.262053 -129.60883) (xy 40.257982 -129.553208) (xy 37.750496 -129.553208) (xy 37.750496 -130.36042)
			(xy 37.807646 -130.417316) (xy 37.834316 -130.407156) (xy 37.835078 -130.407156) (xy 37.839396 -130.405378)
			(xy 37.855508 -130.399378) (xy 37.888579 -130.389963) (xy 37.905436 -130.386582) (xy 37.920251 -130.38237)
			(xy 37.946577 -130.36641) (xy 37.966947 -130.343326) (xy 37.979509 -130.315219) (xy 37.983118 -130.284645)
			(xy 37.977448 -130.254385) (xy 37.970714 -130.240532) (xy 37.968936 -130.237484) (xy 37.968936 -130.236976)
			(xy 37.968682 -130.236976) (xy 37.953897 -130.208649) (xy 37.932947 -130.148288) (xy 37.922339 -130.085281)
			(xy 37.921692 -130.053334) (xy 37.921692 -130.045968) (xy 37.922672 -130.019061) (xy 37.931266 -129.96591)
			(xy 37.947248 -129.914495) (xy 37.9703 -129.865838) (xy 37.999965 -129.820906) (xy 38.035654 -129.780591)
			(xy 38.076656 -129.745695) (xy 38.122157 -129.716911) (xy 38.171254 -129.694811) (xy 38.222971 -129.679834)
			(xy 38.276279 -129.672277) (xy 38.3032 -129.671826) (xy 38.330936 -129.672331) (xy 38.385821 -129.680375)
			(xy 38.438964 -129.69628) (xy 38.489244 -129.71971) (xy 38.535603 -129.750173) (xy 38.577064 -129.787025)
			(xy 38.612753 -129.829491) (xy 38.641919 -129.876676) (xy 38.663947 -129.927587) (xy 38.678374 -129.98115)
			(xy 38.682168 -130.00863) (xy 38.683692 -130.022346) (xy 38.685445 -130.049954) (xy 38.681926 -130.105162)
			(xy 38.670477 -130.159283) (xy 38.651339 -130.211186) (xy 38.624911 -130.259785) (xy 38.591748 -130.304061)
			(xy 38.552542 -130.343088) (xy 38.508115 -130.37605) (xy 38.459397 -130.402255) (xy 38.407407 -130.421157)
			(xy 38.380416 -130.427222) (xy 38.367283 -130.429976) (xy 38.343015 -130.441406) (xy 38.322569 -130.458771)
			(xy 38.307361 -130.48087) (xy 38.298446 -130.50617) (xy 38.29644 -130.53292) (xy 38.301483 -130.559267)
			(xy 38.30701 -130.571494) (xy 38.319068 -130.593287) (xy 38.338059 -130.639331) (xy 38.350903 -130.687453)
			(xy 38.357384 -130.736837) (xy 38.35781 -130.76174) (xy 38.357432 -130.782822) (xy 38.66718 -130.782822)
			(xy 38.671251 -130.7272) (xy 38.683377 -130.672763) (xy 38.7033 -130.620672) (xy 38.730596 -130.572037)
			(xy 38.764682 -130.527894) (xy 38.804831 -130.489185) (xy 38.850189 -130.456734) (xy 38.899789 -130.431233)
			(xy 38.952573 -130.413226) (xy 39.007416 -130.403096) (xy 39.06315 -130.401059) (xy 39.118587 -130.407159)
			(xy 39.172544 -130.421265) (xy 39.223873 -130.443077) (xy 39.271479 -130.472131) (xy 39.314347 -130.507806)
			(xy 39.351564 -130.549343) (xy 39.382337 -130.595856) (xy 39.406009 -130.646353) (xy 39.422077 -130.69976)
			(xy 39.430197 -130.754936) (xy 39.430706 -130.782822) (xy 39.430197 -130.810708) (xy 39.422077 -130.865884)
			(xy 39.406009 -130.919291) (xy 39.382337 -130.969788) (xy 39.351564 -131.016301) (xy 39.314347 -131.057838)
			(xy 39.271479 -131.093513) (xy 39.223873 -131.122567) (xy 39.172544 -131.144379) (xy 39.118587 -131.158485)
			(xy 39.06315 -131.164585) (xy 39.007416 -131.162548) (xy 38.952573 -131.152418) (xy 38.899789 -131.134411)
			(xy 38.850189 -131.10891) (xy 38.804831 -131.076459) (xy 38.764682 -131.03775) (xy 38.730596 -130.993607)
			(xy 38.7033 -130.944972) (xy 38.683377 -130.892881) (xy 38.671251 -130.838444) (xy 38.66718 -130.782822)
			(xy 38.357432 -130.782822) (xy 38.357321 -130.789009) (xy 38.349555 -130.842991) (xy 38.334187 -130.895318)
			(xy 38.311529 -130.944926) (xy 38.282043 -130.990806) (xy 38.246328 -131.032022) (xy 38.205112 -131.067738)
			(xy 38.159233 -131.097225) (xy 38.109626 -131.119884) (xy 38.057298 -131.135253) (xy 38.003317 -131.14302)
			(xy 37.976048 -131.143502) (xy 37.975794 -131.143502) (xy 37.94454 -131.14279) (xy 37.88289 -131.132447)
			(xy 37.853112 -131.122928) (xy 37.833235 -131.115848) (xy 37.795049 -131.097896) (xy 37.776912 -131.087114)
			(xy 37.76472 -131.079748) (xy 37.702236 -131.079748) (xy 37.677254 -131.079232) (xy 37.627912 -131.071372)
			(xy 37.580403 -131.055903) (xy 37.535893 -131.033204) (xy 37.495474 -131.003832) (xy 37.477446 -130.98653)
			(xy 37.32149 -130.83032) (xy 37.207952 -130.716782) (xy 37.190665 -130.698785) (xy 37.16135 -130.658403)
			(xy 37.138703 -130.613938) (xy 37.123281 -130.56648) (xy 37.115462 -130.517196) (xy 37.114988 -130.492246)
			(xy 37.114988 -129.262632) (xy 37.115449 -129.23768) (xy 37.123251 -129.188389) (xy 37.138668 -129.140925)
			(xy 37.16132 -129.096457) (xy 37.190649 -129.056081) (xy 37.207952 -129.038096) (xy 37.36594 -128.880108)
			(xy 36.923726 -128.438148) (xy 36.906372 -128.420163) (xy 36.876971 -128.379751) (xy 36.854262 -128.335232)
			(xy 36.838807 -128.287706) (xy 36.830986 -128.238346) (xy 36.830508 -128.213358) (xy 36.830508 -126.40437)
			(xy 36.831021 -126.379387) (xy 36.838875 -126.330041) (xy 36.854339 -126.282528) (xy 36.877033 -126.238012)
			(xy 36.9064 -126.197586) (xy 36.923726 -126.17958) (xy 37.385498 -125.718062) (xy 36.835842 -125.168406)
			(xy 36.815106 -125.14683) (xy 36.779944 -125.098413) (xy 36.752783 -125.045095) (xy 36.734293 -124.988185)
			(xy 36.724927 -124.929085) (xy 36.724336 -124.899166) (xy 36.724336 -122.559826) (xy 36.72494 -122.529909)
			(xy 36.734323 -122.470814) (xy 36.752814 -122.413907) (xy 36.779962 -122.360585) (xy 36.8151 -122.312154)
			(xy 36.835842 -122.290586) (xy 37.125148 -122.00128) (xy 36.906708 -121.78284) (xy 35.536124 -121.78284)
			(xy 35.521111 -121.783372) (xy 35.492381 -121.792097) (xy 35.467429 -121.808799) (xy 35.448412 -121.832035)
			(xy 35.436974 -121.859797) (xy 35.434103 -121.889685) (xy 35.436556 -121.904506) (xy 35.437064 -121.906792)
			(xy 35.440354 -121.924646) (xy 35.443919 -121.960776) (xy 35.444176 -121.978928) (xy 35.444176 -121.981468)
			(xy 35.443621 -122.008672) (xy 35.435747 -122.06251) (xy 35.420304 -122.114682) (xy 35.397606 -122.164132)
			(xy 35.368112 -122.209855) (xy 35.332421 -122.250924) (xy 35.291257 -122.286505) (xy 35.245455 -122.315878)
			(xy 35.195946 -122.338445) (xy 35.143732 -122.353748) (xy 35.089873 -122.361479) (xy 35.035463 -122.361479)
			(xy 34.981604 -122.353748) (xy 34.92939 -122.338445) (xy 34.879881 -122.315878) (xy 34.834079 -122.286505)
			(xy 34.792915 -122.250924) (xy 34.757224 -122.209855) (xy 34.72773 -122.164132) (xy 34.705032 -122.114682)
			(xy 34.689589 -122.06251) (xy 34.681715 -122.008672) (xy 34.68116 -121.981468) (xy 34.68116 -121.980198)
			(xy 34.681386 -121.961729) (xy 34.68495 -121.924962) (xy 34.688272 -121.906792) (xy 34.68878 -121.904506)
			(xy 34.691211 -121.889692) (xy 34.688318 -121.859826) (xy 34.676872 -121.83209) (xy 34.657861 -121.808876)
			(xy 34.632924 -121.792188) (xy 34.604215 -121.783466) (xy 34.589212 -121.78284) (xy 34.213038 -121.78284)
			(xy 34.198023 -121.783371) (xy 34.169289 -121.792093) (xy 34.144334 -121.808794) (xy 34.125314 -121.832031)
			(xy 34.113874 -121.859796) (xy 34.111003 -121.889687) (xy 34.11347 -121.904506) (xy 34.113978 -121.906792)
			(xy 34.117268 -121.924646) (xy 34.120832 -121.960776) (xy 34.12109 -121.978928) (xy 34.12109 -121.981468)
			(xy 34.120535 -122.008672) (xy 34.112661 -122.06251) (xy 34.097218 -122.114682) (xy 34.07452 -122.164132)
			(xy 34.045026 -122.209855) (xy 34.009335 -122.250924) (xy 33.968171 -122.286505) (xy 33.922369 -122.315878)
			(xy 33.87286 -122.338445) (xy 33.820646 -122.353748) (xy 33.766787 -122.361479) (xy 33.712377 -122.361479)
			(xy 33.658518 -122.353748) (xy 33.606304 -122.338445) (xy 33.556795 -122.315878) (xy 33.510993 -122.286505)
			(xy 33.469829 -122.250924) (xy 33.434138 -122.209855) (xy 33.404644 -122.164132) (xy 33.381946 -122.114682)
			(xy 33.366503 -122.06251) (xy 33.358629 -122.008672) (xy 33.358074 -121.981468) (xy 33.358074 -121.980198)
			(xy 33.3583 -121.961729) (xy 33.361864 -121.924962) (xy 33.365186 -121.906792) (xy 33.365694 -121.904506)
			(xy 33.368125 -121.889691) (xy 33.365232 -121.859825) (xy 33.353786 -121.832087) (xy 33.334775 -121.808871)
			(xy 33.309839 -121.79218) (xy 33.281129 -121.783455) (xy 33.266126 -121.78284) (xy 28.434792 -121.78284)
			(xy 28.434792 -123.200414) (xy 29.125416 -123.200414) (xy 29.129487 -123.144792) (xy 29.141613 -123.090355)
			(xy 29.161536 -123.038264) (xy 29.188832 -122.989629) (xy 29.222918 -122.945486) (xy 29.263067 -122.906777)
			(xy 29.308425 -122.874326) (xy 29.358025 -122.848825) (xy 29.410809 -122.830818) (xy 29.465652 -122.820688)
			(xy 29.521386 -122.818651) (xy 29.576823 -122.824751) (xy 29.63078 -122.838857) (xy 29.682109 -122.860669)
			(xy 29.729715 -122.889723) (xy 29.772583 -122.925398) (xy 29.8098 -122.966935) (xy 29.840573 -123.013448)
			(xy 29.864245 -123.063945) (xy 29.880313 -123.117352) (xy 29.888433 -123.172528) (xy 29.888942 -123.200414)
			(xy 29.888433 -123.2283) (xy 29.880313 -123.283476) (xy 29.864245 -123.336883) (xy 29.840573 -123.38738)
			(xy 29.8098 -123.433893) (xy 29.772583 -123.47543) (xy 29.729715 -123.511105) (xy 29.682109 -123.540159)
			(xy 29.63078 -123.561971) (xy 29.576823 -123.576077) (xy 29.521386 -123.582177) (xy 29.465652 -123.58014)
			(xy 29.410809 -123.57001) (xy 29.358025 -123.552003) (xy 29.308425 -123.526502) (xy 29.263067 -123.494051)
			(xy 29.222918 -123.455342) (xy 29.188832 -123.411199) (xy 29.161536 -123.362564) (xy 29.141613 -123.310473)
			(xy 29.129487 -123.256036) (xy 29.125416 -123.200414) (xy 28.434792 -123.200414) (xy 28.434792 -123.630944)
			(xy 31.385762 -123.630944) (xy 31.389833 -123.575322) (xy 31.401959 -123.520885) (xy 31.421882 -123.468794)
			(xy 31.449178 -123.420159) (xy 31.483264 -123.376016) (xy 31.523413 -123.337307) (xy 31.568771 -123.304856)
			(xy 31.618371 -123.279355) (xy 31.671155 -123.261348) (xy 31.725998 -123.251218) (xy 31.781732 -123.249181)
			(xy 31.837169 -123.255281) (xy 31.891126 -123.269387) (xy 31.942455 -123.291199) (xy 31.990061 -123.320253)
			(xy 32.032929 -123.355928) (xy 32.070146 -123.397465) (xy 32.100919 -123.443978) (xy 32.124591 -123.494475)
			(xy 32.140659 -123.547882) (xy 32.148779 -123.603058) (xy 32.149288 -123.630944) (xy 32.148779 -123.65883)
			(xy 32.140659 -123.714006) (xy 32.124591 -123.767413) (xy 32.100919 -123.81791) (xy 32.070146 -123.864423)
			(xy 32.032929 -123.90596) (xy 32.031934 -123.906788) (xy 32.966912 -123.906788) (xy 32.970983 -123.851166)
			(xy 32.983109 -123.796729) (xy 33.003032 -123.744638) (xy 33.030328 -123.696003) (xy 33.064414 -123.65186)
			(xy 33.104563 -123.613151) (xy 33.149921 -123.5807) (xy 33.199521 -123.555199) (xy 33.252305 -123.537192)
			(xy 33.307148 -123.527062) (xy 33.362882 -123.525025) (xy 33.418319 -123.531125) (xy 33.472276 -123.545231)
			(xy 33.523605 -123.567043) (xy 33.571211 -123.596097) (xy 33.614079 -123.631772) (xy 33.651296 -123.673309)
			(xy 33.682069 -123.719822) (xy 33.705741 -123.770319) (xy 33.721809 -123.823726) (xy 33.729929 -123.878902)
			(xy 33.730118 -123.889262) (xy 33.909506 -123.889262) (xy 33.913577 -123.83364) (xy 33.925703 -123.779203)
			(xy 33.945626 -123.727112) (xy 33.972922 -123.678477) (xy 34.007008 -123.634334) (xy 34.047157 -123.595625)
			(xy 34.092515 -123.563174) (xy 34.142115 -123.537673) (xy 34.194899 -123.519666) (xy 34.249742 -123.509536)
			(xy 34.305476 -123.507499) (xy 34.360913 -123.513599) (xy 34.41487 -123.527705) (xy 34.466199 -123.549517)
			(xy 34.513805 -123.578571) (xy 34.556673 -123.614246) (xy 34.59389 -123.655783) (xy 34.624663 -123.702296)
			(xy 34.648335 -123.752793) (xy 34.664403 -123.8062) (xy 34.672523 -123.861376) (xy 34.673032 -123.889262)
			(xy 34.672523 -123.917148) (xy 34.664403 -123.972324) (xy 34.648335 -124.025731) (xy 34.624663 -124.076228)
			(xy 34.59389 -124.122741) (xy 34.556673 -124.164278) (xy 34.513805 -124.199953) (xy 34.466199 -124.229007)
			(xy 34.41487 -124.250819) (xy 34.360913 -124.264925) (xy 34.305476 -124.271025) (xy 34.249742 -124.268988)
			(xy 34.194899 -124.258858) (xy 34.142115 -124.240851) (xy 34.092515 -124.21535) (xy 34.047157 -124.182899)
			(xy 34.007008 -124.14419) (xy 33.972922 -124.100047) (xy 33.945626 -124.051412) (xy 33.925703 -123.999321)
			(xy 33.913577 -123.944884) (xy 33.909506 -123.889262) (xy 33.730118 -123.889262) (xy 33.730438 -123.906788)
			(xy 33.729929 -123.934674) (xy 33.721809 -123.98985) (xy 33.705741 -124.043257) (xy 33.682069 -124.093754)
			(xy 33.651296 -124.140267) (xy 33.614079 -124.181804) (xy 33.571211 -124.217479) (xy 33.523605 -124.246533)
			(xy 33.472276 -124.268345) (xy 33.418319 -124.282451) (xy 33.362882 -124.288551) (xy 33.307148 -124.286514)
			(xy 33.252305 -124.276384) (xy 33.199521 -124.258377) (xy 33.149921 -124.232876) (xy 33.104563 -124.200425)
			(xy 33.064414 -124.161716) (xy 33.030328 -124.117573) (xy 33.003032 -124.068938) (xy 32.983109 -124.016847)
			(xy 32.970983 -123.96241) (xy 32.966912 -123.906788) (xy 32.031934 -123.906788) (xy 31.990061 -123.941635)
			(xy 31.942455 -123.970689) (xy 31.891126 -123.992501) (xy 31.837169 -124.006607) (xy 31.781732 -124.012707)
			(xy 31.725998 -124.01067) (xy 31.671155 -124.00054) (xy 31.618371 -123.982533) (xy 31.568771 -123.957032)
			(xy 31.523413 -123.924581) (xy 31.483264 -123.885872) (xy 31.449178 -123.841729) (xy 31.421882 -123.793094)
			(xy 31.401959 -123.741003) (xy 31.389833 -123.686566) (xy 31.385762 -123.630944) (xy 28.434792 -123.630944)
			(xy 28.434792 -124.238004) (xy 28.328366 -124.34443) (xy 28.326588 -124.346208) (xy 28.326334 -124.346462)
			(xy 28.322778 -124.350272) (xy 27.748484 -124.924566) (xy 31.371284 -124.924566) (xy 31.375355 -124.868944)
			(xy 31.387481 -124.814507) (xy 31.407404 -124.762416) (xy 31.4347 -124.713781) (xy 31.468786 -124.669638)
			(xy 31.508935 -124.630929) (xy 31.554293 -124.598478) (xy 31.603893 -124.572977) (xy 31.656677 -124.55497)
			(xy 31.71152 -124.54484) (xy 31.767254 -124.542803) (xy 31.822691 -124.548903) (xy 31.876648 -124.563009)
			(xy 31.927977 -124.584821) (xy 31.975583 -124.613875) (xy 32.018451 -124.64955) (xy 32.055668 -124.691087)
			(xy 32.086441 -124.7376) (xy 32.110113 -124.788097) (xy 32.126181 -124.841504) (xy 32.134301 -124.89668)
			(xy 32.13481 -124.924566) (xy 32.134301 -124.952452) (xy 32.126181 -125.007628) (xy 32.110113 -125.061035)
			(xy 32.086441 -125.111532) (xy 32.055668 -125.158045) (xy 32.018451 -125.199582) (xy 31.975583 -125.235257)
			(xy 31.927977 -125.264311) (xy 31.876648 -125.286123) (xy 31.822691 -125.300229) (xy 31.767254 -125.306329)
			(xy 31.71152 -125.304292) (xy 31.656677 -125.294162) (xy 31.603893 -125.276155) (xy 31.554293 -125.250654)
			(xy 31.508935 -125.218203) (xy 31.468786 -125.179494) (xy 31.4347 -125.135351) (xy 31.407404 -125.086716)
			(xy 31.387481 -125.034625) (xy 31.375355 -124.980188) (xy 31.371284 -124.924566) (xy 27.748484 -124.924566)
			(xy 27.694128 -124.978922) (xy 27.684476 -124.98832) (xy 27.582622 -125.090174) (xy 27.427428 -125.090174)
			(xy 27.424634 -125.090428) (xy 26.650188 -125.090428) (xy 26.638504 -125.090682) (xy 26.63825 -125.090682)
			(xy 26.626058 -125.090174) (xy 26.480262 -125.090174) (xy 26.382218 -124.991876) (xy 26.381202 -124.99086)
			(xy 26.373636 -124.984022) (xy 26.359149 -124.969664) (xy 26.352246 -124.962158) (xy 26.35123 -124.960888)
			(xy 26.256996 -124.866908) (xy 26.256996 -124.721112) (xy 26.256488 -124.70892) (xy 26.256996 -124.696728)
			(xy 26.256996 -124.550932) (xy 26.35123 -124.456952) (xy 26.352246 -124.455682) (xy 26.359139 -124.448166)
			(xy 26.373624 -124.433805) (xy 26.381202 -124.42698) (xy 26.382218 -124.425964) (xy 26.480262 -124.327666)
			(xy 26.626058 -124.327666) (xy 26.63825 -124.327158) (xy 26.638504 -124.327158) (xy 26.650188 -124.327412)
			(xy 27.067002 -124.327412) (xy 27.078432 -124.28474) (xy 27.080463 -124.275609) (xy 27.078539 -124.25702)
			(xy 27.070075 -124.240358) (xy 27.056198 -124.22784) (xy 27.038754 -124.221133) (xy 27.02941 -124.220732)
			(xy 26.274014 -124.220732) (xy 23.934131 -126.560834) (xy 27.732988 -126.560834) (xy 27.737059 -126.505212)
			(xy 27.749185 -126.450775) (xy 27.769108 -126.398684) (xy 27.796404 -126.350049) (xy 27.83049 -126.305906)
			(xy 27.870639 -126.267197) (xy 27.915997 -126.234746) (xy 27.965597 -126.209245) (xy 28.018381 -126.191238)
			(xy 28.073224 -126.181108) (xy 28.128958 -126.179071) (xy 28.184395 -126.185171) (xy 28.238352 -126.199277)
			(xy 28.289681 -126.221089) (xy 28.337287 -126.250143) (xy 28.380155 -126.285818) (xy 28.417372 -126.327355)
			(xy 28.448145 -126.373868) (xy 28.471817 -126.424365) (xy 28.487885 -126.477772) (xy 28.496005 -126.532948)
			(xy 28.496514 -126.560834) (xy 28.496005 -126.58872) (xy 28.487885 -126.643896) (xy 28.471817 -126.697303)
			(xy 28.448145 -126.7478) (xy 28.417372 -126.794313) (xy 28.380155 -126.83585) (xy 28.337287 -126.871525)
			(xy 28.289681 -126.900579) (xy 28.238352 -126.922391) (xy 28.184395 -126.936497) (xy 28.128958 -126.942597)
			(xy 28.073224 -126.94056) (xy 28.018381 -126.93043) (xy 27.965597 -126.912423) (xy 27.915997 -126.886922)
			(xy 27.870639 -126.854471) (xy 27.83049 -126.815762) (xy 27.796404 -126.771619) (xy 27.769108 -126.722984)
			(xy 27.749185 -126.670893) (xy 27.737059 -126.616456) (xy 27.732988 -126.560834) (xy 23.934131 -126.560834)
			(xy 23.561548 -126.933452) (xy 23.561548 -128.364996) (xy 25.623518 -128.364996) (xy 25.627589 -128.309374)
			(xy 25.639715 -128.254937) (xy 25.659638 -128.202846) (xy 25.686934 -128.154211) (xy 25.72102 -128.110068)
			(xy 25.761169 -128.071359) (xy 25.806527 -128.038908) (xy 25.856127 -128.013407) (xy 25.908911 -127.9954)
			(xy 25.963754 -127.98527) (xy 26.019488 -127.983233) (xy 26.074925 -127.989333) (xy 26.128882 -128.003439)
			(xy 26.180211 -128.025251) (xy 26.227817 -128.054305) (xy 26.270685 -128.08998) (xy 26.307902 -128.131517)
			(xy 26.338675 -128.17803) (xy 26.362347 -128.228527) (xy 26.378415 -128.281934) (xy 26.386535 -128.33711)
			(xy 26.387044 -128.364996) (xy 26.386535 -128.392882) (xy 26.378415 -128.448058) (xy 26.362347 -128.501465)
			(xy 26.338675 -128.551962) (xy 26.307902 -128.598475) (xy 26.270685 -128.640012) (xy 26.227817 -128.675687)
			(xy 26.180211 -128.704741) (xy 26.128882 -128.726553) (xy 26.074925 -128.740659) (xy 26.019488 -128.746759)
			(xy 25.963754 -128.744722) (xy 25.908911 -128.734592) (xy 25.856127 -128.716585) (xy 25.806527 -128.691084)
			(xy 25.761169 -128.658633) (xy 25.72102 -128.619924) (xy 25.686934 -128.575781) (xy 25.659638 -128.527146)
			(xy 25.639715 -128.475055) (xy 25.627589 -128.420618) (xy 25.623518 -128.364996) (xy 23.561548 -128.364996)
			(xy 23.561548 -130.936663) (xy 24.961212 -130.936663) (xy 24.968967 -130.882704) (xy 24.984323 -130.830398)
			(xy 25.006967 -130.780809) (xy 25.036438 -130.734948) (xy 25.072136 -130.693749) (xy 25.113334 -130.658049)
			(xy 25.159193 -130.628576) (xy 25.208781 -130.60593) (xy 25.261086 -130.590571) (xy 25.315045 -130.582813)
			(xy 25.369559 -130.582813) (xy 25.423518 -130.590572) (xy 25.475823 -130.605931) (xy 25.52541 -130.628578)
			(xy 25.571269 -130.658051) (xy 25.612467 -130.693752) (xy 25.648164 -130.734952) (xy 25.677635 -130.780813)
			(xy 25.700278 -130.830401) (xy 25.715634 -130.882708) (xy 25.723389 -130.936667) (xy 25.72385 -130.963924)
			(xy 25.72318 -130.996583) (xy 25.712073 -131.060948) (xy 25.701752 -131.09194) (xy 25.697687 -131.10491)
			(xy 25.695635 -131.131995) (xy 25.700795 -131.158664) (xy 25.712802 -131.183029) (xy 25.730807 -131.203368)
			(xy 25.753536 -131.218241) (xy 25.779382 -131.226598) (xy 25.806516 -131.227846) (xy 25.819862 -131.22529)
			(xy 25.840537 -131.220891) (xy 25.882546 -131.216187) (xy 25.903682 -131.215892) (xy 25.930936 -131.216336)
			(xy 25.984891 -131.224091) (xy 26.037192 -131.239445) (xy 26.086776 -131.262087) (xy 26.132633 -131.291555)
			(xy 26.17383 -131.327249) (xy 26.209527 -131.368442) (xy 26.238999 -131.414297) (xy 26.261644 -131.463879)
			(xy 26.277003 -131.51618) (xy 26.284762 -131.570134) (xy 26.284764 -131.624642) (xy 26.277008 -131.678597)
			(xy 26.261653 -131.730898) (xy 26.23901 -131.780482) (xy 26.209542 -131.826338) (xy 26.173847 -131.867534)
			(xy 26.132653 -131.903231) (xy 26.086798 -131.932702) (xy 26.037215 -131.955346) (xy 25.984914 -131.970704)
			(xy 25.93096 -131.978463) (xy 25.876452 -131.978464) (xy 25.822497 -131.970707) (xy 25.770196 -131.955351)
			(xy 25.720613 -131.932707) (xy 25.674757 -131.903238) (xy 25.633562 -131.867543) (xy 25.597865 -131.826348)
			(xy 25.568396 -131.780492) (xy 25.545751 -131.730909) (xy 25.530394 -131.678608) (xy 25.522637 -131.624654)
			(xy 25.522174 -131.5974) (xy 25.522829 -131.564741) (xy 25.533946 -131.500375) (xy 25.544272 -131.469384)
			(xy 25.548512 -131.456463) (xy 25.550554 -131.429351) (xy 25.545376 -131.40266) (xy 25.533345 -131.378277)
			(xy 25.515313 -131.357929) (xy 25.492555 -131.343053) (xy 25.46668 -131.334703) (xy 25.439519 -131.333468)
			(xy 25.426162 -131.336034) (xy 25.405486 -131.340428) (xy 25.363478 -131.345136) (xy 25.342342 -131.345432)
			(xy 25.315085 -131.34499) (xy 25.261125 -131.337238) (xy 25.208818 -131.321884) (xy 25.159229 -131.299243)
			(xy 25.113366 -131.269775) (xy 25.072164 -131.23408) (xy 25.036462 -131.192884) (xy 25.006986 -131.147026)
			(xy 24.984337 -131.09744) (xy 24.968976 -131.045135) (xy 24.961214 -130.991177) (xy 24.961212 -130.936663)
			(xy 23.561548 -130.936663) (xy 23.561548 -133.6802) (xy 24.987502 -133.6802) (xy 24.991573 -133.624578)
			(xy 25.003699 -133.570141) (xy 25.023622 -133.51805) (xy 25.050918 -133.469415) (xy 25.085004 -133.425272)
			(xy 25.125153 -133.386563) (xy 25.170511 -133.354112) (xy 25.220111 -133.328611) (xy 25.272895 -133.310604)
			(xy 25.327738 -133.300474) (xy 25.383472 -133.298437) (xy 25.438909 -133.304537) (xy 25.492866 -133.318643)
			(xy 25.544195 -133.340455) (xy 25.591801 -133.369509) (xy 25.634669 -133.405184) (xy 25.671886 -133.446721)
			(xy 25.702659 -133.493234) (xy 25.726331 -133.543731) (xy 25.742399 -133.597138) (xy 25.750519 -133.652314)
			(xy 25.751028 -133.6802) (xy 25.750519 -133.708086) (xy 25.742399 -133.763262) (xy 25.726331 -133.816669)
			(xy 25.702659 -133.867166) (xy 25.671886 -133.913679) (xy 25.634669 -133.955216) (xy 25.591801 -133.990891)
			(xy 25.544195 -134.019945) (xy 25.492866 -134.041757) (xy 25.438909 -134.055863) (xy 25.383472 -134.061963)
			(xy 25.327738 -134.059926) (xy 25.272895 -134.049796) (xy 25.220111 -134.031789) (xy 25.170511 -134.006288)
			(xy 25.125153 -133.973837) (xy 25.085004 -133.935128) (xy 25.050918 -133.890985) (xy 25.023622 -133.84235)
			(xy 25.003699 -133.790259) (xy 24.991573 -133.735822) (xy 24.987502 -133.6802) (xy 23.561548 -133.6802)
			(xy 23.561548 -134.824216) (xy 26.2255 -134.824216) (xy 26.2255 -132.004308) (xy 26.952956 -131.276852)
			(xy 27.572208 -131.276852) (xy 27.586349 -131.276391) (xy 27.613539 -131.268602) (xy 27.637548 -131.253652)
			(xy 27.656533 -131.232688) (xy 27.669039 -131.20732) (xy 27.674104 -131.179494) (xy 27.67134 -131.151346)
			(xy 27.660959 -131.125037) (xy 27.652726 -131.11353) (xy 27.637796 -131.093503) (xy 27.612787 -131.050259)
			(xy 27.593639 -131.00412) (xy 27.580681 -130.955875) (xy 27.574135 -130.906351) (xy 27.573732 -130.881374)
			(xy 27.573732 -130.880866) (xy 27.574218 -130.853615) (xy 27.581974 -130.799667) (xy 27.597329 -130.747372)
			(xy 27.619971 -130.697795) (xy 27.649437 -130.651945) (xy 27.685128 -130.610754) (xy 27.726319 -130.575063)
			(xy 27.772169 -130.545597) (xy 27.821746 -130.522955) (xy 27.874041 -130.5076) (xy 27.927989 -130.499844)
			(xy 27.982491 -130.499844) (xy 28.036439 -130.5076) (xy 28.088734 -130.522955) (xy 28.138311 -130.545597)
			(xy 28.184161 -130.575063) (xy 28.225352 -130.610754) (xy 28.261043 -130.651945) (xy 28.290509 -130.697795)
			(xy 28.313151 -130.747372) (xy 28.328506 -130.799667) (xy 28.336262 -130.853615) (xy 28.336748 -130.880866)
			(xy 28.336186 -130.910298) (xy 28.327155 -130.968464) (xy 28.309303 -131.024555) (xy 28.283051 -131.07724)
			(xy 28.249023 -131.125271) (xy 28.208026 -131.167509) (xy 28.184856 -131.185666) (xy 28.164536 -131.200906)
			(xy 28.164536 -131.276852) (xy 28.331668 -131.276852) (xy 28.9433 -130.66522) (xy 28.9433 -130.101594)
			(xy 28.942835 -130.087829) (xy 28.93545 -130.061308) (xy 28.921247 -130.037724) (xy 28.901258 -130.018793)
			(xy 28.876938 -130.005893) (xy 28.850054 -129.999961) (xy 28.822563 -130.001428) (xy 28.796463 -130.010189)
			(xy 28.784804 -130.01752) (xy 28.760989 -130.033062) (xy 28.709711 -130.057645) (xy 28.655351 -130.074342)
			(xy 28.599115 -130.082782) (xy 28.570682 -130.083306) (xy 28.54343 -130.082839) (xy 28.489482 -130.07508)
			(xy 28.437186 -130.059722) (xy 28.387609 -130.037079) (xy 28.341759 -130.007611) (xy 28.300569 -129.971917)
			(xy 28.264877 -129.930725) (xy 28.235411 -129.884873) (xy 28.212771 -129.835295) (xy 28.197416 -129.782999)
			(xy 28.18966 -129.72905) (xy 28.189174 -129.701798) (xy 28.189663 -129.674963) (xy 28.19719 -129.621822)
			(xy 28.212094 -129.570262) (xy 28.234082 -129.521302) (xy 28.262718 -129.475909) (xy 28.297436 -129.43498)
			(xy 28.31719 -129.41681) (xy 28.327545 -129.406861) (xy 28.342854 -129.382587) (xy 28.350803 -129.355013)
			(xy 28.350764 -129.326315) (xy 28.342741 -129.298762) (xy 28.327366 -129.27453) (xy 28.316936 -129.264664)
			(xy 28.297112 -129.246479) (xy 28.262256 -129.205507) (xy 28.233501 -129.160043) (xy 28.211418 -129.110991)
			(xy 28.196444 -129.059324) (xy 28.188878 -129.006065) (xy 28.188412 -128.979168) (xy 28.188412 -128.978406)
			(xy 28.18891 -128.951891) (xy 28.196296 -128.899378) (xy 28.203144 -128.873758) (xy 28.206593 -128.860001)
			(xy 28.206656 -128.831653) (xy 28.198909 -128.804385) (xy 28.183951 -128.780305) (xy 28.162938 -128.761277)
			(xy 28.137498 -128.748772) (xy 28.109597 -128.743759) (xy 28.095448 -128.744726) (xy 28.057856 -128.746504)
			(xy 28.030609 -128.745975) (xy 27.97667 -128.738213) (xy 27.924384 -128.722855) (xy 27.874816 -128.700212)
			(xy 27.828975 -128.670745) (xy 27.787794 -128.635055) (xy 27.752112 -128.593867) (xy 27.722654 -128.548021)
			(xy 27.70002 -128.498449) (xy 27.684671 -128.44616) (xy 27.67692 -128.392219) (xy 27.676924 -128.337725)
			(xy 27.684683 -128.283785) (xy 27.70004 -128.231499) (xy 27.722681 -128.18193) (xy 27.752145 -128.136088)
			(xy 27.787834 -128.094906) (xy 27.82902 -128.059221) (xy 27.874865 -128.029761) (xy 27.924436 -128.007126)
			(xy 27.976724 -127.991775) (xy 28.030665 -127.984021) (xy 28.085159 -127.984023) (xy 28.139099 -127.99178)
			(xy 28.191386 -128.007134) (xy 28.240956 -128.029773) (xy 28.286799 -128.059236) (xy 28.327983 -128.094923)
			(xy 28.363669 -128.136107) (xy 28.393131 -128.181951) (xy 28.415769 -128.231521) (xy 28.431122 -128.283809)
			(xy 28.438878 -128.337749) (xy 28.439364 -128.364996) (xy 28.439364 -128.365758) (xy 28.43888 -128.392273)
			(xy 28.431485 -128.444787) (xy 28.424632 -128.470406) (xy 28.421138 -128.484151) (xy 28.421089 -128.512502)
			(xy 28.428848 -128.539771) (xy 28.443814 -128.563849) (xy 28.464831 -128.582877) (xy 28.490274 -128.595383)
			(xy 28.518178 -128.600401) (xy 28.532328 -128.599438) (xy 28.56992 -128.59766) (xy 28.598434 -128.598218)
			(xy 28.654822 -128.606751) (xy 28.709311 -128.623581) (xy 28.76069 -128.648332) (xy 28.78455 -128.663954)
			(xy 28.796188 -128.671332) (xy 28.822288 -128.680137) (xy 28.849793 -128.68165) (xy 28.876701 -128.67576)
			(xy 28.901059 -128.662897) (xy 28.921096 -128.643994) (xy 28.935355 -128.620426) (xy 28.9428 -128.593905)
			(xy 28.9433 -128.580134) (xy 28.9433 -126.081028) (xy 29.271976 -125.752352) (xy 30.362144 -125.752352)
			(xy 30.564074 -125.954282) (xy 31.145478 -125.954282) (xy 31.149549 -125.89866) (xy 31.161675 -125.844223)
			(xy 31.181598 -125.792132) (xy 31.208894 -125.743497) (xy 31.24298 -125.699354) (xy 31.283129 -125.660645)
			(xy 31.328487 -125.628194) (xy 31.378087 -125.602693) (xy 31.430871 -125.584686) (xy 31.485714 -125.574556)
			(xy 31.541448 -125.572519) (xy 31.596885 -125.578619) (xy 31.650842 -125.592725) (xy 31.702171 -125.614537)
			(xy 31.749777 -125.643591) (xy 31.792645 -125.679266) (xy 31.829862 -125.720803) (xy 31.860635 -125.767316)
			(xy 31.884307 -125.817813) (xy 31.900375 -125.87122) (xy 31.908495 -125.926396) (xy 31.909004 -125.954282)
			(xy 31.908495 -125.982168) (xy 31.900375 -126.037344) (xy 31.893881 -126.05893) (xy 33.07918 -126.05893)
			(xy 33.083251 -126.003308) (xy 33.095377 -125.948871) (xy 33.1153 -125.89678) (xy 33.142596 -125.848145)
			(xy 33.176682 -125.804002) (xy 33.216831 -125.765293) (xy 33.262189 -125.732842) (xy 33.311789 -125.707341)
			(xy 33.364573 -125.689334) (xy 33.419416 -125.679204) (xy 33.47515 -125.677167) (xy 33.530587 -125.683267)
			(xy 33.584544 -125.697373) (xy 33.635873 -125.719185) (xy 33.683479 -125.748239) (xy 33.726347 -125.783914)
			(xy 33.763564 -125.825451) (xy 33.794337 -125.871964) (xy 33.818009 -125.922461) (xy 33.834077 -125.975868)
			(xy 33.842197 -126.031044) (xy 33.842706 -126.05893) (xy 33.842197 -126.086816) (xy 33.834077 -126.141992)
			(xy 33.818009 -126.195399) (xy 33.794337 -126.245896) (xy 33.784437 -126.26086) (xy 34.41141 -126.26086)
			(xy 34.415481 -126.205238) (xy 34.427607 -126.150801) (xy 34.44753 -126.09871) (xy 34.474826 -126.050075)
			(xy 34.508912 -126.005932) (xy 34.549061 -125.967223) (xy 34.594419 -125.934772) (xy 34.644019 -125.909271)
			(xy 34.696803 -125.891264) (xy 34.751646 -125.881134) (xy 34.80738 -125.879097) (xy 34.862817 -125.885197)
			(xy 34.916774 -125.899303) (xy 34.968103 -125.921115) (xy 35.015709 -125.950169) (xy 35.058577 -125.985844)
			(xy 35.095794 -126.027381) (xy 35.126567 -126.073894) (xy 35.150239 -126.124391) (xy 35.166307 -126.177798)
			(xy 35.174427 -126.232974) (xy 35.174936 -126.26086) (xy 35.174427 -126.288746) (xy 35.166307 -126.343922)
			(xy 35.150239 -126.397329) (xy 35.126567 -126.447826) (xy 35.095794 -126.494339) (xy 35.058577 -126.535876)
			(xy 35.015709 -126.571551) (xy 34.968103 -126.600605) (xy 34.916774 -126.622417) (xy 34.862817 -126.636523)
			(xy 34.80738 -126.642623) (xy 34.751646 -126.640586) (xy 34.696803 -126.630456) (xy 34.644019 -126.612449)
			(xy 34.594419 -126.586948) (xy 34.549061 -126.554497) (xy 34.508912 -126.515788) (xy 34.474826 -126.471645)
			(xy 34.44753 -126.42301) (xy 34.427607 -126.370919) (xy 34.415481 -126.316482) (xy 34.41141 -126.26086)
			(xy 33.784437 -126.26086) (xy 33.763564 -126.292409) (xy 33.726347 -126.333946) (xy 33.683479 -126.369621)
			(xy 33.635873 -126.398675) (xy 33.584544 -126.420487) (xy 33.530587 -126.434593) (xy 33.47515 -126.440693)
			(xy 33.419416 -126.438656) (xy 33.364573 -126.428526) (xy 33.311789 -126.410519) (xy 33.262189 -126.385018)
			(xy 33.216831 -126.352567) (xy 33.176682 -126.313858) (xy 33.142596 -126.269715) (xy 33.1153 -126.22108)
			(xy 33.095377 -126.168989) (xy 33.083251 -126.114552) (xy 33.07918 -126.05893) (xy 31.893881 -126.05893)
			(xy 31.884307 -126.090751) (xy 31.860635 -126.141248) (xy 31.829862 -126.187761) (xy 31.792645 -126.229298)
			(xy 31.749777 -126.264973) (xy 31.702171 -126.294027) (xy 31.650842 -126.315839) (xy 31.596885 -126.329945)
			(xy 31.541448 -126.336045) (xy 31.485714 -126.334008) (xy 31.430871 -126.323878) (xy 31.378087 -126.305871)
			(xy 31.328487 -126.28037) (xy 31.283129 -126.247919) (xy 31.24298 -126.20921) (xy 31.208894 -126.165067)
			(xy 31.181598 -126.116432) (xy 31.161675 -126.064341) (xy 31.149549 -126.009904) (xy 31.145478 -125.954282)
			(xy 30.564074 -125.954282) (xy 31.282132 -126.67234) (xy 31.847028 -126.67234) (xy 31.872428 -126.69774)
			(xy 35.487862 -126.69774) (xy 35.491933 -126.642118) (xy 35.504059 -126.587681) (xy 35.523982 -126.53559)
			(xy 35.551278 -126.486955) (xy 35.585364 -126.442812) (xy 35.625513 -126.404103) (xy 35.670871 -126.371652)
			(xy 35.720471 -126.346151) (xy 35.773255 -126.328144) (xy 35.828098 -126.318014) (xy 35.883832 -126.315977)
			(xy 35.939269 -126.322077) (xy 35.993226 -126.336183) (xy 36.044555 -126.357995) (xy 36.092161 -126.387049)
			(xy 36.135029 -126.422724) (xy 36.172246 -126.464261) (xy 36.203019 -126.510774) (xy 36.226691 -126.561271)
			(xy 36.242759 -126.614678) (xy 36.250879 -126.669854) (xy 36.251388 -126.69774) (xy 36.250879 -126.725626)
			(xy 36.242759 -126.780802) (xy 36.226691 -126.834209) (xy 36.203019 -126.884706) (xy 36.172246 -126.931219)
			(xy 36.135029 -126.972756) (xy 36.092161 -127.008431) (xy 36.044555 -127.037485) (xy 35.993226 -127.059297)
			(xy 35.939269 -127.073403) (xy 35.883832 -127.079503) (xy 35.828098 -127.077466) (xy 35.773255 -127.067336)
			(xy 35.720471 -127.049329) (xy 35.670871 -127.023828) (xy 35.625513 -126.991377) (xy 35.585364 -126.952668)
			(xy 35.551278 -126.908525) (xy 35.523982 -126.85989) (xy 35.504059 -126.807799) (xy 35.491933 -126.753362)
			(xy 35.487862 -126.69774) (xy 31.872428 -126.69774) (xy 33.135316 -127.960628) (xy 33.135316 -127.966724)
			(xy 35.514532 -127.966724) (xy 35.518603 -127.911102) (xy 35.530729 -127.856665) (xy 35.550652 -127.804574)
			(xy 35.577948 -127.755939) (xy 35.612034 -127.711796) (xy 35.652183 -127.673087) (xy 35.697541 -127.640636)
			(xy 35.747141 -127.615135) (xy 35.799925 -127.597128) (xy 35.854768 -127.586998) (xy 35.910502 -127.584961)
			(xy 35.965939 -127.591061) (xy 36.019896 -127.605167) (xy 36.071225 -127.626979) (xy 36.118831 -127.656033)
			(xy 36.161699 -127.691708) (xy 36.198916 -127.733245) (xy 36.229689 -127.779758) (xy 36.253361 -127.830255)
			(xy 36.269429 -127.883662) (xy 36.277549 -127.938838) (xy 36.278058 -127.966724) (xy 36.277549 -127.99461)
			(xy 36.269429 -128.049786) (xy 36.253361 -128.103193) (xy 36.229689 -128.15369) (xy 36.198916 -128.200203)
			(xy 36.161699 -128.24174) (xy 36.118831 -128.277415) (xy 36.071225 -128.306469) (xy 36.019896 -128.328281)
			(xy 35.965939 -128.342387) (xy 35.910502 -128.348487) (xy 35.854768 -128.34645) (xy 35.799925 -128.33632)
			(xy 35.747141 -128.318313) (xy 35.697541 -128.292812) (xy 35.652183 -128.260361) (xy 35.612034 -128.221652)
			(xy 35.577948 -128.177509) (xy 35.550652 -128.128874) (xy 35.530729 -128.076783) (xy 35.518603 -128.022346)
			(xy 35.514532 -127.966724) (xy 33.135316 -127.966724) (xy 33.135316 -128.898257) (xy 34.774519 -128.898257)
			(xy 34.774519 -128.843743) (xy 34.782278 -128.789784) (xy 34.797637 -128.737479) (xy 34.820284 -128.687892)
			(xy 34.849757 -128.642033) (xy 34.885458 -128.600835) (xy 34.926658 -128.565138) (xy 34.97252 -128.535668)
			(xy 35.022109 -128.513025) (xy 35.074416 -128.497671) (xy 35.128375 -128.489917) (xy 35.155632 -128.489456)
			(xy 35.183235 -128.48994) (xy 35.237867 -128.497876) (xy 35.290784 -128.513608) (xy 35.340879 -128.536805)
			(xy 35.387106 -128.566983) (xy 35.428498 -128.603512) (xy 35.46419 -128.645628) (xy 35.479228 -128.66878)
			(xy 35.486745 -128.680134) (xy 35.506723 -128.698627) (xy 35.530881 -128.711177) (xy 35.557498 -128.716889)
			(xy 35.584678 -128.715357) (xy 35.610485 -128.70669) (xy 35.633079 -128.691506) (xy 35.642296 -128.68148)
			(xy 35.660491 -128.661057) (xy 35.701733 -128.625128) (xy 35.747683 -128.595458) (xy 35.7974 -128.572655)
			(xy 35.849864 -128.557185) (xy 35.904 -128.549366) (xy 35.931348 -128.548892) (xy 35.9586 -128.549333)
			(xy 36.01255 -128.557096) (xy 36.064845 -128.572457) (xy 36.114423 -128.595104) (xy 36.160273 -128.624575)
			(xy 36.201463 -128.660271) (xy 36.237153 -128.701466) (xy 36.266619 -128.747319) (xy 36.289259 -128.7969)
			(xy 36.304614 -128.849197) (xy 36.31237 -128.903148) (xy 36.312856 -128.9304) (xy 36.312354 -128.959318)
			(xy 36.303624 -129.01649) (xy 36.286364 -129.07169) (xy 36.260969 -129.123652) (xy 36.228022 -129.171186)
			(xy 36.188277 -129.213201) (xy 36.16579 -129.23139) (xy 36.154505 -129.240742) (xy 36.137427 -129.264546)
			(xy 36.127817 -129.292223) (xy 36.12647 -129.321489) (xy 36.133495 -129.349931) (xy 36.148314 -129.375205)
			(xy 36.158678 -129.385568) (xy 36.177306 -129.403687) (xy 36.210021 -129.444059) (xy 36.236951 -129.4885)
			(xy 36.257598 -129.536186) (xy 36.271578 -129.586234) (xy 36.278634 -129.637716) (xy 36.279074 -129.663698)
			(xy 36.278643 -129.690952) (xy 36.270885 -129.744906) (xy 36.255528 -129.797207) (xy 36.232883 -129.846789)
			(xy 36.203412 -129.892644) (xy 36.167715 -129.933837) (xy 36.126518 -129.969531) (xy 36.080661 -129.998998)
			(xy 36.031077 -130.021639) (xy 35.978775 -130.036992) (xy 35.92482 -130.044745) (xy 35.897566 -130.045206)
			(xy 35.868794 -130.044675) (xy 35.811906 -130.035999) (xy 35.784282 -130.027934) (xy 35.770239 -130.023972)
			(xy 35.741071 -130.023495) (xy 35.712955 -130.031276) (xy 35.688183 -130.046681) (xy 35.66877 -130.068456)
			(xy 35.656298 -130.094827) (xy 35.651782 -130.123647) (xy 35.653218 -130.13817) (xy 35.654756 -130.150495)
			(xy 35.656405 -130.17528) (xy 35.65652 -130.1877) (xy 35.656045 -130.214953) (xy 35.648288 -130.268904)
			(xy 35.632931 -130.321202) (xy 35.610289 -130.370783) (xy 35.58082 -130.416636) (xy 35.545126 -130.457829)
			(xy 35.503933 -130.493523) (xy 35.458079 -130.52299) (xy 35.408499 -130.545633) (xy 35.3562 -130.560988)
			(xy 35.302249 -130.568745) (xy 35.247743 -130.568744) (xy 35.193792 -130.560987) (xy 35.141494 -130.54563)
			(xy 35.091914 -130.522987) (xy 35.046061 -130.493518) (xy 35.004868 -130.457823) (xy 34.969175 -130.41663)
			(xy 34.939708 -130.370776) (xy 34.917066 -130.321195) (xy 34.901711 -130.268896) (xy 34.893955 -130.214945)
			(xy 34.893956 -130.160439) (xy 34.901714 -130.106488) (xy 34.917071 -130.05419) (xy 34.939715 -130.00461)
			(xy 34.969185 -129.958757) (xy 35.00488 -129.917565) (xy 35.046073 -129.881873) (xy 35.091928 -129.852406)
			(xy 35.141509 -129.829764) (xy 35.193807 -129.81441) (xy 35.247759 -129.806654) (xy 35.275012 -129.806192)
			(xy 35.303784 -129.806728) (xy 35.360672 -129.815401) (xy 35.388296 -129.823464) (xy 35.402345 -129.827403)
			(xy 35.431511 -129.827886) (xy 35.459625 -129.820109) (xy 35.484397 -129.804708) (xy 35.50381 -129.782936)
			(xy 35.516281 -129.756567) (xy 35.520797 -129.72775) (xy 35.51936 -129.713228) (xy 35.517822 -129.700903)
			(xy 35.516173 -129.676118) (xy 35.516058 -129.663698) (xy 35.516553 -129.63478) (xy 35.525284 -129.577607)
			(xy 35.542545 -129.522406) (xy 35.567941 -129.470444) (xy 35.600889 -129.422911) (xy 35.640636 -129.380897)
			(xy 35.663124 -129.362708) (xy 35.67441 -129.353358) (xy 35.691486 -129.329553) (xy 35.701094 -129.301876)
			(xy 35.702441 -129.27261) (xy 35.695417 -129.244168) (xy 35.680599 -129.218894) (xy 35.670236 -129.20853)
			(xy 35.65251 -129.191376) (xy 35.62117 -129.153283) (xy 35.607752 -129.132584) (xy 35.600137 -129.121302)
			(xy 35.580177 -129.102818) (xy 35.556041 -129.09027) (xy 35.529445 -129.084551) (xy 35.502284 -129.086069)
			(xy 35.47649 -129.094714) (xy 35.453901 -129.109872) (xy 35.444684 -129.119884) (xy 35.426492 -129.14031)
			(xy 35.38525 -129.176239) (xy 35.339299 -129.20591) (xy 35.289582 -129.228714) (xy 35.237117 -129.244183)
			(xy 35.182981 -129.251999) (xy 35.155632 -129.252472) (xy 35.128375 -129.252083) (xy 35.074416 -129.244329)
			(xy 35.022109 -129.228975) (xy 34.97252 -129.206332) (xy 34.926658 -129.176862) (xy 34.885458 -129.141165)
			(xy 34.849757 -129.099967) (xy 34.820284 -129.054108) (xy 34.797637 -129.004521) (xy 34.782278 -128.952216)
			(xy 34.774519 -128.898257) (xy 33.135316 -128.898257) (xy 33.135316 -131.179062) (xy 34.962844 -131.179062)
			(xy 34.966915 -131.12344) (xy 34.979041 -131.069003) (xy 34.998964 -131.016912) (xy 35.02626 -130.968277)
			(xy 35.060346 -130.924134) (xy 35.100495 -130.885425) (xy 35.145853 -130.852974) (xy 35.195453 -130.827473)
			(xy 35.248237 -130.809466) (xy 35.30308 -130.799336) (xy 35.358814 -130.797299) (xy 35.414251 -130.803399)
			(xy 35.468208 -130.817505) (xy 35.519537 -130.839317) (xy 35.567143 -130.868371) (xy 35.610011 -130.904046)
			(xy 35.647228 -130.945583) (xy 35.678001 -130.992096) (xy 35.701673 -131.042593) (xy 35.717741 -131.096)
			(xy 35.725861 -131.151176) (xy 35.72637 -131.179062) (xy 35.725861 -131.206948) (xy 35.717741 -131.262124)
			(xy 35.701673 -131.315531) (xy 35.678001 -131.366028) (xy 35.647228 -131.412541) (xy 35.610011 -131.454078)
			(xy 35.567143 -131.489753) (xy 35.519537 -131.518807) (xy 35.468208 -131.540619) (xy 35.414251 -131.554725)
			(xy 35.358814 -131.560825) (xy 35.30308 -131.558788) (xy 35.248237 -131.548658) (xy 35.195453 -131.530651)
			(xy 35.145853 -131.50515) (xy 35.100495 -131.472699) (xy 35.060346 -131.43399) (xy 35.02626 -131.389847)
			(xy 34.998964 -131.341212) (xy 34.979041 -131.289121) (xy 34.966915 -131.234684) (xy 34.962844 -131.179062)
			(xy 33.135316 -131.179062) (xy 33.135316 -132.049774) (xy 37.591998 -132.049774) (xy 37.596069 -131.994152)
			(xy 37.608195 -131.939715) (xy 37.628118 -131.887624) (xy 37.655414 -131.838989) (xy 37.6895 -131.794846)
			(xy 37.729649 -131.756137) (xy 37.775007 -131.723686) (xy 37.824607 -131.698185) (xy 37.877391 -131.680178)
			(xy 37.932234 -131.670048) (xy 37.987968 -131.668011) (xy 38.043405 -131.674111) (xy 38.097362 -131.688217)
			(xy 38.148691 -131.710029) (xy 38.196297 -131.739083) (xy 38.239165 -131.774758) (xy 38.276382 -131.816295)
			(xy 38.307155 -131.862808) (xy 38.330827 -131.913305) (xy 38.346895 -131.966712) (xy 38.355015 -132.021888)
			(xy 38.355524 -132.049774) (xy 38.355015 -132.07766) (xy 38.346895 -132.132836) (xy 38.330827 -132.186243)
			(xy 38.307155 -132.23674) (xy 38.276382 -132.283253) (xy 38.239165 -132.32479) (xy 38.196297 -132.360465)
			(xy 38.148691 -132.389519) (xy 38.097362 -132.411331) (xy 38.043405 -132.425437) (xy 37.987968 -132.431537)
			(xy 37.932234 -132.4295) (xy 37.877391 -132.41937) (xy 37.824607 -132.401363) (xy 37.775007 -132.375862)
			(xy 37.729649 -132.343411) (xy 37.6895 -132.304702) (xy 37.655414 -132.260559) (xy 37.628118 -132.211924)
			(xy 37.608195 -132.159833) (xy 37.596069 -132.105396) (xy 37.591998 -132.049774) (xy 33.135316 -132.049774)
			(xy 33.135316 -132.429504) (xy 33.031938 -132.532882) (xy 38.89832 -132.532882) (xy 38.902391 -132.47726)
			(xy 38.914517 -132.422823) (xy 38.93444 -132.370732) (xy 38.961736 -132.322097) (xy 38.995822 -132.277954)
			(xy 39.035971 -132.239245) (xy 39.081329 -132.206794) (xy 39.130929 -132.181293) (xy 39.183713 -132.163286)
			(xy 39.238556 -132.153156) (xy 39.29429 -132.151119) (xy 39.349727 -132.157219) (xy 39.403684 -132.171325)
			(xy 39.455013 -132.193137) (xy 39.502619 -132.222191) (xy 39.545487 -132.257866) (xy 39.582704 -132.299403)
			(xy 39.613477 -132.345916) (xy 39.637149 -132.396413) (xy 39.653217 -132.44982) (xy 39.661337 -132.504996)
			(xy 39.661846 -132.532882) (xy 39.661337 -132.560768) (xy 39.653217 -132.615944) (xy 39.637149 -132.669351)
			(xy 39.613477 -132.719848) (xy 39.582704 -132.766361) (xy 39.545487 -132.807898) (xy 39.502619 -132.843573)
			(xy 39.455013 -132.872627) (xy 39.403684 -132.894439) (xy 39.349727 -132.908545) (xy 39.29429 -132.914645)
			(xy 39.238556 -132.912608) (xy 39.183713 -132.902478) (xy 39.130929 -132.884471) (xy 39.081329 -132.85897)
			(xy 39.035971 -132.826519) (xy 38.995822 -132.78781) (xy 38.961736 -132.743667) (xy 38.93444 -132.695032)
			(xy 38.914517 -132.642941) (xy 38.902391 -132.588504) (xy 38.89832 -132.532882) (xy 33.031938 -132.532882)
			(xy 32.937704 -132.627116) (xy 30.586172 -132.627116) (xy 29.628592 -133.584696) (xy 28.423108 -133.584696)
			(xy 28.402788 -133.564376) (xy 28.152852 -133.564376) (xy 28.014168 -133.70306) (xy 28.014168 -134.481316)
			(xy 28.190952 -134.6581) (xy 29.753052 -134.6581) (xy 29.876496 -134.781798) (xy 29.876496 -134.902448)
			(xy 31.301436 -134.902448) (xy 31.797498 -134.406386) (xy 31.807659 -134.39537) (xy 31.821783 -134.368962)
			(xy 31.827643 -134.339592) (xy 31.824736 -134.309785) (xy 31.813311 -134.282102) (xy 31.79435 -134.25892)
			(xy 31.769481 -134.242233) (xy 31.740843 -134.233473) (xy 31.72587 -134.232904) (xy 30.594808 -134.232904)
			(xy 30.519116 -134.308596) (xy 30.519116 -134.329932) (xy 30.518717 -134.357209) (xy 30.511013 -134.411216)
			(xy 30.495697 -134.463575) (xy 30.473079 -134.513218) (xy 30.443621 -134.559135) (xy 30.407925 -134.600388)
			(xy 30.366716 -134.636136) (xy 30.320837 -134.665651) (xy 30.271221 -134.68833) (xy 30.218882 -134.703712)
			(xy 30.164885 -134.711483) (xy 30.137608 -134.711948) (xy 30.111066 -134.711513) (xy 30.058496 -134.70413)
			(xy 30.007457 -134.689533) (xy 29.958933 -134.668005) (xy 29.913861 -134.639959) (xy 29.873109 -134.605939)
			(xy 29.837466 -134.566599) (xy 29.807618 -134.5227) (xy 29.79547 -134.499096) (xy 29.788388 -134.48588)
			(xy 29.767901 -134.464005) (xy 29.741952 -134.449007) (xy 29.71277 -134.442176) (xy 29.68286 -134.444097)
			(xy 29.654792 -134.454606) (xy 29.642562 -134.463282) (xy 29.617477 -134.4816) (xy 29.562619 -134.510728)
			(xy 29.503768 -134.530585) (xy 29.442477 -134.540648) (xy 29.411422 -134.54126) (xy 29.38504 -134.540875)
			(xy 29.332779 -134.533611) (xy 29.282017 -134.519218) (xy 29.23372 -134.497972) (xy 29.18881 -134.470275)
			(xy 29.148143 -134.436658) (xy 29.112493 -134.39776) (xy 29.082541 -134.354322) (xy 29.0703 -134.330948)
			(xy 29.063598 -134.318589) (xy 29.044623 -134.297861) (xy 29.020709 -134.283099) (xy 28.993673 -134.275427)
			(xy 28.965571 -134.275427) (xy 28.938535 -134.283099) (xy 28.914621 -134.297861) (xy 28.895646 -134.318589)
			(xy 28.888944 -134.330948) (xy 28.876706 -134.35432) (xy 28.846742 -134.397742) (xy 28.811085 -134.436626)
			(xy 28.770415 -134.470231) (xy 28.725505 -134.497917) (xy 28.677213 -134.519158) (xy 28.626456 -134.533548)
			(xy 28.574201 -134.540813) (xy 28.547822 -134.54126) (xy 28.520565 -134.540895) (xy 28.466605 -134.533139)
			(xy 28.414297 -134.517783) (xy 28.364708 -134.495139) (xy 28.318847 -134.465668) (xy 28.277646 -134.42997)
			(xy 28.241945 -134.388771) (xy 28.212472 -134.342911) (xy 28.189825 -134.293323) (xy 28.174466 -134.241017)
			(xy 28.166707 -134.187057) (xy 28.166707 -134.132543) (xy 28.174466 -134.078583) (xy 28.189825 -134.026277)
			(xy 28.212472 -133.976689) (xy 28.241945 -133.930829) (xy 28.277646 -133.88963) (xy 28.318846 -133.853932)
			(xy 28.364708 -133.824461) (xy 28.414297 -133.801817) (xy 28.466605 -133.786461) (xy 28.520565 -133.778705)
			(xy 28.547822 -133.778244) (xy 28.5742 -133.778728) (xy 28.626454 -133.785982) (xy 28.677212 -133.800363)
			(xy 28.725505 -133.821597) (xy 28.770415 -133.84928) (xy 28.811084 -133.882882) (xy 28.846739 -133.921766)
			(xy 28.876699 -133.965189) (xy 28.888944 -133.988556) (xy 28.895646 -134.000915) (xy 28.914621 -134.021643)
			(xy 28.938535 -134.036405) (xy 28.965571 -134.044077) (xy 28.993673 -134.044077) (xy 29.020709 -134.036405)
			(xy 29.044623 -134.021643) (xy 29.063598 -134.000915) (xy 29.0703 -133.988556) (xy 29.082506 -133.965166)
			(xy 29.112475 -133.921743) (xy 29.148136 -133.88286) (xy 29.188811 -133.849256) (xy 29.233725 -133.821571)
			(xy 29.282022 -133.800334) (xy 29.332783 -133.785948) (xy 29.385042 -133.778688) (xy 29.411422 -133.778244)
			(xy 29.437962 -133.778742) (xy 29.490529 -133.786115) (xy 29.541566 -133.800702) (xy 29.59009 -133.822221)
			(xy 29.635162 -133.850258) (xy 29.675915 -133.884271) (xy 29.71156 -133.923603) (xy 29.741411 -133.967495)
			(xy 29.75356 -133.991096) (xy 29.760607 -134.004333) (xy 29.781101 -134.026212) (xy 29.807058 -134.04121)
			(xy 29.836249 -134.048038) (xy 29.866165 -134.04611) (xy 29.894238 -134.035592) (xy 29.906468 -134.02691)
			(xy 29.926511 -134.012147) (xy 29.969703 -133.9874) (xy 30.015747 -133.968479) (xy 30.06386 -133.955707)
			(xy 30.113226 -133.949301) (xy 30.138116 -133.948932) (xy 30.159452 -133.948932) (xy 30.309566 -133.798818)
			(xy 30.327673 -133.781593) (xy 30.369234 -133.753853) (xy 30.415405 -133.734747) (xy 30.464414 -133.725007)
			(xy 30.489398 -133.724396) (xy 34.71926 -133.724396) (xy 34.744245 -133.724976) (xy 34.793256 -133.734727)
			(xy 34.839425 -133.753843) (xy 34.880984 -133.781592) (xy 34.899092 -133.798818) (xy 34.93897 -133.838696)
			(xy 38.067994 -133.838696) (xy 38.072065 -133.783074) (xy 38.084191 -133.728637) (xy 38.104114 -133.676546)
			(xy 38.13141 -133.627911) (xy 38.165496 -133.583768) (xy 38.205645 -133.545059) (xy 38.251003 -133.512608)
			(xy 38.300603 -133.487107) (xy 38.353387 -133.4691) (xy 38.40823 -133.45897) (xy 38.463964 -133.456933)
			(xy 38.519401 -133.463033) (xy 38.573358 -133.477139) (xy 38.624687 -133.498951) (xy 38.672293 -133.528005)
			(xy 38.715161 -133.56368) (xy 38.752378 -133.605217) (xy 38.783151 -133.65173) (xy 38.806823 -133.702227)
			(xy 38.822891 -133.755634) (xy 38.831011 -133.81081) (xy 38.83152 -133.838696) (xy 38.831011 -133.866582)
			(xy 38.822891 -133.921758) (xy 38.806823 -133.975165) (xy 38.783151 -134.025662) (xy 38.752378 -134.072175)
			(xy 38.715161 -134.113712) (xy 38.672293 -134.149387) (xy 38.624687 -134.178441) (xy 38.573358 -134.200253)
			(xy 38.519401 -134.214359) (xy 38.463964 -134.220459) (xy 38.40823 -134.218422) (xy 38.353387 -134.208292)
			(xy 38.300603 -134.190285) (xy 38.251003 -134.164784) (xy 38.205645 -134.132333) (xy 38.165496 -134.093624)
			(xy 38.13141 -134.049481) (xy 38.104114 -134.000846) (xy 38.084191 -133.948755) (xy 38.072065 -133.894318)
			(xy 38.067994 -133.838696) (xy 34.93897 -133.838696) (xy 38.539166 -137.438892) (xy 38.556401 -137.45699)
			(xy 38.584139 -137.498554) (xy 38.603243 -137.544727) (xy 38.612979 -137.593739) (xy 38.613588 -137.618724)
			(xy 38.613588 -144.48872) (xy 51.012924 -144.48872) (xy 51.012928 -144.434227) (xy 51.020687 -144.380288)
			(xy 51.036042 -144.328003) (xy 51.058683 -144.278435) (xy 51.088146 -144.232593) (xy 51.123834 -144.191411)
			(xy 51.165019 -144.155727) (xy 51.210863 -144.126267) (xy 51.260433 -144.103631) (xy 51.312719 -144.08828)
			(xy 51.366659 -144.080526) (xy 51.421152 -144.080526) (xy 51.475091 -144.088282) (xy 51.527377 -144.103635)
			(xy 51.576946 -144.126272) (xy 51.62279 -144.155734) (xy 51.663974 -144.191419) (xy 51.69966 -144.232602)
			(xy 51.729122 -144.278444) (xy 51.736434 -144.294455) (xy 53.058229 -144.294455) (xy 53.058229 -144.239945)
			(xy 53.065987 -144.185989) (xy 53.081345 -144.133686) (xy 53.10399 -144.084102) (xy 53.133461 -144.038245)
			(xy 53.169159 -143.997049) (xy 53.210356 -143.961353) (xy 53.256214 -143.931883) (xy 53.305799 -143.90924)
			(xy 53.358102 -143.893884) (xy 53.412059 -143.886128) (xy 53.439314 -143.885666) (xy 53.472576 -143.886375)
			(xy 53.5381 -143.897867) (xy 53.569616 -143.908526) (xy 53.583198 -143.913028) (xy 53.611739 -143.914958)
			(xy 53.639697 -143.908906) (xy 53.664884 -143.895343) (xy 53.685327 -143.875334) (xy 53.699426 -143.850443)
			(xy 53.70322 -143.836644) (xy 53.710286 -143.809161) (xy 53.73138 -143.756484) (xy 53.760045 -143.707514)
			(xy 53.795649 -143.663332) (xy 53.837407 -143.624912) (xy 53.884396 -143.593104) (xy 53.93558 -143.568608)
			(xy 53.989828 -143.551967) (xy 54.045943 -143.543547) (xy 54.074314 -143.54302) (xy 54.101567 -143.543451)
			(xy 54.155517 -143.55121) (xy 54.207814 -143.566567) (xy 54.257393 -143.589211) (xy 54.303245 -143.618679)
			(xy 54.344436 -143.654374) (xy 54.380129 -143.695566) (xy 54.409596 -143.74142) (xy 54.432238 -143.790999)
			(xy 54.447593 -143.843297) (xy 54.45535 -143.897247) (xy 54.45535 -143.951753) (xy 54.447593 -144.005703)
			(xy 54.432238 -144.058001) (xy 54.409596 -144.10758) (xy 54.380129 -144.153434) (xy 54.344436 -144.194626)
			(xy 54.303245 -144.230321) (xy 54.257393 -144.259789) (xy 54.207814 -144.282433) (xy 54.155517 -144.29779)
			(xy 54.101567 -144.305549) (xy 54.074314 -144.306036) (xy 54.041052 -144.305319) (xy 53.975529 -144.293832)
			(xy 53.944012 -144.283176) (xy 53.930421 -144.278704) (xy 53.901885 -144.276768) (xy 53.873929 -144.282814)
			(xy 53.848744 -144.296371) (xy 53.828301 -144.316375) (xy 53.814203 -144.341261) (xy 53.810408 -144.355058)
			(xy 53.803409 -144.38256) (xy 53.78231 -144.435241) (xy 53.753638 -144.484215) (xy 53.718025 -144.528399)
			(xy 53.676259 -144.566818) (xy 53.62926 -144.598624) (xy 53.578068 -144.623114) (xy 53.523811 -144.639749)
			(xy 53.467689 -144.64816) (xy 53.439314 -144.648682) (xy 53.412059 -144.648272) (xy 53.358102 -144.640516)
			(xy 53.305799 -144.62516) (xy 53.256214 -144.602517) (xy 53.210356 -144.573047) (xy 53.169159 -144.537351)
			(xy 53.133461 -144.496155) (xy 53.10399 -144.450298) (xy 53.081345 -144.400714) (xy 53.065987 -144.348411)
			(xy 53.058229 -144.294455) (xy 51.736434 -144.294455) (xy 51.751761 -144.328013) (xy 51.767116 -144.380299)
			(xy 51.774873 -144.434237) (xy 51.77536 -144.461484) (xy 51.77493 -144.486875) (xy 51.768173 -144.537207)
			(xy 51.761898 -144.561814) (xy 51.758525 -144.576472) (xy 51.759445 -144.606518) (xy 51.769069 -144.634996)
			(xy 51.786564 -144.65944) (xy 51.810415 -144.677736) (xy 51.838559 -144.688299) (xy 51.868558 -144.690215)
			(xy 51.88331 -144.68729) (xy 51.904903 -144.682524) (xy 51.948829 -144.677431) (xy 51.97094 -144.67713)
			(xy 51.998187 -144.677621) (xy 52.052126 -144.685382) (xy 52.104412 -144.700739) (xy 52.153979 -144.723381)
			(xy 52.199821 -144.752847) (xy 52.241002 -144.788536) (xy 52.276686 -144.829723) (xy 52.306145 -144.875568)
			(xy 52.32878 -144.925139) (xy 52.34413 -144.977427) (xy 52.351883 -145.031367) (xy 52.351881 -145.085861)
			(xy 52.344124 -145.139801) (xy 52.32877 -145.192087) (xy 52.306131 -145.241657) (xy 52.276669 -145.2875)
			(xy 52.240982 -145.328684) (xy 52.199798 -145.36437) (xy 52.153955 -145.393832) (xy 52.104385 -145.416471)
			(xy 52.052099 -145.431824) (xy 51.998159 -145.439581) (xy 51.943665 -145.439583) (xy 51.889725 -145.431829)
			(xy 51.837437 -145.416479) (xy 51.787866 -145.393844) (xy 51.742021 -145.364384) (xy 51.700835 -145.328701)
			(xy 51.665146 -145.287519) (xy 51.63568 -145.241678) (xy 51.613039 -145.19211) (xy 51.597681 -145.139824)
			(xy 51.589921 -145.085885) (xy 51.589432 -145.058638) (xy 51.589867 -145.033247) (xy 51.596621 -144.982916)
			(xy 51.602894 -144.958308) (xy 51.606253 -144.943646) (xy 51.605338 -144.913601) (xy 51.595718 -144.885123)
			(xy 51.578225 -144.860677) (xy 51.554375 -144.842382) (xy 51.526232 -144.83182) (xy 51.496234 -144.829906)
			(xy 51.481482 -144.832832) (xy 51.459889 -144.8376) (xy 51.415963 -144.842691) (xy 51.393852 -144.842992)
			(xy 51.366605 -144.84247) (xy 51.312667 -144.834709) (xy 51.260383 -144.81935) (xy 51.210816 -144.796707)
			(xy 51.164976 -144.767241) (xy 51.123796 -144.731551) (xy 51.088114 -144.690364) (xy 51.058657 -144.644518)
			(xy 51.036024 -144.594947) (xy 51.020675 -144.54266) (xy 51.012924 -144.48872) (xy 38.613588 -144.48872)
			(xy 38.613588 -146.75866) (xy 43.126914 -146.75866) (xy 43.127436 -146.729921) (xy 43.136063 -146.673095)
			(xy 43.153114 -146.618205) (xy 43.178206 -146.566493) (xy 43.210769 -146.51913) (xy 43.230038 -146.497802)
			(xy 43.240134 -146.486238) (xy 43.253567 -146.458655) (xy 43.258189 -146.428324) (xy 43.253582 -146.397991)
			(xy 43.240162 -146.370401) (xy 43.230038 -146.358864) (xy 43.21077 -146.337534) (xy 43.178203 -146.290173)
			(xy 43.15311 -146.238462) (xy 43.136059 -146.183572) (xy 43.127435 -146.126745) (xy 43.126914 -146.098006)
			(xy 43.12738 -146.070636) (xy 43.135197 -146.016457) (xy 43.150686 -145.963953) (xy 43.173528 -145.914206)
			(xy 43.203253 -145.86824) (xy 43.220894 -145.847308) (xy 43.230126 -145.835977) (xy 43.242304 -145.80942)
			(xy 43.246478 -145.780505) (xy 43.242307 -145.751588) (xy 43.23013 -145.725031) (xy 43.220894 -145.713704)
			(xy 43.203242 -145.692782) (xy 43.173533 -145.646806) (xy 43.150699 -145.597056) (xy 43.135211 -145.544553)
			(xy 43.127386 -145.490376) (xy 43.126914 -145.463006) (xy 43.127361 -145.435752) (xy 43.135118 -145.3818)
			(xy 43.150474 -145.3295) (xy 43.173117 -145.279919) (xy 43.202587 -145.234064) (xy 43.238282 -145.192871)
			(xy 43.279477 -145.157177) (xy 43.325333 -145.12771) (xy 43.374915 -145.105068) (xy 43.427215 -145.089714)
			(xy 43.481168 -145.08196) (xy 43.508422 -145.081498) (xy 43.535793 -145.081952) (xy 43.589972 -145.089773)
			(xy 43.642476 -145.105265) (xy 43.692222 -145.128109) (xy 43.738189 -145.157836) (xy 43.75912 -145.175478)
			(xy 43.770448 -145.184714) (xy 43.797005 -145.19689) (xy 43.825922 -145.201063) (xy 43.854839 -145.19689)
			(xy 43.881396 -145.184714) (xy 43.892724 -145.175478) (xy 43.913671 -145.157858) (xy 43.95964 -145.128144)
			(xy 44.009384 -145.105305) (xy 44.061881 -145.089809) (xy 44.116054 -145.081975) (xy 44.143422 -145.081498)
			(xy 44.172161 -145.082009) (xy 44.228989 -145.090635) (xy 44.28388 -145.107688) (xy 44.335592 -145.132782)
			(xy 44.382954 -145.16535) (xy 44.40428 -145.184622) (xy 44.415814 -145.194694) (xy 44.44336 -145.208036)
			(xy 44.473622 -145.212621) (xy 44.503884 -145.208036) (xy 44.53143 -145.194694) (xy 44.542964 -145.184622)
			(xy 44.564291 -145.165352) (xy 44.611654 -145.132787) (xy 44.663365 -145.107696) (xy 44.718256 -145.090646)
			(xy 44.775083 -145.082024) (xy 44.832561 -145.082024) (xy 44.889388 -145.090646) (xy 44.944279 -145.107696)
			(xy 44.99599 -145.132787) (xy 45.043353 -145.165352) (xy 45.06468 -145.184622) (xy 45.076214 -145.194694)
			(xy 45.10376 -145.208036) (xy 45.134022 -145.212621) (xy 45.164284 -145.208036) (xy 45.19183 -145.194694)
			(xy 45.203364 -145.184622) (xy 45.224691 -145.165352) (xy 45.272054 -145.132787) (xy 45.323765 -145.107696)
			(xy 45.378656 -145.090646) (xy 45.435483 -145.082024) (xy 45.492961 -145.082024) (xy 45.549788 -145.090646)
			(xy 45.604679 -145.107696) (xy 45.65639 -145.132787) (xy 45.703753 -145.165352) (xy 45.72508 -145.184622)
			(xy 45.736614 -145.194694) (xy 45.76416 -145.208036) (xy 45.794422 -145.212621) (xy 45.824684 -145.208036)
			(xy 45.85223 -145.194694) (xy 45.863764 -145.184622) (xy 45.885091 -145.165352) (xy 45.932454 -145.132787)
			(xy 45.984165 -145.107696) (xy 46.039056 -145.090646) (xy 46.095883 -145.082024) (xy 46.153361 -145.082024)
			(xy 46.210188 -145.090646) (xy 46.265079 -145.107696) (xy 46.31679 -145.132787) (xy 46.364153 -145.165352)
			(xy 46.38548 -145.184622) (xy 46.397014 -145.194694) (xy 46.42456 -145.208036) (xy 46.454822 -145.212621)
			(xy 46.485084 -145.208036) (xy 46.51263 -145.194694) (xy 46.524164 -145.184622) (xy 46.545491 -145.165352)
			(xy 46.592854 -145.132787) (xy 46.644565 -145.107696) (xy 46.699456 -145.090646) (xy 46.756283 -145.082024)
			(xy 46.813761 -145.082024) (xy 46.870588 -145.090646) (xy 46.925479 -145.107696) (xy 46.97719 -145.132787)
			(xy 47.024553 -145.165352) (xy 47.04588 -145.184622) (xy 47.057414 -145.194694) (xy 47.08496 -145.208036)
			(xy 47.115222 -145.212621) (xy 47.145484 -145.208036) (xy 47.17303 -145.194694) (xy 47.184564 -145.184622)
			(xy 47.20588 -145.165338) (xy 47.253245 -145.132774) (xy 47.30496 -145.107685) (xy 47.359853 -145.090637)
			(xy 47.416682 -145.082017) (xy 47.445422 -145.081498) (xy 47.472674 -145.081957) (xy 47.526623 -145.089717)
			(xy 47.578919 -145.105075) (xy 47.628496 -145.127719) (xy 47.674347 -145.157189) (xy 47.715537 -145.192883)
			(xy 47.751228 -145.234076) (xy 47.780694 -145.279928) (xy 47.803335 -145.329508) (xy 47.818689 -145.381804)
			(xy 47.826445 -145.435754) (xy 47.82693 -145.463006) (xy 47.826467 -145.489242) (xy 47.819271 -145.541217)
			(xy 47.805017 -145.591715) (xy 47.783973 -145.639781) (xy 47.756538 -145.684508) (xy 47.723228 -145.725051)
			(xy 47.704248 -145.743168) (xy 47.696871 -145.750692) (xy 47.688442 -145.769979) (xy 47.688444 -145.791029)
			(xy 47.696876 -145.810315) (xy 47.704248 -145.817844) (xy 47.725584 -145.83918) (xy 47.733113 -145.846552)
			(xy 47.752398 -145.854983) (xy 47.773446 -145.854983) (xy 47.792731 -145.846552) (xy 47.80026 -145.83918)
			(xy 47.818371 -145.820192) (xy 47.858911 -145.786874) (xy 47.903638 -145.759432) (xy 47.951706 -145.738384)
			(xy 48.002206 -145.724128) (xy 48.054185 -145.716934) (xy 48.080422 -145.716498) (xy 48.107674 -145.716957)
			(xy 48.161623 -145.724717) (xy 48.213919 -145.740075) (xy 48.263496 -145.762719) (xy 48.309347 -145.792189)
			(xy 48.350537 -145.827883) (xy 48.386228 -145.869076) (xy 48.400993 -145.892052) (xy 49.996289 -145.892052)
			(xy 49.996289 -145.837548) (xy 50.004047 -145.783598) (xy 50.019404 -145.731301) (xy 50.042047 -145.681722)
			(xy 50.071517 -145.635871) (xy 50.107212 -145.594681) (xy 50.148406 -145.55899) (xy 50.194261 -145.529526)
			(xy 50.243842 -145.506888) (xy 50.296141 -145.491537) (xy 50.350092 -145.483786) (xy 50.377344 -145.483326)
			(xy 50.407031 -145.483911) (xy 50.465689 -145.493102) (xy 50.522215 -145.511271) (xy 50.575243 -145.537978)
			(xy 50.623492 -145.57258) (xy 50.665798 -145.614239) (xy 50.683922 -145.637758) (xy 50.692348 -145.648365)
			(xy 50.713661 -145.665072) (xy 50.738615 -145.675591) (xy 50.765456 -145.679181) (xy 50.792297 -145.675591)
			(xy 50.817251 -145.665072) (xy 50.838564 -145.648365) (xy 50.84699 -145.637758) (xy 50.86512 -145.614243)
			(xy 50.907427 -145.572585) (xy 50.955675 -145.537982) (xy 51.008701 -145.511271) (xy 51.065225 -145.493095)
			(xy 51.123881 -145.483893) (xy 51.153568 -145.483326) (xy 51.180825 -145.483719) (xy 51.234784 -145.491473)
			(xy 51.28709 -145.506827) (xy 51.336679 -145.52947) (xy 51.38254 -145.55894) (xy 51.423741 -145.594637)
			(xy 51.459441 -145.635834) (xy 51.488915 -145.681693) (xy 51.511561 -145.73128) (xy 51.52692 -145.783585)
			(xy 51.534679 -145.837543) (xy 51.534679 -145.892057) (xy 51.52692 -145.946015) (xy 51.511561 -145.99832)
			(xy 51.488915 -146.047907) (xy 51.459441 -146.093766) (xy 51.423741 -146.134963) (xy 51.38254 -146.17066)
			(xy 51.336679 -146.20013) (xy 51.28709 -146.222773) (xy 51.234784 -146.238127) (xy 51.180825 -146.245881)
			(xy 51.153568 -146.246342) (xy 51.123881 -146.24576) (xy 51.065222 -146.23657) (xy 51.008695 -146.218402)
			(xy 50.955667 -146.191694) (xy 50.907418 -146.157091) (xy 50.865114 -146.11543) (xy 50.84699 -146.09191)
			(xy 50.838564 -146.081303) (xy 50.817251 -146.064596) (xy 50.792297 -146.054077) (xy 50.765456 -146.050487)
			(xy 50.738615 -146.054077) (xy 50.713661 -146.064596) (xy 50.692348 -146.081303) (xy 50.683922 -146.09191)
			(xy 50.665776 -146.115412) (xy 50.623474 -146.157073) (xy 50.575229 -146.191678) (xy 50.522206 -146.218392)
			(xy 50.465685 -146.23657) (xy 50.40703 -146.245774) (xy 50.377344 -146.246342) (xy 50.350092 -146.245814)
			(xy 50.296141 -146.238063) (xy 50.243842 -146.222712) (xy 50.194261 -146.200074) (xy 50.148406 -146.17061)
			(xy 50.107212 -146.134919) (xy 50.071517 -146.093729) (xy 50.042047 -146.047878) (xy 50.019404 -145.998299)
			(xy 50.004047 -145.946002) (xy 49.996289 -145.892052) (xy 48.400993 -145.892052) (xy 48.415694 -145.914928)
			(xy 48.438335 -145.964508) (xy 48.453689 -146.016804) (xy 48.461445 -146.070754) (xy 48.46193 -146.098006)
			(xy 48.461402 -146.126745) (xy 48.452779 -146.183571) (xy 48.43573 -146.238462) (xy 48.410639 -146.290174)
			(xy 48.378076 -146.337537) (xy 48.358806 -146.358864) (xy 48.348699 -146.3704) (xy 48.335361 -146.398008)
			(xy 48.330783 -146.428324) (xy 48.335375 -146.458639) (xy 48.348727 -146.48624) (xy 48.358806 -146.497802)
			(xy 48.378048 -146.519154) (xy 48.41062 -146.566508) (xy 48.435719 -146.618213) (xy 48.452776 -146.673099)
			(xy 48.461405 -146.729923) (xy 48.46193 -146.75866) (xy 48.461408 -146.785911) (xy 48.453657 -146.839859)
			(xy 48.438307 -146.892154) (xy 48.415671 -146.941732) (xy 48.386209 -146.987585) (xy 48.350521 -147.028777)
			(xy 48.309334 -147.064472) (xy 48.263487 -147.093941) (xy 48.213912 -147.116585) (xy 48.161619 -147.131943)
			(xy 48.107673 -147.139703) (xy 48.080422 -147.140168) (xy 48.053052 -147.139697) (xy 47.998873 -147.131881)
			(xy 47.946369 -147.116394) (xy 47.896622 -147.093553) (xy 47.850656 -147.063829) (xy 47.829724 -147.046188)
			(xy 47.818396 -147.036952) (xy 47.791839 -147.024776) (xy 47.762922 -147.020603) (xy 47.734005 -147.024776)
			(xy 47.707448 -147.036952) (xy 47.69612 -147.046188) (xy 47.67519 -147.063829) (xy 47.629217 -147.093541)
			(xy 47.579469 -147.116377) (xy 47.526968 -147.131867) (xy 47.472791 -147.139695) (xy 47.445422 -147.140168)
			(xy 47.416685 -147.139613) (xy 47.359859 -147.130995) (xy 47.30497 -147.113951) (xy 47.253257 -147.088867)
			(xy 47.205893 -147.05631) (xy 47.184564 -147.037044) (xy 47.17303 -147.026972) (xy 47.145484 -147.01363)
			(xy 47.115222 -147.009045) (xy 47.08496 -147.01363) (xy 47.057414 -147.026972) (xy 47.04588 -147.037044)
			(xy 47.024553 -147.056314) (xy 46.97719 -147.088879) (xy 46.925479 -147.11397) (xy 46.870588 -147.13102)
			(xy 46.813761 -147.139642) (xy 46.756283 -147.139642) (xy 46.699456 -147.13102) (xy 46.644565 -147.11397)
			(xy 46.592854 -147.088879) (xy 46.545491 -147.056314) (xy 46.524164 -147.037044) (xy 46.51263 -147.026972)
			(xy 46.485084 -147.01363) (xy 46.454822 -147.009045) (xy 46.42456 -147.01363) (xy 46.397014 -147.026972)
			(xy 46.38548 -147.037044) (xy 46.364153 -147.056314) (xy 46.31679 -147.088879) (xy 46.265079 -147.11397)
			(xy 46.210188 -147.13102) (xy 46.153361 -147.139642) (xy 46.095883 -147.139642) (xy 46.039056 -147.13102)
			(xy 45.984165 -147.11397) (xy 45.932454 -147.088879) (xy 45.885091 -147.056314) (xy 45.863764 -147.037044)
			(xy 45.85223 -147.026972) (xy 45.824684 -147.01363) (xy 45.794422 -147.009045) (xy 45.76416 -147.01363)
			(xy 45.736614 -147.026972) (xy 45.72508 -147.037044) (xy 45.703753 -147.056314) (xy 45.65639 -147.088879)
			(xy 45.604679 -147.11397) (xy 45.549788 -147.13102) (xy 45.492961 -147.139642) (xy 45.435483 -147.139642)
			(xy 45.378656 -147.13102) (xy 45.323765 -147.11397) (xy 45.272054 -147.088879) (xy 45.224691 -147.056314)
			(xy 45.203364 -147.037044) (xy 45.19183 -147.026972) (xy 45.164284 -147.01363) (xy 45.134022 -147.009045)
			(xy 45.10376 -147.01363) (xy 45.076214 -147.026972) (xy 45.06468 -147.037044) (xy 45.043353 -147.056314)
			(xy 44.99599 -147.088879) (xy 44.944279 -147.11397) (xy 44.889388 -147.13102) (xy 44.832561 -147.139642)
			(xy 44.775083 -147.139642) (xy 44.718256 -147.13102) (xy 44.663365 -147.11397) (xy 44.611654 -147.088879)
			(xy 44.564291 -147.056314) (xy 44.542964 -147.037044) (xy 44.53143 -147.026972) (xy 44.503884 -147.01363)
			(xy 44.473622 -147.009045) (xy 44.44336 -147.01363) (xy 44.415814 -147.026972) (xy 44.40428 -147.037044)
			(xy 44.382941 -147.056301) (xy 44.335583 -147.08887) (xy 44.283874 -147.113965) (xy 44.228986 -147.131019)
			(xy 44.17216 -147.139645) (xy 44.143422 -147.140168) (xy 44.116052 -147.139697) (xy 44.061873 -147.131881)
			(xy 44.009369 -147.116394) (xy 43.959622 -147.093553) (xy 43.913656 -147.063829) (xy 43.892724 -147.046188)
			(xy 43.881396 -147.036952) (xy 43.854839 -147.024776) (xy 43.825922 -147.020603) (xy 43.797005 -147.024776)
			(xy 43.770448 -147.036952) (xy 43.75912 -147.046188) (xy 43.73819 -147.063829) (xy 43.692217 -147.093541)
			(xy 43.642469 -147.116377) (xy 43.589968 -147.131867) (xy 43.535791 -147.139695) (xy 43.508422 -147.140168)
			(xy 43.481168 -147.139724) (xy 43.427214 -147.131969) (xy 43.374914 -147.116614) (xy 43.325331 -147.093971)
			(xy 43.279476 -147.064502) (xy 43.238282 -147.028806) (xy 43.202588 -146.98761) (xy 43.17312 -146.941753)
			(xy 43.15048 -146.89217) (xy 43.135127 -146.839868) (xy 43.127375 -146.785914) (xy 43.126914 -146.75866)
			(xy 38.613588 -146.75866) (xy 38.613588 -147.977451) (xy 50.206652 -147.977451) (xy 50.206652 -147.922949)
			(xy 50.214408 -147.869001) (xy 50.229762 -147.816707) (xy 50.252401 -147.767129) (xy 50.281865 -147.721277)
			(xy 50.317554 -147.680086) (xy 50.358742 -147.644392) (xy 50.40459 -147.614922) (xy 50.454165 -147.592277)
			(xy 50.506458 -147.576917) (xy 50.560405 -147.569155) (xy 50.587656 -147.568666) (xy 50.617561 -147.569202)
			(xy 50.67664 -147.578514) (xy 50.705258 -147.587208) (xy 50.719167 -147.591239) (xy 50.748099 -147.592148)
			(xy 50.776118 -147.584883) (xy 50.800963 -147.570032) (xy 50.820629 -147.548792) (xy 50.833527 -147.522879)
			(xy 50.836576 -147.508722) (xy 50.843165 -147.475884) (xy 50.866284 -147.413031) (xy 50.88255 -147.383754)
			(xy 50.889618 -147.370804) (xy 50.896647 -147.342161) (xy 50.895197 -147.312704) (xy 50.885389 -147.28489)
			(xy 50.868042 -147.261039) (xy 50.844601 -147.243141) (xy 50.830988 -147.23745) (xy 50.80422 -147.226735)
			(xy 50.753979 -147.19845) (xy 50.70857 -147.162922) (xy 50.669027 -147.120963) (xy 50.636253 -147.073528)
			(xy 50.610993 -147.0217) (xy 50.593825 -146.96666) (xy 50.585139 -146.909662) (xy 50.584608 -146.880834)
			(xy 50.585094 -146.853583) (xy 50.59285 -146.799635) (xy 50.608205 -146.74734) (xy 50.630847 -146.697763)
			(xy 50.660313 -146.651913) (xy 50.696004 -146.610722) (xy 50.737195 -146.575031) (xy 50.783045 -146.545565)
			(xy 50.832622 -146.522923) (xy 50.884917 -146.507568) (xy 50.938865 -146.499812) (xy 50.993367 -146.499812)
			(xy 51.047315 -146.507568) (xy 51.09961 -146.522923) (xy 51.149187 -146.545565) (xy 51.195037 -146.575031)
			(xy 51.236228 -146.610722) (xy 51.271919 -146.651913) (xy 51.301385 -146.697763) (xy 51.324027 -146.74734)
			(xy 51.339382 -146.799635) (xy 51.347138 -146.853583) (xy 51.347624 -146.880834) (xy 51.347239 -146.90607)
			(xy 51.340617 -146.956104) (xy 51.32744 -147.004824) (xy 51.30794 -147.051376) (xy 51.295554 -147.073366)
			(xy 51.28846 -147.086303) (xy 51.281434 -147.114951) (xy 51.282888 -147.144412) (xy 51.292701 -147.172229)
			(xy 51.310054 -147.196081) (xy 51.3335 -147.21398) (xy 51.347116 -147.21967) (xy 51.373892 -147.230366)
			(xy 51.424134 -147.258654) (xy 51.469543 -147.294184) (xy 51.509085 -147.336146) (xy 51.541859 -147.383583)
			(xy 51.567117 -147.435414) (xy 51.584283 -147.490457) (xy 51.592966 -147.547457) (xy 51.593496 -147.576286)
			(xy 51.593032 -147.603539) (xy 51.585276 -147.657491) (xy 51.569921 -147.709789) (xy 51.54728 -147.75937)
			(xy 51.517812 -147.805224) (xy 51.482118 -147.846417) (xy 51.440925 -147.882111) (xy 51.395072 -147.911579)
			(xy 51.345491 -147.934221) (xy 51.293193 -147.949576) (xy 51.239241 -147.957331) (xy 51.211988 -147.957794)
			(xy 51.182083 -147.957273) (xy 51.123003 -147.947951) (xy 51.094386 -147.939252) (xy 51.080457 -147.935302)
			(xy 51.051539 -147.934385) (xy 51.02353 -147.941636) (xy 50.998691 -147.956471) (xy 50.979026 -147.977693)
			(xy 50.966122 -148.003589) (xy 50.963068 -148.017738) (xy 50.957919 -148.043816) (xy 50.941346 -148.09432)
			(xy 50.917921 -148.142034) (xy 50.888096 -148.186032) (xy 50.852451 -148.225463) (xy 50.811676 -148.259561)
			(xy 50.76656 -148.287667) (xy 50.717979 -148.309236) (xy 50.666873 -148.323849) (xy 50.614233 -148.331225)
			(xy 50.587656 -148.331682) (xy 50.560405 -148.331245) (xy 50.506458 -148.323483) (xy 50.454165 -148.308123)
			(xy 50.40459 -148.285478) (xy 50.358742 -148.256008) (xy 50.317554 -148.220314) (xy 50.281865 -148.179123)
			(xy 50.252401 -148.133271) (xy 50.229762 -148.083693) (xy 50.214408 -148.031399) (xy 50.206652 -147.977451)
			(xy 38.613588 -147.977451) (xy 38.613588 -150.44547) (xy 50.99304 -150.44547) (xy 50.993427 -150.418214)
			(xy 51.001189 -150.364258) (xy 51.016552 -150.311956) (xy 51.039201 -150.262372) (xy 51.068677 -150.216517)
			(xy 51.104379 -150.175323) (xy 51.145579 -150.13963) (xy 51.191441 -150.110164) (xy 51.241029 -150.087524)
			(xy 51.293334 -150.072173) (xy 51.347292 -150.064422) (xy 51.374548 -150.063962) (xy 51.402122 -150.064442)
			(xy 51.456695 -150.072388) (xy 51.509556 -150.088109) (xy 51.559603 -150.111276) (xy 51.605792 -150.141408)
			(xy 51.647163 -150.177875) (xy 51.665378 -150.198582) (xy 51.675276 -150.20948) (xy 51.699926 -150.225555)
			(xy 51.728134 -150.233939) (xy 51.757562 -150.233939) (xy 51.78577 -150.225555) (xy 51.81042 -150.20948)
			(xy 51.820318 -150.198582) (xy 51.838512 -150.177855) (xy 51.879885 -150.141387) (xy 51.926079 -150.111257)
			(xy 51.97613 -150.088094) (xy 52.028995 -150.072381) (xy 52.083572 -150.064445) (xy 52.111148 -150.063962)
			(xy 52.137649 -150.064415) (xy 52.19014 -150.071762) (xy 52.241107 -150.086307) (xy 52.289569 -150.10777)
			(xy 52.334592 -150.135737) (xy 52.355242 -150.152354) (xy 52.367396 -150.161784) (xy 52.395794 -150.173573)
			(xy 52.426411 -150.176397) (xy 52.456486 -150.170003) (xy 52.483306 -150.154967) (xy 52.504451 -150.132645)
			(xy 52.511706 -150.11908) (xy 52.523817 -150.095395) (xy 52.553737 -150.051413) (xy 52.589605 -150.01213)
			(xy 52.630693 -149.978345) (xy 52.653184 -149.96414) (xy 52.665431 -149.956248) (xy 52.685104 -149.934769)
			(xy 52.697907 -149.908607) (xy 52.702796 -149.879894) (xy 52.699373 -149.850969) (xy 52.694078 -149.837394)
			(xy 52.684593 -149.814182) (xy 52.671241 -149.76585) (xy 52.664511 -149.716161) (xy 52.664106 -149.69109)
			(xy 52.66454 -149.666021) (xy 52.671286 -149.616338) (xy 52.684614 -149.568004) (xy 52.694078 -149.544786)
			(xy 52.699333 -149.531207) (xy 52.702713 -149.502299) (xy 52.697811 -149.47361) (xy 52.685024 -149.447464)
			(xy 52.665389 -149.42598) (xy 52.653184 -149.41804) (xy 52.630024 -149.403514) (xy 52.587899 -149.368668)
			(xy 52.551317 -149.328041) (xy 52.521063 -149.282506) (xy 52.497786 -149.233039) (xy 52.481986 -149.180703)
			(xy 52.474001 -149.126619) (xy 52.474003 -149.07195) (xy 52.481993 -149.017867) (xy 52.497797 -148.965532)
			(xy 52.521079 -148.916067) (xy 52.551336 -148.870534) (xy 52.587922 -148.829911) (xy 52.630049 -148.795068)
			(xy 52.653184 -148.7805) (xy 52.66539 -148.772551) (xy 52.685063 -148.751088) (xy 52.697871 -148.724941)
			(xy 52.702771 -148.696241) (xy 52.699363 -148.667326) (xy 52.694078 -148.653754) (xy 52.684581 -148.630547)
			(xy 52.671233 -148.582213) (xy 52.664508 -148.532522) (xy 52.664106 -148.50745) (xy 52.664627 -148.479565)
			(xy 52.672939 -148.424418) (xy 52.689377 -148.371126) (xy 52.713575 -148.32088) (xy 52.744991 -148.274801)
			(xy 52.782924 -148.233919) (xy 52.826526 -148.199147) (xy 52.874824 -148.171262) (xy 52.926739 -148.150887)
			(xy 52.98111 -148.138477) (xy 53.036724 -148.13431) (xy 53.092338 -148.138477) (xy 53.146709 -148.150887)
			(xy 53.198624 -148.171262) (xy 53.246922 -148.199147) (xy 53.290524 -148.233919) (xy 53.328457 -148.274801)
			(xy 53.359873 -148.32088) (xy 53.384071 -148.371126) (xy 53.400509 -148.424418) (xy 53.408821 -148.479565)
			(xy 53.409342 -148.50745) (xy 53.408875 -148.534782) (xy 53.400906 -148.588863) (xy 53.385118 -148.641198)
			(xy 53.36185 -148.690662) (xy 53.331601 -148.736195) (xy 53.295022 -148.776817) (xy 53.252897 -148.811655)
			(xy 53.229764 -148.82622) (xy 53.217537 -148.834138) (xy 53.19787 -148.855612) (xy 53.185068 -148.881767)
			(xy 53.180173 -148.910472) (xy 53.183584 -148.939392) (xy 53.18887 -148.952966) (xy 53.198345 -148.976181)
			(xy 53.211701 -149.024512) (xy 53.218435 -149.074199) (xy 53.218842 -149.09927) (xy 53.218431 -149.12434)
			(xy 53.211677 -149.174023) (xy 53.198339 -149.222357) (xy 53.18887 -149.245574) (xy 53.183624 -149.259151)
			(xy 53.180262 -149.288051) (xy 53.185173 -149.316729) (xy 53.197961 -149.342863) (xy 53.217591 -149.364338)
			(xy 53.229764 -149.37232) (xy 53.252885 -149.386903) (xy 53.295003 -149.421747) (xy 53.331579 -149.462369)
			(xy 53.361829 -149.507898) (xy 53.385103 -149.557358) (xy 53.400902 -149.609688) (xy 53.408888 -149.663764)
			(xy 53.408889 -149.718426) (xy 53.400905 -149.772502) (xy 53.385107 -149.824832) (xy 53.361834 -149.874292)
			(xy 53.331585 -149.919823) (xy 53.29501 -149.960446) (xy 53.252893 -149.995291) (xy 53.229764 -150.00986)
			(xy 53.217509 -150.017739) (xy 53.197842 -150.039225) (xy 53.185043 -150.06539) (xy 53.180156 -150.094104)
			(xy 53.183577 -150.12303) (xy 53.18887 -150.136606) (xy 53.198357 -150.159817) (xy 53.211708 -150.208149)
			(xy 53.218438 -150.257838) (xy 53.218842 -150.28291) (xy 53.21837 -150.309752) (xy 53.210665 -150.362881)
			(xy 53.195416 -150.414354) (xy 53.172938 -150.463106) (xy 53.143697 -150.508127) (xy 53.108298 -150.548487)
			(xy 53.067473 -150.583349) (xy 53.022069 -150.611993) (xy 52.973024 -150.633824) (xy 52.947316 -150.641558)
			(xy 52.932841 -150.646276) (xy 52.907286 -150.662788) (xy 52.887726 -150.686092) (xy 52.875894 -150.714122)
			(xy 52.87284 -150.744393) (xy 52.878835 -150.774222) (xy 52.885594 -150.787862) (xy 52.900228 -150.816008)
			(xy 52.920955 -150.875959) (xy 52.931453 -150.938517) (xy 52.932076 -150.970234) (xy 52.931855 -150.988253)
			(xy 52.928421 -151.024128) (xy 52.925218 -151.041862) (xy 52.922936 -151.057077) (xy 52.926453 -151.087622)
			(xy 52.938901 -151.115736) (xy 52.959153 -151.138871) (xy 52.985373 -151.154931) (xy 53.000148 -151.15921)
			(xy 53.027191 -151.166611) (xy 53.078917 -151.188241) (xy 53.126922 -151.217205) (xy 53.170174 -151.25288)
			(xy 53.207741 -151.294499) (xy 53.238815 -151.341165) (xy 53.262728 -151.391876) (xy 53.278965 -151.44554)
			(xy 53.287177 -151.501001) (xy 53.287676 -151.529034) (xy 53.287254 -151.556288) (xy 53.279492 -151.610239)
			(xy 53.264131 -151.662537) (xy 53.241483 -151.712117) (xy 53.21201 -151.757968) (xy 53.176312 -151.799159)
			(xy 53.135115 -151.83485) (xy 53.089259 -151.864315) (xy 53.039675 -151.886954) (xy 52.987375 -151.902306)
			(xy 52.933422 -151.910058) (xy 52.906168 -151.910542) (xy 52.878594 -151.91005) (xy 52.824022 -151.902105)
			(xy 52.771161 -151.886387) (xy 52.721115 -151.863222) (xy 52.674925 -151.833093) (xy 52.633554 -151.796628)
			(xy 52.615338 -151.775922) (xy 52.60544 -151.765024) (xy 52.58079 -151.748949) (xy 52.552582 -151.740565)
			(xy 52.523154 -151.740565) (xy 52.494946 -151.748949) (xy 52.470296 -151.765024) (xy 52.460398 -151.775922)
			(xy 52.442183 -151.796628) (xy 52.400812 -151.833093) (xy 52.354622 -151.86322) (xy 52.304575 -151.886383)
			(xy 52.251714 -151.902099) (xy 52.197142 -151.910039) (xy 52.141994 -151.910039) (xy 52.087422 -151.902099)
			(xy 52.034561 -151.886383) (xy 51.984514 -151.86322) (xy 51.938324 -151.833093) (xy 51.896953 -151.796628)
			(xy 51.878738 -151.775922) (xy 51.86884 -151.765024) (xy 51.84419 -151.748949) (xy 51.815982 -151.740565)
			(xy 51.786554 -151.740565) (xy 51.758346 -151.748949) (xy 51.733696 -151.765024) (xy 51.723798 -151.775922)
			(xy 51.705596 -151.796642) (xy 51.664225 -151.83311) (xy 51.618033 -151.863241) (xy 51.567983 -151.886405)
			(xy 51.515119 -151.90212) (xy 51.460543 -151.910058) (xy 51.432968 -151.910542) (xy 51.405718 -151.910052)
			(xy 51.351772 -151.902292) (xy 51.299479 -151.886935) (xy 51.249904 -151.864292) (xy 51.204055 -151.834826)
			(xy 51.162866 -151.799135) (xy 51.127175 -151.757946) (xy 51.097709 -151.712098) (xy 51.075066 -151.662523)
			(xy 51.059708 -151.61023) (xy 51.051948 -151.556284) (xy 51.05146 -151.529034) (xy 51.052043 -151.501181)
			(xy 51.060161 -151.44607) (xy 51.0762 -151.392722) (xy 51.09982 -151.342272) (xy 51.130519 -151.295788)
			(xy 51.167647 -151.254258) (xy 51.210414 -151.218563) (xy 51.257914 -151.189461) (xy 51.309138 -151.167569)
			(xy 51.33594 -151.159972) (xy 51.350063 -151.155719) (xy 51.375204 -151.14032) (xy 51.394916 -151.118396)
			(xy 51.407566 -151.091764) (xy 51.412104 -151.062632) (xy 51.410616 -151.047958) (xy 51.408945 -151.034942)
			(xy 51.407166 -151.008757) (xy 51.40706 -150.995634) (xy 51.407158 -150.981485) (xy 51.409189 -150.953262)
			(xy 51.411124 -150.939246) (xy 51.412683 -150.925896) (xy 51.409585 -150.899209) (xy 51.39962 -150.874259)
			(xy 51.38348 -150.852781) (xy 51.362288 -150.836267) (xy 51.337516 -150.825867) (xy 51.324256 -150.823676)
			(xy 51.297113 -150.81953) (xy 51.244287 -150.804561) (xy 51.194152 -150.782174) (xy 51.147744 -150.752832)
			(xy 51.106021 -150.717141) (xy 51.069844 -150.675838) (xy 51.039961 -150.629777) (xy 51.016989 -150.579907)
			(xy 51.001402 -150.52726) (xy 50.993522 -150.472923) (xy 50.99304 -150.44547) (xy 38.613588 -150.44547)
			(xy 38.613588 -150.470108) (xy 39.788351 -151.644871) (xy 43.782962 -151.644871) (xy 43.786968 -151.589723)
			(xy 43.798892 -151.535731) (xy 43.818485 -151.484026) (xy 43.845337 -151.435691) (xy 43.878885 -151.391738)
			(xy 43.898312 -151.372062) (xy 43.907656 -151.362295) (xy 43.921334 -151.338994) (xy 43.928423 -151.312922)
			(xy 43.928426 -151.285903) (xy 43.921344 -151.259829) (xy 43.907671 -151.236525) (xy 43.898312 -151.226774)
			(xy 43.880473 -151.208774) (xy 43.849246 -151.16886) (xy 43.823579 -151.125162) (xy 43.803922 -151.078452)
			(xy 43.790624 -151.029549) (xy 43.783917 -150.979317) (xy 43.783504 -150.953978) (xy 43.783957 -150.926726)
			(xy 43.791717 -150.872776) (xy 43.807076 -150.82048) (xy 43.82972 -150.770902) (xy 43.85919 -150.725051)
			(xy 43.894885 -150.683861) (xy 43.936078 -150.64817) (xy 43.981932 -150.618704) (xy 44.031512 -150.596064)
			(xy 44.083809 -150.58071) (xy 44.13776 -150.572955) (xy 44.165012 -150.57247) (xy 44.194271 -150.573037)
			(xy 44.252103 -150.581981) (xy 44.307894 -150.599642) (xy 44.360337 -150.625607) (xy 44.408206 -150.659268)
			(xy 44.42968 -150.67915) (xy 44.439987 -150.688465) (xy 44.464413 -150.701673) (xy 44.491499 -150.707794)
			(xy 44.519231 -150.706373) (xy 44.545549 -150.697515) (xy 44.568497 -150.681879) (xy 44.577762 -150.67153)
			(xy 44.596006 -150.650711) (xy 44.637408 -150.613972) (xy 44.683688 -150.583606) (xy 44.733873 -150.560253)
			(xy 44.786908 -150.544404) (xy 44.841678 -150.536392) (xy 44.869354 -150.535894) (xy 44.896723 -150.536388)
			(xy 44.950901 -150.5442) (xy 45.003404 -150.559682) (xy 45.053151 -150.582518) (xy 45.099119 -150.612236)
			(xy 45.120052 -150.629874) (xy 45.13138 -150.63911) (xy 45.157937 -150.651286) (xy 45.186854 -150.655459)
			(xy 45.215771 -150.651286) (xy 45.242328 -150.63911) (xy 45.253656 -150.629874) (xy 45.274589 -150.612233)
			(xy 45.320557 -150.582509) (xy 45.370303 -150.559663) (xy 45.422805 -150.544167) (xy 45.476983 -150.536338)
			(xy 45.531725 -150.536338) (xy 45.585903 -150.544167) (xy 45.638405 -150.559663) (xy 45.688151 -150.582509)
			(xy 45.734119 -150.612233) (xy 45.755052 -150.629874) (xy 45.76638 -150.63911) (xy 45.792937 -150.651286)
			(xy 45.821854 -150.655459) (xy 45.850771 -150.651286) (xy 45.877328 -150.63911) (xy 45.888656 -150.629874)
			(xy 45.909589 -150.612233) (xy 45.955557 -150.582509) (xy 46.005303 -150.559663) (xy 46.057805 -150.544167)
			(xy 46.111983 -150.536338) (xy 46.166725 -150.536338) (xy 46.220903 -150.544167) (xy 46.273405 -150.559663)
			(xy 46.323151 -150.582509) (xy 46.369119 -150.612233) (xy 46.390052 -150.629874) (xy 46.40138 -150.63911)
			(xy 46.427937 -150.651286) (xy 46.456854 -150.655459) (xy 46.485771 -150.651286) (xy 46.512328 -150.63911)
			(xy 46.523656 -150.629874) (xy 46.54459 -150.612238) (xy 46.590563 -150.582527) (xy 46.64031 -150.55969)
			(xy 46.69281 -150.544199) (xy 46.746985 -150.536369) (xy 46.774354 -150.535894) (xy 46.804152 -150.536484)
			(xy 46.863022 -150.545758) (xy 46.919734 -150.56407) (xy 46.972911 -150.590976) (xy 47.021258 -150.625822)
			(xy 47.042832 -150.646384) (xy 47.054372 -150.657021) (xy 47.082273 -150.671355) (xy 47.113206 -150.676557)
			(xy 47.144261 -150.672139) (xy 47.172516 -150.658516) (xy 47.18431 -150.648162) (xy 47.205669 -150.628715)
			(xy 47.25316 -150.595835) (xy 47.305067 -150.570493) (xy 47.360201 -150.553269) (xy 47.417303 -150.544556)
			(xy 47.446184 -150.544022) (xy 47.473438 -150.54447) (xy 47.527391 -150.552226) (xy 47.579691 -150.567581)
			(xy 47.629273 -150.590224) (xy 47.675128 -150.619693) (xy 47.716321 -150.655389) (xy 47.752015 -150.696584)
			(xy 47.781483 -150.742439) (xy 47.804124 -150.792022) (xy 47.819477 -150.844323) (xy 47.827231 -150.898276)
			(xy 47.827692 -150.92553) (xy 47.827299 -150.950869) (xy 47.820586 -151.001101) (xy 47.807281 -151.050002)
			(xy 47.787619 -151.096711) (xy 47.761946 -151.140406) (xy 47.730715 -151.180317) (xy 47.712884 -151.198326)
			(xy 47.703553 -151.208104) (xy 47.689874 -151.231402) (xy 47.682784 -151.257471) (xy 47.682779 -151.284487)
			(xy 47.689858 -151.310559) (xy 47.703527 -151.333863) (xy 47.712884 -151.343614) (xy 47.732318 -151.363281)
			(xy 47.76586 -151.407234) (xy 47.792706 -151.455569) (xy 47.812293 -151.507273) (xy 47.824211 -151.561262)
			(xy 47.828212 -151.616407) (xy 47.824209 -151.671552) (xy 47.812289 -151.725541) (xy 47.7927 -151.777244)
			(xy 47.765852 -151.825578) (xy 47.732309 -151.86953) (xy 47.712884 -151.889206) (xy 47.703473 -151.898913)
			(xy 47.6898 -151.922231) (xy 47.68272 -151.948319) (xy 47.682729 -151.975351) (xy 47.689827 -152.001433)
			(xy 47.703516 -152.024742) (xy 47.712884 -152.034494) (xy 47.730707 -152.05251) (xy 47.761935 -152.09242)
			(xy 47.787605 -152.136114) (xy 47.807264 -152.182822) (xy 47.820566 -152.231722) (xy 47.827277 -152.281952)
			(xy 47.827692 -152.30729) (xy 47.827235 -152.334543) (xy 47.819479 -152.388495) (xy 47.804124 -152.440794)
			(xy 47.781481 -152.490375) (xy 47.752013 -152.536229) (xy 47.716318 -152.577423) (xy 47.675125 -152.613116)
			(xy 47.62927 -152.642584) (xy 47.579689 -152.665226) (xy 47.527389 -152.680581) (xy 47.473437 -152.688336)
			(xy 47.446184 -152.688798) (xy 47.416385 -152.688249) (xy 47.357513 -152.678966) (xy 47.300799 -152.660644)
			(xy 47.247624 -152.633728) (xy 47.199279 -152.598874) (xy 47.177706 -152.578308) (xy 47.166217 -152.567611)
			(xy 47.138297 -152.553284) (xy 47.107349 -152.548094) (xy 47.076284 -152.552527) (xy 47.048023 -152.566167)
			(xy 47.036228 -152.57653) (xy 47.014852 -152.595958) (xy 46.967366 -152.628841) (xy 46.915463 -152.654186)
			(xy 46.860333 -152.671415) (xy 46.803234 -152.680133) (xy 46.774354 -152.68067) (xy 46.746985 -152.68018)
			(xy 46.692806 -152.672369) (xy 46.640303 -152.656886) (xy 46.590556 -152.634049) (xy 46.544588 -152.604329)
			(xy 46.523656 -152.58669) (xy 46.512328 -152.577454) (xy 46.485771 -152.565278) (xy 46.456854 -152.561105)
			(xy 46.427937 -152.565278) (xy 46.40138 -152.577454) (xy 46.390052 -152.58669) (xy 46.369119 -152.604331)
			(xy 46.323151 -152.634055) (xy 46.273405 -152.656901) (xy 46.220903 -152.672397) (xy 46.166725 -152.680226)
			(xy 46.111983 -152.680226) (xy 46.057805 -152.672397) (xy 46.005303 -152.656901) (xy 45.955557 -152.634055)
			(xy 45.909589 -152.604331) (xy 45.888656 -152.58669) (xy 45.877328 -152.577454) (xy 45.850771 -152.565278)
			(xy 45.821854 -152.561105) (xy 45.792937 -152.565278) (xy 45.76638 -152.577454) (xy 45.755052 -152.58669)
			(xy 45.734119 -152.604331) (xy 45.688151 -152.634055) (xy 45.638405 -152.656901) (xy 45.585903 -152.672397)
			(xy 45.531725 -152.680226) (xy 45.476983 -152.680226) (xy 45.422805 -152.672397) (xy 45.370303 -152.656901)
			(xy 45.320557 -152.634055) (xy 45.274589 -152.604331) (xy 45.253656 -152.58669) (xy 45.242328 -152.577454)
			(xy 45.215771 -152.565278) (xy 45.186854 -152.561105) (xy 45.157937 -152.565278) (xy 45.13138 -152.577454)
			(xy 45.120052 -152.58669) (xy 45.09911 -152.604317) (xy 45.05314 -152.634031) (xy 45.003395 -152.656869)
			(xy 44.950897 -152.672363) (xy 44.896723 -152.680194) (xy 44.869354 -152.68067) (xy 44.840094 -152.680113)
			(xy 44.782263 -152.671165) (xy 44.726473 -152.653501) (xy 44.674029 -152.627534) (xy 44.62616 -152.593872)
			(xy 44.604686 -152.57399) (xy 44.594404 -152.564648) (xy 44.569969 -152.551451) (xy 44.542878 -152.545339)
			(xy 44.515144 -152.546766) (xy 44.488824 -152.555626) (xy 44.465872 -152.571261) (xy 44.456604 -152.58161)
			(xy 44.438387 -152.602453) (xy 44.396978 -152.639189) (xy 44.350692 -152.669551) (xy 44.300502 -152.692899)
			(xy 44.247463 -152.708743) (xy 44.19269 -152.71675) (xy 44.165012 -152.717246) (xy 44.137763 -152.716711)
			(xy 44.083819 -152.708957) (xy 44.031527 -152.693605) (xy 43.981953 -152.670968) (xy 43.936104 -152.641507)
			(xy 43.894915 -152.60582) (xy 43.859223 -152.564636) (xy 43.829756 -152.518791) (xy 43.807112 -152.469219)
			(xy 43.791754 -152.41693) (xy 43.783993 -152.362987) (xy 43.783504 -152.335738) (xy 43.783942 -152.3104)
			(xy 43.790646 -152.26017) (xy 43.803942 -152.21127) (xy 43.823596 -152.164561) (xy 43.849261 -152.120865)
			(xy 43.880485 -152.080952) (xy 43.898312 -152.062942) (xy 43.907675 -152.053192) (xy 43.921352 -152.029887)
			(xy 43.928439 -152.00381) (xy 43.928438 -151.976787) (xy 43.921351 -151.950711) (xy 43.907674 -151.927405)
			(xy 43.898312 -151.917654) (xy 43.878846 -151.898018) (xy 43.845305 -151.85406) (xy 43.818461 -151.805721)
			(xy 43.798875 -151.754012) (xy 43.786959 -151.700019) (xy 43.782962 -151.644871) (xy 39.788351 -151.644871)
			(xy 41.2682 -153.12472) (xy 51.012924 -153.12472) (xy 51.012928 -153.070227) (xy 51.020687 -153.016288)
			(xy 51.036042 -152.964003) (xy 51.058683 -152.914435) (xy 51.088146 -152.868593) (xy 51.123834 -152.827411)
			(xy 51.165019 -152.791727) (xy 51.210863 -152.762267) (xy 51.260433 -152.739631) (xy 51.312719 -152.72428)
			(xy 51.366659 -152.716526) (xy 51.421152 -152.716526) (xy 51.475091 -152.724282) (xy 51.527377 -152.739635)
			(xy 51.576946 -152.762272) (xy 51.62279 -152.791734) (xy 51.663974 -152.827419) (xy 51.69966 -152.868602)
			(xy 51.729122 -152.914444) (xy 51.736434 -152.930455) (xy 53.058229 -152.930455) (xy 53.058229 -152.875945)
			(xy 53.065987 -152.821989) (xy 53.081345 -152.769686) (xy 53.10399 -152.720102) (xy 53.133461 -152.674245)
			(xy 53.169159 -152.633049) (xy 53.210356 -152.597353) (xy 53.256214 -152.567883) (xy 53.305799 -152.54524)
			(xy 53.358102 -152.529884) (xy 53.412059 -152.522128) (xy 53.439314 -152.521666) (xy 53.466685 -152.522108)
			(xy 53.520866 -152.529929) (xy 53.57337 -152.545423) (xy 53.623117 -152.56827) (xy 53.669082 -152.598001)
			(xy 53.690012 -152.615646) (xy 53.70134 -152.624882) (xy 53.727897 -152.637058) (xy 53.756814 -152.641231)
			(xy 53.785731 -152.637058) (xy 53.812288 -152.624882) (xy 53.823616 -152.615646) (xy 53.844575 -152.59804)
			(xy 53.89054 -152.568322) (xy 53.94028 -152.545479) (xy 53.992775 -152.52998) (xy 54.046947 -152.522144)
			(xy 54.074314 -152.521666) (xy 54.101563 -152.522205) (xy 54.155505 -152.529963) (xy 54.207795 -152.545318)
			(xy 54.257367 -152.567958) (xy 54.303212 -152.597423) (xy 54.344398 -152.633112) (xy 54.380085 -152.674299)
			(xy 54.409548 -152.720146) (xy 54.432187 -152.769719) (xy 54.44754 -152.822009) (xy 54.455296 -152.875951)
			(xy 54.455296 -152.930449) (xy 54.44754 -152.984391) (xy 54.432187 -153.036681) (xy 54.409548 -153.086254)
			(xy 54.380085 -153.132101) (xy 54.344398 -153.173288) (xy 54.303212 -153.208977) (xy 54.257367 -153.238442)
			(xy 54.207795 -153.261082) (xy 54.155505 -153.276437) (xy 54.101563 -153.284195) (xy 54.074314 -153.284682)
			(xy 54.046944 -153.284212) (xy 53.992765 -153.276396) (xy 53.940262 -153.260908) (xy 53.890515 -153.238067)
			(xy 53.844548 -153.208343) (xy 53.823616 -153.190702) (xy 53.812288 -153.181466) (xy 53.785731 -153.16929)
			(xy 53.756814 -153.165117) (xy 53.727897 -153.16929) (xy 53.70134 -153.181466) (xy 53.690012 -153.190702)
			(xy 53.669086 -153.208349) (xy 53.623112 -153.23806) (xy 53.573363 -153.260894) (xy 53.520861 -153.276383)
			(xy 53.466684 -153.284209) (xy 53.439314 -153.284682) (xy 53.412059 -153.284272) (xy 53.358102 -153.276516)
			(xy 53.305799 -153.26116) (xy 53.256214 -153.238517) (xy 53.210356 -153.209047) (xy 53.169159 -153.173351)
			(xy 53.133461 -153.132155) (xy 53.10399 -153.086298) (xy 53.081345 -153.036714) (xy 53.065987 -152.984411)
			(xy 53.058229 -152.930455) (xy 51.736434 -152.930455) (xy 51.751761 -152.964013) (xy 51.767116 -153.016299)
			(xy 51.774873 -153.070237) (xy 51.77536 -153.097484) (xy 51.77493 -153.122875) (xy 51.768173 -153.173207)
			(xy 51.761898 -153.197814) (xy 51.758525 -153.212472) (xy 51.759445 -153.242518) (xy 51.769069 -153.270996)
			(xy 51.786564 -153.29544) (xy 51.810415 -153.313736) (xy 51.838559 -153.324299) (xy 51.868558 -153.326215)
			(xy 51.88331 -153.32329) (xy 51.904903 -153.318524) (xy 51.948829 -153.313431) (xy 51.97094 -153.31313)
			(xy 51.998187 -153.313621) (xy 52.052126 -153.321382) (xy 52.104412 -153.336739) (xy 52.153979 -153.359381)
			(xy 52.199821 -153.388847) (xy 52.241002 -153.424536) (xy 52.276686 -153.465723) (xy 52.306145 -153.511568)
			(xy 52.32878 -153.561139) (xy 52.34413 -153.613427) (xy 52.351883 -153.667367) (xy 52.351881 -153.721861)
			(xy 52.344124 -153.775801) (xy 52.32877 -153.828087) (xy 52.306131 -153.877657) (xy 52.276669 -153.9235)
			(xy 52.240982 -153.964684) (xy 52.199798 -154.00037) (xy 52.153955 -154.029832) (xy 52.104385 -154.052471)
			(xy 52.052099 -154.067824) (xy 51.998159 -154.075581) (xy 51.943665 -154.075583) (xy 51.889725 -154.067829)
			(xy 51.837437 -154.052479) (xy 51.787866 -154.029844) (xy 51.742021 -154.000384) (xy 51.700835 -153.964701)
			(xy 51.665146 -153.923519) (xy 51.63568 -153.877678) (xy 51.613039 -153.82811) (xy 51.597681 -153.775824)
			(xy 51.589921 -153.721885) (xy 51.589432 -153.694638) (xy 51.589867 -153.669247) (xy 51.596621 -153.618916)
			(xy 51.602894 -153.594308) (xy 51.606253 -153.579646) (xy 51.605338 -153.549601) (xy 51.595718 -153.521123)
			(xy 51.578225 -153.496677) (xy 51.554375 -153.478382) (xy 51.526232 -153.46782) (xy 51.496234 -153.465906)
			(xy 51.481482 -153.468832) (xy 51.459889 -153.4736) (xy 51.415963 -153.478691) (xy 51.393852 -153.478992)
			(xy 51.366605 -153.47847) (xy 51.312667 -153.470709) (xy 51.260383 -153.45535) (xy 51.210816 -153.432707)
			(xy 51.164976 -153.403241) (xy 51.123796 -153.367551) (xy 51.088114 -153.326364) (xy 51.058657 -153.280518)
			(xy 51.036024 -153.230947) (xy 51.020675 -153.17866) (xy 51.012924 -153.12472) (xy 41.2682 -153.12472)
			(xy 42.671532 -154.528052) (xy 49.996289 -154.528052) (xy 49.996289 -154.473548) (xy 50.004047 -154.419598)
			(xy 50.019404 -154.367301) (xy 50.042047 -154.317722) (xy 50.071517 -154.271871) (xy 50.107212 -154.230681)
			(xy 50.148406 -154.19499) (xy 50.194261 -154.165526) (xy 50.243842 -154.142888) (xy 50.296141 -154.127537)
			(xy 50.350092 -154.119786) (xy 50.377344 -154.119326) (xy 50.407031 -154.119911) (xy 50.465689 -154.129102)
			(xy 50.522215 -154.147271) (xy 50.575243 -154.173978) (xy 50.623492 -154.20858) (xy 50.665798 -154.250239)
			(xy 50.683922 -154.273758) (xy 50.692348 -154.284365) (xy 50.713661 -154.301072) (xy 50.738615 -154.311591)
			(xy 50.765456 -154.315181) (xy 50.792297 -154.311591) (xy 50.817251 -154.301072) (xy 50.838564 -154.284365)
			(xy 50.84699 -154.273758) (xy 50.86512 -154.250243) (xy 50.907427 -154.208585) (xy 50.955675 -154.173982)
			(xy 51.008701 -154.147271) (xy 51.065225 -154.129095) (xy 51.123881 -154.119893) (xy 51.153568 -154.119326)
			(xy 51.180825 -154.119719) (xy 51.234784 -154.127473) (xy 51.28709 -154.142827) (xy 51.336679 -154.16547)
			(xy 51.38254 -154.19494) (xy 51.423741 -154.230637) (xy 51.459441 -154.271834) (xy 51.488915 -154.317693)
			(xy 51.511561 -154.36728) (xy 51.52692 -154.419585) (xy 51.534679 -154.473543) (xy 51.534679 -154.528057)
			(xy 51.52692 -154.582015) (xy 51.511561 -154.63432) (xy 51.488915 -154.683907) (xy 51.459441 -154.729766)
			(xy 51.423741 -154.770963) (xy 51.38254 -154.80666) (xy 51.336679 -154.83613) (xy 51.28709 -154.858773)
			(xy 51.234784 -154.874127) (xy 51.180825 -154.881881) (xy 51.153568 -154.882342) (xy 51.123881 -154.88176)
			(xy 51.065222 -154.87257) (xy 51.008695 -154.854402) (xy 50.955667 -154.827694) (xy 50.907418 -154.793091)
			(xy 50.865114 -154.75143) (xy 50.84699 -154.72791) (xy 50.838564 -154.717303) (xy 50.817251 -154.700596)
			(xy 50.792297 -154.690077) (xy 50.765456 -154.686487) (xy 50.738615 -154.690077) (xy 50.713661 -154.700596)
			(xy 50.692348 -154.717303) (xy 50.683922 -154.72791) (xy 50.665776 -154.751412) (xy 50.623474 -154.793073)
			(xy 50.575229 -154.827678) (xy 50.522206 -154.854392) (xy 50.465685 -154.87257) (xy 50.40703 -154.881774)
			(xy 50.377344 -154.882342) (xy 50.350092 -154.881814) (xy 50.296141 -154.874063) (xy 50.243842 -154.858712)
			(xy 50.194261 -154.836074) (xy 50.148406 -154.80661) (xy 50.107212 -154.770919) (xy 50.071517 -154.729729)
			(xy 50.042047 -154.683878) (xy 50.019404 -154.634299) (xy 50.004047 -154.582002) (xy 49.996289 -154.528052)
			(xy 42.671532 -154.528052) (xy 44.756931 -156.613451) (xy 50.206652 -156.613451) (xy 50.206652 -156.558949)
			(xy 50.214408 -156.505001) (xy 50.229762 -156.452707) (xy 50.252401 -156.403129) (xy 50.281865 -156.357277)
			(xy 50.317554 -156.316086) (xy 50.358742 -156.280392) (xy 50.40459 -156.250922) (xy 50.454165 -156.228277)
			(xy 50.506458 -156.212917) (xy 50.560405 -156.205155) (xy 50.587656 -156.204666) (xy 50.617561 -156.205202)
			(xy 50.67664 -156.214514) (xy 50.705258 -156.223208) (xy 50.719167 -156.227239) (xy 50.748099 -156.228148)
			(xy 50.776118 -156.220883) (xy 50.800963 -156.206032) (xy 50.820629 -156.184792) (xy 50.833527 -156.158879)
			(xy 50.836576 -156.144722) (xy 50.843165 -156.111884) (xy 50.866284 -156.049031) (xy 50.88255 -156.019754)
			(xy 50.889618 -156.006804) (xy 50.896647 -155.978161) (xy 50.895197 -155.948704) (xy 50.885389 -155.92089)
			(xy 50.868042 -155.897039) (xy 50.844601 -155.879141) (xy 50.830988 -155.87345) (xy 50.80422 -155.862735)
			(xy 50.753979 -155.83445) (xy 50.70857 -155.798922) (xy 50.669027 -155.756963) (xy 50.636253 -155.709528)
			(xy 50.610993 -155.6577) (xy 50.593825 -155.60266) (xy 50.585139 -155.545662) (xy 50.584608 -155.516834)
			(xy 50.585094 -155.489583) (xy 50.59285 -155.435635) (xy 50.608205 -155.38334) (xy 50.630847 -155.333763)
			(xy 50.660313 -155.287913) (xy 50.696004 -155.246722) (xy 50.737195 -155.211031) (xy 50.783045 -155.181565)
			(xy 50.832622 -155.158923) (xy 50.884917 -155.143568) (xy 50.938865 -155.135812) (xy 50.993367 -155.135812)
			(xy 51.047315 -155.143568) (xy 51.09961 -155.158923) (xy 51.149187 -155.181565) (xy 51.195037 -155.211031)
			(xy 51.236228 -155.246722) (xy 51.271919 -155.287913) (xy 51.301385 -155.333763) (xy 51.324027 -155.38334)
			(xy 51.339382 -155.435635) (xy 51.347138 -155.489583) (xy 51.347624 -155.516834) (xy 51.347239 -155.54207)
			(xy 51.340617 -155.592104) (xy 51.32744 -155.640824) (xy 51.30794 -155.687376) (xy 51.295554 -155.709366)
			(xy 51.28846 -155.722303) (xy 51.281434 -155.750951) (xy 51.282888 -155.780412) (xy 51.292701 -155.808229)
			(xy 51.310054 -155.832081) (xy 51.3335 -155.84998) (xy 51.347116 -155.85567) (xy 51.373892 -155.866366)
			(xy 51.424134 -155.894654) (xy 51.469543 -155.930184) (xy 51.509085 -155.972146) (xy 51.541859 -156.019583)
			(xy 51.567117 -156.071414) (xy 51.584283 -156.126457) (xy 51.592966 -156.183457) (xy 51.593496 -156.212286)
			(xy 51.593032 -156.239539) (xy 51.585276 -156.293491) (xy 51.569921 -156.345789) (xy 51.54728 -156.39537)
			(xy 51.517812 -156.441224) (xy 51.482118 -156.482417) (xy 51.440925 -156.518111) (xy 51.395072 -156.547579)
			(xy 51.345491 -156.570221) (xy 51.293193 -156.585576) (xy 51.239241 -156.593331) (xy 51.211988 -156.593794)
			(xy 51.182083 -156.593273) (xy 51.123003 -156.583951) (xy 51.094386 -156.575252) (xy 51.080457 -156.571302)
			(xy 51.051539 -156.570385) (xy 51.02353 -156.577636) (xy 50.998691 -156.592471) (xy 50.979026 -156.613693)
			(xy 50.966122 -156.639589) (xy 50.963068 -156.653738) (xy 50.957919 -156.679816) (xy 50.941346 -156.73032)
			(xy 50.917921 -156.778034) (xy 50.888096 -156.822032) (xy 50.852451 -156.861463) (xy 50.811676 -156.895561)
			(xy 50.76656 -156.923667) (xy 50.717979 -156.945236) (xy 50.666873 -156.959849) (xy 50.614233 -156.967225)
			(xy 50.587656 -156.967682) (xy 50.560405 -156.967245) (xy 50.506458 -156.959483) (xy 50.454165 -156.944123)
			(xy 50.40459 -156.921478) (xy 50.358742 -156.892008) (xy 50.317554 -156.856314) (xy 50.281865 -156.815123)
			(xy 50.252401 -156.769271) (xy 50.229762 -156.719693) (xy 50.214408 -156.667399) (xy 50.206652 -156.613451)
			(xy 44.756931 -156.613451) (xy 46.735492 -158.592012) (xy 46.752745 -158.61011) (xy 46.780556 -158.651654)
			(xy 46.79973 -158.697824) (xy 46.809531 -158.746848) (xy 46.810168 -158.771844) (xy 46.810168 -159.08147)
			(xy 50.99304 -159.08147) (xy 50.993427 -159.054214) (xy 51.001189 -159.000258) (xy 51.016552 -158.947956)
			(xy 51.039201 -158.898372) (xy 51.068677 -158.852517) (xy 51.104379 -158.811323) (xy 51.145579 -158.77563)
			(xy 51.191441 -158.746164) (xy 51.241029 -158.723524) (xy 51.293334 -158.708173) (xy 51.347292 -158.700422)
			(xy 51.374548 -158.699962) (xy 51.402122 -158.700442) (xy 51.456695 -158.708388) (xy 51.509556 -158.724109)
			(xy 51.559603 -158.747276) (xy 51.605792 -158.777408) (xy 51.647163 -158.813875) (xy 51.665378 -158.834582)
			(xy 51.675276 -158.84548) (xy 51.699926 -158.861555) (xy 51.728134 -158.869939) (xy 51.757562 -158.869939)
			(xy 51.78577 -158.861555) (xy 51.81042 -158.84548) (xy 51.820318 -158.834582) (xy 51.838512 -158.813855)
			(xy 51.879885 -158.777387) (xy 51.926079 -158.747257) (xy 51.97613 -158.724094) (xy 52.028995 -158.708381)
			(xy 52.083572 -158.700445) (xy 52.111148 -158.699962) (xy 52.137649 -158.700415) (xy 52.19014 -158.707762)
			(xy 52.241107 -158.722307) (xy 52.289569 -158.74377) (xy 52.334592 -158.771737) (xy 52.355242 -158.788354)
			(xy 52.367396 -158.797784) (xy 52.395794 -158.809573) (xy 52.426411 -158.812397) (xy 52.456486 -158.806003)
			(xy 52.483306 -158.790967) (xy 52.504451 -158.768645) (xy 52.511706 -158.75508) (xy 52.523817 -158.731395)
			(xy 52.553737 -158.687413) (xy 52.589605 -158.64813) (xy 52.630693 -158.614345) (xy 52.653184 -158.60014)
			(xy 52.665431 -158.592248) (xy 52.685104 -158.570769) (xy 52.697907 -158.544607) (xy 52.702796 -158.515894)
			(xy 52.699373 -158.486969) (xy 52.694078 -158.473394) (xy 52.684593 -158.450182) (xy 52.671241 -158.40185)
			(xy 52.664511 -158.352161) (xy 52.664106 -158.32709) (xy 52.66454 -158.302021) (xy 52.671286 -158.252338)
			(xy 52.684614 -158.204004) (xy 52.694078 -158.180786) (xy 52.699333 -158.167207) (xy 52.702713 -158.138299)
			(xy 52.697811 -158.10961) (xy 52.685024 -158.083464) (xy 52.665389 -158.06198) (xy 52.653184 -158.05404)
			(xy 52.630024 -158.039514) (xy 52.587899 -158.004668) (xy 52.551317 -157.964041) (xy 52.521063 -157.918506)
			(xy 52.497786 -157.869039) (xy 52.481986 -157.816703) (xy 52.474001 -157.762619) (xy 52.474003 -157.70795)
			(xy 52.481993 -157.653867) (xy 52.497797 -157.601532) (xy 52.521079 -157.552067) (xy 52.551336 -157.506534)
			(xy 52.587922 -157.465911) (xy 52.630049 -157.431068) (xy 52.653184 -157.4165) (xy 52.66539 -157.408551)
			(xy 52.685063 -157.387088) (xy 52.697871 -157.360941) (xy 52.702771 -157.332241) (xy 52.699363 -157.303326)
			(xy 52.694078 -157.289754) (xy 52.684581 -157.266547) (xy 52.671233 -157.218213) (xy 52.664508 -157.168522)
			(xy 52.664106 -157.14345) (xy 52.664627 -157.115565) (xy 52.672939 -157.060418) (xy 52.689377 -157.007126)
			(xy 52.713575 -156.95688) (xy 52.744991 -156.910801) (xy 52.782924 -156.869919) (xy 52.826526 -156.835147)
			(xy 52.874824 -156.807262) (xy 52.926739 -156.786887) (xy 52.98111 -156.774477) (xy 53.036724 -156.77031)
			(xy 53.092338 -156.774477) (xy 53.146709 -156.786887) (xy 53.198624 -156.807262) (xy 53.246922 -156.835147)
			(xy 53.290524 -156.869919) (xy 53.328457 -156.910801) (xy 53.359873 -156.95688) (xy 53.384071 -157.007126)
			(xy 53.400509 -157.060418) (xy 53.408821 -157.115565) (xy 53.409342 -157.14345) (xy 53.408875 -157.170782)
			(xy 53.400906 -157.224863) (xy 53.385118 -157.277198) (xy 53.36185 -157.326662) (xy 53.331601 -157.372195)
			(xy 53.295022 -157.412817) (xy 53.252897 -157.447655) (xy 53.229764 -157.46222) (xy 53.217537 -157.470138)
			(xy 53.19787 -157.491612) (xy 53.185068 -157.517767) (xy 53.180173 -157.546472) (xy 53.183584 -157.575392)
			(xy 53.18887 -157.588966) (xy 53.198345 -157.612181) (xy 53.211701 -157.660512) (xy 53.218435 -157.710199)
			(xy 53.218842 -157.73527) (xy 53.218431 -157.76034) (xy 53.211677 -157.810023) (xy 53.198339 -157.858357)
			(xy 53.18887 -157.881574) (xy 53.183624 -157.895151) (xy 53.180262 -157.924051) (xy 53.185173 -157.952729)
			(xy 53.197961 -157.978863) (xy 53.217591 -158.000338) (xy 53.229764 -158.00832) (xy 53.252885 -158.022903)
			(xy 53.295003 -158.057747) (xy 53.331579 -158.098369) (xy 53.361829 -158.143898) (xy 53.385103 -158.193358)
			(xy 53.400902 -158.245688) (xy 53.408888 -158.299764) (xy 53.408889 -158.354426) (xy 53.400905 -158.408502)
			(xy 53.385107 -158.460832) (xy 53.361834 -158.510292) (xy 53.331585 -158.555823) (xy 53.29501 -158.596446)
			(xy 53.252893 -158.631291) (xy 53.229764 -158.64586) (xy 53.217509 -158.653739) (xy 53.197842 -158.675225)
			(xy 53.185043 -158.70139) (xy 53.180156 -158.730104) (xy 53.183577 -158.75903) (xy 53.18887 -158.772606)
			(xy 53.198357 -158.795817) (xy 53.211708 -158.844149) (xy 53.218438 -158.893838) (xy 53.218842 -158.91891)
			(xy 53.21837 -158.945752) (xy 53.210665 -158.998881) (xy 53.195416 -159.050354) (xy 53.172938 -159.099106)
			(xy 53.143697 -159.144127) (xy 53.108298 -159.184487) (xy 53.067473 -159.219349) (xy 53.022069 -159.247993)
			(xy 52.973024 -159.269824) (xy 52.947316 -159.277558) (xy 52.932841 -159.282276) (xy 52.907286 -159.298788)
			(xy 52.887726 -159.322092) (xy 52.875894 -159.350122) (xy 52.87284 -159.380393) (xy 52.878835 -159.410222)
			(xy 52.885594 -159.423862) (xy 52.900228 -159.452008) (xy 52.920955 -159.511959) (xy 52.931453 -159.574517)
			(xy 52.932076 -159.606234) (xy 52.931855 -159.624253) (xy 52.928421 -159.660128) (xy 52.925218 -159.677862)
			(xy 52.922936 -159.693077) (xy 52.926453 -159.723622) (xy 52.938901 -159.751736) (xy 52.959153 -159.774871)
			(xy 52.985373 -159.790931) (xy 53.000148 -159.79521) (xy 53.027191 -159.802611) (xy 53.078917 -159.824241)
			(xy 53.126922 -159.853205) (xy 53.170174 -159.88888) (xy 53.207741 -159.930499) (xy 53.238815 -159.977165)
			(xy 53.262728 -160.027876) (xy 53.278965 -160.08154) (xy 53.287177 -160.137001) (xy 53.287676 -160.165034)
			(xy 53.287254 -160.192288) (xy 53.279492 -160.246239) (xy 53.264131 -160.298537) (xy 53.241483 -160.348117)
			(xy 53.21201 -160.393968) (xy 53.176312 -160.435159) (xy 53.135115 -160.47085) (xy 53.089259 -160.500315)
			(xy 53.039675 -160.522954) (xy 52.987375 -160.538306) (xy 52.933422 -160.546058) (xy 52.906168 -160.546542)
			(xy 52.878594 -160.54605) (xy 52.824022 -160.538105) (xy 52.771161 -160.522387) (xy 52.721115 -160.499222)
			(xy 52.674925 -160.469093) (xy 52.633554 -160.432628) (xy 52.615338 -160.411922) (xy 52.60544 -160.401024)
			(xy 52.58079 -160.384949) (xy 52.552582 -160.376565) (xy 52.523154 -160.376565) (xy 52.494946 -160.384949)
			(xy 52.470296 -160.401024) (xy 52.460398 -160.411922) (xy 52.442183 -160.432628) (xy 52.400812 -160.469093)
			(xy 52.354622 -160.49922) (xy 52.304575 -160.522383) (xy 52.251714 -160.538099) (xy 52.197142 -160.546039)
			(xy 52.141994 -160.546039) (xy 52.087422 -160.538099) (xy 52.034561 -160.522383) (xy 51.984514 -160.49922)
			(xy 51.938324 -160.469093) (xy 51.896953 -160.432628) (xy 51.878738 -160.411922) (xy 51.86884 -160.401024)
			(xy 51.84419 -160.384949) (xy 51.815982 -160.376565) (xy 51.786554 -160.376565) (xy 51.758346 -160.384949)
			(xy 51.733696 -160.401024) (xy 51.723798 -160.411922) (xy 51.705596 -160.432642) (xy 51.664225 -160.46911)
			(xy 51.618033 -160.499241) (xy 51.567983 -160.522405) (xy 51.515119 -160.53812) (xy 51.460543 -160.546058)
			(xy 51.432968 -160.546542) (xy 51.405718 -160.546052) (xy 51.351772 -160.538292) (xy 51.299479 -160.522935)
			(xy 51.249904 -160.500292) (xy 51.204055 -160.470826) (xy 51.162866 -160.435135) (xy 51.127175 -160.393946)
			(xy 51.097709 -160.348098) (xy 51.075066 -160.298523) (xy 51.059708 -160.24623) (xy 51.051948 -160.192284)
			(xy 51.05146 -160.165034) (xy 51.052043 -160.137181) (xy 51.060161 -160.08207) (xy 51.0762 -160.028722)
			(xy 51.09982 -159.978272) (xy 51.130519 -159.931788) (xy 51.167647 -159.890258) (xy 51.210414 -159.854563)
			(xy 51.257914 -159.825461) (xy 51.309138 -159.803569) (xy 51.33594 -159.795972) (xy 51.350063 -159.791719)
			(xy 51.375204 -159.77632) (xy 51.394916 -159.754396) (xy 51.407566 -159.727764) (xy 51.412104 -159.698632)
			(xy 51.410616 -159.683958) (xy 51.408945 -159.670942) (xy 51.407166 -159.644757) (xy 51.40706 -159.631634)
			(xy 51.407158 -159.617485) (xy 51.409189 -159.589262) (xy 51.411124 -159.575246) (xy 51.412683 -159.561896)
			(xy 51.409585 -159.535209) (xy 51.39962 -159.510259) (xy 51.38348 -159.488781) (xy 51.362288 -159.472267)
			(xy 51.337516 -159.461867) (xy 51.324256 -159.459676) (xy 51.297113 -159.45553) (xy 51.244287 -159.440561)
			(xy 51.194152 -159.418174) (xy 51.147744 -159.388832) (xy 51.106021 -159.353141) (xy 51.069844 -159.311838)
			(xy 51.039961 -159.265777) (xy 51.016989 -159.215907) (xy 51.001402 -159.16326) (xy 50.993522 -159.108923)
			(xy 50.99304 -159.08147) (xy 46.810168 -159.08147) (xy 46.810168 -161.76072) (xy 51.012924 -161.76072)
			(xy 51.012928 -161.706227) (xy 51.020687 -161.652288) (xy 51.036042 -161.600003) (xy 51.058683 -161.550435)
			(xy 51.088146 -161.504593) (xy 51.123834 -161.463411) (xy 51.165019 -161.427727) (xy 51.210863 -161.398267)
			(xy 51.260433 -161.375631) (xy 51.312719 -161.36028) (xy 51.366659 -161.352526) (xy 51.421152 -161.352526)
			(xy 51.475091 -161.360282) (xy 51.527377 -161.375635) (xy 51.576946 -161.398272) (xy 51.62279 -161.427734)
			(xy 51.663974 -161.463419) (xy 51.69966 -161.504602) (xy 51.729122 -161.550444) (xy 51.736434 -161.566455)
			(xy 53.058229 -161.566455) (xy 53.058229 -161.511945) (xy 53.065987 -161.457989) (xy 53.081345 -161.405686)
			(xy 53.10399 -161.356102) (xy 53.133461 -161.310245) (xy 53.169159 -161.269049) (xy 53.210356 -161.233353)
			(xy 53.256214 -161.203883) (xy 53.305799 -161.18124) (xy 53.358102 -161.165884) (xy 53.412059 -161.158128)
			(xy 53.439314 -161.157666) (xy 53.466685 -161.158108) (xy 53.520866 -161.165929) (xy 53.57337 -161.181423)
			(xy 53.623117 -161.20427) (xy 53.669082 -161.234001) (xy 53.690012 -161.251646) (xy 53.70134 -161.260882)
			(xy 53.727897 -161.273058) (xy 53.756814 -161.277231) (xy 53.785731 -161.273058) (xy 53.812288 -161.260882)
			(xy 53.823616 -161.251646) (xy 53.844575 -161.23404) (xy 53.89054 -161.204322) (xy 53.94028 -161.181479)
			(xy 53.992775 -161.16598) (xy 54.046947 -161.158144) (xy 54.074314 -161.157666) (xy 54.101563 -161.158205)
			(xy 54.155505 -161.165963) (xy 54.207795 -161.181318) (xy 54.257367 -161.203958) (xy 54.303212 -161.233423)
			(xy 54.344398 -161.269112) (xy 54.380085 -161.310299) (xy 54.409548 -161.356146) (xy 54.432187 -161.405719)
			(xy 54.44754 -161.458009) (xy 54.455296 -161.511951) (xy 54.455296 -161.566449) (xy 54.44754 -161.620391)
			(xy 54.432187 -161.672681) (xy 54.409548 -161.722254) (xy 54.380085 -161.768101) (xy 54.344398 -161.809288)
			(xy 54.303212 -161.844977) (xy 54.257367 -161.874442) (xy 54.207795 -161.897082) (xy 54.155505 -161.912437)
			(xy 54.101563 -161.920195) (xy 54.074314 -161.920682) (xy 54.046944 -161.920212) (xy 53.992765 -161.912396)
			(xy 53.940262 -161.896908) (xy 53.890515 -161.874067) (xy 53.844548 -161.844343) (xy 53.823616 -161.826702)
			(xy 53.812288 -161.817466) (xy 53.785731 -161.80529) (xy 53.756814 -161.801117) (xy 53.727897 -161.80529)
			(xy 53.70134 -161.817466) (xy 53.690012 -161.826702) (xy 53.669086 -161.844349) (xy 53.623112 -161.87406)
			(xy 53.573363 -161.896894) (xy 53.520861 -161.912383) (xy 53.466684 -161.920209) (xy 53.439314 -161.920682)
			(xy 53.412059 -161.920272) (xy 53.358102 -161.912516) (xy 53.305799 -161.89716) (xy 53.256214 -161.874517)
			(xy 53.210356 -161.845047) (xy 53.169159 -161.809351) (xy 53.133461 -161.768155) (xy 53.10399 -161.722298)
			(xy 53.081345 -161.672714) (xy 53.065987 -161.620411) (xy 53.058229 -161.566455) (xy 51.736434 -161.566455)
			(xy 51.751761 -161.600013) (xy 51.767116 -161.652299) (xy 51.774873 -161.706237) (xy 51.77536 -161.733484)
			(xy 51.77493 -161.758875) (xy 51.768173 -161.809207) (xy 51.761898 -161.833814) (xy 51.758525 -161.848472)
			(xy 51.759445 -161.878518) (xy 51.769069 -161.906996) (xy 51.786564 -161.93144) (xy 51.810415 -161.949736)
			(xy 51.838559 -161.960299) (xy 51.868558 -161.962215) (xy 51.88331 -161.95929) (xy 51.904903 -161.954524)
			(xy 51.948829 -161.949431) (xy 51.97094 -161.94913) (xy 51.998187 -161.949621) (xy 52.052126 -161.957382)
			(xy 52.104412 -161.972739) (xy 52.153979 -161.995381) (xy 52.199821 -162.024847) (xy 52.241002 -162.060536)
			(xy 52.276686 -162.101723) (xy 52.306145 -162.147568) (xy 52.32878 -162.197139) (xy 52.34413 -162.249427)
			(xy 52.351883 -162.303367) (xy 52.351881 -162.357861) (xy 52.344124 -162.411801) (xy 52.32877 -162.464087)
			(xy 52.306131 -162.513657) (xy 52.276669 -162.5595) (xy 52.240982 -162.600684) (xy 52.199798 -162.63637)
			(xy 52.153955 -162.665832) (xy 52.104385 -162.688471) (xy 52.052099 -162.703824) (xy 51.998159 -162.711581)
			(xy 51.943665 -162.711583) (xy 51.889725 -162.703829) (xy 51.837437 -162.688479) (xy 51.787866 -162.665844)
			(xy 51.742021 -162.636384) (xy 51.700835 -162.600701) (xy 51.665146 -162.559519) (xy 51.63568 -162.513678)
			(xy 51.613039 -162.46411) (xy 51.597681 -162.411824) (xy 51.589921 -162.357885) (xy 51.589432 -162.330638)
			(xy 51.589867 -162.305247) (xy 51.596621 -162.254916) (xy 51.602894 -162.230308) (xy 51.606253 -162.215646)
			(xy 51.605338 -162.185601) (xy 51.595718 -162.157123) (xy 51.578225 -162.132677) (xy 51.554375 -162.114382)
			(xy 51.526232 -162.10382) (xy 51.496234 -162.101906) (xy 51.481482 -162.104832) (xy 51.459889 -162.1096)
			(xy 51.415963 -162.114691) (xy 51.393852 -162.114992) (xy 51.366605 -162.11447) (xy 51.312667 -162.106709)
			(xy 51.260383 -162.09135) (xy 51.210816 -162.068707) (xy 51.164976 -162.039241) (xy 51.123796 -162.003551)
			(xy 51.088114 -161.962364) (xy 51.058657 -161.916518) (xy 51.036024 -161.866947) (xy 51.020675 -161.81466)
			(xy 51.012924 -161.76072) (xy 46.810168 -161.76072) (xy 46.810168 -163.164052) (xy 49.996289 -163.164052)
			(xy 49.996289 -163.109548) (xy 50.004047 -163.055598) (xy 50.019404 -163.003301) (xy 50.042047 -162.953722)
			(xy 50.071517 -162.907871) (xy 50.107212 -162.866681) (xy 50.148406 -162.83099) (xy 50.194261 -162.801526)
			(xy 50.243842 -162.778888) (xy 50.296141 -162.763537) (xy 50.350092 -162.755786) (xy 50.377344 -162.755326)
			(xy 50.407031 -162.755911) (xy 50.465689 -162.765102) (xy 50.522215 -162.783271) (xy 50.575243 -162.809978)
			(xy 50.623492 -162.84458) (xy 50.665798 -162.886239) (xy 50.683922 -162.909758) (xy 50.692348 -162.920365)
			(xy 50.713661 -162.937072) (xy 50.738615 -162.947591) (xy 50.765456 -162.951181) (xy 50.792297 -162.947591)
			(xy 50.817251 -162.937072) (xy 50.838564 -162.920365) (xy 50.84699 -162.909758) (xy 50.86512 -162.886243)
			(xy 50.907427 -162.844585) (xy 50.955675 -162.809982) (xy 51.008701 -162.783271) (xy 51.065225 -162.765095)
			(xy 51.123881 -162.755893) (xy 51.153568 -162.755326) (xy 51.180825 -162.755719) (xy 51.234784 -162.763473)
			(xy 51.28709 -162.778827) (xy 51.336679 -162.80147) (xy 51.38254 -162.83094) (xy 51.423741 -162.866637)
			(xy 51.459441 -162.907834) (xy 51.488915 -162.953693) (xy 51.511561 -163.00328) (xy 51.52692 -163.055585)
			(xy 51.534679 -163.109543) (xy 51.534679 -163.164057) (xy 51.52692 -163.218015) (xy 51.511561 -163.27032)
			(xy 51.488915 -163.319907) (xy 51.459441 -163.365766) (xy 51.423741 -163.406963) (xy 51.38254 -163.44266)
			(xy 51.336679 -163.47213) (xy 51.28709 -163.494773) (xy 51.234784 -163.510127) (xy 51.180825 -163.517881)
			(xy 51.153568 -163.518342) (xy 51.123881 -163.51776) (xy 51.065222 -163.50857) (xy 51.008695 -163.490402)
			(xy 50.955667 -163.463694) (xy 50.907418 -163.429091) (xy 50.865114 -163.38743) (xy 50.84699 -163.36391)
			(xy 50.838564 -163.353303) (xy 50.817251 -163.336596) (xy 50.792297 -163.326077) (xy 50.765456 -163.322487)
			(xy 50.738615 -163.326077) (xy 50.713661 -163.336596) (xy 50.692348 -163.353303) (xy 50.683922 -163.36391)
			(xy 50.665776 -163.387412) (xy 50.623474 -163.429073) (xy 50.575229 -163.463678) (xy 50.522206 -163.490392)
			(xy 50.465685 -163.50857) (xy 50.40703 -163.517774) (xy 50.377344 -163.518342) (xy 50.350092 -163.517814)
			(xy 50.296141 -163.510063) (xy 50.243842 -163.494712) (xy 50.194261 -163.472074) (xy 50.148406 -163.44261)
			(xy 50.107212 -163.406919) (xy 50.071517 -163.365729) (xy 50.042047 -163.319878) (xy 50.019404 -163.270299)
			(xy 50.004047 -163.218002) (xy 49.996289 -163.164052) (xy 46.810168 -163.164052) (xy 46.810168 -165.249451)
			(xy 50.206652 -165.249451) (xy 50.206652 -165.194949) (xy 50.214408 -165.141001) (xy 50.229762 -165.088707)
			(xy 50.252401 -165.039129) (xy 50.281865 -164.993277) (xy 50.317554 -164.952086) (xy 50.358742 -164.916392)
			(xy 50.40459 -164.886922) (xy 50.454165 -164.864277) (xy 50.506458 -164.848917) (xy 50.560405 -164.841155)
			(xy 50.587656 -164.840666) (xy 50.617561 -164.841202) (xy 50.67664 -164.850514) (xy 50.705258 -164.859208)
			(xy 50.719167 -164.863239) (xy 50.748099 -164.864148) (xy 50.776118 -164.856883) (xy 50.800963 -164.842032)
			(xy 50.820629 -164.820792) (xy 50.833527 -164.794879) (xy 50.836576 -164.780722) (xy 50.843165 -164.747884)
			(xy 50.866284 -164.685031) (xy 50.88255 -164.655754) (xy 50.889618 -164.642804) (xy 50.896647 -164.614161)
			(xy 50.895197 -164.584704) (xy 50.885389 -164.55689) (xy 50.868042 -164.533039) (xy 50.844601 -164.515141)
			(xy 50.830988 -164.50945) (xy 50.80422 -164.498735) (xy 50.753979 -164.47045) (xy 50.70857 -164.434922)
			(xy 50.669027 -164.392963) (xy 50.636253 -164.345528) (xy 50.610993 -164.2937) (xy 50.593825 -164.23866)
			(xy 50.585139 -164.181662) (xy 50.584608 -164.152834) (xy 50.585094 -164.125583) (xy 50.59285 -164.071635)
			(xy 50.608205 -164.01934) (xy 50.630847 -163.969763) (xy 50.660313 -163.923913) (xy 50.696004 -163.882722)
			(xy 50.737195 -163.847031) (xy 50.783045 -163.817565) (xy 50.832622 -163.794923) (xy 50.884917 -163.779568)
			(xy 50.938865 -163.771812) (xy 50.993367 -163.771812) (xy 51.047315 -163.779568) (xy 51.09961 -163.794923)
			(xy 51.149187 -163.817565) (xy 51.195037 -163.847031) (xy 51.236228 -163.882722) (xy 51.271919 -163.923913)
			(xy 51.301385 -163.969763) (xy 51.324027 -164.01934) (xy 51.339382 -164.071635) (xy 51.347138 -164.125583)
			(xy 51.347624 -164.152834) (xy 51.347239 -164.17807) (xy 51.340617 -164.228104) (xy 51.32744 -164.276824)
			(xy 51.30794 -164.323376) (xy 51.295554 -164.345366) (xy 51.28846 -164.358303) (xy 51.281434 -164.386951)
			(xy 51.282888 -164.416412) (xy 51.292701 -164.444229) (xy 51.310054 -164.468081) (xy 51.3335 -164.48598)
			(xy 51.347116 -164.49167) (xy 51.373892 -164.502366) (xy 51.424134 -164.530654) (xy 51.469543 -164.566184)
			(xy 51.509085 -164.608146) (xy 51.541859 -164.655583) (xy 51.567117 -164.707414) (xy 51.584283 -164.762457)
			(xy 51.592966 -164.819457) (xy 51.593496 -164.848286) (xy 51.593032 -164.875539) (xy 51.585276 -164.929491)
			(xy 51.569921 -164.981789) (xy 51.54728 -165.03137) (xy 51.517812 -165.077224) (xy 51.482118 -165.118417)
			(xy 51.440925 -165.154111) (xy 51.395072 -165.183579) (xy 51.345491 -165.206221) (xy 51.293193 -165.221576)
			(xy 51.239241 -165.229331) (xy 51.211988 -165.229794) (xy 51.182083 -165.229273) (xy 51.123003 -165.219951)
			(xy 51.094386 -165.211252) (xy 51.080457 -165.207302) (xy 51.051539 -165.206385) (xy 51.02353 -165.213636)
			(xy 50.998691 -165.228471) (xy 50.979026 -165.249693) (xy 50.966122 -165.275589) (xy 50.963068 -165.289738)
			(xy 50.957919 -165.315816) (xy 50.941346 -165.36632) (xy 50.917921 -165.414034) (xy 50.888096 -165.458032)
			(xy 50.852451 -165.497463) (xy 50.811676 -165.531561) (xy 50.76656 -165.559667) (xy 50.717979 -165.581236)
			(xy 50.666873 -165.595849) (xy 50.614233 -165.603225) (xy 50.587656 -165.603682) (xy 50.560405 -165.603245)
			(xy 50.506458 -165.595483) (xy 50.454165 -165.580123) (xy 50.40459 -165.557478) (xy 50.358742 -165.528008)
			(xy 50.317554 -165.492314) (xy 50.281865 -165.451123) (xy 50.252401 -165.405271) (xy 50.229762 -165.355693)
			(xy 50.214408 -165.303399) (xy 50.206652 -165.249451) (xy 46.810168 -165.249451) (xy 46.810168 -167.71747)
			(xy 50.99304 -167.71747) (xy 50.993427 -167.690214) (xy 51.001189 -167.636258) (xy 51.016552 -167.583956)
			(xy 51.039201 -167.534372) (xy 51.068677 -167.488517) (xy 51.104379 -167.447323) (xy 51.145579 -167.41163)
			(xy 51.191441 -167.382164) (xy 51.241029 -167.359524) (xy 51.293334 -167.344173) (xy 51.347292 -167.336422)
			(xy 51.374548 -167.335962) (xy 51.402122 -167.336442) (xy 51.456695 -167.344388) (xy 51.509556 -167.360109)
			(xy 51.559603 -167.383276) (xy 51.605792 -167.413408) (xy 51.647163 -167.449875) (xy 51.665378 -167.470582)
			(xy 51.675276 -167.48148) (xy 51.699926 -167.497555) (xy 51.728134 -167.505939) (xy 51.757562 -167.505939)
			(xy 51.78577 -167.497555) (xy 51.81042 -167.48148) (xy 51.820318 -167.470582) (xy 51.838512 -167.449855)
			(xy 51.879885 -167.413387) (xy 51.926079 -167.383257) (xy 51.97613 -167.360094) (xy 52.028995 -167.344381)
			(xy 52.083572 -167.336445) (xy 52.111148 -167.335962) (xy 52.137649 -167.336415) (xy 52.19014 -167.343762)
			(xy 52.241107 -167.358307) (xy 52.289569 -167.37977) (xy 52.334592 -167.407737) (xy 52.355242 -167.424354)
			(xy 52.367396 -167.433784) (xy 52.395794 -167.445573) (xy 52.426411 -167.448397) (xy 52.456486 -167.442003)
			(xy 52.483306 -167.426967) (xy 52.504451 -167.404645) (xy 52.511706 -167.39108) (xy 52.523817 -167.367395)
			(xy 52.553737 -167.323413) (xy 52.589605 -167.28413) (xy 52.630693 -167.250345) (xy 52.653184 -167.23614)
			(xy 52.665431 -167.228248) (xy 52.685104 -167.206769) (xy 52.697907 -167.180607) (xy 52.702796 -167.151894)
			(xy 52.699373 -167.122969) (xy 52.694078 -167.109394) (xy 52.684593 -167.086182) (xy 52.671241 -167.03785)
			(xy 52.664511 -166.988161) (xy 52.664106 -166.96309) (xy 52.66454 -166.938021) (xy 52.671286 -166.888338)
			(xy 52.684614 -166.840004) (xy 52.694078 -166.816786) (xy 52.699333 -166.803207) (xy 52.702713 -166.774299)
			(xy 52.697811 -166.74561) (xy 52.685024 -166.719464) (xy 52.665389 -166.69798) (xy 52.653184 -166.69004)
			(xy 52.630024 -166.675514) (xy 52.587899 -166.640668) (xy 52.551317 -166.600041) (xy 52.521063 -166.554506)
			(xy 52.497786 -166.505039) (xy 52.481986 -166.452703) (xy 52.474001 -166.398619) (xy 52.474003 -166.34395)
			(xy 52.481993 -166.289867) (xy 52.497797 -166.237532) (xy 52.521079 -166.188067) (xy 52.551336 -166.142534)
			(xy 52.587922 -166.101911) (xy 52.630049 -166.067068) (xy 52.653184 -166.0525) (xy 52.66539 -166.044551)
			(xy 52.685063 -166.023088) (xy 52.697871 -165.996941) (xy 52.702771 -165.968241) (xy 52.699363 -165.939326)
			(xy 52.694078 -165.925754) (xy 52.684581 -165.902547) (xy 52.671233 -165.854213) (xy 52.664508 -165.804522)
			(xy 52.664106 -165.77945) (xy 52.664627 -165.751565) (xy 52.672939 -165.696418) (xy 52.689377 -165.643126)
			(xy 52.713575 -165.59288) (xy 52.744991 -165.546801) (xy 52.782924 -165.505919) (xy 52.826526 -165.471147)
			(xy 52.874824 -165.443262) (xy 52.926739 -165.422887) (xy 52.98111 -165.410477) (xy 53.036724 -165.40631)
			(xy 53.092338 -165.410477) (xy 53.146709 -165.422887) (xy 53.198624 -165.443262) (xy 53.246922 -165.471147)
			(xy 53.290524 -165.505919) (xy 53.328457 -165.546801) (xy 53.359873 -165.59288) (xy 53.384071 -165.643126)
			(xy 53.400509 -165.696418) (xy 53.408821 -165.751565) (xy 53.409342 -165.77945) (xy 53.408875 -165.806782)
			(xy 53.400906 -165.860863) (xy 53.385118 -165.913198) (xy 53.36185 -165.962662) (xy 53.331601 -166.008195)
			(xy 53.295022 -166.048817) (xy 53.252897 -166.083655) (xy 53.229764 -166.09822) (xy 53.217537 -166.106138)
			(xy 53.19787 -166.127612) (xy 53.185068 -166.153767) (xy 53.180173 -166.182472) (xy 53.183584 -166.211392)
			(xy 53.18887 -166.224966) (xy 53.198345 -166.248181) (xy 53.211701 -166.296512) (xy 53.218435 -166.346199)
			(xy 53.218842 -166.37127) (xy 53.218431 -166.39634) (xy 53.211677 -166.446023) (xy 53.198339 -166.494357)
			(xy 53.18887 -166.517574) (xy 53.183624 -166.531151) (xy 53.180262 -166.560051) (xy 53.185173 -166.588729)
			(xy 53.197961 -166.614863) (xy 53.217591 -166.636338) (xy 53.229764 -166.64432) (xy 53.252885 -166.658903)
			(xy 53.295003 -166.693747) (xy 53.331579 -166.734369) (xy 53.361829 -166.779898) (xy 53.385103 -166.829358)
			(xy 53.400902 -166.881688) (xy 53.408888 -166.935764) (xy 53.408889 -166.990426) (xy 53.400905 -167.044502)
			(xy 53.385107 -167.096832) (xy 53.361834 -167.146292) (xy 53.331585 -167.191823) (xy 53.29501 -167.232446)
			(xy 53.252893 -167.267291) (xy 53.229764 -167.28186) (xy 53.217509 -167.289739) (xy 53.197842 -167.311225)
			(xy 53.185043 -167.33739) (xy 53.180156 -167.366104) (xy 53.183577 -167.39503) (xy 53.18887 -167.408606)
			(xy 53.198357 -167.431817) (xy 53.211708 -167.480149) (xy 53.218438 -167.529838) (xy 53.218842 -167.55491)
			(xy 53.21837 -167.581752) (xy 53.210665 -167.634881) (xy 53.195416 -167.686354) (xy 53.172938 -167.735106)
			(xy 53.143697 -167.780127) (xy 53.108298 -167.820487) (xy 53.067473 -167.855349) (xy 53.022069 -167.883993)
			(xy 52.973024 -167.905824) (xy 52.947316 -167.913558) (xy 52.932841 -167.918276) (xy 52.907286 -167.934788)
			(xy 52.887726 -167.958092) (xy 52.875894 -167.986122) (xy 52.87284 -168.016393) (xy 52.878835 -168.046222)
			(xy 52.885594 -168.059862) (xy 52.900228 -168.088008) (xy 52.920955 -168.147959) (xy 52.931453 -168.210517)
			(xy 52.932076 -168.242234) (xy 52.931855 -168.260253) (xy 52.928421 -168.296128) (xy 52.925218 -168.313862)
			(xy 52.922936 -168.329077) (xy 52.926453 -168.359622) (xy 52.938901 -168.387736) (xy 52.959153 -168.410871)
			(xy 52.985373 -168.426931) (xy 53.000148 -168.43121) (xy 53.027191 -168.438611) (xy 53.078917 -168.460241)
			(xy 53.126922 -168.489205) (xy 53.170174 -168.52488) (xy 53.207741 -168.566499) (xy 53.238815 -168.613165)
			(xy 53.262728 -168.663876) (xy 53.278965 -168.71754) (xy 53.287177 -168.773001) (xy 53.287676 -168.801034)
			(xy 53.287254 -168.828288) (xy 53.279492 -168.882239) (xy 53.264131 -168.934537) (xy 53.241483 -168.984117)
			(xy 53.21201 -169.029968) (xy 53.176312 -169.071159) (xy 53.135115 -169.10685) (xy 53.089259 -169.136315)
			(xy 53.039675 -169.158954) (xy 52.987375 -169.174306) (xy 52.933422 -169.182058) (xy 52.906168 -169.182542)
			(xy 52.878594 -169.18205) (xy 52.824022 -169.174105) (xy 52.771161 -169.158387) (xy 52.721115 -169.135222)
			(xy 52.674925 -169.105093) (xy 52.633554 -169.068628) (xy 52.615338 -169.047922) (xy 52.60544 -169.037024)
			(xy 52.58079 -169.020949) (xy 52.552582 -169.012565) (xy 52.523154 -169.012565) (xy 52.494946 -169.020949)
			(xy 52.470296 -169.037024) (xy 52.460398 -169.047922) (xy 52.442183 -169.068628) (xy 52.400812 -169.105093)
			(xy 52.354622 -169.13522) (xy 52.304575 -169.158383) (xy 52.251714 -169.174099) (xy 52.197142 -169.182039)
			(xy 52.141994 -169.182039) (xy 52.087422 -169.174099) (xy 52.034561 -169.158383) (xy 51.984514 -169.13522)
			(xy 51.938324 -169.105093) (xy 51.896953 -169.068628) (xy 51.878738 -169.047922) (xy 51.86884 -169.037024)
			(xy 51.84419 -169.020949) (xy 51.815982 -169.012565) (xy 51.786554 -169.012565) (xy 51.758346 -169.020949)
			(xy 51.733696 -169.037024) (xy 51.723798 -169.047922) (xy 51.705596 -169.068642) (xy 51.664225 -169.10511)
			(xy 51.618033 -169.135241) (xy 51.567983 -169.158405) (xy 51.515119 -169.17412) (xy 51.460543 -169.182058)
			(xy 51.432968 -169.182542) (xy 51.405718 -169.182052) (xy 51.351772 -169.174292) (xy 51.299479 -169.158935)
			(xy 51.249904 -169.136292) (xy 51.204055 -169.106826) (xy 51.162866 -169.071135) (xy 51.127175 -169.029946)
			(xy 51.097709 -168.984098) (xy 51.075066 -168.934523) (xy 51.059708 -168.88223) (xy 51.051948 -168.828284)
			(xy 51.05146 -168.801034) (xy 51.052043 -168.773181) (xy 51.060161 -168.71807) (xy 51.0762 -168.664722)
			(xy 51.09982 -168.614272) (xy 51.130519 -168.567788) (xy 51.167647 -168.526258) (xy 51.210414 -168.490563)
			(xy 51.257914 -168.461461) (xy 51.309138 -168.439569) (xy 51.33594 -168.431972) (xy 51.350063 -168.427719)
			(xy 51.375204 -168.41232) (xy 51.394916 -168.390396) (xy 51.407566 -168.363764) (xy 51.412104 -168.334632)
			(xy 51.410616 -168.319958) (xy 51.408945 -168.306942) (xy 51.407166 -168.280757) (xy 51.40706 -168.267634)
			(xy 51.407158 -168.253485) (xy 51.409189 -168.225262) (xy 51.411124 -168.211246) (xy 51.412683 -168.197896)
			(xy 51.409585 -168.171209) (xy 51.39962 -168.146259) (xy 51.38348 -168.124781) (xy 51.362288 -168.108267)
			(xy 51.337516 -168.097867) (xy 51.324256 -168.095676) (xy 51.297113 -168.09153) (xy 51.244287 -168.076561)
			(xy 51.194152 -168.054174) (xy 51.147744 -168.024832) (xy 51.106021 -167.989141) (xy 51.069844 -167.947838)
			(xy 51.039961 -167.901777) (xy 51.016989 -167.851907) (xy 51.001402 -167.79926) (xy 50.993522 -167.744923)
			(xy 50.99304 -167.71747) (xy 46.810168 -167.71747) (xy 46.810168 -169.986198) (xy 47.19701 -170.37304)
			(xy 48.960532 -170.37304) (xy 48.985529 -170.373652) (xy 49.034553 -170.383463) (xy 49.080724 -170.402644)
			(xy 49.122269 -170.430458) (xy 49.140364 -170.447716) (xy 49.548796 -170.856148) (xy 50.017172 -170.856148)
			(xy 50.017649 -170.828574) (xy 50.025597 -170.774002) (xy 50.041318 -170.721142) (xy 50.064486 -170.671096)
			(xy 50.094617 -170.624907) (xy 50.131084 -170.583538) (xy 50.173128 -170.54785) (xy 50.196242 -170.532806)
			(xy 50.208147 -170.524733) (xy 50.227333 -170.503326) (xy 50.239787 -170.477417) (xy 50.244521 -170.449062)
			(xy 50.24116 -170.420513) (xy 50.229971 -170.394033) (xy 50.21184 -170.371725) (xy 50.200306 -170.363134)
			(xy 50.178981 -170.347755) (xy 50.140292 -170.312157) (xy 50.10686 -170.27158) (xy 50.079321 -170.226795)
			(xy 50.058196 -170.178651) (xy 50.043886 -170.128062) (xy 50.036663 -170.075985) (xy 50.036222 -170.049698)
			(xy 50.036708 -170.022447) (xy 50.044464 -169.968499) (xy 50.059819 -169.916204) (xy 50.082461 -169.866627)
			(xy 50.111927 -169.820777) (xy 50.147618 -169.779586) (xy 50.188809 -169.743895) (xy 50.234659 -169.714429)
			(xy 50.284236 -169.691787) (xy 50.336531 -169.676432) (xy 50.390479 -169.668676) (xy 50.444981 -169.668676)
			(xy 50.498929 -169.676432) (xy 50.551224 -169.691787) (xy 50.600801 -169.714429) (xy 50.646651 -169.743895)
			(xy 50.687842 -169.779586) (xy 50.723533 -169.820777) (xy 50.752999 -169.866627) (xy 50.775641 -169.916204)
			(xy 50.790996 -169.968499) (xy 50.798752 -170.022447) (xy 50.799238 -170.049698) (xy 50.798792 -170.077273)
			(xy 50.790838 -170.131847) (xy 50.775111 -170.184707) (xy 50.751938 -170.234752) (xy 50.721802 -170.280941)
			(xy 50.685331 -170.32231) (xy 50.643284 -170.357997) (xy 50.620168 -170.37304) (xy 50.608219 -170.381053)
			(xy 50.58903 -170.402473) (xy 50.576576 -170.428395) (xy 50.571846 -170.456762) (xy 50.575216 -170.485322)
			(xy 50.586418 -170.51181) (xy 50.604562 -170.534121) (xy 50.616104 -170.542712) (xy 50.637453 -170.558059)
			(xy 50.676141 -170.593663) (xy 50.709571 -170.634245) (xy 50.737107 -170.679036) (xy 50.758228 -170.727185)
			(xy 50.772533 -170.777779) (xy 50.779751 -170.829859) (xy 50.780188 -170.856148) (xy 50.779702 -170.883399)
			(xy 50.771946 -170.937347) (xy 50.756591 -170.989642) (xy 50.733949 -171.039219) (xy 50.704483 -171.085069)
			(xy 50.668792 -171.12626) (xy 50.627601 -171.161951) (xy 50.581751 -171.191417) (xy 50.532174 -171.214059)
			(xy 50.479879 -171.229414) (xy 50.425931 -171.23717) (xy 50.371429 -171.23717) (xy 50.317481 -171.229414)
			(xy 50.265186 -171.214059) (xy 50.215609 -171.191417) (xy 50.169759 -171.161951) (xy 50.128568 -171.12626)
			(xy 50.092877 -171.085069) (xy 50.063411 -171.039219) (xy 50.040769 -170.989642) (xy 50.025414 -170.937347)
			(xy 50.017658 -170.883399) (xy 50.017172 -170.856148) (xy 49.548796 -170.856148) (xy 49.735232 -171.042584)
			(xy 49.752462 -171.060703) (xy 49.78028 -171.102239) (xy 49.799461 -171.148403) (xy 49.809268 -171.197422)
			(xy 49.809908 -171.222416) (xy 49.809908 -171.877736) (xy 49.853088 -171.88434) (xy 49.879846 -171.888844)
			(xy 49.931827 -171.904406) (xy 49.981076 -171.927178) (xy 50.026601 -171.956702) (xy 50.067482 -171.99238)
			(xy 50.102892 -172.033492) (xy 50.132118 -172.079209) (xy 50.154569 -172.128606) (xy 50.169791 -172.180687)
			(xy 50.177478 -172.2344) (xy 50.177954 -172.26153) (xy 50.17745 -172.28878) (xy 50.169691 -172.342725)
			(xy 50.154334 -172.395016) (xy 50.131693 -172.44459) (xy 50.102228 -172.490438) (xy 50.066538 -172.531627)
			(xy 50.025351 -172.567318) (xy 49.979505 -172.596785) (xy 49.929931 -172.619429) (xy 49.87764 -172.634787)
			(xy 49.823696 -172.642549) (xy 49.796446 -172.643038) (xy 49.76607 -172.642468) (xy 49.706086 -172.632833)
			(xy 49.648386 -172.613814) (xy 49.59443 -172.585893) (xy 49.545579 -172.549774) (xy 49.523904 -172.528484)
			(xy 49.514176 -172.519126) (xy 49.490915 -172.50545) (xy 49.464879 -172.498363) (xy 49.437895 -172.498363)
			(xy 49.411859 -172.50545) (xy 49.388598 -172.519126) (xy 49.37887 -172.528484) (xy 49.357174 -172.549751)
			(xy 49.30833 -172.585872) (xy 49.254379 -172.613795) (xy 49.196683 -172.632814) (xy 49.136703 -172.642447)
			(xy 49.106328 -172.643038) (xy 49.079079 -172.642496) (xy 49.025135 -172.634744) (xy 48.972843 -172.619394)
			(xy 48.923268 -172.596758) (xy 48.877419 -172.567298) (xy 48.836229 -172.531612) (xy 48.800537 -172.490428)
			(xy 48.77107 -172.444583) (xy 48.748426 -172.395012) (xy 48.733068 -172.342722) (xy 48.725308 -172.288779)
			(xy 48.72482 -172.26153) (xy 48.725392 -172.232617) (xy 48.734109 -172.175452) (xy 48.751348 -172.120255)
			(xy 48.776716 -172.06829) (xy 48.80963 -172.020745) (xy 48.849339 -171.978709) (xy 48.894934 -171.943143)
			(xy 48.919892 -171.928536) (xy 48.919892 -171.488862) (xy 48.694086 -171.263056) (xy 46.933612 -171.263056)
			(xy 46.908616 -171.262419) (xy 46.859593 -171.252616) (xy 46.813422 -171.233443) (xy 46.771876 -171.205635)
			(xy 46.75378 -171.18838) (xy 45.994828 -170.429428) (xy 45.97755 -170.411352) (xy 45.949742 -170.369801)
			(xy 45.930575 -170.323624) (xy 45.920784 -170.274594) (xy 45.920152 -170.249596) (xy 45.920152 -159.035242)
			(xy 37.798502 -150.913338) (xy 37.781292 -150.895217) (xy 37.753546 -150.853662) (xy 37.734435 -150.807496)
			(xy 37.724692 -150.758489) (xy 37.72408 -150.733506) (xy 37.72408 -137.886186) (xy 34.451798 -134.613904)
			(xy 32.309562 -134.613904) (xy 31.782909 -135.140557) (xy 32.578423 -135.140557) (xy 32.578423 -135.086043)
			(xy 32.586182 -135.032083) (xy 32.601542 -134.979777) (xy 32.62419 -134.930189) (xy 32.653665 -134.88433)
			(xy 32.689366 -134.843133) (xy 32.730568 -134.807436) (xy 32.776431 -134.777967) (xy 32.826022 -134.755325)
			(xy 32.87833 -134.739972) (xy 32.932291 -134.73222) (xy 32.959548 -134.73176) (xy 32.98633 -134.732183)
			(xy 33.039367 -134.739689) (xy 33.090834 -134.754533) (xy 33.139722 -134.776423) (xy 33.185071 -134.804931)
			(xy 33.225992 -134.839496) (xy 33.26168 -134.87944) (xy 33.291437 -134.92398) (xy 33.303464 -134.947914)
			(xy 33.309986 -134.960369) (xy 33.328576 -134.98144) (xy 33.352213 -134.996636) (xy 33.379101 -135.004802)
			(xy 33.407196 -135.005317) (xy 33.434365 -134.998143) (xy 33.458543 -134.983824) (xy 33.477894 -134.963448)
			(xy 33.48482 -134.951216) (xy 33.497242 -134.928438) (xy 33.527358 -134.886189) (xy 33.562922 -134.848411)
			(xy 33.603278 -134.815801) (xy 33.647681 -134.788962) (xy 33.695312 -134.768389) (xy 33.745292 -134.75446)
			(xy 33.796698 -134.747434) (xy 33.82264 -134.747) (xy 33.84989 -134.747473) (xy 33.903834 -134.755234)
			(xy 33.956126 -134.770593) (xy 34.005699 -134.793237) (xy 34.051545 -134.822705) (xy 34.092731 -134.858397)
			(xy 34.128419 -134.899587) (xy 34.157883 -134.945436) (xy 34.180521 -134.995012) (xy 34.195875 -135.047305)
			(xy 34.20363 -135.10125) (xy 34.20363 -135.15575) (xy 34.195875 -135.209695) (xy 34.180521 -135.261988)
			(xy 34.157883 -135.311564) (xy 34.128419 -135.357413) (xy 34.092731 -135.398603) (xy 34.051545 -135.434295)
			(xy 34.005699 -135.463763) (xy 33.956126 -135.486407) (xy 33.903834 -135.501766) (xy 33.84989 -135.509527)
			(xy 33.82264 -135.510016) (xy 33.795859 -135.509561) (xy 33.742826 -135.502055) (xy 33.691361 -135.487213)
			(xy 33.642475 -135.465326) (xy 33.597127 -135.436823) (xy 33.556206 -135.402264) (xy 33.520515 -135.362326)
			(xy 33.490754 -135.317793) (xy 33.478724 -135.293862) (xy 33.472219 -135.281399) (xy 33.453623 -135.260331)
			(xy 33.429984 -135.245139) (xy 33.403095 -135.236976) (xy 33.374999 -135.236462) (xy 33.347829 -135.243636)
			(xy 33.32365 -135.257954) (xy 33.304296 -135.278328) (xy 33.297368 -135.29056) (xy 33.284913 -135.313319)
			(xy 33.254798 -135.355564) (xy 33.219236 -135.393339) (xy 33.178885 -135.425948) (xy 33.134487 -135.452788)
			(xy 33.086863 -135.473366) (xy 33.036889 -135.487301) (xy 32.985488 -135.494337) (xy 32.959548 -135.494776)
			(xy 32.932291 -135.49438) (xy 32.87833 -135.486628) (xy 32.826022 -135.471275) (xy 32.776431 -135.448633)
			(xy 32.730568 -135.419164) (xy 32.689366 -135.383467) (xy 32.653665 -135.34227) (xy 32.62419 -135.296411)
			(xy 32.601542 -135.246823) (xy 32.586182 -135.194517) (xy 32.578423 -135.140557) (xy 31.782909 -135.140557)
			(xy 31.586678 -135.336788) (xy 31.568584 -135.354045) (xy 31.527039 -135.381856) (xy 31.480867 -135.401029)
			(xy 31.431842 -135.410828) (xy 31.406846 -135.411464) (xy 29.69514 -135.411464) (xy 29.630624 -135.47598)
			(xy 26.877264 -135.47598) (xy 26.2255 -134.824216) (xy 23.561548 -134.824216) (xy 23.561548 -136.903206)
			(xy 23.93823 -137.279888) (xy 33.298892 -137.279888) (xy 33.299358 -137.253509) (xy 33.306612 -137.201253)
			(xy 33.320994 -137.150494) (xy 33.34223 -137.102199) (xy 33.369914 -137.057289) (xy 33.403521 -137.01662)
			(xy 33.442408 -136.980967) (xy 33.485835 -136.95101) (xy 33.509204 -136.938766) (xy 33.521569 -136.932079)
			(xy 33.542292 -136.913098) (xy 33.557047 -136.889181) (xy 33.564715 -136.862146) (xy 33.564714 -136.834044)
			(xy 33.557043 -136.807009) (xy 33.542285 -136.783094) (xy 33.52156 -136.764115) (xy 33.509204 -136.75741)
			(xy 33.48583 -136.745175) (xy 33.442405 -136.715213) (xy 33.403519 -136.679557) (xy 33.369913 -136.638886)
			(xy 33.342226 -136.593976) (xy 33.320987 -136.545682) (xy 33.306599 -136.494923) (xy 33.299336 -136.442667)
			(xy 33.298892 -136.416288) (xy 33.299378 -136.389037) (xy 33.307134 -136.335089) (xy 33.322489 -136.282794)
			(xy 33.345131 -136.233217) (xy 33.374597 -136.187367) (xy 33.410288 -136.146176) (xy 33.451479 -136.110485)
			(xy 33.497329 -136.081019) (xy 33.546906 -136.058377) (xy 33.599201 -136.043022) (xy 33.653149 -136.035266)
			(xy 33.707651 -136.035266) (xy 33.761599 -136.043022) (xy 33.813894 -136.058377) (xy 33.863471 -136.081019)
			(xy 33.909321 -136.110485) (xy 33.950512 -136.146176) (xy 33.986203 -136.187367) (xy 34.015669 -136.233217)
			(xy 34.038311 -136.282794) (xy 34.053666 -136.335089) (xy 34.061422 -136.389037) (xy 34.061908 -136.416288)
			(xy 34.061505 -136.442669) (xy 34.05424 -136.494928) (xy 34.039849 -136.545689) (xy 34.018604 -136.593984)
			(xy 33.99091 -136.638893) (xy 33.957296 -136.679561) (xy 33.918402 -136.715212) (xy 33.874968 -136.745168)
			(xy 33.851596 -136.75741) (xy 33.839252 -136.764132) (xy 33.818532 -136.783108) (xy 33.803777 -136.807018)
			(xy 33.796107 -136.834047) (xy 33.796106 -136.862143) (xy 33.803772 -136.889173) (xy 33.818525 -136.913084)
			(xy 33.839243 -136.932062) (xy 33.851596 -136.938766) (xy 33.87496 -136.951019) (xy 33.918385 -136.980979)
			(xy 33.957271 -137.016632) (xy 33.990878 -137.0573) (xy 34.018565 -137.102207) (xy 34.039807 -137.150499)
			(xy 34.054197 -137.201255) (xy 34.061462 -137.25351) (xy 34.061908 -137.279888) (xy 34.061422 -137.307139)
			(xy 34.053666 -137.361087) (xy 34.038311 -137.413382) (xy 34.015669 -137.462959) (xy 33.986203 -137.508809)
			(xy 33.950512 -137.55) (xy 33.909321 -137.585691) (xy 33.863471 -137.615157) (xy 33.813894 -137.637799)
			(xy 33.761599 -137.653154) (xy 33.707651 -137.66091) (xy 33.653149 -137.66091) (xy 33.599201 -137.653154)
			(xy 33.546906 -137.637799) (xy 33.497329 -137.615157) (xy 33.451479 -137.585691) (xy 33.410288 -137.55)
			(xy 33.374597 -137.508809) (xy 33.345131 -137.462959) (xy 33.322489 -137.413382) (xy 33.307134 -137.361087)
			(xy 33.299378 -137.307139) (xy 33.298892 -137.279888) (xy 23.93823 -137.279888) (xy 36.87953 -150.221188)
			(xy 36.882324 -150.223982) (xy 36.886134 -150.227792) (xy 36.886642 -150.228554) (xy 36.972494 -150.314406)
			(xy 36.972494 -150.440136) (xy 36.972748 -150.445978) (xy 36.972748 -157.281118) (xy 36.972494 -157.28696)
			(xy 36.972494 -157.41269) (xy 36.886642 -157.498542) (xy 36.886134 -157.499304) (xy 36.882324 -157.503114)
			(xy 36.87953 -157.505908) (xy 36.590224 -157.795214) (xy 36.08324 -158.301944) (xy 36.08324 -161.891218)
			(xy 43.505377 -161.891218) (xy 43.509413 -161.807771) (xy 43.521485 -161.725103) (xy 43.541478 -161.643986)
			(xy 43.569207 -161.565177) (xy 43.604413 -161.489412) (xy 43.646767 -161.417399) (xy 43.695873 -161.34981)
			(xy 43.751274 -161.287276) (xy 43.812451 -161.230381) (xy 43.878834 -161.179655) (xy 43.949802 -161.135574)
			(xy 44.024694 -161.098548) (xy 44.10281 -161.068922) (xy 44.18342 -161.046974) (xy 44.265772 -161.032909)
			(xy 44.349098 -161.026857) (xy 44.432618 -161.028876) (xy 44.515554 -161.038946) (xy 44.59713 -161.056974)
			(xy 44.676586 -161.082791) (xy 44.753179 -161.116156) (xy 44.826195 -161.156757) (xy 44.894951 -161.204216)
			(xy 44.958805 -161.258089) (xy 45.017162 -161.317874) (xy 45.069477 -161.383011) (xy 45.11526 -161.452894)
			(xy 45.154085 -161.526869) (xy 45.18559 -161.604246) (xy 45.209479 -161.684303) (xy 45.22553 -161.766291)
			(xy 45.233593 -161.849446) (xy 45.234098 -161.891218) (xy 45.233593 -161.93299) (xy 45.22553 -162.016145)
			(xy 45.209479 -162.098133) (xy 45.18559 -162.17819) (xy 45.154085 -162.255567) (xy 45.11526 -162.329542)
			(xy 45.069477 -162.399425) (xy 45.017162 -162.464562) (xy 44.958805 -162.524347) (xy 44.894951 -162.57822)
			(xy 44.826195 -162.625679) (xy 44.753179 -162.66628) (xy 44.676586 -162.699645) (xy 44.59713 -162.725462)
			(xy 44.515554 -162.74349) (xy 44.432618 -162.75356) (xy 44.349098 -162.755579) (xy 44.265772 -162.749527)
			(xy 44.18342 -162.735462) (xy 44.10281 -162.713514) (xy 44.024694 -162.683888) (xy 43.949802 -162.646862)
			(xy 43.878834 -162.602781) (xy 43.812451 -162.552055) (xy 43.751274 -162.49516) (xy 43.695873 -162.432626)
			(xy 43.646767 -162.365037) (xy 43.604413 -162.293024) (xy 43.569207 -162.217259) (xy 43.541478 -162.13845)
			(xy 43.521485 -162.057333) (xy 43.509413 -161.974665) (xy 43.505377 -161.891218) (xy 36.08324 -161.891218)
			(xy 36.08324 -164.433688) (xy 43.480986 -164.433688) (xy 43.480986 -164.348992) (xy 43.489037 -164.264678)
			(xy 43.505066 -164.181512) (xy 43.528927 -164.100245) (xy 43.560406 -164.021615) (xy 43.599217 -163.946334)
			(xy 43.645007 -163.875082) (xy 43.697363 -163.808506) (xy 43.755811 -163.747208) (xy 43.819821 -163.691743)
			(xy 43.888813 -163.642614) (xy 43.962163 -163.600265) (xy 44.039206 -163.565081) (xy 44.119245 -163.537379)
			(xy 44.201554 -163.517411) (xy 44.285389 -163.505358) (xy 44.36999 -163.501328) (xy 44.454591 -163.505358)
			(xy 44.538426 -163.517411) (xy 44.620735 -163.537379) (xy 44.700774 -163.565081) (xy 44.777817 -163.600265)
			(xy 44.851167 -163.642614) (xy 44.920159 -163.691743) (xy 44.984169 -163.747208) (xy 45.042617 -163.808506)
			(xy 45.094973 -163.875082) (xy 45.140763 -163.946334) (xy 45.179574 -164.021615) (xy 45.211053 -164.100245)
			(xy 45.234914 -164.181512) (xy 45.250943 -164.264678) (xy 45.258994 -164.348992) (xy 45.259498 -164.39134)
			(xy 45.258994 -164.433688) (xy 45.250943 -164.518002) (xy 45.234914 -164.601168) (xy 45.211053 -164.682435)
			(xy 45.179574 -164.761065) (xy 45.140763 -164.836346) (xy 45.094973 -164.907598) (xy 45.042617 -164.974174)
			(xy 44.984169 -165.035472) (xy 44.920159 -165.090937) (xy 44.851167 -165.140066) (xy 44.777817 -165.182415)
			(xy 44.700774 -165.217599) (xy 44.620735 -165.245301) (xy 44.538426 -165.265269) (xy 44.454591 -165.277322)
			(xy 44.36999 -165.281353) (xy 44.285389 -165.277322) (xy 44.201554 -165.265269) (xy 44.119245 -165.245301)
			(xy 44.039206 -165.217599) (xy 43.962163 -165.182415) (xy 43.888813 -165.140066) (xy 43.819821 -165.090937)
			(xy 43.755811 -165.035472) (xy 43.697363 -164.974174) (xy 43.645007 -164.907598) (xy 43.599217 -164.836346)
			(xy 43.560406 -164.761065) (xy 43.528927 -164.682435) (xy 43.505066 -164.601168) (xy 43.489037 -164.518002)
			(xy 43.480986 -164.433688) (xy 36.08324 -164.433688) (xy 36.08324 -169.801794) (xy 43.431209 -169.801794)
			(xy 43.435245 -169.718347) (xy 43.447317 -169.635679) (xy 43.46731 -169.554562) (xy 43.495039 -169.475753)
			(xy 43.530245 -169.399988) (xy 43.572599 -169.327975) (xy 43.621705 -169.260386) (xy 43.677106 -169.197852)
			(xy 43.738283 -169.140957) (xy 43.804666 -169.090231) (xy 43.875634 -169.04615) (xy 43.950526 -169.009124)
			(xy 44.028642 -168.979498) (xy 44.109252 -168.95755) (xy 44.191604 -168.943485) (xy 44.27493 -168.937433)
			(xy 44.35845 -168.939452) (xy 44.441386 -168.949522) (xy 44.522962 -168.96755) (xy 44.602418 -168.993367)
			(xy 44.679011 -169.026732) (xy 44.752027 -169.067333) (xy 44.820783 -169.114792) (xy 44.884637 -169.168665)
			(xy 44.942994 -169.22845) (xy 44.995309 -169.293587) (xy 45.041092 -169.36347) (xy 45.079917 -169.437445)
			(xy 45.111422 -169.514822) (xy 45.135311 -169.594879) (xy 45.151362 -169.676867) (xy 45.159425 -169.760022)
			(xy 45.15993 -169.801794) (xy 45.159425 -169.843566) (xy 45.151362 -169.926721) (xy 45.135311 -170.008709)
			(xy 45.111422 -170.088766) (xy 45.079917 -170.166143) (xy 45.041092 -170.240118) (xy 44.995309 -170.310001)
			(xy 44.942994 -170.375138) (xy 44.884637 -170.434923) (xy 44.820783 -170.488796) (xy 44.752027 -170.536255)
			(xy 44.679011 -170.576856) (xy 44.602418 -170.610221) (xy 44.522962 -170.636038) (xy 44.441386 -170.654066)
			(xy 44.35845 -170.664136) (xy 44.27493 -170.666155) (xy 44.191604 -170.660103) (xy 44.109252 -170.646038)
			(xy 44.028642 -170.62409) (xy 43.950526 -170.594464) (xy 43.875634 -170.557438) (xy 43.804666 -170.513357)
			(xy 43.738283 -170.462631) (xy 43.677106 -170.405736) (xy 43.621705 -170.343202) (xy 43.572599 -170.275613)
			(xy 43.530245 -170.2036) (xy 43.495039 -170.127835) (xy 43.46731 -170.049026) (xy 43.447317 -169.967909)
			(xy 43.435245 -169.885241) (xy 43.431209 -169.801794) (xy 36.08324 -169.801794) (xy 36.08324 -170.670474)
			(xy 37.757139 -172.344264) (xy 43.406818 -172.344264) (xy 43.406818 -172.259568) (xy 43.414869 -172.175254)
			(xy 43.430898 -172.092088) (xy 43.454759 -172.010821) (xy 43.486238 -171.932191) (xy 43.525049 -171.85691)
			(xy 43.570839 -171.785658) (xy 43.623195 -171.719082) (xy 43.681643 -171.657784) (xy 43.745653 -171.602319)
			(xy 43.814645 -171.55319) (xy 43.887995 -171.510841) (xy 43.965038 -171.475657) (xy 44.045077 -171.447955)
			(xy 44.127386 -171.427987) (xy 44.211221 -171.415934) (xy 44.295822 -171.411904) (xy 44.380423 -171.415934)
			(xy 44.464258 -171.427987) (xy 44.546567 -171.447955) (xy 44.626606 -171.475657) (xy 44.703649 -171.510841)
			(xy 44.776999 -171.55319) (xy 44.845991 -171.602319) (xy 44.910001 -171.657784) (xy 44.968449 -171.719082)
			(xy 45.020805 -171.785658) (xy 45.066595 -171.85691) (xy 45.105406 -171.932191) (xy 45.136885 -172.010821)
			(xy 45.160746 -172.092088) (xy 45.176775 -172.175254) (xy 45.184826 -172.259568) (xy 45.18533 -172.301916)
			(xy 45.184826 -172.344264) (xy 45.176775 -172.428578) (xy 45.160746 -172.511744) (xy 45.136885 -172.593011)
			(xy 45.105406 -172.671641) (xy 45.066595 -172.746922) (xy 45.020805 -172.818174) (xy 44.968449 -172.88475)
			(xy 44.910001 -172.946048) (xy 44.845991 -173.001513) (xy 44.776999 -173.050642) (xy 44.703649 -173.092991)
			(xy 44.626606 -173.128175) (xy 44.546567 -173.155877) (xy 44.464258 -173.175845) (xy 44.380423 -173.187898)
			(xy 44.295822 -173.191929) (xy 44.211221 -173.187898) (xy 44.127386 -173.175845) (xy 44.045077 -173.155877)
			(xy 43.965038 -173.128175) (xy 43.887995 -173.092991) (xy 43.814645 -173.050642) (xy 43.745653 -173.001513)
			(xy 43.681643 -172.946048) (xy 43.623195 -172.88475) (xy 43.570839 -172.818174) (xy 43.525049 -172.746922)
			(xy 43.486238 -172.671641) (xy 43.454759 -172.593011) (xy 43.430898 -172.511744) (xy 43.414869 -172.428578)
			(xy 43.406818 -172.344264) (xy 37.757139 -172.344264) (xy 39.98722 -174.5742) (xy 45.438314 -174.5742)
			(xy 47.00016 -173.012354) (xy 47.002954 -173.00956) (xy 47.006764 -173.00575) (xy 47.007526 -173.005242)
			(xy 47.093378 -172.91939) (xy 47.219108 -172.91939) (xy 47.22495 -172.919136) (xy 50.471832 -172.919136)
			(xy 50.765964 -172.625004) (xy 50.7764 -172.613779) (xy 50.790609 -172.586637) (xy 50.796143 -172.556505)
			(xy 50.792507 -172.526085) (xy 50.780025 -172.498107) (xy 50.759819 -172.475079) (xy 50.7337 -172.459067)
			(xy 50.718974 -172.454824) (xy 50.691304 -172.447913) (xy 50.638249 -172.426993) (xy 50.5889 -172.398407)
			(xy 50.544358 -172.362792) (xy 50.505614 -172.320943) (xy 50.473534 -172.273791) (xy 50.448831 -172.222388)
			(xy 50.432057 -172.167881) (xy 50.423585 -172.111483) (xy 50.423064 -172.082968) (xy 50.423552 -172.055718)
			(xy 50.431312 -172.001772) (xy 50.44667 -171.949479) (xy 50.469312 -171.899904) (xy 50.498779 -171.854056)
			(xy 50.53447 -171.812867) (xy 50.575659 -171.777177) (xy 50.621508 -171.74771) (xy 50.671083 -171.725068)
			(xy 50.723376 -171.709711) (xy 50.777322 -171.701952) (xy 50.804572 -171.70146) (xy 50.833082 -171.701995)
			(xy 50.889467 -171.71049) (xy 50.943961 -171.727279) (xy 50.995349 -171.751989) (xy 51.04249 -171.784071)
			(xy 51.084332 -171.822808) (xy 51.119945 -171.867341) (xy 51.148536 -171.916676) (xy 51.169468 -171.969716)
			(xy 51.176428 -171.99737) (xy 51.180096 -172.010266) (xy 51.193189 -172.033651) (xy 51.211926 -172.052815)
			(xy 51.235011 -172.066432) (xy 51.260847 -172.07356) (xy 51.287649 -172.073706) (xy 51.313561 -172.066861)
			(xy 51.336794 -172.053497) (xy 51.346608 -172.04436) (xy 52.20081 -171.190158) (xy 52.203604 -171.187364)
			(xy 52.207414 -171.183554) (xy 52.208176 -171.183046) (xy 52.294028 -171.097194) (xy 52.419758 -171.097194)
			(xy 52.4256 -171.09694) (xy 52.954428 -171.09694) (xy 53.103272 -170.948096) (xy 53.103272 -170.903646)
			(xy 53.102852 -170.890097) (xy 53.095732 -170.863951) (xy 53.081982 -170.840601) (xy 53.062571 -170.821693)
			(xy 53.038868 -170.80856) (xy 53.012545 -170.802128) (xy 52.985456 -170.802852) (xy 52.959513 -170.810679)
			(xy 52.947824 -170.81754) (xy 52.924142 -170.832788) (xy 52.873242 -170.856904) (xy 52.819353 -170.873282)
			(xy 52.763642 -170.881566) (xy 52.73548 -170.882056) (xy 52.708228 -170.881569) (xy 52.65428 -170.87381)
			(xy 52.601985 -170.858454) (xy 52.552407 -170.835812) (xy 52.506556 -170.806346) (xy 52.465364 -170.770655)
			(xy 52.429671 -170.729466) (xy 52.400201 -170.683617) (xy 52.377556 -170.634041) (xy 52.362196 -170.581747)
			(xy 52.354433 -170.5278) (xy 52.353972 -170.500548) (xy 52.354442 -170.473573) (xy 52.362047 -170.420161)
			(xy 52.377099 -170.368353) (xy 52.399297 -170.319181) (xy 52.4282 -170.273626) (xy 52.46323 -170.232595)
			(xy 52.50369 -170.196906) (xy 52.548773 -170.167272) (xy 52.597579 -170.144282) (xy 52.649138 -170.128395)
			(xy 52.70242 -170.119928) (xy 52.729384 -170.11904) (xy 52.73548 -170.11904) (xy 52.765101 -170.119598)
			(xy 52.82363 -170.128754) (xy 52.880041 -170.146847) (xy 52.932976 -170.173444) (xy 52.981163 -170.207905)
			(xy 53.002688 -170.22826) (xy 53.002942 -170.228514) (xy 53.007768 -170.233086) (xy 53.019412 -170.243565)
			(xy 53.047442 -170.257511) (xy 53.07838 -170.262311) (xy 53.109318 -170.257511) (xy 53.137348 -170.243565)
			(xy 53.148992 -170.233086) (xy 53.159152 -170.22318) (xy 53.180478 -170.203774) (xy 53.227883 -170.170952)
			(xy 53.279684 -170.145632) (xy 53.334703 -170.12839) (xy 53.39169 -170.119617) (xy 53.420518 -170.11904)
			(xy 53.447401 -170.119451) (xy 53.500648 -170.126902) (xy 53.552322 -170.141751) (xy 53.6014 -170.163706)
			(xy 53.646912 -170.192331) (xy 53.687955 -170.22706) (xy 53.723719 -170.267206) (xy 53.753494 -170.311973)
			(xy 53.776692 -170.360476) (xy 53.792853 -170.411755) (xy 53.801658 -170.464795) (xy 53.802788 -170.491658)
			(xy 53.802788 -170.499786) (xy 53.802347 -170.527815) (xy 53.794257 -170.583283) (xy 53.778144 -170.636973)
			(xy 53.754356 -170.68773) (xy 53.739288 -170.711368) (xy 53.739288 -171.079668) (xy 53.739034 -171.08551)
			(xy 53.739034 -171.21124) (xy 53.653182 -171.297092) (xy 53.652674 -171.297854) (xy 53.648864 -171.301664)
			(xy 53.64607 -171.304458) (xy 53.31079 -171.639738) (xy 53.307996 -171.642532) (xy 53.304186 -171.646342)
			(xy 53.303424 -171.64685) (xy 53.217572 -171.732702) (xy 53.091842 -171.732702) (xy 53.086 -171.732956)
			(xy 52.557172 -171.732956) (xy 50.828194 -173.461934) (xy 50.8254 -173.464728) (xy 50.82159 -173.468538)
			(xy 50.820828 -173.469046) (xy 50.734976 -173.554898) (xy 50.609246 -173.554898) (xy 50.603404 -173.555152)
			(xy 47.356522 -173.555152) (xy 46.370923 -174.540751) (xy 48.944772 -174.540751) (xy 48.944772 -174.486249)
			(xy 48.952528 -174.432302) (xy 48.967883 -174.380008) (xy 48.990523 -174.330431) (xy 49.019988 -174.28458)
			(xy 49.055678 -174.24339) (xy 49.096867 -174.207698) (xy 49.142717 -174.178231) (xy 49.192293 -174.155588)
			(xy 49.244586 -174.140231) (xy 49.298533 -174.132473) (xy 49.325784 -174.131986) (xy 49.350659 -174.132354)
			(xy 49.399986 -174.138825) (xy 49.448052 -174.151659) (xy 49.494039 -174.170637) (xy 49.537167 -174.195438)
			(xy 49.557178 -174.210218) (xy 49.569675 -174.219055) (xy 49.598406 -174.229566) (xy 49.62896 -174.231114)
			(xy 49.658606 -174.223559) (xy 49.684693 -174.207578) (xy 49.704889 -174.184599) (xy 49.71161 -174.170848)
			(xy 49.723254 -174.14601) (xy 49.752631 -174.099682) (xy 49.788337 -174.058036) (xy 49.829637 -174.021931)
			(xy 49.875681 -173.99211) (xy 49.925519 -173.969188) (xy 49.978125 -173.953636) (xy 50.032416 -173.945775)
			(xy 50.059844 -173.945296) (xy 50.087093 -173.945777) (xy 50.141037 -173.953538) (xy 50.193327 -173.968898)
			(xy 50.242899 -173.991541) (xy 50.288745 -174.021009) (xy 50.32993 -174.056701) (xy 50.365617 -174.097891)
			(xy 50.39508 -174.143739) (xy 50.417718 -174.193314) (xy 50.433071 -174.245606) (xy 50.440826 -174.29955)
			(xy 50.440826 -174.35405) (xy 50.433071 -174.407994) (xy 50.417718 -174.460286) (xy 50.39508 -174.509861)
			(xy 50.365617 -174.555709) (xy 50.32993 -174.596899) (xy 50.288745 -174.632591) (xy 50.242899 -174.662059)
			(xy 50.193327 -174.684702) (xy 50.141037 -174.700062) (xy 50.087093 -174.707823) (xy 50.059844 -174.708312)
			(xy 50.03497 -174.707929) (xy 49.985643 -174.701462) (xy 49.937577 -174.688631) (xy 49.89159 -174.669656)
			(xy 49.848462 -174.644859) (xy 49.82845 -174.63008) (xy 49.815931 -174.621277) (xy 49.787208 -174.610762)
			(xy 49.75666 -174.60921) (xy 49.72702 -174.616758) (xy 49.700935 -174.632732) (xy 49.68074 -174.655703)
			(xy 49.674018 -174.66945) (xy 49.662351 -174.694277) (xy 49.632977 -174.740604) (xy 49.597274 -174.78225)
			(xy 49.555977 -174.818355) (xy 49.509937 -174.848178) (xy 49.460103 -174.871102) (xy 49.407499 -174.886657)
			(xy 49.353211 -174.894521) (xy 49.325784 -174.895002) (xy 49.298533 -174.894527) (xy 49.244586 -174.886769)
			(xy 49.192293 -174.871412) (xy 49.142717 -174.848769) (xy 49.096867 -174.819302) (xy 49.055678 -174.78361)
			(xy 49.019988 -174.74242) (xy 48.990523 -174.696569) (xy 48.967883 -174.646992) (xy 48.952528 -174.594698)
			(xy 48.944772 -174.540751) (xy 46.370923 -174.540751) (xy 45.794676 -175.116998) (xy 45.791882 -175.119792)
			(xy 45.788072 -175.123602) (xy 45.78731 -175.12411) (xy 45.701458 -175.209962) (xy 45.575728 -175.209962)
			(xy 45.569886 -175.210216) (xy 39.855648 -175.210216) (xy 39.849806 -175.209962) (xy 39.724076 -175.209962)
			(xy 39.638224 -175.12411) (xy 39.637462 -175.123602) (xy 39.633652 -175.119792) (xy 39.630858 -175.116998)
			(xy 35.53968 -171.02582) (xy 35.536378 -171.022518) (xy 35.534092 -171.020232) (xy 35.533584 -171.01947)
			(xy 35.447732 -170.933618) (xy 35.447732 -158.0388) (xy 35.533584 -157.952948) (xy 35.534092 -157.952186)
			(xy 35.536378 -157.9499) (xy 35.53968 -157.946598) (xy 36.336732 -157.149546) (xy 36.336732 -150.57755)
			(xy 23.01875 -137.259568) (xy 23.015956 -137.256774) (xy 23.012146 -137.252964) (xy 23.011638 -137.252202)
			(xy 22.925786 -137.16635) (xy 22.925786 -137.04062) (xy 22.925532 -137.034778) (xy 22.925532 -126.80188)
			(xy 22.925786 -126.796038) (xy 22.925786 -126.670308) (xy 23.011638 -126.584456) (xy 23.012146 -126.583694)
			(xy 23.015956 -126.579884) (xy 23.01875 -126.57709) (xy 25.917652 -123.678188) (xy 25.91816 -123.67768)
			(xy 25.921716 -123.674378) (xy 25.925018 -123.671076) (xy 26.01087 -123.585224) (xy 27.073352 -123.585224)
			(xy 27.087322 -123.576334) (xy 27.097736 -123.570238) (xy 27.119187 -123.5586) (xy 27.16442 -123.540274)
			(xy 27.211624 -123.52788) (xy 27.260024 -123.521621) (xy 27.284426 -123.521216) (xy 27.305254 -123.521216)
			(xy 27.32913 -123.52401) (xy 27.354038 -123.527374) (xy 27.40274 -123.539801) (xy 27.449392 -123.558505)
			(xy 27.49319 -123.583163) (xy 27.513534 -123.597924) (xy 27.526312 -123.605979) (xy 27.555131 -123.614975)
			(xy 27.58532 -123.615176) (xy 27.614256 -123.606565) (xy 27.639423 -123.58989) (xy 27.658634 -123.5666)
			(xy 27.670218 -123.538721) (xy 27.672284 -123.523756) (xy 27.672284 -121.78284) (xy 27.295602 -121.78284)
			(xy 22.860254 -126.218188) (xy 22.330664 -130.75793) (xy 22.277578 -131.21386) (xy 21.767546 -135.586216)
			(xy 21.767546 -153.766012) (xy 24.445731 -153.766012) (xy 24.449724 -153.556271) (xy 24.4617 -153.346834)
			(xy 24.481641 -153.138005) (xy 24.509518 -152.930086) (xy 24.54529 -152.723379) (xy 24.588905 -152.518184)
			(xy 24.640301 -152.314799) (xy 24.699403 -152.113517) (xy 24.766125 -151.914631) (xy 24.84037 -151.71843)
			(xy 24.92203 -151.525198) (xy 25.010988 -151.335214) (xy 25.107115 -151.148755) (xy 25.21027 -150.966091)
			(xy 25.320305 -150.787486) (xy 25.437059 -150.6132) (xy 25.560364 -150.443485) (xy 25.690041 -150.278587)
			(xy 25.825902 -150.118746) (xy 25.967749 -149.964193) (xy 26.115378 -149.815153) (xy 26.268573 -149.67184)
			(xy 26.427114 -149.534464) (xy 26.590769 -149.403223) (xy 26.759303 -149.278308) (xy 26.932469 -149.1599)
			(xy 27.110019 -149.04817) (xy 27.291693 -148.94328) (xy 27.477228 -148.845383) (xy 27.666356 -148.754621)
			(xy 27.858803 -148.671124) (xy 28.054288 -148.595014) (xy 28.25253 -148.526402) (xy 28.45324 -148.465387)
			(xy 28.656127 -148.412058) (xy 28.860897 -148.366491) (xy 29.067254 -148.328752) (xy 29.274898 -148.298898)
			(xy 29.483528 -148.27697) (xy 29.692841 -148.263001) (xy 29.902535 -148.25701) (xy 30.112304 -148.259007)
			(xy 30.321846 -148.268989) (xy 30.530856 -148.286941) (xy 30.73903 -148.312837) (xy 30.946068 -148.346639)
			(xy 31.151669 -148.388299) (xy 31.355535 -148.437757) (xy 31.55737 -148.49494) (xy 31.756882 -148.559765)
			(xy 31.953781 -148.632139) (xy 32.147782 -148.711956) (xy 32.338604 -148.799102) (xy 32.52597 -148.893449)
			(xy 32.709608 -148.99486) (xy 32.889252 -149.10319) (xy 33.064642 -149.21828) (xy 33.235523 -149.339964)
			(xy 33.401647 -149.468065) (xy 33.562774 -149.602398) (xy 33.718671 -149.742767) (xy 33.86911 -149.88897)
			(xy 34.013874 -150.040794) (xy 34.152753 -150.19802) (xy 34.285546 -150.360419) (xy 34.41206 -150.527755)
			(xy 34.532112 -150.699787) (xy 34.645527 -150.876264) (xy 34.752141 -151.056932) (xy 34.8518 -151.241527)
			(xy 34.944359 -151.429782) (xy 35.029684 -151.621425) (xy 35.107651 -151.816177) (xy 35.178147 -152.013757)
			(xy 35.24107 -152.213876) (xy 35.296329 -152.416247) (xy 35.343843 -152.620574) (xy 35.383544 -152.826562)
			(xy 35.415374 -153.033913) (xy 35.439287 -153.242324) (xy 35.455248 -153.451495) (xy 35.463235 -153.661122)
			(xy 35.463734 -153.766012) (xy 35.463235 -153.870902) (xy 35.455248 -154.080529) (xy 35.439287 -154.2897)
			(xy 35.415374 -154.498111) (xy 35.383544 -154.705462) (xy 35.343843 -154.91145) (xy 35.296329 -155.115777)
			(xy 35.24107 -155.318148) (xy 35.178147 -155.518267) (xy 35.107651 -155.715847) (xy 35.029684 -155.910599)
			(xy 34.944359 -156.102242) (xy 34.8518 -156.290497) (xy 34.752141 -156.475092) (xy 34.645527 -156.65576)
			(xy 34.532112 -156.832237) (xy 34.41206 -157.004269) (xy 34.285546 -157.171605) (xy 34.152753 -157.334004)
			(xy 34.013874 -157.49123) (xy 33.86911 -157.643054) (xy 33.718671 -157.789257) (xy 33.562774 -157.929626)
			(xy 33.401647 -158.063959) (xy 33.235523 -158.19206) (xy 33.064642 -158.313744) (xy 32.889252 -158.428834)
			(xy 32.709608 -158.537164) (xy 32.52597 -158.638575) (xy 32.338604 -158.732922) (xy 32.147782 -158.820068)
			(xy 31.953781 -158.899885) (xy 31.756882 -158.972259) (xy 31.55737 -159.037084) (xy 31.355535 -159.094267)
			(xy 31.151669 -159.143725) (xy 30.946068 -159.185385) (xy 30.73903 -159.219187) (xy 30.530856 -159.245083)
			(xy 30.321846 -159.263035) (xy 30.112304 -159.273017) (xy 29.902535 -159.275014) (xy 29.692841 -159.269023)
			(xy 29.483528 -159.255054) (xy 29.274898 -159.233126) (xy 29.067254 -159.203272) (xy 28.860897 -159.165533)
			(xy 28.656127 -159.119966) (xy 28.45324 -159.066637) (xy 28.25253 -159.005622) (xy 28.054288 -158.93701)
			(xy 27.858803 -158.8609) (xy 27.666356 -158.777403) (xy 27.477228 -158.686641) (xy 27.291693 -158.588744)
			(xy 27.110019 -158.483854) (xy 26.932469 -158.372124) (xy 26.759303 -158.253716) (xy 26.590769 -158.128801)
			(xy 26.427114 -157.99756) (xy 26.268573 -157.860184) (xy 26.115378 -157.716871) (xy 25.967749 -157.567831)
			(xy 25.825902 -157.413278) (xy 25.690041 -157.253437) (xy 25.560364 -157.088539) (xy 25.437059 -156.918824)
			(xy 25.320305 -156.744538) (xy 25.21027 -156.565933) (xy 25.107115 -156.383269) (xy 25.010988 -156.19681)
			(xy 24.92203 -156.006826) (xy 24.84037 -155.813594) (xy 24.766125 -155.617393) (xy 24.699403 -155.418507)
			(xy 24.640301 -155.217225) (xy 24.588905 -155.01384) (xy 24.54529 -154.808645) (xy 24.509518 -154.601938)
			(xy 24.481641 -154.394019) (xy 24.4617 -154.18519) (xy 24.449724 -153.975753) (xy 24.445731 -153.766012)
			(xy 21.767546 -153.766012) (xy 21.767546 -154.197558) (xy 19.309842 -156.655262) (xy 18.966196 -159.601752)
			(xy 21.579562 -159.601752) (xy 21.579562 -159.547248) (xy 21.587318 -159.493299) (xy 21.602673 -159.441004)
			(xy 21.625314 -159.391425) (xy 21.654781 -159.345574) (xy 21.690472 -159.304382) (xy 21.731662 -159.268689)
			(xy 21.777513 -159.239221) (xy 21.827091 -159.216578) (xy 21.879386 -159.201221) (xy 21.933334 -159.193463)
			(xy 21.960586 -159.192976) (xy 21.986966 -159.19339) (xy 22.039225 -159.200653) (xy 22.089985 -159.215044)
			(xy 22.138279 -159.236288) (xy 22.183189 -159.26398) (xy 22.223857 -159.297592) (xy 22.259509 -159.336485)
			(xy 22.289465 -159.379917) (xy 22.301708 -159.403288) (xy 22.30841 -159.415647) (xy 22.327385 -159.436375)
			(xy 22.351299 -159.451137) (xy 22.378335 -159.458809) (xy 22.406437 -159.458809) (xy 22.433473 -159.451137)
			(xy 22.457387 -159.436375) (xy 22.476362 -159.415647) (xy 22.483064 -159.403288) (xy 22.495311 -159.379921)
			(xy 22.525273 -159.336497) (xy 22.560928 -159.297612) (xy 22.601596 -159.264006) (xy 22.646504 -159.236318)
			(xy 22.694796 -159.215077) (xy 22.745553 -159.200687) (xy 22.797807 -159.193422) (xy 22.824186 -159.192976)
			(xy 22.851438 -159.19347) (xy 22.905389 -159.201225) (xy 22.957686 -159.21658) (xy 23.007266 -159.23922)
			(xy 23.053119 -159.268687) (xy 23.094311 -159.304379) (xy 23.130005 -159.34557) (xy 23.159473 -159.391422)
			(xy 23.182116 -159.441001) (xy 23.197472 -159.493298) (xy 23.205229 -159.547248) (xy 23.205229 -159.601752)
			(xy 23.197472 -159.655702) (xy 23.182116 -159.707999) (xy 23.159473 -159.757578) (xy 23.130005 -159.80343)
			(xy 23.094311 -159.844621) (xy 23.053119 -159.880313) (xy 23.007266 -159.90978) (xy 22.957686 -159.93242)
			(xy 22.905389 -159.947775) (xy 22.851438 -159.95553) (xy 22.824186 -159.955992) (xy 22.797807 -159.955536)
			(xy 22.74555 -159.948282) (xy 22.69479 -159.933899) (xy 22.646494 -159.912662) (xy 22.601584 -159.884976)
			(xy 22.560916 -159.851368) (xy 22.525263 -159.812479) (xy 22.495307 -159.76905) (xy 22.483064 -159.74568)
			(xy 22.476362 -159.733321) (xy 22.457387 -159.712593) (xy 22.433473 -159.697831) (xy 22.406437 -159.690159)
			(xy 22.378335 -159.690159) (xy 22.351299 -159.697831) (xy 22.327385 -159.712593) (xy 22.30841 -159.733321)
			(xy 22.301708 -159.74568) (xy 22.289468 -159.769052) (xy 22.259507 -159.812477) (xy 22.223852 -159.851363)
			(xy 22.183183 -159.88497) (xy 22.138273 -159.912657) (xy 22.089979 -159.933897) (xy 22.039221 -159.948285)
			(xy 21.986965 -159.955548) (xy 21.960586 -159.955992) (xy 21.933334 -159.955537) (xy 21.879386 -159.947779)
			(xy 21.827091 -159.932422) (xy 21.777513 -159.909779) (xy 21.731662 -159.880311) (xy 21.690472 -159.844618)
			(xy 21.654781 -159.803426) (xy 21.625314 -159.757575) (xy 21.602673 -159.707996) (xy 21.587318 -159.655701)
			(xy 21.579562 -159.601752) (xy 18.966196 -159.601752) (xy 18.785116 -161.154364) (xy 25.594308 -161.154364)
			(xy 25.598379 -161.098742) (xy 25.610505 -161.044305) (xy 25.630428 -160.992214) (xy 25.657724 -160.943579)
			(xy 25.69181 -160.899436) (xy 25.731959 -160.860727) (xy 25.777317 -160.828276) (xy 25.826917 -160.802775)
			(xy 25.879701 -160.784768) (xy 25.934544 -160.774638) (xy 25.990278 -160.772601) (xy 26.045715 -160.778701)
			(xy 26.099672 -160.792807) (xy 26.151001 -160.814619) (xy 26.198607 -160.843673) (xy 26.241475 -160.879348)
			(xy 26.278692 -160.920885) (xy 26.309465 -160.967398) (xy 26.309713 -160.967928) (xy 26.570432 -160.967928)
			(xy 26.570946 -160.940755) (xy 26.578642 -160.886956) (xy 26.593896 -160.834795) (xy 26.6164 -160.785326)
			(xy 26.645697 -160.739553) (xy 26.681194 -160.698402) (xy 26.722173 -160.662705) (xy 26.767804 -160.633187)
			(xy 26.817163 -160.610444) (xy 26.86925 -160.594938) (xy 26.89606 -160.590484) (xy 26.90991 -160.587923)
			(xy 26.935569 -160.576339) (xy 26.957091 -160.558192) (xy 26.972845 -160.53486) (xy 26.981632 -160.508114)
			(xy 26.982786 -160.479985) (xy 26.97622 -160.45261) (xy 26.96972 -160.440116) (xy 26.958083 -160.418595)
			(xy 26.939749 -160.373234) (xy 26.927352 -160.325905) (xy 26.921095 -160.277381) (xy 26.920698 -160.252918)
			(xy 26.921172 -160.225665) (xy 26.928927 -160.171714) (xy 26.944281 -160.119416) (xy 26.966922 -160.069836)
			(xy 26.996388 -160.023982) (xy 27.032081 -159.982789) (xy 27.073273 -159.947096) (xy 27.119125 -159.917627)
			(xy 27.168705 -159.894985) (xy 27.221003 -159.879629) (xy 27.274953 -159.871873) (xy 27.302206 -159.87141)
			(xy 27.329163 -159.871906) (xy 27.38254 -159.879496) (xy 27.434317 -159.894525) (xy 27.483463 -159.916692)
			(xy 27.528999 -159.945556) (xy 27.570019 -159.980543) (xy 27.58821 -160.000442) (xy 27.5982 -160.011136)
			(xy 27.622961 -160.026717) (xy 27.651124 -160.034637) (xy 27.680377 -160.034246) (xy 27.708318 -160.025576)
			(xy 27.732653 -160.009339) (xy 27.742388 -159.99841) (xy 27.760611 -159.977409) (xy 27.802113 -159.940408)
			(xy 27.848545 -159.909821) (xy 27.898924 -159.886295) (xy 27.952183 -159.870329) (xy 28.007195 -159.86226)
			(xy 28.034996 -159.861758) (xy 28.062246 -159.862281) (xy 28.11619 -159.870036) (xy 28.168482 -159.885389)
			(xy 28.218057 -159.908028) (xy 28.263906 -159.93749) (xy 28.305095 -159.973178) (xy 28.340787 -160.014364)
			(xy 28.370254 -160.060209) (xy 28.392897 -160.109782) (xy 28.408255 -160.162073) (xy 28.416016 -160.216016)
			(xy 28.416504 -160.243266) (xy 28.41498 -160.278064) (xy 28.414165 -160.293081) (xy 28.420272 -160.322513)
			(xy 28.434692 -160.348886) (xy 28.456174 -160.369911) (xy 28.482851 -160.383762) (xy 28.49753 -160.38703)
			(xy 28.526432 -160.392984) (xy 28.582076 -160.412623) (xy 28.634041 -160.440578) (xy 28.681095 -160.476185)
			(xy 28.702 -160.497012) (xy 28.713208 -160.507706) (xy 28.740419 -160.522471) (xy 28.770798 -160.528431)
			(xy 28.801571 -160.525042) (xy 28.829926 -160.512612) (xy 28.841954 -160.502854) (xy 28.862902 -160.485138)
			(xy 28.908953 -160.455318) (xy 28.958804 -160.43241) (xy 29.011425 -160.416888) (xy 29.065728 -160.409072)
			(xy 29.09316 -160.40862) (xy 29.122313 -160.409181) (xy 29.179938 -160.41806) (xy 29.235541 -160.435603)
			(xy 29.287829 -160.4614) (xy 29.335584 -160.494852) (xy 29.377693 -160.535179) (xy 29.413177 -160.581443)
			(xy 29.427678 -160.60674) (xy 29.435187 -160.619327) (xy 29.455948 -160.639992) (xy 29.481718 -160.653918)
			(xy 29.510381 -160.659958) (xy 29.53958 -160.657617) (xy 29.566914 -160.647087) (xy 29.590137 -160.629234)
			(xy 29.599128 -160.617662) (xy 29.61455 -160.596998) (xy 29.650085 -160.559636) (xy 29.690329 -160.5274)
			(xy 29.734547 -160.500876) (xy 29.781933 -160.480549) (xy 29.831626 -160.466789) (xy 29.882719 -160.459845)
			(xy 29.9085 -160.45942) (xy 29.934856 -160.459881) (xy 29.987065 -160.467149) (xy 30.037778 -160.481532)
			(xy 30.086028 -160.502757) (xy 30.130899 -160.53042) (xy 30.171536 -160.563994) (xy 30.189678 -160.583118)
			(xy 30.198948 -160.592739) (xy 30.221445 -160.607141) (xy 30.246909 -160.615206) (xy 30.273594 -160.616381)
			(xy 30.299669 -160.610586) (xy 30.323344 -160.598219) (xy 30.333442 -160.589468) (xy 30.354685 -160.570621)
			(xy 30.4017 -160.53877) (xy 30.452918 -160.514243) (xy 30.507207 -160.497582) (xy 30.563366 -160.489155)
			(xy 30.59176 -160.48863) (xy 30.619017 -160.489014) (xy 30.672978 -160.496767) (xy 30.725286 -160.512121)
			(xy 30.774876 -160.534764) (xy 30.820739 -160.564234) (xy 30.861941 -160.599931) (xy 30.897642 -160.641129)
			(xy 30.927117 -160.686989) (xy 30.949765 -160.736576) (xy 30.965124 -160.788883) (xy 30.972883 -160.842843)
			(xy 30.972883 -160.897357) (xy 30.965124 -160.951317) (xy 30.949765 -161.003624) (xy 30.927117 -161.053211)
			(xy 30.897642 -161.099071) (xy 30.861941 -161.140269) (xy 30.820739 -161.175966) (xy 30.774876 -161.205436)
			(xy 30.725286 -161.228079) (xy 30.672978 -161.243433) (xy 30.619017 -161.251186) (xy 30.59176 -161.251646)
			(xy 30.565402 -161.251223) (xy 30.513191 -161.243949) (xy 30.462478 -161.229559) (xy 30.414227 -161.208327)
			(xy 30.369357 -161.180657) (xy 30.328723 -161.147075) (xy 30.310582 -161.127948) (xy 30.301256 -161.118382)
			(xy 30.278778 -161.103969) (xy 30.253326 -161.095892) (xy 30.22665 -161.094705) (xy 30.200582 -161.100491)
			(xy 30.176913 -161.112851) (xy 30.166818 -161.121598) (xy 30.145586 -161.140458) (xy 30.098569 -161.172308)
			(xy 30.047348 -161.196834) (xy 29.993056 -161.213491) (xy 29.936895 -161.221913) (xy 29.9085 -161.222436)
			(xy 29.879345 -161.22193) (xy 29.821716 -161.213043) (xy 29.76611 -161.195493) (xy 29.713822 -161.169687)
			(xy 29.666068 -161.136226) (xy 29.62396 -161.09589) (xy 29.58848 -161.049617) (xy 29.573982 -161.024316)
			(xy 29.566526 -161.011692) (xy 29.545759 -160.991013) (xy 29.519977 -160.977081) (xy 29.491299 -160.971041)
			(xy 29.462087 -160.973391) (xy 29.434744 -160.983937) (xy 29.41152 -161.001811) (xy 29.402532 -161.013394)
			(xy 29.387061 -161.03402) (xy 29.351535 -161.071385) (xy 29.311301 -161.103626) (xy 29.267092 -161.130155)
			(xy 29.219712 -161.150488) (xy 29.170026 -161.164256) (xy 29.118939 -161.171207) (xy 29.09316 -161.171636)
			(xy 29.067638 -161.171269) (xy 29.017049 -161.164468) (xy 28.967819 -161.15098) (xy 28.920828 -161.131046)
			(xy 28.876916 -161.105023) (xy 28.836868 -161.073374) (xy 28.81884 -161.055304) (xy 28.807683 -161.044552)
			(xy 28.780455 -161.02979) (xy 28.750059 -161.02384) (xy 28.719275 -161.027244) (xy 28.690915 -161.039693)
			(xy 28.678886 -161.049462) (xy 28.657912 -161.067146) (xy 28.611869 -161.096973) (xy 28.562025 -161.119889)
			(xy 28.509409 -161.135419) (xy 28.45511 -161.143241) (xy 28.42768 -161.143696) (xy 28.400428 -161.143241)
			(xy 28.346478 -161.135481) (xy 28.294182 -161.120123) (xy 28.244604 -161.097479) (xy 28.198753 -161.068009)
			(xy 28.157563 -161.032314) (xy 28.121872 -160.991121) (xy 28.092406 -160.945268) (xy 28.069766 -160.895688)
			(xy 28.054412 -160.84339) (xy 28.046657 -160.78944) (xy 28.046172 -160.762188) (xy 28.047696 -160.72739)
			(xy 28.048492 -160.712374) (xy 28.042378 -160.682951) (xy 28.027959 -160.656584) (xy 28.006486 -160.635559)
			(xy 27.97982 -160.6217) (xy 27.965146 -160.618424) (xy 27.94033 -160.613351) (xy 27.892202 -160.597564)
			(xy 27.846588 -160.575544) (xy 27.804291 -160.54768) (xy 27.766054 -160.514462) (xy 27.748992 -160.495742)
			(xy 27.738999 -160.485052) (xy 27.714238 -160.469473) (xy 27.686077 -160.461554) (xy 27.656825 -160.461945)
			(xy 27.628885 -160.470613) (xy 27.604549 -160.486847) (xy 27.594814 -160.497774) (xy 27.576613 -160.51873)
			(xy 27.535206 -160.555693) (xy 27.48888 -160.586264) (xy 27.438613 -160.6098) (xy 27.385466 -160.625802)
			(xy 27.358086 -160.630362) (xy 27.344215 -160.632826) (xy 27.318551 -160.644429) (xy 27.297027 -160.662594)
			(xy 27.281276 -160.685943) (xy 27.272494 -160.712704) (xy 27.271346 -160.740845) (xy 27.277921 -160.768232)
			(xy 27.284426 -160.78073) (xy 27.296085 -160.80224) (xy 27.314413 -160.847605) (xy 27.326803 -160.894938)
			(xy 27.333054 -160.943464) (xy 27.333448 -160.967928) (xy 27.332962 -160.995179) (xy 27.325206 -161.049127)
			(xy 27.309851 -161.101422) (xy 27.287209 -161.150999) (xy 27.257743 -161.196849) (xy 27.222052 -161.23804)
			(xy 27.180861 -161.273731) (xy 27.135011 -161.303197) (xy 27.085434 -161.325839) (xy 27.033139 -161.341194)
			(xy 26.979191 -161.34895) (xy 26.924689 -161.34895) (xy 26.870741 -161.341194) (xy 26.818446 -161.325839)
			(xy 26.768869 -161.303197) (xy 26.723019 -161.273731) (xy 26.681828 -161.23804) (xy 26.646137 -161.196849)
			(xy 26.616671 -161.150999) (xy 26.594029 -161.101422) (xy 26.578674 -161.049127) (xy 26.570918 -160.995179)
			(xy 26.570432 -160.967928) (xy 26.309713 -160.967928) (xy 26.333137 -161.017895) (xy 26.349205 -161.071302)
			(xy 26.357325 -161.126478) (xy 26.357834 -161.154364) (xy 26.357325 -161.18225) (xy 26.349205 -161.237426)
			(xy 26.333137 -161.290833) (xy 26.309465 -161.34133) (xy 26.278692 -161.387843) (xy 26.241475 -161.42938)
			(xy 26.198607 -161.465055) (xy 26.151001 -161.494109) (xy 26.099672 -161.515921) (xy 26.045715 -161.530027)
			(xy 25.990278 -161.536127) (xy 25.934544 -161.53409) (xy 25.879701 -161.52396) (xy 25.826917 -161.505953)
			(xy 25.777317 -161.480452) (xy 25.731959 -161.448001) (xy 25.69181 -161.409292) (xy 25.657724 -161.365149)
			(xy 25.630428 -161.316514) (xy 25.610505 -161.264423) (xy 25.598379 -161.209986) (xy 25.594308 -161.154364)
			(xy 18.785116 -161.154364) (xy 18.678589 -162.067748) (xy 30.453582 -162.067748) (xy 30.457653 -162.012126)
			(xy 30.469779 -161.957689) (xy 30.489702 -161.905598) (xy 30.516998 -161.856963) (xy 30.551084 -161.81282)
			(xy 30.591233 -161.774111) (xy 30.636591 -161.74166) (xy 30.686191 -161.716159) (xy 30.738975 -161.698152)
			(xy 30.793818 -161.688022) (xy 30.849552 -161.685985) (xy 30.904989 -161.692085) (xy 30.958946 -161.706191)
			(xy 31.010275 -161.728003) (xy 31.057881 -161.757057) (xy 31.100749 -161.792732) (xy 31.137966 -161.834269)
			(xy 31.168739 -161.880782) (xy 31.192411 -161.931279) (xy 31.208479 -161.984686) (xy 31.216599 -162.039862)
			(xy 31.217108 -162.067748) (xy 31.216599 -162.095634) (xy 31.208479 -162.15081) (xy 31.192411 -162.204217)
			(xy 31.168739 -162.254714) (xy 31.137966 -162.301227) (xy 31.100749 -162.342764) (xy 31.057881 -162.378439)
			(xy 31.010275 -162.407493) (xy 30.958946 -162.429305) (xy 30.904989 -162.443411) (xy 30.849552 -162.449511)
			(xy 30.793818 -162.447474) (xy 30.738975 -162.437344) (xy 30.686191 -162.419337) (xy 30.636591 -162.393836)
			(xy 30.591233 -162.361385) (xy 30.551084 -162.322676) (xy 30.516998 -162.278533) (xy 30.489702 -162.229898)
			(xy 30.469779 -162.177807) (xy 30.457653 -162.12337) (xy 30.453582 -162.067748) (xy 18.678589 -162.067748)
			(xy 18.667984 -162.15868) (xy 18.618133 -162.586162) (xy 33.079942 -162.586162) (xy 33.084013 -162.53054)
			(xy 33.096139 -162.476103) (xy 33.116062 -162.424012) (xy 33.143358 -162.375377) (xy 33.177444 -162.331234)
			(xy 33.217593 -162.292525) (xy 33.262951 -162.260074) (xy 33.312551 -162.234573) (xy 33.365335 -162.216566)
			(xy 33.420178 -162.206436) (xy 33.475912 -162.204399) (xy 33.531349 -162.210499) (xy 33.585306 -162.224605)
			(xy 33.636635 -162.246417) (xy 33.684241 -162.275471) (xy 33.727109 -162.311146) (xy 33.764326 -162.352683)
			(xy 33.795099 -162.399196) (xy 33.818771 -162.449693) (xy 33.834839 -162.5031) (xy 33.842959 -162.558276)
			(xy 33.843468 -162.586162) (xy 33.842959 -162.614048) (xy 33.834839 -162.669224) (xy 33.818771 -162.722631)
			(xy 33.795099 -162.773128) (xy 33.764326 -162.819641) (xy 33.727109 -162.861178) (xy 33.684241 -162.896853)
			(xy 33.636635 -162.925907) (xy 33.585306 -162.947719) (xy 33.531349 -162.961825) (xy 33.475912 -162.967925)
			(xy 33.420178 -162.965888) (xy 33.365335 -162.955758) (xy 33.312551 -162.937751) (xy 33.262951 -162.91225)
			(xy 33.217593 -162.879799) (xy 33.177444 -162.84109) (xy 33.143358 -162.796947) (xy 33.116062 -162.748312)
			(xy 33.096139 -162.696221) (xy 33.084013 -162.641784) (xy 33.079942 -162.586162) (xy 18.618133 -162.586162)
			(xy 18.566031 -163.032948) (xy 20.014182 -163.032948) (xy 20.018253 -162.977326) (xy 20.030379 -162.922889)
			(xy 20.050302 -162.870798) (xy 20.077598 -162.822163) (xy 20.111684 -162.77802) (xy 20.151833 -162.739311)
			(xy 20.197191 -162.70686) (xy 20.246791 -162.681359) (xy 20.299575 -162.663352) (xy 20.354418 -162.653222)
			(xy 20.410152 -162.651185) (xy 20.465589 -162.657285) (xy 20.519546 -162.671391) (xy 20.570875 -162.693203)
			(xy 20.618481 -162.722257) (xy 20.661349 -162.757932) (xy 20.698566 -162.799469) (xy 20.729339 -162.845982)
			(xy 20.753011 -162.896479) (xy 20.769079 -162.949886) (xy 20.777199 -163.005062) (xy 20.777708 -163.032948)
			(xy 20.777199 -163.060834) (xy 20.769079 -163.11601) (xy 20.753011 -163.169417) (xy 20.729339 -163.219914)
			(xy 20.698566 -163.266427) (xy 20.661349 -163.307964) (xy 20.618481 -163.343639) (xy 20.570875 -163.372693)
			(xy 20.525196 -163.392104) (xy 22.73884 -163.392104) (xy 22.742911 -163.336482) (xy 22.755037 -163.282045)
			(xy 22.77496 -163.229954) (xy 22.802256 -163.181319) (xy 22.836342 -163.137176) (xy 22.876491 -163.098467)
			(xy 22.921849 -163.066016) (xy 22.971449 -163.040515) (xy 23.024233 -163.022508) (xy 23.079076 -163.012378)
			(xy 23.13481 -163.010341) (xy 23.190247 -163.016441) (xy 23.244204 -163.030547) (xy 23.295533 -163.052359)
			(xy 23.343139 -163.081413) (xy 23.386007 -163.117088) (xy 23.423224 -163.158625) (xy 23.453997 -163.205138)
			(xy 23.477669 -163.255635) (xy 23.493737 -163.309042) (xy 23.501857 -163.364218) (xy 23.502366 -163.392104)
			(xy 23.501857 -163.41999) (xy 23.493737 -163.475166) (xy 23.477669 -163.528573) (xy 23.453997 -163.57907)
			(xy 23.428637 -163.617402) (xy 31.594042 -163.617402) (xy 31.598113 -163.56178) (xy 31.610239 -163.507343)
			(xy 31.630162 -163.455252) (xy 31.657458 -163.406617) (xy 31.691544 -163.362474) (xy 31.731693 -163.323765)
			(xy 31.777051 -163.291314) (xy 31.826651 -163.265813) (xy 31.879435 -163.247806) (xy 31.934278 -163.237676)
			(xy 31.990012 -163.235639) (xy 32.045449 -163.241739) (xy 32.099406 -163.255845) (xy 32.150735 -163.277657)
			(xy 32.198341 -163.306711) (xy 32.241209 -163.342386) (xy 32.278426 -163.383923) (xy 32.309199 -163.430436)
			(xy 32.332871 -163.480933) (xy 32.348939 -163.53434) (xy 32.357059 -163.589516) (xy 32.357568 -163.617402)
			(xy 32.357059 -163.645288) (xy 32.348939 -163.700464) (xy 32.332871 -163.753871) (xy 32.309199 -163.804368)
			(xy 32.278426 -163.850881) (xy 32.241209 -163.892418) (xy 32.198341 -163.928093) (xy 32.150735 -163.957147)
			(xy 32.099406 -163.978959) (xy 32.045449 -163.993065) (xy 31.990012 -163.999165) (xy 31.934278 -163.997128)
			(xy 31.879435 -163.986998) (xy 31.826651 -163.968991) (xy 31.777051 -163.94349) (xy 31.731693 -163.911039)
			(xy 31.691544 -163.87233) (xy 31.657458 -163.828187) (xy 31.630162 -163.779552) (xy 31.610239 -163.727461)
			(xy 31.598113 -163.673024) (xy 31.594042 -163.617402) (xy 23.428637 -163.617402) (xy 23.423224 -163.625583)
			(xy 23.386007 -163.66712) (xy 23.343139 -163.702795) (xy 23.295533 -163.731849) (xy 23.244204 -163.753661)
			(xy 23.190247 -163.767767) (xy 23.13481 -163.773867) (xy 23.079076 -163.77183) (xy 23.024233 -163.7617)
			(xy 22.971449 -163.743693) (xy 22.921849 -163.718192) (xy 22.876491 -163.685741) (xy 22.836342 -163.647032)
			(xy 22.802256 -163.602889) (xy 22.77496 -163.554254) (xy 22.755037 -163.502163) (xy 22.742911 -163.447726)
			(xy 22.73884 -163.392104) (xy 20.525196 -163.392104) (xy 20.519546 -163.394505) (xy 20.465589 -163.408611)
			(xy 20.410152 -163.414711) (xy 20.354418 -163.412674) (xy 20.299575 -163.402544) (xy 20.246791 -163.384537)
			(xy 20.197191 -163.359036) (xy 20.151833 -163.326585) (xy 20.111684 -163.287876) (xy 20.077598 -163.243733)
			(xy 20.050302 -163.195098) (xy 20.030379 -163.143007) (xy 20.018253 -163.08857) (xy 20.014182 -163.032948)
			(xy 18.566031 -163.032948) (xy 18.455132 -163.983924) (xy 18.430543 -164.194744) (xy 20.752814 -164.194744)
			(xy 20.756885 -164.139122) (xy 20.769011 -164.084685) (xy 20.788934 -164.032594) (xy 20.81623 -163.983959)
			(xy 20.850316 -163.939816) (xy 20.890465 -163.901107) (xy 20.935823 -163.868656) (xy 20.985423 -163.843155)
			(xy 21.038207 -163.825148) (xy 21.09305 -163.815018) (xy 21.148784 -163.812981) (xy 21.204221 -163.819081)
			(xy 21.258178 -163.833187) (xy 21.309507 -163.854999) (xy 21.357113 -163.884053) (xy 21.399981 -163.919728)
			(xy 21.437198 -163.961265) (xy 21.467971 -164.007778) (xy 21.491643 -164.058275) (xy 21.507711 -164.111682)
			(xy 21.515831 -164.166858) (xy 21.51634 -164.194744) (xy 21.515831 -164.22263) (xy 21.507711 -164.277806)
			(xy 21.500223 -164.302694) (xy 33.044382 -164.302694) (xy 33.048453 -164.247072) (xy 33.060579 -164.192635)
			(xy 33.080502 -164.140544) (xy 33.107798 -164.091909) (xy 33.141884 -164.047766) (xy 33.182033 -164.009057)
			(xy 33.227391 -163.976606) (xy 33.276991 -163.951105) (xy 33.329775 -163.933098) (xy 33.384618 -163.922968)
			(xy 33.440352 -163.920931) (xy 33.495789 -163.927031) (xy 33.549746 -163.941137) (xy 33.601075 -163.962949)
			(xy 33.648681 -163.992003) (xy 33.691549 -164.027678) (xy 33.728766 -164.069215) (xy 33.759539 -164.115728)
			(xy 33.783211 -164.166225) (xy 33.799279 -164.219632) (xy 33.807399 -164.274808) (xy 33.807908 -164.302694)
			(xy 33.807399 -164.33058) (xy 33.799279 -164.385756) (xy 33.783211 -164.439163) (xy 33.759539 -164.48966)
			(xy 33.728766 -164.536173) (xy 33.691549 -164.57771) (xy 33.648681 -164.613385) (xy 33.601075 -164.642439)
			(xy 33.549746 -164.664251) (xy 33.495789 -164.678357) (xy 33.440352 -164.684457) (xy 33.384618 -164.68242)
			(xy 33.329775 -164.67229) (xy 33.276991 -164.654283) (xy 33.227391 -164.628782) (xy 33.182033 -164.596331)
			(xy 33.141884 -164.557622) (xy 33.107798 -164.513479) (xy 33.080502 -164.464844) (xy 33.060579 -164.412753)
			(xy 33.048453 -164.358316) (xy 33.044382 -164.302694) (xy 21.500223 -164.302694) (xy 21.491643 -164.331213)
			(xy 21.467971 -164.38171) (xy 21.437198 -164.428223) (xy 21.399981 -164.46976) (xy 21.357113 -164.505435)
			(xy 21.309507 -164.534489) (xy 21.258178 -164.556301) (xy 21.204221 -164.570407) (xy 21.148784 -164.576507)
			(xy 21.09305 -164.57447) (xy 21.038207 -164.56434) (xy 20.985423 -164.546333) (xy 20.935823 -164.520832)
			(xy 20.890465 -164.488381) (xy 20.850316 -164.449672) (xy 20.81623 -164.405529) (xy 20.788934 -164.356894)
			(xy 20.769011 -164.304803) (xy 20.756885 -164.250366) (xy 20.752814 -164.194744) (xy 18.430543 -164.194744)
			(xy 18.337282 -164.994336) (xy 22.751794 -164.994336) (xy 22.755865 -164.938714) (xy 22.767991 -164.884277)
			(xy 22.787914 -164.832186) (xy 22.81521 -164.783551) (xy 22.849296 -164.739408) (xy 22.889445 -164.700699)
			(xy 22.934803 -164.668248) (xy 22.984403 -164.642747) (xy 23.037187 -164.62474) (xy 23.09203 -164.61461)
			(xy 23.147764 -164.612573) (xy 23.203201 -164.618673) (xy 23.257158 -164.632779) (xy 23.308487 -164.654591)
			(xy 23.356093 -164.683645) (xy 23.398961 -164.71932) (xy 23.436178 -164.760857) (xy 23.466951 -164.80737)
			(xy 23.490623 -164.857867) (xy 23.506691 -164.911274) (xy 23.514811 -164.96645) (xy 23.51532 -164.994336)
			(xy 23.514811 -165.022222) (xy 23.506691 -165.077398) (xy 23.490623 -165.130805) (xy 23.466951 -165.181302)
			(xy 23.436178 -165.227815) (xy 23.398961 -165.269352) (xy 23.356093 -165.305027) (xy 23.308487 -165.334081)
			(xy 23.257158 -165.355893) (xy 23.203201 -165.369999) (xy 23.147764 -165.376099) (xy 23.09203 -165.374062)
			(xy 23.037187 -165.363932) (xy 22.984403 -165.345925) (xy 22.934803 -165.320424) (xy 22.889445 -165.287973)
			(xy 22.849296 -165.249264) (xy 22.81521 -165.205121) (xy 22.787914 -165.156486) (xy 22.767991 -165.104395)
			(xy 22.755865 -165.049958) (xy 22.751794 -164.994336) (xy 18.337282 -164.994336) (xy 18.248999 -165.751256)
			(xy 20.741892 -165.751256) (xy 20.745963 -165.695634) (xy 20.758089 -165.641197) (xy 20.778012 -165.589106)
			(xy 20.805308 -165.540471) (xy 20.839394 -165.496328) (xy 20.879543 -165.457619) (xy 20.924901 -165.425168)
			(xy 20.974501 -165.399667) (xy 21.027285 -165.38166) (xy 21.082128 -165.37153) (xy 21.137862 -165.369493)
			(xy 21.193299 -165.375593) (xy 21.247256 -165.389699) (xy 21.298585 -165.411511) (xy 21.346191 -165.440565)
			(xy 21.389059 -165.47624) (xy 21.426276 -165.517777) (xy 21.457049 -165.56429) (xy 21.469681 -165.591236)
			(xy 30.677612 -165.591236) (xy 30.678089 -165.563983) (xy 30.685841 -165.510032) (xy 30.701194 -165.457733)
			(xy 30.723834 -165.408151) (xy 30.7533 -165.362297) (xy 30.788992 -165.321104) (xy 30.830184 -165.285409)
			(xy 30.876037 -165.255941) (xy 30.925618 -165.2333) (xy 30.977916 -165.217945) (xy 31.031867 -165.21019)
			(xy 31.05912 -165.209728) (xy 31.074876 -165.20987) (xy 31.106285 -165.21241) (xy 31.121858 -165.214808)
			(xy 31.136247 -165.216682) (xy 31.165042 -165.213223) (xy 31.191699 -165.2018) (xy 31.214065 -165.183337)
			(xy 31.230331 -165.159326) (xy 31.239182 -165.131707) (xy 31.239903 -165.102714) (xy 31.236666 -165.08857)
			(xy 31.230712 -165.064563) (xy 31.224341 -165.015512) (xy 31.223966 -164.99078) (xy 31.224477 -164.963529)
			(xy 31.232236 -164.909581) (xy 31.247594 -164.857286) (xy 31.270238 -164.80771) (xy 31.299707 -164.76186)
			(xy 31.335401 -164.720672) (xy 31.376594 -164.684982) (xy 31.422447 -164.655518) (xy 31.472026 -164.63288)
			(xy 31.524322 -164.617527) (xy 31.57827 -164.609774) (xy 31.632773 -164.609777) (xy 31.686721 -164.617537)
			(xy 31.739016 -164.632895) (xy 31.788592 -164.655539) (xy 31.834441 -164.685009) (xy 31.87563 -164.720703)
			(xy 31.911319 -164.761896) (xy 31.940783 -164.807748) (xy 31.963421 -164.857327) (xy 31.978773 -164.909624)
			(xy 31.986526 -164.963572) (xy 31.986523 -165.018075) (xy 31.978763 -165.072023) (xy 31.963404 -165.124318)
			(xy 31.94076 -165.173894) (xy 31.91129 -165.219743) (xy 31.875596 -165.260931) (xy 31.834403 -165.29662)
			(xy 31.78855 -165.326084) (xy 31.738971 -165.348722) (xy 31.686674 -165.364074) (xy 31.632726 -165.371827)
			(xy 31.605474 -165.372288) (xy 31.589718 -165.372146) (xy 31.558309 -165.369606) (xy 31.542736 -165.367208)
			(xy 31.528349 -165.365308) (xy 31.49955 -165.368769) (xy 31.472889 -165.380195) (xy 31.450522 -165.398663)
			(xy 31.434256 -165.422679) (xy 31.425406 -165.450303) (xy 31.424689 -165.4793) (xy 31.427928 -165.493446)
			(xy 31.433885 -165.517453) (xy 31.440254 -165.566504) (xy 31.440628 -165.591236) (xy 31.440072 -165.62106)
			(xy 31.430817 -165.679986) (xy 31.412508 -165.736754) (xy 31.385589 -165.789982) (xy 31.350717 -165.838374)
			(xy 31.330138 -165.859968) (xy 31.320921 -165.869896) (xy 31.307608 -165.893478) (xy 31.300954 -165.919729)
			(xy 31.301426 -165.946805) (xy 31.308991 -165.972808) (xy 31.323119 -165.995911) (xy 31.332678 -166.00551)
			(xy 31.351326 -166.023609) (xy 31.384039 -166.063986) (xy 31.410967 -166.108431) (xy 31.43161 -166.15612)
			(xy 31.445586 -166.206172) (xy 31.452637 -166.257657) (xy 31.453074 -166.28364) (xy 31.452588 -166.310891)
			(xy 31.444832 -166.364839) (xy 31.429477 -166.417134) (xy 31.406835 -166.466711) (xy 31.377369 -166.512561)
			(xy 31.341678 -166.553752) (xy 31.300487 -166.589443) (xy 31.254637 -166.618909) (xy 31.20506 -166.641551)
			(xy 31.152765 -166.656906) (xy 31.098817 -166.664662) (xy 31.044315 -166.664662) (xy 30.990367 -166.656906)
			(xy 30.938072 -166.641551) (xy 30.888495 -166.618909) (xy 30.842645 -166.589443) (xy 30.801454 -166.553752)
			(xy 30.765763 -166.512561) (xy 30.736297 -166.466711) (xy 30.713655 -166.417134) (xy 30.6983 -166.364839)
			(xy 30.690544 -166.310891) (xy 30.690058 -166.28364) (xy 30.690603 -166.253815) (xy 30.699861 -166.19489)
			(xy 30.718174 -166.138122) (xy 30.745094 -166.084894) (xy 30.779968 -166.036502) (xy 30.800548 -166.014908)
			(xy 30.809791 -166.005002) (xy 30.823104 -165.981413) (xy 30.829756 -165.955157) (xy 30.829279 -165.928075)
			(xy 30.821707 -165.902069) (xy 30.807572 -165.878964) (xy 30.798008 -165.869366) (xy 30.779346 -165.851282)
			(xy 30.746635 -165.810901) (xy 30.719709 -165.766453) (xy 30.699069 -165.71876) (xy 30.685095 -165.668707)
			(xy 30.678047 -165.61722) (xy 30.677612 -165.591236) (xy 21.469681 -165.591236) (xy 21.480721 -165.614787)
			(xy 21.496789 -165.668194) (xy 21.504909 -165.72337) (xy 21.505418 -165.751256) (xy 21.504909 -165.779142)
			(xy 21.496789 -165.834318) (xy 21.480721 -165.887725) (xy 21.457049 -165.938222) (xy 21.426276 -165.984735)
			(xy 21.389059 -166.026272) (xy 21.346191 -166.061947) (xy 21.298585 -166.091001) (xy 21.247256 -166.112813)
			(xy 21.193299 -166.126919) (xy 21.137862 -166.133019) (xy 21.082128 -166.130982) (xy 21.027285 -166.120852)
			(xy 20.974501 -166.102845) (xy 20.924901 -166.077344) (xy 20.879543 -166.044893) (xy 20.839394 -166.006184)
			(xy 20.805308 -165.962041) (xy 20.778012 -165.913406) (xy 20.758089 -165.861315) (xy 20.745963 -165.806878)
			(xy 20.741892 -165.751256) (xy 18.248999 -165.751256) (xy 18.190459 -166.25316) (xy 23.932132 -166.25316)
			(xy 23.936203 -166.197538) (xy 23.948329 -166.143101) (xy 23.968252 -166.09101) (xy 23.995548 -166.042375)
			(xy 24.029634 -165.998232) (xy 24.069783 -165.959523) (xy 24.115141 -165.927072) (xy 24.164741 -165.901571)
			(xy 24.217525 -165.883564) (xy 24.272368 -165.873434) (xy 24.328102 -165.871397) (xy 24.383539 -165.877497)
			(xy 24.437496 -165.891603) (xy 24.488825 -165.913415) (xy 24.536431 -165.942469) (xy 24.579299 -165.978144)
			(xy 24.616516 -166.019681) (xy 24.647289 -166.066194) (xy 24.670961 -166.116691) (xy 24.687029 -166.170098)
			(xy 24.695149 -166.225274) (xy 24.695658 -166.25316) (xy 24.695149 -166.281046) (xy 24.687029 -166.336222)
			(xy 24.670961 -166.389629) (xy 24.647289 -166.440126) (xy 24.616516 -166.486639) (xy 24.579299 -166.528176)
			(xy 24.536431 -166.563851) (xy 24.488825 -166.592905) (xy 24.437496 -166.614717) (xy 24.383539 -166.628823)
			(xy 24.328102 -166.634923) (xy 24.272368 -166.632886) (xy 24.217525 -166.622756) (xy 24.164741 -166.604749)
			(xy 24.115141 -166.579248) (xy 24.069783 -166.546797) (xy 24.029634 -166.508088) (xy 23.995548 -166.463945)
			(xy 23.968252 -166.41531) (xy 23.948329 -166.363219) (xy 23.936203 -166.308782) (xy 23.932132 -166.25316)
			(xy 18.190459 -166.25316) (xy 17.909285 -168.663874) (xy 19.969224 -168.663874) (xy 19.973295 -168.608252)
			(xy 19.985421 -168.553815) (xy 20.005344 -168.501724) (xy 20.03264 -168.453089) (xy 20.066726 -168.408946)
			(xy 20.106875 -168.370237) (xy 20.152233 -168.337786) (xy 20.201833 -168.312285) (xy 20.254617 -168.294278)
			(xy 20.30946 -168.284148) (xy 20.365194 -168.282111) (xy 20.420631 -168.288211) (xy 20.474588 -168.302317)
			(xy 20.525917 -168.324129) (xy 20.573523 -168.353183) (xy 20.616391 -168.388858) (xy 20.653608 -168.430395)
			(xy 20.684381 -168.476908) (xy 20.708053 -168.527405) (xy 20.724121 -168.580812) (xy 20.732241 -168.635988)
			(xy 20.73275 -168.663874) (xy 20.732241 -168.69176) (xy 20.724121 -168.746936) (xy 20.708053 -168.800343)
			(xy 20.684381 -168.85084) (xy 20.653608 -168.897353) (xy 20.616391 -168.93889) (xy 20.573523 -168.974565)
			(xy 20.525917 -169.003619) (xy 20.474588 -169.025431) (xy 20.420631 -169.039537) (xy 20.365194 -169.045637)
			(xy 20.30946 -169.0436) (xy 20.254617 -169.03347) (xy 20.201833 -169.015463) (xy 20.152233 -168.989962)
			(xy 20.106875 -168.957511) (xy 20.066726 -168.918802) (xy 20.03264 -168.874659) (xy 20.005344 -168.826024)
			(xy 19.985421 -168.773933) (xy 19.973295 -168.719496) (xy 19.969224 -168.663874) (xy 17.909285 -168.663874)
			(xy 17.826482 -169.373804) (xy 17.809718 -169.516806) (xy 17.809718 -169.624756) (xy 18.555968 -169.624756)
			(xy 18.560039 -169.569134) (xy 18.572165 -169.514697) (xy 18.592088 -169.462606) (xy 18.619384 -169.413971)
			(xy 18.65347 -169.369828) (xy 18.693619 -169.331119) (xy 18.738977 -169.298668) (xy 18.788577 -169.273167)
			(xy 18.841361 -169.25516) (xy 18.896204 -169.24503) (xy 18.951938 -169.242993) (xy 19.007375 -169.249093)
			(xy 19.061332 -169.263199) (xy 19.112661 -169.285011) (xy 19.160267 -169.314065) (xy 19.203135 -169.34974)
			(xy 19.240352 -169.391277) (xy 19.271125 -169.43779) (xy 19.294797 -169.488287) (xy 19.310865 -169.541694)
			(xy 19.318985 -169.59687) (xy 19.319494 -169.624756) (xy 19.318985 -169.652642) (xy 19.318641 -169.654982)
			(xy 19.972272 -169.654982) (xy 19.976343 -169.59936) (xy 19.988469 -169.544923) (xy 20.008392 -169.492832)
			(xy 20.035688 -169.444197) (xy 20.069774 -169.400054) (xy 20.109923 -169.361345) (xy 20.155281 -169.328894)
			(xy 20.204881 -169.303393) (xy 20.257665 -169.285386) (xy 20.312508 -169.275256) (xy 20.368242 -169.273219)
			(xy 20.423679 -169.279319) (xy 20.477636 -169.293425) (xy 20.528965 -169.315237) (xy 20.576571 -169.344291)
			(xy 20.619439 -169.379966) (xy 20.656656 -169.421503) (xy 20.687429 -169.468016) (xy 20.711101 -169.518513)
			(xy 20.727169 -169.57192) (xy 20.735289 -169.627096) (xy 20.735798 -169.654982) (xy 20.735289 -169.682868)
			(xy 20.727169 -169.738044) (xy 20.711101 -169.791451) (xy 20.687429 -169.841948) (xy 20.656656 -169.888461)
			(xy 20.619439 -169.929998) (xy 20.576571 -169.965673) (xy 20.528965 -169.994727) (xy 20.477636 -170.016539)
			(xy 20.423679 -170.030645) (xy 20.368242 -170.036745) (xy 20.312508 -170.034708) (xy 20.257665 -170.024578)
			(xy 20.204881 -170.006571) (xy 20.155281 -169.98107) (xy 20.109923 -169.948619) (xy 20.069774 -169.90991)
			(xy 20.035688 -169.865767) (xy 20.008392 -169.817132) (xy 19.988469 -169.765041) (xy 19.976343 -169.710604)
			(xy 19.972272 -169.654982) (xy 19.318641 -169.654982) (xy 19.310865 -169.707818) (xy 19.294797 -169.761225)
			(xy 19.271125 -169.811722) (xy 19.240352 -169.858235) (xy 19.203135 -169.899772) (xy 19.160267 -169.935447)
			(xy 19.112661 -169.964501) (xy 19.061332 -169.986313) (xy 19.007375 -170.000419) (xy 18.951938 -170.006519)
			(xy 18.896204 -170.004482) (xy 18.841361 -169.994352) (xy 18.788577 -169.976345) (xy 18.738977 -169.950844)
			(xy 18.693619 -169.918393) (xy 18.65347 -169.879684) (xy 18.619384 -169.835541) (xy 18.592088 -169.786906)
			(xy 18.572165 -169.734815) (xy 18.560039 -169.680378) (xy 18.555968 -169.624756) (xy 17.809718 -169.624756)
			(xy 17.809718 -174.79264) (xy 21.571964 -174.79264) (xy 21.576035 -174.737018) (xy 21.588161 -174.682581)
			(xy 21.608084 -174.63049) (xy 21.63538 -174.581855) (xy 21.669466 -174.537712) (xy 21.709615 -174.499003)
			(xy 21.754973 -174.466552) (xy 21.804573 -174.441051) (xy 21.857357 -174.423044) (xy 21.9122 -174.412914)
			(xy 21.967934 -174.410877) (xy 22.023371 -174.416977) (xy 22.077328 -174.431083) (xy 22.128657 -174.452895)
			(xy 22.176263 -174.481949) (xy 22.219131 -174.517624) (xy 22.256348 -174.559161) (xy 22.287121 -174.605674)
			(xy 22.310793 -174.656171) (xy 22.326861 -174.709578) (xy 22.334981 -174.764754) (xy 22.33549 -174.79264)
			(xy 22.334981 -174.820526) (xy 22.326861 -174.875702) (xy 22.310793 -174.929109) (xy 22.287121 -174.979606)
			(xy 22.256348 -175.026119) (xy 22.219131 -175.067656) (xy 22.176263 -175.103331) (xy 22.128657 -175.132385)
			(xy 22.077328 -175.154197) (xy 22.023371 -175.168303) (xy 21.967934 -175.174403) (xy 21.9122 -175.172366)
			(xy 21.857357 -175.162236) (xy 21.804573 -175.144229) (xy 21.754973 -175.118728) (xy 21.709615 -175.086277)
			(xy 21.669466 -175.047568) (xy 21.63538 -175.003425) (xy 21.608084 -174.95479) (xy 21.588161 -174.902699)
			(xy 21.576035 -174.848262) (xy 21.571964 -174.79264) (xy 17.809718 -174.79264) (xy 17.809718 -175.210216)
			(xy 20.264372 -175.210216) (xy 20.268443 -175.154594) (xy 20.280569 -175.100157) (xy 20.300492 -175.048066)
			(xy 20.327788 -174.999431) (xy 20.361874 -174.955288) (xy 20.402023 -174.916579) (xy 20.447381 -174.884128)
			(xy 20.496981 -174.858627) (xy 20.549765 -174.84062) (xy 20.604608 -174.83049) (xy 20.660342 -174.828453)
			(xy 20.715779 -174.834553) (xy 20.769736 -174.848659) (xy 20.821065 -174.870471) (xy 20.868671 -174.899525)
			(xy 20.911539 -174.9352) (xy 20.948756 -174.976737) (xy 20.979529 -175.02325) (xy 21.003201 -175.073747)
			(xy 21.019269 -175.127154) (xy 21.027389 -175.18233) (xy 21.027898 -175.210216) (xy 21.027389 -175.238102)
			(xy 21.019269 -175.293278) (xy 21.003201 -175.346685) (xy 20.979529 -175.397182) (xy 20.948756 -175.443695)
			(xy 20.911539 -175.485232) (xy 20.868671 -175.520907) (xy 20.821065 -175.549961) (xy 20.769736 -175.571773)
			(xy 20.715779 -175.585879) (xy 20.660342 -175.591979) (xy 20.604608 -175.589942) (xy 20.549765 -175.579812)
			(xy 20.496981 -175.561805) (xy 20.447381 -175.536304) (xy 20.402023 -175.503853) (xy 20.361874 -175.465144)
			(xy 20.327788 -175.421001) (xy 20.300492 -175.372366) (xy 20.280569 -175.320275) (xy 20.268443 -175.265838)
			(xy 20.264372 -175.210216) (xy 17.809718 -175.210216) (xy 17.809718 -175.83404) (xy 23.37714 -175.83404)
			(xy 23.381229 -175.778158) (xy 23.393412 -175.723468) (xy 23.413428 -175.671134) (xy 23.440851 -175.622272)
			(xy 23.475096 -175.577924) (xy 23.515432 -175.539034) (xy 23.561002 -175.506432) (xy 23.610833 -175.480813)
			(xy 23.663863 -175.462721) (xy 23.718961 -175.452544) (xy 23.774955 -175.450498) (xy 23.83065 -175.456626)
			(xy 23.884859 -175.470798) (xy 23.936427 -175.492712) (xy 23.984255 -175.521901) (xy 24.027323 -175.557742)
			(xy 24.064713 -175.599472) (xy 24.095629 -175.646202) (xy 24.119412 -175.696935) (xy 24.135554 -175.750591)
			(xy 24.143713 -175.806025) (xy 24.144224 -175.83404) (xy 24.143713 -175.862055) (xy 24.135554 -175.917489)
			(xy 24.119412 -175.971145) (xy 24.095629 -176.021878) (xy 24.064713 -176.068608) (xy 24.027323 -176.110338)
			(xy 23.984255 -176.146179) (xy 23.936427 -176.175368) (xy 23.884859 -176.197282) (xy 23.83065 -176.211454)
			(xy 23.774955 -176.217582) (xy 23.718961 -176.215536) (xy 23.663863 -176.205359) (xy 23.610833 -176.187267)
			(xy 23.561002 -176.161648) (xy 23.515432 -176.129046) (xy 23.475096 -176.090156) (xy 23.440851 -176.045808)
			(xy 23.413428 -175.996946) (xy 23.393412 -175.944612) (xy 23.381229 -175.889922) (xy 23.37714 -175.83404)
			(xy 17.809718 -175.83404) (xy 17.809718 -177.191416) (xy 20.962872 -177.191416) (xy 20.966943 -177.135794)
			(xy 20.979069 -177.081357) (xy 20.998992 -177.029266) (xy 21.026288 -176.980631) (xy 21.060374 -176.936488)
			(xy 21.100523 -176.897779) (xy 21.145881 -176.865328) (xy 21.195481 -176.839827) (xy 21.248265 -176.82182)
			(xy 21.303108 -176.81169) (xy 21.358842 -176.809653) (xy 21.414279 -176.815753) (xy 21.468236 -176.829859)
			(xy 21.519565 -176.851671) (xy 21.567171 -176.880725) (xy 21.610039 -176.9164) (xy 21.647256 -176.957937)
			(xy 21.678029 -177.00445) (xy 21.701701 -177.054947) (xy 21.717769 -177.108354) (xy 21.725889 -177.16353)
			(xy 21.726398 -177.191416) (xy 21.725889 -177.219302) (xy 21.717769 -177.274478) (xy 21.701701 -177.327885)
			(xy 21.678029 -177.378382) (xy 21.647256 -177.424895) (xy 21.610039 -177.466432) (xy 21.567171 -177.502107)
			(xy 21.519565 -177.531161) (xy 21.468236 -177.552973) (xy 21.414279 -177.567079) (xy 21.358842 -177.573179)
			(xy 21.303108 -177.571142) (xy 21.248265 -177.561012) (xy 21.195481 -177.543005) (xy 21.145881 -177.517504)
			(xy 21.100523 -177.485053) (xy 21.060374 -177.446344) (xy 21.026288 -177.402201) (xy 20.998992 -177.353566)
			(xy 20.979069 -177.301475) (xy 20.966943 -177.247038) (xy 20.962872 -177.191416) (xy 17.809718 -177.191416)
			(xy 17.809718 -179.549044) (xy 17.810284 -179.564029) (xy 17.819042 -179.592692) (xy 17.835735 -179.617585)
			(xy 17.858929 -179.636568) (xy 17.88663 -179.648011) (xy 17.916459 -179.650932) (xy 17.945853 -179.645078)
			(xy 17.972288 -179.630953) (xy 17.9832 -179.620672) (xy 19.476466 -178.127406) (xy 19.480276 -178.118262)
			(xy 19.491315 -178.093094) (xy 19.519562 -178.045953) (xy 19.554277 -178.00335) (xy 19.594742 -177.966164)
			(xy 19.640121 -177.935165) (xy 19.689475 -177.910994) (xy 19.741786 -177.894149) (xy 19.795972 -177.884979)
			(xy 19.82343 -177.88382) (xy 19.831558 -177.88382) (xy 19.859587 -177.884259) (xy 19.915057 -177.892346)
			(xy 19.968749 -177.908455) (xy 20.019509 -177.932241) (xy 20.04314 -177.94732) (xy 21.289772 -177.94732)
			(xy 21.314754 -177.947836) (xy 21.364096 -177.955697) (xy 21.411605 -177.971165) (xy 21.456116 -177.993864)
			(xy 21.496536 -178.023234) (xy 21.514562 -178.040538) (xy 22.179534 -178.705764) (xy 24.137112 -178.705764)
			(xy 24.568404 -178.274726) (xy 24.585422 -178.257708) (xy 24.59475 -178.247825) (xy 24.608283 -178.224268)
			(xy 24.615129 -178.197978) (xy 24.614806 -178.170812) (xy 24.607336 -178.144693) (xy 24.593247 -178.121464)
			(xy 24.573535 -178.10277) (xy 24.5618 -178.09591) (xy 24.536518 -178.084455) (xy 24.489284 -178.055308)
			(xy 24.44677 -178.019626) (xy 24.409876 -177.97816) (xy 24.379379 -177.931786) (xy 24.355923 -177.881483)
			(xy 24.340003 -177.828312) (xy 24.331954 -177.773396) (xy 24.331422 -177.745644) (xy 24.331939 -177.717283)
			(xy 24.340336 -177.661185) (xy 24.356951 -177.606951) (xy 24.381418 -177.555776) (xy 24.413196 -177.508791)
			(xy 24.451585 -177.467033) (xy 24.495736 -177.431422) (xy 24.544676 -177.402746) (xy 24.597325 -177.381637)
			(xy 24.624792 -177.37455) (xy 24.663908 -177.365152) (xy 24.663908 -177.127154) (xy 24.657812 -177.115978)
			(xy 24.645851 -177.092689) (xy 24.628878 -177.043166) (xy 24.620254 -176.991531) (xy 24.619712 -176.965356)
			(xy 24.619712 -175.405542) (xy 24.620267 -175.379368) (xy 24.628888 -175.327733) (xy 24.645856 -175.27821)
			(xy 24.657812 -175.25492) (xy 24.663908 -175.243744) (xy 24.663908 -175.062896) (xy 24.664372 -175.037945)
			(xy 24.672179 -174.988657) (xy 24.687601 -174.941198) (xy 24.710257 -174.896735) (xy 24.73959 -174.856364)
			(xy 24.756872 -174.83836) (xy 24.827484 -174.767748) (xy 21.23059 -171.170854) (xy 21.229574 -171.169838)
			(xy 21.223986 -171.16425) (xy 21.223478 -171.163488) (xy 21.137626 -171.077636) (xy 21.137626 -170.947334)
			(xy 21.137372 -170.946064) (xy 21.137372 -170.061128) (xy 21.122295 -170.037494) (xy 21.098492 -169.986741)
			(xy 21.082381 -169.933049) (xy 21.074308 -169.877576) (xy 21.073872 -169.849546) (xy 21.073872 -169.840656)
			(xy 21.075095 -169.812912) (xy 21.084572 -169.758194) (xy 21.101878 -169.705428) (xy 21.12665 -169.655726)
			(xy 21.158363 -169.61014) (xy 21.196347 -169.56963) (xy 21.239802 -169.535053) (xy 21.287808 -169.507139)
			(xy 21.339354 -169.486477) (xy 21.366226 -169.479468) (xy 21.380196 -169.475912) (xy 21.602192 -169.253916)
			(xy 21.602192 -169.11701) (xy 21.515832 -169.11701) (xy 21.50364 -169.150284) (xy 21.493103 -169.17739)
			(xy 21.465002 -169.228303) (xy 21.429498 -169.27436) (xy 21.387414 -169.314494) (xy 21.339725 -169.347775)
			(xy 21.287537 -169.373431) (xy 21.232059 -169.390867) (xy 21.174577 -169.39968) (xy 21.1455 -169.40022)
			(xy 21.118248 -169.399734) (xy 21.064298 -169.391977) (xy 21.012002 -169.376622) (xy 20.962423 -169.35398)
			(xy 20.916571 -169.324513) (xy 20.87538 -169.28882) (xy 20.839687 -169.247629) (xy 20.81022 -169.201777)
			(xy 20.787578 -169.152198) (xy 20.772223 -169.099902) (xy 20.764466 -169.045952) (xy 20.764466 -168.991448)
			(xy 20.772223 -168.937498) (xy 20.787578 -168.885202) (xy 20.81022 -168.835623) (xy 20.839687 -168.789771)
			(xy 20.87538 -168.74858) (xy 20.916571 -168.712887) (xy 20.962423 -168.68342) (xy 21.012002 -168.660778)
			(xy 21.064298 -168.645423) (xy 21.118248 -168.637666) (xy 21.1455 -168.637204) (xy 21.172204 -168.637652)
			(xy 21.22509 -168.645101) (xy 21.27642 -168.659853) (xy 21.32519 -168.681621) (xy 21.370448 -168.709978)
			(xy 21.411308 -168.74437) (xy 21.429472 -168.76395) (xy 21.440491 -168.774023) (xy 21.466925 -168.787866)
			(xy 21.496231 -168.793481) (xy 21.52591 -168.79039) (xy 21.55343 -168.778857) (xy 21.576444 -168.759864)
			(xy 21.59299 -168.735032) (xy 21.601656 -168.706479) (xy 21.602192 -168.69156) (xy 21.602192 -167.885872)
			(xy 20.99691 -167.28059) (xy 20.98294 -167.277034) (xy 20.968682 -167.273472) (xy 20.94071 -167.264446)
			(xy 20.92706 -167.259) (xy 20.900136 -167.246808) (xy 20.886077 -167.241683) (xy 20.856291 -167.238966)
			(xy 20.826994 -167.244989) (xy 20.800696 -167.259236) (xy 20.779649 -167.280487) (xy 20.765656 -167.306922)
			(xy 20.759916 -167.336275) (xy 20.760944 -167.351202) (xy 20.762722 -167.388794) (xy 20.76226 -167.416048)
			(xy 20.754503 -167.470002) (xy 20.739147 -167.522302) (xy 20.716504 -167.571885) (xy 20.687035 -167.617741)
			(xy 20.65134 -167.658936) (xy 20.610145 -167.694632) (xy 20.56429 -167.724101) (xy 20.514707 -167.746745)
			(xy 20.462407 -167.762102) (xy 20.408454 -167.769859) (xy 20.353945 -167.769859) (xy 20.299992 -167.762102)
			(xy 20.247691 -167.746744) (xy 20.198109 -167.724101) (xy 20.152254 -167.694631) (xy 20.111059 -167.658935)
			(xy 20.075364 -167.61774) (xy 20.045896 -167.571884) (xy 20.023253 -167.522301) (xy 20.007897 -167.470001)
			(xy 20.00014 -167.416047) (xy 20.000141 -167.361538) (xy 20.0079 -167.307585) (xy 20.023258 -167.255285)
			(xy 20.045903 -167.205703) (xy 20.075373 -167.159848) (xy 20.11107 -167.118655) (xy 20.152265 -167.08296)
			(xy 20.198122 -167.053492) (xy 20.247705 -167.03085) (xy 20.300006 -167.015495) (xy 20.35396 -167.00774)
			(xy 20.381214 -167.007286) (xy 20.381468 -167.007286) (xy 20.411125 -167.007896) (xy 20.469715 -167.017155)
			(xy 20.526173 -167.035347) (xy 20.552918 -167.04818) (xy 20.566988 -167.053348) (xy 20.596819 -167.056133)
			(xy 20.626175 -167.050146) (xy 20.652533 -167.035903) (xy 20.673627 -167.014627) (xy 20.687643 -166.988147)
			(xy 20.693377 -166.958741) (xy 20.692364 -166.943786) (xy 20.690586 -166.906194) (xy 20.691072 -166.878943)
			(xy 20.698829 -166.824995) (xy 20.714185 -166.772701) (xy 20.736826 -166.723124) (xy 20.766293 -166.677274)
			(xy 20.801984 -166.636084) (xy 20.843174 -166.600393) (xy 20.889024 -166.570926) (xy 20.938601 -166.548285)
			(xy 20.990895 -166.532929) (xy 21.044843 -166.525172) (xy 21.072094 -166.524686) (xy 21.100396 -166.525208)
			(xy 21.156377 -166.533585) (xy 21.210506 -166.550142) (xy 21.261594 -166.574514) (xy 21.30852 -166.606167)
			(xy 21.350255 -166.644407) (xy 21.385882 -166.688393) (xy 21.414618 -166.737161) (xy 21.435834 -166.789638)
			(xy 21.442934 -166.81704) (xy 21.44649 -166.83101) (xy 22.14499 -167.52951) (xy 22.158962 -167.543988)
			(xy 23.966422 -167.543988) (xy 23.970493 -167.488366) (xy 23.982619 -167.433929) (xy 24.002542 -167.381838)
			(xy 24.029838 -167.333203) (xy 24.063924 -167.28906) (xy 24.104073 -167.250351) (xy 24.149431 -167.2179)
			(xy 24.199031 -167.192399) (xy 24.251815 -167.174392) (xy 24.306658 -167.164262) (xy 24.362392 -167.162225)
			(xy 24.417829 -167.168325) (xy 24.471786 -167.182431) (xy 24.523115 -167.204243) (xy 24.570721 -167.233297)
			(xy 24.613589 -167.268972) (xy 24.650806 -167.310509) (xy 24.681579 -167.357022) (xy 24.705251 -167.407519)
			(xy 24.721319 -167.460926) (xy 24.729439 -167.516102) (xy 24.729948 -167.543988) (xy 24.729439 -167.571874)
			(xy 24.721319 -167.62705) (xy 24.705251 -167.680457) (xy 24.681579 -167.730954) (xy 24.650806 -167.777467)
			(xy 24.613589 -167.819004) (xy 24.570721 -167.854679) (xy 24.523115 -167.883733) (xy 24.471786 -167.905545)
			(xy 24.417829 -167.919651) (xy 24.362392 -167.925751) (xy 24.306658 -167.923714) (xy 24.251815 -167.913584)
			(xy 24.199031 -167.895577) (xy 24.149431 -167.870076) (xy 24.104073 -167.837625) (xy 24.063924 -167.798916)
			(xy 24.029838 -167.754773) (xy 24.002542 -167.706138) (xy 23.982619 -167.654047) (xy 23.970493 -167.59961)
			(xy 23.966422 -167.543988) (xy 22.158962 -167.543988) (xy 22.162346 -167.547494) (xy 22.191751 -167.587906)
			(xy 22.214464 -167.632424) (xy 22.229925 -167.67995) (xy 22.237752 -167.729311) (xy 22.238208 -167.7543)
			(xy 22.238208 -168.126918) (xy 26.807412 -168.126918) (xy 26.811483 -168.071296) (xy 26.823609 -168.016859)
			(xy 26.843532 -167.964768) (xy 26.870828 -167.916133) (xy 26.904914 -167.87199) (xy 26.945063 -167.833281)
			(xy 26.990421 -167.80083) (xy 27.040021 -167.775329) (xy 27.092805 -167.757322) (xy 27.147648 -167.747192)
			(xy 27.203382 -167.745155) (xy 27.258819 -167.751255) (xy 27.312776 -167.765361) (xy 27.364105 -167.787173)
			(xy 27.411711 -167.816227) (xy 27.454579 -167.851902) (xy 27.491796 -167.893439) (xy 27.522569 -167.939952)
			(xy 27.545203 -167.988234) (xy 29.594808 -167.988234) (xy 29.598879 -167.932612) (xy 29.611005 -167.878175)
			(xy 29.630928 -167.826084) (xy 29.658224 -167.777449) (xy 29.69231 -167.733306) (xy 29.732459 -167.694597)
			(xy 29.777817 -167.662146) (xy 29.827417 -167.636645) (xy 29.880201 -167.618638) (xy 29.935044 -167.608508)
			(xy 29.990778 -167.606471) (xy 30.046215 -167.612571) (xy 30.100172 -167.626677) (xy 30.151501 -167.648489)
			(xy 30.199107 -167.677543) (xy 30.241975 -167.713218) (xy 30.279192 -167.754755) (xy 30.309965 -167.801268)
			(xy 30.333637 -167.851765) (xy 30.349705 -167.905172) (xy 30.357825 -167.960348) (xy 30.358334 -167.988234)
			(xy 30.357825 -168.01612) (xy 30.349705 -168.071296) (xy 30.333637 -168.124703) (xy 30.309965 -168.1752)
			(xy 30.279192 -168.221713) (xy 30.241975 -168.26325) (xy 30.199107 -168.298925) (xy 30.151501 -168.327979)
			(xy 30.100172 -168.349791) (xy 30.046215 -168.363897) (xy 29.990778 -168.369997) (xy 29.935044 -168.36796)
			(xy 29.880201 -168.35783) (xy 29.827417 -168.339823) (xy 29.777817 -168.314322) (xy 29.732459 -168.281871)
			(xy 29.69231 -168.243162) (xy 29.658224 -168.199019) (xy 29.630928 -168.150384) (xy 29.611005 -168.098293)
			(xy 29.598879 -168.043856) (xy 29.594808 -167.988234) (xy 27.545203 -167.988234) (xy 27.546241 -167.990449)
			(xy 27.562309 -168.043856) (xy 27.570429 -168.099032) (xy 27.570938 -168.126918) (xy 27.570429 -168.154804)
			(xy 27.562309 -168.20998) (xy 27.546241 -168.263387) (xy 27.522569 -168.313884) (xy 27.491796 -168.360397)
			(xy 27.454579 -168.401934) (xy 27.411711 -168.437609) (xy 27.364105 -168.466663) (xy 27.312776 -168.488475)
			(xy 27.258819 -168.502581) (xy 27.203382 -168.508681) (xy 27.147648 -168.506644) (xy 27.092805 -168.496514)
			(xy 27.040021 -168.478507) (xy 26.990421 -168.453006) (xy 26.945063 -168.420555) (xy 26.904914 -168.381846)
			(xy 26.870828 -168.337703) (xy 26.843532 -168.289068) (xy 26.823609 -168.236977) (xy 26.811483 -168.18254)
			(xy 26.807412 -168.126918) (xy 22.238208 -168.126918) (xy 22.238208 -168.587928) (xy 24.769316 -168.587928)
			(xy 24.773387 -168.532306) (xy 24.785513 -168.477869) (xy 24.805436 -168.425778) (xy 24.832732 -168.377143)
			(xy 24.866818 -168.333) (xy 24.906967 -168.294291) (xy 24.952325 -168.26184) (xy 25.001925 -168.236339)
			(xy 25.054709 -168.218332) (xy 25.109552 -168.208202) (xy 25.165286 -168.206165) (xy 25.220723 -168.212265)
			(xy 25.27468 -168.226371) (xy 25.326009 -168.248183) (xy 25.373615 -168.277237) (xy 25.416483 -168.312912)
			(xy 25.4537 -168.354449) (xy 25.484473 -168.400962) (xy 25.508145 -168.451459) (xy 25.524213 -168.504866)
			(xy 25.532333 -168.560042) (xy 25.532842 -168.587928) (xy 25.532333 -168.615814) (xy 25.524213 -168.67099)
			(xy 25.508145 -168.724397) (xy 25.484473 -168.774894) (xy 25.4537 -168.821407) (xy 25.416483 -168.862944)
			(xy 25.373615 -168.898619) (xy 25.326009 -168.927673) (xy 25.27468 -168.949485) (xy 25.220723 -168.963591)
			(xy 25.165286 -168.969691) (xy 25.109552 -168.967654) (xy 25.054709 -168.957524) (xy 25.001925 -168.939517)
			(xy 24.952325 -168.914016) (xy 24.906967 -168.881565) (xy 24.866818 -168.842856) (xy 24.832732 -168.798713)
			(xy 24.805436 -168.750078) (xy 24.785513 -168.697987) (xy 24.773387 -168.64355) (xy 24.769316 -168.587928)
			(xy 22.238208 -168.587928) (xy 22.238208 -169.385488) (xy 22.23769 -169.410469) (xy 22.229829 -169.459811)
			(xy 22.220947 -169.487088) (xy 25.88082 -169.487088) (xy 25.884891 -169.431466) (xy 25.897017 -169.377029)
			(xy 25.91694 -169.324938) (xy 25.944236 -169.276303) (xy 25.978322 -169.23216) (xy 26.018471 -169.193451)
			(xy 26.063829 -169.161) (xy 26.113429 -169.135499) (xy 26.166213 -169.117492) (xy 26.221056 -169.107362)
			(xy 26.27679 -169.105325) (xy 26.332227 -169.111425) (xy 26.386184 -169.125531) (xy 26.437513 -169.147343)
			(xy 26.485119 -169.176397) (xy 26.527987 -169.212072) (xy 26.565204 -169.253609) (xy 26.595977 -169.300122)
			(xy 26.619649 -169.350619) (xy 26.635717 -169.404026) (xy 26.643837 -169.459202) (xy 26.644346 -169.487088)
			(xy 26.643837 -169.514974) (xy 26.635717 -169.57015) (xy 26.619649 -169.623557) (xy 26.595977 -169.674054)
			(xy 26.565204 -169.720567) (xy 26.527987 -169.762104) (xy 26.485119 -169.797779) (xy 26.437513 -169.826833)
			(xy 26.386184 -169.848645) (xy 26.332227 -169.862751) (xy 26.27679 -169.868851) (xy 26.221056 -169.866814)
			(xy 26.166213 -169.856684) (xy 26.113429 -169.838677) (xy 26.063829 -169.813176) (xy 26.018471 -169.780725)
			(xy 25.978322 -169.742016) (xy 25.944236 -169.697873) (xy 25.91694 -169.649238) (xy 25.897017 -169.597147)
			(xy 25.884891 -169.54271) (xy 25.88082 -169.487088) (xy 22.220947 -169.487088) (xy 22.214359 -169.507319)
			(xy 22.191661 -169.551829) (xy 22.162291 -169.59225) (xy 22.14499 -169.610278) (xy 21.829522 -169.925746)
			(xy 21.82622 -169.939716) (xy 21.82114 -169.95902) (xy 21.819362 -169.964862) (xy 21.810887 -169.990319)
			(xy 21.787815 -170.03876) (xy 21.773388 -170.061382) (xy 21.773388 -170.67022) (xy 30.752032 -170.67022)
			(xy 30.756103 -170.614598) (xy 30.768229 -170.560161) (xy 30.788152 -170.50807) (xy 30.815448 -170.459435)
			(xy 30.849534 -170.415292) (xy 30.889683 -170.376583) (xy 30.935041 -170.344132) (xy 30.984641 -170.318631)
			(xy 31.037425 -170.300624) (xy 31.092268 -170.290494) (xy 31.148002 -170.288457) (xy 31.203439 -170.294557)
			(xy 31.257396 -170.308663) (xy 31.308725 -170.330475) (xy 31.356331 -170.359529) (xy 31.399199 -170.395204)
			(xy 31.436416 -170.436741) (xy 31.467189 -170.483254) (xy 31.490861 -170.533751) (xy 31.506929 -170.587158)
			(xy 31.515049 -170.642334) (xy 31.515558 -170.67022) (xy 31.515049 -170.698106) (xy 31.506929 -170.753282)
			(xy 31.490861 -170.806689) (xy 31.467189 -170.857186) (xy 31.436416 -170.903699) (xy 31.399199 -170.945236)
			(xy 31.356331 -170.980911) (xy 31.308725 -171.009965) (xy 31.257396 -171.031777) (xy 31.203439 -171.045883)
			(xy 31.148002 -171.051983) (xy 31.092268 -171.049946) (xy 31.037425 -171.039816) (xy 30.984641 -171.021809)
			(xy 30.935041 -170.996308) (xy 30.889683 -170.963857) (xy 30.849534 -170.925148) (xy 30.815448 -170.881005)
			(xy 30.788152 -170.83237) (xy 30.768229 -170.780279) (xy 30.756103 -170.725842) (xy 30.752032 -170.67022)
			(xy 21.773388 -170.67022) (xy 21.773388 -170.814492) (xy 25.352248 -174.393352) (xy 25.366218 -174.396908)
			(xy 25.39856 -174.405328) (xy 25.459873 -174.431907) (xy 25.488138 -174.44974) (xy 27.158696 -174.44974)
			(xy 30.130242 -171.478194) (xy 30.13583 -171.472606) (xy 30.136592 -171.472098) (xy 30.222444 -171.386246)
			(xy 30.351476 -171.386246) (xy 30.354016 -171.385992) (xy 32.464248 -171.385992) (xy 33.237932 -170.612308)
			(xy 33.237932 -169.461942) (xy 33.207198 -169.448734) (xy 33.181841 -169.437295) (xy 33.134458 -169.408157)
			(xy 33.091804 -169.372452) (xy 33.054783 -169.330936) (xy 33.024177 -169.284487) (xy 33.000635 -169.234089)
			(xy 32.984655 -169.180808) (xy 32.976575 -169.125773) (xy 32.976058 -169.09796) (xy 32.976547 -169.070693)
			(xy 32.984314 -169.016715) (xy 32.999683 -168.964391) (xy 33.022341 -168.914787) (xy 33.051829 -168.868913)
			(xy 33.087544 -168.827702) (xy 33.128761 -168.791993) (xy 33.17464 -168.762513) (xy 33.224248 -168.739862)
			(xy 33.276574 -168.724501) (xy 33.330553 -168.716743) (xy 33.35782 -168.716198) (xy 33.358074 -168.716198)
			(xy 33.386046 -168.716712) (xy 33.441386 -168.724915) (xy 33.49494 -168.741092) (xy 33.545568 -168.764897)
			(xy 33.569148 -168.779952) (xy 33.761172 -168.779952) (xy 34.524188 -168.016936) (xy 34.524188 -161.672524)
			(xy 34.48685 -161.635186) (xy 34.340546 -161.488628) (xy 34.111692 -161.488628) (xy 34.088124 -161.50371)
			(xy 34.037505 -161.52755) (xy 33.983945 -161.543734) (xy 33.928594 -161.551916) (xy 33.900618 -161.552382)
			(xy 33.873366 -161.55192) (xy 33.819417 -161.544166) (xy 33.767121 -161.528812) (xy 33.717542 -161.506172)
			(xy 33.671689 -161.476707) (xy 33.630497 -161.441016) (xy 33.594804 -161.399825) (xy 33.565336 -161.353974)
			(xy 33.542694 -161.304396) (xy 33.527338 -161.252101) (xy 33.519581 -161.198152) (xy 33.519581 -161.143648)
			(xy 33.527338 -161.089699) (xy 33.542694 -161.037404) (xy 33.565336 -160.987826) (xy 33.594804 -160.941975)
			(xy 33.630497 -160.900784) (xy 33.671689 -160.865093) (xy 33.717542 -160.835628) (xy 33.767121 -160.812988)
			(xy 33.819417 -160.797634) (xy 33.873366 -160.78988) (xy 33.900618 -160.789366) (xy 33.928593 -160.789859)
			(xy 33.983941 -160.798037) (xy 34.037501 -160.814215) (xy 34.088121 -160.838045) (xy 34.111692 -160.85312)
			(xy 34.60369 -160.85312) (xy 34.689542 -160.938972) (xy 34.690304 -160.93948) (xy 34.695892 -160.945068)
			(xy 34.696908 -160.946084) (xy 35.066986 -161.316162) (xy 35.068256 -161.317432) (xy 35.07359 -161.322766)
			(xy 35.074098 -161.323528) (xy 35.15995 -161.40938) (xy 35.15995 -161.538412) (xy 35.160204 -161.540952)
			(xy 35.160204 -168.148508) (xy 35.15995 -168.151048) (xy 35.15995 -168.28008) (xy 35.074098 -168.365932)
			(xy 35.07359 -168.366694) (xy 35.068256 -168.372028) (xy 35.066986 -168.373298) (xy 34.17824 -169.262044)
			(xy 34.17824 -169.26179) (xy 34.024316 -169.415714) (xy 33.873948 -169.415714) (xy 33.873948 -170.74388)
			(xy 33.873694 -170.74642) (xy 33.873694 -170.875452) (xy 33.787842 -170.961304) (xy 33.787334 -170.962066)
			(xy 33.781746 -170.967654) (xy 32.819594 -171.929806) (xy 32.814006 -171.935394) (xy 32.813244 -171.935902)
			(xy 32.727392 -172.021754) (xy 32.59836 -172.021754) (xy 32.59582 -172.022008) (xy 30.485842 -172.022008)
			(xy 27.510486 -174.99711) (xy 27.42184 -175.085502) (xy 27.291538 -175.085502) (xy 27.290268 -175.085756)
			(xy 26.280872 -175.085756) (xy 26.268737 -175.109398) (xy 26.2389 -175.153372) (xy 26.203246 -175.192778)
			(xy 26.162467 -175.226852) (xy 26.117353 -175.254936) (xy 26.068777 -175.276484) (xy 26.01768 -175.29108)
			(xy 25.965051 -175.298441) (xy 25.93848 -175.298862) (xy 25.937972 -175.298862) (xy 25.911825 -175.298368)
			(xy 25.860037 -175.291098) (xy 25.809728 -175.276822) (xy 25.761841 -175.255807) (xy 25.739344 -175.242474)
			(xy 25.727152 -175.235108) (xy 25.557988 -175.235108) (xy 25.299416 -175.49368) (xy 25.299416 -175.7934)
			(xy 25.541222 -175.7934) (xy 25.545293 -175.737778) (xy 25.557419 -175.683341) (xy 25.577342 -175.63125)
			(xy 25.604638 -175.582615) (xy 25.638724 -175.538472) (xy 25.678873 -175.499763) (xy 25.724231 -175.467312)
			(xy 25.773831 -175.441811) (xy 25.826615 -175.423804) (xy 25.881458 -175.413674) (xy 25.937192 -175.411637)
			(xy 25.992629 -175.417737) (xy 26.046586 -175.431843) (xy 26.097915 -175.453655) (xy 26.145521 -175.482709)
			(xy 26.156993 -175.492256) (xy 35.295733 -175.492256) (xy 35.295733 -175.437744) (xy 35.303491 -175.383786)
			(xy 35.31885 -175.331482) (xy 35.341497 -175.281896) (xy 35.370971 -175.236039) (xy 35.406671 -175.194842)
			(xy 35.447871 -175.159147) (xy 35.493731 -175.129678) (xy 35.54332 -175.107036) (xy 35.595625 -175.091683)
			(xy 35.649584 -175.08393) (xy 35.67684 -175.08347) (xy 35.70421 -175.083954) (xy 35.758389 -175.091765)
			(xy 35.810892 -175.107249) (xy 35.86064 -175.130087) (xy 35.906607 -175.159809) (xy 35.927538 -175.17745)
			(xy 35.938866 -175.186686) (xy 35.965423 -175.198862) (xy 35.99434 -175.203035) (xy 36.023257 -175.198862)
			(xy 36.049814 -175.186686) (xy 36.061142 -175.17745) (xy 36.082092 -175.159832) (xy 36.128059 -175.130116)
			(xy 36.177802 -175.107275) (xy 36.230299 -175.091779) (xy 36.284472 -175.083946) (xy 36.31184 -175.08347)
			(xy 36.339088 -175.084003) (xy 36.393028 -175.091764) (xy 36.445315 -175.107121) (xy 36.494884 -175.129763)
			(xy 36.540727 -175.159229) (xy 36.58191 -175.194918) (xy 36.617595 -175.236105) (xy 36.633929 -175.261524)
			(xy 51.230528 -175.261524) (xy 51.234599 -175.205902) (xy 51.246725 -175.151465) (xy 51.266648 -175.099374)
			(xy 51.293944 -175.050739) (xy 51.32803 -175.006596) (xy 51.368179 -174.967887) (xy 51.413537 -174.935436)
			(xy 51.463137 -174.909935) (xy 51.515921 -174.891928) (xy 51.570764 -174.881798) (xy 51.626498 -174.879761)
			(xy 51.681935 -174.885861) (xy 51.735892 -174.899967) (xy 51.787221 -174.921779) (xy 51.834827 -174.950833)
			(xy 51.877695 -174.986508) (xy 51.914912 -175.028045) (xy 51.945685 -175.074558) (xy 51.969357 -175.125055)
			(xy 51.985425 -175.178462) (xy 51.993545 -175.233638) (xy 51.994054 -175.261524) (xy 51.993957 -175.266858)
			(xy 52.228748 -175.266858) (xy 52.232819 -175.211236) (xy 52.244945 -175.156799) (xy 52.264868 -175.104708)
			(xy 52.292164 -175.056073) (xy 52.32625 -175.01193) (xy 52.366399 -174.973221) (xy 52.411757 -174.94077)
			(xy 52.461357 -174.915269) (xy 52.514141 -174.897262) (xy 52.568984 -174.887132) (xy 52.624718 -174.885095)
			(xy 52.680155 -174.891195) (xy 52.734112 -174.905301) (xy 52.785441 -174.927113) (xy 52.833047 -174.956167)
			(xy 52.875915 -174.991842) (xy 52.913132 -175.033379) (xy 52.943905 -175.079892) (xy 52.967577 -175.130389)
			(xy 52.983645 -175.183796) (xy 52.991765 -175.238972) (xy 52.992274 -175.266858) (xy 52.991765 -175.294744)
			(xy 52.983645 -175.34992) (xy 52.967577 -175.403327) (xy 52.943905 -175.453824) (xy 52.913132 -175.500337)
			(xy 52.875915 -175.541874) (xy 52.833047 -175.577549) (xy 52.785441 -175.606603) (xy 52.734112 -175.628415)
			(xy 52.680155 -175.642521) (xy 52.624718 -175.648621) (xy 52.568984 -175.646584) (xy 52.514141 -175.636454)
			(xy 52.461357 -175.618447) (xy 52.411757 -175.592946) (xy 52.366399 -175.560495) (xy 52.32625 -175.521786)
			(xy 52.292164 -175.477643) (xy 52.264868 -175.429008) (xy 52.244945 -175.376917) (xy 52.232819 -175.32248)
			(xy 52.228748 -175.266858) (xy 51.993957 -175.266858) (xy 51.993545 -175.28941) (xy 51.985425 -175.344586)
			(xy 51.969357 -175.397993) (xy 51.945685 -175.44849) (xy 51.914912 -175.495003) (xy 51.877695 -175.53654)
			(xy 51.834827 -175.572215) (xy 51.787221 -175.601269) (xy 51.735892 -175.623081) (xy 51.681935 -175.637187)
			(xy 51.626498 -175.643287) (xy 51.570764 -175.64125) (xy 51.515921 -175.63112) (xy 51.463137 -175.613113)
			(xy 51.413537 -175.587612) (xy 51.368179 -175.555161) (xy 51.32803 -175.516452) (xy 51.293944 -175.472309)
			(xy 51.266648 -175.423674) (xy 51.246725 -175.371583) (xy 51.234599 -175.317146) (xy 51.230528 -175.261524)
			(xy 36.633929 -175.261524) (xy 36.647056 -175.281951) (xy 36.669693 -175.331523) (xy 36.685045 -175.383811)
			(xy 36.6928 -175.437752) (xy 36.6928 -175.492248) (xy 36.685045 -175.546189) (xy 36.669693 -175.598477)
			(xy 36.647056 -175.648049) (xy 36.617595 -175.693895) (xy 36.58191 -175.735082) (xy 36.540727 -175.770771)
			(xy 36.494884 -175.800237) (xy 36.445315 -175.822879) (xy 36.393028 -175.838236) (xy 36.339088 -175.845997)
			(xy 36.31184 -175.846486) (xy 36.28447 -175.846) (xy 36.230292 -175.838187) (xy 36.177789 -175.822703)
			(xy 36.128042 -175.799866) (xy 36.082074 -175.770145) (xy 36.061142 -175.752506) (xy 36.049814 -175.74327)
			(xy 36.023257 -175.731094) (xy 35.99434 -175.726921) (xy 35.965423 -175.731094) (xy 35.938866 -175.74327)
			(xy 35.927538 -175.752506) (xy 35.906603 -175.770142) (xy 35.860631 -175.799854) (xy 35.810884 -175.82269)
			(xy 35.758384 -175.838182) (xy 35.704209 -175.846011) (xy 35.67684 -175.846486) (xy 35.649584 -175.84607)
			(xy 35.595625 -175.838317) (xy 35.54332 -175.822964) (xy 35.493731 -175.800322) (xy 35.447871 -175.770853)
			(xy 35.406671 -175.735158) (xy 35.370971 -175.693961) (xy 35.341497 -175.648104) (xy 35.31885 -175.598518)
			(xy 35.303491 -175.546214) (xy 35.295733 -175.492256) (xy 26.156993 -175.492256) (xy 26.188389 -175.518384)
			(xy 26.225606 -175.559921) (xy 26.256379 -175.606434) (xy 26.280051 -175.656931) (xy 26.296119 -175.710338)
			(xy 26.304239 -175.765514) (xy 26.304748 -175.7934) (xy 26.304239 -175.821286) (xy 26.296119 -175.876462)
			(xy 26.280051 -175.929869) (xy 26.256379 -175.980366) (xy 26.225606 -176.026879) (xy 26.188389 -176.068416)
			(xy 26.145521 -176.104091) (xy 26.097915 -176.133145) (xy 26.046586 -176.154957) (xy 25.992629 -176.169063)
			(xy 25.937192 -176.175163) (xy 25.881458 -176.173126) (xy 25.826615 -176.162996) (xy 25.773831 -176.144989)
			(xy 25.724231 -176.119488) (xy 25.678873 -176.087037) (xy 25.638724 -176.048328) (xy 25.604638 -176.004185)
			(xy 25.577342 -175.95555) (xy 25.557419 -175.903459) (xy 25.545293 -175.849022) (xy 25.541222 -175.7934)
			(xy 25.299416 -175.7934) (xy 25.299416 -176.181004) (xy 51.225448 -176.181004) (xy 51.229519 -176.125382)
			(xy 51.241645 -176.070945) (xy 51.261568 -176.018854) (xy 51.288864 -175.970219) (xy 51.32295 -175.926076)
			(xy 51.363099 -175.887367) (xy 51.408457 -175.854916) (xy 51.458057 -175.829415) (xy 51.510841 -175.811408)
			(xy 51.565684 -175.801278) (xy 51.621418 -175.799241) (xy 51.676855 -175.805341) (xy 51.730812 -175.819447)
			(xy 51.782141 -175.841259) (xy 51.829747 -175.870313) (xy 51.872615 -175.905988) (xy 51.909832 -175.947525)
			(xy 51.940605 -175.994038) (xy 51.964277 -176.044535) (xy 51.980345 -176.097942) (xy 51.988465 -176.153118)
			(xy 51.988974 -176.181004) (xy 51.988928 -176.183544) (xy 52.231542 -176.183544) (xy 52.235613 -176.127922)
			(xy 52.247739 -176.073485) (xy 52.267662 -176.021394) (xy 52.294958 -175.972759) (xy 52.329044 -175.928616)
			(xy 52.369193 -175.889907) (xy 52.414551 -175.857456) (xy 52.464151 -175.831955) (xy 52.516935 -175.813948)
			(xy 52.571778 -175.803818) (xy 52.627512 -175.801781) (xy 52.682949 -175.807881) (xy 52.736906 -175.821987)
			(xy 52.788235 -175.843799) (xy 52.835841 -175.872853) (xy 52.878709 -175.908528) (xy 52.915926 -175.950065)
			(xy 52.946699 -175.996578) (xy 52.970371 -176.047075) (xy 52.986439 -176.100482) (xy 52.994559 -176.155658)
			(xy 52.995068 -176.183544) (xy 52.994559 -176.21143) (xy 52.986439 -176.266606) (xy 52.970371 -176.320013)
			(xy 52.946699 -176.37051) (xy 52.915926 -176.417023) (xy 52.878709 -176.45856) (xy 52.835841 -176.494235)
			(xy 52.788235 -176.523289) (xy 52.736906 -176.545101) (xy 52.682949 -176.559207) (xy 52.627512 -176.565307)
			(xy 52.571778 -176.56327) (xy 52.516935 -176.55314) (xy 52.464151 -176.535133) (xy 52.414551 -176.509632)
			(xy 52.369193 -176.477181) (xy 52.329044 -176.438472) (xy 52.294958 -176.394329) (xy 52.267662 -176.345694)
			(xy 52.247739 -176.293603) (xy 52.235613 -176.239166) (xy 52.231542 -176.183544) (xy 51.988928 -176.183544)
			(xy 51.988465 -176.20889) (xy 51.980345 -176.264066) (xy 51.964277 -176.317473) (xy 51.940605 -176.36797)
			(xy 51.909832 -176.414483) (xy 51.872615 -176.45602) (xy 51.829747 -176.491695) (xy 51.782141 -176.520749)
			(xy 51.730812 -176.542561) (xy 51.676855 -176.556667) (xy 51.621418 -176.562767) (xy 51.565684 -176.56073)
			(xy 51.510841 -176.5506) (xy 51.458057 -176.532593) (xy 51.408457 -176.507092) (xy 51.363099 -176.474641)
			(xy 51.32295 -176.435932) (xy 51.288864 -176.391789) (xy 51.261568 -176.343154) (xy 51.241645 -176.291063)
			(xy 51.229519 -176.236626) (xy 51.225448 -176.181004) (xy 25.299416 -176.181004) (xy 25.299416 -176.877218)
			(xy 25.571958 -177.14976) (xy 25.632918 -177.091086) (xy 25.634442 -177.07229) (xy 25.637355 -177.044068)
			(xy 25.650467 -176.98887) (xy 25.671611 -176.936224) (xy 25.700319 -176.88729) (xy 25.735959 -176.843148)
			(xy 25.777745 -176.804772) (xy 25.824754 -176.773009) (xy 25.875949 -176.74856) (xy 25.930201 -176.731963)
			(xy 25.986313 -176.723586) (xy 26.01468 -176.72304) (xy 26.04193 -176.723502) (xy 26.095877 -176.731256)
			(xy 26.14817 -176.746608) (xy 26.197747 -176.769246) (xy 26.243597 -176.79871) (xy 26.284786 -176.834399)
			(xy 26.320478 -176.875587) (xy 26.349944 -176.921436) (xy 26.354015 -176.930349) (xy 49.335704 -176.930349)
			(xy 49.335704 -176.875851) (xy 49.34346 -176.821908) (xy 49.358813 -176.769618) (xy 49.381452 -176.720045)
			(xy 49.410916 -176.674198) (xy 49.446604 -176.633011) (xy 49.48779 -176.597322) (xy 49.533636 -176.567857)
			(xy 49.583208 -176.545217) (xy 49.635498 -176.529862) (xy 49.689441 -176.522105) (xy 49.71669 -176.521618)
			(xy 49.74406 -176.522086) (xy 49.798239 -176.529902) (xy 49.850743 -176.545391) (xy 49.90049 -176.568232)
			(xy 49.946456 -176.597957) (xy 49.967388 -176.615598) (xy 49.978716 -176.624834) (xy 50.005273 -176.63701)
			(xy 50.03419 -176.641183) (xy 50.063107 -176.63701) (xy 50.089664 -176.624834) (xy 50.100992 -176.615598)
			(xy 50.121925 -176.597957) (xy 50.167893 -176.568233) (xy 50.217639 -176.545387) (xy 50.270141 -176.529891)
			(xy 50.324319 -176.522062) (xy 50.379061 -176.522062) (xy 50.433239 -176.529891) (xy 50.485741 -176.545387)
			(xy 50.535487 -176.568233) (xy 50.581455 -176.597957) (xy 50.602388 -176.615598) (xy 50.613716 -176.624834)
			(xy 50.640273 -176.63701) (xy 50.66919 -176.641183) (xy 50.698107 -176.63701) (xy 50.724664 -176.624834)
			(xy 50.735992 -176.615598) (xy 50.756916 -176.597949) (xy 50.802891 -176.568239) (xy 50.852641 -176.545405)
			(xy 50.905143 -176.529916) (xy 50.95932 -176.52209) (xy 50.98669 -176.521618) (xy 51.013944 -176.522065)
			(xy 51.067897 -176.529821) (xy 51.120196 -176.545177) (xy 51.169778 -176.56782) (xy 51.215633 -176.59729)
			(xy 51.256826 -176.632985) (xy 51.29252 -176.67418) (xy 51.321987 -176.720036) (xy 51.344629 -176.769619)
			(xy 51.359982 -176.821919) (xy 51.367736 -176.875872) (xy 51.368198 -176.903126) (xy 51.367748 -176.930497)
			(xy 51.359926 -176.984677) (xy 51.344433 -177.03718) (xy 51.321588 -177.086926) (xy 51.291861 -177.132893)
			(xy 51.274218 -177.153824) (xy 51.264955 -177.165132) (xy 51.252778 -177.191696) (xy 51.24861 -177.22062)
			(xy 51.252789 -177.249541) (xy 51.264976 -177.276101) (xy 51.274218 -177.287428) (xy 51.29184 -177.308374)
			(xy 51.321553 -177.354343) (xy 51.344392 -177.404087) (xy 51.359888 -177.456585) (xy 51.367721 -177.510758)
			(xy 51.368198 -177.538126) (xy 51.367746 -177.565378) (xy 51.359986 -177.619328) (xy 51.344627 -177.671624)
			(xy 51.321982 -177.721202) (xy 51.292512 -177.767053) (xy 51.256817 -177.808243) (xy 51.215624 -177.843934)
			(xy 51.16977 -177.873399) (xy 51.12019 -177.89604) (xy 51.067893 -177.911394) (xy 51.013942 -177.919149)
			(xy 50.98669 -177.919634) (xy 50.959319 -177.91919) (xy 50.905138 -177.911369) (xy 50.852634 -177.895876)
			(xy 50.802888 -177.873029) (xy 50.756922 -177.843298) (xy 50.735992 -177.825654) (xy 50.724664 -177.816418)
			(xy 50.698107 -177.804242) (xy 50.66919 -177.800069) (xy 50.640273 -177.804242) (xy 50.613716 -177.816418)
			(xy 50.602388 -177.825654) (xy 50.581428 -177.843258) (xy 50.535463 -177.872977) (xy 50.485723 -177.89582)
			(xy 50.433228 -177.911319) (xy 50.379057 -177.919156) (xy 50.35169 -177.919634) (xy 50.32444 -177.919132)
			(xy 50.270494 -177.911374) (xy 50.218201 -177.896019) (xy 50.168626 -177.873379) (xy 50.122776 -177.843914)
			(xy 50.081587 -177.808224) (xy 50.045896 -177.767036) (xy 50.016429 -177.721189) (xy 49.993786 -177.671614)
			(xy 49.978429 -177.619322) (xy 49.97067 -177.565376) (xy 49.970182 -177.538126) (xy 49.970663 -177.511891)
			(xy 49.977854 -177.459916) (xy 49.992105 -177.409419) (xy 50.013145 -177.361352) (xy 50.040578 -177.316625)
			(xy 50.073885 -177.276082) (xy 50.092864 -177.257964) (xy 50.100207 -177.250412) (xy 50.108638 -177.231137)
			(xy 50.108646 -177.210098) (xy 50.100228 -177.190817) (xy 50.092864 -177.183288) (xy 50.071528 -177.161952)
			(xy 50.063999 -177.15458) (xy 50.044714 -177.146149) (xy 50.023666 -177.146149) (xy 50.004381 -177.15458)
			(xy 49.996852 -177.161952) (xy 49.978741 -177.180941) (xy 49.938201 -177.214257) (xy 49.893474 -177.241698)
			(xy 49.845406 -177.262746) (xy 49.794905 -177.277002) (xy 49.742927 -177.284197) (xy 49.71669 -177.284634)
			(xy 49.689441 -177.284095) (xy 49.635498 -177.276338) (xy 49.583208 -177.260983) (xy 49.533636 -177.238343)
			(xy 49.48779 -177.208878) (xy 49.446604 -177.173189) (xy 49.410916 -177.132002) (xy 49.381452 -177.086155)
			(xy 49.358813 -177.036582) (xy 49.34346 -176.984292) (xy 49.335704 -176.930349) (xy 26.354015 -176.930349)
			(xy 26.372585 -176.971011) (xy 26.38794 -177.023304) (xy 26.395697 -177.07725) (xy 26.395697 -177.13175)
			(xy 26.38794 -177.185696) (xy 26.372585 -177.237989) (xy 26.349944 -177.287564) (xy 26.320478 -177.333413)
			(xy 26.284786 -177.374601) (xy 26.243597 -177.41029) (xy 26.197747 -177.439754) (xy 26.14817 -177.462392)
			(xy 26.095877 -177.477744) (xy 26.04193 -177.485498) (xy 26.01468 -177.486056) (xy 25.985011 -177.485491)
			(xy 25.926389 -177.476305) (xy 25.869895 -177.458156) (xy 25.81689 -177.431483) (xy 25.79243 -177.414682)
			(xy 25.781288 -177.407162) (xy 25.756142 -177.397686) (xy 25.729394 -177.395094) (xy 25.702896 -177.399566)
			(xy 25.678481 -177.410792) (xy 25.657837 -177.427996) (xy 25.642393 -177.449987) (xy 25.633217 -177.475245)
			(xy 25.631648 -177.488596) (xy 25.631648 -177.525254) (xy 35.243449 -177.525254) (xy 35.243449 -177.470746)
			(xy 35.251207 -177.416793) (xy 35.266564 -177.364493) (xy 35.289208 -177.314911) (xy 35.318678 -177.269056)
			(xy 35.354374 -177.227863) (xy 35.395569 -177.192168) (xy 35.441425 -177.1627) (xy 35.491008 -177.140058)
			(xy 35.543308 -177.124704) (xy 35.597262 -177.116948) (xy 35.624516 -177.116486) (xy 35.651886 -177.116946)
			(xy 35.706066 -177.124766) (xy 35.758569 -177.140257) (xy 35.808315 -177.163099) (xy 35.854282 -177.192825)
			(xy 35.875214 -177.210466) (xy 35.886542 -177.219702) (xy 35.913099 -177.231878) (xy 35.942016 -177.236051)
			(xy 35.970933 -177.231878) (xy 35.99749 -177.219702) (xy 36.008818 -177.210466) (xy 36.029766 -177.192847)
			(xy 36.075735 -177.163133) (xy 36.125478 -177.140294) (xy 36.177975 -177.124798) (xy 36.232148 -177.116964)
			(xy 36.259516 -177.116486) (xy 36.286766 -177.116985) (xy 36.340711 -177.124743) (xy 36.393003 -177.140099)
			(xy 36.442578 -177.162741) (xy 36.488425 -177.192207) (xy 36.529613 -177.227898) (xy 36.565302 -177.269087)
			(xy 36.594767 -177.314936) (xy 36.617406 -177.364512) (xy 36.63276 -177.416804) (xy 36.640516 -177.47075)
			(xy 36.640516 -177.52525) (xy 36.63276 -177.579196) (xy 36.617406 -177.631488) (xy 36.594767 -177.681064)
			(xy 36.565302 -177.726913) (xy 36.529613 -177.768102) (xy 36.488425 -177.803793) (xy 36.442578 -177.833259)
			(xy 36.393003 -177.855901) (xy 36.340711 -177.871257) (xy 36.286766 -177.879015) (xy 36.259516 -177.879502)
			(xy 36.232146 -177.879026) (xy 36.177967 -177.871211) (xy 36.125464 -177.855724) (xy 36.075717 -177.832884)
			(xy 36.02975 -177.803162) (xy 36.008818 -177.785522) (xy 35.99749 -177.776286) (xy 35.970933 -177.76411)
			(xy 35.942016 -177.759937) (xy 35.913099 -177.76411) (xy 35.886542 -177.776286) (xy 35.875214 -177.785522)
			(xy 35.85429 -177.803171) (xy 35.808315 -177.832881) (xy 35.758565 -177.855715) (xy 35.706063 -177.871203)
			(xy 35.651886 -177.879029) (xy 35.624516 -177.879502) (xy 35.597262 -177.879052) (xy 35.543308 -177.871296)
			(xy 35.491008 -177.855942) (xy 35.441425 -177.8333) (xy 35.395569 -177.803832) (xy 35.354374 -177.768137)
			(xy 35.318678 -177.726944) (xy 35.289208 -177.681089) (xy 35.266564 -177.631507) (xy 35.251207 -177.579207)
			(xy 35.243449 -177.525254) (xy 25.631648 -177.525254) (xy 25.631648 -178.26228) (xy 25.63116 -178.28723)
			(xy 25.623358 -178.336517) (xy 25.607943 -178.383977) (xy 25.585294 -178.428441) (xy 25.555968 -178.468815)
			(xy 25.538684 -178.486816) (xy 25.305004 -178.720242) (xy 25.217628 -178.807872) (xy 24.777192 -179.248562)
			(xy 24.759209 -179.265919) (xy 24.718798 -179.295327) (xy 24.67428 -179.318043) (xy 24.626753 -179.333505)
			(xy 24.577391 -179.341333) (xy 24.552402 -179.34178) (xy 21.82749 -179.34178) (xy 21.824696 -179.341526)
			(xy 21.695918 -179.341526) (xy 21.608288 -179.253896) (xy 21.597874 -179.244244) (xy 21.588089 -179.233496)
			(xy 21.563764 -179.217607) (xy 21.535947 -179.209219) (xy 21.506894 -179.209012) (xy 21.47896 -179.217002)
			(xy 21.454411 -179.232542) (xy 21.435237 -179.254372) (xy 21.42871 -179.267358) (xy 21.416837 -179.291665)
			(xy 21.38725 -179.336951) (xy 21.351561 -179.377602) (xy 21.310484 -179.412802) (xy 21.264845 -179.441842)
			(xy 21.215561 -179.464142) (xy 21.163619 -179.479253) (xy 21.110064 -179.486872) (xy 21.083016 -179.487322)
			(xy 21.055762 -179.48686) (xy 21.001809 -179.479105) (xy 20.949508 -179.463751) (xy 20.899925 -179.441109)
			(xy 20.854069 -179.411642) (xy 20.812873 -179.375948) (xy 20.777176 -179.334755) (xy 20.747705 -179.288902)
			(xy 20.72506 -179.23932) (xy 20.709701 -179.187021) (xy 20.701942 -179.133068) (xy 20.701508 -179.105814)
			(xy 20.702034 -179.077347) (xy 20.710493 -179.021045) (xy 20.727226 -178.966626) (xy 20.75186 -178.915298)
			(xy 20.783849 -178.8682) (xy 20.822483 -178.82638) (xy 20.866902 -178.790766) (xy 20.916121 -178.762149)
			(xy 20.969046 -178.741164) (xy 20.996656 -178.734212) (xy 21.042376 -178.688238) (xy 20.937474 -178.583336)
			(xy 20.04314 -178.583336) (xy 20.017613 -178.599567) (xy 19.962553 -178.624617) (xy 19.904229 -178.64066)
			(xy 19.87423 -178.64455) (xy 19.85645 -178.646582) (xy 19.095212 -179.40782) (xy 18.939647 -179.563354)
			(xy 35.249545 -179.563354) (xy 35.249545 -179.508846) (xy 35.257302 -179.454892) (xy 35.272659 -179.402592)
			(xy 35.295303 -179.35301) (xy 35.324773 -179.307155) (xy 35.360469 -179.265961) (xy 35.401665 -179.230266)
			(xy 35.44752 -179.200798) (xy 35.497103 -179.178155) (xy 35.549404 -179.1628) (xy 35.603358 -179.155044)
			(xy 35.630612 -179.154582) (xy 35.657983 -179.155021) (xy 35.712164 -179.162842) (xy 35.764669 -179.178337)
			(xy 35.814415 -179.201185) (xy 35.86038 -179.230917) (xy 35.88131 -179.248562) (xy 35.892638 -179.257798)
			(xy 35.919195 -179.269974) (xy 35.948112 -179.274147) (xy 35.977029 -179.269974) (xy 36.003586 -179.257798)
			(xy 36.014914 -179.248562) (xy 36.035863 -179.230943) (xy 36.081831 -179.20123) (xy 36.131575 -179.17839)
			(xy 36.184072 -179.162894) (xy 36.238244 -179.155059) (xy 36.265612 -179.154582) (xy 36.292862 -179.155089)
			(xy 36.346807 -179.162847) (xy 36.399099 -179.178203) (xy 36.448673 -179.200844) (xy 36.494521 -179.23031)
			(xy 36.535708 -179.266) (xy 36.571398 -179.307189) (xy 36.600862 -179.353037) (xy 36.623502 -179.402612)
			(xy 36.638856 -179.454905) (xy 36.646612 -179.50885) (xy 36.646612 -179.56335) (xy 36.646611 -179.563354)
			(xy 40.532745 -179.563354) (xy 40.532745 -179.508846) (xy 40.540502 -179.454892) (xy 40.555859 -179.402592)
			(xy 40.578503 -179.35301) (xy 40.607973 -179.307155) (xy 40.643669 -179.265961) (xy 40.684865 -179.230266)
			(xy 40.73072 -179.200798) (xy 40.780303 -179.178155) (xy 40.832604 -179.1628) (xy 40.886558 -179.155044)
			(xy 40.913812 -179.154582) (xy 40.941183 -179.155021) (xy 40.995364 -179.162842) (xy 41.047869 -179.178337)
			(xy 41.097615 -179.201185) (xy 41.14358 -179.230917) (xy 41.16451 -179.248562) (xy 41.175838 -179.257798)
			(xy 41.202395 -179.269974) (xy 41.231312 -179.274147) (xy 41.260229 -179.269974) (xy 41.286786 -179.257798)
			(xy 41.298114 -179.248562) (xy 41.319063 -179.230943) (xy 41.365031 -179.20123) (xy 41.414775 -179.17839)
			(xy 41.467272 -179.162894) (xy 41.521444 -179.155059) (xy 41.548812 -179.154582) (xy 41.576062 -179.155089)
			(xy 41.630007 -179.162847) (xy 41.682299 -179.178203) (xy 41.731873 -179.200844) (xy 41.777721 -179.23031)
			(xy 41.818908 -179.266) (xy 41.854598 -179.307189) (xy 41.884062 -179.353037) (xy 41.906702 -179.402612)
			(xy 41.922056 -179.454905) (xy 41.929812 -179.50885) (xy 41.929812 -179.56335) (xy 41.922056 -179.617295)
			(xy 41.906702 -179.669588) (xy 41.884062 -179.719163) (xy 41.854598 -179.765011) (xy 41.818908 -179.8062)
			(xy 41.777721 -179.84189) (xy 41.731873 -179.871356) (xy 41.682299 -179.893997) (xy 41.630007 -179.909353)
			(xy 41.576062 -179.917111) (xy 41.548812 -179.917598) (xy 41.521442 -179.917125) (xy 41.467263 -179.909309)
			(xy 41.41476 -179.893822) (xy 41.365013 -179.870981) (xy 41.319046 -179.841258) (xy 41.298114 -179.823618)
			(xy 41.286786 -179.814382) (xy 41.260229 -179.802206) (xy 41.231312 -179.798033) (xy 41.202395 -179.802206)
			(xy 41.175838 -179.814382) (xy 41.16451 -179.823618) (xy 41.143587 -179.841269) (xy 41.097612 -179.870978)
			(xy 41.047862 -179.893812) (xy 40.995359 -179.9093) (xy 40.941182 -179.917125) (xy 40.913812 -179.917598)
			(xy 40.886558 -179.917156) (xy 40.832604 -179.9094) (xy 40.780303 -179.894045) (xy 40.73072 -179.871402)
			(xy 40.684865 -179.841934) (xy 40.643669 -179.806239) (xy 40.607973 -179.765045) (xy 40.578503 -179.71919)
			(xy 40.555859 -179.669608) (xy 40.540502 -179.617308) (xy 40.532745 -179.563354) (xy 36.646611 -179.563354)
			(xy 36.638856 -179.617295) (xy 36.623502 -179.669588) (xy 36.600862 -179.719163) (xy 36.571398 -179.765011)
			(xy 36.535708 -179.8062) (xy 36.494521 -179.84189) (xy 36.448673 -179.871356) (xy 36.399099 -179.893997)
			(xy 36.346807 -179.909353) (xy 36.292862 -179.917111) (xy 36.265612 -179.917598) (xy 36.238242 -179.917125)
			(xy 36.184063 -179.909309) (xy 36.13156 -179.893822) (xy 36.081813 -179.870981) (xy 36.035846 -179.841258)
			(xy 36.014914 -179.823618) (xy 36.003586 -179.814382) (xy 35.977029 -179.802206) (xy 35.948112 -179.798033)
			(xy 35.919195 -179.802206) (xy 35.892638 -179.814382) (xy 35.88131 -179.823618) (xy 35.860387 -179.841269)
			(xy 35.814412 -179.870978) (xy 35.764662 -179.893812) (xy 35.712159 -179.9093) (xy 35.657982 -179.917125)
			(xy 35.630612 -179.917598) (xy 35.603358 -179.917156) (xy 35.549404 -179.9094) (xy 35.497103 -179.894045)
			(xy 35.44752 -179.871402) (xy 35.401665 -179.841934) (xy 35.360469 -179.806239) (xy 35.324773 -179.765045)
			(xy 35.295303 -179.71919) (xy 35.272659 -179.669608) (xy 35.257302 -179.617308) (xy 35.249545 -179.563354)
			(xy 18.939647 -179.563354) (xy 17.838928 -180.66385) (xy 17.838928 -181.954932) (xy 23.963628 -181.954932)
			(xy 23.967699 -181.89931) (xy 23.979825 -181.844873) (xy 23.999748 -181.792782) (xy 24.027044 -181.744147)
			(xy 24.06113 -181.700004) (xy 24.101279 -181.661295) (xy 24.146637 -181.628844) (xy 24.196237 -181.603343)
			(xy 24.249021 -181.585336) (xy 24.303864 -181.575206) (xy 24.359598 -181.573169) (xy 24.415035 -181.579269)
			(xy 24.468992 -181.593375) (xy 24.520321 -181.615187) (xy 24.567927 -181.644241) (xy 24.610795 -181.679916)
			(xy 24.648012 -181.721453) (xy 24.678785 -181.767966) (xy 24.702457 -181.818463) (xy 24.718525 -181.87187)
			(xy 24.726645 -181.927046) (xy 24.727154 -181.954932) (xy 24.726645 -181.982818) (xy 24.718525 -182.037994)
			(xy 24.702457 -182.091401) (xy 24.678785 -182.141898) (xy 24.648012 -182.188411) (xy 24.610795 -182.229948)
			(xy 24.567927 -182.265623) (xy 24.520321 -182.294677) (xy 24.468992 -182.316489) (xy 24.415035 -182.330595)
			(xy 24.359598 -182.336695) (xy 24.303864 -182.334658) (xy 24.249021 -182.324528) (xy 24.196237 -182.306521)
			(xy 24.146637 -182.28102) (xy 24.101279 -182.248569) (xy 24.06113 -182.20986) (xy 24.027044 -182.165717)
			(xy 23.999748 -182.117082) (xy 23.979825 -182.064991) (xy 23.967699 -182.010554) (xy 23.963628 -181.954932)
			(xy 17.838928 -181.954932) (xy 17.838928 -182.855362) (xy 18.068544 -183.084724) (xy 18.207736 -183.223916)
			(xy 21.29282 -183.223916) (xy 21.307933 -183.201175) (xy 21.343628 -183.159858) (xy 21.384848 -183.124052)
			(xy 21.430753 -183.094488) (xy 21.480404 -183.071771) (xy 21.532786 -183.056365) (xy 21.58683 -183.048585)
			(xy 21.61413 -183.048148) (xy 21.641135 -183.048612) (xy 21.694606 -183.05622) (xy 21.746469 -183.071295)
			(xy 21.795687 -183.093535) (xy 21.841276 -183.122495) (xy 21.882325 -183.157595) (xy 21.918011 -183.198135)
			(xy 21.944904 -183.239156) (xy 22.886922 -183.239156) (xy 22.890993 -183.183534) (xy 22.903119 -183.129097)
			(xy 22.923042 -183.077006) (xy 22.950338 -183.028371) (xy 22.984424 -182.984228) (xy 23.024573 -182.945519)
			(xy 23.069931 -182.913068) (xy 23.119531 -182.887567) (xy 23.172315 -182.86956) (xy 23.227158 -182.85943)
			(xy 23.282892 -182.857393) (xy 23.338329 -182.863493) (xy 23.392286 -182.877599) (xy 23.443615 -182.899411)
			(xy 23.491221 -182.928465) (xy 23.534089 -182.96414) (xy 23.571306 -183.005677) (xy 23.602079 -183.05219)
			(xy 23.625751 -183.102687) (xy 23.641819 -183.156094) (xy 23.649939 -183.21127) (xy 23.650448 -183.239156)
			(xy 23.649939 -183.267042) (xy 23.641819 -183.322218) (xy 23.639824 -183.32885) (xy 35.261795 -183.32885)
			(xy 35.261795 -183.27435) (xy 35.269552 -183.220404) (xy 35.284906 -183.168112) (xy 35.307547 -183.118536)
			(xy 35.337012 -183.072688) (xy 35.372702 -183.031499) (xy 35.413891 -182.995809) (xy 35.45974 -182.966345)
			(xy 35.509315 -182.943705) (xy 35.561608 -182.928351) (xy 35.615554 -182.920595) (xy 35.642804 -182.920132)
			(xy 35.670175 -182.920588) (xy 35.724355 -182.928407) (xy 35.776858 -182.943898) (xy 35.826605 -182.966742)
			(xy 35.872571 -182.996469) (xy 35.893502 -183.014112) (xy 35.90483 -183.023348) (xy 35.931387 -183.035524)
			(xy 35.960304 -183.039697) (xy 35.989221 -183.035524) (xy 36.015778 -183.023348) (xy 36.027106 -183.014112)
			(xy 36.048027 -182.996459) (xy 36.094002 -182.966748) (xy 36.143753 -182.943915) (xy 36.196256 -182.928427)
			(xy 36.250434 -182.920604) (xy 36.277804 -182.920132) (xy 36.305058 -182.920538) (xy 36.359011 -182.928296)
			(xy 36.411311 -182.943653) (xy 36.460893 -182.966297) (xy 36.506747 -182.995766) (xy 36.547941 -183.031462)
			(xy 36.583636 -183.072656) (xy 36.613105 -183.118511) (xy 36.635748 -183.168093) (xy 36.651105 -183.220393)
			(xy 36.658862 -183.274346) (xy 36.658862 -183.32885) (xy 40.544995 -183.32885) (xy 40.544995 -183.27435)
			(xy 40.552752 -183.220404) (xy 40.568106 -183.168112) (xy 40.590747 -183.118536) (xy 40.620212 -183.072688)
			(xy 40.655902 -183.031499) (xy 40.697091 -182.995809) (xy 40.74294 -182.966345) (xy 40.792515 -182.943705)
			(xy 40.844808 -182.928351) (xy 40.898754 -182.920595) (xy 40.926004 -182.920132) (xy 40.953375 -182.920588)
			(xy 41.007555 -182.928407) (xy 41.060058 -182.943898) (xy 41.109805 -182.966742) (xy 41.155771 -182.996469)
			(xy 41.176702 -183.014112) (xy 41.18803 -183.023348) (xy 41.214587 -183.035524) (xy 41.243504 -183.039697)
			(xy 41.272421 -183.035524) (xy 41.298978 -183.023348) (xy 41.310306 -183.014112) (xy 41.331227 -182.996459)
			(xy 41.377202 -182.966748) (xy 41.426953 -182.943915) (xy 41.479456 -182.928427) (xy 41.533634 -182.920604)
			(xy 41.561004 -182.920132) (xy 41.588258 -182.920538) (xy 41.642211 -182.928296) (xy 41.694511 -182.943653)
			(xy 41.744093 -182.966297) (xy 41.789947 -182.995766) (xy 41.831141 -183.031462) (xy 41.866836 -183.072656)
			(xy 41.896305 -183.118511) (xy 41.918948 -183.168093) (xy 41.934305 -183.220393) (xy 41.942062 -183.274346)
			(xy 41.942062 -183.328854) (xy 41.934305 -183.382807) (xy 41.918948 -183.435107) (xy 41.896305 -183.484689)
			(xy 41.866836 -183.530544) (xy 41.831141 -183.571738) (xy 41.789947 -183.607434) (xy 41.744093 -183.636903)
			(xy 41.694511 -183.659547) (xy 41.642211 -183.674904) (xy 41.588258 -183.682662) (xy 41.561004 -183.683148)
			(xy 41.533633 -183.682692) (xy 41.479453 -183.674874) (xy 41.42695 -183.659383) (xy 41.377203 -183.636539)
			(xy 41.331237 -183.606811) (xy 41.310306 -183.589168) (xy 41.298978 -183.579932) (xy 41.272421 -183.567756)
			(xy 41.243504 -183.563583) (xy 41.214587 -183.567756) (xy 41.18803 -183.579932) (xy 41.176702 -183.589168)
			(xy 41.155776 -183.606815) (xy 41.109802 -183.636526) (xy 41.060053 -183.659361) (xy 41.007551 -183.674851)
			(xy 40.953374 -183.682676) (xy 40.926004 -183.683148) (xy 40.898754 -183.682605) (xy 40.844808 -183.674849)
			(xy 40.792515 -183.659495) (xy 40.74294 -183.636855) (xy 40.697091 -183.607391) (xy 40.655902 -183.571701)
			(xy 40.620212 -183.530512) (xy 40.590747 -183.484664) (xy 40.568106 -183.435088) (xy 40.552752 -183.382796)
			(xy 40.544995 -183.32885) (xy 36.658862 -183.32885) (xy 36.658862 -183.328854) (xy 36.651105 -183.382807)
			(xy 36.635748 -183.435107) (xy 36.613105 -183.484689) (xy 36.583636 -183.530544) (xy 36.547941 -183.571738)
			(xy 36.506747 -183.607434) (xy 36.460893 -183.636903) (xy 36.411311 -183.659547) (xy 36.359011 -183.674904)
			(xy 36.305058 -183.682662) (xy 36.277804 -183.683148) (xy 36.250433 -183.682692) (xy 36.196253 -183.674874)
			(xy 36.14375 -183.659383) (xy 36.094003 -183.636539) (xy 36.048037 -183.606811) (xy 36.027106 -183.589168)
			(xy 36.015778 -183.579932) (xy 35.989221 -183.567756) (xy 35.960304 -183.563583) (xy 35.931387 -183.567756)
			(xy 35.90483 -183.579932) (xy 35.893502 -183.589168) (xy 35.872576 -183.606815) (xy 35.826602 -183.636526)
			(xy 35.776853 -183.659361) (xy 35.724351 -183.674851) (xy 35.670174 -183.682676) (xy 35.642804 -183.683148)
			(xy 35.615554 -183.682605) (xy 35.561608 -183.674849) (xy 35.509315 -183.659495) (xy 35.45974 -183.636855)
			(xy 35.413891 -183.607391) (xy 35.372702 -183.571701) (xy 35.337012 -183.530512) (xy 35.307547 -183.484664)
			(xy 35.284906 -183.435088) (xy 35.269552 -183.382796) (xy 35.261795 -183.32885) (xy 23.639824 -183.32885)
			(xy 23.625751 -183.375625) (xy 23.602079 -183.426122) (xy 23.571306 -183.472635) (xy 23.534089 -183.514172)
			(xy 23.491221 -183.549847) (xy 23.443615 -183.578901) (xy 23.392286 -183.600713) (xy 23.338329 -183.614819)
			(xy 23.282892 -183.620919) (xy 23.227158 -183.618882) (xy 23.172315 -183.608752) (xy 23.119531 -183.590745)
			(xy 23.069931 -183.565244) (xy 23.024573 -183.532793) (xy 22.984424 -183.494084) (xy 22.950338 -183.449941)
			(xy 22.923042 -183.401306) (xy 22.903119 -183.349215) (xy 22.890993 -183.294778) (xy 22.886922 -183.239156)
			(xy 21.944904 -183.239156) (xy 21.947623 -183.243303) (xy 21.970568 -183.292197) (xy 21.978874 -183.317896)
			(xy 21.982684 -183.330088) (xy 22.90826 -184.255664) (xy 43.784266 -184.255664)
		)
		(stroke
			(width 0)
			(type solid)
		)
		(fill yes)
		(layer "In4.Cu")
		(net "GND")
	)
	(gr_poly
		(pts
			(xy 381.909066 -287.83407) (xy 381.919822 -287.844072) (xy 381.945678 -287.857985) (xy 381.974424 -287.863959)
			(xy 382.003681 -287.861501) (xy 382.031028 -287.850815) (xy 382.042924 -287.842198) (xy 382.064795 -287.82585)
			(xy 382.112816 -287.799864) (xy 382.164459 -287.782136) (xy 382.218315 -287.773151) (xy 382.245616 -287.772602)
			(xy 382.255228 -287.772685) (xy 382.274417 -287.773827) (xy 382.28397 -287.774888) (xy 382.298706 -287.735772)
			(xy 382.334052 -287.660018) (xy 382.375861 -287.587629) (xy 382.423813 -287.519155) (xy 382.45034 -287.486852)
			(xy 382.434928 -287.4653) (xy 382.410441 -287.418318) (xy 382.393758 -287.368032) (xy 382.385305 -287.31573)
			(xy 382.384808 -287.28924) (xy 382.385288 -287.263268) (xy 382.393408 -287.211961) (xy 382.409453 -287.162557)
			(xy 382.43303 -287.116271) (xy 382.463558 -287.074243) (xy 382.500284 -287.037509) (xy 382.542305 -287.006971)
			(xy 382.588585 -286.983383) (xy 382.637985 -286.967326) (xy 382.68929 -286.959194) (xy 382.715262 -286.958786)
			(xy 382.742752 -286.959336) (xy 382.796974 -286.968442) (xy 382.848942 -286.986391) (xy 382.897225 -287.012691)
			(xy 382.940492 -287.046615) (xy 382.977551 -287.087229) (xy 383.00738 -287.133414) (xy 383.018792 -287.15843)
			(xy 383.06011 -287.151616) (xy 383.143542 -287.144369) (xy 383.185416 -287.143952) (xy 383.227162 -287.144405)
			(xy 383.310337 -287.151655) (xy 383.351532 -287.15843) (xy 383.362911 -287.133395) (xy 383.392728 -287.087191)
			(xy 383.429784 -287.046563) (xy 383.473057 -287.012632) (xy 383.521351 -286.986336) (xy 383.573333 -286.9684)
			(xy 383.627567 -286.959321) (xy 383.655062 -286.958786) (xy 383.681032 -286.959266) (xy 383.732333 -286.967387)
			(xy 383.781733 -286.983434) (xy 383.828013 -287.007012) (xy 383.870034 -287.037541) (xy 383.906761 -287.074268)
			(xy 383.937289 -287.116289) (xy 383.960867 -287.162569) (xy 383.976914 -287.211968) (xy 383.985034 -287.26327)
			(xy 383.985516 -287.28924) (xy 383.985433 -287.300516) (xy 383.98391 -287.323015) (xy 383.982468 -287.334198)
			(xy 383.98097 -287.34879) (xy 383.985428 -287.377771) (xy 383.997928 -287.404295) (xy 384.017443 -287.42618)
			(xy 384.042368 -287.441625) (xy 384.056382 -287.445958) (xy 384.089814 -287.455306) (xy 384.15588 -287.476649)
			(xy 384.188462 -287.48863) (xy 384.218942 -287.50006) (xy 384.292856 -287.426146) (xy 384.282442 -287.396174)
			(xy 384.274135 -287.370159) (xy 384.265192 -287.31629) (xy 384.264662 -287.288986) (xy 384.265146 -287.263018)
			(xy 384.273273 -287.211721) (xy 384.289324 -287.162328) (xy 384.312905 -287.116053) (xy 384.343434 -287.074037)
			(xy 384.38016 -287.037314) (xy 384.422179 -287.006789) (xy 384.468456 -286.983213) (xy 384.517851 -286.967166)
			(xy 384.569148 -286.959044) (xy 384.595116 -286.958532) (xy 384.62242 -286.95907) (xy 384.676291 -286.968001)
			(xy 384.702304 -286.976312) (xy 384.732276 -286.986726) (xy 384.84937 -286.869632) (xy 384.858766 -286.859532)
			(xy 384.872271 -286.835491) (xy 384.878859 -286.808714) (xy 384.878052 -286.781151) (xy 384.869907 -286.754807)
			(xy 384.855017 -286.731597) (xy 384.845052 -286.722058) (xy 384.824597 -286.703081) (xy 384.789738 -286.659519)
			(xy 384.762694 -286.610719) (xy 384.744233 -286.558069) (xy 384.734881 -286.503066) (xy 384.734308 -286.47517)
			(xy 384.734819 -286.449203) (xy 384.742947 -286.39791) (xy 384.758998 -286.348519) (xy 384.782577 -286.302246)
			(xy 384.813103 -286.260231) (xy 384.849825 -286.223508) (xy 384.891839 -286.192981) (xy 384.938111 -286.169401)
			(xy 384.987502 -286.153349) (xy 385.038795 -286.14522) (xy 385.064762 -286.144716) (xy 385.092656 -286.1453)
			(xy 385.147651 -286.154671) (xy 385.200294 -286.173138) (xy 385.249091 -286.200177) (xy 385.292659 -286.235021)
			(xy 385.31165 -286.25546) (xy 385.321158 -286.265483) (xy 385.344356 -286.280464) (xy 385.370726 -286.288662)
			(xy 385.398328 -286.289475) (xy 385.425135 -286.282844) (xy 385.449175 -286.269256) (xy 385.459224 -286.259778)
			(xy 385.55676 -286.162242) (xy 385.566571 -286.151844) (xy 385.580503 -286.126893) (xy 385.586971 -286.099059)
			(xy 385.58547 -286.070522) (xy 385.576116 -286.04352) (xy 385.559644 -286.020169) (xy 385.537343 -286.0023)
			(xy 385.510963 -285.991314) (xy 385.496816 -285.989268) (xy 385.470315 -285.985684) (xy 385.418877 -285.971069)
			(xy 385.370461 -285.948365) (xy 385.326332 -285.918163) (xy 385.28764 -285.881252) (xy 385.255394 -285.838594)
			(xy 385.230434 -285.791302) (xy 385.213413 -285.740609) (xy 385.204773 -285.687837) (xy 385.204208 -285.6611)
			(xy 385.204717 -285.635132) (xy 385.212841 -285.583834) (xy 385.228889 -285.534439) (xy 385.252467 -285.488163)
			(xy 385.282992 -285.446144) (xy 385.319715 -285.409417) (xy 385.36173 -285.378886) (xy 385.408004 -285.355304)
			(xy 385.457397 -285.33925) (xy 385.508694 -285.33112) (xy 385.534662 -285.330646) (xy 385.561405 -285.33116)
			(xy 385.614193 -285.339773) (xy 385.664903 -285.35678) (xy 385.71221 -285.381737) (xy 385.754876 -285.41399)
			(xy 385.791787 -285.452698) (xy 385.821979 -285.496849) (xy 385.84466 -285.545287) (xy 385.85924 -285.596747)
			(xy 385.86283 -285.623254) (xy 385.864957 -285.637376) (xy 385.875973 -285.663711) (xy 385.893845 -285.68597)
			(xy 385.917177 -285.702417) (xy 385.944149 -285.711767) (xy 385.972654 -285.71329) (xy 386.000469 -285.706868)
			(xy 386.025421 -285.693001) (xy 386.035804 -285.683198) (xy 386.16001 -285.558992) (xy 386.16382 -285.548324)
			(xy 386.17378 -285.522651) (xy 386.200975 -285.474773) (xy 386.235724 -285.432059) (xy 386.256022 -285.41345)
			(xy 386.256022 -285.252414) (xy 386.255582 -285.238408) (xy 386.247976 -285.211448) (xy 386.233333 -285.187568)
			(xy 386.212753 -285.168564) (xy 386.187785 -285.155865) (xy 386.160306 -285.150426) (xy 386.132382 -285.152657)
			(xy 386.119116 -285.157164) (xy 386.091451 -285.166744) (xy 386.033832 -285.177091) (xy 386.004562 -285.177738)
			(xy 385.978598 -285.177226) (xy 385.92731 -285.169097) (xy 385.877925 -285.153046) (xy 385.831659 -285.129467)
			(xy 385.78965 -285.098942) (xy 385.752933 -285.062221) (xy 385.722413 -285.020209) (xy 385.698839 -284.97394)
			(xy 385.682794 -284.924553) (xy 385.674671 -284.873264) (xy 385.674671 -284.821336) (xy 385.682794 -284.770047)
			(xy 385.698839 -284.72066) (xy 385.722413 -284.674391) (xy 385.752933 -284.632379) (xy 385.78965 -284.595658)
			(xy 385.831659 -284.565133) (xy 385.877925 -284.541554) (xy 385.92731 -284.525503) (xy 385.978598 -284.517374)
			(xy 386.004562 -284.51683) (xy 386.033832 -284.51748) (xy 386.091451 -284.527825) (xy 386.119116 -284.537404)
			(xy 386.132398 -284.541851) (xy 386.16031 -284.544077) (xy 386.187777 -284.538641) (xy 386.212737 -284.525952)
			(xy 386.233313 -284.506962) (xy 386.24796 -284.483098) (xy 386.255577 -284.456154) (xy 386.256022 -284.442154)
			(xy 386.256022 -284.281626) (xy 386.235372 -284.262631) (xy 386.200155 -284.218958) (xy 386.172812 -284.169969)
			(xy 386.154129 -284.117068) (xy 386.144641 -284.061773) (xy 386.144008 -284.033722) (xy 386.144748 -284.001789)
			(xy 386.157028 -283.939114) (xy 386.168392 -283.909262) (xy 386.181092 -283.878274) (xy 385.555998 -283.25318)
			(xy 385.546216 -283.243978) (xy 385.52294 -283.230598) (xy 385.496982 -283.223743) (xy 385.470135 -283.223886)
			(xy 385.444252 -283.231018) (xy 385.42112 -283.244646) (xy 385.402337 -283.263829) (xy 385.3892 -283.287243)
			(xy 385.385564 -283.30017) (xy 385.37923 -283.323681) (xy 385.360601 -283.368665) (xy 385.335572 -283.41043)
			(xy 385.304687 -283.44807) (xy 385.268612 -283.48077) (xy 385.22813 -283.507823) (xy 385.184116 -283.528643)
			(xy 385.137523 -283.54278) (xy 385.089361 -283.549927) (xy 385.065016 -283.55036) (xy 385.039046 -283.549878)
			(xy 384.987744 -283.541755) (xy 384.938345 -283.525707) (xy 384.892065 -283.502128) (xy 384.850043 -283.4716)
			(xy 384.813314 -283.434874) (xy 384.782783 -283.392854) (xy 384.759201 -283.346575) (xy 384.74315 -283.297177)
			(xy 384.735023 -283.245876) (xy 384.734562 -283.219906) (xy 384.734995 -283.195561) (xy 384.742139 -283.147397)
			(xy 384.756274 -283.100803) (xy 384.777093 -283.056788) (xy 384.804146 -283.016305) (xy 384.836847 -282.980229)
			(xy 384.874488 -282.949343) (xy 384.916254 -282.924315) (xy 384.96124 -282.905687) (xy 384.984752 -282.899358)
			(xy 384.997669 -282.89568) (xy 385.021093 -282.882557) (xy 385.040286 -282.863782) (xy 385.053923 -282.840654)
			(xy 385.061061 -282.814771) (xy 385.061206 -282.787922) (xy 385.054348 -282.761964) (xy 385.040962 -282.73869)
			(xy 385.031742 -282.728924) (xy 384.956812 -282.653994) (xy 384.945456 -282.643466) (xy 384.917987 -282.6292)
			(xy 384.88751 -282.623799) (xy 384.856812 -282.627759) (xy 384.828702 -282.640716) (xy 384.816858 -282.650692)
			(xy 384.798519 -282.666718) (xy 384.758018 -282.693763) (xy 384.71399 -282.714579) (xy 384.667386 -282.728714)
			(xy 384.619212 -282.735864) (xy 384.594862 -282.73629) (xy 384.568896 -282.735778) (xy 384.517603 -282.727649)
			(xy 384.468213 -282.711598) (xy 384.421942 -282.688018) (xy 384.379928 -282.657492) (xy 384.343207 -282.62077)
			(xy 384.312681 -282.578756) (xy 384.289102 -282.532485) (xy 384.27305 -282.483095) (xy 384.264922 -282.431802)
			(xy 384.264408 -282.405836) (xy 384.264839 -282.381485) (xy 384.271979 -282.333309) (xy 384.286109 -282.286703)
			(xy 384.306925 -282.242673) (xy 384.333975 -282.202174) (xy 384.350006 -282.18384) (xy 384.360021 -282.172015)
			(xy 384.37303 -282.143906) (xy 384.377007 -282.113189) (xy 384.371583 -282.082694) (xy 384.35726 -282.055231)
			(xy 384.346704 -282.043886) (xy 384.214116 -281.911298) (xy 384.1877 -281.916378) (xy 384.172171 -281.919221)
			(xy 384.140748 -281.922279) (xy 384.124962 -281.922474) (xy 384.098996 -281.921962) (xy 384.047705 -281.913833)
			(xy 383.998316 -281.897781) (xy 383.952046 -281.874202) (xy 383.910033 -281.843675) (xy 383.873313 -281.806953)
			(xy 383.842789 -281.764939) (xy 383.819212 -281.718668) (xy 383.803163 -281.669278) (xy 383.795037 -281.617986)
			(xy 383.794508 -281.59202) (xy 383.794723 -281.576235) (xy 383.797776 -281.544813) (xy 383.800604 -281.529282)
			(xy 383.805684 -281.502866) (xy 381.784098 -279.48128) (xy 381.764032 -279.480518) (xy 381.739244 -279.479211)
			(xy 381.690454 -279.470087) (xy 381.643577 -279.453769) (xy 381.599669 -279.430622) (xy 381.559716 -279.401167)
			(xy 381.524619 -279.366068) (xy 381.495167 -279.326114) (xy 381.472023 -279.282204) (xy 381.455707 -279.235326)
			(xy 381.446587 -279.186535) (xy 381.445262 -279.161748) (xy 381.4445 -279.141682) (xy 381.18161 -278.878792)
			(xy 380.293372 -278.878792) (xy 380.279022 -278.879287) (xy 380.251458 -278.887279) (xy 380.227206 -278.902625)
			(xy 380.208181 -278.924112) (xy 380.195885 -278.950044) (xy 380.19129 -278.978374) (xy 380.194757 -279.006863)
			(xy 380.1999 -279.02027) (xy 380.208331 -279.040903) (xy 380.220199 -279.083865) (xy 380.226186 -279.128032)
			(xy 380.22657 -279.150318) (xy 380.226061 -279.176285) (xy 380.217936 -279.22758) (xy 380.201888 -279.276973)
			(xy 380.17831 -279.323247) (xy 380.147784 -279.365263) (xy 380.111061 -279.401986) (xy 380.069045 -279.432512)
			(xy 380.022771 -279.45609) (xy 379.973378 -279.472138) (xy 379.922083 -279.480263) (xy 379.870149 -279.480263)
			(xy 379.818854 -279.472138) (xy 379.769461 -279.45609) (xy 379.723187 -279.432512) (xy 379.681171 -279.401986)
			(xy 379.644448 -279.365263) (xy 379.613922 -279.323247) (xy 379.590344 -279.276973) (xy 379.574296 -279.22758)
			(xy 379.566171 -279.176285) (xy 379.565662 -279.150318) (xy 379.566027 -279.128031) (xy 379.572018 -279.083863)
			(xy 379.583894 -279.040901) (xy 379.592332 -279.02027) (xy 379.597513 -279.006876) (xy 379.600986 -278.978381)
			(xy 379.596389 -278.950045) (xy 379.584087 -278.924109) (xy 379.565052 -278.902621) (xy 379.540788 -278.887282)
			(xy 379.513213 -278.879302) (xy 379.49886 -278.878792) (xy 379.353318 -278.878792) (xy 379.338964 -278.879281)
			(xy 379.311388 -278.887266) (xy 379.287124 -278.90261) (xy 379.268088 -278.9241) (xy 379.255786 -278.95004)
			(xy 379.25119 -278.978378) (xy 379.254661 -279.006876) (xy 379.259846 -279.02027) (xy 379.268278 -279.040902)
			(xy 379.280148 -279.083864) (xy 379.286136 -279.128032) (xy 379.286516 -279.150318) (xy 379.286007 -279.176285)
			(xy 379.277882 -279.22758) (xy 379.261834 -279.276973) (xy 379.238256 -279.323247) (xy 379.20773 -279.365263)
			(xy 379.171007 -279.401986) (xy 379.128991 -279.432512) (xy 379.082717 -279.45609) (xy 379.033324 -279.472138)
			(xy 378.982029 -279.480263) (xy 378.930095 -279.480263) (xy 378.8788 -279.472138) (xy 378.829407 -279.45609)
			(xy 378.783133 -279.432512) (xy 378.741117 -279.401986) (xy 378.704394 -279.365263) (xy 378.673868 -279.323247)
			(xy 378.65029 -279.276973) (xy 378.634242 -279.22758) (xy 378.626117 -279.176285) (xy 378.625608 -279.150318)
			(xy 378.626169 -279.12302) (xy 378.635144 -279.069166) (xy 378.652854 -279.017521) (xy 378.678816 -278.969492)
			(xy 378.712323 -278.926387) (xy 378.732034 -278.907494) (xy 378.741771 -278.897895) (xy 378.7562 -278.874683)
			(xy 378.763951 -278.848473) (xy 378.764467 -278.821146) (xy 378.757711 -278.794663) (xy 378.744169 -278.770922)
			(xy 378.734828 -278.760936) (xy 378.615956 -278.642064) (xy 378.586492 -278.651462) (xy 378.562051 -278.658736)
			(xy 378.511658 -278.666522) (xy 378.486162 -278.666956) (xy 378.460197 -278.666444) (xy 378.408906 -278.658315)
			(xy 378.359519 -278.642263) (xy 378.31325 -278.618683) (xy 378.271239 -278.588156) (xy 378.23452 -278.551434)
			(xy 378.203998 -278.50942) (xy 378.180423 -278.463148) (xy 378.164377 -278.413759) (xy 378.156253 -278.362467)
			(xy 378.155708 -278.336502) (xy 378.156161 -278.311007) (xy 378.16394 -278.260615) (xy 378.171202 -278.236172)
			(xy 378.1806 -278.206708) (xy 377.558808 -277.584916) (xy 377.547959 -277.574774) (xy 377.521828 -277.56069)
			(xy 377.492748 -277.554725) (xy 377.463182 -277.557382) (xy 377.435632 -277.568436) (xy 377.41243 -277.586952)
			(xy 377.395539 -277.611363) (xy 377.390406 -277.625302) (xy 377.381853 -277.649765) (xy 377.358221 -277.695882)
			(xy 377.327682 -277.737746) (xy 377.290985 -277.774332) (xy 377.249029 -277.804745) (xy 377.20284 -277.828237)
			(xy 377.153552 -277.844235) (xy 377.102371 -277.852346) (xy 377.076462 -277.852886) (xy 377.050496 -277.852374)
			(xy 376.999204 -277.844245) (xy 376.949814 -277.828193) (xy 376.903543 -277.804614) (xy 376.86153 -277.774088)
			(xy 376.824808 -277.737366) (xy 376.794283 -277.695352) (xy 376.770704 -277.64908) (xy 376.754653 -277.599691)
			(xy 376.746526 -277.548398) (xy 376.746008 -277.522432) (xy 376.746457 -277.497837) (xy 376.753744 -277.449189)
			(xy 376.76816 -277.402158) (xy 376.789388 -277.357784) (xy 376.816959 -277.317046) (xy 376.850264 -277.280845)
			(xy 376.888567 -277.24998) (xy 376.931021 -277.225134) (xy 376.976689 -277.206854) (xy 377.024562 -277.195545)
			(xy 377.04903 -277.192994) (xy 377.064059 -277.191178) (xy 377.09215 -277.179935) (xy 377.115725 -277.160968)
			(xy 377.132722 -277.135937) (xy 377.141657 -277.107029) (xy 377.142248 -277.091902) (xy 377.142248 -276.32533)
			(xy 377.141684 -276.310179) (xy 377.132789 -276.281212) (xy 377.1158 -276.25612) (xy 377.092207 -276.237104)
			(xy 377.064079 -276.225831) (xy 377.04903 -276.223984) (xy 377.023297 -276.221317) (xy 376.973052 -276.209001)
			(xy 376.925341 -276.189003) (xy 376.88133 -276.161813) (xy 376.842096 -276.128094) (xy 376.808597 -276.088672)
			(xy 376.781654 -276.04451) (xy 376.761924 -275.996687) (xy 376.749889 -275.946374) (xy 376.745845 -275.8948)
			(xy 376.749889 -275.843226) (xy 376.761924 -275.792913) (xy 376.781654 -275.74509) (xy 376.808597 -275.700928)
			(xy 376.842096 -275.661506) (xy 376.88133 -275.627787) (xy 376.925341 -275.600597) (xy 376.973052 -275.580599)
			(xy 377.023297 -275.568283) (xy 377.04903 -275.565616) (xy 377.064094 -275.563816) (xy 377.092252 -275.552566)
			(xy 377.115866 -275.533545) (xy 377.132854 -275.508429) (xy 377.141719 -275.479432) (xy 377.142248 -275.46427)
			(xy 377.142248 -274.697444) (xy 377.141709 -274.6823) (xy 377.132841 -274.653339) (xy 377.115847 -274.628269)
			(xy 377.09223 -274.609307) (xy 377.06408 -274.59813) (xy 377.04903 -274.596352) (xy 377.024561 -274.593839)
			(xy 376.976699 -274.582498) (xy 376.931044 -274.564196) (xy 376.888602 -274.539336) (xy 376.850309 -274.508465)
			(xy 376.817008 -274.472265) (xy 376.789435 -274.431534) (xy 376.768196 -274.387168) (xy 376.753761 -274.340147)
			(xy 376.746447 -274.291507) (xy 376.746008 -274.266914) (xy 376.746503 -274.241115) (xy 376.754519 -274.190144)
			(xy 376.77036 -274.141038) (xy 376.79364 -274.09499) (xy 376.823793 -274.05312) (xy 376.860086 -274.016444)
			(xy 376.901639 -273.985855) (xy 376.924316 -273.973544) (xy 376.936249 -273.966875) (xy 376.956317 -273.948327)
			(xy 376.970737 -273.925115) (xy 376.978475 -273.898907) (xy 376.978974 -273.871585) (xy 376.972199 -273.845111)
			(xy 376.958636 -273.821388) (xy 376.949208 -273.811492) (xy 376.832368 -273.694652) (xy 376.813912 -273.711281)
			(xy 376.772941 -273.739374) (xy 376.728225 -273.761014) (xy 376.680773 -273.775714) (xy 376.631655 -273.783141)
			(xy 376.606816 -273.783552) (xy 376.580861 -273.783045) (xy 376.529588 -273.77493) (xy 376.480215 -273.758899)
			(xy 376.433957 -273.735344) (xy 376.39195 -273.704846) (xy 376.355229 -273.668154) (xy 376.324696 -273.626172)
			(xy 376.301104 -273.579933) (xy 376.285032 -273.530573) (xy 376.276876 -273.479307) (xy 376.276362 -273.453352)
			(xy 376.276362 -273.402552) (xy 375.99747 -273.402552) (xy 375.99747 -273.453352) (xy 375.996942 -273.479306)
			(xy 375.988786 -273.530571) (xy 375.972715 -273.579929) (xy 375.949124 -273.626168) (xy 375.918593 -273.668149)
			(xy 375.881874 -273.70484) (xy 375.839869 -273.735339) (xy 375.793612 -273.758894) (xy 375.744241 -273.774927)
			(xy 375.692971 -273.783044) (xy 375.641061 -273.783044) (xy 375.589791 -273.774927) (xy 375.54042 -273.758894)
			(xy 375.494163 -273.735339) (xy 375.452158 -273.70484) (xy 375.415439 -273.668149) (xy 375.384908 -273.626168)
			(xy 375.361317 -273.579929) (xy 375.345246 -273.530571) (xy 375.33709 -273.479306) (xy 375.336562 -273.453352)
			(xy 375.336562 -273.402552) (xy 375.05767 -273.402552) (xy 375.05767 -273.453352) (xy 375.057142 -273.479306)
			(xy 375.048986 -273.530571) (xy 375.032915 -273.579929) (xy 375.009324 -273.626168) (xy 374.978793 -273.668149)
			(xy 374.942074 -273.70484) (xy 374.900069 -273.735339) (xy 374.853812 -273.758894) (xy 374.804441 -273.774927)
			(xy 374.753171 -273.783044) (xy 374.701261 -273.783044) (xy 374.649991 -273.774927) (xy 374.60062 -273.758894)
			(xy 374.554363 -273.735339) (xy 374.512358 -273.70484) (xy 374.475639 -273.668149) (xy 374.445108 -273.626168)
			(xy 374.421517 -273.579929) (xy 374.405446 -273.530571) (xy 374.39729 -273.479306) (xy 374.396762 -273.453352)
			(xy 374.396762 -273.402552) (xy 374.11787 -273.402552) (xy 374.11787 -273.453352) (xy 374.117342 -273.479306)
			(xy 374.109186 -273.530571) (xy 374.093115 -273.579929) (xy 374.069524 -273.626168) (xy 374.038993 -273.668149)
			(xy 374.002274 -273.70484) (xy 373.960269 -273.735339) (xy 373.914012 -273.758894) (xy 373.864641 -273.774927)
			(xy 373.813371 -273.783044) (xy 373.761461 -273.783044) (xy 373.710191 -273.774927) (xy 373.66082 -273.758894)
			(xy 373.614563 -273.735339) (xy 373.572558 -273.70484) (xy 373.535839 -273.668149) (xy 373.505308 -273.626168)
			(xy 373.481717 -273.579929) (xy 373.465646 -273.530571) (xy 373.45749 -273.479306) (xy 373.456962 -273.453352)
			(xy 373.456962 -273.402552) (xy 373.17807 -273.402552) (xy 373.17807 -273.453352) (xy 373.177542 -273.479306)
			(xy 373.169386 -273.530571) (xy 373.153315 -273.579929) (xy 373.129724 -273.626168) (xy 373.099193 -273.668149)
			(xy 373.062474 -273.70484) (xy 373.020469 -273.735339) (xy 372.974212 -273.758894) (xy 372.924841 -273.774927)
			(xy 372.873571 -273.783044) (xy 372.821661 -273.783044) (xy 372.770391 -273.774927) (xy 372.72102 -273.758894)
			(xy 372.674763 -273.735339) (xy 372.632758 -273.70484) (xy 372.596039 -273.668149) (xy 372.565508 -273.626168)
			(xy 372.541917 -273.579929) (xy 372.525846 -273.530571) (xy 372.51769 -273.479306) (xy 372.517162 -273.453352)
			(xy 372.517162 -273.402552) (xy 372.23827 -273.402552) (xy 372.23827 -273.453352) (xy 372.237742 -273.479306)
			(xy 372.229586 -273.530571) (xy 372.213515 -273.579929) (xy 372.189924 -273.626168) (xy 372.159393 -273.668149)
			(xy 372.122674 -273.70484) (xy 372.080669 -273.735339) (xy 372.034412 -273.758894) (xy 371.985041 -273.774927)
			(xy 371.933771 -273.783044) (xy 371.881861 -273.783044) (xy 371.830591 -273.774927) (xy 371.78122 -273.758894)
			(xy 371.734963 -273.735339) (xy 371.692958 -273.70484) (xy 371.656239 -273.668149) (xy 371.625708 -273.626168)
			(xy 371.602117 -273.579929) (xy 371.586046 -273.530571) (xy 371.57789 -273.479306) (xy 371.577362 -273.453352)
			(xy 371.577362 -273.402552) (xy 371.298216 -273.402552) (xy 371.298216 -273.453352) (xy 371.297688 -273.479306)
			(xy 371.289532 -273.530571) (xy 371.273461 -273.579929) (xy 371.24987 -273.626168) (xy 371.219339 -273.668149)
			(xy 371.18262 -273.70484) (xy 371.140615 -273.735339) (xy 371.094358 -273.758894) (xy 371.044987 -273.774927)
			(xy 370.993717 -273.783044) (xy 370.941807 -273.783044) (xy 370.890537 -273.774927) (xy 370.841166 -273.758894)
			(xy 370.794909 -273.735339) (xy 370.752904 -273.70484) (xy 370.716185 -273.668149) (xy 370.685654 -273.626168)
			(xy 370.662063 -273.579929) (xy 370.645992 -273.530571) (xy 370.637836 -273.479306) (xy 370.637308 -273.453352)
			(xy 370.637308 -273.402552) (xy 370.35867 -273.402552) (xy 370.35867 -273.453352) (xy 370.358142 -273.479306)
			(xy 370.349986 -273.530571) (xy 370.333915 -273.579929) (xy 370.310324 -273.626168) (xy 370.279793 -273.668149)
			(xy 370.243074 -273.70484) (xy 370.201069 -273.735339) (xy 370.154812 -273.758894) (xy 370.105441 -273.774927)
			(xy 370.054171 -273.783044) (xy 370.002261 -273.783044) (xy 369.950991 -273.774927) (xy 369.90162 -273.758894)
			(xy 369.855363 -273.735339) (xy 369.813358 -273.70484) (xy 369.776639 -273.668149) (xy 369.746108 -273.626168)
			(xy 369.722517 -273.579929) (xy 369.706446 -273.530571) (xy 369.69829 -273.479306) (xy 369.697762 -273.453352)
			(xy 369.697762 -273.402552) (xy 369.41887 -273.402552) (xy 369.41887 -273.453352) (xy 369.418342 -273.479306)
			(xy 369.410186 -273.530571) (xy 369.394115 -273.579929) (xy 369.370524 -273.626168) (xy 369.339993 -273.668149)
			(xy 369.303274 -273.70484) (xy 369.261269 -273.735339) (xy 369.215012 -273.758894) (xy 369.165641 -273.774927)
			(xy 369.114371 -273.783044) (xy 369.062461 -273.783044) (xy 369.011191 -273.774927) (xy 368.96182 -273.758894)
			(xy 368.915563 -273.735339) (xy 368.873558 -273.70484) (xy 368.836839 -273.668149) (xy 368.806308 -273.626168)
			(xy 368.782717 -273.579929) (xy 368.766646 -273.530571) (xy 368.75849 -273.479306) (xy 368.757962 -273.453352)
			(xy 368.757962 -273.402552) (xy 368.47907 -273.402552) (xy 368.47907 -273.453352) (xy 368.478542 -273.479306)
			(xy 368.470386 -273.530571) (xy 368.454315 -273.579929) (xy 368.430724 -273.626168) (xy 368.400193 -273.668149)
			(xy 368.363474 -273.70484) (xy 368.321469 -273.735339) (xy 368.275212 -273.758894) (xy 368.225841 -273.774927)
			(xy 368.174571 -273.783044) (xy 368.122661 -273.783044) (xy 368.071391 -273.774927) (xy 368.02202 -273.758894)
			(xy 367.975763 -273.735339) (xy 367.933758 -273.70484) (xy 367.897039 -273.668149) (xy 367.866508 -273.626168)
			(xy 367.842917 -273.579929) (xy 367.826846 -273.530571) (xy 367.81869 -273.479306) (xy 367.818162 -273.453352)
			(xy 367.818162 -273.402552) (xy 367.53927 -273.402552) (xy 367.53927 -273.453352) (xy 367.538742 -273.479306)
			(xy 367.530586 -273.530571) (xy 367.514515 -273.579929) (xy 367.490924 -273.626168) (xy 367.460393 -273.668149)
			(xy 367.423674 -273.70484) (xy 367.381669 -273.735339) (xy 367.335412 -273.758894) (xy 367.286041 -273.774927)
			(xy 367.234771 -273.783044) (xy 367.182861 -273.783044) (xy 367.131591 -273.774927) (xy 367.08222 -273.758894)
			(xy 367.035963 -273.735339) (xy 366.993958 -273.70484) (xy 366.957239 -273.668149) (xy 366.926708 -273.626168)
			(xy 366.903117 -273.579929) (xy 366.887046 -273.530571) (xy 366.87889 -273.479306) (xy 366.878362 -273.453352)
			(xy 366.878362 -273.402552) (xy 366.59947 -273.402552) (xy 366.59947 -273.453352) (xy 366.598942 -273.479307)
			(xy 366.590786 -273.530572) (xy 366.574716 -273.579932) (xy 366.551125 -273.626172) (xy 366.520595 -273.668155)
			(xy 366.483875 -273.704848) (xy 366.441871 -273.735348) (xy 366.395614 -273.758906) (xy 366.346242 -273.774942)
			(xy 366.294971 -273.783061) (xy 366.269016 -273.783552) (xy 366.247467 -273.783222) (xy 366.204732 -273.777645)
			(xy 366.163089 -273.766545) (xy 366.143032 -273.75866) (xy 366.11179 -273.745706) (xy 365.998506 -273.85899)
			(xy 365.988771 -273.869382) (xy 365.97497 -273.894275) (xy 365.968585 -273.922012) (xy 365.970113 -273.950434)
			(xy 365.979436 -273.977326) (xy 365.995827 -274.000596) (xy 366.006634 -274.009866) (xy 366.025473 -274.025634)
			(xy 366.058726 -274.061794) (xy 366.086254 -274.102482) (xy 366.107449 -274.146799) (xy 366.121844 -274.193768)
			(xy 366.129121 -274.242351) (xy 366.12957 -274.266914) (xy 366.12913 -274.291341) (xy 366.128901 -274.292881)
			(xy 366.408717 -274.292881) (xy 366.408717 -274.240947) (xy 366.416842 -274.189652) (xy 366.43289 -274.140259)
			(xy 366.456468 -274.093985) (xy 366.486994 -274.051969) (xy 366.523717 -274.015246) (xy 366.565733 -273.98472)
			(xy 366.612007 -273.961142) (xy 366.6614 -273.945094) (xy 366.712695 -273.936969) (xy 366.764629 -273.936969)
			(xy 366.815924 -273.945094) (xy 366.865317 -273.961142) (xy 366.911591 -273.98472) (xy 366.953607 -274.015246)
			(xy 366.99033 -274.051969) (xy 367.020856 -274.093985) (xy 367.044434 -274.140259) (xy 367.060482 -274.189652)
			(xy 367.068607 -274.240947) (xy 367.069116 -274.266914) (xy 367.068607 -274.292881) (xy 367.348517 -274.292881)
			(xy 367.348517 -274.240947) (xy 367.356642 -274.189652) (xy 367.37269 -274.140259) (xy 367.396268 -274.093985)
			(xy 367.426794 -274.051969) (xy 367.463517 -274.015246) (xy 367.505533 -273.98472) (xy 367.551807 -273.961142)
			(xy 367.6012 -273.945094) (xy 367.652495 -273.936969) (xy 367.704429 -273.936969) (xy 367.755724 -273.945094)
			(xy 367.805117 -273.961142) (xy 367.851391 -273.98472) (xy 367.893407 -274.015246) (xy 367.93013 -274.051969)
			(xy 367.960656 -274.093985) (xy 367.984234 -274.140259) (xy 368.000282 -274.189652) (xy 368.008407 -274.240947)
			(xy 368.008916 -274.266914) (xy 368.008407 -274.292881) (xy 368.288317 -274.292881) (xy 368.288317 -274.240947)
			(xy 368.296442 -274.189652) (xy 368.31249 -274.140259) (xy 368.336068 -274.093985) (xy 368.366594 -274.051969)
			(xy 368.403317 -274.015246) (xy 368.445333 -273.98472) (xy 368.491607 -273.961142) (xy 368.541 -273.945094)
			(xy 368.592295 -273.936969) (xy 368.644229 -273.936969) (xy 368.695524 -273.945094) (xy 368.744917 -273.961142)
			(xy 368.791191 -273.98472) (xy 368.833207 -274.015246) (xy 368.86993 -274.051969) (xy 368.900456 -274.093985)
			(xy 368.924034 -274.140259) (xy 368.940082 -274.189652) (xy 368.948207 -274.240947) (xy 368.948716 -274.266914)
			(xy 368.948207 -274.292881) (xy 369.228371 -274.292881) (xy 369.228371 -274.240947) (xy 369.236496 -274.189652)
			(xy 369.252544 -274.140259) (xy 369.276122 -274.093985) (xy 369.306648 -274.051969) (xy 369.343371 -274.015246)
			(xy 369.385387 -273.98472) (xy 369.431661 -273.961142) (xy 369.481054 -273.945094) (xy 369.532349 -273.936969)
			(xy 369.584283 -273.936969) (xy 369.635578 -273.945094) (xy 369.684971 -273.961142) (xy 369.731245 -273.98472)
			(xy 369.773261 -274.015246) (xy 369.809984 -274.051969) (xy 369.84051 -274.093985) (xy 369.864088 -274.140259)
			(xy 369.880136 -274.189652) (xy 369.888261 -274.240947) (xy 369.88877 -274.266914) (xy 369.888261 -274.292881)
			(xy 370.167917 -274.292881) (xy 370.167917 -274.240947) (xy 370.176042 -274.189652) (xy 370.19209 -274.140259)
			(xy 370.215668 -274.093985) (xy 370.246194 -274.051969) (xy 370.282917 -274.015246) (xy 370.324933 -273.98472)
			(xy 370.371207 -273.961142) (xy 370.4206 -273.945094) (xy 370.471895 -273.936969) (xy 370.523829 -273.936969)
			(xy 370.575124 -273.945094) (xy 370.624517 -273.961142) (xy 370.670791 -273.98472) (xy 370.712807 -274.015246)
			(xy 370.74953 -274.051969) (xy 370.780056 -274.093985) (xy 370.803634 -274.140259) (xy 370.819682 -274.189652)
			(xy 370.827807 -274.240947) (xy 370.828316 -274.266914) (xy 370.827807 -274.292881) (xy 371.107717 -274.292881)
			(xy 371.107717 -274.240947) (xy 371.115842 -274.189652) (xy 371.13189 -274.140259) (xy 371.155468 -274.093985)
			(xy 371.185994 -274.051969) (xy 371.222717 -274.015246) (xy 371.264733 -273.98472) (xy 371.311007 -273.961142)
			(xy 371.3604 -273.945094) (xy 371.411695 -273.936969) (xy 371.463629 -273.936969) (xy 371.514924 -273.945094)
			(xy 371.564317 -273.961142) (xy 371.610591 -273.98472) (xy 371.652607 -274.015246) (xy 371.68933 -274.051969)
			(xy 371.719856 -274.093985) (xy 371.743434 -274.140259) (xy 371.759482 -274.189652) (xy 371.767607 -274.240947)
			(xy 371.768116 -274.266914) (xy 371.767607 -274.292881) (xy 372.047517 -274.292881) (xy 372.047517 -274.240947)
			(xy 372.055642 -274.189652) (xy 372.07169 -274.140259) (xy 372.095268 -274.093985) (xy 372.125794 -274.051969)
			(xy 372.162517 -274.015246) (xy 372.204533 -273.98472) (xy 372.250807 -273.961142) (xy 372.3002 -273.945094)
			(xy 372.351495 -273.936969) (xy 372.403429 -273.936969) (xy 372.454724 -273.945094) (xy 372.504117 -273.961142)
			(xy 372.550391 -273.98472) (xy 372.592407 -274.015246) (xy 372.62913 -274.051969) (xy 372.659656 -274.093985)
			(xy 372.683234 -274.140259) (xy 372.699282 -274.189652) (xy 372.707407 -274.240947) (xy 372.707916 -274.266914)
			(xy 372.707407 -274.292881) (xy 372.987317 -274.292881) (xy 372.987317 -274.240947) (xy 372.995442 -274.189652)
			(xy 373.01149 -274.140259) (xy 373.035068 -274.093985) (xy 373.065594 -274.051969) (xy 373.102317 -274.015246)
			(xy 373.144333 -273.98472) (xy 373.190607 -273.961142) (xy 373.24 -273.945094) (xy 373.291295 -273.936969)
			(xy 373.343229 -273.936969) (xy 373.394524 -273.945094) (xy 373.443917 -273.961142) (xy 373.490191 -273.98472)
			(xy 373.532207 -274.015246) (xy 373.56893 -274.051969) (xy 373.599456 -274.093985) (xy 373.623034 -274.140259)
			(xy 373.639082 -274.189652) (xy 373.647207 -274.240947) (xy 373.647716 -274.266914) (xy 373.647207 -274.292881)
			(xy 373.927371 -274.292881) (xy 373.927371 -274.240947) (xy 373.935496 -274.189652) (xy 373.951544 -274.140259)
			(xy 373.975122 -274.093985) (xy 374.005648 -274.051969) (xy 374.042371 -274.015246) (xy 374.084387 -273.98472)
			(xy 374.130661 -273.961142) (xy 374.180054 -273.945094) (xy 374.231349 -273.936969) (xy 374.283283 -273.936969)
			(xy 374.334578 -273.945094) (xy 374.383971 -273.961142) (xy 374.430245 -273.98472) (xy 374.472261 -274.015246)
			(xy 374.508984 -274.051969) (xy 374.53951 -274.093985) (xy 374.563088 -274.140259) (xy 374.579136 -274.189652)
			(xy 374.587261 -274.240947) (xy 374.58777 -274.266914) (xy 374.587261 -274.292881) (xy 374.866917 -274.292881)
			(xy 374.866917 -274.240947) (xy 374.875042 -274.189652) (xy 374.89109 -274.140259) (xy 374.914668 -274.093985)
			(xy 374.945194 -274.051969) (xy 374.981917 -274.015246) (xy 375.023933 -273.98472) (xy 375.070207 -273.961142)
			(xy 375.1196 -273.945094) (xy 375.170895 -273.936969) (xy 375.222829 -273.936969) (xy 375.274124 -273.945094)
			(xy 375.323517 -273.961142) (xy 375.369791 -273.98472) (xy 375.411807 -274.015246) (xy 375.44853 -274.051969)
			(xy 375.479056 -274.093985) (xy 375.502634 -274.140259) (xy 375.518682 -274.189652) (xy 375.526807 -274.240947)
			(xy 375.527316 -274.266914) (xy 375.526807 -274.292881) (xy 375.806717 -274.292881) (xy 375.806717 -274.240947)
			(xy 375.814842 -274.189652) (xy 375.83089 -274.140259) (xy 375.854468 -274.093985) (xy 375.884994 -274.051969)
			(xy 375.921717 -274.015246) (xy 375.963733 -273.98472) (xy 376.010007 -273.961142) (xy 376.0594 -273.945094)
			(xy 376.110695 -273.936969) (xy 376.162629 -273.936969) (xy 376.213924 -273.945094) (xy 376.263317 -273.961142)
			(xy 376.309591 -273.98472) (xy 376.351607 -274.015246) (xy 376.38833 -274.051969) (xy 376.418856 -274.093985)
			(xy 376.442434 -274.140259) (xy 376.458482 -274.189652) (xy 376.466607 -274.240947) (xy 376.467116 -274.266914)
			(xy 376.466607 -274.292881) (xy 376.458482 -274.344176) (xy 376.442434 -274.393569) (xy 376.418856 -274.439843)
			(xy 376.38833 -274.481859) (xy 376.351607 -274.518582) (xy 376.309591 -274.549108) (xy 376.263317 -274.572686)
			(xy 376.213924 -274.588734) (xy 376.162629 -274.596859) (xy 376.110695 -274.596859) (xy 376.0594 -274.588734)
			(xy 376.010007 -274.572686) (xy 375.963733 -274.549108) (xy 375.921717 -274.518582) (xy 375.884994 -274.481859)
			(xy 375.854468 -274.439843) (xy 375.83089 -274.393569) (xy 375.814842 -274.344176) (xy 375.806717 -274.292881)
			(xy 375.526807 -274.292881) (xy 375.518682 -274.344176) (xy 375.502634 -274.393569) (xy 375.479056 -274.439843)
			(xy 375.44853 -274.481859) (xy 375.411807 -274.518582) (xy 375.369791 -274.549108) (xy 375.323517 -274.572686)
			(xy 375.274124 -274.588734) (xy 375.222829 -274.596859) (xy 375.170895 -274.596859) (xy 375.1196 -274.588734)
			(xy 375.070207 -274.572686) (xy 375.023933 -274.549108) (xy 374.981917 -274.518582) (xy 374.945194 -274.481859)
			(xy 374.914668 -274.439843) (xy 374.89109 -274.393569) (xy 374.875042 -274.344176) (xy 374.866917 -274.292881)
			(xy 374.587261 -274.292881) (xy 374.579136 -274.344176) (xy 374.563088 -274.393569) (xy 374.53951 -274.439843)
			(xy 374.508984 -274.481859) (xy 374.472261 -274.518582) (xy 374.430245 -274.549108) (xy 374.383971 -274.572686)
			(xy 374.334578 -274.588734) (xy 374.283283 -274.596859) (xy 374.231349 -274.596859) (xy 374.180054 -274.588734)
			(xy 374.130661 -274.572686) (xy 374.084387 -274.549108) (xy 374.042371 -274.518582) (xy 374.005648 -274.481859)
			(xy 373.975122 -274.439843) (xy 373.951544 -274.393569) (xy 373.935496 -274.344176) (xy 373.927371 -274.292881)
			(xy 373.647207 -274.292881) (xy 373.639082 -274.344176) (xy 373.623034 -274.393569) (xy 373.599456 -274.439843)
			(xy 373.56893 -274.481859) (xy 373.532207 -274.518582) (xy 373.490191 -274.549108) (xy 373.443917 -274.572686)
			(xy 373.394524 -274.588734) (xy 373.343229 -274.596859) (xy 373.291295 -274.596859) (xy 373.24 -274.588734)
			(xy 373.190607 -274.572686) (xy 373.144333 -274.549108) (xy 373.102317 -274.518582) (xy 373.065594 -274.481859)
			(xy 373.035068 -274.439843) (xy 373.01149 -274.393569) (xy 372.995442 -274.344176) (xy 372.987317 -274.292881)
			(xy 372.707407 -274.292881) (xy 372.699282 -274.344176) (xy 372.683234 -274.393569) (xy 372.659656 -274.439843)
			(xy 372.62913 -274.481859) (xy 372.592407 -274.518582) (xy 372.550391 -274.549108) (xy 372.504117 -274.572686)
			(xy 372.454724 -274.588734) (xy 372.403429 -274.596859) (xy 372.351495 -274.596859) (xy 372.3002 -274.588734)
			(xy 372.250807 -274.572686) (xy 372.204533 -274.549108) (xy 372.162517 -274.518582) (xy 372.125794 -274.481859)
			(xy 372.095268 -274.439843) (xy 372.07169 -274.393569) (xy 372.055642 -274.344176) (xy 372.047517 -274.292881)
			(xy 371.767607 -274.292881) (xy 371.759482 -274.344176) (xy 371.743434 -274.393569) (xy 371.719856 -274.439843)
			(xy 371.68933 -274.481859) (xy 371.652607 -274.518582) (xy 371.610591 -274.549108) (xy 371.564317 -274.572686)
			(xy 371.514924 -274.588734) (xy 371.463629 -274.596859) (xy 371.411695 -274.596859) (xy 371.3604 -274.588734)
			(xy 371.311007 -274.572686) (xy 371.264733 -274.549108) (xy 371.222717 -274.518582) (xy 371.185994 -274.481859)
			(xy 371.155468 -274.439843) (xy 371.13189 -274.393569) (xy 371.115842 -274.344176) (xy 371.107717 -274.292881)
			(xy 370.827807 -274.292881) (xy 370.819682 -274.344176) (xy 370.803634 -274.393569) (xy 370.780056 -274.439843)
			(xy 370.74953 -274.481859) (xy 370.712807 -274.518582) (xy 370.670791 -274.549108) (xy 370.624517 -274.572686)
			(xy 370.575124 -274.588734) (xy 370.523829 -274.596859) (xy 370.471895 -274.596859) (xy 370.4206 -274.588734)
			(xy 370.371207 -274.572686) (xy 370.324933 -274.549108) (xy 370.282917 -274.518582) (xy 370.246194 -274.481859)
			(xy 370.215668 -274.439843) (xy 370.19209 -274.393569) (xy 370.176042 -274.344176) (xy 370.167917 -274.292881)
			(xy 369.888261 -274.292881) (xy 369.880136 -274.344176) (xy 369.864088 -274.393569) (xy 369.84051 -274.439843)
			(xy 369.809984 -274.481859) (xy 369.773261 -274.518582) (xy 369.731245 -274.549108) (xy 369.684971 -274.572686)
			(xy 369.635578 -274.588734) (xy 369.584283 -274.596859) (xy 369.532349 -274.596859) (xy 369.481054 -274.588734)
			(xy 369.431661 -274.572686) (xy 369.385387 -274.549108) (xy 369.343371 -274.518582) (xy 369.306648 -274.481859)
			(xy 369.276122 -274.439843) (xy 369.252544 -274.393569) (xy 369.236496 -274.344176) (xy 369.228371 -274.292881)
			(xy 368.948207 -274.292881) (xy 368.940082 -274.344176) (xy 368.924034 -274.393569) (xy 368.900456 -274.439843)
			(xy 368.86993 -274.481859) (xy 368.833207 -274.518582) (xy 368.791191 -274.549108) (xy 368.744917 -274.572686)
			(xy 368.695524 -274.588734) (xy 368.644229 -274.596859) (xy 368.592295 -274.596859) (xy 368.541 -274.588734)
			(xy 368.491607 -274.572686) (xy 368.445333 -274.549108) (xy 368.403317 -274.518582) (xy 368.366594 -274.481859)
			(xy 368.336068 -274.439843) (xy 368.31249 -274.393569) (xy 368.296442 -274.344176) (xy 368.288317 -274.292881)
			(xy 368.008407 -274.292881) (xy 368.000282 -274.344176) (xy 367.984234 -274.393569) (xy 367.960656 -274.439843)
			(xy 367.93013 -274.481859) (xy 367.893407 -274.518582) (xy 367.851391 -274.549108) (xy 367.805117 -274.572686)
			(xy 367.755724 -274.588734) (xy 367.704429 -274.596859) (xy 367.652495 -274.596859) (xy 367.6012 -274.588734)
			(xy 367.551807 -274.572686) (xy 367.505533 -274.549108) (xy 367.463517 -274.518582) (xy 367.426794 -274.481859)
			(xy 367.396268 -274.439843) (xy 367.37269 -274.393569) (xy 367.356642 -274.344176) (xy 367.348517 -274.292881)
			(xy 367.068607 -274.292881) (xy 367.060482 -274.344176) (xy 367.044434 -274.393569) (xy 367.020856 -274.439843)
			(xy 366.99033 -274.481859) (xy 366.953607 -274.518582) (xy 366.911591 -274.549108) (xy 366.865317 -274.572686)
			(xy 366.815924 -274.588734) (xy 366.764629 -274.596859) (xy 366.712695 -274.596859) (xy 366.6614 -274.588734)
			(xy 366.612007 -274.572686) (xy 366.565733 -274.549108) (xy 366.523717 -274.518582) (xy 366.486994 -274.481859)
			(xy 366.456468 -274.439843) (xy 366.43289 -274.393569) (xy 366.416842 -274.344176) (xy 366.408717 -274.292881)
			(xy 366.128901 -274.292881) (xy 366.121935 -274.339663) (xy 366.107705 -274.386399) (xy 366.086749 -274.430531)
			(xy 366.059524 -274.471096) (xy 366.026624 -274.507212) (xy 365.988765 -274.53809) (xy 365.946773 -274.563058)
			(xy 365.924338 -274.57273) (xy 365.892842 -274.585684) (xy 365.892842 -275.106697) (xy 367.818671 -275.106697)
			(xy 367.818671 -275.054763) (xy 367.826796 -275.003468) (xy 367.842844 -274.954075) (xy 367.866422 -274.907801)
			(xy 367.896948 -274.865785) (xy 367.933671 -274.829062) (xy 367.975687 -274.798536) (xy 368.021961 -274.774958)
			(xy 368.071354 -274.75891) (xy 368.122649 -274.750785) (xy 368.174583 -274.750785) (xy 368.225878 -274.75891)
			(xy 368.275271 -274.774958) (xy 368.321545 -274.798536) (xy 368.363561 -274.829062) (xy 368.400284 -274.865785)
			(xy 368.43081 -274.907801) (xy 368.454388 -274.954075) (xy 368.470436 -275.003468) (xy 368.478561 -275.054763)
			(xy 368.47907 -275.08073) (xy 368.478566 -275.106443) (xy 368.758217 -275.106443) (xy 368.758217 -275.054509)
			(xy 368.766342 -275.003214) (xy 368.78239 -274.953821) (xy 368.805968 -274.907547) (xy 368.836494 -274.865531)
			(xy 368.873217 -274.828808) (xy 368.915233 -274.798282) (xy 368.961507 -274.774704) (xy 369.0109 -274.758656)
			(xy 369.062195 -274.750531) (xy 369.114129 -274.750531) (xy 369.165424 -274.758656) (xy 369.214817 -274.774704)
			(xy 369.261091 -274.798282) (xy 369.303107 -274.828808) (xy 369.33983 -274.865531) (xy 369.370356 -274.907547)
			(xy 369.393934 -274.953821) (xy 369.409982 -275.003214) (xy 369.418107 -275.054509) (xy 369.418616 -275.080476)
			(xy 369.418107 -275.106443) (xy 369.418067 -275.106697) (xy 369.698271 -275.106697) (xy 369.698271 -275.054763)
			(xy 369.706396 -275.003468) (xy 369.722444 -274.954075) (xy 369.746022 -274.907801) (xy 369.776548 -274.865785)
			(xy 369.813271 -274.829062) (xy 369.855287 -274.798536) (xy 369.901561 -274.774958) (xy 369.950954 -274.75891)
			(xy 370.002249 -274.750785) (xy 370.054183 -274.750785) (xy 370.105478 -274.75891) (xy 370.154871 -274.774958)
			(xy 370.201145 -274.798536) (xy 370.243161 -274.829062) (xy 370.279884 -274.865785) (xy 370.31041 -274.907801)
			(xy 370.333988 -274.954075) (xy 370.350036 -275.003468) (xy 370.358161 -275.054763) (xy 370.35867 -275.08073)
			(xy 370.358161 -275.106697) (xy 370.638071 -275.106697) (xy 370.638071 -275.054763) (xy 370.646196 -275.003468)
			(xy 370.662244 -274.954075) (xy 370.685822 -274.907801) (xy 370.716348 -274.865785) (xy 370.753071 -274.829062)
			(xy 370.795087 -274.798536) (xy 370.841361 -274.774958) (xy 370.890754 -274.75891) (xy 370.942049 -274.750785)
			(xy 370.993983 -274.750785) (xy 371.045278 -274.75891) (xy 371.094671 -274.774958) (xy 371.140945 -274.798536)
			(xy 371.182961 -274.829062) (xy 371.219684 -274.865785) (xy 371.25021 -274.907801) (xy 371.273788 -274.954075)
			(xy 371.289836 -275.003468) (xy 371.297961 -275.054763) (xy 371.29847 -275.08073) (xy 371.297961 -275.106697)
			(xy 371.577871 -275.106697) (xy 371.577871 -275.054763) (xy 371.585996 -275.003468) (xy 371.602044 -274.954075)
			(xy 371.625622 -274.907801) (xy 371.656148 -274.865785) (xy 371.692871 -274.829062) (xy 371.734887 -274.798536)
			(xy 371.781161 -274.774958) (xy 371.830554 -274.75891) (xy 371.881849 -274.750785) (xy 371.933783 -274.750785)
			(xy 371.985078 -274.75891) (xy 372.034471 -274.774958) (xy 372.080745 -274.798536) (xy 372.122761 -274.829062)
			(xy 372.159484 -274.865785) (xy 372.19001 -274.907801) (xy 372.213588 -274.954075) (xy 372.229636 -275.003468)
			(xy 372.237761 -275.054763) (xy 372.23827 -275.08073) (xy 372.237761 -275.106697) (xy 372.517671 -275.106697)
			(xy 372.517671 -275.054763) (xy 372.525796 -275.003468) (xy 372.541844 -274.954075) (xy 372.565422 -274.907801)
			(xy 372.595948 -274.865785) (xy 372.632671 -274.829062) (xy 372.674687 -274.798536) (xy 372.720961 -274.774958)
			(xy 372.770354 -274.75891) (xy 372.821649 -274.750785) (xy 372.873583 -274.750785) (xy 372.924878 -274.75891)
			(xy 372.974271 -274.774958) (xy 373.020545 -274.798536) (xy 373.062561 -274.829062) (xy 373.099284 -274.865785)
			(xy 373.12981 -274.907801) (xy 373.153388 -274.954075) (xy 373.169436 -275.003468) (xy 373.177561 -275.054763)
			(xy 373.17807 -275.08073) (xy 373.177561 -275.106697) (xy 373.457471 -275.106697) (xy 373.457471 -275.054763)
			(xy 373.465596 -275.003468) (xy 373.481644 -274.954075) (xy 373.505222 -274.907801) (xy 373.535748 -274.865785)
			(xy 373.572471 -274.829062) (xy 373.614487 -274.798536) (xy 373.660761 -274.774958) (xy 373.710154 -274.75891)
			(xy 373.761449 -274.750785) (xy 373.813383 -274.750785) (xy 373.864678 -274.75891) (xy 373.914071 -274.774958)
			(xy 373.960345 -274.798536) (xy 374.002361 -274.829062) (xy 374.039084 -274.865785) (xy 374.06961 -274.907801)
			(xy 374.093188 -274.954075) (xy 374.109236 -275.003468) (xy 374.117361 -275.054763) (xy 374.11787 -275.08073)
			(xy 374.117361 -275.106697) (xy 374.397017 -275.106697) (xy 374.397017 -275.054763) (xy 374.405142 -275.003468)
			(xy 374.42119 -274.954075) (xy 374.444768 -274.907801) (xy 374.475294 -274.865785) (xy 374.512017 -274.829062)
			(xy 374.554033 -274.798536) (xy 374.600307 -274.774958) (xy 374.6497 -274.75891) (xy 374.700995 -274.750785)
			(xy 374.752929 -274.750785) (xy 374.804224 -274.75891) (xy 374.853617 -274.774958) (xy 374.899891 -274.798536)
			(xy 374.941907 -274.829062) (xy 374.97863 -274.865785) (xy 375.009156 -274.907801) (xy 375.032734 -274.954075)
			(xy 375.048782 -275.003468) (xy 375.056907 -275.054763) (xy 375.057416 -275.08073) (xy 375.056907 -275.106697)
			(xy 375.337071 -275.106697) (xy 375.337071 -275.054763) (xy 375.345196 -275.003468) (xy 375.361244 -274.954075)
			(xy 375.384822 -274.907801) (xy 375.415348 -274.865785) (xy 375.452071 -274.829062) (xy 375.494087 -274.798536)
			(xy 375.540361 -274.774958) (xy 375.589754 -274.75891) (xy 375.641049 -274.750785) (xy 375.692983 -274.750785)
			(xy 375.744278 -274.75891) (xy 375.793671 -274.774958) (xy 375.839945 -274.798536) (xy 375.881961 -274.829062)
			(xy 375.918684 -274.865785) (xy 375.94921 -274.907801) (xy 375.972788 -274.954075) (xy 375.988836 -275.003468)
			(xy 375.996961 -275.054763) (xy 375.99747 -275.08073) (xy 375.996961 -275.106697) (xy 376.276871 -275.106697)
			(xy 376.276871 -275.054763) (xy 376.284996 -275.003468) (xy 376.301044 -274.954075) (xy 376.324622 -274.907801)
			(xy 376.355148 -274.865785) (xy 376.391871 -274.829062) (xy 376.433887 -274.798536) (xy 376.480161 -274.774958)
			(xy 376.529554 -274.75891) (xy 376.580849 -274.750785) (xy 376.632783 -274.750785) (xy 376.684078 -274.75891)
			(xy 376.733471 -274.774958) (xy 376.779745 -274.798536) (xy 376.821761 -274.829062) (xy 376.858484 -274.865785)
			(xy 376.88901 -274.907801) (xy 376.912588 -274.954075) (xy 376.928636 -275.003468) (xy 376.936761 -275.054763)
			(xy 376.93727 -275.08073) (xy 376.936761 -275.106697) (xy 376.928636 -275.157992) (xy 376.912588 -275.207385)
			(xy 376.88901 -275.253659) (xy 376.858484 -275.295675) (xy 376.821761 -275.332398) (xy 376.779745 -275.362924)
			(xy 376.733471 -275.386502) (xy 376.684078 -275.40255) (xy 376.632783 -275.410675) (xy 376.580849 -275.410675)
			(xy 376.529554 -275.40255) (xy 376.480161 -275.386502) (xy 376.433887 -275.362924) (xy 376.391871 -275.332398)
			(xy 376.355148 -275.295675) (xy 376.324622 -275.253659) (xy 376.301044 -275.207385) (xy 376.284996 -275.157992)
			(xy 376.276871 -275.106697) (xy 375.996961 -275.106697) (xy 375.988836 -275.157992) (xy 375.972788 -275.207385)
			(xy 375.94921 -275.253659) (xy 375.918684 -275.295675) (xy 375.881961 -275.332398) (xy 375.839945 -275.362924)
			(xy 375.793671 -275.386502) (xy 375.744278 -275.40255) (xy 375.692983 -275.410675) (xy 375.641049 -275.410675)
			(xy 375.589754 -275.40255) (xy 375.540361 -275.386502) (xy 375.494087 -275.362924) (xy 375.452071 -275.332398)
			(xy 375.415348 -275.295675) (xy 375.384822 -275.253659) (xy 375.361244 -275.207385) (xy 375.345196 -275.157992)
			(xy 375.337071 -275.106697) (xy 375.056907 -275.106697) (xy 375.048782 -275.157992) (xy 375.032734 -275.207385)
			(xy 375.009156 -275.253659) (xy 374.97863 -275.295675) (xy 374.941907 -275.332398) (xy 374.899891 -275.362924)
			(xy 374.853617 -275.386502) (xy 374.804224 -275.40255) (xy 374.752929 -275.410675) (xy 374.700995 -275.410675)
			(xy 374.6497 -275.40255) (xy 374.600307 -275.386502) (xy 374.554033 -275.362924) (xy 374.512017 -275.332398)
			(xy 374.475294 -275.295675) (xy 374.444768 -275.253659) (xy 374.42119 -275.207385) (xy 374.405142 -275.157992)
			(xy 374.397017 -275.106697) (xy 374.117361 -275.106697) (xy 374.109236 -275.157992) (xy 374.093188 -275.207385)
			(xy 374.06961 -275.253659) (xy 374.039084 -275.295675) (xy 374.002361 -275.332398) (xy 373.960345 -275.362924)
			(xy 373.914071 -275.386502) (xy 373.864678 -275.40255) (xy 373.813383 -275.410675) (xy 373.761449 -275.410675)
			(xy 373.710154 -275.40255) (xy 373.660761 -275.386502) (xy 373.614487 -275.362924) (xy 373.572471 -275.332398)
			(xy 373.535748 -275.295675) (xy 373.505222 -275.253659) (xy 373.481644 -275.207385) (xy 373.465596 -275.157992)
			(xy 373.457471 -275.106697) (xy 373.177561 -275.106697) (xy 373.169436 -275.157992) (xy 373.153388 -275.207385)
			(xy 373.12981 -275.253659) (xy 373.099284 -275.295675) (xy 373.062561 -275.332398) (xy 373.020545 -275.362924)
			(xy 372.974271 -275.386502) (xy 372.924878 -275.40255) (xy 372.873583 -275.410675) (xy 372.821649 -275.410675)
			(xy 372.770354 -275.40255) (xy 372.720961 -275.386502) (xy 372.674687 -275.362924) (xy 372.632671 -275.332398)
			(xy 372.595948 -275.295675) (xy 372.565422 -275.253659) (xy 372.541844 -275.207385) (xy 372.525796 -275.157992)
			(xy 372.517671 -275.106697) (xy 372.237761 -275.106697) (xy 372.229636 -275.157992) (xy 372.213588 -275.207385)
			(xy 372.19001 -275.253659) (xy 372.159484 -275.295675) (xy 372.122761 -275.332398) (xy 372.080745 -275.362924)
			(xy 372.034471 -275.386502) (xy 371.985078 -275.40255) (xy 371.933783 -275.410675) (xy 371.881849 -275.410675)
			(xy 371.830554 -275.40255) (xy 371.781161 -275.386502) (xy 371.734887 -275.362924) (xy 371.692871 -275.332398)
			(xy 371.656148 -275.295675) (xy 371.625622 -275.253659) (xy 371.602044 -275.207385) (xy 371.585996 -275.157992)
			(xy 371.577871 -275.106697) (xy 371.297961 -275.106697) (xy 371.289836 -275.157992) (xy 371.273788 -275.207385)
			(xy 371.25021 -275.253659) (xy 371.219684 -275.295675) (xy 371.182961 -275.332398) (xy 371.140945 -275.362924)
			(xy 371.094671 -275.386502) (xy 371.045278 -275.40255) (xy 370.993983 -275.410675) (xy 370.942049 -275.410675)
			(xy 370.890754 -275.40255) (xy 370.841361 -275.386502) (xy 370.795087 -275.362924) (xy 370.753071 -275.332398)
			(xy 370.716348 -275.295675) (xy 370.685822 -275.253659) (xy 370.662244 -275.207385) (xy 370.646196 -275.157992)
			(xy 370.638071 -275.106697) (xy 370.358161 -275.106697) (xy 370.350036 -275.157992) (xy 370.333988 -275.207385)
			(xy 370.31041 -275.253659) (xy 370.279884 -275.295675) (xy 370.243161 -275.332398) (xy 370.201145 -275.362924)
			(xy 370.154871 -275.386502) (xy 370.105478 -275.40255) (xy 370.054183 -275.410675) (xy 370.002249 -275.410675)
			(xy 369.950954 -275.40255) (xy 369.901561 -275.386502) (xy 369.855287 -275.362924) (xy 369.813271 -275.332398)
			(xy 369.776548 -275.295675) (xy 369.746022 -275.253659) (xy 369.722444 -275.207385) (xy 369.706396 -275.157992)
			(xy 369.698271 -275.106697) (xy 369.418067 -275.106697) (xy 369.409982 -275.157738) (xy 369.393934 -275.207131)
			(xy 369.370356 -275.253405) (xy 369.33983 -275.295421) (xy 369.303107 -275.332144) (xy 369.261091 -275.36267)
			(xy 369.214817 -275.386248) (xy 369.165424 -275.402296) (xy 369.114129 -275.410421) (xy 369.062195 -275.410421)
			(xy 369.0109 -275.402296) (xy 368.961507 -275.386248) (xy 368.915233 -275.36267) (xy 368.873217 -275.332144)
			(xy 368.836494 -275.295421) (xy 368.805968 -275.253405) (xy 368.78239 -275.207131) (xy 368.766342 -275.157738)
			(xy 368.758217 -275.106443) (xy 368.478566 -275.106443) (xy 368.478561 -275.106697) (xy 368.470436 -275.157992)
			(xy 368.454388 -275.207385) (xy 368.43081 -275.253659) (xy 368.400284 -275.295675) (xy 368.363561 -275.332398)
			(xy 368.321545 -275.362924) (xy 368.275271 -275.386502) (xy 368.225878 -275.40255) (xy 368.174583 -275.410675)
			(xy 368.122649 -275.410675) (xy 368.071354 -275.40255) (xy 368.021961 -275.386502) (xy 367.975687 -275.362924)
			(xy 367.933671 -275.332398) (xy 367.896948 -275.295675) (xy 367.866422 -275.253659) (xy 367.842844 -275.207385)
			(xy 367.826796 -275.157992) (xy 367.818671 -275.106697) (xy 365.892842 -275.106697) (xy 365.892842 -275.576284)
			(xy 365.924338 -275.588984) (xy 365.94777 -275.599103) (xy 365.991454 -275.625495) (xy 366.030561 -275.658291)
			(xy 366.06416 -275.69671) (xy 366.091451 -275.739839) (xy 366.111786 -275.786651) (xy 366.118648 -275.811234)
			(xy 366.12195 -275.824442) (xy 366.235996 -275.938488) (xy 366.246641 -275.94848) (xy 366.272259 -275.962462)
			(xy 366.300785 -275.968632) (xy 366.329891 -275.966485) (xy 366.357203 -275.956198) (xy 366.380492 -275.93861)
			(xy 366.39786 -275.915155) (xy 366.407889 -275.887747) (xy 366.409224 -275.87321) (xy 366.411299 -275.848408)
			(xy 366.421961 -275.799794) (xy 366.439791 -275.753328) (xy 366.464388 -275.710062) (xy 366.495194 -275.670973)
			(xy 366.531513 -275.636945) (xy 366.572524 -275.608748) (xy 366.617299 -275.587019) (xy 366.664827 -275.57225)
			(xy 366.714031 -275.564775) (xy 366.738916 -275.564346) (xy 366.764882 -275.564856) (xy 366.816175 -275.572983)
			(xy 366.865566 -275.589033) (xy 366.911838 -275.612611) (xy 366.953851 -275.643138) (xy 366.990572 -275.679861)
			(xy 367.021097 -275.721876) (xy 367.044673 -275.768149) (xy 367.060721 -275.81754) (xy 367.068845 -275.868834)
			(xy 367.06937 -275.8948) (xy 367.068919 -275.919684) (xy 367.068793 -275.920513) (xy 367.348771 -275.920513)
			(xy 367.348771 -275.868579) (xy 367.356896 -275.817284) (xy 367.372944 -275.767891) (xy 367.396522 -275.721617)
			(xy 367.427048 -275.679601) (xy 367.463771 -275.642878) (xy 367.505787 -275.612352) (xy 367.552061 -275.588774)
			(xy 367.601454 -275.572726) (xy 367.652749 -275.564601) (xy 367.704683 -275.564601) (xy 367.755978 -275.572726)
			(xy 367.805371 -275.588774) (xy 367.851645 -275.612352) (xy 367.893661 -275.642878) (xy 367.930384 -275.679601)
			(xy 367.96091 -275.721617) (xy 367.984488 -275.767891) (xy 368.000536 -275.817284) (xy 368.008661 -275.868579)
			(xy 368.00917 -275.894546) (xy 368.008661 -275.920513) (xy 368.288571 -275.920513) (xy 368.288571 -275.868579)
			(xy 368.296696 -275.817284) (xy 368.312744 -275.767891) (xy 368.336322 -275.721617) (xy 368.366848 -275.679601)
			(xy 368.403571 -275.642878) (xy 368.445587 -275.612352) (xy 368.491861 -275.588774) (xy 368.541254 -275.572726)
			(xy 368.592549 -275.564601) (xy 368.644483 -275.564601) (xy 368.695778 -275.572726) (xy 368.745171 -275.588774)
			(xy 368.791445 -275.612352) (xy 368.833461 -275.642878) (xy 368.870184 -275.679601) (xy 368.90071 -275.721617)
			(xy 368.924288 -275.767891) (xy 368.940336 -275.817284) (xy 368.948461 -275.868579) (xy 368.94897 -275.894546)
			(xy 368.948461 -275.920513) (xy 369.228371 -275.920513) (xy 369.228371 -275.868579) (xy 369.236496 -275.817284)
			(xy 369.252544 -275.767891) (xy 369.276122 -275.721617) (xy 369.306648 -275.679601) (xy 369.343371 -275.642878)
			(xy 369.385387 -275.612352) (xy 369.431661 -275.588774) (xy 369.481054 -275.572726) (xy 369.532349 -275.564601)
			(xy 369.584283 -275.564601) (xy 369.635578 -275.572726) (xy 369.684971 -275.588774) (xy 369.731245 -275.612352)
			(xy 369.773261 -275.642878) (xy 369.809984 -275.679601) (xy 369.84051 -275.721617) (xy 369.864088 -275.767891)
			(xy 369.880136 -275.817284) (xy 369.888261 -275.868579) (xy 369.88877 -275.894546) (xy 369.888261 -275.920513)
			(xy 369.888221 -275.920767) (xy 370.168171 -275.920767) (xy 370.168171 -275.868833) (xy 370.176296 -275.817538)
			(xy 370.192344 -275.768145) (xy 370.215922 -275.721871) (xy 370.246448 -275.679855) (xy 370.283171 -275.643132)
			(xy 370.325187 -275.612606) (xy 370.371461 -275.589028) (xy 370.420854 -275.57298) (xy 370.472149 -275.564855)
			(xy 370.524083 -275.564855) (xy 370.575378 -275.57298) (xy 370.624771 -275.589028) (xy 370.671045 -275.612606)
			(xy 370.713061 -275.643132) (xy 370.749784 -275.679855) (xy 370.78031 -275.721871) (xy 370.803888 -275.768145)
			(xy 370.819936 -275.817538) (xy 370.828061 -275.868833) (xy 370.82857 -275.8948) (xy 370.828061 -275.920767)
			(xy 371.107717 -275.920767) (xy 371.107717 -275.868833) (xy 371.115842 -275.817538) (xy 371.13189 -275.768145)
			(xy 371.155468 -275.721871) (xy 371.185994 -275.679855) (xy 371.222717 -275.643132) (xy 371.264733 -275.612606)
			(xy 371.311007 -275.589028) (xy 371.3604 -275.57298) (xy 371.411695 -275.564855) (xy 371.463629 -275.564855)
			(xy 371.514924 -275.57298) (xy 371.564317 -275.589028) (xy 371.610591 -275.612606) (xy 371.652607 -275.643132)
			(xy 371.68933 -275.679855) (xy 371.719856 -275.721871) (xy 371.743434 -275.768145) (xy 371.759482 -275.817538)
			(xy 371.767607 -275.868833) (xy 371.768116 -275.8948) (xy 371.767607 -275.920767) (xy 372.047517 -275.920767)
			(xy 372.047517 -275.868833) (xy 372.055642 -275.817538) (xy 372.07169 -275.768145) (xy 372.095268 -275.721871)
			(xy 372.125794 -275.679855) (xy 372.162517 -275.643132) (xy 372.204533 -275.612606) (xy 372.250807 -275.589028)
			(xy 372.3002 -275.57298) (xy 372.351495 -275.564855) (xy 372.403429 -275.564855) (xy 372.454724 -275.57298)
			(xy 372.504117 -275.589028) (xy 372.550391 -275.612606) (xy 372.592407 -275.643132) (xy 372.62913 -275.679855)
			(xy 372.659656 -275.721871) (xy 372.683234 -275.768145) (xy 372.699282 -275.817538) (xy 372.707407 -275.868833)
			(xy 372.707916 -275.8948) (xy 372.707407 -275.920767) (xy 372.987317 -275.920767) (xy 372.987317 -275.868833)
			(xy 372.995442 -275.817538) (xy 373.01149 -275.768145) (xy 373.035068 -275.721871) (xy 373.065594 -275.679855)
			(xy 373.102317 -275.643132) (xy 373.144333 -275.612606) (xy 373.190607 -275.589028) (xy 373.24 -275.57298)
			(xy 373.291295 -275.564855) (xy 373.343229 -275.564855) (xy 373.394524 -275.57298) (xy 373.443917 -275.589028)
			(xy 373.490191 -275.612606) (xy 373.532207 -275.643132) (xy 373.56893 -275.679855) (xy 373.599456 -275.721871)
			(xy 373.623034 -275.768145) (xy 373.639082 -275.817538) (xy 373.647207 -275.868833) (xy 373.647716 -275.8948)
			(xy 373.647207 -275.920767) (xy 373.927117 -275.920767) (xy 373.927117 -275.868833) (xy 373.935242 -275.817538)
			(xy 373.95129 -275.768145) (xy 373.974868 -275.721871) (xy 374.005394 -275.679855) (xy 374.042117 -275.643132)
			(xy 374.084133 -275.612606) (xy 374.130407 -275.589028) (xy 374.1798 -275.57298) (xy 374.231095 -275.564855)
			(xy 374.283029 -275.564855) (xy 374.334324 -275.57298) (xy 374.383717 -275.589028) (xy 374.429991 -275.612606)
			(xy 374.472007 -275.643132) (xy 374.50873 -275.679855) (xy 374.539256 -275.721871) (xy 374.562834 -275.768145)
			(xy 374.578882 -275.817538) (xy 374.587007 -275.868833) (xy 374.587516 -275.8948) (xy 374.587007 -275.920767)
			(xy 374.866917 -275.920767) (xy 374.866917 -275.868833) (xy 374.875042 -275.817538) (xy 374.89109 -275.768145)
			(xy 374.914668 -275.721871) (xy 374.945194 -275.679855) (xy 374.981917 -275.643132) (xy 375.023933 -275.612606)
			(xy 375.070207 -275.589028) (xy 375.1196 -275.57298) (xy 375.170895 -275.564855) (xy 375.222829 -275.564855)
			(xy 375.274124 -275.57298) (xy 375.323517 -275.589028) (xy 375.369791 -275.612606) (xy 375.411807 -275.643132)
			(xy 375.44853 -275.679855) (xy 375.479056 -275.721871) (xy 375.502634 -275.768145) (xy 375.518682 -275.817538)
			(xy 375.526807 -275.868833) (xy 375.527316 -275.8948) (xy 375.526807 -275.920767) (xy 375.806717 -275.920767)
			(xy 375.806717 -275.868833) (xy 375.814842 -275.817538) (xy 375.83089 -275.768145) (xy 375.854468 -275.721871)
			(xy 375.884994 -275.679855) (xy 375.921717 -275.643132) (xy 375.963733 -275.612606) (xy 376.010007 -275.589028)
			(xy 376.0594 -275.57298) (xy 376.110695 -275.564855) (xy 376.162629 -275.564855) (xy 376.213924 -275.57298)
			(xy 376.263317 -275.589028) (xy 376.309591 -275.612606) (xy 376.351607 -275.643132) (xy 376.38833 -275.679855)
			(xy 376.418856 -275.721871) (xy 376.442434 -275.768145) (xy 376.458482 -275.817538) (xy 376.466607 -275.868833)
			(xy 376.467116 -275.8948) (xy 376.466607 -275.920767) (xy 376.458482 -275.972062) (xy 376.442434 -276.021455)
			(xy 376.418856 -276.067729) (xy 376.38833 -276.109745) (xy 376.351607 -276.146468) (xy 376.309591 -276.176994)
			(xy 376.263317 -276.200572) (xy 376.213924 -276.21662) (xy 376.162629 -276.224745) (xy 376.110695 -276.224745)
			(xy 376.0594 -276.21662) (xy 376.010007 -276.200572) (xy 375.963733 -276.176994) (xy 375.921717 -276.146468)
			(xy 375.884994 -276.109745) (xy 375.854468 -276.067729) (xy 375.83089 -276.021455) (xy 375.814842 -275.972062)
			(xy 375.806717 -275.920767) (xy 375.526807 -275.920767) (xy 375.518682 -275.972062) (xy 375.502634 -276.021455)
			(xy 375.479056 -276.067729) (xy 375.44853 -276.109745) (xy 375.411807 -276.146468) (xy 375.369791 -276.176994)
			(xy 375.323517 -276.200572) (xy 375.274124 -276.21662) (xy 375.222829 -276.224745) (xy 375.170895 -276.224745)
			(xy 375.1196 -276.21662) (xy 375.070207 -276.200572) (xy 375.023933 -276.176994) (xy 374.981917 -276.146468)
			(xy 374.945194 -276.109745) (xy 374.914668 -276.067729) (xy 374.89109 -276.021455) (xy 374.875042 -275.972062)
			(xy 374.866917 -275.920767) (xy 374.587007 -275.920767) (xy 374.578882 -275.972062) (xy 374.562834 -276.021455)
			(xy 374.539256 -276.067729) (xy 374.50873 -276.109745) (xy 374.472007 -276.146468) (xy 374.429991 -276.176994)
			(xy 374.383717 -276.200572) (xy 374.334324 -276.21662) (xy 374.283029 -276.224745) (xy 374.231095 -276.224745)
			(xy 374.1798 -276.21662) (xy 374.130407 -276.200572) (xy 374.084133 -276.176994) (xy 374.042117 -276.146468)
			(xy 374.005394 -276.109745) (xy 373.974868 -276.067729) (xy 373.95129 -276.021455) (xy 373.935242 -275.972062)
			(xy 373.927117 -275.920767) (xy 373.647207 -275.920767) (xy 373.639082 -275.972062) (xy 373.623034 -276.021455)
			(xy 373.599456 -276.067729) (xy 373.56893 -276.109745) (xy 373.532207 -276.146468) (xy 373.490191 -276.176994)
			(xy 373.443917 -276.200572) (xy 373.394524 -276.21662) (xy 373.343229 -276.224745) (xy 373.291295 -276.224745)
			(xy 373.24 -276.21662) (xy 373.190607 -276.200572) (xy 373.144333 -276.176994) (xy 373.102317 -276.146468)
			(xy 373.065594 -276.109745) (xy 373.035068 -276.067729) (xy 373.01149 -276.021455) (xy 372.995442 -275.972062)
			(xy 372.987317 -275.920767) (xy 372.707407 -275.920767) (xy 372.699282 -275.972062) (xy 372.683234 -276.021455)
			(xy 372.659656 -276.067729) (xy 372.62913 -276.109745) (xy 372.592407 -276.146468) (xy 372.550391 -276.176994)
			(xy 372.504117 -276.200572) (xy 372.454724 -276.21662) (xy 372.403429 -276.224745) (xy 372.351495 -276.224745)
			(xy 372.3002 -276.21662) (xy 372.250807 -276.200572) (xy 372.204533 -276.176994) (xy 372.162517 -276.146468)
			(xy 372.125794 -276.109745) (xy 372.095268 -276.067729) (xy 372.07169 -276.021455) (xy 372.055642 -275.972062)
			(xy 372.047517 -275.920767) (xy 371.767607 -275.920767) (xy 371.759482 -275.972062) (xy 371.743434 -276.021455)
			(xy 371.719856 -276.067729) (xy 371.68933 -276.109745) (xy 371.652607 -276.146468) (xy 371.610591 -276.176994)
			(xy 371.564317 -276.200572) (xy 371.514924 -276.21662) (xy 371.463629 -276.224745) (xy 371.411695 -276.224745)
			(xy 371.3604 -276.21662) (xy 371.311007 -276.200572) (xy 371.264733 -276.176994) (xy 371.222717 -276.146468)
			(xy 371.185994 -276.109745) (xy 371.155468 -276.067729) (xy 371.13189 -276.021455) (xy 371.115842 -275.972062)
			(xy 371.107717 -275.920767) (xy 370.828061 -275.920767) (xy 370.819936 -275.972062) (xy 370.803888 -276.021455)
			(xy 370.78031 -276.067729) (xy 370.749784 -276.109745) (xy 370.713061 -276.146468) (xy 370.671045 -276.176994)
			(xy 370.624771 -276.200572) (xy 370.575378 -276.21662) (xy 370.524083 -276.224745) (xy 370.472149 -276.224745)
			(xy 370.420854 -276.21662) (xy 370.371461 -276.200572) (xy 370.325187 -276.176994) (xy 370.283171 -276.146468)
			(xy 370.246448 -276.109745) (xy 370.215922 -276.067729) (xy 370.192344 -276.021455) (xy 370.176296 -275.972062)
			(xy 370.168171 -275.920767) (xy 369.888221 -275.920767) (xy 369.880136 -275.971808) (xy 369.864088 -276.021201)
			(xy 369.84051 -276.067475) (xy 369.809984 -276.109491) (xy 369.773261 -276.146214) (xy 369.731245 -276.17674)
			(xy 369.684971 -276.200318) (xy 369.635578 -276.216366) (xy 369.584283 -276.224491) (xy 369.532349 -276.224491)
			(xy 369.481054 -276.216366) (xy 369.431661 -276.200318) (xy 369.385387 -276.17674) (xy 369.343371 -276.146214)
			(xy 369.306648 -276.109491) (xy 369.276122 -276.067475) (xy 369.252544 -276.021201) (xy 369.236496 -275.971808)
			(xy 369.228371 -275.920513) (xy 368.948461 -275.920513) (xy 368.940336 -275.971808) (xy 368.924288 -276.021201)
			(xy 368.90071 -276.067475) (xy 368.870184 -276.109491) (xy 368.833461 -276.146214) (xy 368.791445 -276.17674)
			(xy 368.745171 -276.200318) (xy 368.695778 -276.216366) (xy 368.644483 -276.224491) (xy 368.592549 -276.224491)
			(xy 368.541254 -276.216366) (xy 368.491861 -276.200318) (xy 368.445587 -276.17674) (xy 368.403571 -276.146214)
			(xy 368.366848 -276.109491) (xy 368.336322 -276.067475) (xy 368.312744 -276.021201) (xy 368.296696 -275.971808)
			(xy 368.288571 -275.920513) (xy 368.008661 -275.920513) (xy 368.000536 -275.971808) (xy 367.984488 -276.021201)
			(xy 367.96091 -276.067475) (xy 367.930384 -276.109491) (xy 367.893661 -276.146214) (xy 367.851645 -276.17674)
			(xy 367.805371 -276.200318) (xy 367.755978 -276.216366) (xy 367.704683 -276.224491) (xy 367.652749 -276.224491)
			(xy 367.601454 -276.216366) (xy 367.552061 -276.200318) (xy 367.505787 -276.17674) (xy 367.463771 -276.146214)
			(xy 367.427048 -276.109491) (xy 367.396522 -276.067475) (xy 367.372944 -276.021201) (xy 367.356896 -275.971808)
			(xy 367.348771 -275.920513) (xy 367.068793 -275.920513) (xy 367.061454 -275.96889) (xy 367.046692 -276.016419)
			(xy 367.024969 -276.061196) (xy 366.996774 -276.102208) (xy 366.962747 -276.138527) (xy 366.923657 -276.169331)
			(xy 366.880389 -276.193923) (xy 366.833922 -276.211747) (xy 366.785307 -276.222399) (xy 366.760506 -276.224492)
			(xy 366.745996 -276.225921) (xy 366.718638 -276.235972) (xy 366.695229 -276.253336) (xy 366.677673 -276.276602)
			(xy 366.667398 -276.303876) (xy 366.66524 -276.332942) (xy 366.671374 -276.361435) (xy 366.685301 -276.387039)
			(xy 366.695228 -276.39772) (xy 366.803178 -276.50567) (xy 366.8135 -276.515359) (xy 366.838218 -276.529136)
			(xy 366.865769 -276.535601) (xy 366.894036 -276.534257) (xy 366.920849 -276.525208) (xy 366.944149 -276.509149)
			(xy 366.953546 -276.498558) (xy 366.969309 -276.480066) (xy 367.005339 -276.447465) (xy 367.045759 -276.420498)
			(xy 367.089696 -276.399748) (xy 367.1362 -276.385663) (xy 367.184267 -276.378549) (xy 367.208562 -276.378162)
			(xy 367.234533 -276.378642) (xy 367.285836 -276.386762) (xy 367.335236 -276.402809) (xy 367.381518 -276.426387)
			(xy 367.423541 -276.456915) (xy 367.46027 -276.493642) (xy 367.490801 -276.535663) (xy 367.514382 -276.581943)
			(xy 367.530432 -276.631343) (xy 367.538556 -276.682645) (xy 367.539016 -276.708616) (xy 367.538585 -276.732908)
			(xy 367.538374 -276.734329) (xy 367.818417 -276.734329) (xy 367.818417 -276.682395) (xy 367.826542 -276.6311)
			(xy 367.84259 -276.581707) (xy 367.866168 -276.535433) (xy 367.896694 -276.493417) (xy 367.933417 -276.456694)
			(xy 367.975433 -276.426168) (xy 368.021707 -276.40259) (xy 368.0711 -276.386542) (xy 368.122395 -276.378417)
			(xy 368.174329 -276.378417) (xy 368.225624 -276.386542) (xy 368.275017 -276.40259) (xy 368.321291 -276.426168)
			(xy 368.363307 -276.456694) (xy 368.40003 -276.493417) (xy 368.430556 -276.535433) (xy 368.454134 -276.581707)
			(xy 368.470182 -276.6311) (xy 368.478307 -276.682395) (xy 368.478816 -276.708362) (xy 368.478307 -276.734329)
			(xy 368.478267 -276.734583) (xy 368.758471 -276.734583) (xy 368.758471 -276.682649) (xy 368.766596 -276.631354)
			(xy 368.782644 -276.581961) (xy 368.806222 -276.535687) (xy 368.836748 -276.493671) (xy 368.873471 -276.456948)
			(xy 368.915487 -276.426422) (xy 368.961761 -276.402844) (xy 369.011154 -276.386796) (xy 369.062449 -276.378671)
			(xy 369.114383 -276.378671) (xy 369.165678 -276.386796) (xy 369.215071 -276.402844) (xy 369.261345 -276.426422)
			(xy 369.303361 -276.456948) (xy 369.340084 -276.493671) (xy 369.37061 -276.535687) (xy 369.394188 -276.581961)
			(xy 369.410236 -276.631354) (xy 369.418361 -276.682649) (xy 369.41887 -276.708616) (xy 369.418361 -276.734583)
			(xy 370.638071 -276.734583) (xy 370.638071 -276.682649) (xy 370.646196 -276.631354) (xy 370.662244 -276.581961)
			(xy 370.685822 -276.535687) (xy 370.716348 -276.493671) (xy 370.753071 -276.456948) (xy 370.795087 -276.426422)
			(xy 370.841361 -276.402844) (xy 370.890754 -276.386796) (xy 370.942049 -276.378671) (xy 370.993983 -276.378671)
			(xy 371.045278 -276.386796) (xy 371.094671 -276.402844) (xy 371.140945 -276.426422) (xy 371.182961 -276.456948)
			(xy 371.219684 -276.493671) (xy 371.25021 -276.535687) (xy 371.273788 -276.581961) (xy 371.289836 -276.631354)
			(xy 371.297961 -276.682649) (xy 371.29847 -276.708616) (xy 371.297961 -276.734583) (xy 371.577871 -276.734583)
			(xy 371.577871 -276.682649) (xy 371.585996 -276.631354) (xy 371.602044 -276.581961) (xy 371.625622 -276.535687)
			(xy 371.656148 -276.493671) (xy 371.692871 -276.456948) (xy 371.734887 -276.426422) (xy 371.781161 -276.402844)
			(xy 371.830554 -276.386796) (xy 371.881849 -276.378671) (xy 371.933783 -276.378671) (xy 371.985078 -276.386796)
			(xy 372.034471 -276.402844) (xy 372.080745 -276.426422) (xy 372.122761 -276.456948) (xy 372.159484 -276.493671)
			(xy 372.19001 -276.535687) (xy 372.213588 -276.581961) (xy 372.229636 -276.631354) (xy 372.237761 -276.682649)
			(xy 372.23827 -276.708616) (xy 372.237761 -276.734583) (xy 372.517671 -276.734583) (xy 372.517671 -276.682649)
			(xy 372.525796 -276.631354) (xy 372.541844 -276.581961) (xy 372.565422 -276.535687) (xy 372.595948 -276.493671)
			(xy 372.632671 -276.456948) (xy 372.674687 -276.426422) (xy 372.720961 -276.402844) (xy 372.770354 -276.386796)
			(xy 372.821649 -276.378671) (xy 372.873583 -276.378671) (xy 372.924878 -276.386796) (xy 372.974271 -276.402844)
			(xy 373.020545 -276.426422) (xy 373.062561 -276.456948) (xy 373.099284 -276.493671) (xy 373.12981 -276.535687)
			(xy 373.153388 -276.581961) (xy 373.169436 -276.631354) (xy 373.177561 -276.682649) (xy 373.17807 -276.708616)
			(xy 373.177561 -276.734583) (xy 373.457217 -276.734583) (xy 373.457217 -276.682649) (xy 373.465342 -276.631354)
			(xy 373.48139 -276.581961) (xy 373.504968 -276.535687) (xy 373.535494 -276.493671) (xy 373.572217 -276.456948)
			(xy 373.614233 -276.426422) (xy 373.660507 -276.402844) (xy 373.7099 -276.386796) (xy 373.761195 -276.378671)
			(xy 373.813129 -276.378671) (xy 373.864424 -276.386796) (xy 373.913817 -276.402844) (xy 373.960091 -276.426422)
			(xy 374.002107 -276.456948) (xy 374.03883 -276.493671) (xy 374.069356 -276.535687) (xy 374.092934 -276.581961)
			(xy 374.108982 -276.631354) (xy 374.117107 -276.682649) (xy 374.117616 -276.708616) (xy 374.117107 -276.734583)
			(xy 374.397271 -276.734583) (xy 374.397271 -276.682649) (xy 374.405396 -276.631354) (xy 374.421444 -276.581961)
			(xy 374.445022 -276.535687) (xy 374.475548 -276.493671) (xy 374.512271 -276.456948) (xy 374.554287 -276.426422)
			(xy 374.600561 -276.402844) (xy 374.649954 -276.386796) (xy 374.701249 -276.378671) (xy 374.753183 -276.378671)
			(xy 374.804478 -276.386796) (xy 374.853871 -276.402844) (xy 374.900145 -276.426422) (xy 374.942161 -276.456948)
			(xy 374.978884 -276.493671) (xy 375.00941 -276.535687) (xy 375.032988 -276.581961) (xy 375.049036 -276.631354)
			(xy 375.057161 -276.682649) (xy 375.05767 -276.708616) (xy 375.057161 -276.734583) (xy 375.337071 -276.734583)
			(xy 375.337071 -276.682649) (xy 375.345196 -276.631354) (xy 375.361244 -276.581961) (xy 375.384822 -276.535687)
			(xy 375.415348 -276.493671) (xy 375.452071 -276.456948) (xy 375.494087 -276.426422) (xy 375.540361 -276.402844)
			(xy 375.589754 -276.386796) (xy 375.641049 -276.378671) (xy 375.692983 -276.378671) (xy 375.744278 -276.386796)
			(xy 375.793671 -276.402844) (xy 375.839945 -276.426422) (xy 375.881961 -276.456948) (xy 375.918684 -276.493671)
			(xy 375.94921 -276.535687) (xy 375.972788 -276.581961) (xy 375.988836 -276.631354) (xy 375.996961 -276.682649)
			(xy 375.99747 -276.708616) (xy 375.996961 -276.734583) (xy 376.276871 -276.734583) (xy 376.276871 -276.682649)
			(xy 376.284996 -276.631354) (xy 376.301044 -276.581961) (xy 376.324622 -276.535687) (xy 376.355148 -276.493671)
			(xy 376.391871 -276.456948) (xy 376.433887 -276.426422) (xy 376.480161 -276.402844) (xy 376.529554 -276.386796)
			(xy 376.580849 -276.378671) (xy 376.632783 -276.378671) (xy 376.684078 -276.386796) (xy 376.733471 -276.402844)
			(xy 376.779745 -276.426422) (xy 376.821761 -276.456948) (xy 376.858484 -276.493671) (xy 376.88901 -276.535687)
			(xy 376.912588 -276.581961) (xy 376.928636 -276.631354) (xy 376.936761 -276.682649) (xy 376.93727 -276.708616)
			(xy 376.936761 -276.734583) (xy 376.928636 -276.785878) (xy 376.912588 -276.835271) (xy 376.88901 -276.881545)
			(xy 376.858484 -276.923561) (xy 376.821761 -276.960284) (xy 376.779745 -276.99081) (xy 376.733471 -277.014388)
			(xy 376.684078 -277.030436) (xy 376.632783 -277.038561) (xy 376.580849 -277.038561) (xy 376.529554 -277.030436)
			(xy 376.480161 -277.014388) (xy 376.433887 -276.99081) (xy 376.391871 -276.960284) (xy 376.355148 -276.923561)
			(xy 376.324622 -276.881545) (xy 376.301044 -276.835271) (xy 376.284996 -276.785878) (xy 376.276871 -276.734583)
			(xy 375.996961 -276.734583) (xy 375.988836 -276.785878) (xy 375.972788 -276.835271) (xy 375.94921 -276.881545)
			(xy 375.918684 -276.923561) (xy 375.881961 -276.960284) (xy 375.839945 -276.99081) (xy 375.793671 -277.014388)
			(xy 375.744278 -277.030436) (xy 375.692983 -277.038561) (xy 375.641049 -277.038561) (xy 375.589754 -277.030436)
			(xy 375.540361 -277.014388) (xy 375.494087 -276.99081) (xy 375.452071 -276.960284) (xy 375.415348 -276.923561)
			(xy 375.384822 -276.881545) (xy 375.361244 -276.835271) (xy 375.345196 -276.785878) (xy 375.337071 -276.734583)
			(xy 375.057161 -276.734583) (xy 375.049036 -276.785878) (xy 375.032988 -276.835271) (xy 375.00941 -276.881545)
			(xy 374.978884 -276.923561) (xy 374.942161 -276.960284) (xy 374.900145 -276.99081) (xy 374.853871 -277.014388)
			(xy 374.804478 -277.030436) (xy 374.753183 -277.038561) (xy 374.701249 -277.038561) (xy 374.649954 -277.030436)
			(xy 374.600561 -277.014388) (xy 374.554287 -276.99081) (xy 374.512271 -276.960284) (xy 374.475548 -276.923561)
			(xy 374.445022 -276.881545) (xy 374.421444 -276.835271) (xy 374.405396 -276.785878) (xy 374.397271 -276.734583)
			(xy 374.117107 -276.734583) (xy 374.108982 -276.785878) (xy 374.092934 -276.835271) (xy 374.069356 -276.881545)
			(xy 374.03883 -276.923561) (xy 374.002107 -276.960284) (xy 373.960091 -276.99081) (xy 373.913817 -277.014388)
			(xy 373.864424 -277.030436) (xy 373.813129 -277.038561) (xy 373.761195 -277.038561) (xy 373.7099 -277.030436)
			(xy 373.660507 -277.014388) (xy 373.614233 -276.99081) (xy 373.572217 -276.960284) (xy 373.535494 -276.923561)
			(xy 373.504968 -276.881545) (xy 373.48139 -276.835271) (xy 373.465342 -276.785878) (xy 373.457217 -276.734583)
			(xy 373.177561 -276.734583) (xy 373.169436 -276.785878) (xy 373.153388 -276.835271) (xy 373.12981 -276.881545)
			(xy 373.099284 -276.923561) (xy 373.062561 -276.960284) (xy 373.020545 -276.99081) (xy 372.974271 -277.014388)
			(xy 372.924878 -277.030436) (xy 372.873583 -277.038561) (xy 372.821649 -277.038561) (xy 372.770354 -277.030436)
			(xy 372.720961 -277.014388) (xy 372.674687 -276.99081) (xy 372.632671 -276.960284) (xy 372.595948 -276.923561)
			(xy 372.565422 -276.881545) (xy 372.541844 -276.835271) (xy 372.525796 -276.785878) (xy 372.517671 -276.734583)
			(xy 372.237761 -276.734583) (xy 372.229636 -276.785878) (xy 372.213588 -276.835271) (xy 372.19001 -276.881545)
			(xy 372.159484 -276.923561) (xy 372.122761 -276.960284) (xy 372.080745 -276.99081) (xy 372.034471 -277.014388)
			(xy 371.985078 -277.030436) (xy 371.933783 -277.038561) (xy 371.881849 -277.038561) (xy 371.830554 -277.030436)
			(xy 371.781161 -277.014388) (xy 371.734887 -276.99081) (xy 371.692871 -276.960284) (xy 371.656148 -276.923561)
			(xy 371.625622 -276.881545) (xy 371.602044 -276.835271) (xy 371.585996 -276.785878) (xy 371.577871 -276.734583)
			(xy 371.297961 -276.734583) (xy 371.289836 -276.785878) (xy 371.273788 -276.835271) (xy 371.25021 -276.881545)
			(xy 371.219684 -276.923561) (xy 371.182961 -276.960284) (xy 371.140945 -276.99081) (xy 371.094671 -277.014388)
			(xy 371.045278 -277.030436) (xy 370.993983 -277.038561) (xy 370.942049 -277.038561) (xy 370.890754 -277.030436)
			(xy 370.841361 -277.014388) (xy 370.795087 -276.99081) (xy 370.753071 -276.960284) (xy 370.716348 -276.923561)
			(xy 370.685822 -276.881545) (xy 370.662244 -276.835271) (xy 370.646196 -276.785878) (xy 370.638071 -276.734583)
			(xy 369.418361 -276.734583) (xy 369.410236 -276.785878) (xy 369.394188 -276.835271) (xy 369.37061 -276.881545)
			(xy 369.340084 -276.923561) (xy 369.303361 -276.960284) (xy 369.261345 -276.99081) (xy 369.215071 -277.014388)
			(xy 369.165678 -277.030436) (xy 369.114383 -277.038561) (xy 369.062449 -277.038561) (xy 369.011154 -277.030436)
			(xy 368.961761 -277.014388) (xy 368.915487 -276.99081) (xy 368.873471 -276.960284) (xy 368.836748 -276.923561)
			(xy 368.806222 -276.881545) (xy 368.782644 -276.835271) (xy 368.766596 -276.785878) (xy 368.758471 -276.734583)
			(xy 368.478267 -276.734583) (xy 368.470182 -276.785624) (xy 368.454134 -276.835017) (xy 368.430556 -276.881291)
			(xy 368.40003 -276.923307) (xy 368.363307 -276.96003) (xy 368.321291 -276.990556) (xy 368.275017 -277.014134)
			(xy 368.225624 -277.030182) (xy 368.174329 -277.038307) (xy 368.122395 -277.038307) (xy 368.0711 -277.030182)
			(xy 368.021707 -277.014134) (xy 367.975433 -276.990556) (xy 367.933417 -276.96003) (xy 367.896694 -276.923307)
			(xy 367.866168 -276.881291) (xy 367.84259 -276.835017) (xy 367.826542 -276.785624) (xy 367.818417 -276.734329)
			(xy 367.538374 -276.734329) (xy 367.531465 -276.780969) (xy 367.517383 -276.827468) (xy 367.496641 -276.871402)
			(xy 367.469688 -276.911825) (xy 367.437103 -276.947863) (xy 367.41862 -276.963632) (xy 367.407976 -276.97298)
			(xy 367.391884 -276.99628) (xy 367.382823 -277.023107) (xy 367.381491 -277.051392) (xy 367.38799 -277.078953)
			(xy 367.40182 -277.103662) (xy 367.411508 -277.114) (xy 367.525046 -277.227538) (xy 367.556288 -277.215346)
			(xy 367.585703 -277.204381) (xy 367.647333 -277.192491) (xy 367.678716 -277.191724) (xy 367.704683 -277.192234)
			(xy 367.755977 -277.200361) (xy 367.805369 -277.21641) (xy 367.851643 -277.239989) (xy 367.893658 -277.270515)
			(xy 367.930381 -277.307237) (xy 367.960908 -277.349252) (xy 367.984487 -277.395525) (xy 368.000538 -277.444917)
			(xy 368.008665 -277.496211) (xy 368.00917 -277.522178) (xy 368.008654 -277.548145) (xy 368.288571 -277.548145)
			(xy 368.288571 -277.496211) (xy 368.296696 -277.444916) (xy 368.312744 -277.395523) (xy 368.336322 -277.349249)
			(xy 368.366848 -277.307233) (xy 368.403571 -277.27051) (xy 368.445587 -277.239984) (xy 368.491861 -277.216406)
			(xy 368.541254 -277.200358) (xy 368.592549 -277.192233) (xy 368.644483 -277.192233) (xy 368.695778 -277.200358)
			(xy 368.745171 -277.216406) (xy 368.791445 -277.239984) (xy 368.833461 -277.27051) (xy 368.870184 -277.307233)
			(xy 368.90071 -277.349249) (xy 368.924288 -277.395523) (xy 368.940336 -277.444916) (xy 368.948461 -277.496211)
			(xy 368.94897 -277.522178) (xy 368.948461 -277.548145) (xy 369.228371 -277.548145) (xy 369.228371 -277.496211)
			(xy 369.236496 -277.444916) (xy 369.252544 -277.395523) (xy 369.276122 -277.349249) (xy 369.306648 -277.307233)
			(xy 369.343371 -277.27051) (xy 369.385387 -277.239984) (xy 369.431661 -277.216406) (xy 369.481054 -277.200358)
			(xy 369.532349 -277.192233) (xy 369.584283 -277.192233) (xy 369.635578 -277.200358) (xy 369.684971 -277.216406)
			(xy 369.731245 -277.239984) (xy 369.773261 -277.27051) (xy 369.809984 -277.307233) (xy 369.84051 -277.349249)
			(xy 369.864088 -277.395523) (xy 369.880136 -277.444916) (xy 369.888261 -277.496211) (xy 369.88877 -277.522178)
			(xy 369.888261 -277.548145) (xy 370.168171 -277.548145) (xy 370.168171 -277.496211) (xy 370.176296 -277.444916)
			(xy 370.192344 -277.395523) (xy 370.215922 -277.349249) (xy 370.246448 -277.307233) (xy 370.283171 -277.27051)
			(xy 370.325187 -277.239984) (xy 370.371461 -277.216406) (xy 370.420854 -277.200358) (xy 370.472149 -277.192233)
			(xy 370.524083 -277.192233) (xy 370.575378 -277.200358) (xy 370.624771 -277.216406) (xy 370.671045 -277.239984)
			(xy 370.713061 -277.27051) (xy 370.749784 -277.307233) (xy 370.78031 -277.349249) (xy 370.803888 -277.395523)
			(xy 370.819936 -277.444916) (xy 370.828061 -277.496211) (xy 370.82857 -277.522178) (xy 370.828061 -277.548145)
			(xy 370.828021 -277.548399) (xy 371.107717 -277.548399) (xy 371.107717 -277.496465) (xy 371.115842 -277.44517)
			(xy 371.13189 -277.395777) (xy 371.155468 -277.349503) (xy 371.185994 -277.307487) (xy 371.222717 -277.270764)
			(xy 371.264733 -277.240238) (xy 371.311007 -277.21666) (xy 371.3604 -277.200612) (xy 371.411695 -277.192487)
			(xy 371.463629 -277.192487) (xy 371.514924 -277.200612) (xy 371.564317 -277.21666) (xy 371.610591 -277.240238)
			(xy 371.652607 -277.270764) (xy 371.68933 -277.307487) (xy 371.719856 -277.349503) (xy 371.743434 -277.395777)
			(xy 371.759482 -277.44517) (xy 371.767607 -277.496465) (xy 371.768116 -277.522432) (xy 371.767607 -277.548399)
			(xy 372.047517 -277.548399) (xy 372.047517 -277.496465) (xy 372.055642 -277.44517) (xy 372.07169 -277.395777)
			(xy 372.095268 -277.349503) (xy 372.125794 -277.307487) (xy 372.162517 -277.270764) (xy 372.204533 -277.240238)
			(xy 372.250807 -277.21666) (xy 372.3002 -277.200612) (xy 372.351495 -277.192487) (xy 372.403429 -277.192487)
			(xy 372.454724 -277.200612) (xy 372.504117 -277.21666) (xy 372.550391 -277.240238) (xy 372.592407 -277.270764)
			(xy 372.62913 -277.307487) (xy 372.659656 -277.349503) (xy 372.683234 -277.395777) (xy 372.699282 -277.44517)
			(xy 372.707407 -277.496465) (xy 372.707916 -277.522432) (xy 372.707407 -277.548399) (xy 372.987571 -277.548399)
			(xy 372.987571 -277.496465) (xy 372.995696 -277.44517) (xy 373.011744 -277.395777) (xy 373.035322 -277.349503)
			(xy 373.065848 -277.307487) (xy 373.102571 -277.270764) (xy 373.144587 -277.240238) (xy 373.190861 -277.21666)
			(xy 373.240254 -277.200612) (xy 373.291549 -277.192487) (xy 373.343483 -277.192487) (xy 373.394778 -277.200612)
			(xy 373.444171 -277.21666) (xy 373.490445 -277.240238) (xy 373.532461 -277.270764) (xy 373.569184 -277.307487)
			(xy 373.59971 -277.349503) (xy 373.623288 -277.395777) (xy 373.639336 -277.44517) (xy 373.647461 -277.496465)
			(xy 373.64797 -277.522432) (xy 373.647461 -277.548399) (xy 373.927117 -277.548399) (xy 373.927117 -277.496465)
			(xy 373.935242 -277.44517) (xy 373.95129 -277.395777) (xy 373.974868 -277.349503) (xy 374.005394 -277.307487)
			(xy 374.042117 -277.270764) (xy 374.084133 -277.240238) (xy 374.130407 -277.21666) (xy 374.1798 -277.200612)
			(xy 374.231095 -277.192487) (xy 374.283029 -277.192487) (xy 374.334324 -277.200612) (xy 374.383717 -277.21666)
			(xy 374.429991 -277.240238) (xy 374.472007 -277.270764) (xy 374.50873 -277.307487) (xy 374.539256 -277.349503)
			(xy 374.562834 -277.395777) (xy 374.578882 -277.44517) (xy 374.587007 -277.496465) (xy 374.587516 -277.522432)
			(xy 374.587007 -277.548399) (xy 374.866917 -277.548399) (xy 374.866917 -277.496465) (xy 374.875042 -277.44517)
			(xy 374.89109 -277.395777) (xy 374.914668 -277.349503) (xy 374.945194 -277.307487) (xy 374.981917 -277.270764)
			(xy 375.023933 -277.240238) (xy 375.070207 -277.21666) (xy 375.1196 -277.200612) (xy 375.170895 -277.192487)
			(xy 375.222829 -277.192487) (xy 375.274124 -277.200612) (xy 375.323517 -277.21666) (xy 375.369791 -277.240238)
			(xy 375.411807 -277.270764) (xy 375.44853 -277.307487) (xy 375.479056 -277.349503) (xy 375.502634 -277.395777)
			(xy 375.518682 -277.44517) (xy 375.526807 -277.496465) (xy 375.527316 -277.522432) (xy 375.526807 -277.548399)
			(xy 375.806717 -277.548399) (xy 375.806717 -277.496465) (xy 375.814842 -277.44517) (xy 375.83089 -277.395777)
			(xy 375.854468 -277.349503) (xy 375.884994 -277.307487) (xy 375.921717 -277.270764) (xy 375.963733 -277.240238)
			(xy 376.010007 -277.21666) (xy 376.0594 -277.200612) (xy 376.110695 -277.192487) (xy 376.162629 -277.192487)
			(xy 376.213924 -277.200612) (xy 376.263317 -277.21666) (xy 376.309591 -277.240238) (xy 376.351607 -277.270764)
			(xy 376.38833 -277.307487) (xy 376.418856 -277.349503) (xy 376.442434 -277.395777) (xy 376.458482 -277.44517)
			(xy 376.466607 -277.496465) (xy 376.467116 -277.522432) (xy 376.466607 -277.548399) (xy 376.458482 -277.599694)
			(xy 376.442434 -277.649087) (xy 376.418856 -277.695361) (xy 376.38833 -277.737377) (xy 376.351607 -277.7741)
			(xy 376.309591 -277.804626) (xy 376.263317 -277.828204) (xy 376.213924 -277.844252) (xy 376.162629 -277.852377)
			(xy 376.110695 -277.852377) (xy 376.0594 -277.844252) (xy 376.010007 -277.828204) (xy 375.963733 -277.804626)
			(xy 375.921717 -277.7741) (xy 375.884994 -277.737377) (xy 375.854468 -277.695361) (xy 375.83089 -277.649087)
			(xy 375.814842 -277.599694) (xy 375.806717 -277.548399) (xy 375.526807 -277.548399) (xy 375.518682 -277.599694)
			(xy 375.502634 -277.649087) (xy 375.479056 -277.695361) (xy 375.44853 -277.737377) (xy 375.411807 -277.7741)
			(xy 375.369791 -277.804626) (xy 375.323517 -277.828204) (xy 375.274124 -277.844252) (xy 375.222829 -277.852377)
			(xy 375.170895 -277.852377) (xy 375.1196 -277.844252) (xy 375.070207 -277.828204) (xy 375.023933 -277.804626)
			(xy 374.981917 -277.7741) (xy 374.945194 -277.737377) (xy 374.914668 -277.695361) (xy 374.89109 -277.649087)
			(xy 374.875042 -277.599694) (xy 374.866917 -277.548399) (xy 374.587007 -277.548399) (xy 374.578882 -277.599694)
			(xy 374.562834 -277.649087) (xy 374.539256 -277.695361) (xy 374.50873 -277.737377) (xy 374.472007 -277.7741)
			(xy 374.429991 -277.804626) (xy 374.383717 -277.828204) (xy 374.334324 -277.844252) (xy 374.283029 -277.852377)
			(xy 374.231095 -277.852377) (xy 374.1798 -277.844252) (xy 374.130407 -277.828204) (xy 374.084133 -277.804626)
			(xy 374.042117 -277.7741) (xy 374.005394 -277.737377) (xy 373.974868 -277.695361) (xy 373.95129 -277.649087)
			(xy 373.935242 -277.599694) (xy 373.927117 -277.548399) (xy 373.647461 -277.548399) (xy 373.639336 -277.599694)
			(xy 373.623288 -277.649087) (xy 373.59971 -277.695361) (xy 373.569184 -277.737377) (xy 373.532461 -277.7741)
			(xy 373.490445 -277.804626) (xy 373.444171 -277.828204) (xy 373.394778 -277.844252) (xy 373.343483 -277.852377)
			(xy 373.291549 -277.852377) (xy 373.240254 -277.844252) (xy 373.190861 -277.828204) (xy 373.144587 -277.804626)
			(xy 373.102571 -277.7741) (xy 373.065848 -277.737377) (xy 373.035322 -277.695361) (xy 373.011744 -277.649087)
			(xy 372.995696 -277.599694) (xy 372.987571 -277.548399) (xy 372.707407 -277.548399) (xy 372.699282 -277.599694)
			(xy 372.683234 -277.649087) (xy 372.659656 -277.695361) (xy 372.62913 -277.737377) (xy 372.592407 -277.7741)
			(xy 372.550391 -277.804626) (xy 372.504117 -277.828204) (xy 372.454724 -277.844252) (xy 372.403429 -277.852377)
			(xy 372.351495 -277.852377) (xy 372.3002 -277.844252) (xy 372.250807 -277.828204) (xy 372.204533 -277.804626)
			(xy 372.162517 -277.7741) (xy 372.125794 -277.737377) (xy 372.095268 -277.695361) (xy 372.07169 -277.649087)
			(xy 372.055642 -277.599694) (xy 372.047517 -277.548399) (xy 371.767607 -277.548399) (xy 371.759482 -277.599694)
			(xy 371.743434 -277.649087) (xy 371.719856 -277.695361) (xy 371.68933 -277.737377) (xy 371.652607 -277.7741)
			(xy 371.610591 -277.804626) (xy 371.564317 -277.828204) (xy 371.514924 -277.844252) (xy 371.463629 -277.852377)
			(xy 371.411695 -277.852377) (xy 371.3604 -277.844252) (xy 371.311007 -277.828204) (xy 371.264733 -277.804626)
			(xy 371.222717 -277.7741) (xy 371.185994 -277.737377) (xy 371.155468 -277.695361) (xy 371.13189 -277.649087)
			(xy 371.115842 -277.599694) (xy 371.107717 -277.548399) (xy 370.828021 -277.548399) (xy 370.819936 -277.59944)
			(xy 370.803888 -277.648833) (xy 370.78031 -277.695107) (xy 370.749784 -277.737123) (xy 370.713061 -277.773846)
			(xy 370.671045 -277.804372) (xy 370.624771 -277.82795) (xy 370.575378 -277.843998) (xy 370.524083 -277.852123)
			(xy 370.472149 -277.852123) (xy 370.420854 -277.843998) (xy 370.371461 -277.82795) (xy 370.325187 -277.804372)
			(xy 370.283171 -277.773846) (xy 370.246448 -277.737123) (xy 370.215922 -277.695107) (xy 370.192344 -277.648833)
			(xy 370.176296 -277.59944) (xy 370.168171 -277.548145) (xy 369.888261 -277.548145) (xy 369.880136 -277.59944)
			(xy 369.864088 -277.648833) (xy 369.84051 -277.695107) (xy 369.809984 -277.737123) (xy 369.773261 -277.773846)
			(xy 369.731245 -277.804372) (xy 369.684971 -277.82795) (xy 369.635578 -277.843998) (xy 369.584283 -277.852123)
			(xy 369.532349 -277.852123) (xy 369.481054 -277.843998) (xy 369.431661 -277.82795) (xy 369.385387 -277.804372)
			(xy 369.343371 -277.773846) (xy 369.306648 -277.737123) (xy 369.276122 -277.695107) (xy 369.252544 -277.648833)
			(xy 369.236496 -277.59944) (xy 369.228371 -277.548145) (xy 368.948461 -277.548145) (xy 368.940336 -277.59944)
			(xy 368.924288 -277.648833) (xy 368.90071 -277.695107) (xy 368.870184 -277.737123) (xy 368.833461 -277.773846)
			(xy 368.791445 -277.804372) (xy 368.745171 -277.82795) (xy 368.695778 -277.843998) (xy 368.644483 -277.852123)
			(xy 368.592549 -277.852123) (xy 368.541254 -277.843998) (xy 368.491861 -277.82795) (xy 368.445587 -277.804372)
			(xy 368.403571 -277.773846) (xy 368.366848 -277.737123) (xy 368.336322 -277.695107) (xy 368.312744 -277.648833)
			(xy 368.296696 -277.59944) (xy 368.288571 -277.548145) (xy 368.008654 -277.548145) (xy 368.008632 -277.549276)
			(xy 367.99979 -277.602746) (xy 367.982324 -277.65405) (xy 367.956705 -277.701808) (xy 367.94059 -277.7236)
			(xy 367.94059 -278.362215) (xy 368.758217 -278.362215) (xy 368.758217 -278.310281) (xy 368.766342 -278.258986)
			(xy 368.78239 -278.209593) (xy 368.805968 -278.163319) (xy 368.836494 -278.121303) (xy 368.873217 -278.08458)
			(xy 368.915233 -278.054054) (xy 368.961507 -278.030476) (xy 369.0109 -278.014428) (xy 369.062195 -278.006303)
			(xy 369.114129 -278.006303) (xy 369.165424 -278.014428) (xy 369.214817 -278.030476) (xy 369.261091 -278.054054)
			(xy 369.303107 -278.08458) (xy 369.33983 -278.121303) (xy 369.370356 -278.163319) (xy 369.393934 -278.209593)
			(xy 369.409982 -278.258986) (xy 369.418107 -278.310281) (xy 369.418616 -278.336248) (xy 369.418107 -278.362215)
			(xy 369.418067 -278.362469) (xy 369.698017 -278.362469) (xy 369.698017 -278.310535) (xy 369.706142 -278.25924)
			(xy 369.72219 -278.209847) (xy 369.745768 -278.163573) (xy 369.776294 -278.121557) (xy 369.813017 -278.084834)
			(xy 369.855033 -278.054308) (xy 369.901307 -278.03073) (xy 369.9507 -278.014682) (xy 370.001995 -278.006557)
			(xy 370.053929 -278.006557) (xy 370.105224 -278.014682) (xy 370.154617 -278.03073) (xy 370.200891 -278.054308)
			(xy 370.242907 -278.084834) (xy 370.27963 -278.121557) (xy 370.310156 -278.163573) (xy 370.333734 -278.209847)
			(xy 370.349782 -278.25924) (xy 370.357907 -278.310535) (xy 370.358416 -278.336502) (xy 370.357907 -278.362469)
			(xy 370.638071 -278.362469) (xy 370.638071 -278.310535) (xy 370.646196 -278.25924) (xy 370.662244 -278.209847)
			(xy 370.685822 -278.163573) (xy 370.716348 -278.121557) (xy 370.753071 -278.084834) (xy 370.795087 -278.054308)
			(xy 370.841361 -278.03073) (xy 370.890754 -278.014682) (xy 370.942049 -278.006557) (xy 370.993983 -278.006557)
			(xy 371.045278 -278.014682) (xy 371.094671 -278.03073) (xy 371.140945 -278.054308) (xy 371.182961 -278.084834)
			(xy 371.219684 -278.121557) (xy 371.25021 -278.163573) (xy 371.273788 -278.209847) (xy 371.289836 -278.25924)
			(xy 371.297961 -278.310535) (xy 371.29847 -278.336502) (xy 371.297961 -278.362469) (xy 372.517671 -278.362469)
			(xy 372.517671 -278.310535) (xy 372.525796 -278.25924) (xy 372.541844 -278.209847) (xy 372.565422 -278.163573)
			(xy 372.595948 -278.121557) (xy 372.632671 -278.084834) (xy 372.674687 -278.054308) (xy 372.720961 -278.03073)
			(xy 372.770354 -278.014682) (xy 372.821649 -278.006557) (xy 372.873583 -278.006557) (xy 372.924878 -278.014682)
			(xy 372.974271 -278.03073) (xy 373.020545 -278.054308) (xy 373.062561 -278.084834) (xy 373.099284 -278.121557)
			(xy 373.12981 -278.163573) (xy 373.153388 -278.209847) (xy 373.169436 -278.25924) (xy 373.177561 -278.310535)
			(xy 373.17807 -278.336502) (xy 373.177561 -278.362469) (xy 373.457471 -278.362469) (xy 373.457471 -278.310535)
			(xy 373.465596 -278.25924) (xy 373.481644 -278.209847) (xy 373.505222 -278.163573) (xy 373.535748 -278.121557)
			(xy 373.572471 -278.084834) (xy 373.614487 -278.054308) (xy 373.660761 -278.03073) (xy 373.710154 -278.014682)
			(xy 373.761449 -278.006557) (xy 373.813383 -278.006557) (xy 373.864678 -278.014682) (xy 373.914071 -278.03073)
			(xy 373.960345 -278.054308) (xy 374.002361 -278.084834) (xy 374.039084 -278.121557) (xy 374.06961 -278.163573)
			(xy 374.093188 -278.209847) (xy 374.109236 -278.25924) (xy 374.117361 -278.310535) (xy 374.11787 -278.336502)
			(xy 374.117361 -278.362469) (xy 374.397271 -278.362469) (xy 374.397271 -278.310535) (xy 374.405396 -278.25924)
			(xy 374.421444 -278.209847) (xy 374.445022 -278.163573) (xy 374.475548 -278.121557) (xy 374.512271 -278.084834)
			(xy 374.554287 -278.054308) (xy 374.600561 -278.03073) (xy 374.649954 -278.014682) (xy 374.701249 -278.006557)
			(xy 374.753183 -278.006557) (xy 374.804478 -278.014682) (xy 374.853871 -278.03073) (xy 374.900145 -278.054308)
			(xy 374.942161 -278.084834) (xy 374.978884 -278.121557) (xy 375.00941 -278.163573) (xy 375.032988 -278.209847)
			(xy 375.049036 -278.25924) (xy 375.057161 -278.310535) (xy 375.05767 -278.336502) (xy 375.057161 -278.362469)
			(xy 375.337071 -278.362469) (xy 375.337071 -278.310535) (xy 375.345196 -278.25924) (xy 375.361244 -278.209847)
			(xy 375.384822 -278.163573) (xy 375.415348 -278.121557) (xy 375.452071 -278.084834) (xy 375.494087 -278.054308)
			(xy 375.540361 -278.03073) (xy 375.589754 -278.014682) (xy 375.641049 -278.006557) (xy 375.692983 -278.006557)
			(xy 375.744278 -278.014682) (xy 375.793671 -278.03073) (xy 375.839945 -278.054308) (xy 375.881961 -278.084834)
			(xy 375.918684 -278.121557) (xy 375.94921 -278.163573) (xy 375.972788 -278.209847) (xy 375.988836 -278.25924)
			(xy 375.996961 -278.310535) (xy 375.99747 -278.336502) (xy 375.996961 -278.362469) (xy 376.276617 -278.362469)
			(xy 376.276617 -278.310535) (xy 376.284742 -278.25924) (xy 376.30079 -278.209847) (xy 376.324368 -278.163573)
			(xy 376.354894 -278.121557) (xy 376.391617 -278.084834) (xy 376.433633 -278.054308) (xy 376.479907 -278.03073)
			(xy 376.5293 -278.014682) (xy 376.580595 -278.006557) (xy 376.632529 -278.006557) (xy 376.683824 -278.014682)
			(xy 376.733217 -278.03073) (xy 376.779491 -278.054308) (xy 376.821507 -278.084834) (xy 376.85823 -278.121557)
			(xy 376.888756 -278.163573) (xy 376.912334 -278.209847) (xy 376.928382 -278.25924) (xy 376.936507 -278.310535)
			(xy 376.937016 -278.336502) (xy 376.936507 -278.362469) (xy 377.216671 -278.362469) (xy 377.216671 -278.310535)
			(xy 377.224796 -278.25924) (xy 377.240844 -278.209847) (xy 377.264422 -278.163573) (xy 377.294948 -278.121557)
			(xy 377.331671 -278.084834) (xy 377.373687 -278.054308) (xy 377.419961 -278.03073) (xy 377.469354 -278.014682)
			(xy 377.520649 -278.006557) (xy 377.572583 -278.006557) (xy 377.623878 -278.014682) (xy 377.673271 -278.03073)
			(xy 377.719545 -278.054308) (xy 377.761561 -278.084834) (xy 377.798284 -278.121557) (xy 377.82881 -278.163573)
			(xy 377.852388 -278.209847) (xy 377.868436 -278.25924) (xy 377.876561 -278.310535) (xy 377.87707 -278.336502)
			(xy 377.876561 -278.362469) (xy 377.868436 -278.413764) (xy 377.852388 -278.463157) (xy 377.82881 -278.509431)
			(xy 377.798284 -278.551447) (xy 377.761561 -278.58817) (xy 377.719545 -278.618696) (xy 377.673271 -278.642274)
			(xy 377.623878 -278.658322) (xy 377.572583 -278.666447) (xy 377.520649 -278.666447) (xy 377.469354 -278.658322)
			(xy 377.419961 -278.642274) (xy 377.373687 -278.618696) (xy 377.331671 -278.58817) (xy 377.294948 -278.551447)
			(xy 377.264422 -278.509431) (xy 377.240844 -278.463157) (xy 377.224796 -278.413764) (xy 377.216671 -278.362469)
			(xy 376.936507 -278.362469) (xy 376.928382 -278.413764) (xy 376.912334 -278.463157) (xy 376.888756 -278.509431)
			(xy 376.85823 -278.551447) (xy 376.821507 -278.58817) (xy 376.779491 -278.618696) (xy 376.733217 -278.642274)
			(xy 376.683824 -278.658322) (xy 376.632529 -278.666447) (xy 376.580595 -278.666447) (xy 376.5293 -278.658322)
			(xy 376.479907 -278.642274) (xy 376.433633 -278.618696) (xy 376.391617 -278.58817) (xy 376.354894 -278.551447)
			(xy 376.324368 -278.509431) (xy 376.30079 -278.463157) (xy 376.284742 -278.413764) (xy 376.276617 -278.362469)
			(xy 375.996961 -278.362469) (xy 375.988836 -278.413764) (xy 375.972788 -278.463157) (xy 375.94921 -278.509431)
			(xy 375.918684 -278.551447) (xy 375.881961 -278.58817) (xy 375.839945 -278.618696) (xy 375.793671 -278.642274)
			(xy 375.744278 -278.658322) (xy 375.692983 -278.666447) (xy 375.641049 -278.666447) (xy 375.589754 -278.658322)
			(xy 375.540361 -278.642274) (xy 375.494087 -278.618696) (xy 375.452071 -278.58817) (xy 375.415348 -278.551447)
			(xy 375.384822 -278.509431) (xy 375.361244 -278.463157) (xy 375.345196 -278.413764) (xy 375.337071 -278.362469)
			(xy 375.057161 -278.362469) (xy 375.049036 -278.413764) (xy 375.032988 -278.463157) (xy 375.00941 -278.509431)
			(xy 374.978884 -278.551447) (xy 374.942161 -278.58817) (xy 374.900145 -278.618696) (xy 374.853871 -278.642274)
			(xy 374.804478 -278.658322) (xy 374.753183 -278.666447) (xy 374.701249 -278.666447) (xy 374.649954 -278.658322)
			(xy 374.600561 -278.642274) (xy 374.554287 -278.618696) (xy 374.512271 -278.58817) (xy 374.475548 -278.551447)
			(xy 374.445022 -278.509431) (xy 374.421444 -278.463157) (xy 374.405396 -278.413764) (xy 374.397271 -278.362469)
			(xy 374.117361 -278.362469) (xy 374.109236 -278.413764) (xy 374.093188 -278.463157) (xy 374.06961 -278.509431)
			(xy 374.039084 -278.551447) (xy 374.002361 -278.58817) (xy 373.960345 -278.618696) (xy 373.914071 -278.642274)
			(xy 373.864678 -278.658322) (xy 373.813383 -278.666447) (xy 373.761449 -278.666447) (xy 373.710154 -278.658322)
			(xy 373.660761 -278.642274) (xy 373.614487 -278.618696) (xy 373.572471 -278.58817) (xy 373.535748 -278.551447)
			(xy 373.505222 -278.509431) (xy 373.481644 -278.463157) (xy 373.465596 -278.413764) (xy 373.457471 -278.362469)
			(xy 373.177561 -278.362469) (xy 373.169436 -278.413764) (xy 373.153388 -278.463157) (xy 373.12981 -278.509431)
			(xy 373.099284 -278.551447) (xy 373.062561 -278.58817) (xy 373.020545 -278.618696) (xy 372.974271 -278.642274)
			(xy 372.924878 -278.658322) (xy 372.873583 -278.666447) (xy 372.821649 -278.666447) (xy 372.770354 -278.658322)
			(xy 372.720961 -278.642274) (xy 372.674687 -278.618696) (xy 372.632671 -278.58817) (xy 372.595948 -278.551447)
			(xy 372.565422 -278.509431) (xy 372.541844 -278.463157) (xy 372.525796 -278.413764) (xy 372.517671 -278.362469)
			(xy 371.297961 -278.362469) (xy 371.289836 -278.413764) (xy 371.273788 -278.463157) (xy 371.25021 -278.509431)
			(xy 371.219684 -278.551447) (xy 371.182961 -278.58817) (xy 371.140945 -278.618696) (xy 371.094671 -278.642274)
			(xy 371.045278 -278.658322) (xy 370.993983 -278.666447) (xy 370.942049 -278.666447) (xy 370.890754 -278.658322)
			(xy 370.841361 -278.642274) (xy 370.795087 -278.618696) (xy 370.753071 -278.58817) (xy 370.716348 -278.551447)
			(xy 370.685822 -278.509431) (xy 370.662244 -278.463157) (xy 370.646196 -278.413764) (xy 370.638071 -278.362469)
			(xy 370.357907 -278.362469) (xy 370.349782 -278.413764) (xy 370.333734 -278.463157) (xy 370.310156 -278.509431)
			(xy 370.27963 -278.551447) (xy 370.242907 -278.58817) (xy 370.200891 -278.618696) (xy 370.154617 -278.642274)
			(xy 370.105224 -278.658322) (xy 370.053929 -278.666447) (xy 370.001995 -278.666447) (xy 369.9507 -278.658322)
			(xy 369.901307 -278.642274) (xy 369.855033 -278.618696) (xy 369.813017 -278.58817) (xy 369.776294 -278.551447)
			(xy 369.745768 -278.509431) (xy 369.72219 -278.463157) (xy 369.706142 -278.413764) (xy 369.698017 -278.362469)
			(xy 369.418067 -278.362469) (xy 369.409982 -278.41351) (xy 369.393934 -278.462903) (xy 369.370356 -278.509177)
			(xy 369.33983 -278.551193) (xy 369.303107 -278.587916) (xy 369.261091 -278.618442) (xy 369.214817 -278.64202)
			(xy 369.165424 -278.658068) (xy 369.114129 -278.666193) (xy 369.062195 -278.666193) (xy 369.0109 -278.658068)
			(xy 368.961507 -278.64202) (xy 368.915233 -278.618442) (xy 368.873217 -278.587916) (xy 368.836494 -278.551193)
			(xy 368.805968 -278.509177) (xy 368.78239 -278.462903) (xy 368.766342 -278.41351) (xy 368.758217 -278.362215)
			(xy 367.94059 -278.362215) (xy 367.94059 -278.94915) (xy 367.956639 -278.970936) (xy 367.982161 -279.018645)
			(xy 367.999564 -279.069877) (xy 368.008383 -279.123261) (xy 368.00838 -279.176285) (xy 368.288571 -279.176285)
			(xy 368.288571 -279.124351) (xy 368.296696 -279.073056) (xy 368.312744 -279.023663) (xy 368.336322 -278.977389)
			(xy 368.366848 -278.935373) (xy 368.403571 -278.89865) (xy 368.445587 -278.868124) (xy 368.491861 -278.844546)
			(xy 368.541254 -278.828498) (xy 368.592549 -278.820373) (xy 368.644483 -278.820373) (xy 368.695778 -278.828498)
			(xy 368.745171 -278.844546) (xy 368.791445 -278.868124) (xy 368.833461 -278.89865) (xy 368.870184 -278.935373)
			(xy 368.90071 -278.977389) (xy 368.924288 -279.023663) (xy 368.940336 -279.073056) (xy 368.948461 -279.124351)
			(xy 368.94897 -279.150318) (xy 368.948461 -279.176285) (xy 369.228117 -279.176285) (xy 369.228117 -279.124351)
			(xy 369.236242 -279.073056) (xy 369.25229 -279.023663) (xy 369.275868 -278.977389) (xy 369.306394 -278.935373)
			(xy 369.343117 -278.89865) (xy 369.385133 -278.868124) (xy 369.431407 -278.844546) (xy 369.4808 -278.828498)
			(xy 369.532095 -278.820373) (xy 369.584029 -278.820373) (xy 369.635324 -278.828498) (xy 369.684717 -278.844546)
			(xy 369.730991 -278.868124) (xy 369.773007 -278.89865) (xy 369.80973 -278.935373) (xy 369.840256 -278.977389)
			(xy 369.863834 -279.023663) (xy 369.879882 -279.073056) (xy 369.888007 -279.124351) (xy 369.888516 -279.150318)
			(xy 369.888007 -279.176285) (xy 370.167917 -279.176285) (xy 370.167917 -279.124351) (xy 370.176042 -279.073056)
			(xy 370.19209 -279.023663) (xy 370.215668 -278.977389) (xy 370.246194 -278.935373) (xy 370.282917 -278.89865)
			(xy 370.324933 -278.868124) (xy 370.371207 -278.844546) (xy 370.4206 -278.828498) (xy 370.471895 -278.820373)
			(xy 370.523829 -278.820373) (xy 370.575124 -278.828498) (xy 370.624517 -278.844546) (xy 370.670791 -278.868124)
			(xy 370.712807 -278.89865) (xy 370.74953 -278.935373) (xy 370.780056 -278.977389) (xy 370.803634 -279.023663)
			(xy 370.819682 -279.073056) (xy 370.827807 -279.124351) (xy 370.828316 -279.150318) (xy 370.827807 -279.176285)
			(xy 371.107971 -279.176285) (xy 371.107971 -279.124351) (xy 371.116096 -279.073056) (xy 371.132144 -279.023663)
			(xy 371.155722 -278.977389) (xy 371.186248 -278.935373) (xy 371.222971 -278.89865) (xy 371.264987 -278.868124)
			(xy 371.311261 -278.844546) (xy 371.360654 -278.828498) (xy 371.411949 -278.820373) (xy 371.463883 -278.820373)
			(xy 371.515178 -278.828498) (xy 371.564571 -278.844546) (xy 371.610845 -278.868124) (xy 371.652861 -278.89865)
			(xy 371.689584 -278.935373) (xy 371.72011 -278.977389) (xy 371.743688 -279.023663) (xy 371.759736 -279.073056)
			(xy 371.767861 -279.124351) (xy 371.76837 -279.150318) (xy 371.767861 -279.176285) (xy 372.047517 -279.176285)
			(xy 372.047517 -279.124351) (xy 372.055642 -279.073056) (xy 372.07169 -279.023663) (xy 372.095268 -278.977389)
			(xy 372.125794 -278.935373) (xy 372.162517 -278.89865) (xy 372.204533 -278.868124) (xy 372.250807 -278.844546)
			(xy 372.3002 -278.828498) (xy 372.351495 -278.820373) (xy 372.403429 -278.820373) (xy 372.454724 -278.828498)
			(xy 372.504117 -278.844546) (xy 372.550391 -278.868124) (xy 372.592407 -278.89865) (xy 372.62913 -278.935373)
			(xy 372.659656 -278.977389) (xy 372.683234 -279.023663) (xy 372.699282 -279.073056) (xy 372.707407 -279.124351)
			(xy 372.707916 -279.150318) (xy 372.707407 -279.176285) (xy 372.987317 -279.176285) (xy 372.987317 -279.124351)
			(xy 372.995442 -279.073056) (xy 373.01149 -279.023663) (xy 373.035068 -278.977389) (xy 373.065594 -278.935373)
			(xy 373.102317 -278.89865) (xy 373.144333 -278.868124) (xy 373.190607 -278.844546) (xy 373.24 -278.828498)
			(xy 373.291295 -278.820373) (xy 373.343229 -278.820373) (xy 373.394524 -278.828498) (xy 373.443917 -278.844546)
			(xy 373.490191 -278.868124) (xy 373.532207 -278.89865) (xy 373.56893 -278.935373) (xy 373.599456 -278.977389)
			(xy 373.623034 -279.023663) (xy 373.639082 -279.073056) (xy 373.647207 -279.124351) (xy 373.647716 -279.150318)
			(xy 373.647207 -279.176285) (xy 373.927117 -279.176285) (xy 373.927117 -279.124351) (xy 373.935242 -279.073056)
			(xy 373.95129 -279.023663) (xy 373.974868 -278.977389) (xy 374.005394 -278.935373) (xy 374.042117 -278.89865)
			(xy 374.084133 -278.868124) (xy 374.130407 -278.844546) (xy 374.1798 -278.828498) (xy 374.231095 -278.820373)
			(xy 374.283029 -278.820373) (xy 374.334324 -278.828498) (xy 374.383717 -278.844546) (xy 374.429991 -278.868124)
			(xy 374.472007 -278.89865) (xy 374.50873 -278.935373) (xy 374.539256 -278.977389) (xy 374.562834 -279.023663)
			(xy 374.578882 -279.073056) (xy 374.587007 -279.124351) (xy 374.587516 -279.150318) (xy 374.587007 -279.176285)
			(xy 374.866917 -279.176285) (xy 374.866917 -279.124351) (xy 374.875042 -279.073056) (xy 374.89109 -279.023663)
			(xy 374.914668 -278.977389) (xy 374.945194 -278.935373) (xy 374.981917 -278.89865) (xy 375.023933 -278.868124)
			(xy 375.070207 -278.844546) (xy 375.1196 -278.828498) (xy 375.170895 -278.820373) (xy 375.222829 -278.820373)
			(xy 375.274124 -278.828498) (xy 375.323517 -278.844546) (xy 375.369791 -278.868124) (xy 375.411807 -278.89865)
			(xy 375.44853 -278.935373) (xy 375.479056 -278.977389) (xy 375.502634 -279.023663) (xy 375.518682 -279.073056)
			(xy 375.526807 -279.124351) (xy 375.527316 -279.150318) (xy 375.526807 -279.176285) (xy 375.806717 -279.176285)
			(xy 375.806717 -279.124351) (xy 375.814842 -279.073056) (xy 375.83089 -279.023663) (xy 375.854468 -278.977389)
			(xy 375.884994 -278.935373) (xy 375.921717 -278.89865) (xy 375.963733 -278.868124) (xy 376.010007 -278.844546)
			(xy 376.0594 -278.828498) (xy 376.110695 -278.820373) (xy 376.162629 -278.820373) (xy 376.213924 -278.828498)
			(xy 376.263317 -278.844546) (xy 376.309591 -278.868124) (xy 376.351607 -278.89865) (xy 376.38833 -278.935373)
			(xy 376.418856 -278.977389) (xy 376.442434 -279.023663) (xy 376.458482 -279.073056) (xy 376.466607 -279.124351)
			(xy 376.467116 -279.150318) (xy 376.466607 -279.176285) (xy 376.746517 -279.176285) (xy 376.746517 -279.124351)
			(xy 376.754642 -279.073056) (xy 376.77069 -279.023663) (xy 376.794268 -278.977389) (xy 376.824794 -278.935373)
			(xy 376.861517 -278.89865) (xy 376.903533 -278.868124) (xy 376.949807 -278.844546) (xy 376.9992 -278.828498)
			(xy 377.050495 -278.820373) (xy 377.102429 -278.820373) (xy 377.153724 -278.828498) (xy 377.203117 -278.844546)
			(xy 377.249391 -278.868124) (xy 377.291407 -278.89865) (xy 377.32813 -278.935373) (xy 377.358656 -278.977389)
			(xy 377.382234 -279.023663) (xy 377.398282 -279.073056) (xy 377.406407 -279.124351) (xy 377.406916 -279.150318)
			(xy 377.406407 -279.176285) (xy 377.686571 -279.176285) (xy 377.686571 -279.124351) (xy 377.694696 -279.073056)
			(xy 377.710744 -279.023663) (xy 377.734322 -278.977389) (xy 377.764848 -278.935373) (xy 377.801571 -278.89865)
			(xy 377.843587 -278.868124) (xy 377.889861 -278.844546) (xy 377.939254 -278.828498) (xy 377.990549 -278.820373)
			(xy 378.042483 -278.820373) (xy 378.093778 -278.828498) (xy 378.143171 -278.844546) (xy 378.189445 -278.868124)
			(xy 378.231461 -278.89865) (xy 378.268184 -278.935373) (xy 378.29871 -278.977389) (xy 378.322288 -279.023663)
			(xy 378.338336 -279.073056) (xy 378.346461 -279.124351) (xy 378.34697 -279.150318) (xy 378.346461 -279.176285)
			(xy 378.338336 -279.22758) (xy 378.322288 -279.276973) (xy 378.29871 -279.323247) (xy 378.268184 -279.365263)
			(xy 378.231461 -279.401986) (xy 378.189445 -279.432512) (xy 378.143171 -279.45609) (xy 378.093778 -279.472138)
			(xy 378.042483 -279.480263) (xy 377.990549 -279.480263) (xy 377.939254 -279.472138) (xy 377.889861 -279.45609)
			(xy 377.843587 -279.432512) (xy 377.801571 -279.401986) (xy 377.764848 -279.365263) (xy 377.734322 -279.323247)
			(xy 377.710744 -279.276973) (xy 377.694696 -279.22758) (xy 377.686571 -279.176285) (xy 377.406407 -279.176285)
			(xy 377.398282 -279.22758) (xy 377.382234 -279.276973) (xy 377.358656 -279.323247) (xy 377.32813 -279.365263)
			(xy 377.291407 -279.401986) (xy 377.249391 -279.432512) (xy 377.203117 -279.45609) (xy 377.153724 -279.472138)
			(xy 377.102429 -279.480263) (xy 377.050495 -279.480263) (xy 376.9992 -279.472138) (xy 376.949807 -279.45609)
			(xy 376.903533 -279.432512) (xy 376.861517 -279.401986) (xy 376.824794 -279.365263) (xy 376.794268 -279.323247)
			(xy 376.77069 -279.276973) (xy 376.754642 -279.22758) (xy 376.746517 -279.176285) (xy 376.466607 -279.176285)
			(xy 376.458482 -279.22758) (xy 376.442434 -279.276973) (xy 376.418856 -279.323247) (xy 376.38833 -279.365263)
			(xy 376.351607 -279.401986) (xy 376.309591 -279.432512) (xy 376.263317 -279.45609) (xy 376.213924 -279.472138)
			(xy 376.162629 -279.480263) (xy 376.110695 -279.480263) (xy 376.0594 -279.472138) (xy 376.010007 -279.45609)
			(xy 375.963733 -279.432512) (xy 375.921717 -279.401986) (xy 375.884994 -279.365263) (xy 375.854468 -279.323247)
			(xy 375.83089 -279.276973) (xy 375.814842 -279.22758) (xy 375.806717 -279.176285) (xy 375.526807 -279.176285)
			(xy 375.518682 -279.22758) (xy 375.502634 -279.276973) (xy 375.479056 -279.323247) (xy 375.44853 -279.365263)
			(xy 375.411807 -279.401986) (xy 375.369791 -279.432512) (xy 375.323517 -279.45609) (xy 375.274124 -279.472138)
			(xy 375.222829 -279.480263) (xy 375.170895 -279.480263) (xy 375.1196 -279.472138) (xy 375.070207 -279.45609)
			(xy 375.023933 -279.432512) (xy 374.981917 -279.401986) (xy 374.945194 -279.365263) (xy 374.914668 -279.323247)
			(xy 374.89109 -279.276973) (xy 374.875042 -279.22758) (xy 374.866917 -279.176285) (xy 374.587007 -279.176285)
			(xy 374.578882 -279.22758) (xy 374.562834 -279.276973) (xy 374.539256 -279.323247) (xy 374.50873 -279.365263)
			(xy 374.472007 -279.401986) (xy 374.429991 -279.432512) (xy 374.383717 -279.45609) (xy 374.334324 -279.472138)
			(xy 374.283029 -279.480263) (xy 374.231095 -279.480263) (xy 374.1798 -279.472138) (xy 374.130407 -279.45609)
			(xy 374.084133 -279.432512) (xy 374.042117 -279.401986) (xy 374.005394 -279.365263) (xy 373.974868 -279.323247)
			(xy 373.95129 -279.276973) (xy 373.935242 -279.22758) (xy 373.927117 -279.176285) (xy 373.647207 -279.176285)
			(xy 373.639082 -279.22758) (xy 373.623034 -279.276973) (xy 373.599456 -279.323247) (xy 373.56893 -279.365263)
			(xy 373.532207 -279.401986) (xy 373.490191 -279.432512) (xy 373.443917 -279.45609) (xy 373.394524 -279.472138)
			(xy 373.343229 -279.480263) (xy 373.291295 -279.480263) (xy 373.24 -279.472138) (xy 373.190607 -279.45609)
			(xy 373.144333 -279.432512) (xy 373.102317 -279.401986) (xy 373.065594 -279.365263) (xy 373.035068 -279.323247)
			(xy 373.01149 -279.276973) (xy 372.995442 -279.22758) (xy 372.987317 -279.176285) (xy 372.707407 -279.176285)
			(xy 372.699282 -279.22758) (xy 372.683234 -279.276973) (xy 372.659656 -279.323247) (xy 372.62913 -279.365263)
			(xy 372.592407 -279.401986) (xy 372.550391 -279.432512) (xy 372.504117 -279.45609) (xy 372.454724 -279.472138)
			(xy 372.403429 -279.480263) (xy 372.351495 -279.480263) (xy 372.3002 -279.472138) (xy 372.250807 -279.45609)
			(xy 372.204533 -279.432512) (xy 372.162517 -279.401986) (xy 372.125794 -279.365263) (xy 372.095268 -279.323247)
			(xy 372.07169 -279.276973) (xy 372.055642 -279.22758) (xy 372.047517 -279.176285) (xy 371.767861 -279.176285)
			(xy 371.759736 -279.22758) (xy 371.743688 -279.276973) (xy 371.72011 -279.323247) (xy 371.689584 -279.365263)
			(xy 371.652861 -279.401986) (xy 371.610845 -279.432512) (xy 371.564571 -279.45609) (xy 371.515178 -279.472138)
			(xy 371.463883 -279.480263) (xy 371.411949 -279.480263) (xy 371.360654 -279.472138) (xy 371.311261 -279.45609)
			(xy 371.264987 -279.432512) (xy 371.222971 -279.401986) (xy 371.186248 -279.365263) (xy 371.155722 -279.323247)
			(xy 371.132144 -279.276973) (xy 371.116096 -279.22758) (xy 371.107971 -279.176285) (xy 370.827807 -279.176285)
			(xy 370.819682 -279.22758) (xy 370.803634 -279.276973) (xy 370.780056 -279.323247) (xy 370.74953 -279.365263)
			(xy 370.712807 -279.401986) (xy 370.670791 -279.432512) (xy 370.624517 -279.45609) (xy 370.575124 -279.472138)
			(xy 370.523829 -279.480263) (xy 370.471895 -279.480263) (xy 370.4206 -279.472138) (xy 370.371207 -279.45609)
			(xy 370.324933 -279.432512) (xy 370.282917 -279.401986) (xy 370.246194 -279.365263) (xy 370.215668 -279.323247)
			(xy 370.19209 -279.276973) (xy 370.176042 -279.22758) (xy 370.167917 -279.176285) (xy 369.888007 -279.176285)
			(xy 369.879882 -279.22758) (xy 369.863834 -279.276973) (xy 369.840256 -279.323247) (xy 369.80973 -279.365263)
			(xy 369.773007 -279.401986) (xy 369.730991 -279.432512) (xy 369.684717 -279.45609) (xy 369.635324 -279.472138)
			(xy 369.584029 -279.480263) (xy 369.532095 -279.480263) (xy 369.4808 -279.472138) (xy 369.431407 -279.45609)
			(xy 369.385133 -279.432512) (xy 369.343117 -279.401986) (xy 369.306394 -279.365263) (xy 369.275868 -279.323247)
			(xy 369.25229 -279.276973) (xy 369.236242 -279.22758) (xy 369.228117 -279.176285) (xy 368.948461 -279.176285)
			(xy 368.940336 -279.22758) (xy 368.924288 -279.276973) (xy 368.90071 -279.323247) (xy 368.870184 -279.365263)
			(xy 368.833461 -279.401986) (xy 368.791445 -279.432512) (xy 368.745171 -279.45609) (xy 368.695778 -279.472138)
			(xy 368.644483 -279.480263) (xy 368.592549 -279.480263) (xy 368.541254 -279.472138) (xy 368.491861 -279.45609)
			(xy 368.445587 -279.432512) (xy 368.403571 -279.401986) (xy 368.366848 -279.365263) (xy 368.336322 -279.323247)
			(xy 368.312744 -279.276973) (xy 368.296696 -279.22758) (xy 368.288571 -279.176285) (xy 368.00838 -279.176285)
			(xy 368.00838 -279.177368) (xy 367.999557 -279.230751) (xy 367.98215 -279.281981) (xy 367.956624 -279.329688)
			(xy 367.94059 -279.351486) (xy 367.94059 -279.545288) (xy 367.941142 -279.560738) (xy 367.95039 -279.590221)
			(xy 367.968017 -279.615601) (xy 367.992415 -279.634563) (xy 368.02136 -279.645379) (xy 368.052214 -279.647063)
			(xy 368.067336 -279.64384) (xy 368.087319 -279.639088) (xy 368.128078 -279.633996) (xy 368.148616 -279.63368)
			(xy 368.17458 -279.63419) (xy 368.225868 -279.642316) (xy 368.275253 -279.658364) (xy 368.32152 -279.68194)
			(xy 368.363529 -279.712464) (xy 368.400247 -279.749183) (xy 368.430768 -279.791194) (xy 368.454342 -279.837462)
			(xy 368.470388 -279.886848) (xy 368.478511 -279.938136) (xy 368.478511 -279.990064) (xy 368.478505 -279.990101)
			(xy 368.758471 -279.990101) (xy 368.758471 -279.938167) (xy 368.766596 -279.886872) (xy 368.782644 -279.837479)
			(xy 368.806222 -279.791205) (xy 368.836748 -279.749189) (xy 368.873471 -279.712466) (xy 368.915487 -279.68194)
			(xy 368.961761 -279.658362) (xy 369.011154 -279.642314) (xy 369.062449 -279.634189) (xy 369.114383 -279.634189)
			(xy 369.165678 -279.642314) (xy 369.215071 -279.658362) (xy 369.261345 -279.68194) (xy 369.303361 -279.712466)
			(xy 369.340084 -279.749189) (xy 369.37061 -279.791205) (xy 369.394188 -279.837479) (xy 369.410236 -279.886872)
			(xy 369.418361 -279.938167) (xy 369.41887 -279.964134) (xy 369.418361 -279.990101) (xy 370.638071 -279.990101)
			(xy 370.638071 -279.938167) (xy 370.646196 -279.886872) (xy 370.662244 -279.837479) (xy 370.685822 -279.791205)
			(xy 370.716348 -279.749189) (xy 370.753071 -279.712466) (xy 370.795087 -279.68194) (xy 370.841361 -279.658362)
			(xy 370.890754 -279.642314) (xy 370.942049 -279.634189) (xy 370.993983 -279.634189) (xy 371.045278 -279.642314)
			(xy 371.094671 -279.658362) (xy 371.140945 -279.68194) (xy 371.182961 -279.712466) (xy 371.219684 -279.749189)
			(xy 371.25021 -279.791205) (xy 371.273788 -279.837479) (xy 371.289836 -279.886872) (xy 371.297961 -279.938167)
			(xy 371.29847 -279.964134) (xy 371.297961 -279.990101) (xy 371.577617 -279.990101) (xy 371.577617 -279.938167)
			(xy 371.585742 -279.886872) (xy 371.60179 -279.837479) (xy 371.625368 -279.791205) (xy 371.655894 -279.749189)
			(xy 371.692617 -279.712466) (xy 371.734633 -279.68194) (xy 371.780907 -279.658362) (xy 371.8303 -279.642314)
			(xy 371.881595 -279.634189) (xy 371.933529 -279.634189) (xy 371.984824 -279.642314) (xy 372.034217 -279.658362)
			(xy 372.080491 -279.68194) (xy 372.122507 -279.712466) (xy 372.15923 -279.749189) (xy 372.189756 -279.791205)
			(xy 372.213334 -279.837479) (xy 372.229382 -279.886872) (xy 372.237507 -279.938167) (xy 372.238016 -279.964134)
			(xy 372.237507 -279.990101) (xy 372.517671 -279.990101) (xy 372.517671 -279.938167) (xy 372.525796 -279.886872)
			(xy 372.541844 -279.837479) (xy 372.565422 -279.791205) (xy 372.595948 -279.749189) (xy 372.632671 -279.712466)
			(xy 372.674687 -279.68194) (xy 372.720961 -279.658362) (xy 372.770354 -279.642314) (xy 372.821649 -279.634189)
			(xy 372.873583 -279.634189) (xy 372.924878 -279.642314) (xy 372.974271 -279.658362) (xy 373.020545 -279.68194)
			(xy 373.062561 -279.712466) (xy 373.099284 -279.749189) (xy 373.12981 -279.791205) (xy 373.153388 -279.837479)
			(xy 373.169436 -279.886872) (xy 373.177561 -279.938167) (xy 373.17807 -279.964134) (xy 373.177561 -279.990101)
			(xy 373.457471 -279.990101) (xy 373.457471 -279.938167) (xy 373.465596 -279.886872) (xy 373.481644 -279.837479)
			(xy 373.505222 -279.791205) (xy 373.535748 -279.749189) (xy 373.572471 -279.712466) (xy 373.614487 -279.68194)
			(xy 373.660761 -279.658362) (xy 373.710154 -279.642314) (xy 373.761449 -279.634189) (xy 373.813383 -279.634189)
			(xy 373.864678 -279.642314) (xy 373.914071 -279.658362) (xy 373.960345 -279.68194) (xy 374.002361 -279.712466)
			(xy 374.039084 -279.749189) (xy 374.06961 -279.791205) (xy 374.093188 -279.837479) (xy 374.109236 -279.886872)
			(xy 374.117361 -279.938167) (xy 374.11787 -279.964134) (xy 374.117361 -279.990101) (xy 374.397017 -279.990101)
			(xy 374.397017 -279.938167) (xy 374.405142 -279.886872) (xy 374.42119 -279.837479) (xy 374.444768 -279.791205)
			(xy 374.475294 -279.749189) (xy 374.512017 -279.712466) (xy 374.554033 -279.68194) (xy 374.600307 -279.658362)
			(xy 374.6497 -279.642314) (xy 374.700995 -279.634189) (xy 374.752929 -279.634189) (xy 374.804224 -279.642314)
			(xy 374.853617 -279.658362) (xy 374.899891 -279.68194) (xy 374.941907 -279.712466) (xy 374.97863 -279.749189)
			(xy 375.009156 -279.791205) (xy 375.032734 -279.837479) (xy 375.048782 -279.886872) (xy 375.056907 -279.938167)
			(xy 375.057416 -279.964134) (xy 375.056907 -279.990101) (xy 375.337071 -279.990101) (xy 375.337071 -279.938167)
			(xy 375.345196 -279.886872) (xy 375.361244 -279.837479) (xy 375.384822 -279.791205) (xy 375.415348 -279.749189)
			(xy 375.452071 -279.712466) (xy 375.494087 -279.68194) (xy 375.540361 -279.658362) (xy 375.589754 -279.642314)
			(xy 375.641049 -279.634189) (xy 375.692983 -279.634189) (xy 375.744278 -279.642314) (xy 375.793671 -279.658362)
			(xy 375.839945 -279.68194) (xy 375.881961 -279.712466) (xy 375.918684 -279.749189) (xy 375.94921 -279.791205)
			(xy 375.972788 -279.837479) (xy 375.988836 -279.886872) (xy 375.996961 -279.938167) (xy 375.99747 -279.964134)
			(xy 375.996966 -279.989847) (xy 376.276617 -279.989847) (xy 376.276617 -279.937913) (xy 376.284742 -279.886618)
			(xy 376.30079 -279.837225) (xy 376.324368 -279.790951) (xy 376.354894 -279.748935) (xy 376.391617 -279.712212)
			(xy 376.433633 -279.681686) (xy 376.479907 -279.658108) (xy 376.5293 -279.64206) (xy 376.580595 -279.633935)
			(xy 376.632529 -279.633935) (xy 376.683824 -279.64206) (xy 376.733217 -279.658108) (xy 376.779491 -279.681686)
			(xy 376.821507 -279.712212) (xy 376.85823 -279.748935) (xy 376.888756 -279.790951) (xy 376.912334 -279.837225)
			(xy 376.928382 -279.886618) (xy 376.936507 -279.937913) (xy 376.937016 -279.96388) (xy 376.936507 -279.989847)
			(xy 376.936467 -279.990101) (xy 378.156471 -279.990101) (xy 378.156471 -279.938167) (xy 378.164596 -279.886872)
			(xy 378.180644 -279.837479) (xy 378.204222 -279.791205) (xy 378.234748 -279.749189) (xy 378.271471 -279.712466)
			(xy 378.313487 -279.68194) (xy 378.359761 -279.658362) (xy 378.409154 -279.642314) (xy 378.460449 -279.634189)
			(xy 378.512383 -279.634189) (xy 378.563678 -279.642314) (xy 378.613071 -279.658362) (xy 378.659345 -279.68194)
			(xy 378.701361 -279.712466) (xy 378.738084 -279.749189) (xy 378.76861 -279.791205) (xy 378.792188 -279.837479)
			(xy 378.808236 -279.886872) (xy 378.816361 -279.938167) (xy 378.81687 -279.964134) (xy 378.816361 -279.990101)
			(xy 379.096271 -279.990101) (xy 379.096271 -279.938167) (xy 379.104396 -279.886872) (xy 379.120444 -279.837479)
			(xy 379.144022 -279.791205) (xy 379.174548 -279.749189) (xy 379.211271 -279.712466) (xy 379.253287 -279.68194)
			(xy 379.299561 -279.658362) (xy 379.348954 -279.642314) (xy 379.400249 -279.634189) (xy 379.452183 -279.634189)
			(xy 379.503478 -279.642314) (xy 379.552871 -279.658362) (xy 379.599145 -279.68194) (xy 379.641161 -279.712466)
			(xy 379.677884 -279.749189) (xy 379.70841 -279.791205) (xy 379.731988 -279.837479) (xy 379.748036 -279.886872)
			(xy 379.756161 -279.938167) (xy 379.75667 -279.964134) (xy 379.756161 -279.990101) (xy 380.035817 -279.990101)
			(xy 380.035817 -279.938167) (xy 380.043942 -279.886872) (xy 380.05999 -279.837479) (xy 380.083568 -279.791205)
			(xy 380.114094 -279.749189) (xy 380.150817 -279.712466) (xy 380.192833 -279.68194) (xy 380.239107 -279.658362)
			(xy 380.2885 -279.642314) (xy 380.339795 -279.634189) (xy 380.391729 -279.634189) (xy 380.443024 -279.642314)
			(xy 380.492417 -279.658362) (xy 380.538691 -279.68194) (xy 380.580707 -279.712466) (xy 380.61743 -279.749189)
			(xy 380.647956 -279.791205) (xy 380.671534 -279.837479) (xy 380.687582 -279.886872) (xy 380.695707 -279.938167)
			(xy 380.696216 -279.964134) (xy 380.695707 -279.990101) (xy 380.687582 -280.041396) (xy 380.671534 -280.090789)
			(xy 380.647956 -280.137063) (xy 380.61743 -280.179079) (xy 380.580707 -280.215802) (xy 380.538691 -280.246328)
			(xy 380.492417 -280.269906) (xy 380.443024 -280.285954) (xy 380.391729 -280.294079) (xy 380.339795 -280.294079)
			(xy 380.2885 -280.285954) (xy 380.239107 -280.269906) (xy 380.192833 -280.246328) (xy 380.150817 -280.215802)
			(xy 380.114094 -280.179079) (xy 380.083568 -280.137063) (xy 380.05999 -280.090789) (xy 380.043942 -280.041396)
			(xy 380.035817 -279.990101) (xy 379.756161 -279.990101) (xy 379.748036 -280.041396) (xy 379.731988 -280.090789)
			(xy 379.70841 -280.137063) (xy 379.677884 -280.179079) (xy 379.641161 -280.215802) (xy 379.599145 -280.246328)
			(xy 379.552871 -280.269906) (xy 379.503478 -280.285954) (xy 379.452183 -280.294079) (xy 379.400249 -280.294079)
			(xy 379.348954 -280.285954) (xy 379.299561 -280.269906) (xy 379.253287 -280.246328) (xy 379.211271 -280.215802)
			(xy 379.174548 -280.179079) (xy 379.144022 -280.137063) (xy 379.120444 -280.090789) (xy 379.104396 -280.041396)
			(xy 379.096271 -279.990101) (xy 378.816361 -279.990101) (xy 378.808236 -280.041396) (xy 378.792188 -280.090789)
			(xy 378.76861 -280.137063) (xy 378.738084 -280.179079) (xy 378.701361 -280.215802) (xy 378.659345 -280.246328)
			(xy 378.613071 -280.269906) (xy 378.563678 -280.285954) (xy 378.512383 -280.294079) (xy 378.460449 -280.294079)
			(xy 378.409154 -280.285954) (xy 378.359761 -280.269906) (xy 378.313487 -280.246328) (xy 378.271471 -280.215802)
			(xy 378.234748 -280.179079) (xy 378.204222 -280.137063) (xy 378.180644 -280.090789) (xy 378.164596 -280.041396)
			(xy 378.156471 -279.990101) (xy 376.936467 -279.990101) (xy 376.928382 -280.041142) (xy 376.912334 -280.090535)
			(xy 376.888756 -280.136809) (xy 376.85823 -280.178825) (xy 376.821507 -280.215548) (xy 376.779491 -280.246074)
			(xy 376.733217 -280.269652) (xy 376.683824 -280.2857) (xy 376.632529 -280.293825) (xy 376.580595 -280.293825)
			(xy 376.5293 -280.2857) (xy 376.479907 -280.269652) (xy 376.433633 -280.246074) (xy 376.391617 -280.215548)
			(xy 376.354894 -280.178825) (xy 376.324368 -280.136809) (xy 376.30079 -280.090535) (xy 376.284742 -280.041142)
			(xy 376.276617 -279.989847) (xy 375.996966 -279.989847) (xy 375.996961 -279.990101) (xy 375.988836 -280.041396)
			(xy 375.972788 -280.090789) (xy 375.94921 -280.137063) (xy 375.918684 -280.179079) (xy 375.881961 -280.215802)
			(xy 375.839945 -280.246328) (xy 375.793671 -280.269906) (xy 375.744278 -280.285954) (xy 375.692983 -280.294079)
			(xy 375.641049 -280.294079) (xy 375.589754 -280.285954) (xy 375.540361 -280.269906) (xy 375.494087 -280.246328)
			(xy 375.452071 -280.215802) (xy 375.415348 -280.179079) (xy 375.384822 -280.137063) (xy 375.361244 -280.090789)
			(xy 375.345196 -280.041396) (xy 375.337071 -279.990101) (xy 375.056907 -279.990101) (xy 375.048782 -280.041396)
			(xy 375.032734 -280.090789) (xy 375.009156 -280.137063) (xy 374.97863 -280.179079) (xy 374.941907 -280.215802)
			(xy 374.899891 -280.246328) (xy 374.853617 -280.269906) (xy 374.804224 -280.285954) (xy 374.752929 -280.294079)
			(xy 374.700995 -280.294079) (xy 374.6497 -280.285954) (xy 374.600307 -280.269906) (xy 374.554033 -280.246328)
			(xy 374.512017 -280.215802) (xy 374.475294 -280.179079) (xy 374.444768 -280.137063) (xy 374.42119 -280.090789)
			(xy 374.405142 -280.041396) (xy 374.397017 -279.990101) (xy 374.117361 -279.990101) (xy 374.109236 -280.041396)
			(xy 374.093188 -280.090789) (xy 374.06961 -280.137063) (xy 374.039084 -280.179079) (xy 374.002361 -280.215802)
			(xy 373.960345 -280.246328) (xy 373.914071 -280.269906) (xy 373.864678 -280.285954) (xy 373.813383 -280.294079)
			(xy 373.761449 -280.294079) (xy 373.710154 -280.285954) (xy 373.660761 -280.269906) (xy 373.614487 -280.246328)
			(xy 373.572471 -280.215802) (xy 373.535748 -280.179079) (xy 373.505222 -280.137063) (xy 373.481644 -280.090789)
			(xy 373.465596 -280.041396) (xy 373.457471 -279.990101) (xy 373.177561 -279.990101) (xy 373.169436 -280.041396)
			(xy 373.153388 -280.090789) (xy 373.12981 -280.137063) (xy 373.099284 -280.179079) (xy 373.062561 -280.215802)
			(xy 373.020545 -280.246328) (xy 372.974271 -280.269906) (xy 372.924878 -280.285954) (xy 372.873583 -280.294079)
			(xy 372.821649 -280.294079) (xy 372.770354 -280.285954) (xy 372.720961 -280.269906) (xy 372.674687 -280.246328)
			(xy 372.632671 -280.215802) (xy 372.595948 -280.179079) (xy 372.565422 -280.137063) (xy 372.541844 -280.090789)
			(xy 372.525796 -280.041396) (xy 372.517671 -279.990101) (xy 372.237507 -279.990101) (xy 372.229382 -280.041396)
			(xy 372.213334 -280.090789) (xy 372.189756 -280.137063) (xy 372.15923 -280.179079) (xy 372.122507 -280.215802)
			(xy 372.080491 -280.246328) (xy 372.034217 -280.269906) (xy 371.984824 -280.285954) (xy 371.933529 -280.294079)
			(xy 371.881595 -280.294079) (xy 371.8303 -280.285954) (xy 371.780907 -280.269906) (xy 371.734633 -280.246328)
			(xy 371.692617 -280.215802) (xy 371.655894 -280.179079) (xy 371.625368 -280.137063) (xy 371.60179 -280.090789)
			(xy 371.585742 -280.041396) (xy 371.577617 -279.990101) (xy 371.297961 -279.990101) (xy 371.289836 -280.041396)
			(xy 371.273788 -280.090789) (xy 371.25021 -280.137063) (xy 371.219684 -280.179079) (xy 371.182961 -280.215802)
			(xy 371.140945 -280.246328) (xy 371.094671 -280.269906) (xy 371.045278 -280.285954) (xy 370.993983 -280.294079)
			(xy 370.942049 -280.294079) (xy 370.890754 -280.285954) (xy 370.841361 -280.269906) (xy 370.795087 -280.246328)
			(xy 370.753071 -280.215802) (xy 370.716348 -280.179079) (xy 370.685822 -280.137063) (xy 370.662244 -280.090789)
			(xy 370.646196 -280.041396) (xy 370.638071 -279.990101) (xy 369.418361 -279.990101) (xy 369.410236 -280.041396)
			(xy 369.394188 -280.090789) (xy 369.37061 -280.137063) (xy 369.340084 -280.179079) (xy 369.303361 -280.215802)
			(xy 369.261345 -280.246328) (xy 369.215071 -280.269906) (xy 369.165678 -280.285954) (xy 369.114383 -280.294079)
			(xy 369.062449 -280.294079) (xy 369.011154 -280.285954) (xy 368.961761 -280.269906) (xy 368.915487 -280.246328)
			(xy 368.873471 -280.215802) (xy 368.836748 -280.179079) (xy 368.806222 -280.137063) (xy 368.782644 -280.090789)
			(xy 368.766596 -280.041396) (xy 368.758471 -279.990101) (xy 368.478505 -279.990101) (xy 368.470388 -280.041352)
			(xy 368.454342 -280.090738) (xy 368.430768 -280.137006) (xy 368.400247 -280.179017) (xy 368.363529 -280.215736)
			(xy 368.32152 -280.24626) (xy 368.275253 -280.269836) (xy 368.225868 -280.285884) (xy 368.17458 -280.29401)
			(xy 368.148616 -280.294588) (xy 368.128078 -280.294277) (xy 368.087318 -280.289184) (xy 368.067336 -280.284428)
			(xy 368.052224 -280.281127) (xy 368.021351 -280.282784) (xy 367.992387 -280.293601) (xy 367.967985 -280.312586)
			(xy 367.95038 -280.338002) (xy 367.941183 -280.36752) (xy 367.94059 -280.38298) (xy 367.94059 -280.577036)
			(xy 367.95664 -280.598822) (xy 367.982165 -280.646531) (xy 367.99957 -280.697764) (xy 368.00839 -280.751149)
			(xy 368.00839 -280.804171) (xy 368.288317 -280.804171) (xy 368.288317 -280.752237) (xy 368.296442 -280.700942)
			(xy 368.31249 -280.651549) (xy 368.336068 -280.605275) (xy 368.366594 -280.563259) (xy 368.403317 -280.526536)
			(xy 368.445333 -280.49601) (xy 368.491607 -280.472432) (xy 368.541 -280.456384) (xy 368.592295 -280.448259)
			(xy 368.644229 -280.448259) (xy 368.695524 -280.456384) (xy 368.744917 -280.472432) (xy 368.791191 -280.49601)
			(xy 368.833207 -280.526536) (xy 368.86993 -280.563259) (xy 368.900456 -280.605275) (xy 368.924034 -280.651549)
			(xy 368.940082 -280.700942) (xy 368.948207 -280.752237) (xy 368.948716 -280.778204) (xy 368.948207 -280.804171)
			(xy 369.228117 -280.804171) (xy 369.228117 -280.752237) (xy 369.236242 -280.700942) (xy 369.25229 -280.651549)
			(xy 369.275868 -280.605275) (xy 369.306394 -280.563259) (xy 369.343117 -280.526536) (xy 369.385133 -280.49601)
			(xy 369.431407 -280.472432) (xy 369.4808 -280.456384) (xy 369.532095 -280.448259) (xy 369.584029 -280.448259)
			(xy 369.635324 -280.456384) (xy 369.684717 -280.472432) (xy 369.730991 -280.49601) (xy 369.773007 -280.526536)
			(xy 369.80973 -280.563259) (xy 369.840256 -280.605275) (xy 369.863834 -280.651549) (xy 369.879882 -280.700942)
			(xy 369.888007 -280.752237) (xy 369.888516 -280.778204) (xy 369.888007 -280.804171) (xy 370.167917 -280.804171)
			(xy 370.167917 -280.752237) (xy 370.176042 -280.700942) (xy 370.19209 -280.651549) (xy 370.215668 -280.605275)
			(xy 370.246194 -280.563259) (xy 370.282917 -280.526536) (xy 370.324933 -280.49601) (xy 370.371207 -280.472432)
			(xy 370.4206 -280.456384) (xy 370.471895 -280.448259) (xy 370.523829 -280.448259) (xy 370.575124 -280.456384)
			(xy 370.624517 -280.472432) (xy 370.670791 -280.49601) (xy 370.712807 -280.526536) (xy 370.74953 -280.563259)
			(xy 370.780056 -280.605275) (xy 370.803634 -280.651549) (xy 370.819682 -280.700942) (xy 370.827807 -280.752237)
			(xy 370.828316 -280.778204) (xy 370.827807 -280.804171) (xy 371.107717 -280.804171) (xy 371.107717 -280.752237)
			(xy 371.115842 -280.700942) (xy 371.13189 -280.651549) (xy 371.155468 -280.605275) (xy 371.185994 -280.563259)
			(xy 371.222717 -280.526536) (xy 371.264733 -280.49601) (xy 371.311007 -280.472432) (xy 371.3604 -280.456384)
			(xy 371.411695 -280.448259) (xy 371.463629 -280.448259) (xy 371.514924 -280.456384) (xy 371.564317 -280.472432)
			(xy 371.610591 -280.49601) (xy 371.652607 -280.526536) (xy 371.68933 -280.563259) (xy 371.719856 -280.605275)
			(xy 371.743434 -280.651549) (xy 371.759482 -280.700942) (xy 371.767607 -280.752237) (xy 371.768116 -280.778204)
			(xy 371.767607 -280.804171) (xy 372.047517 -280.804171) (xy 372.047517 -280.752237) (xy 372.055642 -280.700942)
			(xy 372.07169 -280.651549) (xy 372.095268 -280.605275) (xy 372.125794 -280.563259) (xy 372.162517 -280.526536)
			(xy 372.204533 -280.49601) (xy 372.250807 -280.472432) (xy 372.3002 -280.456384) (xy 372.351495 -280.448259)
			(xy 372.403429 -280.448259) (xy 372.454724 -280.456384) (xy 372.504117 -280.472432) (xy 372.550391 -280.49601)
			(xy 372.592407 -280.526536) (xy 372.62913 -280.563259) (xy 372.659656 -280.605275) (xy 372.683234 -280.651549)
			(xy 372.699282 -280.700942) (xy 372.707407 -280.752237) (xy 372.707916 -280.778204) (xy 372.707407 -280.804171)
			(xy 372.987317 -280.804171) (xy 372.987317 -280.752237) (xy 372.995442 -280.700942) (xy 373.01149 -280.651549)
			(xy 373.035068 -280.605275) (xy 373.065594 -280.563259) (xy 373.102317 -280.526536) (xy 373.144333 -280.49601)
			(xy 373.190607 -280.472432) (xy 373.24 -280.456384) (xy 373.291295 -280.448259) (xy 373.343229 -280.448259)
			(xy 373.394524 -280.456384) (xy 373.443917 -280.472432) (xy 373.490191 -280.49601) (xy 373.532207 -280.526536)
			(xy 373.56893 -280.563259) (xy 373.599456 -280.605275) (xy 373.623034 -280.651549) (xy 373.639082 -280.700942)
			(xy 373.647207 -280.752237) (xy 373.647716 -280.778204) (xy 373.647207 -280.804171) (xy 373.927371 -280.804171)
			(xy 373.927371 -280.752237) (xy 373.935496 -280.700942) (xy 373.951544 -280.651549) (xy 373.975122 -280.605275)
			(xy 374.005648 -280.563259) (xy 374.042371 -280.526536) (xy 374.084387 -280.49601) (xy 374.130661 -280.472432)
			(xy 374.180054 -280.456384) (xy 374.231349 -280.448259) (xy 374.283283 -280.448259) (xy 374.334578 -280.456384)
			(xy 374.383971 -280.472432) (xy 374.430245 -280.49601) (xy 374.472261 -280.526536) (xy 374.508984 -280.563259)
			(xy 374.53951 -280.605275) (xy 374.563088 -280.651549) (xy 374.579136 -280.700942) (xy 374.587261 -280.752237)
			(xy 374.58777 -280.778204) (xy 374.587261 -280.804171) (xy 374.867171 -280.804171) (xy 374.867171 -280.752237)
			(xy 374.875296 -280.700942) (xy 374.891344 -280.651549) (xy 374.914922 -280.605275) (xy 374.945448 -280.563259)
			(xy 374.982171 -280.526536) (xy 375.024187 -280.49601) (xy 375.070461 -280.472432) (xy 375.119854 -280.456384)
			(xy 375.171149 -280.448259) (xy 375.223083 -280.448259) (xy 375.274378 -280.456384) (xy 375.323771 -280.472432)
			(xy 375.370045 -280.49601) (xy 375.412061 -280.526536) (xy 375.448784 -280.563259) (xy 375.47931 -280.605275)
			(xy 375.502888 -280.651549) (xy 375.518936 -280.700942) (xy 375.527061 -280.752237) (xy 375.52757 -280.778204)
			(xy 375.527061 -280.804171) (xy 375.806971 -280.804171) (xy 375.806971 -280.752237) (xy 375.815096 -280.700942)
			(xy 375.831144 -280.651549) (xy 375.854722 -280.605275) (xy 375.885248 -280.563259) (xy 375.921971 -280.526536)
			(xy 375.963987 -280.49601) (xy 376.010261 -280.472432) (xy 376.059654 -280.456384) (xy 376.110949 -280.448259)
			(xy 376.162883 -280.448259) (xy 376.214178 -280.456384) (xy 376.263571 -280.472432) (xy 376.309845 -280.49601)
			(xy 376.351861 -280.526536) (xy 376.388584 -280.563259) (xy 376.41911 -280.605275) (xy 376.442688 -280.651549)
			(xy 376.458736 -280.700942) (xy 376.466861 -280.752237) (xy 376.46737 -280.778204) (xy 376.466861 -280.804171)
			(xy 376.746771 -280.804171) (xy 376.746771 -280.752237) (xy 376.754896 -280.700942) (xy 376.770944 -280.651549)
			(xy 376.794522 -280.605275) (xy 376.825048 -280.563259) (xy 376.861771 -280.526536) (xy 376.903787 -280.49601)
			(xy 376.950061 -280.472432) (xy 376.999454 -280.456384) (xy 377.050749 -280.448259) (xy 377.102683 -280.448259)
			(xy 377.153978 -280.456384) (xy 377.203371 -280.472432) (xy 377.249645 -280.49601) (xy 377.291661 -280.526536)
			(xy 377.328384 -280.563259) (xy 377.35891 -280.605275) (xy 377.382488 -280.651549) (xy 377.398536 -280.700942)
			(xy 377.406661 -280.752237) (xy 377.40717 -280.778204) (xy 377.406661 -280.804171) (xy 377.686571 -280.804171)
			(xy 377.686571 -280.752237) (xy 377.694696 -280.700942) (xy 377.710744 -280.651549) (xy 377.734322 -280.605275)
			(xy 377.764848 -280.563259) (xy 377.801571 -280.526536) (xy 377.843587 -280.49601) (xy 377.889861 -280.472432)
			(xy 377.939254 -280.456384) (xy 377.990549 -280.448259) (xy 378.042483 -280.448259) (xy 378.093778 -280.456384)
			(xy 378.143171 -280.472432) (xy 378.189445 -280.49601) (xy 378.231461 -280.526536) (xy 378.268184 -280.563259)
			(xy 378.29871 -280.605275) (xy 378.322288 -280.651549) (xy 378.338336 -280.700942) (xy 378.346461 -280.752237)
			(xy 378.34697 -280.778204) (xy 378.346461 -280.804171) (xy 378.626117 -280.804171) (xy 378.626117 -280.752237)
			(xy 378.634242 -280.700942) (xy 378.65029 -280.651549) (xy 378.673868 -280.605275) (xy 378.704394 -280.563259)
			(xy 378.741117 -280.526536) (xy 378.783133 -280.49601) (xy 378.829407 -280.472432) (xy 378.8788 -280.456384)
			(xy 378.930095 -280.448259) (xy 378.982029 -280.448259) (xy 379.033324 -280.456384) (xy 379.082717 -280.472432)
			(xy 379.128991 -280.49601) (xy 379.171007 -280.526536) (xy 379.20773 -280.563259) (xy 379.238256 -280.605275)
			(xy 379.261834 -280.651549) (xy 379.277882 -280.700942) (xy 379.286007 -280.752237) (xy 379.286516 -280.778204)
			(xy 379.286007 -280.804171) (xy 379.565917 -280.804171) (xy 379.565917 -280.752237) (xy 379.574042 -280.700942)
			(xy 379.59009 -280.651549) (xy 379.613668 -280.605275) (xy 379.644194 -280.563259) (xy 379.680917 -280.526536)
			(xy 379.722933 -280.49601) (xy 379.769207 -280.472432) (xy 379.8186 -280.456384) (xy 379.869895 -280.448259)
			(xy 379.921829 -280.448259) (xy 379.973124 -280.456384) (xy 380.022517 -280.472432) (xy 380.068791 -280.49601)
			(xy 380.110807 -280.526536) (xy 380.14753 -280.563259) (xy 380.178056 -280.605275) (xy 380.201634 -280.651549)
			(xy 380.217682 -280.700942) (xy 380.225807 -280.752237) (xy 380.226316 -280.778204) (xy 380.225807 -280.804171)
			(xy 380.505717 -280.804171) (xy 380.505717 -280.752237) (xy 380.513842 -280.700942) (xy 380.52989 -280.651549)
			(xy 380.553468 -280.605275) (xy 380.583994 -280.563259) (xy 380.620717 -280.526536) (xy 380.662733 -280.49601)
			(xy 380.709007 -280.472432) (xy 380.7584 -280.456384) (xy 380.809695 -280.448259) (xy 380.861629 -280.448259)
			(xy 380.912924 -280.456384) (xy 380.962317 -280.472432) (xy 381.008591 -280.49601) (xy 381.050607 -280.526536)
			(xy 381.08733 -280.563259) (xy 381.117856 -280.605275) (xy 381.141434 -280.651549) (xy 381.157482 -280.700942)
			(xy 381.165607 -280.752237) (xy 381.166116 -280.778204) (xy 381.165607 -280.804171) (xy 381.445517 -280.804171)
			(xy 381.445517 -280.752237) (xy 381.453642 -280.700942) (xy 381.46969 -280.651549) (xy 381.493268 -280.605275)
			(xy 381.523794 -280.563259) (xy 381.560517 -280.526536) (xy 381.602533 -280.49601) (xy 381.648807 -280.472432)
			(xy 381.6982 -280.456384) (xy 381.749495 -280.448259) (xy 381.801429 -280.448259) (xy 381.852724 -280.456384)
			(xy 381.902117 -280.472432) (xy 381.948391 -280.49601) (xy 381.990407 -280.526536) (xy 382.02713 -280.563259)
			(xy 382.057656 -280.605275) (xy 382.081234 -280.651549) (xy 382.097282 -280.700942) (xy 382.105407 -280.752237)
			(xy 382.105916 -280.778204) (xy 382.105407 -280.804171) (xy 382.097282 -280.855466) (xy 382.081234 -280.904859)
			(xy 382.057656 -280.951133) (xy 382.02713 -280.993149) (xy 381.990407 -281.029872) (xy 381.948391 -281.060398)
			(xy 381.902117 -281.083976) (xy 381.852724 -281.100024) (xy 381.801429 -281.108149) (xy 381.749495 -281.108149)
			(xy 381.6982 -281.100024) (xy 381.648807 -281.083976) (xy 381.602533 -281.060398) (xy 381.560517 -281.029872)
			(xy 381.523794 -280.993149) (xy 381.493268 -280.951133) (xy 381.46969 -280.904859) (xy 381.453642 -280.855466)
			(xy 381.445517 -280.804171) (xy 381.165607 -280.804171) (xy 381.157482 -280.855466) (xy 381.141434 -280.904859)
			(xy 381.117856 -280.951133) (xy 381.08733 -280.993149) (xy 381.050607 -281.029872) (xy 381.008591 -281.060398)
			(xy 380.962317 -281.083976) (xy 380.912924 -281.100024) (xy 380.861629 -281.108149) (xy 380.809695 -281.108149)
			(xy 380.7584 -281.100024) (xy 380.709007 -281.083976) (xy 380.662733 -281.060398) (xy 380.620717 -281.029872)
			(xy 380.583994 -280.993149) (xy 380.553468 -280.951133) (xy 380.52989 -280.904859) (xy 380.513842 -280.855466)
			(xy 380.505717 -280.804171) (xy 380.225807 -280.804171) (xy 380.217682 -280.855466) (xy 380.201634 -280.904859)
			(xy 380.178056 -280.951133) (xy 380.14753 -280.993149) (xy 380.110807 -281.029872) (xy 380.068791 -281.060398)
			(xy 380.022517 -281.083976) (xy 379.973124 -281.100024) (xy 379.921829 -281.108149) (xy 379.869895 -281.108149)
			(xy 379.8186 -281.100024) (xy 379.769207 -281.083976) (xy 379.722933 -281.060398) (xy 379.680917 -281.029872)
			(xy 379.644194 -280.993149) (xy 379.613668 -280.951133) (xy 379.59009 -280.904859) (xy 379.574042 -280.855466)
			(xy 379.565917 -280.804171) (xy 379.286007 -280.804171) (xy 379.277882 -280.855466) (xy 379.261834 -280.904859)
			(xy 379.238256 -280.951133) (xy 379.20773 -280.993149) (xy 379.171007 -281.029872) (xy 379.128991 -281.060398)
			(xy 379.082717 -281.083976) (xy 379.033324 -281.100024) (xy 378.982029 -281.108149) (xy 378.930095 -281.108149)
			(xy 378.8788 -281.100024) (xy 378.829407 -281.083976) (xy 378.783133 -281.060398) (xy 378.741117 -281.029872)
			(xy 378.704394 -280.993149) (xy 378.673868 -280.951133) (xy 378.65029 -280.904859) (xy 378.634242 -280.855466)
			(xy 378.626117 -280.804171) (xy 378.346461 -280.804171) (xy 378.338336 -280.855466) (xy 378.322288 -280.904859)
			(xy 378.29871 -280.951133) (xy 378.268184 -280.993149) (xy 378.231461 -281.029872) (xy 378.189445 -281.060398)
			(xy 378.143171 -281.083976) (xy 378.093778 -281.100024) (xy 378.042483 -281.108149) (xy 377.990549 -281.108149)
			(xy 377.939254 -281.100024) (xy 377.889861 -281.083976) (xy 377.843587 -281.060398) (xy 377.801571 -281.029872)
			(xy 377.764848 -280.993149) (xy 377.734322 -280.951133) (xy 377.710744 -280.904859) (xy 377.694696 -280.855466)
			(xy 377.686571 -280.804171) (xy 377.406661 -280.804171) (xy 377.398536 -280.855466) (xy 377.382488 -280.904859)
			(xy 377.35891 -280.951133) (xy 377.328384 -280.993149) (xy 377.291661 -281.029872) (xy 377.249645 -281.060398)
			(xy 377.203371 -281.083976) (xy 377.153978 -281.100024) (xy 377.102683 -281.108149) (xy 377.050749 -281.108149)
			(xy 376.999454 -281.100024) (xy 376.950061 -281.083976) (xy 376.903787 -281.060398) (xy 376.861771 -281.029872)
			(xy 376.825048 -280.993149) (xy 376.794522 -280.951133) (xy 376.770944 -280.904859) (xy 376.754896 -280.855466)
			(xy 376.746771 -280.804171) (xy 376.466861 -280.804171) (xy 376.458736 -280.855466) (xy 376.442688 -280.904859)
			(xy 376.41911 -280.951133) (xy 376.388584 -280.993149) (xy 376.351861 -281.029872) (xy 376.309845 -281.060398)
			(xy 376.263571 -281.083976) (xy 376.214178 -281.100024) (xy 376.162883 -281.108149) (xy 376.110949 -281.108149)
			(xy 376.059654 -281.100024) (xy 376.010261 -281.083976) (xy 375.963987 -281.060398) (xy 375.921971 -281.029872)
			(xy 375.885248 -280.993149) (xy 375.854722 -280.951133) (xy 375.831144 -280.904859) (xy 375.815096 -280.855466)
			(xy 375.806971 -280.804171) (xy 375.527061 -280.804171) (xy 375.518936 -280.855466) (xy 375.502888 -280.904859)
			(xy 375.47931 -280.951133) (xy 375.448784 -280.993149) (xy 375.412061 -281.029872) (xy 375.370045 -281.060398)
			(xy 375.323771 -281.083976) (xy 375.274378 -281.100024) (xy 375.223083 -281.108149) (xy 375.171149 -281.108149)
			(xy 375.119854 -281.100024) (xy 375.070461 -281.083976) (xy 375.024187 -281.060398) (xy 374.982171 -281.029872)
			(xy 374.945448 -280.993149) (xy 374.914922 -280.951133) (xy 374.891344 -280.904859) (xy 374.875296 -280.855466)
			(xy 374.867171 -280.804171) (xy 374.587261 -280.804171) (xy 374.579136 -280.855466) (xy 374.563088 -280.904859)
			(xy 374.53951 -280.951133) (xy 374.508984 -280.993149) (xy 374.472261 -281.029872) (xy 374.430245 -281.060398)
			(xy 374.383971 -281.083976) (xy 374.334578 -281.100024) (xy 374.283283 -281.108149) (xy 374.231349 -281.108149)
			(xy 374.180054 -281.100024) (xy 374.130661 -281.083976) (xy 374.084387 -281.060398) (xy 374.042371 -281.029872)
			(xy 374.005648 -280.993149) (xy 373.975122 -280.951133) (xy 373.951544 -280.904859) (xy 373.935496 -280.855466)
			(xy 373.927371 -280.804171) (xy 373.647207 -280.804171) (xy 373.639082 -280.855466) (xy 373.623034 -280.904859)
			(xy 373.599456 -280.951133) (xy 373.56893 -280.993149) (xy 373.532207 -281.029872) (xy 373.490191 -281.060398)
			(xy 373.443917 -281.083976) (xy 373.394524 -281.100024) (xy 373.343229 -281.108149) (xy 373.291295 -281.108149)
			(xy 373.24 -281.100024) (xy 373.190607 -281.083976) (xy 373.144333 -281.060398) (xy 373.102317 -281.029872)
			(xy 373.065594 -280.993149) (xy 373.035068 -280.951133) (xy 373.01149 -280.904859) (xy 372.995442 -280.855466)
			(xy 372.987317 -280.804171) (xy 372.707407 -280.804171) (xy 372.699282 -280.855466) (xy 372.683234 -280.904859)
			(xy 372.659656 -280.951133) (xy 372.62913 -280.993149) (xy 372.592407 -281.029872) (xy 372.550391 -281.060398)
			(xy 372.504117 -281.083976) (xy 372.454724 -281.100024) (xy 372.403429 -281.108149) (xy 372.351495 -281.108149)
			(xy 372.3002 -281.100024) (xy 372.250807 -281.083976) (xy 372.204533 -281.060398) (xy 372.162517 -281.029872)
			(xy 372.125794 -280.993149) (xy 372.095268 -280.951133) (xy 372.07169 -280.904859) (xy 372.055642 -280.855466)
			(xy 372.047517 -280.804171) (xy 371.767607 -280.804171) (xy 371.759482 -280.855466) (xy 371.743434 -280.904859)
			(xy 371.719856 -280.951133) (xy 371.68933 -280.993149) (xy 371.652607 -281.029872) (xy 371.610591 -281.060398)
			(xy 371.564317 -281.083976) (xy 371.514924 -281.100024) (xy 371.463629 -281.108149) (xy 371.411695 -281.108149)
			(xy 371.3604 -281.100024) (xy 371.311007 -281.083976) (xy 371.264733 -281.060398) (xy 371.222717 -281.029872)
			(xy 371.185994 -280.993149) (xy 371.155468 -280.951133) (xy 371.13189 -280.904859) (xy 371.115842 -280.855466)
			(xy 371.107717 -280.804171) (xy 370.827807 -280.804171) (xy 370.819682 -280.855466) (xy 370.803634 -280.904859)
			(xy 370.780056 -280.951133) (xy 370.74953 -280.993149) (xy 370.712807 -281.029872) (xy 370.670791 -281.060398)
			(xy 370.624517 -281.083976) (xy 370.575124 -281.100024) (xy 370.523829 -281.108149) (xy 370.471895 -281.108149)
			(xy 370.4206 -281.100024) (xy 370.371207 -281.083976) (xy 370.324933 -281.060398) (xy 370.282917 -281.029872)
			(xy 370.246194 -280.993149) (xy 370.215668 -280.951133) (xy 370.19209 -280.904859) (xy 370.176042 -280.855466)
			(xy 370.167917 -280.804171) (xy 369.888007 -280.804171) (xy 369.879882 -280.855466) (xy 369.863834 -280.904859)
			(xy 369.840256 -280.951133) (xy 369.80973 -280.993149) (xy 369.773007 -281.029872) (xy 369.730991 -281.060398)
			(xy 369.684717 -281.083976) (xy 369.635324 -281.100024) (xy 369.584029 -281.108149) (xy 369.532095 -281.108149)
			(xy 369.4808 -281.100024) (xy 369.431407 -281.083976) (xy 369.385133 -281.060398) (xy 369.343117 -281.029872)
			(xy 369.306394 -280.993149) (xy 369.275868 -280.951133) (xy 369.25229 -280.904859) (xy 369.236242 -280.855466)
			(xy 369.228117 -280.804171) (xy 368.948207 -280.804171) (xy 368.940082 -280.855466) (xy 368.924034 -280.904859)
			(xy 368.900456 -280.951133) (xy 368.86993 -280.993149) (xy 368.833207 -281.029872) (xy 368.791191 -281.060398)
			(xy 368.744917 -281.083976) (xy 368.695524 -281.100024) (xy 368.644229 -281.108149) (xy 368.592295 -281.108149)
			(xy 368.541 -281.100024) (xy 368.491607 -281.083976) (xy 368.445333 -281.060398) (xy 368.403317 -281.029872)
			(xy 368.366594 -280.993149) (xy 368.336068 -280.951133) (xy 368.31249 -280.904859) (xy 368.296442 -280.855466)
			(xy 368.288317 -280.804171) (xy 368.00839 -280.804171) (xy 368.00839 -280.805257) (xy 367.999568 -280.858642)
			(xy 367.982162 -280.909874) (xy 367.956637 -280.957584) (xy 367.94059 -280.979372) (xy 367.94059 -281.173174)
			(xy 367.94114 -281.188625) (xy 367.950386 -281.218113) (xy 367.968012 -281.243496) (xy 367.992411 -281.262461)
			(xy 368.021359 -281.273279) (xy 368.052216 -281.274963) (xy 368.067336 -281.271726) (xy 368.087319 -281.266974)
			(xy 368.128078 -281.261882) (xy 368.148616 -281.261566) (xy 368.174581 -281.262076) (xy 368.225871 -281.270202)
			(xy 368.275258 -281.286251) (xy 368.321527 -281.309828) (xy 368.363538 -281.340353) (xy 368.400257 -281.377074)
			(xy 368.43078 -281.419086) (xy 368.454355 -281.465357) (xy 368.470402 -281.514745) (xy 368.478525 -281.566035)
			(xy 368.478525 -281.617965) (xy 368.478522 -281.617987) (xy 368.758471 -281.617987) (xy 368.758471 -281.566053)
			(xy 368.766596 -281.514758) (xy 368.782644 -281.465365) (xy 368.806222 -281.419091) (xy 368.836748 -281.377075)
			(xy 368.873471 -281.340352) (xy 368.915487 -281.309826) (xy 368.961761 -281.286248) (xy 369.011154 -281.2702)
			(xy 369.062449 -281.262075) (xy 369.114383 -281.262075) (xy 369.165678 -281.2702) (xy 369.215071 -281.286248)
			(xy 369.261345 -281.309826) (xy 369.303361 -281.340352) (xy 369.340084 -281.377075) (xy 369.37061 -281.419091)
			(xy 369.394188 -281.465365) (xy 369.410236 -281.514758) (xy 369.418361 -281.566053) (xy 369.41887 -281.59202)
			(xy 369.418361 -281.617987) (xy 369.698271 -281.617987) (xy 369.698271 -281.566053) (xy 369.706396 -281.514758)
			(xy 369.722444 -281.465365) (xy 369.746022 -281.419091) (xy 369.776548 -281.377075) (xy 369.813271 -281.340352)
			(xy 369.855287 -281.309826) (xy 369.901561 -281.286248) (xy 369.950954 -281.2702) (xy 370.002249 -281.262075)
			(xy 370.054183 -281.262075) (xy 370.105478 -281.2702) (xy 370.154871 -281.286248) (xy 370.201145 -281.309826)
			(xy 370.243161 -281.340352) (xy 370.279884 -281.377075) (xy 370.31041 -281.419091) (xy 370.333988 -281.465365)
			(xy 370.350036 -281.514758) (xy 370.358161 -281.566053) (xy 370.35867 -281.59202) (xy 370.358161 -281.617987)
			(xy 370.638071 -281.617987) (xy 370.638071 -281.566053) (xy 370.646196 -281.514758) (xy 370.662244 -281.465365)
			(xy 370.685822 -281.419091) (xy 370.716348 -281.377075) (xy 370.753071 -281.340352) (xy 370.795087 -281.309826)
			(xy 370.841361 -281.286248) (xy 370.890754 -281.2702) (xy 370.942049 -281.262075) (xy 370.993983 -281.262075)
			(xy 371.045278 -281.2702) (xy 371.094671 -281.286248) (xy 371.140945 -281.309826) (xy 371.182961 -281.340352)
			(xy 371.219684 -281.377075) (xy 371.25021 -281.419091) (xy 371.273788 -281.465365) (xy 371.289836 -281.514758)
			(xy 371.297961 -281.566053) (xy 371.29847 -281.59202) (xy 371.297961 -281.617987) (xy 371.577871 -281.617987)
			(xy 371.577871 -281.566053) (xy 371.585996 -281.514758) (xy 371.602044 -281.465365) (xy 371.625622 -281.419091)
			(xy 371.656148 -281.377075) (xy 371.692871 -281.340352) (xy 371.734887 -281.309826) (xy 371.781161 -281.286248)
			(xy 371.830554 -281.2702) (xy 371.881849 -281.262075) (xy 371.933783 -281.262075) (xy 371.985078 -281.2702)
			(xy 372.034471 -281.286248) (xy 372.080745 -281.309826) (xy 372.122761 -281.340352) (xy 372.159484 -281.377075)
			(xy 372.19001 -281.419091) (xy 372.213588 -281.465365) (xy 372.229636 -281.514758) (xy 372.237761 -281.566053)
			(xy 372.23827 -281.59202) (xy 372.237761 -281.617987) (xy 372.517671 -281.617987) (xy 372.517671 -281.566053)
			(xy 372.525796 -281.514758) (xy 372.541844 -281.465365) (xy 372.565422 -281.419091) (xy 372.595948 -281.377075)
			(xy 372.632671 -281.340352) (xy 372.674687 -281.309826) (xy 372.720961 -281.286248) (xy 372.770354 -281.2702)
			(xy 372.821649 -281.262075) (xy 372.873583 -281.262075) (xy 372.924878 -281.2702) (xy 372.974271 -281.286248)
			(xy 373.020545 -281.309826) (xy 373.062561 -281.340352) (xy 373.099284 -281.377075) (xy 373.12981 -281.419091)
			(xy 373.153388 -281.465365) (xy 373.169436 -281.514758) (xy 373.177561 -281.566053) (xy 373.17807 -281.59202)
			(xy 373.177561 -281.617987) (xy 373.457471 -281.617987) (xy 373.457471 -281.566053) (xy 373.465596 -281.514758)
			(xy 373.481644 -281.465365) (xy 373.505222 -281.419091) (xy 373.535748 -281.377075) (xy 373.572471 -281.340352)
			(xy 373.614487 -281.309826) (xy 373.660761 -281.286248) (xy 373.710154 -281.2702) (xy 373.761449 -281.262075)
			(xy 373.813383 -281.262075) (xy 373.864678 -281.2702) (xy 373.914071 -281.286248) (xy 373.960345 -281.309826)
			(xy 374.002361 -281.340352) (xy 374.039084 -281.377075) (xy 374.06961 -281.419091) (xy 374.093188 -281.465365)
			(xy 374.109236 -281.514758) (xy 374.117361 -281.566053) (xy 374.11787 -281.59202) (xy 374.117361 -281.617987)
			(xy 374.397017 -281.617987) (xy 374.397017 -281.566053) (xy 374.405142 -281.514758) (xy 374.42119 -281.465365)
			(xy 374.444768 -281.419091) (xy 374.475294 -281.377075) (xy 374.512017 -281.340352) (xy 374.554033 -281.309826)
			(xy 374.600307 -281.286248) (xy 374.6497 -281.2702) (xy 374.700995 -281.262075) (xy 374.752929 -281.262075)
			(xy 374.804224 -281.2702) (xy 374.853617 -281.286248) (xy 374.899891 -281.309826) (xy 374.941907 -281.340352)
			(xy 374.97863 -281.377075) (xy 375.009156 -281.419091) (xy 375.032734 -281.465365) (xy 375.048782 -281.514758)
			(xy 375.056907 -281.566053) (xy 375.057416 -281.59202) (xy 375.056912 -281.617733) (xy 375.336817 -281.617733)
			(xy 375.336817 -281.565799) (xy 375.344942 -281.514504) (xy 375.36099 -281.465111) (xy 375.384568 -281.418837)
			(xy 375.415094 -281.376821) (xy 375.451817 -281.340098) (xy 375.493833 -281.309572) (xy 375.540107 -281.285994)
			(xy 375.5895 -281.269946) (xy 375.640795 -281.261821) (xy 375.692729 -281.261821) (xy 375.744024 -281.269946)
			(xy 375.793417 -281.285994) (xy 375.839691 -281.309572) (xy 375.881707 -281.340098) (xy 375.91843 -281.376821)
			(xy 375.948956 -281.418837) (xy 375.972534 -281.465111) (xy 375.988582 -281.514504) (xy 375.996707 -281.565799)
			(xy 375.997216 -281.591766) (xy 375.996707 -281.617733) (xy 375.996667 -281.617987) (xy 376.276871 -281.617987)
			(xy 376.276871 -281.566053) (xy 376.284996 -281.514758) (xy 376.301044 -281.465365) (xy 376.324622 -281.419091)
			(xy 376.355148 -281.377075) (xy 376.391871 -281.340352) (xy 376.433887 -281.309826) (xy 376.480161 -281.286248)
			(xy 376.529554 -281.2702) (xy 376.580849 -281.262075) (xy 376.632783 -281.262075) (xy 376.684078 -281.2702)
			(xy 376.733471 -281.286248) (xy 376.779745 -281.309826) (xy 376.821761 -281.340352) (xy 376.858484 -281.377075)
			(xy 376.88901 -281.419091) (xy 376.912588 -281.465365) (xy 376.928636 -281.514758) (xy 376.936761 -281.566053)
			(xy 376.93727 -281.59202) (xy 376.936761 -281.617987) (xy 377.216417 -281.617987) (xy 377.216417 -281.566053)
			(xy 377.224542 -281.514758) (xy 377.24059 -281.465365) (xy 377.264168 -281.419091) (xy 377.294694 -281.377075)
			(xy 377.331417 -281.340352) (xy 377.373433 -281.309826) (xy 377.419707 -281.286248) (xy 377.4691 -281.2702)
			(xy 377.520395 -281.262075) (xy 377.572329 -281.262075) (xy 377.623624 -281.2702) (xy 377.673017 -281.286248)
			(xy 377.719291 -281.309826) (xy 377.761307 -281.340352) (xy 377.79803 -281.377075) (xy 377.828556 -281.419091)
			(xy 377.852134 -281.465365) (xy 377.868182 -281.514758) (xy 377.876307 -281.566053) (xy 377.876816 -281.59202)
			(xy 377.876307 -281.617987) (xy 378.156471 -281.617987) (xy 378.156471 -281.566053) (xy 378.164596 -281.514758)
			(xy 378.180644 -281.465365) (xy 378.204222 -281.419091) (xy 378.234748 -281.377075) (xy 378.271471 -281.340352)
			(xy 378.313487 -281.309826) (xy 378.359761 -281.286248) (xy 378.409154 -281.2702) (xy 378.460449 -281.262075)
			(xy 378.512383 -281.262075) (xy 378.563678 -281.2702) (xy 378.613071 -281.286248) (xy 378.659345 -281.309826)
			(xy 378.701361 -281.340352) (xy 378.738084 -281.377075) (xy 378.76861 -281.419091) (xy 378.792188 -281.465365)
			(xy 378.808236 -281.514758) (xy 378.816361 -281.566053) (xy 378.81687 -281.59202) (xy 378.816361 -281.617987)
			(xy 379.096271 -281.617987) (xy 379.096271 -281.566053) (xy 379.104396 -281.514758) (xy 379.120444 -281.465365)
			(xy 379.144022 -281.419091) (xy 379.174548 -281.377075) (xy 379.211271 -281.340352) (xy 379.253287 -281.309826)
			(xy 379.299561 -281.286248) (xy 379.348954 -281.2702) (xy 379.400249 -281.262075) (xy 379.452183 -281.262075)
			(xy 379.503478 -281.2702) (xy 379.552871 -281.286248) (xy 379.599145 -281.309826) (xy 379.641161 -281.340352)
			(xy 379.677884 -281.377075) (xy 379.70841 -281.419091) (xy 379.731988 -281.465365) (xy 379.748036 -281.514758)
			(xy 379.756161 -281.566053) (xy 379.75667 -281.59202) (xy 379.756161 -281.617987) (xy 380.036071 -281.617987)
			(xy 380.036071 -281.566053) (xy 380.044196 -281.514758) (xy 380.060244 -281.465365) (xy 380.083822 -281.419091)
			(xy 380.114348 -281.377075) (xy 380.151071 -281.340352) (xy 380.193087 -281.309826) (xy 380.239361 -281.286248)
			(xy 380.288754 -281.2702) (xy 380.340049 -281.262075) (xy 380.391983 -281.262075) (xy 380.443278 -281.2702)
			(xy 380.492671 -281.286248) (xy 380.538945 -281.309826) (xy 380.580961 -281.340352) (xy 380.617684 -281.377075)
			(xy 380.64821 -281.419091) (xy 380.671788 -281.465365) (xy 380.687836 -281.514758) (xy 380.695961 -281.566053)
			(xy 380.69647 -281.59202) (xy 380.695961 -281.617987) (xy 380.975871 -281.617987) (xy 380.975871 -281.566053)
			(xy 380.983996 -281.514758) (xy 381.000044 -281.465365) (xy 381.023622 -281.419091) (xy 381.054148 -281.377075)
			(xy 381.090871 -281.340352) (xy 381.132887 -281.309826) (xy 381.179161 -281.286248) (xy 381.228554 -281.2702)
			(xy 381.279849 -281.262075) (xy 381.331783 -281.262075) (xy 381.383078 -281.2702) (xy 381.432471 -281.286248)
			(xy 381.478745 -281.309826) (xy 381.520761 -281.340352) (xy 381.557484 -281.377075) (xy 381.58801 -281.419091)
			(xy 381.611588 -281.465365) (xy 381.627636 -281.514758) (xy 381.635761 -281.566053) (xy 381.63627 -281.59202)
			(xy 381.635761 -281.617987) (xy 381.915671 -281.617987) (xy 381.915671 -281.566053) (xy 381.923796 -281.514758)
			(xy 381.939844 -281.465365) (xy 381.963422 -281.419091) (xy 381.993948 -281.377075) (xy 382.030671 -281.340352)
			(xy 382.072687 -281.309826) (xy 382.118961 -281.286248) (xy 382.168354 -281.2702) (xy 382.219649 -281.262075)
			(xy 382.271583 -281.262075) (xy 382.322878 -281.2702) (xy 382.372271 -281.286248) (xy 382.418545 -281.309826)
			(xy 382.460561 -281.340352) (xy 382.497284 -281.377075) (xy 382.52781 -281.419091) (xy 382.551388 -281.465365)
			(xy 382.567436 -281.514758) (xy 382.575561 -281.566053) (xy 382.57607 -281.59202) (xy 382.575561 -281.617987)
			(xy 382.855217 -281.617987) (xy 382.855217 -281.566053) (xy 382.863342 -281.514758) (xy 382.87939 -281.465365)
			(xy 382.902968 -281.419091) (xy 382.933494 -281.377075) (xy 382.970217 -281.340352) (xy 383.012233 -281.309826)
			(xy 383.058507 -281.286248) (xy 383.1079 -281.2702) (xy 383.159195 -281.262075) (xy 383.211129 -281.262075)
			(xy 383.262424 -281.2702) (xy 383.311817 -281.286248) (xy 383.358091 -281.309826) (xy 383.400107 -281.340352)
			(xy 383.43683 -281.377075) (xy 383.467356 -281.419091) (xy 383.490934 -281.465365) (xy 383.506982 -281.514758)
			(xy 383.515107 -281.566053) (xy 383.515616 -281.59202) (xy 383.515107 -281.617987) (xy 383.506982 -281.669282)
			(xy 383.490934 -281.718675) (xy 383.467356 -281.764949) (xy 383.43683 -281.806965) (xy 383.400107 -281.843688)
			(xy 383.358091 -281.874214) (xy 383.311817 -281.897792) (xy 383.262424 -281.91384) (xy 383.211129 -281.921965)
			(xy 383.159195 -281.921965) (xy 383.1079 -281.91384) (xy 383.058507 -281.897792) (xy 383.012233 -281.874214)
			(xy 382.970217 -281.843688) (xy 382.933494 -281.806965) (xy 382.902968 -281.764949) (xy 382.87939 -281.718675)
			(xy 382.863342 -281.669282) (xy 382.855217 -281.617987) (xy 382.575561 -281.617987) (xy 382.567436 -281.669282)
			(xy 382.551388 -281.718675) (xy 382.52781 -281.764949) (xy 382.497284 -281.806965) (xy 382.460561 -281.843688)
			(xy 382.418545 -281.874214) (xy 382.372271 -281.897792) (xy 382.322878 -281.91384) (xy 382.271583 -281.921965)
			(xy 382.219649 -281.921965) (xy 382.168354 -281.91384) (xy 382.118961 -281.897792) (xy 382.072687 -281.874214)
			(xy 382.030671 -281.843688) (xy 381.993948 -281.806965) (xy 381.963422 -281.764949) (xy 381.939844 -281.718675)
			(xy 381.923796 -281.669282) (xy 381.915671 -281.617987) (xy 381.635761 -281.617987) (xy 381.627636 -281.669282)
			(xy 381.611588 -281.718675) (xy 381.58801 -281.764949) (xy 381.557484 -281.806965) (xy 381.520761 -281.843688)
			(xy 381.478745 -281.874214) (xy 381.432471 -281.897792) (xy 381.383078 -281.91384) (xy 381.331783 -281.921965)
			(xy 381.279849 -281.921965) (xy 381.228554 -281.91384) (xy 381.179161 -281.897792) (xy 381.132887 -281.874214)
			(xy 381.090871 -281.843688) (xy 381.054148 -281.806965) (xy 381.023622 -281.764949) (xy 381.000044 -281.718675)
			(xy 380.983996 -281.669282) (xy 380.975871 -281.617987) (xy 380.695961 -281.617987) (xy 380.687836 -281.669282)
			(xy 380.671788 -281.718675) (xy 380.64821 -281.764949) (xy 380.617684 -281.806965) (xy 380.580961 -281.843688)
			(xy 380.538945 -281.874214) (xy 380.492671 -281.897792) (xy 380.443278 -281.91384) (xy 380.391983 -281.921965)
			(xy 380.340049 -281.921965) (xy 380.288754 -281.91384) (xy 380.239361 -281.897792) (xy 380.193087 -281.874214)
			(xy 380.151071 -281.843688) (xy 380.114348 -281.806965) (xy 380.083822 -281.764949) (xy 380.060244 -281.718675)
			(xy 380.044196 -281.669282) (xy 380.036071 -281.617987) (xy 379.756161 -281.617987) (xy 379.748036 -281.669282)
			(xy 379.731988 -281.718675) (xy 379.70841 -281.764949) (xy 379.677884 -281.806965) (xy 379.641161 -281.843688)
			(xy 379.599145 -281.874214) (xy 379.552871 -281.897792) (xy 379.503478 -281.91384) (xy 379.452183 -281.921965)
			(xy 379.400249 -281.921965) (xy 379.348954 -281.91384) (xy 379.299561 -281.897792) (xy 379.253287 -281.874214)
			(xy 379.211271 -281.843688) (xy 379.174548 -281.806965) (xy 379.144022 -281.764949) (xy 379.120444 -281.718675)
			(xy 379.104396 -281.669282) (xy 379.096271 -281.617987) (xy 378.816361 -281.617987) (xy 378.808236 -281.669282)
			(xy 378.792188 -281.718675) (xy 378.76861 -281.764949) (xy 378.738084 -281.806965) (xy 378.701361 -281.843688)
			(xy 378.659345 -281.874214) (xy 378.613071 -281.897792) (xy 378.563678 -281.91384) (xy 378.512383 -281.921965)
			(xy 378.460449 -281.921965) (xy 378.409154 -281.91384) (xy 378.359761 -281.897792) (xy 378.313487 -281.874214)
			(xy 378.271471 -281.843688) (xy 378.234748 -281.806965) (xy 378.204222 -281.764949) (xy 378.180644 -281.718675)
			(xy 378.164596 -281.669282) (xy 378.156471 -281.617987) (xy 377.876307 -281.617987) (xy 377.868182 -281.669282)
			(xy 377.852134 -281.718675) (xy 377.828556 -281.764949) (xy 377.79803 -281.806965) (xy 377.761307 -281.843688)
			(xy 377.719291 -281.874214) (xy 377.673017 -281.897792) (xy 377.623624 -281.91384) (xy 377.572329 -281.921965)
			(xy 377.520395 -281.921965) (xy 377.4691 -281.91384) (xy 377.419707 -281.897792) (xy 377.373433 -281.874214)
			(xy 377.331417 -281.843688) (xy 377.294694 -281.806965) (xy 377.264168 -281.764949) (xy 377.24059 -281.718675)
			(xy 377.224542 -281.669282) (xy 377.216417 -281.617987) (xy 376.936761 -281.617987) (xy 376.928636 -281.669282)
			(xy 376.912588 -281.718675) (xy 376.88901 -281.764949) (xy 376.858484 -281.806965) (xy 376.821761 -281.843688)
			(xy 376.779745 -281.874214) (xy 376.733471 -281.897792) (xy 376.684078 -281.91384) (xy 376.632783 -281.921965)
			(xy 376.580849 -281.921965) (xy 376.529554 -281.91384) (xy 376.480161 -281.897792) (xy 376.433887 -281.874214)
			(xy 376.391871 -281.843688) (xy 376.355148 -281.806965) (xy 376.324622 -281.764949) (xy 376.301044 -281.718675)
			(xy 376.284996 -281.669282) (xy 376.276871 -281.617987) (xy 375.996667 -281.617987) (xy 375.988582 -281.669028)
			(xy 375.972534 -281.718421) (xy 375.948956 -281.764695) (xy 375.91843 -281.806711) (xy 375.881707 -281.843434)
			(xy 375.839691 -281.87396) (xy 375.793417 -281.897538) (xy 375.744024 -281.913586) (xy 375.692729 -281.921711)
			(xy 375.640795 -281.921711) (xy 375.5895 -281.913586) (xy 375.540107 -281.897538) (xy 375.493833 -281.87396)
			(xy 375.451817 -281.843434) (xy 375.415094 -281.806711) (xy 375.384568 -281.764695) (xy 375.36099 -281.718421)
			(xy 375.344942 -281.669028) (xy 375.336817 -281.617733) (xy 375.056912 -281.617733) (xy 375.056907 -281.617987)
			(xy 375.048782 -281.669282) (xy 375.032734 -281.718675) (xy 375.009156 -281.764949) (xy 374.97863 -281.806965)
			(xy 374.941907 -281.843688) (xy 374.899891 -281.874214) (xy 374.853617 -281.897792) (xy 374.804224 -281.91384)
			(xy 374.752929 -281.921965) (xy 374.700995 -281.921965) (xy 374.6497 -281.91384) (xy 374.600307 -281.897792)
			(xy 374.554033 -281.874214) (xy 374.512017 -281.843688) (xy 374.475294 -281.806965) (xy 374.444768 -281.764949)
			(xy 374.42119 -281.718675) (xy 374.405142 -281.669282) (xy 374.397017 -281.617987) (xy 374.117361 -281.617987)
			(xy 374.109236 -281.669282) (xy 374.093188 -281.718675) (xy 374.06961 -281.764949) (xy 374.039084 -281.806965)
			(xy 374.002361 -281.843688) (xy 373.960345 -281.874214) (xy 373.914071 -281.897792) (xy 373.864678 -281.91384)
			(xy 373.813383 -281.921965) (xy 373.761449 -281.921965) (xy 373.710154 -281.91384) (xy 373.660761 -281.897792)
			(xy 373.614487 -281.874214) (xy 373.572471 -281.843688) (xy 373.535748 -281.806965) (xy 373.505222 -281.764949)
			(xy 373.481644 -281.718675) (xy 373.465596 -281.669282) (xy 373.457471 -281.617987) (xy 373.177561 -281.617987)
			(xy 373.169436 -281.669282) (xy 373.153388 -281.718675) (xy 373.12981 -281.764949) (xy 373.099284 -281.806965)
			(xy 373.062561 -281.843688) (xy 373.020545 -281.874214) (xy 372.974271 -281.897792) (xy 372.924878 -281.91384)
			(xy 372.873583 -281.921965) (xy 372.821649 -281.921965) (xy 372.770354 -281.91384) (xy 372.720961 -281.897792)
			(xy 372.674687 -281.874214) (xy 372.632671 -281.843688) (xy 372.595948 -281.806965) (xy 372.565422 -281.764949)
			(xy 372.541844 -281.718675) (xy 372.525796 -281.669282) (xy 372.517671 -281.617987) (xy 372.237761 -281.617987)
			(xy 372.229636 -281.669282) (xy 372.213588 -281.718675) (xy 372.19001 -281.764949) (xy 372.159484 -281.806965)
			(xy 372.122761 -281.843688) (xy 372.080745 -281.874214) (xy 372.034471 -281.897792) (xy 371.985078 -281.91384)
			(xy 371.933783 -281.921965) (xy 371.881849 -281.921965) (xy 371.830554 -281.91384) (xy 371.781161 -281.897792)
			(xy 371.734887 -281.874214) (xy 371.692871 -281.843688) (xy 371.656148 -281.806965) (xy 371.625622 -281.764949)
			(xy 371.602044 -281.718675) (xy 371.585996 -281.669282) (xy 371.577871 -281.617987) (xy 371.297961 -281.617987)
			(xy 371.289836 -281.669282) (xy 371.273788 -281.718675) (xy 371.25021 -281.764949) (xy 371.219684 -281.806965)
			(xy 371.182961 -281.843688) (xy 371.140945 -281.874214) (xy 371.094671 -281.897792) (xy 371.045278 -281.91384)
			(xy 370.993983 -281.921965) (xy 370.942049 -281.921965) (xy 370.890754 -281.91384) (xy 370.841361 -281.897792)
			(xy 370.795087 -281.874214) (xy 370.753071 -281.843688) (xy 370.716348 -281.806965) (xy 370.685822 -281.764949)
			(xy 370.662244 -281.718675) (xy 370.646196 -281.669282) (xy 370.638071 -281.617987) (xy 370.358161 -281.617987)
			(xy 370.350036 -281.669282) (xy 370.333988 -281.718675) (xy 370.31041 -281.764949) (xy 370.279884 -281.806965)
			(xy 370.243161 -281.843688) (xy 370.201145 -281.874214) (xy 370.154871 -281.897792) (xy 370.105478 -281.91384)
			(xy 370.054183 -281.921965) (xy 370.002249 -281.921965) (xy 369.950954 -281.91384) (xy 369.901561 -281.897792)
			(xy 369.855287 -281.874214) (xy 369.813271 -281.843688) (xy 369.776548 -281.806965) (xy 369.746022 -281.764949)
			(xy 369.722444 -281.718675) (xy 369.706396 -281.669282) (xy 369.698271 -281.617987) (xy 369.418361 -281.617987)
			(xy 369.410236 -281.669282) (xy 369.394188 -281.718675) (xy 369.37061 -281.764949) (xy 369.340084 -281.806965)
			(xy 369.303361 -281.843688) (xy 369.261345 -281.874214) (xy 369.215071 -281.897792) (xy 369.165678 -281.91384)
			(xy 369.114383 -281.921965) (xy 369.062449 -281.921965) (xy 369.011154 -281.91384) (xy 368.961761 -281.897792)
			(xy 368.915487 -281.874214) (xy 368.873471 -281.843688) (xy 368.836748 -281.806965) (xy 368.806222 -281.764949)
			(xy 368.782644 -281.718675) (xy 368.766596 -281.669282) (xy 368.758471 -281.617987) (xy 368.478522 -281.617987)
			(xy 368.470402 -281.669255) (xy 368.454355 -281.718643) (xy 368.43078 -281.764914) (xy 368.400257 -281.806926)
			(xy 368.363538 -281.843647) (xy 368.321527 -281.874172) (xy 368.275258 -281.897749) (xy 368.225871 -281.913798)
			(xy 368.174581 -281.921924) (xy 368.148616 -281.922474) (xy 368.128078 -281.922163) (xy 368.087318 -281.917071)
			(xy 368.067336 -281.912314) (xy 368.052223 -281.909014) (xy 368.021349 -281.910671) (xy 367.992384 -281.921487)
			(xy 367.96798 -281.940472) (xy 367.950372 -281.965887) (xy 367.941172 -281.995406) (xy 367.94059 -282.010866)
			(xy 367.94059 -282.204668) (xy 367.956638 -282.226454) (xy 367.982157 -282.274163) (xy 367.999557 -282.325394)
			(xy 368.008373 -282.378776) (xy 368.008368 -282.431803) (xy 368.288317 -282.431803) (xy 368.288317 -282.379869)
			(xy 368.296442 -282.328574) (xy 368.31249 -282.279181) (xy 368.336068 -282.232907) (xy 368.366594 -282.190891)
			(xy 368.403317 -282.154168) (xy 368.445333 -282.123642) (xy 368.491607 -282.100064) (xy 368.541 -282.084016)
			(xy 368.592295 -282.075891) (xy 368.644229 -282.075891) (xy 368.695524 -282.084016) (xy 368.744917 -282.100064)
			(xy 368.791191 -282.123642) (xy 368.833207 -282.154168) (xy 368.86993 -282.190891) (xy 368.900456 -282.232907)
			(xy 368.924034 -282.279181) (xy 368.940082 -282.328574) (xy 368.948207 -282.379869) (xy 368.948716 -282.405836)
			(xy 368.948207 -282.431803) (xy 369.228117 -282.431803) (xy 369.228117 -282.379869) (xy 369.236242 -282.328574)
			(xy 369.25229 -282.279181) (xy 369.275868 -282.232907) (xy 369.306394 -282.190891) (xy 369.343117 -282.154168)
			(xy 369.385133 -282.123642) (xy 369.431407 -282.100064) (xy 369.4808 -282.084016) (xy 369.532095 -282.075891)
			(xy 369.584029 -282.075891) (xy 369.635324 -282.084016) (xy 369.684717 -282.100064) (xy 369.730991 -282.123642)
			(xy 369.773007 -282.154168) (xy 369.80973 -282.190891) (xy 369.840256 -282.232907) (xy 369.863834 -282.279181)
			(xy 369.879882 -282.328574) (xy 369.888007 -282.379869) (xy 369.888516 -282.405836) (xy 369.888007 -282.431803)
			(xy 370.167917 -282.431803) (xy 370.167917 -282.379869) (xy 370.176042 -282.328574) (xy 370.19209 -282.279181)
			(xy 370.215668 -282.232907) (xy 370.246194 -282.190891) (xy 370.282917 -282.154168) (xy 370.324933 -282.123642)
			(xy 370.371207 -282.100064) (xy 370.4206 -282.084016) (xy 370.471895 -282.075891) (xy 370.523829 -282.075891)
			(xy 370.575124 -282.084016) (xy 370.624517 -282.100064) (xy 370.670791 -282.123642) (xy 370.712807 -282.154168)
			(xy 370.74953 -282.190891) (xy 370.780056 -282.232907) (xy 370.803634 -282.279181) (xy 370.819682 -282.328574)
			(xy 370.827807 -282.379869) (xy 370.828316 -282.405836) (xy 370.827807 -282.431803) (xy 371.107717 -282.431803)
			(xy 371.107717 -282.379869) (xy 371.115842 -282.328574) (xy 371.13189 -282.279181) (xy 371.155468 -282.232907)
			(xy 371.185994 -282.190891) (xy 371.222717 -282.154168) (xy 371.264733 -282.123642) (xy 371.311007 -282.100064)
			(xy 371.3604 -282.084016) (xy 371.411695 -282.075891) (xy 371.463629 -282.075891) (xy 371.514924 -282.084016)
			(xy 371.564317 -282.100064) (xy 371.610591 -282.123642) (xy 371.652607 -282.154168) (xy 371.68933 -282.190891)
			(xy 371.719856 -282.232907) (xy 371.743434 -282.279181) (xy 371.759482 -282.328574) (xy 371.767607 -282.379869)
			(xy 371.768116 -282.405836) (xy 371.767607 -282.431803) (xy 372.047517 -282.431803) (xy 372.047517 -282.379869)
			(xy 372.055642 -282.328574) (xy 372.07169 -282.279181) (xy 372.095268 -282.232907) (xy 372.125794 -282.190891)
			(xy 372.162517 -282.154168) (xy 372.204533 -282.123642) (xy 372.250807 -282.100064) (xy 372.3002 -282.084016)
			(xy 372.351495 -282.075891) (xy 372.403429 -282.075891) (xy 372.454724 -282.084016) (xy 372.504117 -282.100064)
			(xy 372.550391 -282.123642) (xy 372.592407 -282.154168) (xy 372.62913 -282.190891) (xy 372.659656 -282.232907)
			(xy 372.683234 -282.279181) (xy 372.699282 -282.328574) (xy 372.707407 -282.379869) (xy 372.707916 -282.405836)
			(xy 372.707407 -282.431803) (xy 372.987317 -282.431803) (xy 372.987317 -282.379869) (xy 372.995442 -282.328574)
			(xy 373.01149 -282.279181) (xy 373.035068 -282.232907) (xy 373.065594 -282.190891) (xy 373.102317 -282.154168)
			(xy 373.144333 -282.123642) (xy 373.190607 -282.100064) (xy 373.24 -282.084016) (xy 373.291295 -282.075891)
			(xy 373.343229 -282.075891) (xy 373.394524 -282.084016) (xy 373.443917 -282.100064) (xy 373.490191 -282.123642)
			(xy 373.532207 -282.154168) (xy 373.56893 -282.190891) (xy 373.599456 -282.232907) (xy 373.623034 -282.279181)
			(xy 373.639082 -282.328574) (xy 373.647207 -282.379869) (xy 373.647716 -282.405836) (xy 373.647207 -282.431803)
			(xy 373.927371 -282.431803) (xy 373.927371 -282.379869) (xy 373.935496 -282.328574) (xy 373.951544 -282.279181)
			(xy 373.975122 -282.232907) (xy 374.005648 -282.190891) (xy 374.042371 -282.154168) (xy 374.084387 -282.123642)
			(xy 374.130661 -282.100064) (xy 374.180054 -282.084016) (xy 374.231349 -282.075891) (xy 374.283283 -282.075891)
			(xy 374.334578 -282.084016) (xy 374.383971 -282.100064) (xy 374.430245 -282.123642) (xy 374.472261 -282.154168)
			(xy 374.508984 -282.190891) (xy 374.53951 -282.232907) (xy 374.563088 -282.279181) (xy 374.579136 -282.328574)
			(xy 374.587261 -282.379869) (xy 374.58777 -282.405836) (xy 374.587266 -282.431549) (xy 374.867171 -282.431549)
			(xy 374.867171 -282.379615) (xy 374.875296 -282.32832) (xy 374.891344 -282.278927) (xy 374.914922 -282.232653)
			(xy 374.945448 -282.190637) (xy 374.982171 -282.153914) (xy 375.024187 -282.123388) (xy 375.070461 -282.09981)
			(xy 375.119854 -282.083762) (xy 375.171149 -282.075637) (xy 375.223083 -282.075637) (xy 375.274378 -282.083762)
			(xy 375.323771 -282.09981) (xy 375.370045 -282.123388) (xy 375.412061 -282.153914) (xy 375.448784 -282.190637)
			(xy 375.47931 -282.232653) (xy 375.502888 -282.278927) (xy 375.518936 -282.32832) (xy 375.527061 -282.379615)
			(xy 375.52757 -282.405582) (xy 375.527061 -282.431549) (xy 375.806971 -282.431549) (xy 375.806971 -282.379615)
			(xy 375.815096 -282.32832) (xy 375.831144 -282.278927) (xy 375.854722 -282.232653) (xy 375.885248 -282.190637)
			(xy 375.921971 -282.153914) (xy 375.963987 -282.123388) (xy 376.010261 -282.09981) (xy 376.059654 -282.083762)
			(xy 376.110949 -282.075637) (xy 376.162883 -282.075637) (xy 376.214178 -282.083762) (xy 376.263571 -282.09981)
			(xy 376.309845 -282.123388) (xy 376.351861 -282.153914) (xy 376.388584 -282.190637) (xy 376.41911 -282.232653)
			(xy 376.442688 -282.278927) (xy 376.458736 -282.32832) (xy 376.466861 -282.379615) (xy 376.46737 -282.405582)
			(xy 376.466861 -282.431549) (xy 376.746771 -282.431549) (xy 376.746771 -282.379615) (xy 376.754896 -282.32832)
			(xy 376.770944 -282.278927) (xy 376.794522 -282.232653) (xy 376.825048 -282.190637) (xy 376.861771 -282.153914)
			(xy 376.903787 -282.123388) (xy 376.950061 -282.09981) (xy 376.999454 -282.083762) (xy 377.050749 -282.075637)
			(xy 377.102683 -282.075637) (xy 377.153978 -282.083762) (xy 377.203371 -282.09981) (xy 377.249645 -282.123388)
			(xy 377.291661 -282.153914) (xy 377.328384 -282.190637) (xy 377.35891 -282.232653) (xy 377.382488 -282.278927)
			(xy 377.398536 -282.32832) (xy 377.406661 -282.379615) (xy 377.40717 -282.405582) (xy 377.406661 -282.431549)
			(xy 377.686571 -282.431549) (xy 377.686571 -282.379615) (xy 377.694696 -282.32832) (xy 377.710744 -282.278927)
			(xy 377.734322 -282.232653) (xy 377.764848 -282.190637) (xy 377.801571 -282.153914) (xy 377.843587 -282.123388)
			(xy 377.889861 -282.09981) (xy 377.939254 -282.083762) (xy 377.990549 -282.075637) (xy 378.042483 -282.075637)
			(xy 378.093778 -282.083762) (xy 378.143171 -282.09981) (xy 378.189445 -282.123388) (xy 378.231461 -282.153914)
			(xy 378.268184 -282.190637) (xy 378.29871 -282.232653) (xy 378.322288 -282.278927) (xy 378.338336 -282.32832)
			(xy 378.346461 -282.379615) (xy 378.34697 -282.405582) (xy 378.346461 -282.431549) (xy 378.346421 -282.431803)
			(xy 378.626117 -282.431803) (xy 378.626117 -282.379869) (xy 378.634242 -282.328574) (xy 378.65029 -282.279181)
			(xy 378.673868 -282.232907) (xy 378.704394 -282.190891) (xy 378.741117 -282.154168) (xy 378.783133 -282.123642)
			(xy 378.829407 -282.100064) (xy 378.8788 -282.084016) (xy 378.930095 -282.075891) (xy 378.982029 -282.075891)
			(xy 379.033324 -282.084016) (xy 379.082717 -282.100064) (xy 379.128991 -282.123642) (xy 379.171007 -282.154168)
			(xy 379.20773 -282.190891) (xy 379.238256 -282.232907) (xy 379.261834 -282.279181) (xy 379.277882 -282.328574)
			(xy 379.286007 -282.379869) (xy 379.286516 -282.405836) (xy 379.286007 -282.431803) (xy 379.565917 -282.431803)
			(xy 379.565917 -282.379869) (xy 379.574042 -282.328574) (xy 379.59009 -282.279181) (xy 379.613668 -282.232907)
			(xy 379.644194 -282.190891) (xy 379.680917 -282.154168) (xy 379.722933 -282.123642) (xy 379.769207 -282.100064)
			(xy 379.8186 -282.084016) (xy 379.869895 -282.075891) (xy 379.921829 -282.075891) (xy 379.973124 -282.084016)
			(xy 380.022517 -282.100064) (xy 380.068791 -282.123642) (xy 380.110807 -282.154168) (xy 380.14753 -282.190891)
			(xy 380.178056 -282.232907) (xy 380.201634 -282.279181) (xy 380.217682 -282.328574) (xy 380.225807 -282.379869)
			(xy 380.226316 -282.405836) (xy 380.225807 -282.431803) (xy 380.505717 -282.431803) (xy 380.505717 -282.379869)
			(xy 380.513842 -282.328574) (xy 380.52989 -282.279181) (xy 380.553468 -282.232907) (xy 380.583994 -282.190891)
			(xy 380.620717 -282.154168) (xy 380.662733 -282.123642) (xy 380.709007 -282.100064) (xy 380.7584 -282.084016)
			(xy 380.809695 -282.075891) (xy 380.861629 -282.075891) (xy 380.912924 -282.084016) (xy 380.962317 -282.100064)
			(xy 381.008591 -282.123642) (xy 381.050607 -282.154168) (xy 381.08733 -282.190891) (xy 381.117856 -282.232907)
			(xy 381.141434 -282.279181) (xy 381.157482 -282.328574) (xy 381.165607 -282.379869) (xy 381.166116 -282.405836)
			(xy 381.165607 -282.431803) (xy 381.445517 -282.431803) (xy 381.445517 -282.379869) (xy 381.453642 -282.328574)
			(xy 381.46969 -282.279181) (xy 381.493268 -282.232907) (xy 381.523794 -282.190891) (xy 381.560517 -282.154168)
			(xy 381.602533 -282.123642) (xy 381.648807 -282.100064) (xy 381.6982 -282.084016) (xy 381.749495 -282.075891)
			(xy 381.801429 -282.075891) (xy 381.852724 -282.084016) (xy 381.902117 -282.100064) (xy 381.948391 -282.123642)
			(xy 381.990407 -282.154168) (xy 382.02713 -282.190891) (xy 382.057656 -282.232907) (xy 382.081234 -282.279181)
			(xy 382.097282 -282.328574) (xy 382.105407 -282.379869) (xy 382.105916 -282.405836) (xy 382.105407 -282.431803)
			(xy 382.385571 -282.431803) (xy 382.385571 -282.379869) (xy 382.393696 -282.328574) (xy 382.409744 -282.279181)
			(xy 382.433322 -282.232907) (xy 382.463848 -282.190891) (xy 382.500571 -282.154168) (xy 382.542587 -282.123642)
			(xy 382.588861 -282.100064) (xy 382.638254 -282.084016) (xy 382.689549 -282.075891) (xy 382.741483 -282.075891)
			(xy 382.792778 -282.084016) (xy 382.842171 -282.100064) (xy 382.888445 -282.123642) (xy 382.930461 -282.154168)
			(xy 382.967184 -282.190891) (xy 382.99771 -282.232907) (xy 383.021288 -282.279181) (xy 383.037336 -282.328574)
			(xy 383.045461 -282.379869) (xy 383.04597 -282.405836) (xy 383.045461 -282.431803) (xy 383.325117 -282.431803)
			(xy 383.325117 -282.379869) (xy 383.333242 -282.328574) (xy 383.34929 -282.279181) (xy 383.372868 -282.232907)
			(xy 383.403394 -282.190891) (xy 383.440117 -282.154168) (xy 383.482133 -282.123642) (xy 383.528407 -282.100064)
			(xy 383.5778 -282.084016) (xy 383.629095 -282.075891) (xy 383.681029 -282.075891) (xy 383.732324 -282.084016)
			(xy 383.781717 -282.100064) (xy 383.827991 -282.123642) (xy 383.870007 -282.154168) (xy 383.90673 -282.190891)
			(xy 383.937256 -282.232907) (xy 383.960834 -282.279181) (xy 383.976882 -282.328574) (xy 383.985007 -282.379869)
			(xy 383.985516 -282.405836) (xy 383.985007 -282.431803) (xy 383.976882 -282.483098) (xy 383.960834 -282.532491)
			(xy 383.937256 -282.578765) (xy 383.90673 -282.620781) (xy 383.870007 -282.657504) (xy 383.827991 -282.68803)
			(xy 383.781717 -282.711608) (xy 383.732324 -282.727656) (xy 383.681029 -282.735781) (xy 383.629095 -282.735781)
			(xy 383.5778 -282.727656) (xy 383.528407 -282.711608) (xy 383.482133 -282.68803) (xy 383.440117 -282.657504)
			(xy 383.403394 -282.620781) (xy 383.372868 -282.578765) (xy 383.34929 -282.532491) (xy 383.333242 -282.483098)
			(xy 383.325117 -282.431803) (xy 383.045461 -282.431803) (xy 383.037336 -282.483098) (xy 383.021288 -282.532491)
			(xy 382.99771 -282.578765) (xy 382.967184 -282.620781) (xy 382.930461 -282.657504) (xy 382.888445 -282.68803)
			(xy 382.842171 -282.711608) (xy 382.792778 -282.727656) (xy 382.741483 -282.735781) (xy 382.689549 -282.735781)
			(xy 382.638254 -282.727656) (xy 382.588861 -282.711608) (xy 382.542587 -282.68803) (xy 382.500571 -282.657504)
			(xy 382.463848 -282.620781) (xy 382.433322 -282.578765) (xy 382.409744 -282.532491) (xy 382.393696 -282.483098)
			(xy 382.385571 -282.431803) (xy 382.105407 -282.431803) (xy 382.097282 -282.483098) (xy 382.081234 -282.532491)
			(xy 382.057656 -282.578765) (xy 382.02713 -282.620781) (xy 381.990407 -282.657504) (xy 381.948391 -282.68803)
			(xy 381.902117 -282.711608) (xy 381.852724 -282.727656) (xy 381.801429 -282.735781) (xy 381.749495 -282.735781)
			(xy 381.6982 -282.727656) (xy 381.648807 -282.711608) (xy 381.602533 -282.68803) (xy 381.560517 -282.657504)
			(xy 381.523794 -282.620781) (xy 381.493268 -282.578765) (xy 381.46969 -282.532491) (xy 381.453642 -282.483098)
			(xy 381.445517 -282.431803) (xy 381.165607 -282.431803) (xy 381.157482 -282.483098) (xy 381.141434 -282.532491)
			(xy 381.117856 -282.578765) (xy 381.08733 -282.620781) (xy 381.050607 -282.657504) (xy 381.008591 -282.68803)
			(xy 380.962317 -282.711608) (xy 380.912924 -282.727656) (xy 380.861629 -282.735781) (xy 380.809695 -282.735781)
			(xy 380.7584 -282.727656) (xy 380.709007 -282.711608) (xy 380.662733 -282.68803) (xy 380.620717 -282.657504)
			(xy 380.583994 -282.620781) (xy 380.553468 -282.578765) (xy 380.52989 -282.532491) (xy 380.513842 -282.483098)
			(xy 380.505717 -282.431803) (xy 380.225807 -282.431803) (xy 380.217682 -282.483098) (xy 380.201634 -282.532491)
			(xy 380.178056 -282.578765) (xy 380.14753 -282.620781) (xy 380.110807 -282.657504) (xy 380.068791 -282.68803)
			(xy 380.022517 -282.711608) (xy 379.973124 -282.727656) (xy 379.921829 -282.735781) (xy 379.869895 -282.735781)
			(xy 379.8186 -282.727656) (xy 379.769207 -282.711608) (xy 379.722933 -282.68803) (xy 379.680917 -282.657504)
			(xy 379.644194 -282.620781) (xy 379.613668 -282.578765) (xy 379.59009 -282.532491) (xy 379.574042 -282.483098)
			(xy 379.565917 -282.431803) (xy 379.286007 -282.431803) (xy 379.277882 -282.483098) (xy 379.261834 -282.532491)
			(xy 379.238256 -282.578765) (xy 379.20773 -282.620781) (xy 379.171007 -282.657504) (xy 379.128991 -282.68803)
			(xy 379.082717 -282.711608) (xy 379.033324 -282.727656) (xy 378.982029 -282.735781) (xy 378.930095 -282.735781)
			(xy 378.8788 -282.727656) (xy 378.829407 -282.711608) (xy 378.783133 -282.68803) (xy 378.741117 -282.657504)
			(xy 378.704394 -282.620781) (xy 378.673868 -282.578765) (xy 378.65029 -282.532491) (xy 378.634242 -282.483098)
			(xy 378.626117 -282.431803) (xy 378.346421 -282.431803) (xy 378.338336 -282.482844) (xy 378.322288 -282.532237)
			(xy 378.29871 -282.578511) (xy 378.268184 -282.620527) (xy 378.231461 -282.65725) (xy 378.189445 -282.687776)
			(xy 378.143171 -282.711354) (xy 378.093778 -282.727402) (xy 378.042483 -282.735527) (xy 377.990549 -282.735527)
			(xy 377.939254 -282.727402) (xy 377.889861 -282.711354) (xy 377.843587 -282.687776) (xy 377.801571 -282.65725)
			(xy 377.764848 -282.620527) (xy 377.734322 -282.578511) (xy 377.710744 -282.532237) (xy 377.694696 -282.482844)
			(xy 377.686571 -282.431549) (xy 377.406661 -282.431549) (xy 377.398536 -282.482844) (xy 377.382488 -282.532237)
			(xy 377.35891 -282.578511) (xy 377.328384 -282.620527) (xy 377.291661 -282.65725) (xy 377.249645 -282.687776)
			(xy 377.203371 -282.711354) (xy 377.153978 -282.727402) (xy 377.102683 -282.735527) (xy 377.050749 -282.735527)
			(xy 376.999454 -282.727402) (xy 376.950061 -282.711354) (xy 376.903787 -282.687776) (xy 376.861771 -282.65725)
			(xy 376.825048 -282.620527) (xy 376.794522 -282.578511) (xy 376.770944 -282.532237) (xy 376.754896 -282.482844)
			(xy 376.746771 -282.431549) (xy 376.466861 -282.431549) (xy 376.458736 -282.482844) (xy 376.442688 -282.532237)
			(xy 376.41911 -282.578511) (xy 376.388584 -282.620527) (xy 376.351861 -282.65725) (xy 376.309845 -282.687776)
			(xy 376.263571 -282.711354) (xy 376.214178 -282.727402) (xy 376.162883 -282.735527) (xy 376.110949 -282.735527)
			(xy 376.059654 -282.727402) (xy 376.010261 -282.711354) (xy 375.963987 -282.687776) (xy 375.921971 -282.65725)
			(xy 375.885248 -282.620527) (xy 375.854722 -282.578511) (xy 375.831144 -282.532237) (xy 375.815096 -282.482844)
			(xy 375.806971 -282.431549) (xy 375.527061 -282.431549) (xy 375.518936 -282.482844) (xy 375.502888 -282.532237)
			(xy 375.47931 -282.578511) (xy 375.448784 -282.620527) (xy 375.412061 -282.65725) (xy 375.370045 -282.687776)
			(xy 375.323771 -282.711354) (xy 375.274378 -282.727402) (xy 375.223083 -282.735527) (xy 375.171149 -282.735527)
			(xy 375.119854 -282.727402) (xy 375.070461 -282.711354) (xy 375.024187 -282.687776) (xy 374.982171 -282.65725)
			(xy 374.945448 -282.620527) (xy 374.914922 -282.578511) (xy 374.891344 -282.532237) (xy 374.875296 -282.482844)
			(xy 374.867171 -282.431549) (xy 374.587266 -282.431549) (xy 374.587261 -282.431803) (xy 374.579136 -282.483098)
			(xy 374.563088 -282.532491) (xy 374.53951 -282.578765) (xy 374.508984 -282.620781) (xy 374.472261 -282.657504)
			(xy 374.430245 -282.68803) (xy 374.383971 -282.711608) (xy 374.334578 -282.727656) (xy 374.283283 -282.735781)
			(xy 374.231349 -282.735781) (xy 374.180054 -282.727656) (xy 374.130661 -282.711608) (xy 374.084387 -282.68803)
			(xy 374.042371 -282.657504) (xy 374.005648 -282.620781) (xy 373.975122 -282.578765) (xy 373.951544 -282.532491)
			(xy 373.935496 -282.483098) (xy 373.927371 -282.431803) (xy 373.647207 -282.431803) (xy 373.639082 -282.483098)
			(xy 373.623034 -282.532491) (xy 373.599456 -282.578765) (xy 373.56893 -282.620781) (xy 373.532207 -282.657504)
			(xy 373.490191 -282.68803) (xy 373.443917 -282.711608) (xy 373.394524 -282.727656) (xy 373.343229 -282.735781)
			(xy 373.291295 -282.735781) (xy 373.24 -282.727656) (xy 373.190607 -282.711608) (xy 373.144333 -282.68803)
			(xy 373.102317 -282.657504) (xy 373.065594 -282.620781) (xy 373.035068 -282.578765) (xy 373.01149 -282.532491)
			(xy 372.995442 -282.483098) (xy 372.987317 -282.431803) (xy 372.707407 -282.431803) (xy 372.699282 -282.483098)
			(xy 372.683234 -282.532491) (xy 372.659656 -282.578765) (xy 372.62913 -282.620781) (xy 372.592407 -282.657504)
			(xy 372.550391 -282.68803) (xy 372.504117 -282.711608) (xy 372.454724 -282.727656) (xy 372.403429 -282.735781)
			(xy 372.351495 -282.735781) (xy 372.3002 -282.727656) (xy 372.250807 -282.711608) (xy 372.204533 -282.68803)
			(xy 372.162517 -282.657504) (xy 372.125794 -282.620781) (xy 372.095268 -282.578765) (xy 372.07169 -282.532491)
			(xy 372.055642 -282.483098) (xy 372.047517 -282.431803) (xy 371.767607 -282.431803) (xy 371.759482 -282.483098)
			(xy 371.743434 -282.532491) (xy 371.719856 -282.578765) (xy 371.68933 -282.620781) (xy 371.652607 -282.657504)
			(xy 371.610591 -282.68803) (xy 371.564317 -282.711608) (xy 371.514924 -282.727656) (xy 371.463629 -282.735781)
			(xy 371.411695 -282.735781) (xy 371.3604 -282.727656) (xy 371.311007 -282.711608) (xy 371.264733 -282.68803)
			(xy 371.222717 -282.657504) (xy 371.185994 -282.620781) (xy 371.155468 -282.578765) (xy 371.13189 -282.532491)
			(xy 371.115842 -282.483098) (xy 371.107717 -282.431803) (xy 370.827807 -282.431803) (xy 370.819682 -282.483098)
			(xy 370.803634 -282.532491) (xy 370.780056 -282.578765) (xy 370.74953 -282.620781) (xy 370.712807 -282.657504)
			(xy 370.670791 -282.68803) (xy 370.624517 -282.711608) (xy 370.575124 -282.727656) (xy 370.523829 -282.735781)
			(xy 370.471895 -282.735781) (xy 370.4206 -282.727656) (xy 370.371207 -282.711608) (xy 370.324933 -282.68803)
			(xy 370.282917 -282.657504) (xy 370.246194 -282.620781) (xy 370.215668 -282.578765) (xy 370.19209 -282.532491)
			(xy 370.176042 -282.483098) (xy 370.167917 -282.431803) (xy 369.888007 -282.431803) (xy 369.879882 -282.483098)
			(xy 369.863834 -282.532491) (xy 369.840256 -282.578765) (xy 369.80973 -282.620781) (xy 369.773007 -282.657504)
			(xy 369.730991 -282.68803) (xy 369.684717 -282.711608) (xy 369.635324 -282.727656) (xy 369.584029 -282.735781)
			(xy 369.532095 -282.735781) (xy 369.4808 -282.727656) (xy 369.431407 -282.711608) (xy 369.385133 -282.68803)
			(xy 369.343117 -282.657504) (xy 369.306394 -282.620781) (xy 369.275868 -282.578765) (xy 369.25229 -282.532491)
			(xy 369.236242 -282.483098) (xy 369.228117 -282.431803) (xy 368.948207 -282.431803) (xy 368.940082 -282.483098)
			(xy 368.924034 -282.532491) (xy 368.900456 -282.578765) (xy 368.86993 -282.620781) (xy 368.833207 -282.657504)
			(xy 368.791191 -282.68803) (xy 368.744917 -282.711608) (xy 368.695524 -282.727656) (xy 368.644229 -282.735781)
			(xy 368.592295 -282.735781) (xy 368.541 -282.727656) (xy 368.491607 -282.711608) (xy 368.445333 -282.68803)
			(xy 368.403317 -282.657504) (xy 368.366594 -282.620781) (xy 368.336068 -282.578765) (xy 368.31249 -282.532491)
			(xy 368.296442 -282.483098) (xy 368.288317 -282.431803) (xy 368.008368 -282.431803) (xy 368.008368 -282.432881)
			(xy 367.999543 -282.486262) (xy 367.982134 -282.53749) (xy 367.956607 -282.585195) (xy 367.94059 -282.607004)
			(xy 367.94059 -282.80106) (xy 367.941138 -282.816513) (xy 367.950382 -282.846004) (xy 367.968007 -282.871391)
			(xy 367.992408 -282.890359) (xy 368.021358 -282.901179) (xy 368.052218 -282.902862) (xy 368.067336 -282.899612)
			(xy 368.087319 -282.894861) (xy 368.128078 -282.889769) (xy 368.148616 -282.889452) (xy 368.174582 -282.889962)
			(xy 368.225874 -282.898089) (xy 368.275264 -282.914138) (xy 368.321534 -282.937717) (xy 368.363547 -282.968243)
			(xy 368.400268 -283.004965) (xy 368.430792 -283.046979) (xy 368.454368 -283.093251) (xy 368.470415 -283.142641)
			(xy 368.478539 -283.193934) (xy 368.478539 -283.245866) (xy 368.478538 -283.245873) (xy 368.758217 -283.245873)
			(xy 368.758217 -283.193939) (xy 368.766342 -283.142644) (xy 368.78239 -283.093251) (xy 368.805968 -283.046977)
			(xy 368.836494 -283.004961) (xy 368.873217 -282.968238) (xy 368.915233 -282.937712) (xy 368.961507 -282.914134)
			(xy 369.0109 -282.898086) (xy 369.062195 -282.889961) (xy 369.114129 -282.889961) (xy 369.165424 -282.898086)
			(xy 369.214817 -282.914134) (xy 369.261091 -282.937712) (xy 369.303107 -282.968238) (xy 369.33983 -283.004961)
			(xy 369.370356 -283.046977) (xy 369.393934 -283.093251) (xy 369.409982 -283.142644) (xy 369.418107 -283.193939)
			(xy 369.418616 -283.219906) (xy 369.418107 -283.245873) (xy 369.698017 -283.245873) (xy 369.698017 -283.193939)
			(xy 369.706142 -283.142644) (xy 369.72219 -283.093251) (xy 369.745768 -283.046977) (xy 369.776294 -283.004961)
			(xy 369.813017 -282.968238) (xy 369.855033 -282.937712) (xy 369.901307 -282.914134) (xy 369.9507 -282.898086)
			(xy 370.001995 -282.889961) (xy 370.053929 -282.889961) (xy 370.105224 -282.898086) (xy 370.154617 -282.914134)
			(xy 370.200891 -282.937712) (xy 370.242907 -282.968238) (xy 370.27963 -283.004961) (xy 370.310156 -283.046977)
			(xy 370.333734 -283.093251) (xy 370.349782 -283.142644) (xy 370.357907 -283.193939) (xy 370.358416 -283.219906)
			(xy 370.357907 -283.245873) (xy 370.638071 -283.245873) (xy 370.638071 -283.193939) (xy 370.646196 -283.142644)
			(xy 370.662244 -283.093251) (xy 370.685822 -283.046977) (xy 370.716348 -283.004961) (xy 370.753071 -282.968238)
			(xy 370.795087 -282.937712) (xy 370.841361 -282.914134) (xy 370.890754 -282.898086) (xy 370.942049 -282.889961)
			(xy 370.993983 -282.889961) (xy 371.045278 -282.898086) (xy 371.094671 -282.914134) (xy 371.140945 -282.937712)
			(xy 371.182961 -282.968238) (xy 371.219684 -283.004961) (xy 371.25021 -283.046977) (xy 371.273788 -283.093251)
			(xy 371.289836 -283.142644) (xy 371.297961 -283.193939) (xy 371.29847 -283.219906) (xy 371.297961 -283.245873)
			(xy 372.517671 -283.245873) (xy 372.517671 -283.193939) (xy 372.525796 -283.142644) (xy 372.541844 -283.093251)
			(xy 372.565422 -283.046977) (xy 372.595948 -283.004961) (xy 372.632671 -282.968238) (xy 372.674687 -282.937712)
			(xy 372.720961 -282.914134) (xy 372.770354 -282.898086) (xy 372.821649 -282.889961) (xy 372.873583 -282.889961)
			(xy 372.924878 -282.898086) (xy 372.974271 -282.914134) (xy 373.020545 -282.937712) (xy 373.062561 -282.968238)
			(xy 373.099284 -283.004961) (xy 373.12981 -283.046977) (xy 373.153388 -283.093251) (xy 373.169436 -283.142644)
			(xy 373.177561 -283.193939) (xy 373.17807 -283.219906) (xy 373.177561 -283.245873) (xy 373.457471 -283.245873)
			(xy 373.457471 -283.193939) (xy 373.465596 -283.142644) (xy 373.481644 -283.093251) (xy 373.505222 -283.046977)
			(xy 373.535748 -283.004961) (xy 373.572471 -282.968238) (xy 373.614487 -282.937712) (xy 373.660761 -282.914134)
			(xy 373.710154 -282.898086) (xy 373.761449 -282.889961) (xy 373.813383 -282.889961) (xy 373.864678 -282.898086)
			(xy 373.914071 -282.914134) (xy 373.960345 -282.937712) (xy 374.002361 -282.968238) (xy 374.039084 -283.004961)
			(xy 374.06961 -283.046977) (xy 374.093188 -283.093251) (xy 374.109236 -283.142644) (xy 374.117361 -283.193939)
			(xy 374.11787 -283.219906) (xy 374.117361 -283.245873) (xy 374.397017 -283.245873) (xy 374.397017 -283.193939)
			(xy 374.405142 -283.142644) (xy 374.42119 -283.093251) (xy 374.444768 -283.046977) (xy 374.475294 -283.004961)
			(xy 374.512017 -282.968238) (xy 374.554033 -282.937712) (xy 374.600307 -282.914134) (xy 374.6497 -282.898086)
			(xy 374.700995 -282.889961) (xy 374.752929 -282.889961) (xy 374.804224 -282.898086) (xy 374.853617 -282.914134)
			(xy 374.899891 -282.937712) (xy 374.941907 -282.968238) (xy 374.97863 -283.004961) (xy 375.009156 -283.046977)
			(xy 375.032734 -283.093251) (xy 375.048782 -283.142644) (xy 375.056907 -283.193939) (xy 375.057416 -283.219906)
			(xy 375.056912 -283.245619) (xy 376.276617 -283.245619) (xy 376.276617 -283.193685) (xy 376.284742 -283.14239)
			(xy 376.30079 -283.092997) (xy 376.324368 -283.046723) (xy 376.354894 -283.004707) (xy 376.391617 -282.967984)
			(xy 376.433633 -282.937458) (xy 376.479907 -282.91388) (xy 376.5293 -282.897832) (xy 376.580595 -282.889707)
			(xy 376.632529 -282.889707) (xy 376.683824 -282.897832) (xy 376.733217 -282.91388) (xy 376.779491 -282.937458)
			(xy 376.821507 -282.967984) (xy 376.85823 -283.004707) (xy 376.888756 -283.046723) (xy 376.912334 -283.092997)
			(xy 376.928382 -283.14239) (xy 376.936507 -283.193685) (xy 376.937016 -283.219652) (xy 376.936507 -283.245619)
			(xy 376.936467 -283.245873) (xy 377.216417 -283.245873) (xy 377.216417 -283.193939) (xy 377.224542 -283.142644)
			(xy 377.24059 -283.093251) (xy 377.264168 -283.046977) (xy 377.294694 -283.004961) (xy 377.331417 -282.968238)
			(xy 377.373433 -282.937712) (xy 377.419707 -282.914134) (xy 377.4691 -282.898086) (xy 377.520395 -282.889961)
			(xy 377.572329 -282.889961) (xy 377.623624 -282.898086) (xy 377.673017 -282.914134) (xy 377.719291 -282.937712)
			(xy 377.761307 -282.968238) (xy 377.79803 -283.004961) (xy 377.828556 -283.046977) (xy 377.852134 -283.093251)
			(xy 377.868182 -283.142644) (xy 377.876307 -283.193939) (xy 377.876816 -283.219906) (xy 377.876307 -283.245873)
			(xy 378.156217 -283.245873) (xy 378.156217 -283.193939) (xy 378.164342 -283.142644) (xy 378.18039 -283.093251)
			(xy 378.203968 -283.046977) (xy 378.234494 -283.004961) (xy 378.271217 -282.968238) (xy 378.313233 -282.937712)
			(xy 378.359507 -282.914134) (xy 378.4089 -282.898086) (xy 378.460195 -282.889961) (xy 378.512129 -282.889961)
			(xy 378.563424 -282.898086) (xy 378.612817 -282.914134) (xy 378.659091 -282.937712) (xy 378.701107 -282.968238)
			(xy 378.73783 -283.004961) (xy 378.768356 -283.046977) (xy 378.791934 -283.093251) (xy 378.807982 -283.142644)
			(xy 378.816107 -283.193939) (xy 378.816616 -283.219906) (xy 378.816107 -283.245873) (xy 379.096271 -283.245873)
			(xy 379.096271 -283.193939) (xy 379.104396 -283.142644) (xy 379.120444 -283.093251) (xy 379.144022 -283.046977)
			(xy 379.174548 -283.004961) (xy 379.211271 -282.968238) (xy 379.253287 -282.937712) (xy 379.299561 -282.914134)
			(xy 379.348954 -282.898086) (xy 379.400249 -282.889961) (xy 379.452183 -282.889961) (xy 379.503478 -282.898086)
			(xy 379.552871 -282.914134) (xy 379.599145 -282.937712) (xy 379.641161 -282.968238) (xy 379.677884 -283.004961)
			(xy 379.70841 -283.046977) (xy 379.731988 -283.093251) (xy 379.748036 -283.142644) (xy 379.756161 -283.193939)
			(xy 379.75667 -283.219906) (xy 379.756161 -283.245873) (xy 380.035817 -283.245873) (xy 380.035817 -283.193939)
			(xy 380.043942 -283.142644) (xy 380.05999 -283.093251) (xy 380.083568 -283.046977) (xy 380.114094 -283.004961)
			(xy 380.150817 -282.968238) (xy 380.192833 -282.937712) (xy 380.239107 -282.914134) (xy 380.2885 -282.898086)
			(xy 380.339795 -282.889961) (xy 380.391729 -282.889961) (xy 380.443024 -282.898086) (xy 380.492417 -282.914134)
			(xy 380.538691 -282.937712) (xy 380.580707 -282.968238) (xy 380.61743 -283.004961) (xy 380.647956 -283.046977)
			(xy 380.671534 -283.093251) (xy 380.687582 -283.142644) (xy 380.695707 -283.193939) (xy 380.696216 -283.219906)
			(xy 380.695707 -283.245873) (xy 380.975871 -283.245873) (xy 380.975871 -283.193939) (xy 380.983996 -283.142644)
			(xy 381.000044 -283.093251) (xy 381.023622 -283.046977) (xy 381.054148 -283.004961) (xy 381.090871 -282.968238)
			(xy 381.132887 -282.937712) (xy 381.179161 -282.914134) (xy 381.228554 -282.898086) (xy 381.279849 -282.889961)
			(xy 381.331783 -282.889961) (xy 381.383078 -282.898086) (xy 381.432471 -282.914134) (xy 381.478745 -282.937712)
			(xy 381.520761 -282.968238) (xy 381.557484 -283.004961) (xy 381.58801 -283.046977) (xy 381.611588 -283.093251)
			(xy 381.627636 -283.142644) (xy 381.635761 -283.193939) (xy 381.63627 -283.219906) (xy 381.635761 -283.245873)
			(xy 381.915671 -283.245873) (xy 381.915671 -283.193939) (xy 381.923796 -283.142644) (xy 381.939844 -283.093251)
			(xy 381.963422 -283.046977) (xy 381.993948 -283.004961) (xy 382.030671 -282.968238) (xy 382.072687 -282.937712)
			(xy 382.118961 -282.914134) (xy 382.168354 -282.898086) (xy 382.219649 -282.889961) (xy 382.271583 -282.889961)
			(xy 382.322878 -282.898086) (xy 382.372271 -282.914134) (xy 382.418545 -282.937712) (xy 382.460561 -282.968238)
			(xy 382.497284 -283.004961) (xy 382.52781 -283.046977) (xy 382.551388 -283.093251) (xy 382.567436 -283.142644)
			(xy 382.575561 -283.193939) (xy 382.57607 -283.219906) (xy 382.575561 -283.245873) (xy 382.855217 -283.245873)
			(xy 382.855217 -283.193939) (xy 382.863342 -283.142644) (xy 382.87939 -283.093251) (xy 382.902968 -283.046977)
			(xy 382.933494 -283.004961) (xy 382.970217 -282.968238) (xy 383.012233 -282.937712) (xy 383.058507 -282.914134)
			(xy 383.1079 -282.898086) (xy 383.159195 -282.889961) (xy 383.211129 -282.889961) (xy 383.262424 -282.898086)
			(xy 383.311817 -282.914134) (xy 383.358091 -282.937712) (xy 383.400107 -282.968238) (xy 383.43683 -283.004961)
			(xy 383.467356 -283.046977) (xy 383.490934 -283.093251) (xy 383.506982 -283.142644) (xy 383.515107 -283.193939)
			(xy 383.515616 -283.219906) (xy 383.515107 -283.245873) (xy 383.795017 -283.245873) (xy 383.795017 -283.193939)
			(xy 383.803142 -283.142644) (xy 383.81919 -283.093251) (xy 383.842768 -283.046977) (xy 383.873294 -283.004961)
			(xy 383.910017 -282.968238) (xy 383.952033 -282.937712) (xy 383.998307 -282.914134) (xy 384.0477 -282.898086)
			(xy 384.098995 -282.889961) (xy 384.150929 -282.889961) (xy 384.202224 -282.898086) (xy 384.251617 -282.914134)
			(xy 384.297891 -282.937712) (xy 384.339907 -282.968238) (xy 384.37663 -283.004961) (xy 384.407156 -283.046977)
			(xy 384.430734 -283.093251) (xy 384.446782 -283.142644) (xy 384.454907 -283.193939) (xy 384.455416 -283.219906)
			(xy 384.454907 -283.245873) (xy 384.446782 -283.297168) (xy 384.430734 -283.346561) (xy 384.407156 -283.392835)
			(xy 384.37663 -283.434851) (xy 384.339907 -283.471574) (xy 384.297891 -283.5021) (xy 384.251617 -283.525678)
			(xy 384.202224 -283.541726) (xy 384.150929 -283.549851) (xy 384.098995 -283.549851) (xy 384.0477 -283.541726)
			(xy 383.998307 -283.525678) (xy 383.952033 -283.5021) (xy 383.910017 -283.471574) (xy 383.873294 -283.434851)
			(xy 383.842768 -283.392835) (xy 383.81919 -283.346561) (xy 383.803142 -283.297168) (xy 383.795017 -283.245873)
			(xy 383.515107 -283.245873) (xy 383.506982 -283.297168) (xy 383.490934 -283.346561) (xy 383.467356 -283.392835)
			(xy 383.43683 -283.434851) (xy 383.400107 -283.471574) (xy 383.358091 -283.5021) (xy 383.311817 -283.525678)
			(xy 383.262424 -283.541726) (xy 383.211129 -283.549851) (xy 383.159195 -283.549851) (xy 383.1079 -283.541726)
			(xy 383.058507 -283.525678) (xy 383.012233 -283.5021) (xy 382.970217 -283.471574) (xy 382.933494 -283.434851)
			(xy 382.902968 -283.392835) (xy 382.87939 -283.346561) (xy 382.863342 -283.297168) (xy 382.855217 -283.245873)
			(xy 382.575561 -283.245873) (xy 382.567436 -283.297168) (xy 382.551388 -283.346561) (xy 382.52781 -283.392835)
			(xy 382.497284 -283.434851) (xy 382.460561 -283.471574) (xy 382.418545 -283.5021) (xy 382.372271 -283.525678)
			(xy 382.322878 -283.541726) (xy 382.271583 -283.549851) (xy 382.219649 -283.549851) (xy 382.168354 -283.541726)
			(xy 382.118961 -283.525678) (xy 382.072687 -283.5021) (xy 382.030671 -283.471574) (xy 381.993948 -283.434851)
			(xy 381.963422 -283.392835) (xy 381.939844 -283.346561) (xy 381.923796 -283.297168) (xy 381.915671 -283.245873)
			(xy 381.635761 -283.245873) (xy 381.627636 -283.297168) (xy 381.611588 -283.346561) (xy 381.58801 -283.392835)
			(xy 381.557484 -283.434851) (xy 381.520761 -283.471574) (xy 381.478745 -283.5021) (xy 381.432471 -283.525678)
			(xy 381.383078 -283.541726) (xy 381.331783 -283.549851) (xy 381.279849 -283.549851) (xy 381.228554 -283.541726)
			(xy 381.179161 -283.525678) (xy 381.132887 -283.5021) (xy 381.090871 -283.471574) (xy 381.054148 -283.434851)
			(xy 381.023622 -283.392835) (xy 381.000044 -283.346561) (xy 380.983996 -283.297168) (xy 380.975871 -283.245873)
			(xy 380.695707 -283.245873) (xy 380.687582 -283.297168) (xy 380.671534 -283.346561) (xy 380.647956 -283.392835)
			(xy 380.61743 -283.434851) (xy 380.580707 -283.471574) (xy 380.538691 -283.5021) (xy 380.492417 -283.525678)
			(xy 380.443024 -283.541726) (xy 380.391729 -283.549851) (xy 380.339795 -283.549851) (xy 380.2885 -283.541726)
			(xy 380.239107 -283.525678) (xy 380.192833 -283.5021) (xy 380.150817 -283.471574) (xy 380.114094 -283.434851)
			(xy 380.083568 -283.392835) (xy 380.05999 -283.346561) (xy 380.043942 -283.297168) (xy 380.035817 -283.245873)
			(xy 379.756161 -283.245873) (xy 379.748036 -283.297168) (xy 379.731988 -283.346561) (xy 379.70841 -283.392835)
			(xy 379.677884 -283.434851) (xy 379.641161 -283.471574) (xy 379.599145 -283.5021) (xy 379.552871 -283.525678)
			(xy 379.503478 -283.541726) (xy 379.452183 -283.549851) (xy 379.400249 -283.549851) (xy 379.348954 -283.541726)
			(xy 379.299561 -283.525678) (xy 379.253287 -283.5021) (xy 379.211271 -283.471574) (xy 379.174548 -283.434851)
			(xy 379.144022 -283.392835) (xy 379.120444 -283.346561) (xy 379.104396 -283.297168) (xy 379.096271 -283.245873)
			(xy 378.816107 -283.245873) (xy 378.807982 -283.297168) (xy 378.791934 -283.346561) (xy 378.768356 -283.392835)
			(xy 378.73783 -283.434851) (xy 378.701107 -283.471574) (xy 378.659091 -283.5021) (xy 378.612817 -283.525678)
			(xy 378.563424 -283.541726) (xy 378.512129 -283.549851) (xy 378.460195 -283.549851) (xy 378.4089 -283.541726)
			(xy 378.359507 -283.525678) (xy 378.313233 -283.5021) (xy 378.271217 -283.471574) (xy 378.234494 -283.434851)
			(xy 378.203968 -283.392835) (xy 378.18039 -283.346561) (xy 378.164342 -283.297168) (xy 378.156217 -283.245873)
			(xy 377.876307 -283.245873) (xy 377.868182 -283.297168) (xy 377.852134 -283.346561) (xy 377.828556 -283.392835)
			(xy 377.79803 -283.434851) (xy 377.761307 -283.471574) (xy 377.719291 -283.5021) (xy 377.673017 -283.525678)
			(xy 377.623624 -283.541726) (xy 377.572329 -283.549851) (xy 377.520395 -283.549851) (xy 377.4691 -283.541726)
			(xy 377.419707 -283.525678) (xy 377.373433 -283.5021) (xy 377.331417 -283.471574) (xy 377.294694 -283.434851)
			(xy 377.264168 -283.392835) (xy 377.24059 -283.346561) (xy 377.224542 -283.297168) (xy 377.216417 -283.245873)
			(xy 376.936467 -283.245873) (xy 376.928382 -283.296914) (xy 376.912334 -283.346307) (xy 376.888756 -283.392581)
			(xy 376.85823 -283.434597) (xy 376.821507 -283.47132) (xy 376.779491 -283.501846) (xy 376.733217 -283.525424)
			(xy 376.683824 -283.541472) (xy 376.632529 -283.549597) (xy 376.580595 -283.549597) (xy 376.5293 -283.541472)
			(xy 376.479907 -283.525424) (xy 376.433633 -283.501846) (xy 376.391617 -283.47132) (xy 376.354894 -283.434597)
			(xy 376.324368 -283.392581) (xy 376.30079 -283.346307) (xy 376.284742 -283.296914) (xy 376.276617 -283.245619)
			(xy 375.056912 -283.245619) (xy 375.056907 -283.245873) (xy 375.048782 -283.297168) (xy 375.032734 -283.346561)
			(xy 375.009156 -283.392835) (xy 374.97863 -283.434851) (xy 374.941907 -283.471574) (xy 374.899891 -283.5021)
			(xy 374.853617 -283.525678) (xy 374.804224 -283.541726) (xy 374.752929 -283.549851) (xy 374.700995 -283.549851)
			(xy 374.6497 -283.541726) (xy 374.600307 -283.525678) (xy 374.554033 -283.5021) (xy 374.512017 -283.471574)
			(xy 374.475294 -283.434851) (xy 374.444768 -283.392835) (xy 374.42119 -283.346561) (xy 374.405142 -283.297168)
			(xy 374.397017 -283.245873) (xy 374.117361 -283.245873) (xy 374.109236 -283.297168) (xy 374.093188 -283.346561)
			(xy 374.06961 -283.392835) (xy 374.039084 -283.434851) (xy 374.002361 -283.471574) (xy 373.960345 -283.5021)
			(xy 373.914071 -283.525678) (xy 373.864678 -283.541726) (xy 373.813383 -283.549851) (xy 373.761449 -283.549851)
			(xy 373.710154 -283.541726) (xy 373.660761 -283.525678) (xy 373.614487 -283.5021) (xy 373.572471 -283.471574)
			(xy 373.535748 -283.434851) (xy 373.505222 -283.392835) (xy 373.481644 -283.346561) (xy 373.465596 -283.297168)
			(xy 373.457471 -283.245873) (xy 373.177561 -283.245873) (xy 373.169436 -283.297168) (xy 373.153388 -283.346561)
			(xy 373.12981 -283.392835) (xy 373.099284 -283.434851) (xy 373.062561 -283.471574) (xy 373.020545 -283.5021)
			(xy 372.974271 -283.525678) (xy 372.924878 -283.541726) (xy 372.873583 -283.549851) (xy 372.821649 -283.549851)
			(xy 372.770354 -283.541726) (xy 372.720961 -283.525678) (xy 372.674687 -283.5021) (xy 372.632671 -283.471574)
			(xy 372.595948 -283.434851) (xy 372.565422 -283.392835) (xy 372.541844 -283.346561) (xy 372.525796 -283.297168)
			(xy 372.517671 -283.245873) (xy 371.297961 -283.245873) (xy 371.289836 -283.297168) (xy 371.273788 -283.346561)
			(xy 371.25021 -283.392835) (xy 371.219684 -283.434851) (xy 371.182961 -283.471574) (xy 371.140945 -283.5021)
			(xy 371.094671 -283.525678) (xy 371.045278 -283.541726) (xy 370.993983 -283.549851) (xy 370.942049 -283.549851)
			(xy 370.890754 -283.541726) (xy 370.841361 -283.525678) (xy 370.795087 -283.5021) (xy 370.753071 -283.471574)
			(xy 370.716348 -283.434851) (xy 370.685822 -283.392835) (xy 370.662244 -283.346561) (xy 370.646196 -283.297168)
			(xy 370.638071 -283.245873) (xy 370.357907 -283.245873) (xy 370.349782 -283.297168) (xy 370.333734 -283.346561)
			(xy 370.310156 -283.392835) (xy 370.27963 -283.434851) (xy 370.242907 -283.471574) (xy 370.200891 -283.5021)
			(xy 370.154617 -283.525678) (xy 370.105224 -283.541726) (xy 370.053929 -283.549851) (xy 370.001995 -283.549851)
			(xy 369.9507 -283.541726) (xy 369.901307 -283.525678) (xy 369.855033 -283.5021) (xy 369.813017 -283.471574)
			(xy 369.776294 -283.434851) (xy 369.745768 -283.392835) (xy 369.72219 -283.346561) (xy 369.706142 -283.297168)
			(xy 369.698017 -283.245873) (xy 369.418107 -283.245873) (xy 369.409982 -283.297168) (xy 369.393934 -283.346561)
			(xy 369.370356 -283.392835) (xy 369.33983 -283.434851) (xy 369.303107 -283.471574) (xy 369.261091 -283.5021)
			(xy 369.214817 -283.525678) (xy 369.165424 -283.541726) (xy 369.114129 -283.549851) (xy 369.062195 -283.549851)
			(xy 369.0109 -283.541726) (xy 368.961507 -283.525678) (xy 368.915233 -283.5021) (xy 368.873217 -283.471574)
			(xy 368.836494 -283.434851) (xy 368.805968 -283.392835) (xy 368.78239 -283.346561) (xy 368.766342 -283.297168)
			(xy 368.758217 -283.245873) (xy 368.478538 -283.245873) (xy 368.470415 -283.297159) (xy 368.454368 -283.346549)
			(xy 368.430792 -283.392821) (xy 368.400268 -283.434835) (xy 368.363547 -283.471557) (xy 368.321534 -283.502083)
			(xy 368.275264 -283.525662) (xy 368.225874 -283.541711) (xy 368.174582 -283.549838) (xy 368.148616 -283.55036)
			(xy 368.128078 -283.550049) (xy 368.087318 -283.544957) (xy 368.067336 -283.5402) (xy 368.052223 -283.5369)
			(xy 368.021347 -283.538557) (xy 367.99238 -283.549374) (xy 367.967975 -283.568358) (xy 367.950364 -283.593773)
			(xy 367.94116 -283.623291) (xy 367.94059 -283.638752) (xy 367.94059 -283.832554) (xy 367.956639 -283.85434)
			(xy 367.98216 -283.902049) (xy 367.999563 -283.953281) (xy 368.008381 -284.006664) (xy 368.008378 -284.059689)
			(xy 368.288317 -284.059689) (xy 368.288317 -284.007755) (xy 368.296442 -283.95646) (xy 368.31249 -283.907067)
			(xy 368.336068 -283.860793) (xy 368.366594 -283.818777) (xy 368.403317 -283.782054) (xy 368.445333 -283.751528)
			(xy 368.491607 -283.72795) (xy 368.541 -283.711902) (xy 368.592295 -283.703777) (xy 368.644229 -283.703777)
			(xy 368.695524 -283.711902) (xy 368.744917 -283.72795) (xy 368.791191 -283.751528) (xy 368.833207 -283.782054)
			(xy 368.86993 -283.818777) (xy 368.900456 -283.860793) (xy 368.924034 -283.907067) (xy 368.940082 -283.95646)
			(xy 368.948207 -284.007755) (xy 368.948716 -284.033722) (xy 368.948207 -284.059689) (xy 369.228117 -284.059689)
			(xy 369.228117 -284.007755) (xy 369.236242 -283.95646) (xy 369.25229 -283.907067) (xy 369.275868 -283.860793)
			(xy 369.306394 -283.818777) (xy 369.343117 -283.782054) (xy 369.385133 -283.751528) (xy 369.431407 -283.72795)
			(xy 369.4808 -283.711902) (xy 369.532095 -283.703777) (xy 369.584029 -283.703777) (xy 369.635324 -283.711902)
			(xy 369.684717 -283.72795) (xy 369.730991 -283.751528) (xy 369.773007 -283.782054) (xy 369.80973 -283.818777)
			(xy 369.840256 -283.860793) (xy 369.863834 -283.907067) (xy 369.879882 -283.95646) (xy 369.888007 -284.007755)
			(xy 369.888516 -284.033722) (xy 369.888007 -284.059689) (xy 370.167917 -284.059689) (xy 370.167917 -284.007755)
			(xy 370.176042 -283.95646) (xy 370.19209 -283.907067) (xy 370.215668 -283.860793) (xy 370.246194 -283.818777)
			(xy 370.282917 -283.782054) (xy 370.324933 -283.751528) (xy 370.371207 -283.72795) (xy 370.4206 -283.711902)
			(xy 370.471895 -283.703777) (xy 370.523829 -283.703777) (xy 370.575124 -283.711902) (xy 370.624517 -283.72795)
			(xy 370.670791 -283.751528) (xy 370.712807 -283.782054) (xy 370.74953 -283.818777) (xy 370.780056 -283.860793)
			(xy 370.803634 -283.907067) (xy 370.819682 -283.95646) (xy 370.827807 -284.007755) (xy 370.828316 -284.033722)
			(xy 370.827807 -284.059689) (xy 371.107717 -284.059689) (xy 371.107717 -284.007755) (xy 371.115842 -283.95646)
			(xy 371.13189 -283.907067) (xy 371.155468 -283.860793) (xy 371.185994 -283.818777) (xy 371.222717 -283.782054)
			(xy 371.264733 -283.751528) (xy 371.311007 -283.72795) (xy 371.3604 -283.711902) (xy 371.411695 -283.703777)
			(xy 371.463629 -283.703777) (xy 371.514924 -283.711902) (xy 371.564317 -283.72795) (xy 371.610591 -283.751528)
			(xy 371.652607 -283.782054) (xy 371.68933 -283.818777) (xy 371.719856 -283.860793) (xy 371.743434 -283.907067)
			(xy 371.759482 -283.95646) (xy 371.767607 -284.007755) (xy 371.768116 -284.033722) (xy 371.767607 -284.059689)
			(xy 372.047517 -284.059689) (xy 372.047517 -284.007755) (xy 372.055642 -283.95646) (xy 372.07169 -283.907067)
			(xy 372.095268 -283.860793) (xy 372.125794 -283.818777) (xy 372.162517 -283.782054) (xy 372.204533 -283.751528)
			(xy 372.250807 -283.72795) (xy 372.3002 -283.711902) (xy 372.351495 -283.703777) (xy 372.403429 -283.703777)
			(xy 372.454724 -283.711902) (xy 372.504117 -283.72795) (xy 372.550391 -283.751528) (xy 372.592407 -283.782054)
			(xy 372.62913 -283.818777) (xy 372.659656 -283.860793) (xy 372.683234 -283.907067) (xy 372.699282 -283.95646)
			(xy 372.707407 -284.007755) (xy 372.707916 -284.033722) (xy 372.707407 -284.059689) (xy 372.987571 -284.059689)
			(xy 372.987571 -284.007755) (xy 372.995696 -283.95646) (xy 373.011744 -283.907067) (xy 373.035322 -283.860793)
			(xy 373.065848 -283.818777) (xy 373.102571 -283.782054) (xy 373.144587 -283.751528) (xy 373.190861 -283.72795)
			(xy 373.240254 -283.711902) (xy 373.291549 -283.703777) (xy 373.343483 -283.703777) (xy 373.394778 -283.711902)
			(xy 373.444171 -283.72795) (xy 373.490445 -283.751528) (xy 373.532461 -283.782054) (xy 373.569184 -283.818777)
			(xy 373.59971 -283.860793) (xy 373.623288 -283.907067) (xy 373.639336 -283.95646) (xy 373.647461 -284.007755)
			(xy 373.64797 -284.033722) (xy 373.647461 -284.059689) (xy 373.927117 -284.059689) (xy 373.927117 -284.007755)
			(xy 373.935242 -283.95646) (xy 373.95129 -283.907067) (xy 373.974868 -283.860793) (xy 374.005394 -283.818777)
			(xy 374.042117 -283.782054) (xy 374.084133 -283.751528) (xy 374.130407 -283.72795) (xy 374.1798 -283.711902)
			(xy 374.231095 -283.703777) (xy 374.283029 -283.703777) (xy 374.334324 -283.711902) (xy 374.383717 -283.72795)
			(xy 374.429991 -283.751528) (xy 374.472007 -283.782054) (xy 374.50873 -283.818777) (xy 374.539256 -283.860793)
			(xy 374.562834 -283.907067) (xy 374.578882 -283.95646) (xy 374.587007 -284.007755) (xy 374.587516 -284.033722)
			(xy 374.587007 -284.059689) (xy 374.866917 -284.059689) (xy 374.866917 -284.007755) (xy 374.875042 -283.95646)
			(xy 374.89109 -283.907067) (xy 374.914668 -283.860793) (xy 374.945194 -283.818777) (xy 374.981917 -283.782054)
			(xy 375.023933 -283.751528) (xy 375.070207 -283.72795) (xy 375.1196 -283.711902) (xy 375.170895 -283.703777)
			(xy 375.222829 -283.703777) (xy 375.274124 -283.711902) (xy 375.323517 -283.72795) (xy 375.369791 -283.751528)
			(xy 375.411807 -283.782054) (xy 375.44853 -283.818777) (xy 375.479056 -283.860793) (xy 375.502634 -283.907067)
			(xy 375.518682 -283.95646) (xy 375.526807 -284.007755) (xy 375.527316 -284.033722) (xy 375.526807 -284.059689)
			(xy 375.806717 -284.059689) (xy 375.806717 -284.007755) (xy 375.814842 -283.95646) (xy 375.83089 -283.907067)
			(xy 375.854468 -283.860793) (xy 375.884994 -283.818777) (xy 375.921717 -283.782054) (xy 375.963733 -283.751528)
			(xy 376.010007 -283.72795) (xy 376.0594 -283.711902) (xy 376.110695 -283.703777) (xy 376.162629 -283.703777)
			(xy 376.213924 -283.711902) (xy 376.263317 -283.72795) (xy 376.309591 -283.751528) (xy 376.351607 -283.782054)
			(xy 376.38833 -283.818777) (xy 376.418856 -283.860793) (xy 376.442434 -283.907067) (xy 376.458482 -283.95646)
			(xy 376.466607 -284.007755) (xy 376.467116 -284.033722) (xy 376.466607 -284.059689) (xy 376.746517 -284.059689)
			(xy 376.746517 -284.007755) (xy 376.754642 -283.95646) (xy 376.77069 -283.907067) (xy 376.794268 -283.860793)
			(xy 376.824794 -283.818777) (xy 376.861517 -283.782054) (xy 376.903533 -283.751528) (xy 376.949807 -283.72795)
			(xy 376.9992 -283.711902) (xy 377.050495 -283.703777) (xy 377.102429 -283.703777) (xy 377.153724 -283.711902)
			(xy 377.203117 -283.72795) (xy 377.249391 -283.751528) (xy 377.291407 -283.782054) (xy 377.32813 -283.818777)
			(xy 377.358656 -283.860793) (xy 377.382234 -283.907067) (xy 377.398282 -283.95646) (xy 377.406407 -284.007755)
			(xy 377.406916 -284.033722) (xy 377.406407 -284.059689) (xy 377.686317 -284.059689) (xy 377.686317 -284.007755)
			(xy 377.694442 -283.95646) (xy 377.71049 -283.907067) (xy 377.734068 -283.860793) (xy 377.764594 -283.818777)
			(xy 377.801317 -283.782054) (xy 377.843333 -283.751528) (xy 377.889607 -283.72795) (xy 377.939 -283.711902)
			(xy 377.990295 -283.703777) (xy 378.042229 -283.703777) (xy 378.093524 -283.711902) (xy 378.142917 -283.72795)
			(xy 378.189191 -283.751528) (xy 378.231207 -283.782054) (xy 378.26793 -283.818777) (xy 378.298456 -283.860793)
			(xy 378.322034 -283.907067) (xy 378.338082 -283.95646) (xy 378.346207 -284.007755) (xy 378.346716 -284.033722)
			(xy 378.346207 -284.059689) (xy 378.626117 -284.059689) (xy 378.626117 -284.007755) (xy 378.634242 -283.95646)
			(xy 378.65029 -283.907067) (xy 378.673868 -283.860793) (xy 378.704394 -283.818777) (xy 378.741117 -283.782054)
			(xy 378.783133 -283.751528) (xy 378.829407 -283.72795) (xy 378.8788 -283.711902) (xy 378.930095 -283.703777)
			(xy 378.982029 -283.703777) (xy 379.033324 -283.711902) (xy 379.082717 -283.72795) (xy 379.128991 -283.751528)
			(xy 379.171007 -283.782054) (xy 379.20773 -283.818777) (xy 379.238256 -283.860793) (xy 379.261834 -283.907067)
			(xy 379.277882 -283.95646) (xy 379.286007 -284.007755) (xy 379.286516 -284.033722) (xy 379.286007 -284.059689)
			(xy 379.565917 -284.059689) (xy 379.565917 -284.007755) (xy 379.574042 -283.95646) (xy 379.59009 -283.907067)
			(xy 379.613668 -283.860793) (xy 379.644194 -283.818777) (xy 379.680917 -283.782054) (xy 379.722933 -283.751528)
			(xy 379.769207 -283.72795) (xy 379.8186 -283.711902) (xy 379.869895 -283.703777) (xy 379.921829 -283.703777)
			(xy 379.973124 -283.711902) (xy 380.022517 -283.72795) (xy 380.068791 -283.751528) (xy 380.110807 -283.782054)
			(xy 380.14753 -283.818777) (xy 380.178056 -283.860793) (xy 380.201634 -283.907067) (xy 380.217682 -283.95646)
			(xy 380.225807 -284.007755) (xy 380.226316 -284.033722) (xy 380.225807 -284.059689) (xy 380.505717 -284.059689)
			(xy 380.505717 -284.007755) (xy 380.513842 -283.95646) (xy 380.52989 -283.907067) (xy 380.553468 -283.860793)
			(xy 380.583994 -283.818777) (xy 380.620717 -283.782054) (xy 380.662733 -283.751528) (xy 380.709007 -283.72795)
			(xy 380.7584 -283.711902) (xy 380.809695 -283.703777) (xy 380.861629 -283.703777) (xy 380.912924 -283.711902)
			(xy 380.962317 -283.72795) (xy 381.008591 -283.751528) (xy 381.050607 -283.782054) (xy 381.08733 -283.818777)
			(xy 381.117856 -283.860793) (xy 381.141434 -283.907067) (xy 381.157482 -283.95646) (xy 381.165607 -284.007755)
			(xy 381.166116 -284.033722) (xy 381.165607 -284.059689) (xy 382.385317 -284.059689) (xy 382.385317 -284.007755)
			(xy 382.393442 -283.95646) (xy 382.40949 -283.907067) (xy 382.433068 -283.860793) (xy 382.463594 -283.818777)
			(xy 382.500317 -283.782054) (xy 382.542333 -283.751528) (xy 382.588607 -283.72795) (xy 382.638 -283.711902)
			(xy 382.689295 -283.703777) (xy 382.741229 -283.703777) (xy 382.792524 -283.711902) (xy 382.841917 -283.72795)
			(xy 382.888191 -283.751528) (xy 382.930207 -283.782054) (xy 382.96693 -283.818777) (xy 382.997456 -283.860793)
			(xy 383.021034 -283.907067) (xy 383.037082 -283.95646) (xy 383.045207 -284.007755) (xy 383.045716 -284.033722)
			(xy 383.045207 -284.059689) (xy 383.037082 -284.110984) (xy 383.021034 -284.160377) (xy 382.997456 -284.206651)
			(xy 382.96693 -284.248667) (xy 382.930207 -284.28539) (xy 382.888191 -284.315916) (xy 382.841917 -284.339494)
			(xy 382.792524 -284.355542) (xy 382.741229 -284.363667) (xy 382.689295 -284.363667) (xy 382.638 -284.355542)
			(xy 382.588607 -284.339494) (xy 382.542333 -284.315916) (xy 382.500317 -284.28539) (xy 382.463594 -284.248667)
			(xy 382.433068 -284.206651) (xy 382.40949 -284.160377) (xy 382.393442 -284.110984) (xy 382.385317 -284.059689)
			(xy 381.165607 -284.059689) (xy 381.157482 -284.110984) (xy 381.141434 -284.160377) (xy 381.117856 -284.206651)
			(xy 381.08733 -284.248667) (xy 381.050607 -284.28539) (xy 381.008591 -284.315916) (xy 380.962317 -284.339494)
			(xy 380.912924 -284.355542) (xy 380.861629 -284.363667) (xy 380.809695 -284.363667) (xy 380.7584 -284.355542)
			(xy 380.709007 -284.339494) (xy 380.662733 -284.315916) (xy 380.620717 -284.28539) (xy 380.583994 -284.248667)
			(xy 380.553468 -284.206651) (xy 380.52989 -284.160377) (xy 380.513842 -284.110984) (xy 380.505717 -284.059689)
			(xy 380.225807 -284.059689) (xy 380.217682 -284.110984) (xy 380.201634 -284.160377) (xy 380.178056 -284.206651)
			(xy 380.14753 -284.248667) (xy 380.110807 -284.28539) (xy 380.068791 -284.315916) (xy 380.022517 -284.339494)
			(xy 379.973124 -284.355542) (xy 379.921829 -284.363667) (xy 379.869895 -284.363667) (xy 379.8186 -284.355542)
			(xy 379.769207 -284.339494) (xy 379.722933 -284.315916) (xy 379.680917 -284.28539) (xy 379.644194 -284.248667)
			(xy 379.613668 -284.206651) (xy 379.59009 -284.160377) (xy 379.574042 -284.110984) (xy 379.565917 -284.059689)
			(xy 379.286007 -284.059689) (xy 379.277882 -284.110984) (xy 379.261834 -284.160377) (xy 379.238256 -284.206651)
			(xy 379.20773 -284.248667) (xy 379.171007 -284.28539) (xy 379.128991 -284.315916) (xy 379.082717 -284.339494)
			(xy 379.033324 -284.355542) (xy 378.982029 -284.363667) (xy 378.930095 -284.363667) (xy 378.8788 -284.355542)
			(xy 378.829407 -284.339494) (xy 378.783133 -284.315916) (xy 378.741117 -284.28539) (xy 378.704394 -284.248667)
			(xy 378.673868 -284.206651) (xy 378.65029 -284.160377) (xy 378.634242 -284.110984) (xy 378.626117 -284.059689)
			(xy 378.346207 -284.059689) (xy 378.338082 -284.110984) (xy 378.322034 -284.160377) (xy 378.298456 -284.206651)
			(xy 378.26793 -284.248667) (xy 378.231207 -284.28539) (xy 378.189191 -284.315916) (xy 378.142917 -284.339494)
			(xy 378.093524 -284.355542) (xy 378.042229 -284.363667) (xy 377.990295 -284.363667) (xy 377.939 -284.355542)
			(xy 377.889607 -284.339494) (xy 377.843333 -284.315916) (xy 377.801317 -284.28539) (xy 377.764594 -284.248667)
			(xy 377.734068 -284.206651) (xy 377.71049 -284.160377) (xy 377.694442 -284.110984) (xy 377.686317 -284.059689)
			(xy 377.406407 -284.059689) (xy 377.398282 -284.110984) (xy 377.382234 -284.160377) (xy 377.358656 -284.206651)
			(xy 377.32813 -284.248667) (xy 377.291407 -284.28539) (xy 377.249391 -284.315916) (xy 377.203117 -284.339494)
			(xy 377.153724 -284.355542) (xy 377.102429 -284.363667) (xy 377.050495 -284.363667) (xy 376.9992 -284.355542)
			(xy 376.949807 -284.339494) (xy 376.903533 -284.315916) (xy 376.861517 -284.28539) (xy 376.824794 -284.248667)
			(xy 376.794268 -284.206651) (xy 376.77069 -284.160377) (xy 376.754642 -284.110984) (xy 376.746517 -284.059689)
			(xy 376.466607 -284.059689) (xy 376.458482 -284.110984) (xy 376.442434 -284.160377) (xy 376.418856 -284.206651)
			(xy 376.38833 -284.248667) (xy 376.351607 -284.28539) (xy 376.309591 -284.315916) (xy 376.263317 -284.339494)
			(xy 376.213924 -284.355542) (xy 376.162629 -284.363667) (xy 376.110695 -284.363667) (xy 376.0594 -284.355542)
			(xy 376.010007 -284.339494) (xy 375.963733 -284.315916) (xy 375.921717 -284.28539) (xy 375.884994 -284.248667)
			(xy 375.854468 -284.206651) (xy 375.83089 -284.160377) (xy 375.814842 -284.110984) (xy 375.806717 -284.059689)
			(xy 375.526807 -284.059689) (xy 375.518682 -284.110984) (xy 375.502634 -284.160377) (xy 375.479056 -284.206651)
			(xy 375.44853 -284.248667) (xy 375.411807 -284.28539) (xy 375.369791 -284.315916) (xy 375.323517 -284.339494)
			(xy 375.274124 -284.355542) (xy 375.222829 -284.363667) (xy 375.170895 -284.363667) (xy 375.1196 -284.355542)
			(xy 375.070207 -284.339494) (xy 375.023933 -284.315916) (xy 374.981917 -284.28539) (xy 374.945194 -284.248667)
			(xy 374.914668 -284.206651) (xy 374.89109 -284.160377) (xy 374.875042 -284.110984) (xy 374.866917 -284.059689)
			(xy 374.587007 -284.059689) (xy 374.578882 -284.110984) (xy 374.562834 -284.160377) (xy 374.539256 -284.206651)
			(xy 374.50873 -284.248667) (xy 374.472007 -284.28539) (xy 374.429991 -284.315916) (xy 374.383717 -284.339494)
			(xy 374.334324 -284.355542) (xy 374.283029 -284.363667) (xy 374.231095 -284.363667) (xy 374.1798 -284.355542)
			(xy 374.130407 -284.339494) (xy 374.084133 -284.315916) (xy 374.042117 -284.28539) (xy 374.005394 -284.248667)
			(xy 373.974868 -284.206651) (xy 373.95129 -284.160377) (xy 373.935242 -284.110984) (xy 373.927117 -284.059689)
			(xy 373.647461 -284.059689) (xy 373.639336 -284.110984) (xy 373.623288 -284.160377) (xy 373.59971 -284.206651)
			(xy 373.569184 -284.248667) (xy 373.532461 -284.28539) (xy 373.490445 -284.315916) (xy 373.444171 -284.339494)
			(xy 373.394778 -284.355542) (xy 373.343483 -284.363667) (xy 373.291549 -284.363667) (xy 373.240254 -284.355542)
			(xy 373.190861 -284.339494) (xy 373.144587 -284.315916) (xy 373.102571 -284.28539) (xy 373.065848 -284.248667)
			(xy 373.035322 -284.206651) (xy 373.011744 -284.160377) (xy 372.995696 -284.110984) (xy 372.987571 -284.059689)
			(xy 372.707407 -284.059689) (xy 372.699282 -284.110984) (xy 372.683234 -284.160377) (xy 372.659656 -284.206651)
			(xy 372.62913 -284.248667) (xy 372.592407 -284.28539) (xy 372.550391 -284.315916) (xy 372.504117 -284.339494)
			(xy 372.454724 -284.355542) (xy 372.403429 -284.363667) (xy 372.351495 -284.363667) (xy 372.3002 -284.355542)
			(xy 372.250807 -284.339494) (xy 372.204533 -284.315916) (xy 372.162517 -284.28539) (xy 372.125794 -284.248667)
			(xy 372.095268 -284.206651) (xy 372.07169 -284.160377) (xy 372.055642 -284.110984) (xy 372.047517 -284.059689)
			(xy 371.767607 -284.059689) (xy 371.759482 -284.110984) (xy 371.743434 -284.160377) (xy 371.719856 -284.206651)
			(xy 371.68933 -284.248667) (xy 371.652607 -284.28539) (xy 371.610591 -284.315916) (xy 371.564317 -284.339494)
			(xy 371.514924 -284.355542) (xy 371.463629 -284.363667) (xy 371.411695 -284.363667) (xy 371.3604 -284.355542)
			(xy 371.311007 -284.339494) (xy 371.264733 -284.315916) (xy 371.222717 -284.28539) (xy 371.185994 -284.248667)
			(xy 371.155468 -284.206651) (xy 371.13189 -284.160377) (xy 371.115842 -284.110984) (xy 371.107717 -284.059689)
			(xy 370.827807 -284.059689) (xy 370.819682 -284.110984) (xy 370.803634 -284.160377) (xy 370.780056 -284.206651)
			(xy 370.74953 -284.248667) (xy 370.712807 -284.28539) (xy 370.670791 -284.315916) (xy 370.624517 -284.339494)
			(xy 370.575124 -284.355542) (xy 370.523829 -284.363667) (xy 370.471895 -284.363667) (xy 370.4206 -284.355542)
			(xy 370.371207 -284.339494) (xy 370.324933 -284.315916) (xy 370.282917 -284.28539) (xy 370.246194 -284.248667)
			(xy 370.215668 -284.206651) (xy 370.19209 -284.160377) (xy 370.176042 -284.110984) (xy 370.167917 -284.059689)
			(xy 369.888007 -284.059689) (xy 369.879882 -284.110984) (xy 369.863834 -284.160377) (xy 369.840256 -284.206651)
			(xy 369.80973 -284.248667) (xy 369.773007 -284.28539) (xy 369.730991 -284.315916) (xy 369.684717 -284.339494)
			(xy 369.635324 -284.355542) (xy 369.584029 -284.363667) (xy 369.532095 -284.363667) (xy 369.4808 -284.355542)
			(xy 369.431407 -284.339494) (xy 369.385133 -284.315916) (xy 369.343117 -284.28539) (xy 369.306394 -284.248667)
			(xy 369.275868 -284.206651) (xy 369.25229 -284.160377) (xy 369.236242 -284.110984) (xy 369.228117 -284.059689)
			(xy 368.948207 -284.059689) (xy 368.940082 -284.110984) (xy 368.924034 -284.160377) (xy 368.900456 -284.206651)
			(xy 368.86993 -284.248667) (xy 368.833207 -284.28539) (xy 368.791191 -284.315916) (xy 368.744917 -284.339494)
			(xy 368.695524 -284.355542) (xy 368.644229 -284.363667) (xy 368.592295 -284.363667) (xy 368.541 -284.355542)
			(xy 368.491607 -284.339494) (xy 368.445333 -284.315916) (xy 368.403317 -284.28539) (xy 368.366594 -284.248667)
			(xy 368.336068 -284.206651) (xy 368.31249 -284.160377) (xy 368.296442 -284.110984) (xy 368.288317 -284.059689)
			(xy 368.008378 -284.059689) (xy 368.008378 -284.060771) (xy 367.999554 -284.114153) (xy 367.982146 -284.165383)
			(xy 367.95662 -284.21309) (xy 367.94059 -284.23489) (xy 367.94059 -284.847538) (xy 368.757962 -284.847538)
			(xy 368.758471 -284.821571) (xy 368.766596 -284.770276) (xy 368.782644 -284.720883) (xy 368.806222 -284.674609)
			(xy 368.836748 -284.632593) (xy 368.873471 -284.59587) (xy 368.915487 -284.565344) (xy 368.961761 -284.541766)
			(xy 369.011154 -284.525718) (xy 369.062449 -284.517593) (xy 369.114383 -284.517593) (xy 369.165678 -284.525718)
			(xy 369.215071 -284.541766) (xy 369.261345 -284.565344) (xy 369.303361 -284.59587) (xy 369.340084 -284.632593)
			(xy 369.37061 -284.674609) (xy 369.394188 -284.720883) (xy 369.410236 -284.770276) (xy 369.418361 -284.821571)
			(xy 369.41887 -284.847538) (xy 370.637562 -284.847538) (xy 370.638071 -284.821571) (xy 370.646196 -284.770276)
			(xy 370.662244 -284.720883) (xy 370.685822 -284.674609) (xy 370.716348 -284.632593) (xy 370.753071 -284.59587)
			(xy 370.795087 -284.565344) (xy 370.841361 -284.541766) (xy 370.890754 -284.525718) (xy 370.942049 -284.517593)
			(xy 370.993983 -284.517593) (xy 371.045278 -284.525718) (xy 371.094671 -284.541766) (xy 371.140945 -284.565344)
			(xy 371.182961 -284.59587) (xy 371.219684 -284.632593) (xy 371.25021 -284.674609) (xy 371.273788 -284.720883)
			(xy 371.289836 -284.770276) (xy 371.297961 -284.821571) (xy 371.29847 -284.847538) (xy 372.517162 -284.847538)
			(xy 372.517671 -284.821571) (xy 372.525796 -284.770276) (xy 372.541844 -284.720883) (xy 372.565422 -284.674609)
			(xy 372.595948 -284.632593) (xy 372.632671 -284.59587) (xy 372.674687 -284.565344) (xy 372.720961 -284.541766)
			(xy 372.770354 -284.525718) (xy 372.821649 -284.517593) (xy 372.873583 -284.517593) (xy 372.924878 -284.525718)
			(xy 372.974271 -284.541766) (xy 373.020545 -284.565344) (xy 373.062561 -284.59587) (xy 373.099284 -284.632593)
			(xy 373.12981 -284.674609) (xy 373.153388 -284.720883) (xy 373.169436 -284.770276) (xy 373.177561 -284.821571)
			(xy 373.17807 -284.847538) (xy 373.177567 -284.873505) (xy 373.457471 -284.873505) (xy 373.457471 -284.821571)
			(xy 373.465596 -284.770276) (xy 373.481644 -284.720883) (xy 373.505222 -284.674609) (xy 373.535748 -284.632593)
			(xy 373.572471 -284.59587) (xy 373.614487 -284.565344) (xy 373.660761 -284.541766) (xy 373.710154 -284.525718)
			(xy 373.761449 -284.517593) (xy 373.813383 -284.517593) (xy 373.864678 -284.525718) (xy 373.914071 -284.541766)
			(xy 373.960345 -284.565344) (xy 374.002361 -284.59587) (xy 374.039084 -284.632593) (xy 374.06961 -284.674609)
			(xy 374.093188 -284.720883) (xy 374.109236 -284.770276) (xy 374.117361 -284.821571) (xy 374.11787 -284.847538)
			(xy 374.396762 -284.847538) (xy 374.397271 -284.821571) (xy 374.405396 -284.770276) (xy 374.421444 -284.720883)
			(xy 374.445022 -284.674609) (xy 374.475548 -284.632593) (xy 374.512271 -284.59587) (xy 374.554287 -284.565344)
			(xy 374.600561 -284.541766) (xy 374.649954 -284.525718) (xy 374.701249 -284.517593) (xy 374.753183 -284.517593)
			(xy 374.804478 -284.525718) (xy 374.853871 -284.541766) (xy 374.900145 -284.565344) (xy 374.942161 -284.59587)
			(xy 374.978884 -284.632593) (xy 375.00941 -284.674609) (xy 375.032988 -284.720883) (xy 375.049036 -284.770276)
			(xy 375.057161 -284.821571) (xy 375.05767 -284.847538) (xy 376.276362 -284.847538) (xy 376.276871 -284.821571)
			(xy 376.284996 -284.770276) (xy 376.301044 -284.720883) (xy 376.324622 -284.674609) (xy 376.355148 -284.632593)
			(xy 376.391871 -284.59587) (xy 376.433887 -284.565344) (xy 376.480161 -284.541766) (xy 376.529554 -284.525718)
			(xy 376.580849 -284.517593) (xy 376.632783 -284.517593) (xy 376.684078 -284.525718) (xy 376.733471 -284.541766)
			(xy 376.779745 -284.565344) (xy 376.821761 -284.59587) (xy 376.858484 -284.632593) (xy 376.88901 -284.674609)
			(xy 376.912588 -284.720883) (xy 376.928636 -284.770276) (xy 376.936761 -284.821571) (xy 376.93727 -284.847538)
			(xy 378.155962 -284.847538) (xy 378.156471 -284.821571) (xy 378.164596 -284.770276) (xy 378.180644 -284.720883)
			(xy 378.204222 -284.674609) (xy 378.234748 -284.632593) (xy 378.271471 -284.59587) (xy 378.313487 -284.565344)
			(xy 378.359761 -284.541766) (xy 378.409154 -284.525718) (xy 378.460449 -284.517593) (xy 378.512383 -284.517593)
			(xy 378.563678 -284.525718) (xy 378.613071 -284.541766) (xy 378.659345 -284.565344) (xy 378.701361 -284.59587)
			(xy 378.738084 -284.632593) (xy 378.76861 -284.674609) (xy 378.792188 -284.720883) (xy 378.808236 -284.770276)
			(xy 378.816361 -284.821571) (xy 378.81687 -284.847538) (xy 380.035562 -284.847538) (xy 380.036071 -284.821571)
			(xy 380.044196 -284.770276) (xy 380.060244 -284.720883) (xy 380.083822 -284.674609) (xy 380.114348 -284.632593)
			(xy 380.151071 -284.59587) (xy 380.193087 -284.565344) (xy 380.239361 -284.541766) (xy 380.288754 -284.525718)
			(xy 380.340049 -284.517593) (xy 380.391983 -284.517593) (xy 380.443278 -284.525718) (xy 380.492671 -284.541766)
			(xy 380.538945 -284.565344) (xy 380.580961 -284.59587) (xy 380.617684 -284.632593) (xy 380.64821 -284.674609)
			(xy 380.671788 -284.720883) (xy 380.687836 -284.770276) (xy 380.695961 -284.821571) (xy 380.69647 -284.847538)
			(xy 380.695967 -284.873505) (xy 381.915671 -284.873505) (xy 381.915671 -284.821571) (xy 381.923796 -284.770276)
			(xy 381.939844 -284.720883) (xy 381.963422 -284.674609) (xy 381.993948 -284.632593) (xy 382.030671 -284.59587)
			(xy 382.072687 -284.565344) (xy 382.118961 -284.541766) (xy 382.168354 -284.525718) (xy 382.219649 -284.517593)
			(xy 382.271583 -284.517593) (xy 382.322878 -284.525718) (xy 382.372271 -284.541766) (xy 382.418545 -284.565344)
			(xy 382.460561 -284.59587) (xy 382.497284 -284.632593) (xy 382.52781 -284.674609) (xy 382.551388 -284.720883)
			(xy 382.567436 -284.770276) (xy 382.575561 -284.821571) (xy 382.57607 -284.847538) (xy 382.575566 -284.873251)
			(xy 382.855217 -284.873251) (xy 382.855217 -284.821317) (xy 382.863342 -284.770022) (xy 382.87939 -284.720629)
			(xy 382.902968 -284.674355) (xy 382.933494 -284.632339) (xy 382.970217 -284.595616) (xy 383.012233 -284.56509)
			(xy 383.058507 -284.541512) (xy 383.1079 -284.525464) (xy 383.159195 -284.517339) (xy 383.211129 -284.517339)
			(xy 383.262424 -284.525464) (xy 383.311817 -284.541512) (xy 383.358091 -284.56509) (xy 383.400107 -284.595616)
			(xy 383.43683 -284.632339) (xy 383.467356 -284.674355) (xy 383.490934 -284.720629) (xy 383.506982 -284.770022)
			(xy 383.515107 -284.821317) (xy 383.515616 -284.847284) (xy 383.515107 -284.873251) (xy 383.795017 -284.873251)
			(xy 383.795017 -284.821317) (xy 383.803142 -284.770022) (xy 383.81919 -284.720629) (xy 383.842768 -284.674355)
			(xy 383.873294 -284.632339) (xy 383.910017 -284.595616) (xy 383.952033 -284.56509) (xy 383.998307 -284.541512)
			(xy 384.0477 -284.525464) (xy 384.098995 -284.517339) (xy 384.150929 -284.517339) (xy 384.202224 -284.525464)
			(xy 384.251617 -284.541512) (xy 384.297891 -284.56509) (xy 384.339907 -284.595616) (xy 384.37663 -284.632339)
			(xy 384.407156 -284.674355) (xy 384.430734 -284.720629) (xy 384.446782 -284.770022) (xy 384.454907 -284.821317)
			(xy 384.455416 -284.847284) (xy 384.454907 -284.873251) (xy 384.734817 -284.873251) (xy 384.734817 -284.821317)
			(xy 384.742942 -284.770022) (xy 384.75899 -284.720629) (xy 384.782568 -284.674355) (xy 384.813094 -284.632339)
			(xy 384.849817 -284.595616) (xy 384.891833 -284.56509) (xy 384.938107 -284.541512) (xy 384.9875 -284.525464)
			(xy 385.038795 -284.517339) (xy 385.090729 -284.517339) (xy 385.142024 -284.525464) (xy 385.191417 -284.541512)
			(xy 385.237691 -284.56509) (xy 385.279707 -284.595616) (xy 385.31643 -284.632339) (xy 385.346956 -284.674355)
			(xy 385.370534 -284.720629) (xy 385.386582 -284.770022) (xy 385.394707 -284.821317) (xy 385.395216 -284.847284)
			(xy 385.394707 -284.873251) (xy 385.386582 -284.924546) (xy 385.370534 -284.973939) (xy 385.346956 -285.020213)
			(xy 385.31643 -285.062229) (xy 385.279707 -285.098952) (xy 385.237691 -285.129478) (xy 385.191417 -285.153056)
			(xy 385.142024 -285.169104) (xy 385.090729 -285.177229) (xy 385.038795 -285.177229) (xy 384.9875 -285.169104)
			(xy 384.938107 -285.153056) (xy 384.891833 -285.129478) (xy 384.849817 -285.098952) (xy 384.813094 -285.062229)
			(xy 384.782568 -285.020213) (xy 384.75899 -284.973939) (xy 384.742942 -284.924546) (xy 384.734817 -284.873251)
			(xy 384.454907 -284.873251) (xy 384.446782 -284.924546) (xy 384.430734 -284.973939) (xy 384.407156 -285.020213)
			(xy 384.37663 -285.062229) (xy 384.339907 -285.098952) (xy 384.297891 -285.129478) (xy 384.251617 -285.153056)
			(xy 384.202224 -285.169104) (xy 384.150929 -285.177229) (xy 384.098995 -285.177229) (xy 384.0477 -285.169104)
			(xy 383.998307 -285.153056) (xy 383.952033 -285.129478) (xy 383.910017 -285.098952) (xy 383.873294 -285.062229)
			(xy 383.842768 -285.020213) (xy 383.81919 -284.973939) (xy 383.803142 -284.924546) (xy 383.795017 -284.873251)
			(xy 383.515107 -284.873251) (xy 383.506982 -284.924546) (xy 383.490934 -284.973939) (xy 383.467356 -285.020213)
			(xy 383.43683 -285.062229) (xy 383.400107 -285.098952) (xy 383.358091 -285.129478) (xy 383.311817 -285.153056)
			(xy 383.262424 -285.169104) (xy 383.211129 -285.177229) (xy 383.159195 -285.177229) (xy 383.1079 -285.169104)
			(xy 383.058507 -285.153056) (xy 383.012233 -285.129478) (xy 382.970217 -285.098952) (xy 382.933494 -285.062229)
			(xy 382.902968 -285.020213) (xy 382.87939 -284.973939) (xy 382.863342 -284.924546) (xy 382.855217 -284.873251)
			(xy 382.575566 -284.873251) (xy 382.575561 -284.873505) (xy 382.567436 -284.9248) (xy 382.551388 -284.974193)
			(xy 382.52781 -285.020467) (xy 382.497284 -285.062483) (xy 382.460561 -285.099206) (xy 382.418545 -285.129732)
			(xy 382.372271 -285.15331) (xy 382.322878 -285.169358) (xy 382.271583 -285.177483) (xy 382.219649 -285.177483)
			(xy 382.168354 -285.169358) (xy 382.118961 -285.15331) (xy 382.072687 -285.129732) (xy 382.030671 -285.099206)
			(xy 381.993948 -285.062483) (xy 381.963422 -285.020467) (xy 381.939844 -284.974193) (xy 381.923796 -284.9248)
			(xy 381.915671 -284.873505) (xy 380.695967 -284.873505) (xy 380.695928 -284.875524) (xy 380.686471 -284.930692)
			(xy 380.677674 -284.957266) (xy 380.670054 -284.979364) (xy 380.873762 -285.33217) (xy 380.896622 -285.336488)
			(xy 380.921546 -285.341648) (xy 380.969531 -285.358612) (xy 381.014351 -285.382729) (xy 381.054944 -285.41343)
			(xy 381.090354 -285.449989) (xy 381.119742 -285.491543) (xy 381.142415 -285.537109) (xy 381.157837 -285.585612)
			(xy 381.165644 -285.635906) (xy 381.166116 -285.661354) (xy 381.165607 -285.687321) (xy 381.157482 -285.738616)
			(xy 381.141434 -285.788009) (xy 381.117856 -285.834283) (xy 381.08733 -285.876299) (xy 381.050607 -285.913022)
			(xy 381.008591 -285.943548) (xy 380.962317 -285.967126) (xy 380.912924 -285.983174) (xy 380.861629 -285.991299)
			(xy 380.809695 -285.991299) (xy 380.7584 -285.983174) (xy 380.709007 -285.967126) (xy 380.662733 -285.943548)
			(xy 380.620717 -285.913022) (xy 380.583994 -285.876299) (xy 380.553468 -285.834283) (xy 380.52989 -285.788009)
			(xy 380.513842 -285.738616) (xy 380.505717 -285.687321) (xy 380.505208 -285.661354) (xy 380.505749 -285.633368)
			(xy 380.515207 -285.5782) (xy 380.524004 -285.551626) (xy 380.531624 -285.529528) (xy 380.327916 -285.176722)
			(xy 380.305056 -285.172404) (xy 380.280127 -285.167267) (xy 380.232141 -285.1503) (xy 380.187322 -285.126179)
			(xy 380.146728 -285.095475) (xy 380.111319 -285.058913) (xy 380.081932 -285.017357) (xy 380.05926 -284.971788)
			(xy 380.043839 -284.923282) (xy 380.036033 -284.872987) (xy 380.035562 -284.847538) (xy 378.81687 -284.847538)
			(xy 378.816328 -284.875524) (xy 378.806871 -284.930692) (xy 378.798074 -284.957266) (xy 378.790454 -284.979364)
			(xy 378.994162 -285.33217) (xy 379.017022 -285.336488) (xy 379.041946 -285.341648) (xy 379.089931 -285.358612)
			(xy 379.134751 -285.382729) (xy 379.175344 -285.41343) (xy 379.210754 -285.449989) (xy 379.240142 -285.491543)
			(xy 379.262815 -285.537109) (xy 379.278237 -285.585612) (xy 379.286044 -285.635906) (xy 379.286516 -285.661354)
			(xy 379.286007 -285.687321) (xy 379.277882 -285.738616) (xy 379.261834 -285.788009) (xy 379.238256 -285.834283)
			(xy 379.20773 -285.876299) (xy 379.171007 -285.913022) (xy 379.128991 -285.943548) (xy 379.082717 -285.967126)
			(xy 379.033324 -285.983174) (xy 378.982029 -285.991299) (xy 378.930095 -285.991299) (xy 378.8788 -285.983174)
			(xy 378.829407 -285.967126) (xy 378.783133 -285.943548) (xy 378.741117 -285.913022) (xy 378.704394 -285.876299)
			(xy 378.673868 -285.834283) (xy 378.65029 -285.788009) (xy 378.634242 -285.738616) (xy 378.626117 -285.687321)
			(xy 378.625608 -285.661354) (xy 378.626149 -285.633368) (xy 378.635607 -285.5782) (xy 378.644404 -285.551626)
			(xy 378.652024 -285.529528) (xy 378.448316 -285.176722) (xy 378.425456 -285.172404) (xy 378.400527 -285.167267)
			(xy 378.352541 -285.1503) (xy 378.307722 -285.126179) (xy 378.267128 -285.095475) (xy 378.231719 -285.058913)
			(xy 378.202332 -285.017357) (xy 378.17966 -284.971788) (xy 378.164239 -284.923282) (xy 378.156433 -284.872987)
			(xy 378.155962 -284.847538) (xy 376.93727 -284.847538) (xy 376.936728 -284.875524) (xy 376.927271 -284.930692)
			(xy 376.918474 -284.957266) (xy 376.910854 -284.979364) (xy 377.114562 -285.33217) (xy 377.137422 -285.336488)
			(xy 377.162346 -285.341648) (xy 377.210331 -285.358612) (xy 377.255151 -285.382729) (xy 377.295744 -285.41343)
			(xy 377.331154 -285.449989) (xy 377.360542 -285.491543) (xy 377.383215 -285.537109) (xy 377.398637 -285.585612)
			(xy 377.406444 -285.635906) (xy 377.406916 -285.661354) (xy 377.406407 -285.687321) (xy 377.398282 -285.738616)
			(xy 377.382234 -285.788009) (xy 377.358656 -285.834283) (xy 377.32813 -285.876299) (xy 377.291407 -285.913022)
			(xy 377.249391 -285.943548) (xy 377.203117 -285.967126) (xy 377.153724 -285.983174) (xy 377.102429 -285.991299)
			(xy 377.050495 -285.991299) (xy 376.9992 -285.983174) (xy 376.949807 -285.967126) (xy 376.903533 -285.943548)
			(xy 376.861517 -285.913022) (xy 376.824794 -285.876299) (xy 376.794268 -285.834283) (xy 376.77069 -285.788009)
			(xy 376.754642 -285.738616) (xy 376.746517 -285.687321) (xy 376.746008 -285.661354) (xy 376.746549 -285.633368)
			(xy 376.756007 -285.5782) (xy 376.764804 -285.551626) (xy 376.772424 -285.529528) (xy 376.568716 -285.176722)
			(xy 376.545856 -285.172404) (xy 376.520927 -285.167267) (xy 376.472941 -285.1503) (xy 376.428122 -285.126179)
			(xy 376.387528 -285.095475) (xy 376.352119 -285.058913) (xy 376.322732 -285.017357) (xy 376.30006 -284.971788)
			(xy 376.284639 -284.923282) (xy 376.276833 -284.872987) (xy 376.276362 -284.847538) (xy 375.05767 -284.847538)
			(xy 375.057128 -284.875524) (xy 375.047671 -284.930692) (xy 375.038874 -284.957266) (xy 375.031254 -284.979364)
			(xy 375.234962 -285.33217) (xy 375.257822 -285.336488) (xy 375.282746 -285.341648) (xy 375.330731 -285.358612)
			(xy 375.375551 -285.382729) (xy 375.416144 -285.41343) (xy 375.451554 -285.449989) (xy 375.480942 -285.491543)
			(xy 375.503615 -285.537109) (xy 375.519037 -285.585612) (xy 375.526844 -285.635906) (xy 375.527316 -285.661354)
			(xy 375.526807 -285.687321) (xy 375.518682 -285.738616) (xy 375.502634 -285.788009) (xy 375.479056 -285.834283)
			(xy 375.44853 -285.876299) (xy 375.411807 -285.913022) (xy 375.369791 -285.943548) (xy 375.323517 -285.967126)
			(xy 375.274124 -285.983174) (xy 375.222829 -285.991299) (xy 375.170895 -285.991299) (xy 375.1196 -285.983174)
			(xy 375.070207 -285.967126) (xy 375.023933 -285.943548) (xy 374.981917 -285.913022) (xy 374.945194 -285.876299)
			(xy 374.914668 -285.834283) (xy 374.89109 -285.788009) (xy 374.875042 -285.738616) (xy 374.866917 -285.687321)
			(xy 374.866408 -285.661354) (xy 374.866949 -285.633368) (xy 374.876407 -285.5782) (xy 374.885204 -285.551626)
			(xy 374.892824 -285.529528) (xy 374.689116 -285.176722) (xy 374.666256 -285.172404) (xy 374.641327 -285.167267)
			(xy 374.593341 -285.1503) (xy 374.548522 -285.126179) (xy 374.507928 -285.095475) (xy 374.472519 -285.058913)
			(xy 374.443132 -285.017357) (xy 374.42046 -284.971788) (xy 374.405039 -284.923282) (xy 374.397233 -284.872987)
			(xy 374.396762 -284.847538) (xy 374.11787 -284.847538) (xy 374.117361 -284.873505) (xy 374.109236 -284.9248)
			(xy 374.093188 -284.974193) (xy 374.06961 -285.020467) (xy 374.039084 -285.062483) (xy 374.002361 -285.099206)
			(xy 373.960345 -285.129732) (xy 373.914071 -285.15331) (xy 373.864678 -285.169358) (xy 373.813383 -285.177483)
			(xy 373.761449 -285.177483) (xy 373.710154 -285.169358) (xy 373.660761 -285.15331) (xy 373.614487 -285.129732)
			(xy 373.572471 -285.099206) (xy 373.535748 -285.062483) (xy 373.505222 -285.020467) (xy 373.481644 -284.974193)
			(xy 373.465596 -284.9248) (xy 373.457471 -284.873505) (xy 373.177567 -284.873505) (xy 373.177528 -284.875524)
			(xy 373.168071 -284.930692) (xy 373.159274 -284.957266) (xy 373.151654 -284.979364) (xy 373.355362 -285.33217)
			(xy 373.378222 -285.336488) (xy 373.403146 -285.341648) (xy 373.451131 -285.358612) (xy 373.495951 -285.382729)
			(xy 373.536544 -285.41343) (xy 373.571954 -285.449989) (xy 373.601342 -285.491543) (xy 373.624015 -285.537109)
			(xy 373.639437 -285.585612) (xy 373.647244 -285.635906) (xy 373.647716 -285.661354) (xy 373.647207 -285.687321)
			(xy 373.639082 -285.738616) (xy 373.623034 -285.788009) (xy 373.599456 -285.834283) (xy 373.56893 -285.876299)
			(xy 373.532207 -285.913022) (xy 373.490191 -285.943548) (xy 373.443917 -285.967126) (xy 373.394524 -285.983174)
			(xy 373.343229 -285.991299) (xy 373.291295 -285.991299) (xy 373.24 -285.983174) (xy 373.190607 -285.967126)
			(xy 373.144333 -285.943548) (xy 373.102317 -285.913022) (xy 373.065594 -285.876299) (xy 373.035068 -285.834283)
			(xy 373.01149 -285.788009) (xy 372.995442 -285.738616) (xy 372.987317 -285.687321) (xy 372.986808 -285.661354)
			(xy 372.987349 -285.633368) (xy 372.996807 -285.5782) (xy 373.005604 -285.551626) (xy 373.013224 -285.529528)
			(xy 372.809516 -285.176722) (xy 372.786656 -285.172404) (xy 372.761727 -285.167267) (xy 372.713741 -285.1503)
			(xy 372.668922 -285.126179) (xy 372.628328 -285.095475) (xy 372.592919 -285.058913) (xy 372.563532 -285.017357)
			(xy 372.54086 -284.971788) (xy 372.525439 -284.923282) (xy 372.517633 -284.872987) (xy 372.517162 -284.847538)
			(xy 371.29847 -284.847538) (xy 371.297928 -284.875524) (xy 371.288471 -284.930692) (xy 371.279674 -284.957266)
			(xy 371.272054 -284.979364) (xy 371.475762 -285.33217) (xy 371.498622 -285.336488) (xy 371.523546 -285.341648)
			(xy 371.571531 -285.358612) (xy 371.616351 -285.382729) (xy 371.656944 -285.41343) (xy 371.692354 -285.449989)
			(xy 371.721742 -285.491543) (xy 371.744415 -285.537109) (xy 371.759837 -285.585612) (xy 371.767644 -285.635906)
			(xy 371.768116 -285.661354) (xy 371.767607 -285.687321) (xy 371.759482 -285.738616) (xy 371.743434 -285.788009)
			(xy 371.719856 -285.834283) (xy 371.68933 -285.876299) (xy 371.652607 -285.913022) (xy 371.610591 -285.943548)
			(xy 371.564317 -285.967126) (xy 371.514924 -285.983174) (xy 371.463629 -285.991299) (xy 371.411695 -285.991299)
			(xy 371.3604 -285.983174) (xy 371.311007 -285.967126) (xy 371.264733 -285.943548) (xy 371.222717 -285.913022)
			(xy 371.185994 -285.876299) (xy 371.155468 -285.834283) (xy 371.13189 -285.788009) (xy 371.115842 -285.738616)
			(xy 371.107717 -285.687321) (xy 371.107208 -285.661354) (xy 371.107749 -285.633368) (xy 371.117207 -285.5782)
			(xy 371.126004 -285.551626) (xy 371.133624 -285.529528) (xy 370.929916 -285.176722) (xy 370.907056 -285.172404)
			(xy 370.882127 -285.167267) (xy 370.834141 -285.1503) (xy 370.789322 -285.126179) (xy 370.748728 -285.095475)
			(xy 370.713319 -285.058913) (xy 370.683932 -285.017357) (xy 370.66126 -284.971788) (xy 370.645839 -284.923282)
			(xy 370.638033 -284.872987) (xy 370.637562 -284.847538) (xy 369.41887 -284.847538) (xy 369.418328 -284.875524)
			(xy 369.408871 -284.930692) (xy 369.400074 -284.957266) (xy 369.392454 -284.979364) (xy 369.596162 -285.33217)
			(xy 369.619022 -285.336488) (xy 369.643946 -285.341648) (xy 369.691931 -285.358612) (xy 369.736751 -285.382729)
			(xy 369.777344 -285.41343) (xy 369.812754 -285.449989) (xy 369.842142 -285.491543) (xy 369.864815 -285.537109)
			(xy 369.880237 -285.585612) (xy 369.888044 -285.635906) (xy 369.888516 -285.661354) (xy 369.888007 -285.687321)
			(xy 369.879882 -285.738616) (xy 369.863834 -285.788009) (xy 369.840256 -285.834283) (xy 369.80973 -285.876299)
			(xy 369.773007 -285.913022) (xy 369.730991 -285.943548) (xy 369.684717 -285.967126) (xy 369.635324 -285.983174)
			(xy 369.584029 -285.991299) (xy 369.532095 -285.991299) (xy 369.4808 -285.983174) (xy 369.431407 -285.967126)
			(xy 369.385133 -285.943548) (xy 369.343117 -285.913022) (xy 369.306394 -285.876299) (xy 369.275868 -285.834283)
			(xy 369.25229 -285.788009) (xy 369.236242 -285.738616) (xy 369.228117 -285.687321) (xy 369.227608 -285.661354)
			(xy 369.228149 -285.633368) (xy 369.237607 -285.5782) (xy 369.246404 -285.551626) (xy 369.254024 -285.529528)
			(xy 369.050316 -285.176722) (xy 369.027456 -285.172404) (xy 369.002527 -285.167267) (xy 368.954541 -285.1503)
			(xy 368.909722 -285.126179) (xy 368.869128 -285.095475) (xy 368.833719 -285.058913) (xy 368.804332 -285.017357)
			(xy 368.78166 -284.971788) (xy 368.766239 -284.923282) (xy 368.758433 -284.872987) (xy 368.757962 -284.847538)
			(xy 367.94059 -284.847538) (xy 367.94059 -285.460186) (xy 367.956644 -285.481972) (xy 367.982177 -285.529683)
			(xy 367.99959 -285.580918) (xy 368.008417 -285.634307) (xy 368.008423 -285.68842) (xy 367.999608 -285.741811)
			(xy 367.982206 -285.79305) (xy 367.956684 -285.840767) (xy 367.94059 -285.862522) (xy 367.94059 -286.056578)
			(xy 367.941141 -286.072029) (xy 367.950387 -286.101515) (xy 367.968013 -286.126897) (xy 367.992412 -286.145862)
			(xy 368.021359 -286.156679) (xy 368.052215 -286.158363) (xy 368.067336 -286.15513) (xy 368.087656 -286.150558)
			(xy 368.110516 -286.14624) (xy 368.314224 -285.79318) (xy 368.306604 -285.771082) (xy 368.297814 -285.744507)
			(xy 368.288372 -285.689339) (xy 368.287808 -285.661354) (xy 368.288317 -285.635387) (xy 368.296442 -285.584092)
			(xy 368.31249 -285.534699) (xy 368.336068 -285.488425) (xy 368.366594 -285.446409) (xy 368.403317 -285.409686)
			(xy 368.445333 -285.37916) (xy 368.491607 -285.355582) (xy 368.541 -285.339534) (xy 368.592295 -285.331409)
			(xy 368.644229 -285.331409) (xy 368.695524 -285.339534) (xy 368.744917 -285.355582) (xy 368.791191 -285.37916)
			(xy 368.833207 -285.409686) (xy 368.86993 -285.446409) (xy 368.900456 -285.488425) (xy 368.924034 -285.534699)
			(xy 368.940082 -285.584092) (xy 368.948207 -285.635387) (xy 368.948716 -285.661354) (xy 368.948244 -285.686802)
			(xy 368.940436 -285.737094) (xy 368.925013 -285.785596) (xy 368.902339 -285.831162) (xy 368.872951 -285.872715)
			(xy 368.837541 -285.909273) (xy 368.796948 -285.939973) (xy 368.752129 -285.964089) (xy 368.704144 -285.981052)
			(xy 368.679222 -285.98622) (xy 368.656362 -285.990538) (xy 368.452654 -286.343598) (xy 368.460274 -286.365696)
			(xy 368.469066 -286.39227) (xy 368.478513 -286.447438) (xy 368.47907 -286.475424) (xy 368.478559 -286.50139)
			(xy 368.478559 -286.501391) (xy 368.758217 -286.501391) (xy 368.758217 -286.449457) (xy 368.766342 -286.398162)
			(xy 368.78239 -286.348769) (xy 368.805968 -286.302495) (xy 368.836494 -286.260479) (xy 368.873217 -286.223756)
			(xy 368.915233 -286.19323) (xy 368.961507 -286.169652) (xy 369.0109 -286.153604) (xy 369.062195 -286.145479)
			(xy 369.114129 -286.145479) (xy 369.165424 -286.153604) (xy 369.214817 -286.169652) (xy 369.261091 -286.19323)
			(xy 369.303107 -286.223756) (xy 369.33983 -286.260479) (xy 369.370356 -286.302495) (xy 369.393934 -286.348769)
			(xy 369.409982 -286.398162) (xy 369.418107 -286.449457) (xy 369.418616 -286.475424) (xy 369.697762 -286.475424)
			(xy 369.698167 -286.44997) (xy 369.705957 -286.399662) (xy 369.721371 -286.351145) (xy 369.744044 -286.305566)
			(xy 369.773441 -286.264004) (xy 369.808865 -286.227443) (xy 369.849477 -286.196748) (xy 369.894318 -286.172646)
			(xy 369.942324 -286.155707) (xy 369.967256 -286.150558) (xy 369.990116 -286.14624) (xy 370.193824 -285.79318)
			(xy 370.186204 -285.771082) (xy 370.177462 -285.744495) (xy 370.168017 -285.689335) (xy 370.167408 -285.661354)
			(xy 370.167917 -285.635387) (xy 370.176042 -285.584092) (xy 370.19209 -285.534699) (xy 370.215668 -285.488425)
			(xy 370.246194 -285.446409) (xy 370.282917 -285.409686) (xy 370.324933 -285.37916) (xy 370.371207 -285.355582)
			(xy 370.4206 -285.339534) (xy 370.471895 -285.331409) (xy 370.523829 -285.331409) (xy 370.575124 -285.339534)
			(xy 370.624517 -285.355582) (xy 370.670791 -285.37916) (xy 370.712807 -285.409686) (xy 370.74953 -285.446409)
			(xy 370.780056 -285.488425) (xy 370.803634 -285.534699) (xy 370.819682 -285.584092) (xy 370.827807 -285.635387)
			(xy 370.828316 -285.661354) (xy 370.827909 -285.686808) (xy 370.820122 -285.737117) (xy 370.804709 -285.785635)
			(xy 370.782037 -285.831216) (xy 370.752641 -285.872778) (xy 370.717216 -285.90934) (xy 370.676603 -285.940034)
			(xy 370.631762 -285.964135) (xy 370.583754 -285.981072) (xy 370.558822 -285.98622) (xy 370.535962 -285.990538)
			(xy 370.332254 -286.343598) (xy 370.339874 -286.365696) (xy 370.34861 -286.392285) (xy 370.358059 -286.447444)
			(xy 370.35867 -286.475424) (xy 370.358161 -286.501391) (xy 370.637817 -286.501391) (xy 370.637817 -286.449457)
			(xy 370.645942 -286.398162) (xy 370.66199 -286.348769) (xy 370.685568 -286.302495) (xy 370.716094 -286.260479)
			(xy 370.752817 -286.223756) (xy 370.794833 -286.19323) (xy 370.841107 -286.169652) (xy 370.8905 -286.153604)
			(xy 370.941795 -286.145479) (xy 370.993729 -286.145479) (xy 371.045024 -286.153604) (xy 371.094417 -286.169652)
			(xy 371.140691 -286.19323) (xy 371.182707 -286.223756) (xy 371.21943 -286.260479) (xy 371.249956 -286.302495)
			(xy 371.273534 -286.348769) (xy 371.289582 -286.398162) (xy 371.297707 -286.449457) (xy 371.298216 -286.475424)
			(xy 371.577362 -286.475424) (xy 371.577767 -286.44997) (xy 371.585557 -286.399662) (xy 371.600971 -286.351145)
			(xy 371.623644 -286.305566) (xy 371.653041 -286.264004) (xy 371.688465 -286.227443) (xy 371.729077 -286.196748)
			(xy 371.773918 -286.172646) (xy 371.821924 -286.155707) (xy 371.846856 -286.150558) (xy 371.869716 -286.14624)
			(xy 372.073424 -285.79318) (xy 372.065804 -285.771082) (xy 372.057062 -285.744495) (xy 372.047617 -285.689335)
			(xy 372.047008 -285.661354) (xy 372.047517 -285.635387) (xy 372.055642 -285.584092) (xy 372.07169 -285.534699)
			(xy 372.095268 -285.488425) (xy 372.125794 -285.446409) (xy 372.162517 -285.409686) (xy 372.204533 -285.37916)
			(xy 372.250807 -285.355582) (xy 372.3002 -285.339534) (xy 372.351495 -285.331409) (xy 372.403429 -285.331409)
			(xy 372.454724 -285.339534) (xy 372.504117 -285.355582) (xy 372.550391 -285.37916) (xy 372.592407 -285.409686)
			(xy 372.62913 -285.446409) (xy 372.659656 -285.488425) (xy 372.683234 -285.534699) (xy 372.699282 -285.584092)
			(xy 372.707407 -285.635387) (xy 372.707916 -285.661354) (xy 372.707509 -285.686808) (xy 372.699722 -285.737117)
			(xy 372.684309 -285.785635) (xy 372.661637 -285.831216) (xy 372.632241 -285.872778) (xy 372.596816 -285.90934)
			(xy 372.556203 -285.940034) (xy 372.511362 -285.964135) (xy 372.463354 -285.981072) (xy 372.438422 -285.98622)
			(xy 372.415562 -285.990538) (xy 372.211854 -286.343598) (xy 372.219474 -286.365696) (xy 372.22821 -286.392285)
			(xy 372.237659 -286.447444) (xy 372.23827 -286.475424) (xy 372.237761 -286.501391) (xy 372.517417 -286.501391)
			(xy 372.517417 -286.449457) (xy 372.525542 -286.398162) (xy 372.54159 -286.348769) (xy 372.565168 -286.302495)
			(xy 372.595694 -286.260479) (xy 372.632417 -286.223756) (xy 372.674433 -286.19323) (xy 372.720707 -286.169652)
			(xy 372.7701 -286.153604) (xy 372.821395 -286.145479) (xy 372.873329 -286.145479) (xy 372.924624 -286.153604)
			(xy 372.974017 -286.169652) (xy 373.020291 -286.19323) (xy 373.062307 -286.223756) (xy 373.09903 -286.260479)
			(xy 373.129556 -286.302495) (xy 373.153134 -286.348769) (xy 373.169182 -286.398162) (xy 373.177307 -286.449457)
			(xy 373.177816 -286.475424) (xy 373.456962 -286.475424) (xy 373.457367 -286.44997) (xy 373.465157 -286.399662)
			(xy 373.480571 -286.351145) (xy 373.503244 -286.305566) (xy 373.532641 -286.264004) (xy 373.568065 -286.227443)
			(xy 373.608677 -286.196748) (xy 373.653518 -286.172646) (xy 373.701524 -286.155707) (xy 373.726456 -286.150558)
			(xy 373.749316 -286.14624) (xy 373.953024 -285.79318) (xy 373.945404 -285.771082) (xy 373.936662 -285.744495)
			(xy 373.927217 -285.689335) (xy 373.926608 -285.661354) (xy 373.927117 -285.635387) (xy 373.935242 -285.584092)
			(xy 373.95129 -285.534699) (xy 373.974868 -285.488425) (xy 374.005394 -285.446409) (xy 374.042117 -285.409686)
			(xy 374.084133 -285.37916) (xy 374.130407 -285.355582) (xy 374.1798 -285.339534) (xy 374.231095 -285.331409)
			(xy 374.283029 -285.331409) (xy 374.334324 -285.339534) (xy 374.383717 -285.355582) (xy 374.429991 -285.37916)
			(xy 374.472007 -285.409686) (xy 374.50873 -285.446409) (xy 374.539256 -285.488425) (xy 374.562834 -285.534699)
			(xy 374.578882 -285.584092) (xy 374.587007 -285.635387) (xy 374.587516 -285.661354) (xy 374.587109 -285.686808)
			(xy 374.579322 -285.737117) (xy 374.563909 -285.785635) (xy 374.541237 -285.831216) (xy 374.511841 -285.872778)
			(xy 374.476416 -285.90934) (xy 374.435803 -285.940034) (xy 374.390962 -285.964135) (xy 374.342954 -285.981072)
			(xy 374.318022 -285.98622) (xy 374.295162 -285.990538) (xy 374.091454 -286.343598) (xy 374.099074 -286.365696)
			(xy 374.10781 -286.392285) (xy 374.117259 -286.447444) (xy 374.11787 -286.475424) (xy 374.117361 -286.501391)
			(xy 374.397017 -286.501391) (xy 374.397017 -286.449457) (xy 374.405142 -286.398162) (xy 374.42119 -286.348769)
			(xy 374.444768 -286.302495) (xy 374.475294 -286.260479) (xy 374.512017 -286.223756) (xy 374.554033 -286.19323)
			(xy 374.600307 -286.169652) (xy 374.6497 -286.153604) (xy 374.700995 -286.145479) (xy 374.752929 -286.145479)
			(xy 374.804224 -286.153604) (xy 374.853617 -286.169652) (xy 374.899891 -286.19323) (xy 374.941907 -286.223756)
			(xy 374.97863 -286.260479) (xy 375.009156 -286.302495) (xy 375.032734 -286.348769) (xy 375.048782 -286.398162)
			(xy 375.056907 -286.449457) (xy 375.057416 -286.475424) (xy 375.336562 -286.475424) (xy 375.336967 -286.44997)
			(xy 375.344757 -286.399662) (xy 375.360171 -286.351145) (xy 375.382844 -286.305566) (xy 375.412241 -286.264004)
			(xy 375.447665 -286.227443) (xy 375.488277 -286.196748) (xy 375.533118 -286.172646) (xy 375.581124 -286.155707)
			(xy 375.606056 -286.150558) (xy 375.628916 -286.14624) (xy 375.832624 -285.79318) (xy 375.825004 -285.771082)
			(xy 375.816262 -285.744495) (xy 375.806817 -285.689335) (xy 375.806208 -285.661354) (xy 375.806717 -285.635387)
			(xy 375.814842 -285.584092) (xy 375.83089 -285.534699) (xy 375.854468 -285.488425) (xy 375.884994 -285.446409)
			(xy 375.921717 -285.409686) (xy 375.963733 -285.37916) (xy 376.010007 -285.355582) (xy 376.0594 -285.339534)
			(xy 376.110695 -285.331409) (xy 376.162629 -285.331409) (xy 376.213924 -285.339534) (xy 376.263317 -285.355582)
			(xy 376.309591 -285.37916) (xy 376.351607 -285.409686) (xy 376.38833 -285.446409) (xy 376.418856 -285.488425)
			(xy 376.442434 -285.534699) (xy 376.458482 -285.584092) (xy 376.466607 -285.635387) (xy 376.467116 -285.661354)
			(xy 376.466709 -285.686808) (xy 376.458922 -285.737117) (xy 376.443509 -285.785635) (xy 376.420837 -285.831216)
			(xy 376.391441 -285.872778) (xy 376.356016 -285.90934) (xy 376.315403 -285.940034) (xy 376.270562 -285.964135)
			(xy 376.222554 -285.981072) (xy 376.197622 -285.98622) (xy 376.174762 -285.990538) (xy 375.971054 -286.343598)
			(xy 375.978674 -286.365696) (xy 375.98741 -286.392285) (xy 375.996859 -286.447444) (xy 375.99747 -286.475424)
			(xy 375.996961 -286.501391) (xy 376.276617 -286.501391) (xy 376.276617 -286.449457) (xy 376.284742 -286.398162)
			(xy 376.30079 -286.348769) (xy 376.324368 -286.302495) (xy 376.354894 -286.260479) (xy 376.391617 -286.223756)
			(xy 376.433633 -286.19323) (xy 376.479907 -286.169652) (xy 376.5293 -286.153604) (xy 376.580595 -286.145479)
			(xy 376.632529 -286.145479) (xy 376.683824 -286.153604) (xy 376.733217 -286.169652) (xy 376.779491 -286.19323)
			(xy 376.821507 -286.223756) (xy 376.85823 -286.260479) (xy 376.888756 -286.302495) (xy 376.912334 -286.348769)
			(xy 376.928382 -286.398162) (xy 376.936507 -286.449457) (xy 376.937016 -286.475424) (xy 377.216162 -286.475424)
			(xy 377.216567 -286.44997) (xy 377.224357 -286.399662) (xy 377.239771 -286.351145) (xy 377.262444 -286.305566)
			(xy 377.291841 -286.264004) (xy 377.327265 -286.227443) (xy 377.367877 -286.196748) (xy 377.412718 -286.172646)
			(xy 377.460724 -286.155707) (xy 377.485656 -286.150558) (xy 377.508516 -286.14624) (xy 377.712224 -285.79318)
			(xy 377.704604 -285.771082) (xy 377.695862 -285.744495) (xy 377.686417 -285.689335) (xy 377.685808 -285.661354)
			(xy 377.686317 -285.635387) (xy 377.694442 -285.584092) (xy 377.71049 -285.534699) (xy 377.734068 -285.488425)
			(xy 377.764594 -285.446409) (xy 377.801317 -285.409686) (xy 377.843333 -285.37916) (xy 377.889607 -285.355582)
			(xy 377.939 -285.339534) (xy 377.990295 -285.331409) (xy 378.042229 -285.331409) (xy 378.093524 -285.339534)
			(xy 378.142917 -285.355582) (xy 378.189191 -285.37916) (xy 378.231207 -285.409686) (xy 378.26793 -285.446409)
			(xy 378.298456 -285.488425) (xy 378.322034 -285.534699) (xy 378.338082 -285.584092) (xy 378.346207 -285.635387)
			(xy 378.346716 -285.661354) (xy 378.346309 -285.686808) (xy 378.338522 -285.737117) (xy 378.323109 -285.785635)
			(xy 378.300437 -285.831216) (xy 378.271041 -285.872778) (xy 378.235616 -285.90934) (xy 378.195003 -285.940034)
			(xy 378.150162 -285.964135) (xy 378.102154 -285.981072) (xy 378.077222 -285.98622) (xy 378.054362 -285.990538)
			(xy 377.850654 -286.343598) (xy 377.858274 -286.365696) (xy 377.86701 -286.392285) (xy 377.876459 -286.447444)
			(xy 377.87707 -286.475424) (xy 377.876561 -286.501391) (xy 378.156217 -286.501391) (xy 378.156217 -286.449457)
			(xy 378.164342 -286.398162) (xy 378.18039 -286.348769) (xy 378.203968 -286.302495) (xy 378.234494 -286.260479)
			(xy 378.271217 -286.223756) (xy 378.313233 -286.19323) (xy 378.359507 -286.169652) (xy 378.4089 -286.153604)
			(xy 378.460195 -286.145479) (xy 378.512129 -286.145479) (xy 378.563424 -286.153604) (xy 378.612817 -286.169652)
			(xy 378.659091 -286.19323) (xy 378.701107 -286.223756) (xy 378.73783 -286.260479) (xy 378.768356 -286.302495)
			(xy 378.791934 -286.348769) (xy 378.807982 -286.398162) (xy 378.816107 -286.449457) (xy 378.816616 -286.475424)
			(xy 379.095762 -286.475424) (xy 379.096167 -286.44997) (xy 379.103957 -286.399662) (xy 379.119371 -286.351145)
			(xy 379.142044 -286.305566) (xy 379.171441 -286.264004) (xy 379.206865 -286.227443) (xy 379.247477 -286.196748)
			(xy 379.292318 -286.172646) (xy 379.340324 -286.155707) (xy 379.365256 -286.150558) (xy 379.388116 -286.14624)
			(xy 379.591824 -285.79318) (xy 379.584204 -285.771082) (xy 379.575462 -285.744495) (xy 379.566017 -285.689335)
			(xy 379.565408 -285.661354) (xy 379.565917 -285.635387) (xy 379.574042 -285.584092) (xy 379.59009 -285.534699)
			(xy 379.613668 -285.488425) (xy 379.644194 -285.446409) (xy 379.680917 -285.409686) (xy 379.722933 -285.37916)
			(xy 379.769207 -285.355582) (xy 379.8186 -285.339534) (xy 379.869895 -285.331409) (xy 379.921829 -285.331409)
			(xy 379.973124 -285.339534) (xy 380.022517 -285.355582) (xy 380.068791 -285.37916) (xy 380.110807 -285.409686)
			(xy 380.14753 -285.446409) (xy 380.178056 -285.488425) (xy 380.201634 -285.534699) (xy 380.217682 -285.584092)
			(xy 380.225807 -285.635387) (xy 380.226316 -285.661354) (xy 380.225909 -285.686808) (xy 380.218122 -285.737117)
			(xy 380.202709 -285.785635) (xy 380.180037 -285.831216) (xy 380.150641 -285.872778) (xy 380.115216 -285.90934)
			(xy 380.074603 -285.940034) (xy 380.029762 -285.964135) (xy 379.981754 -285.981072) (xy 379.956822 -285.98622)
			(xy 379.933962 -285.990538) (xy 379.730254 -286.343598) (xy 379.737874 -286.365696) (xy 379.74661 -286.392285)
			(xy 379.756059 -286.447444) (xy 379.75667 -286.475424) (xy 379.756161 -286.501391) (xy 380.035817 -286.501391)
			(xy 380.035817 -286.449457) (xy 380.043942 -286.398162) (xy 380.05999 -286.348769) (xy 380.083568 -286.302495)
			(xy 380.114094 -286.260479) (xy 380.150817 -286.223756) (xy 380.192833 -286.19323) (xy 380.239107 -286.169652)
			(xy 380.2885 -286.153604) (xy 380.339795 -286.145479) (xy 380.391729 -286.145479) (xy 380.443024 -286.153604)
			(xy 380.492417 -286.169652) (xy 380.538691 -286.19323) (xy 380.580707 -286.223756) (xy 380.61743 -286.260479)
			(xy 380.647956 -286.302495) (xy 380.671534 -286.348769) (xy 380.687582 -286.398162) (xy 380.695707 -286.449457)
			(xy 380.696216 -286.475424) (xy 380.975362 -286.475424) (xy 380.975767 -286.44997) (xy 380.983557 -286.399662)
			(xy 380.998971 -286.351145) (xy 381.021644 -286.305566) (xy 381.051041 -286.264004) (xy 381.086465 -286.227443)
			(xy 381.127077 -286.196748) (xy 381.171918 -286.172646) (xy 381.219924 -286.155707) (xy 381.244856 -286.150558)
			(xy 381.267716 -286.14624) (xy 381.471424 -285.79318) (xy 381.463804 -285.771082) (xy 381.455062 -285.744495)
			(xy 381.445617 -285.689335) (xy 381.445008 -285.661354) (xy 381.445517 -285.635387) (xy 381.453642 -285.584092)
			(xy 381.46969 -285.534699) (xy 381.493268 -285.488425) (xy 381.523794 -285.446409) (xy 381.560517 -285.409686)
			(xy 381.602533 -285.37916) (xy 381.648807 -285.355582) (xy 381.6982 -285.339534) (xy 381.749495 -285.331409)
			(xy 381.801429 -285.331409) (xy 381.852724 -285.339534) (xy 381.902117 -285.355582) (xy 381.948391 -285.37916)
			(xy 381.990407 -285.409686) (xy 382.02713 -285.446409) (xy 382.057656 -285.488425) (xy 382.081234 -285.534699)
			(xy 382.097282 -285.584092) (xy 382.105407 -285.635387) (xy 382.105916 -285.661354) (xy 382.105509 -285.686808)
			(xy 382.10543 -285.687321) (xy 382.385317 -285.687321) (xy 382.385317 -285.635387) (xy 382.393442 -285.584092)
			(xy 382.40949 -285.534699) (xy 382.433068 -285.488425) (xy 382.463594 -285.446409) (xy 382.500317 -285.409686)
			(xy 382.542333 -285.37916) (xy 382.588607 -285.355582) (xy 382.638 -285.339534) (xy 382.689295 -285.331409)
			(xy 382.741229 -285.331409) (xy 382.792524 -285.339534) (xy 382.841917 -285.355582) (xy 382.888191 -285.37916)
			(xy 382.930207 -285.409686) (xy 382.96693 -285.446409) (xy 382.997456 -285.488425) (xy 383.021034 -285.534699)
			(xy 383.037082 -285.584092) (xy 383.045207 -285.635387) (xy 383.045716 -285.661354) (xy 383.045212 -285.687067)
			(xy 383.325117 -285.687067) (xy 383.325117 -285.635133) (xy 383.333242 -285.583838) (xy 383.34929 -285.534445)
			(xy 383.372868 -285.488171) (xy 383.403394 -285.446155) (xy 383.440117 -285.409432) (xy 383.482133 -285.378906)
			(xy 383.528407 -285.355328) (xy 383.5778 -285.33928) (xy 383.629095 -285.331155) (xy 383.681029 -285.331155)
			(xy 383.732324 -285.33928) (xy 383.781717 -285.355328) (xy 383.827991 -285.378906) (xy 383.870007 -285.409432)
			(xy 383.90673 -285.446155) (xy 383.937256 -285.488171) (xy 383.960834 -285.534445) (xy 383.976882 -285.583838)
			(xy 383.985007 -285.635133) (xy 383.985516 -285.6611) (xy 383.985007 -285.687067) (xy 383.984967 -285.687321)
			(xy 384.264917 -285.687321) (xy 384.264917 -285.635387) (xy 384.273042 -285.584092) (xy 384.28909 -285.534699)
			(xy 384.312668 -285.488425) (xy 384.343194 -285.446409) (xy 384.379917 -285.409686) (xy 384.421933 -285.37916)
			(xy 384.468207 -285.355582) (xy 384.5176 -285.339534) (xy 384.568895 -285.331409) (xy 384.620829 -285.331409)
			(xy 384.672124 -285.339534) (xy 384.721517 -285.355582) (xy 384.767791 -285.37916) (xy 384.809807 -285.409686)
			(xy 384.84653 -285.446409) (xy 384.877056 -285.488425) (xy 384.900634 -285.534699) (xy 384.916682 -285.584092)
			(xy 384.924807 -285.635387) (xy 384.925316 -285.661354) (xy 384.924807 -285.687321) (xy 384.916682 -285.738616)
			(xy 384.900634 -285.788009) (xy 384.877056 -285.834283) (xy 384.84653 -285.876299) (xy 384.809807 -285.913022)
			(xy 384.767791 -285.943548) (xy 384.721517 -285.967126) (xy 384.672124 -285.983174) (xy 384.620829 -285.991299)
			(xy 384.568895 -285.991299) (xy 384.5176 -285.983174) (xy 384.468207 -285.967126) (xy 384.421933 -285.943548)
			(xy 384.379917 -285.913022) (xy 384.343194 -285.876299) (xy 384.312668 -285.834283) (xy 384.28909 -285.788009)
			(xy 384.273042 -285.738616) (xy 384.264917 -285.687321) (xy 383.984967 -285.687321) (xy 383.976882 -285.738362)
			(xy 383.960834 -285.787755) (xy 383.937256 -285.834029) (xy 383.90673 -285.876045) (xy 383.870007 -285.912768)
			(xy 383.827991 -285.943294) (xy 383.781717 -285.966872) (xy 383.732324 -285.98292) (xy 383.681029 -285.991045)
			(xy 383.629095 -285.991045) (xy 383.5778 -285.98292) (xy 383.528407 -285.966872) (xy 383.482133 -285.943294)
			(xy 383.440117 -285.912768) (xy 383.403394 -285.876045) (xy 383.372868 -285.834029) (xy 383.34929 -285.787755)
			(xy 383.333242 -285.738362) (xy 383.325117 -285.687067) (xy 383.045212 -285.687067) (xy 383.045207 -285.687321)
			(xy 383.037082 -285.738616) (xy 383.021034 -285.788009) (xy 382.997456 -285.834283) (xy 382.96693 -285.876299)
			(xy 382.930207 -285.913022) (xy 382.888191 -285.943548) (xy 382.841917 -285.967126) (xy 382.792524 -285.983174)
			(xy 382.741229 -285.991299) (xy 382.689295 -285.991299) (xy 382.638 -285.983174) (xy 382.588607 -285.967126)
			(xy 382.542333 -285.943548) (xy 382.500317 -285.913022) (xy 382.463594 -285.876299) (xy 382.433068 -285.834283)
			(xy 382.40949 -285.788009) (xy 382.393442 -285.738616) (xy 382.385317 -285.687321) (xy 382.10543 -285.687321)
			(xy 382.097722 -285.737117) (xy 382.082309 -285.785635) (xy 382.059637 -285.831216) (xy 382.030241 -285.872778)
			(xy 381.994816 -285.90934) (xy 381.954203 -285.940034) (xy 381.909362 -285.964135) (xy 381.861354 -285.981072)
			(xy 381.836422 -285.98622) (xy 381.813562 -285.990538) (xy 381.609854 -286.343598) (xy 381.617474 -286.365696)
			(xy 381.62621 -286.392285) (xy 381.635659 -286.447444) (xy 381.63627 -286.475424) (xy 381.635761 -286.501391)
			(xy 381.915671 -286.501391) (xy 381.915671 -286.449457) (xy 381.923796 -286.398162) (xy 381.939844 -286.348769)
			(xy 381.963422 -286.302495) (xy 381.993948 -286.260479) (xy 382.030671 -286.223756) (xy 382.072687 -286.19323)
			(xy 382.118961 -286.169652) (xy 382.168354 -286.153604) (xy 382.219649 -286.145479) (xy 382.271583 -286.145479)
			(xy 382.322878 -286.153604) (xy 382.372271 -286.169652) (xy 382.418545 -286.19323) (xy 382.460561 -286.223756)
			(xy 382.497284 -286.260479) (xy 382.52781 -286.302495) (xy 382.551388 -286.348769) (xy 382.567436 -286.398162)
			(xy 382.575561 -286.449457) (xy 382.57607 -286.475424) (xy 382.575566 -286.501137) (xy 382.855217 -286.501137)
			(xy 382.855217 -286.449203) (xy 382.863342 -286.397908) (xy 382.87939 -286.348515) (xy 382.902968 -286.302241)
			(xy 382.933494 -286.260225) (xy 382.970217 -286.223502) (xy 383.012233 -286.192976) (xy 383.058507 -286.169398)
			(xy 383.1079 -286.15335) (xy 383.159195 -286.145225) (xy 383.211129 -286.145225) (xy 383.262424 -286.15335)
			(xy 383.311817 -286.169398) (xy 383.358091 -286.192976) (xy 383.400107 -286.223502) (xy 383.43683 -286.260225)
			(xy 383.467356 -286.302241) (xy 383.490934 -286.348515) (xy 383.506982 -286.397908) (xy 383.515107 -286.449203)
			(xy 383.515616 -286.47517) (xy 383.515107 -286.501137) (xy 383.795017 -286.501137) (xy 383.795017 -286.449203)
			(xy 383.803142 -286.397908) (xy 383.81919 -286.348515) (xy 383.842768 -286.302241) (xy 383.873294 -286.260225)
			(xy 383.910017 -286.223502) (xy 383.952033 -286.192976) (xy 383.998307 -286.169398) (xy 384.0477 -286.15335)
			(xy 384.098995 -286.145225) (xy 384.150929 -286.145225) (xy 384.202224 -286.15335) (xy 384.251617 -286.169398)
			(xy 384.297891 -286.192976) (xy 384.339907 -286.223502) (xy 384.37663 -286.260225) (xy 384.407156 -286.302241)
			(xy 384.430734 -286.348515) (xy 384.446782 -286.397908) (xy 384.454907 -286.449203) (xy 384.455416 -286.47517)
			(xy 384.454907 -286.501137) (xy 384.446782 -286.552432) (xy 384.430734 -286.601825) (xy 384.407156 -286.648099)
			(xy 384.37663 -286.690115) (xy 384.339907 -286.726838) (xy 384.297891 -286.757364) (xy 384.251617 -286.780942)
			(xy 384.202224 -286.79699) (xy 384.150929 -286.805115) (xy 384.098995 -286.805115) (xy 384.0477 -286.79699)
			(xy 383.998307 -286.780942) (xy 383.952033 -286.757364) (xy 383.910017 -286.726838) (xy 383.873294 -286.690115)
			(xy 383.842768 -286.648099) (xy 383.81919 -286.601825) (xy 383.803142 -286.552432) (xy 383.795017 -286.501137)
			(xy 383.515107 -286.501137) (xy 383.506982 -286.552432) (xy 383.490934 -286.601825) (xy 383.467356 -286.648099)
			(xy 383.43683 -286.690115) (xy 383.400107 -286.726838) (xy 383.358091 -286.757364) (xy 383.311817 -286.780942)
			(xy 383.262424 -286.79699) (xy 383.211129 -286.805115) (xy 383.159195 -286.805115) (xy 383.1079 -286.79699)
			(xy 383.058507 -286.780942) (xy 383.012233 -286.757364) (xy 382.970217 -286.726838) (xy 382.933494 -286.690115)
			(xy 382.902968 -286.648099) (xy 382.87939 -286.601825) (xy 382.863342 -286.552432) (xy 382.855217 -286.501137)
			(xy 382.575566 -286.501137) (xy 382.575561 -286.501391) (xy 382.567436 -286.552686) (xy 382.551388 -286.602079)
			(xy 382.52781 -286.648353) (xy 382.497284 -286.690369) (xy 382.460561 -286.727092) (xy 382.418545 -286.757618)
			(xy 382.372271 -286.781196) (xy 382.322878 -286.797244) (xy 382.271583 -286.805369) (xy 382.219649 -286.805369)
			(xy 382.168354 -286.797244) (xy 382.118961 -286.781196) (xy 382.072687 -286.757618) (xy 382.030671 -286.727092)
			(xy 381.993948 -286.690369) (xy 381.963422 -286.648353) (xy 381.939844 -286.602079) (xy 381.923796 -286.552686)
			(xy 381.915671 -286.501391) (xy 381.635761 -286.501391) (xy 381.627636 -286.552686) (xy 381.611588 -286.602079)
			(xy 381.58801 -286.648353) (xy 381.557484 -286.690369) (xy 381.520761 -286.727092) (xy 381.478745 -286.757618)
			(xy 381.432471 -286.781196) (xy 381.383078 -286.797244) (xy 381.331783 -286.805369) (xy 381.279849 -286.805369)
			(xy 381.228554 -286.797244) (xy 381.179161 -286.781196) (xy 381.132887 -286.757618) (xy 381.090871 -286.727092)
			(xy 381.054148 -286.690369) (xy 381.023622 -286.648353) (xy 381.000044 -286.602079) (xy 380.983996 -286.552686)
			(xy 380.975871 -286.501391) (xy 380.975362 -286.475424) (xy 380.696216 -286.475424) (xy 380.695707 -286.501391)
			(xy 380.687582 -286.552686) (xy 380.671534 -286.602079) (xy 380.647956 -286.648353) (xy 380.61743 -286.690369)
			(xy 380.580707 -286.727092) (xy 380.538691 -286.757618) (xy 380.492417 -286.781196) (xy 380.443024 -286.797244)
			(xy 380.391729 -286.805369) (xy 380.339795 -286.805369) (xy 380.2885 -286.797244) (xy 380.239107 -286.781196)
			(xy 380.192833 -286.757618) (xy 380.150817 -286.727092) (xy 380.114094 -286.690369) (xy 380.083568 -286.648353)
			(xy 380.05999 -286.602079) (xy 380.043942 -286.552686) (xy 380.035817 -286.501391) (xy 379.756161 -286.501391)
			(xy 379.748036 -286.552686) (xy 379.731988 -286.602079) (xy 379.70841 -286.648353) (xy 379.677884 -286.690369)
			(xy 379.641161 -286.727092) (xy 379.599145 -286.757618) (xy 379.552871 -286.781196) (xy 379.503478 -286.797244)
			(xy 379.452183 -286.805369) (xy 379.400249 -286.805369) (xy 379.348954 -286.797244) (xy 379.299561 -286.781196)
			(xy 379.253287 -286.757618) (xy 379.211271 -286.727092) (xy 379.174548 -286.690369) (xy 379.144022 -286.648353)
			(xy 379.120444 -286.602079) (xy 379.104396 -286.552686) (xy 379.096271 -286.501391) (xy 379.095762 -286.475424)
			(xy 378.816616 -286.475424) (xy 378.816107 -286.501391) (xy 378.807982 -286.552686) (xy 378.791934 -286.602079)
			(xy 378.768356 -286.648353) (xy 378.73783 -286.690369) (xy 378.701107 -286.727092) (xy 378.659091 -286.757618)
			(xy 378.612817 -286.781196) (xy 378.563424 -286.797244) (xy 378.512129 -286.805369) (xy 378.460195 -286.805369)
			(xy 378.4089 -286.797244) (xy 378.359507 -286.781196) (xy 378.313233 -286.757618) (xy 378.271217 -286.727092)
			(xy 378.234494 -286.690369) (xy 378.203968 -286.648353) (xy 378.18039 -286.602079) (xy 378.164342 -286.552686)
			(xy 378.156217 -286.501391) (xy 377.876561 -286.501391) (xy 377.868436 -286.552686) (xy 377.852388 -286.602079)
			(xy 377.82881 -286.648353) (xy 377.798284 -286.690369) (xy 377.761561 -286.727092) (xy 377.719545 -286.757618)
			(xy 377.673271 -286.781196) (xy 377.623878 -286.797244) (xy 377.572583 -286.805369) (xy 377.520649 -286.805369)
			(xy 377.469354 -286.797244) (xy 377.419961 -286.781196) (xy 377.373687 -286.757618) (xy 377.331671 -286.727092)
			(xy 377.294948 -286.690369) (xy 377.264422 -286.648353) (xy 377.240844 -286.602079) (xy 377.224796 -286.552686)
			(xy 377.216671 -286.501391) (xy 377.216162 -286.475424) (xy 376.937016 -286.475424) (xy 376.936507 -286.501391)
			(xy 376.928382 -286.552686) (xy 376.912334 -286.602079) (xy 376.888756 -286.648353) (xy 376.85823 -286.690369)
			(xy 376.821507 -286.727092) (xy 376.779491 -286.757618) (xy 376.733217 -286.781196) (xy 376.683824 -286.797244)
			(xy 376.632529 -286.805369) (xy 376.580595 -286.805369) (xy 376.5293 -286.797244) (xy 376.479907 -286.781196)
			(xy 376.433633 -286.757618) (xy 376.391617 -286.727092) (xy 376.354894 -286.690369) (xy 376.324368 -286.648353)
			(xy 376.30079 -286.602079) (xy 376.284742 -286.552686) (xy 376.276617 -286.501391) (xy 375.996961 -286.501391)
			(xy 375.988836 -286.552686) (xy 375.972788 -286.602079) (xy 375.94921 -286.648353) (xy 375.918684 -286.690369)
			(xy 375.881961 -286.727092) (xy 375.839945 -286.757618) (xy 375.793671 -286.781196) (xy 375.744278 -286.797244)
			(xy 375.692983 -286.805369) (xy 375.641049 -286.805369) (xy 375.589754 -286.797244) (xy 375.540361 -286.781196)
			(xy 375.494087 -286.757618) (xy 375.452071 -286.727092) (xy 375.415348 -286.690369) (xy 375.384822 -286.648353)
			(xy 375.361244 -286.602079) (xy 375.345196 -286.552686) (xy 375.337071 -286.501391) (xy 375.336562 -286.475424)
			(xy 375.057416 -286.475424) (xy 375.056907 -286.501391) (xy 375.048782 -286.552686) (xy 375.032734 -286.602079)
			(xy 375.009156 -286.648353) (xy 374.97863 -286.690369) (xy 374.941907 -286.727092) (xy 374.899891 -286.757618)
			(xy 374.853617 -286.781196) (xy 374.804224 -286.797244) (xy 374.752929 -286.805369) (xy 374.700995 -286.805369)
			(xy 374.6497 -286.797244) (xy 374.600307 -286.781196) (xy 374.554033 -286.757618) (xy 374.512017 -286.727092)
			(xy 374.475294 -286.690369) (xy 374.444768 -286.648353) (xy 374.42119 -286.602079) (xy 374.405142 -286.552686)
			(xy 374.397017 -286.501391) (xy 374.117361 -286.501391) (xy 374.109236 -286.552686) (xy 374.093188 -286.602079)
			(xy 374.06961 -286.648353) (xy 374.039084 -286.690369) (xy 374.002361 -286.727092) (xy 373.960345 -286.757618)
			(xy 373.914071 -286.781196) (xy 373.864678 -286.797244) (xy 373.813383 -286.805369) (xy 373.761449 -286.805369)
			(xy 373.710154 -286.797244) (xy 373.660761 -286.781196) (xy 373.614487 -286.757618) (xy 373.572471 -286.727092)
			(xy 373.535748 -286.690369) (xy 373.505222 -286.648353) (xy 373.481644 -286.602079) (xy 373.465596 -286.552686)
			(xy 373.457471 -286.501391) (xy 373.456962 -286.475424) (xy 373.177816 -286.475424) (xy 373.177307 -286.501391)
			(xy 373.169182 -286.552686) (xy 373.153134 -286.602079) (xy 373.129556 -286.648353) (xy 373.09903 -286.690369)
			(xy 373.062307 -286.727092) (xy 373.020291 -286.757618) (xy 372.974017 -286.781196) (xy 372.924624 -286.797244)
			(xy 372.873329 -286.805369) (xy 372.821395 -286.805369) (xy 372.7701 -286.797244) (xy 372.720707 -286.781196)
			(xy 372.674433 -286.757618) (xy 372.632417 -286.727092) (xy 372.595694 -286.690369) (xy 372.565168 -286.648353)
			(xy 372.54159 -286.602079) (xy 372.525542 -286.552686) (xy 372.517417 -286.501391) (xy 372.237761 -286.501391)
			(xy 372.229636 -286.552686) (xy 372.213588 -286.602079) (xy 372.19001 -286.648353) (xy 372.159484 -286.690369)
			(xy 372.122761 -286.727092) (xy 372.080745 -286.757618) (xy 372.034471 -286.781196) (xy 371.985078 -286.797244)
			(xy 371.933783 -286.805369) (xy 371.881849 -286.805369) (xy 371.830554 -286.797244) (xy 371.781161 -286.781196)
			(xy 371.734887 -286.757618) (xy 371.692871 -286.727092) (xy 371.656148 -286.690369) (xy 371.625622 -286.648353)
			(xy 371.602044 -286.602079) (xy 371.585996 -286.552686) (xy 371.577871 -286.501391) (xy 371.577362 -286.475424)
			(xy 371.298216 -286.475424) (xy 371.297707 -286.501391) (xy 371.289582 -286.552686) (xy 371.273534 -286.602079)
			(xy 371.249956 -286.648353) (xy 371.21943 -286.690369) (xy 371.182707 -286.727092) (xy 371.140691 -286.757618)
			(xy 371.094417 -286.781196) (xy 371.045024 -286.797244) (xy 370.993729 -286.805369) (xy 370.941795 -286.805369)
			(xy 370.8905 -286.797244) (xy 370.841107 -286.781196) (xy 370.794833 -286.757618) (xy 370.752817 -286.727092)
			(xy 370.716094 -286.690369) (xy 370.685568 -286.648353) (xy 370.66199 -286.602079) (xy 370.645942 -286.552686)
			(xy 370.637817 -286.501391) (xy 370.358161 -286.501391) (xy 370.350036 -286.552686) (xy 370.333988 -286.602079)
			(xy 370.31041 -286.648353) (xy 370.279884 -286.690369) (xy 370.243161 -286.727092) (xy 370.201145 -286.757618)
			(xy 370.154871 -286.781196) (xy 370.105478 -286.797244) (xy 370.054183 -286.805369) (xy 370.002249 -286.805369)
			(xy 369.950954 -286.797244) (xy 369.901561 -286.781196) (xy 369.855287 -286.757618) (xy 369.813271 -286.727092)
			(xy 369.776548 -286.690369) (xy 369.746022 -286.648353) (xy 369.722444 -286.602079) (xy 369.706396 -286.552686)
			(xy 369.698271 -286.501391) (xy 369.697762 -286.475424) (xy 369.418616 -286.475424) (xy 369.418107 -286.501391)
			(xy 369.409982 -286.552686) (xy 369.393934 -286.602079) (xy 369.370356 -286.648353) (xy 369.33983 -286.690369)
			(xy 369.303107 -286.727092) (xy 369.261091 -286.757618) (xy 369.214817 -286.781196) (xy 369.165424 -286.797244)
			(xy 369.114129 -286.805369) (xy 369.062195 -286.805369) (xy 369.0109 -286.797244) (xy 368.961507 -286.781196)
			(xy 368.915233 -286.757618) (xy 368.873217 -286.727092) (xy 368.836494 -286.690369) (xy 368.805968 -286.648353)
			(xy 368.78239 -286.602079) (xy 368.766342 -286.552686) (xy 368.758217 -286.501391) (xy 368.478559 -286.501391)
			(xy 368.470432 -286.552684) (xy 368.454381 -286.602074) (xy 368.430802 -286.648346) (xy 368.400276 -286.69036)
			(xy 368.363553 -286.727081) (xy 368.321539 -286.757607) (xy 368.275266 -286.781184) (xy 368.225876 -286.797234)
			(xy 368.174582 -286.80536) (xy 368.148616 -286.805878) (xy 368.128078 -286.805567) (xy 368.087318 -286.800473)
			(xy 368.067336 -286.795718) (xy 368.052223 -286.792418) (xy 368.021349 -286.794075) (xy 367.992385 -286.804891)
			(xy 367.967981 -286.823876) (xy 367.950374 -286.849291) (xy 367.941175 -286.87881) (xy 367.94059 -286.89427)
			(xy 367.94059 -287.087818) (xy 367.956674 -287.109629) (xy 367.982263 -287.157395) (xy 367.999731 -287.208691)
			(xy 368.008614 -287.262146) (xy 368.00917 -287.28924) (xy 368.008635 -287.316339) (xy 367.999799 -287.369812)
			(xy 367.982338 -287.42112) (xy 367.956722 -287.468882) (xy 367.94059 -287.490662) (xy 367.94059 -287.767522)
			(xy 367.986056 -287.812988) (xy 368.017806 -287.799526) (xy 368.038512 -287.79103) (xy 368.081638 -287.779057)
			(xy 368.125984 -287.772999) (xy 368.148362 -287.772602) (xy 368.158037 -287.772679) (xy 368.177354 -287.77382)
			(xy 368.18697 -287.774888) (xy 368.201706 -287.735772) (xy 368.237052 -287.660018) (xy 368.278861 -287.587629)
			(xy 368.326813 -287.519155) (xy 368.35334 -287.486852) (xy 368.337928 -287.4653) (xy 368.313441 -287.418318)
			(xy 368.296758 -287.368032) (xy 368.288305 -287.31573) (xy 368.287808 -287.28924) (xy 368.288288 -287.263268)
			(xy 368.296408 -287.211961) (xy 368.312453 -287.162557) (xy 368.33603 -287.116271) (xy 368.366558 -287.074243)
			(xy 368.403284 -287.037509) (xy 368.445305 -287.006971) (xy 368.491585 -286.983383) (xy 368.540985 -286.967326)
			(xy 368.59229 -286.959194) (xy 368.618262 -286.958786) (xy 368.645752 -286.959336) (xy 368.699974 -286.968442)
			(xy 368.751942 -286.986391) (xy 368.800225 -287.012691) (xy 368.843492 -287.046615) (xy 368.880551 -287.087229)
			(xy 368.91038 -287.133414) (xy 368.921792 -287.15843) (xy 368.96311 -287.151616) (xy 369.046542 -287.144369)
			(xy 369.088416 -287.143952) (xy 369.130162 -287.144405) (xy 369.213337 -287.151655) (xy 369.254532 -287.15843)
			(xy 369.265911 -287.133395) (xy 369.295728 -287.087191) (xy 369.332784 -287.046563) (xy 369.376057 -287.012632)
			(xy 369.424351 -286.986336) (xy 369.476333 -286.9684) (xy 369.530567 -286.959321) (xy 369.558062 -286.958786)
			(xy 369.584032 -286.959266) (xy 369.635333 -286.967387) (xy 369.684733 -286.983434) (xy 369.731013 -287.007012)
			(xy 369.773034 -287.037541) (xy 369.809761 -287.074268) (xy 369.840289 -287.116289) (xy 369.863867 -287.162569)
			(xy 369.879914 -287.211968) (xy 369.888034 -287.26327) (xy 369.888516 -287.28924) (xy 369.888433 -287.300516)
			(xy 369.88691 -287.323015) (xy 369.885468 -287.334198) (xy 369.88397 -287.34879) (xy 369.888428 -287.377771)
			(xy 369.900928 -287.404295) (xy 369.920443 -287.42618) (xy 369.945368 -287.441625) (xy 369.959382 -287.445958)
			(xy 369.980237 -287.451727) (xy 370.021645 -287.464302) (xy 370.042186 -287.471104) (xy 370.056783 -287.475392)
			(xy 370.087181 -287.47612) (xy 370.116446 -287.467865) (xy 370.141984 -287.45136) (xy 370.161529 -287.428068)
			(xy 370.173351 -287.400053) (xy 370.1764 -287.3698) (xy 370.174012 -287.354772) (xy 370.170921 -287.338566)
			(xy 370.167608 -287.305737) (xy 370.167408 -287.28924) (xy 370.167888 -287.263268) (xy 370.176008 -287.211961)
			(xy 370.192053 -287.162557) (xy 370.21563 -287.116271) (xy 370.246158 -287.074243) (xy 370.282884 -287.037509)
			(xy 370.324905 -287.006971) (xy 370.371185 -286.983383) (xy 370.420585 -286.967326) (xy 370.47189 -286.959194)
			(xy 370.497862 -286.958786) (xy 370.525352 -286.959336) (xy 370.579574 -286.968442) (xy 370.631542 -286.986391)
			(xy 370.679825 -287.012691) (xy 370.723092 -287.046615) (xy 370.760151 -287.087229) (xy 370.78998 -287.133414)
			(xy 370.801392 -287.15843) (xy 370.84271 -287.151616) (xy 370.926142 -287.144369) (xy 370.968016 -287.143952)
			(xy 371.009762 -287.144405) (xy 371.092937 -287.151655) (xy 371.134132 -287.15843) (xy 371.145511 -287.133395)
			(xy 371.175328 -287.087191) (xy 371.212384 -287.046563) (xy 371.255657 -287.012632) (xy 371.303951 -286.986336)
			(xy 371.355933 -286.9684) (xy 371.410167 -286.959321) (xy 371.437662 -286.958786) (xy 371.463632 -286.959266)
			(xy 371.514933 -286.967387) (xy 371.564333 -286.983434) (xy 371.610613 -287.007012) (xy 371.652634 -287.037541)
			(xy 371.689361 -287.074268) (xy 371.719889 -287.116289) (xy 371.743467 -287.162569) (xy 371.759514 -287.211968)
			(xy 371.767634 -287.26327) (xy 371.768116 -287.28924) (xy 371.768033 -287.300516) (xy 371.76651 -287.323015)
			(xy 371.765068 -287.334198) (xy 371.76357 -287.34879) (xy 371.768028 -287.377771) (xy 371.780528 -287.404295)
			(xy 371.800043 -287.42618) (xy 371.824968 -287.441625) (xy 371.838982 -287.445958) (xy 371.859836 -287.451729)
			(xy 371.901244 -287.464305) (xy 371.921786 -287.471104) (xy 371.936383 -287.475392) (xy 371.966781 -287.47612)
			(xy 371.996046 -287.467865) (xy 372.021584 -287.45136) (xy 372.041129 -287.428068) (xy 372.052951 -287.400053)
			(xy 372.056 -287.3698) (xy 372.053612 -287.354772) (xy 372.050521 -287.338566) (xy 372.047208 -287.305737)
			(xy 372.047008 -287.28924) (xy 372.047488 -287.263268) (xy 372.055608 -287.211961) (xy 372.071653 -287.162557)
			(xy 372.09523 -287.116271) (xy 372.125758 -287.074243) (xy 372.162484 -287.037509) (xy 372.204505 -287.006971)
			(xy 372.250785 -286.983383) (xy 372.300185 -286.967326) (xy 372.35149 -286.959194) (xy 372.377462 -286.958786)
			(xy 372.404952 -286.959336) (xy 372.459174 -286.968442) (xy 372.511142 -286.986391) (xy 372.559425 -287.012691)
			(xy 372.602692 -287.046615) (xy 372.639751 -287.087229) (xy 372.66958 -287.133414) (xy 372.680992 -287.15843)
			(xy 372.72231 -287.151616) (xy 372.805742 -287.144369) (xy 372.847616 -287.143952) (xy 372.889362 -287.144405)
			(xy 372.972537 -287.151655) (xy 373.013732 -287.15843) (xy 373.025111 -287.133395) (xy 373.054928 -287.087191)
			(xy 373.091984 -287.046563) (xy 373.135257 -287.012632) (xy 373.183551 -286.986336) (xy 373.235533 -286.9684)
			(xy 373.289767 -286.959321) (xy 373.317262 -286.958786) (xy 373.343232 -286.959266) (xy 373.394533 -286.967387)
			(xy 373.443933 -286.983434) (xy 373.490213 -287.007012) (xy 373.532234 -287.037541) (xy 373.568961 -287.074268)
			(xy 373.599489 -287.116289) (xy 373.623067 -287.162569) (xy 373.639114 -287.211968) (xy 373.647234 -287.26327)
			(xy 373.647716 -287.28924) (xy 373.647633 -287.300516) (xy 373.64611 -287.323015) (xy 373.644668 -287.334198)
			(xy 373.64317 -287.34879) (xy 373.647628 -287.377771) (xy 373.660128 -287.404295) (xy 373.679643 -287.42618)
			(xy 373.704568 -287.441625) (xy 373.718582 -287.445958) (xy 373.739436 -287.451729) (xy 373.780844 -287.464305)
			(xy 373.801386 -287.471104) (xy 373.815983 -287.475392) (xy 373.846381 -287.47612) (xy 373.875646 -287.467865)
			(xy 373.901184 -287.45136) (xy 373.920729 -287.428068) (xy 373.932551 -287.400053) (xy 373.9356 -287.3698)
			(xy 373.933212 -287.354772) (xy 373.930121 -287.338566) (xy 373.926808 -287.305737) (xy 373.926608 -287.28924)
			(xy 373.927088 -287.263268) (xy 373.935208 -287.211961) (xy 373.951253 -287.162557) (xy 373.97483 -287.116271)
			(xy 374.005358 -287.074243) (xy 374.042084 -287.037509) (xy 374.084105 -287.006971) (xy 374.130385 -286.983383)
			(xy 374.179785 -286.967326) (xy 374.23109 -286.959194) (xy 374.257062 -286.958786) (xy 374.284552 -286.959336)
			(xy 374.338774 -286.968442) (xy 374.390742 -286.986391) (xy 374.439025 -287.012691) (xy 374.482292 -287.046615)
			(xy 374.519351 -287.087229) (xy 374.54918 -287.133414) (xy 374.560592 -287.15843) (xy 374.60191 -287.151616)
			(xy 374.685342 -287.144369) (xy 374.727216 -287.143952) (xy 374.768962 -287.144405) (xy 374.852137 -287.151655)
			(xy 374.893332 -287.15843) (xy 374.904711 -287.133395) (xy 374.934528 -287.087191) (xy 374.971584 -287.046563)
			(xy 375.014857 -287.012632) (xy 375.063151 -286.986336) (xy 375.115133 -286.9684) (xy 375.169367 -286.959321)
			(xy 375.196862 -286.958786) (xy 375.222832 -286.959266) (xy 375.274133 -286.967387) (xy 375.323533 -286.983434)
			(xy 375.369813 -287.007012) (xy 375.411834 -287.037541) (xy 375.448561 -287.074268) (xy 375.479089 -287.116289)
			(xy 375.502667 -287.162569) (xy 375.518714 -287.211968) (xy 375.526834 -287.26327) (xy 375.527316 -287.28924)
			(xy 375.527233 -287.300516) (xy 375.52571 -287.323015) (xy 375.524268 -287.334198) (xy 375.52277 -287.34879)
			(xy 375.527228 -287.377771) (xy 375.539728 -287.404295) (xy 375.559243 -287.42618) (xy 375.584168 -287.441625)
			(xy 375.598182 -287.445958) (xy 375.619036 -287.451729) (xy 375.660444 -287.464305) (xy 375.680986 -287.471104)
			(xy 375.695583 -287.475392) (xy 375.725981 -287.47612) (xy 375.755246 -287.467865) (xy 375.780784 -287.45136)
			(xy 375.800329 -287.428068) (xy 375.812151 -287.400053) (xy 375.8152 -287.3698) (xy 375.812812 -287.354772)
			(xy 375.809721 -287.338566) (xy 375.806408 -287.305737) (xy 375.806208 -287.28924) (xy 375.806688 -287.263268)
			(xy 375.814808 -287.211961) (xy 375.830853 -287.162557) (xy 375.85443 -287.116271) (xy 375.884958 -287.074243)
			(xy 375.921684 -287.037509) (xy 375.963705 -287.006971) (xy 376.009985 -286.983383) (xy 376.059385 -286.967326)
			(xy 376.11069 -286.959194) (xy 376.136662 -286.958786) (xy 376.164152 -286.959336) (xy 376.218374 -286.968442)
			(xy 376.270342 -286.986391) (xy 376.318625 -287.012691) (xy 376.361892 -287.046615) (xy 376.398951 -287.087229)
			(xy 376.42878 -287.133414) (xy 376.440192 -287.15843) (xy 376.48151 -287.151616) (xy 376.564942 -287.144369)
			(xy 376.606816 -287.143952) (xy 376.648562 -287.144405) (xy 376.731737 -287.151655) (xy 376.772932 -287.15843)
			(xy 376.784311 -287.133395) (xy 376.814128 -287.087191) (xy 376.851184 -287.046563) (xy 376.894457 -287.012632)
			(xy 376.942751 -286.986336) (xy 376.994733 -286.9684) (xy 377.048967 -286.959321) (xy 377.076462 -286.958786)
			(xy 377.102432 -286.959266) (xy 377.153733 -286.967387) (xy 377.203133 -286.983434) (xy 377.249413 -287.007012)
			(xy 377.291434 -287.037541) (xy 377.328161 -287.074268) (xy 377.358689 -287.116289) (xy 377.382267 -287.162569)
			(xy 377.398314 -287.211968) (xy 377.406434 -287.26327) (xy 377.406916 -287.28924) (xy 377.406833 -287.300516)
			(xy 377.40531 -287.323015) (xy 377.403868 -287.334198) (xy 377.40237 -287.34879) (xy 377.406828 -287.377771)
			(xy 377.419328 -287.404295) (xy 377.438843 -287.42618) (xy 377.463768 -287.441625) (xy 377.477782 -287.445958)
			(xy 377.498636 -287.451729) (xy 377.540044 -287.464305) (xy 377.560586 -287.471104) (xy 377.575183 -287.475392)
			(xy 377.605581 -287.47612) (xy 377.634846 -287.467865) (xy 377.660384 -287.45136) (xy 377.679929 -287.428068)
			(xy 377.691751 -287.400053) (xy 377.6948 -287.3698) (xy 377.692412 -287.354772) (xy 377.689321 -287.338566)
			(xy 377.686008 -287.305737) (xy 377.685808 -287.28924) (xy 377.686288 -287.263268) (xy 377.694408 -287.211961)
			(xy 377.710453 -287.162557) (xy 377.73403 -287.116271) (xy 377.764558 -287.074243) (xy 377.801284 -287.037509)
			(xy 377.843305 -287.006971) (xy 377.889585 -286.983383) (xy 377.938985 -286.967326) (xy 377.99029 -286.959194)
			(xy 378.016262 -286.958786) (xy 378.043752 -286.959336) (xy 378.097974 -286.968442) (xy 378.149942 -286.986391)
			(xy 378.198225 -287.012691) (xy 378.241492 -287.046615) (xy 378.278551 -287.087229) (xy 378.30838 -287.133414)
			(xy 378.319792 -287.15843) (xy 378.36111 -287.151616) (xy 378.444542 -287.144369) (xy 378.486416 -287.143952)
			(xy 378.528162 -287.144405) (xy 378.611337 -287.151655) (xy 378.652532 -287.15843) (xy 378.663911 -287.133395)
			(xy 378.693728 -287.087191) (xy 378.730784 -287.046563) (xy 378.774057 -287.012632) (xy 378.822351 -286.986336)
			(xy 378.874333 -286.9684) (xy 378.928567 -286.959321) (xy 378.956062 -286.958786) (xy 378.982032 -286.959266)
			(xy 379.033333 -286.967387) (xy 379.082733 -286.983434) (xy 379.129013 -287.007012) (xy 379.171034 -287.037541)
			(xy 379.207761 -287.074268) (xy 379.238289 -287.116289) (xy 379.261867 -287.162569) (xy 379.277914 -287.211968)
			(xy 379.286034 -287.26327) (xy 379.286516 -287.28924) (xy 379.286433 -287.300516) (xy 379.28491 -287.323015)
			(xy 379.283468 -287.334198) (xy 379.28197 -287.34879) (xy 379.286428 -287.377771) (xy 379.298928 -287.404295)
			(xy 379.318443 -287.42618) (xy 379.343368 -287.441625) (xy 379.357382 -287.445958) (xy 379.378236 -287.451729)
			(xy 379.419644 -287.464305) (xy 379.440186 -287.471104) (xy 379.454783 -287.475392) (xy 379.485181 -287.47612)
			(xy 379.514446 -287.467865) (xy 379.539984 -287.45136) (xy 379.559529 -287.428068) (xy 379.571351 -287.400053)
			(xy 379.5744 -287.3698) (xy 379.572012 -287.354772) (xy 379.568921 -287.338566) (xy 379.565608 -287.305737)
			(xy 379.565408 -287.28924) (xy 379.565888 -287.263268) (xy 379.574008 -287.211961) (xy 379.590053 -287.162557)
			(xy 379.61363 -287.116271) (xy 379.644158 -287.074243) (xy 379.680884 -287.037509) (xy 379.722905 -287.006971)
			(xy 379.769185 -286.983383) (xy 379.818585 -286.967326) (xy 379.86989 -286.959194) (xy 379.895862 -286.958786)
			(xy 379.923352 -286.959336) (xy 379.977574 -286.968442) (xy 380.029542 -286.986391) (xy 380.077825 -287.012691)
			(xy 380.121092 -287.046615) (xy 380.158151 -287.087229) (xy 380.18798 -287.133414) (xy 380.199392 -287.15843)
			(xy 380.24071 -287.151616) (xy 380.324142 -287.144369) (xy 380.366016 -287.143952) (xy 380.407762 -287.144405)
			(xy 380.490937 -287.151655) (xy 380.532132 -287.15843) (xy 380.543511 -287.133395) (xy 380.573328 -287.087191)
			(xy 380.610384 -287.046563) (xy 380.653657 -287.012632) (xy 380.701951 -286.986336) (xy 380.753933 -286.9684)
			(xy 380.808167 -286.959321) (xy 380.835662 -286.958786) (xy 380.861632 -286.959266) (xy 380.912933 -286.967387)
			(xy 380.962333 -286.983434) (xy 381.008613 -287.007012) (xy 381.050634 -287.037541) (xy 381.087361 -287.074268)
			(xy 381.117889 -287.116289) (xy 381.141467 -287.162569) (xy 381.157514 -287.211968) (xy 381.165634 -287.26327)
			(xy 381.166116 -287.28924) (xy 381.166033 -287.300516) (xy 381.16451 -287.323015) (xy 381.163068 -287.334198)
			(xy 381.16157 -287.34879) (xy 381.166028 -287.377771) (xy 381.178528 -287.404295) (xy 381.198043 -287.42618)
			(xy 381.222968 -287.441625) (xy 381.236982 -287.445958) (xy 381.257836 -287.451729) (xy 381.299244 -287.464305)
			(xy 381.319786 -287.471104) (xy 381.334383 -287.475392) (xy 381.364781 -287.47612) (xy 381.394046 -287.467865)
			(xy 381.419584 -287.45136) (xy 381.439129 -287.428068) (xy 381.450951 -287.400053) (xy 381.454 -287.3698)
			(xy 381.451612 -287.354772) (xy 381.448521 -287.338566) (xy 381.445208 -287.305737) (xy 381.445008 -287.28924)
			(xy 381.445517 -287.263273) (xy 381.453642 -287.211978) (xy 381.46969 -287.162585) (xy 381.493268 -287.116311)
			(xy 381.523794 -287.074295) (xy 381.560517 -287.037572) (xy 381.602533 -287.007046) (xy 381.648807 -286.983468)
			(xy 381.6982 -286.96742) (xy 381.749495 -286.959295) (xy 381.801429 -286.959295) (xy 381.852724 -286.96742)
			(xy 381.902117 -286.983468) (xy 381.948391 -287.007046) (xy 381.990407 -287.037572) (xy 382.02713 -287.074295)
			(xy 382.057656 -287.116311) (xy 382.081234 -287.162585) (xy 382.097282 -287.211978) (xy 382.105407 -287.263273)
			(xy 382.105916 -287.28924) (xy 382.105421 -287.314988) (xy 382.097425 -287.36586) (xy 382.081635 -287.414875)
			(xy 382.058431 -287.460847) (xy 382.028376 -287.502663) (xy 381.992197 -287.53931) (xy 381.950772 -287.5699)
			(xy 381.905102 -287.593693) (xy 381.880872 -287.602422) (xy 381.866626 -287.607811) (xy 381.84191 -287.625581)
			(xy 381.823521 -287.64984) (xy 381.813086 -287.678436) (xy 381.811532 -287.708838) (xy 381.818996 -287.73835)
			(xy 381.834816 -287.764357) (xy 381.84582 -287.774888) (xy 381.861998 -287.789287) (xy 381.893625 -287.818883)
		)
		(stroke
			(width 0)
			(type solid)
		)
		(fill yes)
		(layer "In4.Cu")
		(net "PVCCFA_EHV_FIVRA_CPU0")
	)
	(gr_poly
		(pts
			(xy 133.968744 -287.833816) (xy 133.979498 -287.843826) (xy 134.005354 -287.857752) (xy 134.034106 -287.863735)
			(xy 134.063371 -287.86128) (xy 134.090725 -287.850591) (xy 134.102602 -287.841944) (xy 134.124511 -287.825671)
			(xy 134.172545 -287.799774) (xy 134.224178 -287.782108) (xy 134.278009 -287.773154) (xy 134.305294 -287.772602)
			(xy 134.314969 -287.77268) (xy 134.334285 -287.773823) (xy 134.343902 -287.774888) (xy 134.358667 -287.735737)
			(xy 134.394076 -287.659916) (xy 134.435948 -287.587464) (xy 134.483966 -287.51893) (xy 134.510526 -287.486598)
			(xy 134.495119 -287.46508) (xy 134.470639 -287.418163) (xy 134.453959 -287.36794) (xy 134.445508 -287.3157)
			(xy 134.444994 -287.28924) (xy 134.445474 -287.26327) (xy 134.453594 -287.211969) (xy 134.469641 -287.16257)
			(xy 134.493219 -287.11629) (xy 134.523748 -287.07427) (xy 134.560476 -287.037543) (xy 134.602497 -287.007015)
			(xy 134.648777 -286.983438) (xy 134.698177 -286.967392) (xy 134.749478 -286.959273) (xy 134.775448 -286.958786)
			(xy 134.802939 -286.959335) (xy 134.857162 -286.968439) (xy 134.909132 -286.986387) (xy 134.957416 -287.012685)
			(xy 135.000685 -287.046609) (xy 135.037746 -287.087223) (xy 135.067577 -287.133408) (xy 135.078978 -287.15843)
			(xy 135.120233 -287.151623) (xy 135.203538 -287.144374) (xy 135.245348 -287.143952) (xy 135.287093 -287.144407)
			(xy 135.370269 -287.151659) (xy 135.411464 -287.15843) (xy 135.422844 -287.133396) (xy 135.452661 -287.087196)
			(xy 135.489718 -287.046571) (xy 135.532991 -287.012644) (xy 135.581286 -286.986353) (xy 135.633267 -286.968422)
			(xy 135.6875 -286.959347) (xy 135.714994 -286.958786) (xy 135.740962 -286.959268) (xy 135.79226 -286.967393)
			(xy 135.841655 -286.983443) (xy 135.88793 -287.007023) (xy 135.929947 -287.037552) (xy 135.96667 -287.074279)
			(xy 135.997195 -287.116299) (xy 136.02077 -287.162577) (xy 136.036815 -287.211973) (xy 136.044934 -287.263271)
			(xy 136.045448 -287.28924) (xy 136.045365 -287.300515) (xy 136.043842 -287.323015) (xy 136.0424 -287.334198)
			(xy 136.040902 -287.348793) (xy 136.045359 -287.377779) (xy 136.057856 -287.404309) (xy 136.077366 -287.426204)
			(xy 136.102287 -287.441664) (xy 136.116314 -287.445958) (xy 136.149747 -287.455303) (xy 136.215813 -287.476648)
			(xy 136.248394 -287.48863) (xy 136.278874 -287.50006) (xy 136.352788 -287.426146) (xy 136.342374 -287.396174)
			(xy 136.334066 -287.370159) (xy 136.325123 -287.31629) (xy 136.324594 -287.288986) (xy 136.325078 -287.263019)
			(xy 136.333205 -287.211724) (xy 136.349257 -287.162333) (xy 136.372838 -287.11606) (xy 136.403368 -287.074047)
			(xy 136.440094 -287.037327) (xy 136.482113 -287.006805) (xy 136.52839 -286.983233) (xy 136.577785 -286.96719)
			(xy 136.629081 -286.959073) (xy 136.655048 -286.958532) (xy 136.682351 -286.959073) (xy 136.736221 -286.968008)
			(xy 136.762236 -286.976312) (xy 136.792208 -286.986726) (xy 136.909302 -286.869632) (xy 136.918696 -286.859531)
			(xy 136.932196 -286.835489) (xy 136.938782 -286.808714) (xy 136.937975 -286.781152) (xy 136.929833 -286.754808)
			(xy 136.914948 -286.731598) (xy 136.904984 -286.722058) (xy 136.884527 -286.703082) (xy 136.849665 -286.659521)
			(xy 136.822618 -286.610721) (xy 136.804156 -286.558071) (xy 136.794802 -286.503067) (xy 136.79424 -286.47517)
			(xy 136.794751 -286.449204) (xy 136.80288 -286.397912) (xy 136.818931 -286.348523) (xy 136.84251 -286.302253)
			(xy 136.873037 -286.260241) (xy 136.909759 -286.223521) (xy 136.951774 -286.192997) (xy 136.998046 -286.169422)
			(xy 137.047436 -286.153374) (xy 137.098728 -286.14525) (xy 137.124694 -286.144716) (xy 137.152587 -286.145302)
			(xy 137.207579 -286.154678) (xy 137.260218 -286.173149) (xy 137.309011 -286.200191) (xy 137.352576 -286.235036)
			(xy 137.371582 -286.25546) (xy 137.38109 -286.265479) (xy 137.404286 -286.280451) (xy 137.430651 -286.288642)
			(xy 137.458248 -286.289449) (xy 137.485047 -286.282814) (xy 137.509079 -286.269224) (xy 137.519156 -286.259778)
			(xy 137.616692 -286.162242) (xy 137.626501 -286.151842) (xy 137.640428 -286.12689) (xy 137.646894 -286.099055)
			(xy 137.645392 -286.070519) (xy 137.63604 -286.043517) (xy 137.61957 -286.020165) (xy 137.597273 -286.002292)
			(xy 137.570897 -285.991299) (xy 137.556748 -285.989268) (xy 137.530245 -285.985687) (xy 137.478803 -285.971075)
			(xy 137.430383 -285.948373) (xy 137.38625 -285.918173) (xy 137.347553 -285.881262) (xy 137.315303 -285.838603)
			(xy 137.290341 -285.791309) (xy 137.273318 -285.740613) (xy 137.264677 -285.687838) (xy 137.26414 -285.6611)
			(xy 137.264649 -285.635133) (xy 137.272774 -285.583837) (xy 137.288822 -285.534444) (xy 137.3124 -285.48817)
			(xy 137.342926 -285.446154) (xy 137.379649 -285.40943) (xy 137.421665 -285.378903) (xy 137.467939 -285.355324)
			(xy 137.517331 -285.339275) (xy 137.568627 -285.33115) (xy 137.594594 -285.330646) (xy 137.62134 -285.331154)
			(xy 137.674137 -285.339759) (xy 137.724856 -285.35676) (xy 137.772172 -285.381713) (xy 137.814848 -285.413965)
			(xy 137.851768 -285.452674) (xy 137.881966 -285.496827) (xy 137.904654 -285.54527) (xy 137.919238 -285.596737)
			(xy 137.922762 -285.623254) (xy 137.924889 -285.637373) (xy 137.935904 -285.663701) (xy 137.953773 -285.685954)
			(xy 137.977102 -285.702394) (xy 138.004069 -285.711738) (xy 138.032568 -285.713257) (xy 138.060375 -285.706831)
			(xy 138.085319 -285.692963) (xy 138.095736 -285.683198) (xy 138.219942 -285.558992) (xy 138.223752 -285.548324)
			(xy 138.233713 -285.522652) (xy 138.26091 -285.474775) (xy 138.295661 -285.432064) (xy 138.315954 -285.41345)
			(xy 138.315954 -285.252414) (xy 138.315513 -285.238413) (xy 138.307908 -285.211463) (xy 138.293265 -285.187594)
			(xy 138.272687 -285.168602) (xy 138.247723 -285.155916) (xy 138.220251 -285.150492) (xy 138.192339 -285.152736)
			(xy 138.179048 -285.157164) (xy 138.151383 -285.166746) (xy 138.093764 -285.177099) (xy 138.064494 -285.177738)
			(xy 138.038528 -285.177228) (xy 137.987237 -285.169104) (xy 137.937847 -285.153055) (xy 137.891576 -285.129478)
			(xy 137.849563 -285.098953) (xy 137.812843 -285.062232) (xy 137.782318 -285.020219) (xy 137.758742 -284.973947)
			(xy 137.742695 -284.924558) (xy 137.734571 -284.873266) (xy 137.734571 -284.821334) (xy 137.742695 -284.770042)
			(xy 137.758742 -284.720653) (xy 137.782318 -284.674381) (xy 137.812843 -284.632368) (xy 137.849563 -284.595647)
			(xy 137.891576 -284.565122) (xy 137.937847 -284.541545) (xy 137.987237 -284.525496) (xy 138.038528 -284.517372)
			(xy 138.064494 -284.51683) (xy 138.093763 -284.517482) (xy 138.15138 -284.527833) (xy 138.179048 -284.537404)
			(xy 138.192335 -284.541861) (xy 138.220261 -284.544104) (xy 138.247746 -284.538677) (xy 138.272724 -284.525989)
			(xy 138.293317 -284.506994) (xy 138.307976 -284.48312) (xy 138.3156 -284.456162) (xy 138.315954 -284.442154)
			(xy 138.315954 -284.281626) (xy 138.295303 -284.262631) (xy 138.260082 -284.21896) (xy 138.232737 -284.169971)
			(xy 138.214052 -284.11707) (xy 138.204563 -284.061774) (xy 138.20394 -284.033722) (xy 138.204681 -284.001789)
			(xy 138.216961 -283.939115) (xy 138.228324 -283.909262) (xy 138.241024 -283.878274) (xy 137.61593 -283.25318)
			(xy 137.60615 -283.243988) (xy 137.582883 -283.230626) (xy 137.556938 -283.223786) (xy 137.530107 -283.223939)
			(xy 137.504243 -283.231074) (xy 137.481129 -283.2447) (xy 137.462362 -283.263876) (xy 137.449237 -283.287278)
			(xy 137.445496 -283.30017) (xy 137.439163 -283.323682) (xy 137.420534 -283.368669) (xy 137.395506 -283.410436)
			(xy 137.364621 -283.448079) (xy 137.328547 -283.480782) (xy 137.288065 -283.507839) (xy 137.244051 -283.528663)
			(xy 137.197457 -283.542804) (xy 137.149294 -283.549955) (xy 137.124948 -283.55036) (xy 137.098976 -283.549881)
			(xy 137.047671 -283.541762) (xy 136.998267 -283.525716) (xy 136.951983 -283.502139) (xy 136.909956 -283.471611)
			(xy 136.873224 -283.434885) (xy 136.842689 -283.392863) (xy 136.819105 -283.346583) (xy 136.803051 -283.297182)
			(xy 136.794923 -283.245878) (xy 136.794494 -283.219906) (xy 136.794927 -283.195561) (xy 136.802072 -283.147399)
			(xy 136.816207 -283.100807) (xy 136.837027 -283.056794) (xy 136.864081 -283.016312) (xy 136.896783 -282.98024)
			(xy 136.934425 -282.949357) (xy 136.976191 -282.924333) (xy 137.021178 -282.905709) (xy 137.044684 -282.899358)
			(xy 137.057598 -282.895677) (xy 137.081014 -282.88255) (xy 137.100201 -282.863776) (xy 137.113833 -282.84065)
			(xy 137.120969 -282.814771) (xy 137.121114 -282.787927) (xy 137.11426 -282.761972) (xy 137.10088 -282.7387)
			(xy 137.091674 -282.728924) (xy 137.016744 -282.653994) (xy 137.005388 -282.643461) (xy 136.977916 -282.629186)
			(xy 136.947434 -282.623777) (xy 136.916728 -282.62773) (xy 136.888609 -282.640684) (xy 136.87679 -282.650692)
			(xy 136.85845 -282.666713) (xy 136.817947 -282.693751) (xy 136.773918 -282.714557) (xy 136.727314 -282.728683)
			(xy 136.679143 -282.735822) (xy 136.654794 -282.73629) (xy 136.628826 -282.73578) (xy 136.57753 -282.727655)
			(xy 136.528136 -282.711607) (xy 136.48186 -282.688029) (xy 136.439842 -282.657504) (xy 136.403116 -282.620781)
			(xy 136.372586 -282.578766) (xy 136.349005 -282.532492) (xy 136.332952 -282.4831) (xy 136.324822 -282.431804)
			(xy 136.32434 -282.405836) (xy 136.32477 -282.381485) (xy 136.331909 -282.333308) (xy 136.346037 -282.286699)
			(xy 136.36685 -282.242668) (xy 136.393896 -282.202165) (xy 136.409938 -282.18384) (xy 136.419958 -282.172017)
			(xy 136.432977 -282.143909) (xy 136.436956 -282.113189) (xy 136.431529 -282.082691) (xy 136.417196 -282.05523)
			(xy 136.406636 -282.043886) (xy 136.274048 -281.911298) (xy 136.247632 -281.916378) (xy 136.232103 -281.919218)
			(xy 136.200679 -281.922269) (xy 136.184894 -281.922474) (xy 136.158927 -281.921964) (xy 136.107631 -281.913839)
			(xy 136.058238 -281.89779) (xy 136.011963 -281.874213) (xy 135.969947 -281.843687) (xy 135.933222 -281.806964)
			(xy 135.902695 -281.764948) (xy 135.879115 -281.718675) (xy 135.863064 -281.669283) (xy 135.854937 -281.617987)
			(xy 135.85444 -281.59202) (xy 135.854655 -281.576235) (xy 135.857708 -281.544813) (xy 135.860536 -281.529282)
			(xy 135.865616 -281.502866) (xy 133.84403 -279.48128) (xy 133.823964 -279.480518) (xy 133.799175 -279.479213)
			(xy 133.750381 -279.470093) (xy 133.7035 -279.453777) (xy 133.659587 -279.430632) (xy 133.619631 -279.401178)
			(xy 133.58453 -279.366079) (xy 133.555075 -279.326123) (xy 133.531928 -279.282212) (xy 133.51561 -279.235331)
			(xy 133.506488 -279.186538) (xy 133.505194 -279.161748) (xy 133.504432 -279.141682) (xy 133.241542 -278.878792)
			(xy 132.353304 -278.878792) (xy 132.338951 -278.879283) (xy 132.311379 -278.88727) (xy 132.287118 -278.902614)
			(xy 132.268086 -278.924104) (xy 132.255786 -278.950041) (xy 132.25119 -278.978377) (xy 132.25466 -279.006872)
			(xy 132.259832 -279.02027) (xy 132.268264 -279.040902) (xy 132.280135 -279.083864) (xy 132.286123 -279.128032)
			(xy 132.286502 -279.150318) (xy 132.285993 -279.176285) (xy 132.277868 -279.22758) (xy 132.26182 -279.276973)
			(xy 132.238242 -279.323247) (xy 132.207716 -279.365263) (xy 132.170993 -279.401986) (xy 132.128977 -279.432512)
			(xy 132.082703 -279.45609) (xy 132.03331 -279.472138) (xy 131.982015 -279.480263) (xy 131.930081 -279.480263)
			(xy 131.878786 -279.472138) (xy 131.829393 -279.45609) (xy 131.783119 -279.432512) (xy 131.741103 -279.401986)
			(xy 131.70438 -279.365263) (xy 131.673854 -279.323247) (xy 131.650276 -279.276973) (xy 131.634228 -279.22758)
			(xy 131.626103 -279.176285) (xy 131.625594 -279.150318) (xy 131.625959 -279.128031) (xy 131.63195 -279.083863)
			(xy 131.643828 -279.040901) (xy 131.652264 -279.02027) (xy 131.657444 -279.006874) (xy 131.660915 -278.978377)
			(xy 131.656318 -278.950039) (xy 131.644017 -278.9241) (xy 131.624983 -278.902609) (xy 131.600721 -278.887264)
			(xy 131.573146 -278.879277) (xy 131.558792 -278.878792) (xy 131.41325 -278.878792) (xy 131.398903 -278.879289)
			(xy 131.371344 -278.887285) (xy 131.347097 -278.902632) (xy 131.328077 -278.924118) (xy 131.315784 -278.950047)
			(xy 131.31119 -278.978372) (xy 131.314656 -279.006857) (xy 131.319778 -279.02027) (xy 131.328209 -279.040902)
			(xy 131.340078 -279.083865) (xy 131.346065 -279.128032) (xy 131.346448 -279.150318) (xy 131.345939 -279.176285)
			(xy 131.337814 -279.22758) (xy 131.321766 -279.276973) (xy 131.298188 -279.323247) (xy 131.267662 -279.365263)
			(xy 131.230939 -279.401986) (xy 131.188923 -279.432512) (xy 131.142649 -279.45609) (xy 131.093256 -279.472138)
			(xy 131.041961 -279.480263) (xy 130.990027 -279.480263) (xy 130.938732 -279.472138) (xy 130.889339 -279.45609)
			(xy 130.843065 -279.432512) (xy 130.801049 -279.401986) (xy 130.764326 -279.365263) (xy 130.7338 -279.323247)
			(xy 130.710222 -279.276973) (xy 130.694174 -279.22758) (xy 130.686049 -279.176285) (xy 130.68554 -279.150318)
			(xy 130.686101 -279.12302) (xy 130.695077 -279.069167) (xy 130.712788 -279.017523) (xy 130.738752 -278.969496)
			(xy 130.772261 -278.926393) (xy 130.791966 -278.907494) (xy 130.8017 -278.897893) (xy 130.816125 -278.87468)
			(xy 130.823873 -278.848472) (xy 130.824389 -278.821147) (xy 130.817636 -278.794665) (xy 130.804098 -278.770924)
			(xy 130.79476 -278.760936) (xy 130.675888 -278.642064) (xy 130.646424 -278.651462) (xy 130.621983 -278.658731)
			(xy 130.57159 -278.666507) (xy 130.546094 -278.666956) (xy 130.520127 -278.666446) (xy 130.468833 -278.658321)
			(xy 130.419441 -278.642272) (xy 130.373167 -278.618694) (xy 130.331152 -278.588168) (xy 130.29443 -278.551445)
			(xy 130.263904 -278.509429) (xy 130.240326 -278.463156) (xy 130.224278 -278.413763) (xy 130.216153 -278.362469)
			(xy 130.21564 -278.336502) (xy 130.216093 -278.311007) (xy 130.223873 -278.260615) (xy 130.231134 -278.236172)
			(xy 130.240532 -278.206708) (xy 129.61874 -277.584916) (xy 129.60789 -277.574768) (xy 129.581754 -277.560676)
			(xy 129.552668 -277.554703) (xy 129.523093 -277.557356) (xy 129.495533 -277.568409) (xy 129.472322 -277.586927)
			(xy 129.455423 -277.611343) (xy 129.450338 -277.625302) (xy 129.441786 -277.649766) (xy 129.418154 -277.695885)
			(xy 129.387616 -277.737753) (xy 129.35092 -277.774343) (xy 129.308963 -277.804759) (xy 129.262775 -277.828256)
			(xy 129.213486 -277.844258) (xy 129.162304 -277.852374) (xy 129.136394 -277.852886) (xy 129.110426 -277.852376)
			(xy 129.05913 -277.844251) (xy 129.009736 -277.828203) (xy 128.963461 -277.804625) (xy 128.921443 -277.774099)
			(xy 128.884718 -277.737377) (xy 128.854188 -277.695361) (xy 128.830607 -277.649088) (xy 128.814555 -277.599695)
			(xy 128.806426 -277.5484) (xy 128.80594 -277.522432) (xy 128.806389 -277.497837) (xy 128.813676 -277.449191)
			(xy 128.828093 -277.402162) (xy 128.849322 -277.35779) (xy 128.876893 -277.317055) (xy 128.910199 -277.280856)
			(xy 128.948502 -277.249995) (xy 128.990956 -277.225152) (xy 129.036625 -277.206876) (xy 129.084497 -277.195572)
			(xy 129.108962 -277.192994) (xy 129.123988 -277.191174) (xy 129.152071 -277.179926) (xy 129.175638 -277.160958)
			(xy 129.192629 -277.135929) (xy 129.20156 -277.107026) (xy 129.20218 -277.091902) (xy 129.20218 -276.32533)
			(xy 129.201617 -276.310178) (xy 129.192723 -276.281206) (xy 129.175735 -276.256109) (xy 129.152143 -276.237087)
			(xy 129.124015 -276.225806) (xy 129.108962 -276.223984) (xy 129.083227 -276.221319) (xy 129.032978 -276.209007)
			(xy 128.985263 -276.189012) (xy 128.941248 -276.161823) (xy 128.90201 -276.128104) (xy 128.868508 -276.088681)
			(xy 128.841561 -276.044518) (xy 128.821828 -275.996693) (xy 128.809792 -275.946377) (xy 128.805747 -275.8948)
			(xy 128.809792 -275.843223) (xy 128.821828 -275.792907) (xy 128.841561 -275.745082) (xy 128.868508 -275.700919)
			(xy 128.90201 -275.661496) (xy 128.941248 -275.627777) (xy 128.985263 -275.600588) (xy 129.032978 -275.580593)
			(xy 129.083227 -275.568281) (xy 129.108962 -275.565616) (xy 129.124033 -275.563825) (xy 129.152208 -275.552585)
			(xy 129.175839 -275.533566) (xy 129.19284 -275.508445) (xy 129.201713 -275.479438) (xy 129.20218 -275.46427)
			(xy 129.20218 -274.697444) (xy 129.201641 -274.682298) (xy 129.192774 -274.653334) (xy 129.175781 -274.628259)
			(xy 129.152165 -274.60929) (xy 129.124015 -274.598106) (xy 129.108962 -274.596352) (xy 129.084491 -274.593841)
			(xy 129.036626 -274.582504) (xy 128.990967 -274.564204) (xy 128.948521 -274.539346) (xy 128.910223 -274.508476)
			(xy 128.876919 -274.472275) (xy 128.849343 -274.431542) (xy 128.828102 -274.387175) (xy 128.813664 -274.340151)
			(xy 128.806349 -274.291509) (xy 128.80594 -274.266914) (xy 128.806435 -274.241114) (xy 128.81445 -274.190141)
			(xy 128.830289 -274.141032) (xy 128.853566 -274.094981) (xy 128.883716 -274.053106) (xy 128.920006 -274.016424)
			(xy 128.961555 -273.985827) (xy 128.984248 -273.973544) (xy 128.996178 -273.966872) (xy 129.016239 -273.948322)
			(xy 129.030655 -273.925111) (xy 129.03839 -273.898906) (xy 129.038889 -273.871587) (xy 129.032117 -273.845117)
			(xy 129.018559 -273.821395) (xy 129.00914 -273.811492) (xy 128.8923 -273.694652) (xy 128.873842 -273.711277)
			(xy 128.83287 -273.739361) (xy 128.788154 -273.760993) (xy 128.740702 -273.775682) (xy 128.691585 -273.7831)
			(xy 128.666748 -273.783552) (xy 128.640791 -273.783047) (xy 128.589515 -273.774937) (xy 128.540138 -273.758908)
			(xy 128.493874 -273.735355) (xy 128.451863 -273.704857) (xy 128.415138 -273.668165) (xy 128.384602 -273.626182)
			(xy 128.361007 -273.57994) (xy 128.344933 -273.530577) (xy 128.336776 -273.479309) (xy 128.336294 -273.453352)
			(xy 128.336294 -273.402552) (xy 128.057402 -273.402552) (xy 128.057402 -273.453352) (xy 128.056874 -273.479306)
			(xy 128.048718 -273.530571) (xy 128.032647 -273.579929) (xy 128.009056 -273.626168) (xy 127.978525 -273.668149)
			(xy 127.941806 -273.70484) (xy 127.899801 -273.735339) (xy 127.853544 -273.758894) (xy 127.804173 -273.774927)
			(xy 127.752903 -273.783044) (xy 127.700993 -273.783044) (xy 127.649723 -273.774927) (xy 127.600352 -273.758894)
			(xy 127.554095 -273.735339) (xy 127.51209 -273.70484) (xy 127.475371 -273.668149) (xy 127.44484 -273.626168)
			(xy 127.421249 -273.579929) (xy 127.405178 -273.530571) (xy 127.397022 -273.479306) (xy 127.396494 -273.453352)
			(xy 127.396494 -273.402552) (xy 127.117602 -273.402552) (xy 127.117602 -273.453352) (xy 127.117074 -273.479306)
			(xy 127.108918 -273.530571) (xy 127.092847 -273.579929) (xy 127.069256 -273.626168) (xy 127.038725 -273.668149)
			(xy 127.002006 -273.70484) (xy 126.960001 -273.735339) (xy 126.913744 -273.758894) (xy 126.864373 -273.774927)
			(xy 126.813103 -273.783044) (xy 126.761193 -273.783044) (xy 126.709923 -273.774927) (xy 126.660552 -273.758894)
			(xy 126.614295 -273.735339) (xy 126.57229 -273.70484) (xy 126.535571 -273.668149) (xy 126.50504 -273.626168)
			(xy 126.481449 -273.579929) (xy 126.465378 -273.530571) (xy 126.457222 -273.479306) (xy 126.456694 -273.453352)
			(xy 126.456694 -273.402552) (xy 126.177802 -273.402552) (xy 126.177802 -273.453352) (xy 126.177274 -273.479306)
			(xy 126.169118 -273.530571) (xy 126.153047 -273.579929) (xy 126.129456 -273.626168) (xy 126.098925 -273.668149)
			(xy 126.062206 -273.70484) (xy 126.020201 -273.735339) (xy 125.973944 -273.758894) (xy 125.924573 -273.774927)
			(xy 125.873303 -273.783044) (xy 125.821393 -273.783044) (xy 125.770123 -273.774927) (xy 125.720752 -273.758894)
			(xy 125.674495 -273.735339) (xy 125.63249 -273.70484) (xy 125.595771 -273.668149) (xy 125.56524 -273.626168)
			(xy 125.541649 -273.579929) (xy 125.525578 -273.530571) (xy 125.517422 -273.479306) (xy 125.516894 -273.453352)
			(xy 125.516894 -273.402552) (xy 125.238002 -273.402552) (xy 125.238002 -273.453352) (xy 125.237474 -273.479306)
			(xy 125.229318 -273.530571) (xy 125.213247 -273.579929) (xy 125.189656 -273.626168) (xy 125.159125 -273.668149)
			(xy 125.122406 -273.70484) (xy 125.080401 -273.735339) (xy 125.034144 -273.758894) (xy 124.984773 -273.774927)
			(xy 124.933503 -273.783044) (xy 124.881593 -273.783044) (xy 124.830323 -273.774927) (xy 124.780952 -273.758894)
			(xy 124.734695 -273.735339) (xy 124.69269 -273.70484) (xy 124.655971 -273.668149) (xy 124.62544 -273.626168)
			(xy 124.601849 -273.579929) (xy 124.585778 -273.530571) (xy 124.577622 -273.479306) (xy 124.577094 -273.453352)
			(xy 124.577094 -273.402552) (xy 124.298202 -273.402552) (xy 124.298202 -273.453352) (xy 124.297674 -273.479306)
			(xy 124.289518 -273.530571) (xy 124.273447 -273.579929) (xy 124.249856 -273.626168) (xy 124.219325 -273.668149)
			(xy 124.182606 -273.70484) (xy 124.140601 -273.735339) (xy 124.094344 -273.758894) (xy 124.044973 -273.774927)
			(xy 123.993703 -273.783044) (xy 123.941793 -273.783044) (xy 123.890523 -273.774927) (xy 123.841152 -273.758894)
			(xy 123.794895 -273.735339) (xy 123.75289 -273.70484) (xy 123.716171 -273.668149) (xy 123.68564 -273.626168)
			(xy 123.662049 -273.579929) (xy 123.645978 -273.530571) (xy 123.637822 -273.479306) (xy 123.637294 -273.453352)
			(xy 123.637294 -273.402552) (xy 123.358148 -273.402552) (xy 123.358148 -273.453352) (xy 123.35762 -273.479306)
			(xy 123.349464 -273.530571) (xy 123.333393 -273.579929) (xy 123.309802 -273.626168) (xy 123.279271 -273.668149)
			(xy 123.242552 -273.70484) (xy 123.200547 -273.735339) (xy 123.15429 -273.758894) (xy 123.104919 -273.774927)
			(xy 123.053649 -273.783044) (xy 123.001739 -273.783044) (xy 122.950469 -273.774927) (xy 122.901098 -273.758894)
			(xy 122.854841 -273.735339) (xy 122.812836 -273.70484) (xy 122.776117 -273.668149) (xy 122.745586 -273.626168)
			(xy 122.721995 -273.579929) (xy 122.705924 -273.530571) (xy 122.697768 -273.479306) (xy 122.69724 -273.453352)
			(xy 122.69724 -273.402552) (xy 122.418602 -273.402552) (xy 122.418602 -273.453352) (xy 122.418074 -273.479306)
			(xy 122.409918 -273.530571) (xy 122.393847 -273.579929) (xy 122.370256 -273.626168) (xy 122.339725 -273.668149)
			(xy 122.303006 -273.70484) (xy 122.261001 -273.735339) (xy 122.214744 -273.758894) (xy 122.165373 -273.774927)
			(xy 122.114103 -273.783044) (xy 122.062193 -273.783044) (xy 122.010923 -273.774927) (xy 121.961552 -273.758894)
			(xy 121.915295 -273.735339) (xy 121.87329 -273.70484) (xy 121.836571 -273.668149) (xy 121.80604 -273.626168)
			(xy 121.782449 -273.579929) (xy 121.766378 -273.530571) (xy 121.758222 -273.479306) (xy 121.757694 -273.453352)
			(xy 121.757694 -273.402552) (xy 121.478802 -273.402552) (xy 121.478802 -273.453352) (xy 121.478274 -273.479306)
			(xy 121.470118 -273.530571) (xy 121.454047 -273.579929) (xy 121.430456 -273.626168) (xy 121.399925 -273.668149)
			(xy 121.363206 -273.70484) (xy 121.321201 -273.735339) (xy 121.274944 -273.758894) (xy 121.225573 -273.774927)
			(xy 121.174303 -273.783044) (xy 121.122393 -273.783044) (xy 121.071123 -273.774927) (xy 121.021752 -273.758894)
			(xy 120.975495 -273.735339) (xy 120.93349 -273.70484) (xy 120.896771 -273.668149) (xy 120.86624 -273.626168)
			(xy 120.842649 -273.579929) (xy 120.826578 -273.530571) (xy 120.818422 -273.479306) (xy 120.817894 -273.453352)
			(xy 120.817894 -273.402552) (xy 120.539002 -273.402552) (xy 120.539002 -273.453352) (xy 120.538474 -273.479306)
			(xy 120.530318 -273.530571) (xy 120.514247 -273.579929) (xy 120.490656 -273.626168) (xy 120.460125 -273.668149)
			(xy 120.423406 -273.70484) (xy 120.381401 -273.735339) (xy 120.335144 -273.758894) (xy 120.285773 -273.774927)
			(xy 120.234503 -273.783044) (xy 120.182593 -273.783044) (xy 120.131323 -273.774927) (xy 120.081952 -273.758894)
			(xy 120.035695 -273.735339) (xy 119.99369 -273.70484) (xy 119.956971 -273.668149) (xy 119.92644 -273.626168)
			(xy 119.902849 -273.579929) (xy 119.886778 -273.530571) (xy 119.878622 -273.479306) (xy 119.878094 -273.453352)
			(xy 119.878094 -273.402552) (xy 119.599202 -273.402552) (xy 119.599202 -273.453352) (xy 119.598674 -273.479306)
			(xy 119.590518 -273.530571) (xy 119.574447 -273.579929) (xy 119.550856 -273.626168) (xy 119.520325 -273.668149)
			(xy 119.483606 -273.70484) (xy 119.441601 -273.735339) (xy 119.395344 -273.758894) (xy 119.345973 -273.774927)
			(xy 119.294703 -273.783044) (xy 119.242793 -273.783044) (xy 119.191523 -273.774927) (xy 119.142152 -273.758894)
			(xy 119.095895 -273.735339) (xy 119.05389 -273.70484) (xy 119.017171 -273.668149) (xy 118.98664 -273.626168)
			(xy 118.963049 -273.579929) (xy 118.946978 -273.530571) (xy 118.938822 -273.479306) (xy 118.938294 -273.453352)
			(xy 118.938294 -273.402552) (xy 118.659402 -273.402552) (xy 118.659402 -273.453352) (xy 118.658874 -273.479308)
			(xy 118.650719 -273.530575) (xy 118.634648 -273.579937) (xy 118.611058 -273.626179) (xy 118.580528 -273.668165)
			(xy 118.54381 -273.704861) (xy 118.501805 -273.735365) (xy 118.455548 -273.758927) (xy 118.406176 -273.774966)
			(xy 118.354904 -273.78309) (xy 118.328948 -273.783552) (xy 118.307399 -273.783224) (xy 118.264663 -273.777651)
			(xy 118.223018 -273.766554) (xy 118.202964 -273.75866) (xy 118.171722 -273.745706) (xy 118.058438 -273.85899)
			(xy 118.048701 -273.869381) (xy 118.034895 -273.894273) (xy 118.028508 -273.922011) (xy 118.030037 -273.950434)
			(xy 118.039362 -273.977328) (xy 118.055758 -274.000596) (xy 118.066566 -274.009866) (xy 118.085403 -274.025635)
			(xy 118.118653 -274.061796) (xy 118.146178 -274.102484) (xy 118.167371 -274.146802) (xy 118.181765 -274.19377)
			(xy 118.189041 -274.242352) (xy 118.189502 -274.266914) (xy 118.189062 -274.291342) (xy 118.188833 -274.292881)
			(xy 118.468649 -274.292881) (xy 118.468649 -274.240947) (xy 118.476774 -274.189652) (xy 118.492822 -274.140259)
			(xy 118.5164 -274.093985) (xy 118.546926 -274.051969) (xy 118.583649 -274.015246) (xy 118.625665 -273.98472)
			(xy 118.671939 -273.961142) (xy 118.721332 -273.945094) (xy 118.772627 -273.936969) (xy 118.824561 -273.936969)
			(xy 118.875856 -273.945094) (xy 118.925249 -273.961142) (xy 118.971523 -273.98472) (xy 119.013539 -274.015246)
			(xy 119.050262 -274.051969) (xy 119.080788 -274.093985) (xy 119.104366 -274.140259) (xy 119.120414 -274.189652)
			(xy 119.128539 -274.240947) (xy 119.129048 -274.266914) (xy 119.128539 -274.292881) (xy 119.408449 -274.292881)
			(xy 119.408449 -274.240947) (xy 119.416574 -274.189652) (xy 119.432622 -274.140259) (xy 119.4562 -274.093985)
			(xy 119.486726 -274.051969) (xy 119.523449 -274.015246) (xy 119.565465 -273.98472) (xy 119.611739 -273.961142)
			(xy 119.661132 -273.945094) (xy 119.712427 -273.936969) (xy 119.764361 -273.936969) (xy 119.815656 -273.945094)
			(xy 119.865049 -273.961142) (xy 119.911323 -273.98472) (xy 119.953339 -274.015246) (xy 119.990062 -274.051969)
			(xy 120.020588 -274.093985) (xy 120.044166 -274.140259) (xy 120.060214 -274.189652) (xy 120.068339 -274.240947)
			(xy 120.068848 -274.266914) (xy 120.068339 -274.292881) (xy 120.348249 -274.292881) (xy 120.348249 -274.240947)
			(xy 120.356374 -274.189652) (xy 120.372422 -274.140259) (xy 120.396 -274.093985) (xy 120.426526 -274.051969)
			(xy 120.463249 -274.015246) (xy 120.505265 -273.98472) (xy 120.551539 -273.961142) (xy 120.600932 -273.945094)
			(xy 120.652227 -273.936969) (xy 120.704161 -273.936969) (xy 120.755456 -273.945094) (xy 120.804849 -273.961142)
			(xy 120.851123 -273.98472) (xy 120.893139 -274.015246) (xy 120.929862 -274.051969) (xy 120.960388 -274.093985)
			(xy 120.983966 -274.140259) (xy 121.000014 -274.189652) (xy 121.008139 -274.240947) (xy 121.008648 -274.266914)
			(xy 121.008139 -274.292881) (xy 121.288303 -274.292881) (xy 121.288303 -274.240947) (xy 121.296428 -274.189652)
			(xy 121.312476 -274.140259) (xy 121.336054 -274.093985) (xy 121.36658 -274.051969) (xy 121.403303 -274.015246)
			(xy 121.445319 -273.98472) (xy 121.491593 -273.961142) (xy 121.540986 -273.945094) (xy 121.592281 -273.936969)
			(xy 121.644215 -273.936969) (xy 121.69551 -273.945094) (xy 121.744903 -273.961142) (xy 121.791177 -273.98472)
			(xy 121.833193 -274.015246) (xy 121.869916 -274.051969) (xy 121.900442 -274.093985) (xy 121.92402 -274.140259)
			(xy 121.940068 -274.189652) (xy 121.948193 -274.240947) (xy 121.948702 -274.266914) (xy 121.948193 -274.292881)
			(xy 122.227849 -274.292881) (xy 122.227849 -274.240947) (xy 122.235974 -274.189652) (xy 122.252022 -274.140259)
			(xy 122.2756 -274.093985) (xy 122.306126 -274.051969) (xy 122.342849 -274.015246) (xy 122.384865 -273.98472)
			(xy 122.431139 -273.961142) (xy 122.480532 -273.945094) (xy 122.531827 -273.936969) (xy 122.583761 -273.936969)
			(xy 122.635056 -273.945094) (xy 122.684449 -273.961142) (xy 122.730723 -273.98472) (xy 122.772739 -274.015246)
			(xy 122.809462 -274.051969) (xy 122.839988 -274.093985) (xy 122.863566 -274.140259) (xy 122.879614 -274.189652)
			(xy 122.887739 -274.240947) (xy 122.888248 -274.266914) (xy 122.887739 -274.292881) (xy 123.167649 -274.292881)
			(xy 123.167649 -274.240947) (xy 123.175774 -274.189652) (xy 123.191822 -274.140259) (xy 123.2154 -274.093985)
			(xy 123.245926 -274.051969) (xy 123.282649 -274.015246) (xy 123.324665 -273.98472) (xy 123.370939 -273.961142)
			(xy 123.420332 -273.945094) (xy 123.471627 -273.936969) (xy 123.523561 -273.936969) (xy 123.574856 -273.945094)
			(xy 123.624249 -273.961142) (xy 123.670523 -273.98472) (xy 123.712539 -274.015246) (xy 123.749262 -274.051969)
			(xy 123.779788 -274.093985) (xy 123.803366 -274.140259) (xy 123.819414 -274.189652) (xy 123.827539 -274.240947)
			(xy 123.828048 -274.266914) (xy 123.827539 -274.292881) (xy 124.107449 -274.292881) (xy 124.107449 -274.240947)
			(xy 124.115574 -274.189652) (xy 124.131622 -274.140259) (xy 124.1552 -274.093985) (xy 124.185726 -274.051969)
			(xy 124.222449 -274.015246) (xy 124.264465 -273.98472) (xy 124.310739 -273.961142) (xy 124.360132 -273.945094)
			(xy 124.411427 -273.936969) (xy 124.463361 -273.936969) (xy 124.514656 -273.945094) (xy 124.564049 -273.961142)
			(xy 124.610323 -273.98472) (xy 124.652339 -274.015246) (xy 124.689062 -274.051969) (xy 124.719588 -274.093985)
			(xy 124.743166 -274.140259) (xy 124.759214 -274.189652) (xy 124.767339 -274.240947) (xy 124.767848 -274.266914)
			(xy 124.767339 -274.292881) (xy 125.047249 -274.292881) (xy 125.047249 -274.240947) (xy 125.055374 -274.189652)
			(xy 125.071422 -274.140259) (xy 125.095 -274.093985) (xy 125.125526 -274.051969) (xy 125.162249 -274.015246)
			(xy 125.204265 -273.98472) (xy 125.250539 -273.961142) (xy 125.299932 -273.945094) (xy 125.351227 -273.936969)
			(xy 125.403161 -273.936969) (xy 125.454456 -273.945094) (xy 125.503849 -273.961142) (xy 125.550123 -273.98472)
			(xy 125.592139 -274.015246) (xy 125.628862 -274.051969) (xy 125.659388 -274.093985) (xy 125.682966 -274.140259)
			(xy 125.699014 -274.189652) (xy 125.707139 -274.240947) (xy 125.707648 -274.266914) (xy 125.707139 -274.292881)
			(xy 125.987303 -274.292881) (xy 125.987303 -274.240947) (xy 125.995428 -274.189652) (xy 126.011476 -274.140259)
			(xy 126.035054 -274.093985) (xy 126.06558 -274.051969) (xy 126.102303 -274.015246) (xy 126.144319 -273.98472)
			(xy 126.190593 -273.961142) (xy 126.239986 -273.945094) (xy 126.291281 -273.936969) (xy 126.343215 -273.936969)
			(xy 126.39451 -273.945094) (xy 126.443903 -273.961142) (xy 126.490177 -273.98472) (xy 126.532193 -274.015246)
			(xy 126.568916 -274.051969) (xy 126.599442 -274.093985) (xy 126.62302 -274.140259) (xy 126.639068 -274.189652)
			(xy 126.647193 -274.240947) (xy 126.647702 -274.266914) (xy 126.647193 -274.292881) (xy 126.926849 -274.292881)
			(xy 126.926849 -274.240947) (xy 126.934974 -274.189652) (xy 126.951022 -274.140259) (xy 126.9746 -274.093985)
			(xy 127.005126 -274.051969) (xy 127.041849 -274.015246) (xy 127.083865 -273.98472) (xy 127.130139 -273.961142)
			(xy 127.179532 -273.945094) (xy 127.230827 -273.936969) (xy 127.282761 -273.936969) (xy 127.334056 -273.945094)
			(xy 127.383449 -273.961142) (xy 127.429723 -273.98472) (xy 127.471739 -274.015246) (xy 127.508462 -274.051969)
			(xy 127.538988 -274.093985) (xy 127.562566 -274.140259) (xy 127.578614 -274.189652) (xy 127.586739 -274.240947)
			(xy 127.587248 -274.266914) (xy 127.586739 -274.292881) (xy 127.866649 -274.292881) (xy 127.866649 -274.240947)
			(xy 127.874774 -274.189652) (xy 127.890822 -274.140259) (xy 127.9144 -274.093985) (xy 127.944926 -274.051969)
			(xy 127.981649 -274.015246) (xy 128.023665 -273.98472) (xy 128.069939 -273.961142) (xy 128.119332 -273.945094)
			(xy 128.170627 -273.936969) (xy 128.222561 -273.936969) (xy 128.273856 -273.945094) (xy 128.323249 -273.961142)
			(xy 128.369523 -273.98472) (xy 128.411539 -274.015246) (xy 128.448262 -274.051969) (xy 128.478788 -274.093985)
			(xy 128.502366 -274.140259) (xy 128.518414 -274.189652) (xy 128.526539 -274.240947) (xy 128.527048 -274.266914)
			(xy 128.526539 -274.292881) (xy 128.518414 -274.344176) (xy 128.502366 -274.393569) (xy 128.478788 -274.439843)
			(xy 128.448262 -274.481859) (xy 128.411539 -274.518582) (xy 128.369523 -274.549108) (xy 128.323249 -274.572686)
			(xy 128.273856 -274.588734) (xy 128.222561 -274.596859) (xy 128.170627 -274.596859) (xy 128.119332 -274.588734)
			(xy 128.069939 -274.572686) (xy 128.023665 -274.549108) (xy 127.981649 -274.518582) (xy 127.944926 -274.481859)
			(xy 127.9144 -274.439843) (xy 127.890822 -274.393569) (xy 127.874774 -274.344176) (xy 127.866649 -274.292881)
			(xy 127.586739 -274.292881) (xy 127.578614 -274.344176) (xy 127.562566 -274.393569) (xy 127.538988 -274.439843)
			(xy 127.508462 -274.481859) (xy 127.471739 -274.518582) (xy 127.429723 -274.549108) (xy 127.383449 -274.572686)
			(xy 127.334056 -274.588734) (xy 127.282761 -274.596859) (xy 127.230827 -274.596859) (xy 127.179532 -274.588734)
			(xy 127.130139 -274.572686) (xy 127.083865 -274.549108) (xy 127.041849 -274.518582) (xy 127.005126 -274.481859)
			(xy 126.9746 -274.439843) (xy 126.951022 -274.393569) (xy 126.934974 -274.344176) (xy 126.926849 -274.292881)
			(xy 126.647193 -274.292881) (xy 126.639068 -274.344176) (xy 126.62302 -274.393569) (xy 126.599442 -274.439843)
			(xy 126.568916 -274.481859) (xy 126.532193 -274.518582) (xy 126.490177 -274.549108) (xy 126.443903 -274.572686)
			(xy 126.39451 -274.588734) (xy 126.343215 -274.596859) (xy 126.291281 -274.596859) (xy 126.239986 -274.588734)
			(xy 126.190593 -274.572686) (xy 126.144319 -274.549108) (xy 126.102303 -274.518582) (xy 126.06558 -274.481859)
			(xy 126.035054 -274.439843) (xy 126.011476 -274.393569) (xy 125.995428 -274.344176) (xy 125.987303 -274.292881)
			(xy 125.707139 -274.292881) (xy 125.699014 -274.344176) (xy 125.682966 -274.393569) (xy 125.659388 -274.439843)
			(xy 125.628862 -274.481859) (xy 125.592139 -274.518582) (xy 125.550123 -274.549108) (xy 125.503849 -274.572686)
			(xy 125.454456 -274.588734) (xy 125.403161 -274.596859) (xy 125.351227 -274.596859) (xy 125.299932 -274.588734)
			(xy 125.250539 -274.572686) (xy 125.204265 -274.549108) (xy 125.162249 -274.518582) (xy 125.125526 -274.481859)
			(xy 125.095 -274.439843) (xy 125.071422 -274.393569) (xy 125.055374 -274.344176) (xy 125.047249 -274.292881)
			(xy 124.767339 -274.292881) (xy 124.759214 -274.344176) (xy 124.743166 -274.393569) (xy 124.719588 -274.439843)
			(xy 124.689062 -274.481859) (xy 124.652339 -274.518582) (xy 124.610323 -274.549108) (xy 124.564049 -274.572686)
			(xy 124.514656 -274.588734) (xy 124.463361 -274.596859) (xy 124.411427 -274.596859) (xy 124.360132 -274.588734)
			(xy 124.310739 -274.572686) (xy 124.264465 -274.549108) (xy 124.222449 -274.518582) (xy 124.185726 -274.481859)
			(xy 124.1552 -274.439843) (xy 124.131622 -274.393569) (xy 124.115574 -274.344176) (xy 124.107449 -274.292881)
			(xy 123.827539 -274.292881) (xy 123.819414 -274.344176) (xy 123.803366 -274.393569) (xy 123.779788 -274.439843)
			(xy 123.749262 -274.481859) (xy 123.712539 -274.518582) (xy 123.670523 -274.549108) (xy 123.624249 -274.572686)
			(xy 123.574856 -274.588734) (xy 123.523561 -274.596859) (xy 123.471627 -274.596859) (xy 123.420332 -274.588734)
			(xy 123.370939 -274.572686) (xy 123.324665 -274.549108) (xy 123.282649 -274.518582) (xy 123.245926 -274.481859)
			(xy 123.2154 -274.439843) (xy 123.191822 -274.393569) (xy 123.175774 -274.344176) (xy 123.167649 -274.292881)
			(xy 122.887739 -274.292881) (xy 122.879614 -274.344176) (xy 122.863566 -274.393569) (xy 122.839988 -274.439843)
			(xy 122.809462 -274.481859) (xy 122.772739 -274.518582) (xy 122.730723 -274.549108) (xy 122.684449 -274.572686)
			(xy 122.635056 -274.588734) (xy 122.583761 -274.596859) (xy 122.531827 -274.596859) (xy 122.480532 -274.588734)
			(xy 122.431139 -274.572686) (xy 122.384865 -274.549108) (xy 122.342849 -274.518582) (xy 122.306126 -274.481859)
			(xy 122.2756 -274.439843) (xy 122.252022 -274.393569) (xy 122.235974 -274.344176) (xy 122.227849 -274.292881)
			(xy 121.948193 -274.292881) (xy 121.940068 -274.344176) (xy 121.92402 -274.393569) (xy 121.900442 -274.439843)
			(xy 121.869916 -274.481859) (xy 121.833193 -274.518582) (xy 121.791177 -274.549108) (xy 121.744903 -274.572686)
			(xy 121.69551 -274.588734) (xy 121.644215 -274.596859) (xy 121.592281 -274.596859) (xy 121.540986 -274.588734)
			(xy 121.491593 -274.572686) (xy 121.445319 -274.549108) (xy 121.403303 -274.518582) (xy 121.36658 -274.481859)
			(xy 121.336054 -274.439843) (xy 121.312476 -274.393569) (xy 121.296428 -274.344176) (xy 121.288303 -274.292881)
			(xy 121.008139 -274.292881) (xy 121.000014 -274.344176) (xy 120.983966 -274.393569) (xy 120.960388 -274.439843)
			(xy 120.929862 -274.481859) (xy 120.893139 -274.518582) (xy 120.851123 -274.549108) (xy 120.804849 -274.572686)
			(xy 120.755456 -274.588734) (xy 120.704161 -274.596859) (xy 120.652227 -274.596859) (xy 120.600932 -274.588734)
			(xy 120.551539 -274.572686) (xy 120.505265 -274.549108) (xy 120.463249 -274.518582) (xy 120.426526 -274.481859)
			(xy 120.396 -274.439843) (xy 120.372422 -274.393569) (xy 120.356374 -274.344176) (xy 120.348249 -274.292881)
			(xy 120.068339 -274.292881) (xy 120.060214 -274.344176) (xy 120.044166 -274.393569) (xy 120.020588 -274.439843)
			(xy 119.990062 -274.481859) (xy 119.953339 -274.518582) (xy 119.911323 -274.549108) (xy 119.865049 -274.572686)
			(xy 119.815656 -274.588734) (xy 119.764361 -274.596859) (xy 119.712427 -274.596859) (xy 119.661132 -274.588734)
			(xy 119.611739 -274.572686) (xy 119.565465 -274.549108) (xy 119.523449 -274.518582) (xy 119.486726 -274.481859)
			(xy 119.4562 -274.439843) (xy 119.432622 -274.393569) (xy 119.416574 -274.344176) (xy 119.408449 -274.292881)
			(xy 119.128539 -274.292881) (xy 119.120414 -274.344176) (xy 119.104366 -274.393569) (xy 119.080788 -274.439843)
			(xy 119.050262 -274.481859) (xy 119.013539 -274.518582) (xy 118.971523 -274.549108) (xy 118.925249 -274.572686)
			(xy 118.875856 -274.588734) (xy 118.824561 -274.596859) (xy 118.772627 -274.596859) (xy 118.721332 -274.588734)
			(xy 118.671939 -274.572686) (xy 118.625665 -274.549108) (xy 118.583649 -274.518582) (xy 118.546926 -274.481859)
			(xy 118.5164 -274.439843) (xy 118.492822 -274.393569) (xy 118.476774 -274.344176) (xy 118.468649 -274.292881)
			(xy 118.188833 -274.292881) (xy 118.181868 -274.339665) (xy 118.167638 -274.386402) (xy 118.146683 -274.430535)
			(xy 118.11946 -274.471103) (xy 118.086561 -274.507221) (xy 118.048704 -274.538102) (xy 118.006712 -274.563074)
			(xy 117.98427 -274.57273) (xy 117.952774 -274.585684) (xy 117.952774 -274.83562) (xy 116.85651 -274.83562)
			(xy 116.842628 -274.83609) (xy 116.81589 -274.84357) (xy 116.792157 -274.85798) (xy 116.773187 -274.878254)
			(xy 116.760383 -274.90289) (xy 116.754692 -274.930065) (xy 116.756537 -274.957768) (xy 116.760752 -274.971002)
			(xy 116.769544 -274.997576) (xy 116.778991 -275.052744) (xy 116.779548 -275.08073) (xy 116.779039 -275.106697)
			(xy 119.878603 -275.106697) (xy 119.878603 -275.054763) (xy 119.886728 -275.003468) (xy 119.902776 -274.954075)
			(xy 119.926354 -274.907801) (xy 119.95688 -274.865785) (xy 119.993603 -274.829062) (xy 120.035619 -274.798536)
			(xy 120.081893 -274.774958) (xy 120.131286 -274.75891) (xy 120.182581 -274.750785) (xy 120.234515 -274.750785)
			(xy 120.28581 -274.75891) (xy 120.335203 -274.774958) (xy 120.381477 -274.798536) (xy 120.423493 -274.829062)
			(xy 120.460216 -274.865785) (xy 120.490742 -274.907801) (xy 120.51432 -274.954075) (xy 120.530368 -275.003468)
			(xy 120.538493 -275.054763) (xy 120.539002 -275.08073) (xy 120.538498 -275.106443) (xy 120.818149 -275.106443)
			(xy 120.818149 -275.054509) (xy 120.826274 -275.003214) (xy 120.842322 -274.953821) (xy 120.8659 -274.907547)
			(xy 120.896426 -274.865531) (xy 120.933149 -274.828808) (xy 120.975165 -274.798282) (xy 121.021439 -274.774704)
			(xy 121.070832 -274.758656) (xy 121.122127 -274.750531) (xy 121.174061 -274.750531) (xy 121.225356 -274.758656)
			(xy 121.274749 -274.774704) (xy 121.321023 -274.798282) (xy 121.363039 -274.828808) (xy 121.399762 -274.865531)
			(xy 121.430288 -274.907547) (xy 121.453866 -274.953821) (xy 121.469914 -275.003214) (xy 121.478039 -275.054509)
			(xy 121.478548 -275.080476) (xy 121.478039 -275.106443) (xy 121.477999 -275.106697) (xy 121.758203 -275.106697)
			(xy 121.758203 -275.054763) (xy 121.766328 -275.003468) (xy 121.782376 -274.954075) (xy 121.805954 -274.907801)
			(xy 121.83648 -274.865785) (xy 121.873203 -274.829062) (xy 121.915219 -274.798536) (xy 121.961493 -274.774958)
			(xy 122.010886 -274.75891) (xy 122.062181 -274.750785) (xy 122.114115 -274.750785) (xy 122.16541 -274.75891)
			(xy 122.214803 -274.774958) (xy 122.261077 -274.798536) (xy 122.303093 -274.829062) (xy 122.339816 -274.865785)
			(xy 122.370342 -274.907801) (xy 122.39392 -274.954075) (xy 122.409968 -275.003468) (xy 122.418093 -275.054763)
			(xy 122.418602 -275.08073) (xy 122.418093 -275.106697) (xy 122.698003 -275.106697) (xy 122.698003 -275.054763)
			(xy 122.706128 -275.003468) (xy 122.722176 -274.954075) (xy 122.745754 -274.907801) (xy 122.77628 -274.865785)
			(xy 122.813003 -274.829062) (xy 122.855019 -274.798536) (xy 122.901293 -274.774958) (xy 122.950686 -274.75891)
			(xy 123.001981 -274.750785) (xy 123.053915 -274.750785) (xy 123.10521 -274.75891) (xy 123.154603 -274.774958)
			(xy 123.200877 -274.798536) (xy 123.242893 -274.829062) (xy 123.279616 -274.865785) (xy 123.310142 -274.907801)
			(xy 123.33372 -274.954075) (xy 123.349768 -275.003468) (xy 123.357893 -275.054763) (xy 123.358402 -275.08073)
			(xy 123.357893 -275.106697) (xy 123.637803 -275.106697) (xy 123.637803 -275.054763) (xy 123.645928 -275.003468)
			(xy 123.661976 -274.954075) (xy 123.685554 -274.907801) (xy 123.71608 -274.865785) (xy 123.752803 -274.829062)
			(xy 123.794819 -274.798536) (xy 123.841093 -274.774958) (xy 123.890486 -274.75891) (xy 123.941781 -274.750785)
			(xy 123.993715 -274.750785) (xy 124.04501 -274.75891) (xy 124.094403 -274.774958) (xy 124.140677 -274.798536)
			(xy 124.182693 -274.829062) (xy 124.219416 -274.865785) (xy 124.249942 -274.907801) (xy 124.27352 -274.954075)
			(xy 124.289568 -275.003468) (xy 124.297693 -275.054763) (xy 124.298202 -275.08073) (xy 124.297693 -275.106697)
			(xy 124.577603 -275.106697) (xy 124.577603 -275.054763) (xy 124.585728 -275.003468) (xy 124.601776 -274.954075)
			(xy 124.625354 -274.907801) (xy 124.65588 -274.865785) (xy 124.692603 -274.829062) (xy 124.734619 -274.798536)
			(xy 124.780893 -274.774958) (xy 124.830286 -274.75891) (xy 124.881581 -274.750785) (xy 124.933515 -274.750785)
			(xy 124.98481 -274.75891) (xy 125.034203 -274.774958) (xy 125.080477 -274.798536) (xy 125.122493 -274.829062)
			(xy 125.159216 -274.865785) (xy 125.189742 -274.907801) (xy 125.21332 -274.954075) (xy 125.229368 -275.003468)
			(xy 125.237493 -275.054763) (xy 125.238002 -275.08073) (xy 125.237493 -275.106697) (xy 125.517403 -275.106697)
			(xy 125.517403 -275.054763) (xy 125.525528 -275.003468) (xy 125.541576 -274.954075) (xy 125.565154 -274.907801)
			(xy 125.59568 -274.865785) (xy 125.632403 -274.829062) (xy 125.674419 -274.798536) (xy 125.720693 -274.774958)
			(xy 125.770086 -274.75891) (xy 125.821381 -274.750785) (xy 125.873315 -274.750785) (xy 125.92461 -274.75891)
			(xy 125.974003 -274.774958) (xy 126.020277 -274.798536) (xy 126.062293 -274.829062) (xy 126.099016 -274.865785)
			(xy 126.129542 -274.907801) (xy 126.15312 -274.954075) (xy 126.169168 -275.003468) (xy 126.177293 -275.054763)
			(xy 126.177802 -275.08073) (xy 126.177293 -275.106697) (xy 126.456949 -275.106697) (xy 126.456949 -275.054763)
			(xy 126.465074 -275.003468) (xy 126.481122 -274.954075) (xy 126.5047 -274.907801) (xy 126.535226 -274.865785)
			(xy 126.571949 -274.829062) (xy 126.613965 -274.798536) (xy 126.660239 -274.774958) (xy 126.709632 -274.75891)
			(xy 126.760927 -274.750785) (xy 126.812861 -274.750785) (xy 126.864156 -274.75891) (xy 126.913549 -274.774958)
			(xy 126.959823 -274.798536) (xy 127.001839 -274.829062) (xy 127.038562 -274.865785) (xy 127.069088 -274.907801)
			(xy 127.092666 -274.954075) (xy 127.108714 -275.003468) (xy 127.116839 -275.054763) (xy 127.117348 -275.08073)
			(xy 127.116839 -275.106697) (xy 127.397003 -275.106697) (xy 127.397003 -275.054763) (xy 127.405128 -275.003468)
			(xy 127.421176 -274.954075) (xy 127.444754 -274.907801) (xy 127.47528 -274.865785) (xy 127.512003 -274.829062)
			(xy 127.554019 -274.798536) (xy 127.600293 -274.774958) (xy 127.649686 -274.75891) (xy 127.700981 -274.750785)
			(xy 127.752915 -274.750785) (xy 127.80421 -274.75891) (xy 127.853603 -274.774958) (xy 127.899877 -274.798536)
			(xy 127.941893 -274.829062) (xy 127.978616 -274.865785) (xy 128.009142 -274.907801) (xy 128.03272 -274.954075)
			(xy 128.048768 -275.003468) (xy 128.056893 -275.054763) (xy 128.057402 -275.08073) (xy 128.056893 -275.106697)
			(xy 128.336803 -275.106697) (xy 128.336803 -275.054763) (xy 128.344928 -275.003468) (xy 128.360976 -274.954075)
			(xy 128.384554 -274.907801) (xy 128.41508 -274.865785) (xy 128.451803 -274.829062) (xy 128.493819 -274.798536)
			(xy 128.540093 -274.774958) (xy 128.589486 -274.75891) (xy 128.640781 -274.750785) (xy 128.692715 -274.750785)
			(xy 128.74401 -274.75891) (xy 128.793403 -274.774958) (xy 128.839677 -274.798536) (xy 128.881693 -274.829062)
			(xy 128.918416 -274.865785) (xy 128.948942 -274.907801) (xy 128.97252 -274.954075) (xy 128.988568 -275.003468)
			(xy 128.996693 -275.054763) (xy 128.997202 -275.08073) (xy 128.996693 -275.106697) (xy 128.988568 -275.157992)
			(xy 128.97252 -275.207385) (xy 128.948942 -275.253659) (xy 128.918416 -275.295675) (xy 128.881693 -275.332398)
			(xy 128.839677 -275.362924) (xy 128.793403 -275.386502) (xy 128.74401 -275.40255) (xy 128.692715 -275.410675)
			(xy 128.640781 -275.410675) (xy 128.589486 -275.40255) (xy 128.540093 -275.386502) (xy 128.493819 -275.362924)
			(xy 128.451803 -275.332398) (xy 128.41508 -275.295675) (xy 128.384554 -275.253659) (xy 128.360976 -275.207385)
			(xy 128.344928 -275.157992) (xy 128.336803 -275.106697) (xy 128.056893 -275.106697) (xy 128.048768 -275.157992)
			(xy 128.03272 -275.207385) (xy 128.009142 -275.253659) (xy 127.978616 -275.295675) (xy 127.941893 -275.332398)
			(xy 127.899877 -275.362924) (xy 127.853603 -275.386502) (xy 127.80421 -275.40255) (xy 127.752915 -275.410675)
			(xy 127.700981 -275.410675) (xy 127.649686 -275.40255) (xy 127.600293 -275.386502) (xy 127.554019 -275.362924)
			(xy 127.512003 -275.332398) (xy 127.47528 -275.295675) (xy 127.444754 -275.253659) (xy 127.421176 -275.207385)
			(xy 127.405128 -275.157992) (xy 127.397003 -275.106697) (xy 127.116839 -275.106697) (xy 127.108714 -275.157992)
			(xy 127.092666 -275.207385) (xy 127.069088 -275.253659) (xy 127.038562 -275.295675) (xy 127.001839 -275.332398)
			(xy 126.959823 -275.362924) (xy 126.913549 -275.386502) (xy 126.864156 -275.40255) (xy 126.812861 -275.410675)
			(xy 126.760927 -275.410675) (xy 126.709632 -275.40255) (xy 126.660239 -275.386502) (xy 126.613965 -275.362924)
			(xy 126.571949 -275.332398) (xy 126.535226 -275.295675) (xy 126.5047 -275.253659) (xy 126.481122 -275.207385)
			(xy 126.465074 -275.157992) (xy 126.456949 -275.106697) (xy 126.177293 -275.106697) (xy 126.169168 -275.157992)
			(xy 126.15312 -275.207385) (xy 126.129542 -275.253659) (xy 126.099016 -275.295675) (xy 126.062293 -275.332398)
			(xy 126.020277 -275.362924) (xy 125.974003 -275.386502) (xy 125.92461 -275.40255) (xy 125.873315 -275.410675)
			(xy 125.821381 -275.410675) (xy 125.770086 -275.40255) (xy 125.720693 -275.386502) (xy 125.674419 -275.362924)
			(xy 125.632403 -275.332398) (xy 125.59568 -275.295675) (xy 125.565154 -275.253659) (xy 125.541576 -275.207385)
			(xy 125.525528 -275.157992) (xy 125.517403 -275.106697) (xy 125.237493 -275.106697) (xy 125.229368 -275.157992)
			(xy 125.21332 -275.207385) (xy 125.189742 -275.253659) (xy 125.159216 -275.295675) (xy 125.122493 -275.332398)
			(xy 125.080477 -275.362924) (xy 125.034203 -275.386502) (xy 124.98481 -275.40255) (xy 124.933515 -275.410675)
			(xy 124.881581 -275.410675) (xy 124.830286 -275.40255) (xy 124.780893 -275.386502) (xy 124.734619 -275.362924)
			(xy 124.692603 -275.332398) (xy 124.65588 -275.295675) (xy 124.625354 -275.253659) (xy 124.601776 -275.207385)
			(xy 124.585728 -275.157992) (xy 124.577603 -275.106697) (xy 124.297693 -275.106697) (xy 124.289568 -275.157992)
			(xy 124.27352 -275.207385) (xy 124.249942 -275.253659) (xy 124.219416 -275.295675) (xy 124.182693 -275.332398)
			(xy 124.140677 -275.362924) (xy 124.094403 -275.386502) (xy 124.04501 -275.40255) (xy 123.993715 -275.410675)
			(xy 123.941781 -275.410675) (xy 123.890486 -275.40255) (xy 123.841093 -275.386502) (xy 123.794819 -275.362924)
			(xy 123.752803 -275.332398) (xy 123.71608 -275.295675) (xy 123.685554 -275.253659) (xy 123.661976 -275.207385)
			(xy 123.645928 -275.157992) (xy 123.637803 -275.106697) (xy 123.357893 -275.106697) (xy 123.349768 -275.157992)
			(xy 123.33372 -275.207385) (xy 123.310142 -275.253659) (xy 123.279616 -275.295675) (xy 123.242893 -275.332398)
			(xy 123.200877 -275.362924) (xy 123.154603 -275.386502) (xy 123.10521 -275.40255) (xy 123.053915 -275.410675)
			(xy 123.001981 -275.410675) (xy 122.950686 -275.40255) (xy 122.901293 -275.386502) (xy 122.855019 -275.362924)
			(xy 122.813003 -275.332398) (xy 122.77628 -275.295675) (xy 122.745754 -275.253659) (xy 122.722176 -275.207385)
			(xy 122.706128 -275.157992) (xy 122.698003 -275.106697) (xy 122.418093 -275.106697) (xy 122.409968 -275.157992)
			(xy 122.39392 -275.207385) (xy 122.370342 -275.253659) (xy 122.339816 -275.295675) (xy 122.303093 -275.332398)
			(xy 122.261077 -275.362924) (xy 122.214803 -275.386502) (xy 122.16541 -275.40255) (xy 122.114115 -275.410675)
			(xy 122.062181 -275.410675) (xy 122.010886 -275.40255) (xy 121.961493 -275.386502) (xy 121.915219 -275.362924)
			(xy 121.873203 -275.332398) (xy 121.83648 -275.295675) (xy 121.805954 -275.253659) (xy 121.782376 -275.207385)
			(xy 121.766328 -275.157992) (xy 121.758203 -275.106697) (xy 121.477999 -275.106697) (xy 121.469914 -275.157738)
			(xy 121.453866 -275.207131) (xy 121.430288 -275.253405) (xy 121.399762 -275.295421) (xy 121.363039 -275.332144)
			(xy 121.321023 -275.36267) (xy 121.274749 -275.386248) (xy 121.225356 -275.402296) (xy 121.174061 -275.410421)
			(xy 121.122127 -275.410421) (xy 121.070832 -275.402296) (xy 121.021439 -275.386248) (xy 120.975165 -275.36267)
			(xy 120.933149 -275.332144) (xy 120.896426 -275.295421) (xy 120.8659 -275.253405) (xy 120.842322 -275.207131)
			(xy 120.826274 -275.157738) (xy 120.818149 -275.106443) (xy 120.538498 -275.106443) (xy 120.538493 -275.106697)
			(xy 120.530368 -275.157992) (xy 120.51432 -275.207385) (xy 120.490742 -275.253659) (xy 120.460216 -275.295675)
			(xy 120.423493 -275.332398) (xy 120.381477 -275.362924) (xy 120.335203 -275.386502) (xy 120.28581 -275.40255)
			(xy 120.234515 -275.410675) (xy 120.182581 -275.410675) (xy 120.131286 -275.40255) (xy 120.081893 -275.386502)
			(xy 120.035619 -275.362924) (xy 119.993603 -275.332398) (xy 119.95688 -275.295675) (xy 119.926354 -275.253659)
			(xy 119.902776 -275.207385) (xy 119.886728 -275.157992) (xy 119.878603 -275.106697) (xy 116.779039 -275.106697)
			(xy 116.770914 -275.157992) (xy 116.754866 -275.207385) (xy 116.731288 -275.253659) (xy 116.700762 -275.295675)
			(xy 116.664039 -275.332398) (xy 116.622023 -275.362924) (xy 116.575749 -275.386502) (xy 116.526356 -275.40255)
			(xy 116.475061 -275.410675) (xy 116.423127 -275.410675) (xy 116.371832 -275.40255) (xy 116.322439 -275.386502)
			(xy 116.276165 -275.362924) (xy 116.234149 -275.332398) (xy 116.197426 -275.295675) (xy 116.1669 -275.253659)
			(xy 116.143322 -275.207385) (xy 116.127274 -275.157992) (xy 116.119149 -275.106697) (xy 116.11864 -275.08073)
			(xy 116.119251 -275.052749) (xy 116.128699 -274.99759) (xy 116.137436 -274.971002) (xy 116.141609 -274.957756)
			(xy 116.14345 -274.930058) (xy 116.137761 -274.902887) (xy 116.124965 -274.878253) (xy 116.106005 -274.857977)
			(xy 116.082285 -274.843556) (xy 116.055557 -274.836059) (xy 116.041678 -274.83562) (xy 115.916456 -274.83562)
			(xy 115.902569 -274.836084) (xy 115.87582 -274.843557) (xy 115.852076 -274.857965) (xy 115.833096 -274.878241)
			(xy 115.820285 -274.902883) (xy 115.814592 -274.930067) (xy 115.816439 -274.957779) (xy 115.820698 -274.971002)
			(xy 115.829489 -274.997577) (xy 115.838934 -275.052744) (xy 115.839494 -275.08073) (xy 115.838983 -275.106697)
			(xy 115.830855 -275.157991) (xy 115.814804 -275.207382) (xy 115.791225 -275.253654) (xy 115.760699 -275.295669)
			(xy 115.723977 -275.332393) (xy 115.681963 -275.36292) (xy 115.635691 -275.3865) (xy 115.5863 -275.402552)
			(xy 115.535007 -275.410682) (xy 115.50904 -275.411184) (xy 115.481852 -275.410635) (xy 115.428208 -275.401737)
			(xy 115.376745 -275.384175) (xy 115.328853 -275.358424) (xy 115.285824 -275.325177) (xy 115.248819 -275.285333)
			(xy 115.218839 -275.239968) (xy 115.207288 -275.21535) (xy 115.201127 -275.202694) (xy 115.183059 -275.181123)
			(xy 115.159794 -275.165298) (xy 115.133094 -275.156417) (xy 115.104984 -275.155155) (xy 115.077596 -275.161608)
			(xy 115.053006 -275.175285) (xy 115.042696 -275.18487) (xy 114.744246 -275.48332) (xy 114.744246 -275.920767)
			(xy 115.649249 -275.920767) (xy 115.649249 -275.868833) (xy 115.657374 -275.817538) (xy 115.673422 -275.768145)
			(xy 115.697 -275.721871) (xy 115.727526 -275.679855) (xy 115.764249 -275.643132) (xy 115.806265 -275.612606)
			(xy 115.852539 -275.589028) (xy 115.901932 -275.57298) (xy 115.953227 -275.564855) (xy 116.005161 -275.564855)
			(xy 116.056456 -275.57298) (xy 116.105849 -275.589028) (xy 116.152123 -275.612606) (xy 116.194139 -275.643132)
			(xy 116.230862 -275.679855) (xy 116.261388 -275.721871) (xy 116.284966 -275.768145) (xy 116.301014 -275.817538)
			(xy 116.309139 -275.868833) (xy 116.309648 -275.8948) (xy 116.309139 -275.920767) (xy 116.589049 -275.920767)
			(xy 116.589049 -275.868833) (xy 116.597174 -275.817538) (xy 116.613222 -275.768145) (xy 116.6368 -275.721871)
			(xy 116.667326 -275.679855) (xy 116.704049 -275.643132) (xy 116.746065 -275.612606) (xy 116.792339 -275.589028)
			(xy 116.841732 -275.57298) (xy 116.893027 -275.564855) (xy 116.944961 -275.564855) (xy 116.996256 -275.57298)
			(xy 117.045649 -275.589028) (xy 117.091923 -275.612606) (xy 117.133939 -275.643132) (xy 117.170662 -275.679855)
			(xy 117.201188 -275.721871) (xy 117.224766 -275.768145) (xy 117.240814 -275.817538) (xy 117.248939 -275.868833)
			(xy 117.249448 -275.8948) (xy 117.248939 -275.920767) (xy 117.528849 -275.920767) (xy 117.528849 -275.868833)
			(xy 117.536974 -275.817538) (xy 117.553022 -275.768145) (xy 117.5766 -275.721871) (xy 117.607126 -275.679855)
			(xy 117.643849 -275.643132) (xy 117.685865 -275.612606) (xy 117.732139 -275.589028) (xy 117.781532 -275.57298)
			(xy 117.832827 -275.564855) (xy 117.884761 -275.564855) (xy 117.936056 -275.57298) (xy 117.985449 -275.589028)
			(xy 118.031723 -275.612606) (xy 118.073739 -275.643132) (xy 118.110462 -275.679855) (xy 118.140988 -275.721871)
			(xy 118.164566 -275.768145) (xy 118.180614 -275.817538) (xy 118.188739 -275.868833) (xy 118.189248 -275.8948)
			(xy 118.188739 -275.920767) (xy 118.468903 -275.920767) (xy 118.468903 -275.868833) (xy 118.477028 -275.817538)
			(xy 118.493076 -275.768145) (xy 118.516654 -275.721871) (xy 118.54718 -275.679855) (xy 118.583903 -275.643132)
			(xy 118.625919 -275.612606) (xy 118.672193 -275.589028) (xy 118.721586 -275.57298) (xy 118.772881 -275.564855)
			(xy 118.824815 -275.564855) (xy 118.87611 -275.57298) (xy 118.925503 -275.589028) (xy 118.971777 -275.612606)
			(xy 119.013793 -275.643132) (xy 119.050516 -275.679855) (xy 119.081042 -275.721871) (xy 119.10462 -275.768145)
			(xy 119.120668 -275.817538) (xy 119.128793 -275.868833) (xy 119.129302 -275.8948) (xy 119.128798 -275.920513)
			(xy 119.408703 -275.920513) (xy 119.408703 -275.868579) (xy 119.416828 -275.817284) (xy 119.432876 -275.767891)
			(xy 119.456454 -275.721617) (xy 119.48698 -275.679601) (xy 119.523703 -275.642878) (xy 119.565719 -275.612352)
			(xy 119.611993 -275.588774) (xy 119.661386 -275.572726) (xy 119.712681 -275.564601) (xy 119.764615 -275.564601)
			(xy 119.81591 -275.572726) (xy 119.865303 -275.588774) (xy 119.911577 -275.612352) (xy 119.953593 -275.642878)
			(xy 119.990316 -275.679601) (xy 120.020842 -275.721617) (xy 120.04442 -275.767891) (xy 120.060468 -275.817284)
			(xy 120.068593 -275.868579) (xy 120.069102 -275.894546) (xy 120.068593 -275.920513) (xy 120.348503 -275.920513)
			(xy 120.348503 -275.868579) (xy 120.356628 -275.817284) (xy 120.372676 -275.767891) (xy 120.396254 -275.721617)
			(xy 120.42678 -275.679601) (xy 120.463503 -275.642878) (xy 120.505519 -275.612352) (xy 120.551793 -275.588774)
			(xy 120.601186 -275.572726) (xy 120.652481 -275.564601) (xy 120.704415 -275.564601) (xy 120.75571 -275.572726)
			(xy 120.805103 -275.588774) (xy 120.851377 -275.612352) (xy 120.893393 -275.642878) (xy 120.930116 -275.679601)
			(xy 120.960642 -275.721617) (xy 120.98422 -275.767891) (xy 121.000268 -275.817284) (xy 121.008393 -275.868579)
			(xy 121.008902 -275.894546) (xy 121.008393 -275.920513) (xy 121.288303 -275.920513) (xy 121.288303 -275.868579)
			(xy 121.296428 -275.817284) (xy 121.312476 -275.767891) (xy 121.336054 -275.721617) (xy 121.36658 -275.679601)
			(xy 121.403303 -275.642878) (xy 121.445319 -275.612352) (xy 121.491593 -275.588774) (xy 121.540986 -275.572726)
			(xy 121.592281 -275.564601) (xy 121.644215 -275.564601) (xy 121.69551 -275.572726) (xy 121.744903 -275.588774)
			(xy 121.791177 -275.612352) (xy 121.833193 -275.642878) (xy 121.869916 -275.679601) (xy 121.900442 -275.721617)
			(xy 121.92402 -275.767891) (xy 121.940068 -275.817284) (xy 121.948193 -275.868579) (xy 121.948702 -275.894546)
			(xy 121.948193 -275.920513) (xy 121.948153 -275.920767) (xy 122.228103 -275.920767) (xy 122.228103 -275.868833)
			(xy 122.236228 -275.817538) (xy 122.252276 -275.768145) (xy 122.275854 -275.721871) (xy 122.30638 -275.679855)
			(xy 122.343103 -275.643132) (xy 122.385119 -275.612606) (xy 122.431393 -275.589028) (xy 122.480786 -275.57298)
			(xy 122.532081 -275.564855) (xy 122.584015 -275.564855) (xy 122.63531 -275.57298) (xy 122.684703 -275.589028)
			(xy 122.730977 -275.612606) (xy 122.772993 -275.643132) (xy 122.809716 -275.679855) (xy 122.840242 -275.721871)
			(xy 122.86382 -275.768145) (xy 122.879868 -275.817538) (xy 122.887993 -275.868833) (xy 122.888502 -275.8948)
			(xy 122.887993 -275.920767) (xy 123.167649 -275.920767) (xy 123.167649 -275.868833) (xy 123.175774 -275.817538)
			(xy 123.191822 -275.768145) (xy 123.2154 -275.721871) (xy 123.245926 -275.679855) (xy 123.282649 -275.643132)
			(xy 123.324665 -275.612606) (xy 123.370939 -275.589028) (xy 123.420332 -275.57298) (xy 123.471627 -275.564855)
			(xy 123.523561 -275.564855) (xy 123.574856 -275.57298) (xy 123.624249 -275.589028) (xy 123.670523 -275.612606)
			(xy 123.712539 -275.643132) (xy 123.749262 -275.679855) (xy 123.779788 -275.721871) (xy 123.803366 -275.768145)
			(xy 123.819414 -275.817538) (xy 123.827539 -275.868833) (xy 123.828048 -275.8948) (xy 123.827539 -275.920767)
			(xy 124.107449 -275.920767) (xy 124.107449 -275.868833) (xy 124.115574 -275.817538) (xy 124.131622 -275.768145)
			(xy 124.1552 -275.721871) (xy 124.185726 -275.679855) (xy 124.222449 -275.643132) (xy 124.264465 -275.612606)
			(xy 124.310739 -275.589028) (xy 124.360132 -275.57298) (xy 124.411427 -275.564855) (xy 124.463361 -275.564855)
			(xy 124.514656 -275.57298) (xy 124.564049 -275.589028) (xy 124.610323 -275.612606) (xy 124.652339 -275.643132)
			(xy 124.689062 -275.679855) (xy 124.719588 -275.721871) (xy 124.743166 -275.768145) (xy 124.759214 -275.817538)
			(xy 124.767339 -275.868833) (xy 124.767848 -275.8948) (xy 124.767339 -275.920767) (xy 125.047249 -275.920767)
			(xy 125.047249 -275.868833) (xy 125.055374 -275.817538) (xy 125.071422 -275.768145) (xy 125.095 -275.721871)
			(xy 125.125526 -275.679855) (xy 125.162249 -275.643132) (xy 125.204265 -275.612606) (xy 125.250539 -275.589028)
			(xy 125.299932 -275.57298) (xy 125.351227 -275.564855) (xy 125.403161 -275.564855) (xy 125.454456 -275.57298)
			(xy 125.503849 -275.589028) (xy 125.550123 -275.612606) (xy 125.592139 -275.643132) (xy 125.628862 -275.679855)
			(xy 125.659388 -275.721871) (xy 125.682966 -275.768145) (xy 125.699014 -275.817538) (xy 125.707139 -275.868833)
			(xy 125.707648 -275.8948) (xy 125.707139 -275.920767) (xy 125.987049 -275.920767) (xy 125.987049 -275.868833)
			(xy 125.995174 -275.817538) (xy 126.011222 -275.768145) (xy 126.0348 -275.721871) (xy 126.065326 -275.679855)
			(xy 126.102049 -275.643132) (xy 126.144065 -275.612606) (xy 126.190339 -275.589028) (xy 126.239732 -275.57298)
			(xy 126.291027 -275.564855) (xy 126.342961 -275.564855) (xy 126.394256 -275.57298) (xy 126.443649 -275.589028)
			(xy 126.489923 -275.612606) (xy 126.531939 -275.643132) (xy 126.568662 -275.679855) (xy 126.599188 -275.721871)
			(xy 126.622766 -275.768145) (xy 126.638814 -275.817538) (xy 126.646939 -275.868833) (xy 126.647448 -275.8948)
			(xy 126.646939 -275.920767) (xy 126.926849 -275.920767) (xy 126.926849 -275.868833) (xy 126.934974 -275.817538)
			(xy 126.951022 -275.768145) (xy 126.9746 -275.721871) (xy 127.005126 -275.679855) (xy 127.041849 -275.643132)
			(xy 127.083865 -275.612606) (xy 127.130139 -275.589028) (xy 127.179532 -275.57298) (xy 127.230827 -275.564855)
			(xy 127.282761 -275.564855) (xy 127.334056 -275.57298) (xy 127.383449 -275.589028) (xy 127.429723 -275.612606)
			(xy 127.471739 -275.643132) (xy 127.508462 -275.679855) (xy 127.538988 -275.721871) (xy 127.562566 -275.768145)
			(xy 127.578614 -275.817538) (xy 127.586739 -275.868833) (xy 127.587248 -275.8948) (xy 127.586739 -275.920767)
			(xy 127.866649 -275.920767) (xy 127.866649 -275.868833) (xy 127.874774 -275.817538) (xy 127.890822 -275.768145)
			(xy 127.9144 -275.721871) (xy 127.944926 -275.679855) (xy 127.981649 -275.643132) (xy 128.023665 -275.612606)
			(xy 128.069939 -275.589028) (xy 128.119332 -275.57298) (xy 128.170627 -275.564855) (xy 128.222561 -275.564855)
			(xy 128.273856 -275.57298) (xy 128.323249 -275.589028) (xy 128.369523 -275.612606) (xy 128.411539 -275.643132)
			(xy 128.448262 -275.679855) (xy 128.478788 -275.721871) (xy 128.502366 -275.768145) (xy 128.518414 -275.817538)
			(xy 128.526539 -275.868833) (xy 128.527048 -275.8948) (xy 128.526539 -275.920767) (xy 128.518414 -275.972062)
			(xy 128.502366 -276.021455) (xy 128.478788 -276.067729) (xy 128.448262 -276.109745) (xy 128.411539 -276.146468)
			(xy 128.369523 -276.176994) (xy 128.323249 -276.200572) (xy 128.273856 -276.21662) (xy 128.222561 -276.224745)
			(xy 128.170627 -276.224745) (xy 128.119332 -276.21662) (xy 128.069939 -276.200572) (xy 128.023665 -276.176994)
			(xy 127.981649 -276.146468) (xy 127.944926 -276.109745) (xy 127.9144 -276.067729) (xy 127.890822 -276.021455)
			(xy 127.874774 -275.972062) (xy 127.866649 -275.920767) (xy 127.586739 -275.920767) (xy 127.578614 -275.972062)
			(xy 127.562566 -276.021455) (xy 127.538988 -276.067729) (xy 127.508462 -276.109745) (xy 127.471739 -276.146468)
			(xy 127.429723 -276.176994) (xy 127.383449 -276.200572) (xy 127.334056 -276.21662) (xy 127.282761 -276.224745)
			(xy 127.230827 -276.224745) (xy 127.179532 -276.21662) (xy 127.130139 -276.200572) (xy 127.083865 -276.176994)
			(xy 127.041849 -276.146468) (xy 127.005126 -276.109745) (xy 126.9746 -276.067729) (xy 126.951022 -276.021455)
			(xy 126.934974 -275.972062) (xy 126.926849 -275.920767) (xy 126.646939 -275.920767) (xy 126.638814 -275.972062)
			(xy 126.622766 -276.021455) (xy 126.599188 -276.067729) (xy 126.568662 -276.109745) (xy 126.531939 -276.146468)
			(xy 126.489923 -276.176994) (xy 126.443649 -276.200572) (xy 126.394256 -276.21662) (xy 126.342961 -276.224745)
			(xy 126.291027 -276.224745) (xy 126.239732 -276.21662) (xy 126.190339 -276.200572) (xy 126.144065 -276.176994)
			(xy 126.102049 -276.146468) (xy 126.065326 -276.109745) (xy 126.0348 -276.067729) (xy 126.011222 -276.021455)
			(xy 125.995174 -275.972062) (xy 125.987049 -275.920767) (xy 125.707139 -275.920767) (xy 125.699014 -275.972062)
			(xy 125.682966 -276.021455) (xy 125.659388 -276.067729) (xy 125.628862 -276.109745) (xy 125.592139 -276.146468)
			(xy 125.550123 -276.176994) (xy 125.503849 -276.200572) (xy 125.454456 -276.21662) (xy 125.403161 -276.224745)
			(xy 125.351227 -276.224745) (xy 125.299932 -276.21662) (xy 125.250539 -276.200572) (xy 125.204265 -276.176994)
			(xy 125.162249 -276.146468) (xy 125.125526 -276.109745) (xy 125.095 -276.067729) (xy 125.071422 -276.021455)
			(xy 125.055374 -275.972062) (xy 125.047249 -275.920767) (xy 124.767339 -275.920767) (xy 124.759214 -275.972062)
			(xy 124.743166 -276.021455) (xy 124.719588 -276.067729) (xy 124.689062 -276.109745) (xy 124.652339 -276.146468)
			(xy 124.610323 -276.176994) (xy 124.564049 -276.200572) (xy 124.514656 -276.21662) (xy 124.463361 -276.224745)
			(xy 124.411427 -276.224745) (xy 124.360132 -276.21662) (xy 124.310739 -276.200572) (xy 124.264465 -276.176994)
			(xy 124.222449 -276.146468) (xy 124.185726 -276.109745) (xy 124.1552 -276.067729) (xy 124.131622 -276.021455)
			(xy 124.115574 -275.972062) (xy 124.107449 -275.920767) (xy 123.827539 -275.920767) (xy 123.819414 -275.972062)
			(xy 123.803366 -276.021455) (xy 123.779788 -276.067729) (xy 123.749262 -276.109745) (xy 123.712539 -276.146468)
			(xy 123.670523 -276.176994) (xy 123.624249 -276.200572) (xy 123.574856 -276.21662) (xy 123.523561 -276.224745)
			(xy 123.471627 -276.224745) (xy 123.420332 -276.21662) (xy 123.370939 -276.200572) (xy 123.324665 -276.176994)
			(xy 123.282649 -276.146468) (xy 123.245926 -276.109745) (xy 123.2154 -276.067729) (xy 123.191822 -276.021455)
			(xy 123.175774 -275.972062) (xy 123.167649 -275.920767) (xy 122.887993 -275.920767) (xy 122.879868 -275.972062)
			(xy 122.86382 -276.021455) (xy 122.840242 -276.067729) (xy 122.809716 -276.109745) (xy 122.772993 -276.146468)
			(xy 122.730977 -276.176994) (xy 122.684703 -276.200572) (xy 122.63531 -276.21662) (xy 122.584015 -276.224745)
			(xy 122.532081 -276.224745) (xy 122.480786 -276.21662) (xy 122.431393 -276.200572) (xy 122.385119 -276.176994)
			(xy 122.343103 -276.146468) (xy 122.30638 -276.109745) (xy 122.275854 -276.067729) (xy 122.252276 -276.021455)
			(xy 122.236228 -275.972062) (xy 122.228103 -275.920767) (xy 121.948153 -275.920767) (xy 121.940068 -275.971808)
			(xy 121.92402 -276.021201) (xy 121.900442 -276.067475) (xy 121.869916 -276.109491) (xy 121.833193 -276.146214)
			(xy 121.791177 -276.17674) (xy 121.744903 -276.200318) (xy 121.69551 -276.216366) (xy 121.644215 -276.224491)
			(xy 121.592281 -276.224491) (xy 121.540986 -276.216366) (xy 121.491593 -276.200318) (xy 121.445319 -276.17674)
			(xy 121.403303 -276.146214) (xy 121.36658 -276.109491) (xy 121.336054 -276.067475) (xy 121.312476 -276.021201)
			(xy 121.296428 -275.971808) (xy 121.288303 -275.920513) (xy 121.008393 -275.920513) (xy 121.000268 -275.971808)
			(xy 120.98422 -276.021201) (xy 120.960642 -276.067475) (xy 120.930116 -276.109491) (xy 120.893393 -276.146214)
			(xy 120.851377 -276.17674) (xy 120.805103 -276.200318) (xy 120.75571 -276.216366) (xy 120.704415 -276.224491)
			(xy 120.652481 -276.224491) (xy 120.601186 -276.216366) (xy 120.551793 -276.200318) (xy 120.505519 -276.17674)
			(xy 120.463503 -276.146214) (xy 120.42678 -276.109491) (xy 120.396254 -276.067475) (xy 120.372676 -276.021201)
			(xy 120.356628 -275.971808) (xy 120.348503 -275.920513) (xy 120.068593 -275.920513) (xy 120.060468 -275.971808)
			(xy 120.04442 -276.021201) (xy 120.020842 -276.067475) (xy 119.990316 -276.109491) (xy 119.953593 -276.146214)
			(xy 119.911577 -276.17674) (xy 119.865303 -276.200318) (xy 119.81591 -276.216366) (xy 119.764615 -276.224491)
			(xy 119.712681 -276.224491) (xy 119.661386 -276.216366) (xy 119.611993 -276.200318) (xy 119.565719 -276.17674)
			(xy 119.523703 -276.146214) (xy 119.48698 -276.109491) (xy 119.456454 -276.067475) (xy 119.432876 -276.021201)
			(xy 119.416828 -275.971808) (xy 119.408703 -275.920513) (xy 119.128798 -275.920513) (xy 119.128793 -275.920767)
			(xy 119.120668 -275.972062) (xy 119.10462 -276.021455) (xy 119.081042 -276.067729) (xy 119.050516 -276.109745)
			(xy 119.013793 -276.146468) (xy 118.971777 -276.176994) (xy 118.925503 -276.200572) (xy 118.87611 -276.21662)
			(xy 118.824815 -276.224745) (xy 118.772881 -276.224745) (xy 118.721586 -276.21662) (xy 118.672193 -276.200572)
			(xy 118.625919 -276.176994) (xy 118.583903 -276.146468) (xy 118.54718 -276.109745) (xy 118.516654 -276.067729)
			(xy 118.493076 -276.021455) (xy 118.477028 -275.972062) (xy 118.468903 -275.920767) (xy 118.188739 -275.920767)
			(xy 118.180614 -275.972062) (xy 118.164566 -276.021455) (xy 118.140988 -276.067729) (xy 118.110462 -276.109745)
			(xy 118.073739 -276.146468) (xy 118.031723 -276.176994) (xy 117.985449 -276.200572) (xy 117.936056 -276.21662)
			(xy 117.884761 -276.224745) (xy 117.832827 -276.224745) (xy 117.781532 -276.21662) (xy 117.732139 -276.200572)
			(xy 117.685865 -276.176994) (xy 117.643849 -276.146468) (xy 117.607126 -276.109745) (xy 117.5766 -276.067729)
			(xy 117.553022 -276.021455) (xy 117.536974 -275.972062) (xy 117.528849 -275.920767) (xy 117.248939 -275.920767)
			(xy 117.240814 -275.972062) (xy 117.224766 -276.021455) (xy 117.201188 -276.067729) (xy 117.170662 -276.109745)
			(xy 117.133939 -276.146468) (xy 117.091923 -276.176994) (xy 117.045649 -276.200572) (xy 116.996256 -276.21662)
			(xy 116.944961 -276.224745) (xy 116.893027 -276.224745) (xy 116.841732 -276.21662) (xy 116.792339 -276.200572)
			(xy 116.746065 -276.176994) (xy 116.704049 -276.146468) (xy 116.667326 -276.109745) (xy 116.6368 -276.067729)
			(xy 116.613222 -276.021455) (xy 116.597174 -275.972062) (xy 116.589049 -275.920767) (xy 116.309139 -275.920767)
			(xy 116.301014 -275.972062) (xy 116.284966 -276.021455) (xy 116.261388 -276.067729) (xy 116.230862 -276.109745)
			(xy 116.194139 -276.146468) (xy 116.152123 -276.176994) (xy 116.105849 -276.200572) (xy 116.056456 -276.21662)
			(xy 116.005161 -276.224745) (xy 115.953227 -276.224745) (xy 115.901932 -276.21662) (xy 115.852539 -276.200572)
			(xy 115.806265 -276.176994) (xy 115.764249 -276.146468) (xy 115.727526 -276.109745) (xy 115.697 -276.067729)
			(xy 115.673422 -276.021455) (xy 115.657374 -275.972062) (xy 115.649249 -275.920767) (xy 114.744246 -275.920767)
			(xy 114.744246 -276.427946) (xy 114.765896 -276.441995) (xy 114.804951 -276.475731) (xy 114.838288 -276.515127)
			(xy 114.865096 -276.559226) (xy 114.884723 -276.606956) (xy 114.896693 -276.657157) (xy 114.900715 -276.708608)
			(xy 114.898703 -276.734329) (xy 115.179349 -276.734329) (xy 115.179349 -276.682395) (xy 115.187474 -276.6311)
			(xy 115.203522 -276.581707) (xy 115.2271 -276.535433) (xy 115.257626 -276.493417) (xy 115.294349 -276.456694)
			(xy 115.336365 -276.426168) (xy 115.382639 -276.40259) (xy 115.432032 -276.386542) (xy 115.483327 -276.378417)
			(xy 115.535261 -276.378417) (xy 115.586556 -276.386542) (xy 115.635949 -276.40259) (xy 115.682223 -276.426168)
			(xy 115.724239 -276.456694) (xy 115.760962 -276.493417) (xy 115.791488 -276.535433) (xy 115.815066 -276.581707)
			(xy 115.831114 -276.6311) (xy 115.839239 -276.682395) (xy 115.839748 -276.708362) (xy 115.839239 -276.734329)
			(xy 116.119149 -276.734329) (xy 116.119149 -276.682395) (xy 116.127274 -276.6311) (xy 116.143322 -276.581707)
			(xy 116.1669 -276.535433) (xy 116.197426 -276.493417) (xy 116.234149 -276.456694) (xy 116.276165 -276.426168)
			(xy 116.322439 -276.40259) (xy 116.371832 -276.386542) (xy 116.423127 -276.378417) (xy 116.475061 -276.378417)
			(xy 116.526356 -276.386542) (xy 116.575749 -276.40259) (xy 116.622023 -276.426168) (xy 116.664039 -276.456694)
			(xy 116.700762 -276.493417) (xy 116.731288 -276.535433) (xy 116.754866 -276.581707) (xy 116.770914 -276.6311)
			(xy 116.779039 -276.682395) (xy 116.779548 -276.708362) (xy 116.779039 -276.734329) (xy 117.058949 -276.734329)
			(xy 117.058949 -276.682395) (xy 117.067074 -276.6311) (xy 117.083122 -276.581707) (xy 117.1067 -276.535433)
			(xy 117.137226 -276.493417) (xy 117.173949 -276.456694) (xy 117.215965 -276.426168) (xy 117.262239 -276.40259)
			(xy 117.311632 -276.386542) (xy 117.362927 -276.378417) (xy 117.414861 -276.378417) (xy 117.466156 -276.386542)
			(xy 117.515549 -276.40259) (xy 117.561823 -276.426168) (xy 117.603839 -276.456694) (xy 117.640562 -276.493417)
			(xy 117.671088 -276.535433) (xy 117.694666 -276.581707) (xy 117.710714 -276.6311) (xy 117.718839 -276.682395)
			(xy 117.719348 -276.708362) (xy 117.718839 -276.734329) (xy 117.998749 -276.734329) (xy 117.998749 -276.682395)
			(xy 118.006874 -276.6311) (xy 118.022922 -276.581707) (xy 118.0465 -276.535433) (xy 118.077026 -276.493417)
			(xy 118.113749 -276.456694) (xy 118.155765 -276.426168) (xy 118.202039 -276.40259) (xy 118.251432 -276.386542)
			(xy 118.302727 -276.378417) (xy 118.354661 -276.378417) (xy 118.405956 -276.386542) (xy 118.455349 -276.40259)
			(xy 118.501623 -276.426168) (xy 118.543639 -276.456694) (xy 118.580362 -276.493417) (xy 118.610888 -276.535433)
			(xy 118.634466 -276.581707) (xy 118.650514 -276.6311) (xy 118.658639 -276.682395) (xy 118.659148 -276.708362)
			(xy 118.658639 -276.734329) (xy 118.658599 -276.734583) (xy 118.938549 -276.734583) (xy 118.938549 -276.682649)
			(xy 118.946674 -276.631354) (xy 118.962722 -276.581961) (xy 118.9863 -276.535687) (xy 119.016826 -276.493671)
			(xy 119.053549 -276.456948) (xy 119.095565 -276.426422) (xy 119.141839 -276.402844) (xy 119.191232 -276.386796)
			(xy 119.242527 -276.378671) (xy 119.294461 -276.378671) (xy 119.345756 -276.386796) (xy 119.395149 -276.402844)
			(xy 119.441423 -276.426422) (xy 119.483439 -276.456948) (xy 119.520162 -276.493671) (xy 119.550688 -276.535687)
			(xy 119.574266 -276.581961) (xy 119.590314 -276.631354) (xy 119.598439 -276.682649) (xy 119.598948 -276.708616)
			(xy 119.598444 -276.734329) (xy 119.878349 -276.734329) (xy 119.878349 -276.682395) (xy 119.886474 -276.6311)
			(xy 119.902522 -276.581707) (xy 119.9261 -276.535433) (xy 119.956626 -276.493417) (xy 119.993349 -276.456694)
			(xy 120.035365 -276.426168) (xy 120.081639 -276.40259) (xy 120.131032 -276.386542) (xy 120.182327 -276.378417)
			(xy 120.234261 -276.378417) (xy 120.285556 -276.386542) (xy 120.334949 -276.40259) (xy 120.381223 -276.426168)
			(xy 120.423239 -276.456694) (xy 120.459962 -276.493417) (xy 120.490488 -276.535433) (xy 120.514066 -276.581707)
			(xy 120.530114 -276.6311) (xy 120.538239 -276.682395) (xy 120.538748 -276.708362) (xy 120.538239 -276.734329)
			(xy 120.538199 -276.734583) (xy 120.818403 -276.734583) (xy 120.818403 -276.682649) (xy 120.826528 -276.631354)
			(xy 120.842576 -276.581961) (xy 120.866154 -276.535687) (xy 120.89668 -276.493671) (xy 120.933403 -276.456948)
			(xy 120.975419 -276.426422) (xy 121.021693 -276.402844) (xy 121.071086 -276.386796) (xy 121.122381 -276.378671)
			(xy 121.174315 -276.378671) (xy 121.22561 -276.386796) (xy 121.275003 -276.402844) (xy 121.321277 -276.426422)
			(xy 121.363293 -276.456948) (xy 121.400016 -276.493671) (xy 121.430542 -276.535687) (xy 121.45412 -276.581961)
			(xy 121.470168 -276.631354) (xy 121.478293 -276.682649) (xy 121.478802 -276.708616) (xy 121.478293 -276.734583)
			(xy 122.698003 -276.734583) (xy 122.698003 -276.682649) (xy 122.706128 -276.631354) (xy 122.722176 -276.581961)
			(xy 122.745754 -276.535687) (xy 122.77628 -276.493671) (xy 122.813003 -276.456948) (xy 122.855019 -276.426422)
			(xy 122.901293 -276.402844) (xy 122.950686 -276.386796) (xy 123.001981 -276.378671) (xy 123.053915 -276.378671)
			(xy 123.10521 -276.386796) (xy 123.154603 -276.402844) (xy 123.200877 -276.426422) (xy 123.242893 -276.456948)
			(xy 123.279616 -276.493671) (xy 123.310142 -276.535687) (xy 123.33372 -276.581961) (xy 123.349768 -276.631354)
			(xy 123.357893 -276.682649) (xy 123.358402 -276.708616) (xy 123.357893 -276.734583) (xy 123.637803 -276.734583)
			(xy 123.637803 -276.682649) (xy 123.645928 -276.631354) (xy 123.661976 -276.581961) (xy 123.685554 -276.535687)
			(xy 123.71608 -276.493671) (xy 123.752803 -276.456948) (xy 123.794819 -276.426422) (xy 123.841093 -276.402844)
			(xy 123.890486 -276.386796) (xy 123.941781 -276.378671) (xy 123.993715 -276.378671) (xy 124.04501 -276.386796)
			(xy 124.094403 -276.402844) (xy 124.140677 -276.426422) (xy 124.182693 -276.456948) (xy 124.219416 -276.493671)
			(xy 124.249942 -276.535687) (xy 124.27352 -276.581961) (xy 124.289568 -276.631354) (xy 124.297693 -276.682649)
			(xy 124.298202 -276.708616) (xy 124.297693 -276.734583) (xy 124.577603 -276.734583) (xy 124.577603 -276.682649)
			(xy 124.585728 -276.631354) (xy 124.601776 -276.581961) (xy 124.625354 -276.535687) (xy 124.65588 -276.493671)
			(xy 124.692603 -276.456948) (xy 124.734619 -276.426422) (xy 124.780893 -276.402844) (xy 124.830286 -276.386796)
			(xy 124.881581 -276.378671) (xy 124.933515 -276.378671) (xy 124.98481 -276.386796) (xy 125.034203 -276.402844)
			(xy 125.080477 -276.426422) (xy 125.122493 -276.456948) (xy 125.159216 -276.493671) (xy 125.189742 -276.535687)
			(xy 125.21332 -276.581961) (xy 125.229368 -276.631354) (xy 125.237493 -276.682649) (xy 125.238002 -276.708616)
			(xy 125.237493 -276.734583) (xy 125.517149 -276.734583) (xy 125.517149 -276.682649) (xy 125.525274 -276.631354)
			(xy 125.541322 -276.581961) (xy 125.5649 -276.535687) (xy 125.595426 -276.493671) (xy 125.632149 -276.456948)
			(xy 125.674165 -276.426422) (xy 125.720439 -276.402844) (xy 125.769832 -276.386796) (xy 125.821127 -276.378671)
			(xy 125.873061 -276.378671) (xy 125.924356 -276.386796) (xy 125.973749 -276.402844) (xy 126.020023 -276.426422)
			(xy 126.062039 -276.456948) (xy 126.098762 -276.493671) (xy 126.129288 -276.535687) (xy 126.152866 -276.581961)
			(xy 126.168914 -276.631354) (xy 126.177039 -276.682649) (xy 126.177548 -276.708616) (xy 126.177039 -276.734583)
			(xy 126.457203 -276.734583) (xy 126.457203 -276.682649) (xy 126.465328 -276.631354) (xy 126.481376 -276.581961)
			(xy 126.504954 -276.535687) (xy 126.53548 -276.493671) (xy 126.572203 -276.456948) (xy 126.614219 -276.426422)
			(xy 126.660493 -276.402844) (xy 126.709886 -276.386796) (xy 126.761181 -276.378671) (xy 126.813115 -276.378671)
			(xy 126.86441 -276.386796) (xy 126.913803 -276.402844) (xy 126.960077 -276.426422) (xy 127.002093 -276.456948)
			(xy 127.038816 -276.493671) (xy 127.069342 -276.535687) (xy 127.09292 -276.581961) (xy 127.108968 -276.631354)
			(xy 127.117093 -276.682649) (xy 127.117602 -276.708616) (xy 127.117093 -276.734583) (xy 127.397003 -276.734583)
			(xy 127.397003 -276.682649) (xy 127.405128 -276.631354) (xy 127.421176 -276.581961) (xy 127.444754 -276.535687)
			(xy 127.47528 -276.493671) (xy 127.512003 -276.456948) (xy 127.554019 -276.426422) (xy 127.600293 -276.402844)
			(xy 127.649686 -276.386796) (xy 127.700981 -276.378671) (xy 127.752915 -276.378671) (xy 127.80421 -276.386796)
			(xy 127.853603 -276.402844) (xy 127.899877 -276.426422) (xy 127.941893 -276.456948) (xy 127.978616 -276.493671)
			(xy 128.009142 -276.535687) (xy 128.03272 -276.581961) (xy 128.048768 -276.631354) (xy 128.056893 -276.682649)
			(xy 128.057402 -276.708616) (xy 128.056893 -276.734583) (xy 128.336803 -276.734583) (xy 128.336803 -276.682649)
			(xy 128.344928 -276.631354) (xy 128.360976 -276.581961) (xy 128.384554 -276.535687) (xy 128.41508 -276.493671)
			(xy 128.451803 -276.456948) (xy 128.493819 -276.426422) (xy 128.540093 -276.402844) (xy 128.589486 -276.386796)
			(xy 128.640781 -276.378671) (xy 128.692715 -276.378671) (xy 128.74401 -276.386796) (xy 128.793403 -276.402844)
			(xy 128.839677 -276.426422) (xy 128.881693 -276.456948) (xy 128.918416 -276.493671) (xy 128.948942 -276.535687)
			(xy 128.97252 -276.581961) (xy 128.988568 -276.631354) (xy 128.996693 -276.682649) (xy 128.997202 -276.708616)
			(xy 128.996693 -276.734583) (xy 128.988568 -276.785878) (xy 128.97252 -276.835271) (xy 128.948942 -276.881545)
			(xy 128.918416 -276.923561) (xy 128.881693 -276.960284) (xy 128.839677 -276.99081) (xy 128.793403 -277.014388)
			(xy 128.74401 -277.030436) (xy 128.692715 -277.038561) (xy 128.640781 -277.038561) (xy 128.589486 -277.030436)
			(xy 128.540093 -277.014388) (xy 128.493819 -276.99081) (xy 128.451803 -276.960284) (xy 128.41508 -276.923561)
			(xy 128.384554 -276.881545) (xy 128.360976 -276.835271) (xy 128.344928 -276.785878) (xy 128.336803 -276.734583)
			(xy 128.056893 -276.734583) (xy 128.048768 -276.785878) (xy 128.03272 -276.835271) (xy 128.009142 -276.881545)
			(xy 127.978616 -276.923561) (xy 127.941893 -276.960284) (xy 127.899877 -276.99081) (xy 127.853603 -277.014388)
			(xy 127.80421 -277.030436) (xy 127.752915 -277.038561) (xy 127.700981 -277.038561) (xy 127.649686 -277.030436)
			(xy 127.600293 -277.014388) (xy 127.554019 -276.99081) (xy 127.512003 -276.960284) (xy 127.47528 -276.923561)
			(xy 127.444754 -276.881545) (xy 127.421176 -276.835271) (xy 127.405128 -276.785878) (xy 127.397003 -276.734583)
			(xy 127.117093 -276.734583) (xy 127.108968 -276.785878) (xy 127.09292 -276.835271) (xy 127.069342 -276.881545)
			(xy 127.038816 -276.923561) (xy 127.002093 -276.960284) (xy 126.960077 -276.99081) (xy 126.913803 -277.014388)
			(xy 126.86441 -277.030436) (xy 126.813115 -277.038561) (xy 126.761181 -277.038561) (xy 126.709886 -277.030436)
			(xy 126.660493 -277.014388) (xy 126.614219 -276.99081) (xy 126.572203 -276.960284) (xy 126.53548 -276.923561)
			(xy 126.504954 -276.881545) (xy 126.481376 -276.835271) (xy 126.465328 -276.785878) (xy 126.457203 -276.734583)
			(xy 126.177039 -276.734583) (xy 126.168914 -276.785878) (xy 126.152866 -276.835271) (xy 126.129288 -276.881545)
			(xy 126.098762 -276.923561) (xy 126.062039 -276.960284) (xy 126.020023 -276.99081) (xy 125.973749 -277.014388)
			(xy 125.924356 -277.030436) (xy 125.873061 -277.038561) (xy 125.821127 -277.038561) (xy 125.769832 -277.030436)
			(xy 125.720439 -277.014388) (xy 125.674165 -276.99081) (xy 125.632149 -276.960284) (xy 125.595426 -276.923561)
			(xy 125.5649 -276.881545) (xy 125.541322 -276.835271) (xy 125.525274 -276.785878) (xy 125.517149 -276.734583)
			(xy 125.237493 -276.734583) (xy 125.229368 -276.785878) (xy 125.21332 -276.835271) (xy 125.189742 -276.881545)
			(xy 125.159216 -276.923561) (xy 125.122493 -276.960284) (xy 125.080477 -276.99081) (xy 125.034203 -277.014388)
			(xy 124.98481 -277.030436) (xy 124.933515 -277.038561) (xy 124.881581 -277.038561) (xy 124.830286 -277.030436)
			(xy 124.780893 -277.014388) (xy 124.734619 -276.99081) (xy 124.692603 -276.960284) (xy 124.65588 -276.923561)
			(xy 124.625354 -276.881545) (xy 124.601776 -276.835271) (xy 124.585728 -276.785878) (xy 124.577603 -276.734583)
			(xy 124.297693 -276.734583) (xy 124.289568 -276.785878) (xy 124.27352 -276.835271) (xy 124.249942 -276.881545)
			(xy 124.219416 -276.923561) (xy 124.182693 -276.960284) (xy 124.140677 -276.99081) (xy 124.094403 -277.014388)
			(xy 124.04501 -277.030436) (xy 123.993715 -277.038561) (xy 123.941781 -277.038561) (xy 123.890486 -277.030436)
			(xy 123.841093 -277.014388) (xy 123.794819 -276.99081) (xy 123.752803 -276.960284) (xy 123.71608 -276.923561)
			(xy 123.685554 -276.881545) (xy 123.661976 -276.835271) (xy 123.645928 -276.785878) (xy 123.637803 -276.734583)
			(xy 123.357893 -276.734583) (xy 123.349768 -276.785878) (xy 123.33372 -276.835271) (xy 123.310142 -276.881545)
			(xy 123.279616 -276.923561) (xy 123.242893 -276.960284) (xy 123.200877 -276.99081) (xy 123.154603 -277.014388)
			(xy 123.10521 -277.030436) (xy 123.053915 -277.038561) (xy 123.001981 -277.038561) (xy 122.950686 -277.030436)
			(xy 122.901293 -277.014388) (xy 122.855019 -276.99081) (xy 122.813003 -276.960284) (xy 122.77628 -276.923561)
			(xy 122.745754 -276.881545) (xy 122.722176 -276.835271) (xy 122.706128 -276.785878) (xy 122.698003 -276.734583)
			(xy 121.478293 -276.734583) (xy 121.470168 -276.785878) (xy 121.45412 -276.835271) (xy 121.430542 -276.881545)
			(xy 121.400016 -276.923561) (xy 121.363293 -276.960284) (xy 121.321277 -276.99081) (xy 121.275003 -277.014388)
			(xy 121.22561 -277.030436) (xy 121.174315 -277.038561) (xy 121.122381 -277.038561) (xy 121.071086 -277.030436)
			(xy 121.021693 -277.014388) (xy 120.975419 -276.99081) (xy 120.933403 -276.960284) (xy 120.89668 -276.923561)
			(xy 120.866154 -276.881545) (xy 120.842576 -276.835271) (xy 120.826528 -276.785878) (xy 120.818403 -276.734583)
			(xy 120.538199 -276.734583) (xy 120.530114 -276.785624) (xy 120.514066 -276.835017) (xy 120.490488 -276.881291)
			(xy 120.459962 -276.923307) (xy 120.423239 -276.96003) (xy 120.381223 -276.990556) (xy 120.334949 -277.014134)
			(xy 120.285556 -277.030182) (xy 120.234261 -277.038307) (xy 120.182327 -277.038307) (xy 120.131032 -277.030182)
			(xy 120.081639 -277.014134) (xy 120.035365 -276.990556) (xy 119.993349 -276.96003) (xy 119.956626 -276.923307)
			(xy 119.9261 -276.881291) (xy 119.902522 -276.835017) (xy 119.886474 -276.785624) (xy 119.878349 -276.734329)
			(xy 119.598444 -276.734329) (xy 119.598439 -276.734583) (xy 119.590314 -276.785878) (xy 119.574266 -276.835271)
			(xy 119.550688 -276.881545) (xy 119.520162 -276.923561) (xy 119.483439 -276.960284) (xy 119.441423 -276.99081)
			(xy 119.395149 -277.014388) (xy 119.345756 -277.030436) (xy 119.294461 -277.038561) (xy 119.242527 -277.038561)
			(xy 119.191232 -277.030436) (xy 119.141839 -277.014388) (xy 119.095565 -276.99081) (xy 119.053549 -276.960284)
			(xy 119.016826 -276.923561) (xy 118.9863 -276.881545) (xy 118.962722 -276.835271) (xy 118.946674 -276.785878)
			(xy 118.938549 -276.734583) (xy 118.658599 -276.734583) (xy 118.650514 -276.785624) (xy 118.634466 -276.835017)
			(xy 118.610888 -276.881291) (xy 118.580362 -276.923307) (xy 118.543639 -276.96003) (xy 118.501623 -276.990556)
			(xy 118.455349 -277.014134) (xy 118.405956 -277.030182) (xy 118.354661 -277.038307) (xy 118.302727 -277.038307)
			(xy 118.251432 -277.030182) (xy 118.202039 -277.014134) (xy 118.155765 -276.990556) (xy 118.113749 -276.96003)
			(xy 118.077026 -276.923307) (xy 118.0465 -276.881291) (xy 118.022922 -276.835017) (xy 118.006874 -276.785624)
			(xy 117.998749 -276.734329) (xy 117.718839 -276.734329) (xy 117.710714 -276.785624) (xy 117.694666 -276.835017)
			(xy 117.671088 -276.881291) (xy 117.640562 -276.923307) (xy 117.603839 -276.96003) (xy 117.561823 -276.990556)
			(xy 117.515549 -277.014134) (xy 117.466156 -277.030182) (xy 117.414861 -277.038307) (xy 117.362927 -277.038307)
			(xy 117.311632 -277.030182) (xy 117.262239 -277.014134) (xy 117.215965 -276.990556) (xy 117.173949 -276.96003)
			(xy 117.137226 -276.923307) (xy 117.1067 -276.881291) (xy 117.083122 -276.835017) (xy 117.067074 -276.785624)
			(xy 117.058949 -276.734329) (xy 116.779039 -276.734329) (xy 116.770914 -276.785624) (xy 116.754866 -276.835017)
			(xy 116.731288 -276.881291) (xy 116.700762 -276.923307) (xy 116.664039 -276.96003) (xy 116.622023 -276.990556)
			(xy 116.575749 -277.014134) (xy 116.526356 -277.030182) (xy 116.475061 -277.038307) (xy 116.423127 -277.038307)
			(xy 116.371832 -277.030182) (xy 116.322439 -277.014134) (xy 116.276165 -276.990556) (xy 116.234149 -276.96003)
			(xy 116.197426 -276.923307) (xy 116.1669 -276.881291) (xy 116.143322 -276.835017) (xy 116.127274 -276.785624)
			(xy 116.119149 -276.734329) (xy 115.839239 -276.734329) (xy 115.831114 -276.785624) (xy 115.815066 -276.835017)
			(xy 115.791488 -276.881291) (xy 115.760962 -276.923307) (xy 115.724239 -276.96003) (xy 115.682223 -276.990556)
			(xy 115.635949 -277.014134) (xy 115.586556 -277.030182) (xy 115.535261 -277.038307) (xy 115.483327 -277.038307)
			(xy 115.432032 -277.030182) (xy 115.382639 -277.014134) (xy 115.336365 -276.990556) (xy 115.294349 -276.96003)
			(xy 115.257626 -276.923307) (xy 115.2271 -276.881291) (xy 115.203522 -276.835017) (xy 115.187474 -276.785624)
			(xy 115.179349 -276.734329) (xy 114.898703 -276.734329) (xy 114.896691 -276.760059) (xy 114.884718 -276.81026)
			(xy 114.865088 -276.857989) (xy 114.838278 -276.902086) (xy 114.804939 -276.941481) (xy 114.765882 -276.975215)
			(xy 114.744246 -276.989286) (xy 114.744246 -277.136098) (xy 114.744749 -277.150898) (xy 114.753229 -277.179258)
			(xy 114.769478 -277.203999) (xy 114.792134 -277.223047) (xy 114.819299 -277.234806) (xy 114.848693 -277.23829)
			(xy 114.877853 -277.233206) (xy 114.891312 -277.22703) (xy 114.914416 -277.215979) (xy 114.963188 -277.200361)
			(xy 115.013788 -277.192464) (xy 115.039394 -277.191978) (xy 115.065363 -277.19246) (xy 115.116661 -277.200585)
			(xy 115.166056 -277.216635) (xy 115.212332 -277.240214) (xy 115.254349 -277.270744) (xy 115.291073 -277.30747)
			(xy 115.321599 -277.34949) (xy 115.345175 -277.395768) (xy 115.361221 -277.445165) (xy 115.369342 -277.496463)
			(xy 115.369848 -277.522432) (xy 115.369359 -277.548145) (xy 115.649503 -277.548145) (xy 115.649503 -277.496211)
			(xy 115.657628 -277.444916) (xy 115.673676 -277.395523) (xy 115.697254 -277.349249) (xy 115.72778 -277.307233)
			(xy 115.764503 -277.27051) (xy 115.806519 -277.239984) (xy 115.852793 -277.216406) (xy 115.902186 -277.200358)
			(xy 115.953481 -277.192233) (xy 116.005415 -277.192233) (xy 116.05671 -277.200358) (xy 116.106103 -277.216406)
			(xy 116.152377 -277.239984) (xy 116.194393 -277.27051) (xy 116.231116 -277.307233) (xy 116.261642 -277.349249)
			(xy 116.28522 -277.395523) (xy 116.301268 -277.444916) (xy 116.309393 -277.496211) (xy 116.309902 -277.522178)
			(xy 116.309393 -277.548145) (xy 116.309353 -277.548399) (xy 116.589049 -277.548399) (xy 116.589049 -277.496465)
			(xy 116.597174 -277.44517) (xy 116.613222 -277.395777) (xy 116.6368 -277.349503) (xy 116.667326 -277.307487)
			(xy 116.704049 -277.270764) (xy 116.746065 -277.240238) (xy 116.792339 -277.21666) (xy 116.841732 -277.200612)
			(xy 116.893027 -277.192487) (xy 116.944961 -277.192487) (xy 116.996256 -277.200612) (xy 117.045649 -277.21666)
			(xy 117.091923 -277.240238) (xy 117.133939 -277.270764) (xy 117.170662 -277.307487) (xy 117.201188 -277.349503)
			(xy 117.224766 -277.395777) (xy 117.240814 -277.44517) (xy 117.248939 -277.496465) (xy 117.249448 -277.522432)
			(xy 117.248944 -277.548145) (xy 117.529103 -277.548145) (xy 117.529103 -277.496211) (xy 117.537228 -277.444916)
			(xy 117.553276 -277.395523) (xy 117.576854 -277.349249) (xy 117.60738 -277.307233) (xy 117.644103 -277.27051)
			(xy 117.686119 -277.239984) (xy 117.732393 -277.216406) (xy 117.781786 -277.200358) (xy 117.833081 -277.192233)
			(xy 117.885015 -277.192233) (xy 117.93631 -277.200358) (xy 117.985703 -277.216406) (xy 118.031977 -277.239984)
			(xy 118.073993 -277.27051) (xy 118.110716 -277.307233) (xy 118.141242 -277.349249) (xy 118.16482 -277.395523)
			(xy 118.180868 -277.444916) (xy 118.188993 -277.496211) (xy 118.189502 -277.522178) (xy 118.188993 -277.548145)
			(xy 118.188953 -277.548399) (xy 118.468903 -277.548399) (xy 118.468903 -277.496465) (xy 118.477028 -277.44517)
			(xy 118.493076 -277.395777) (xy 118.516654 -277.349503) (xy 118.54718 -277.307487) (xy 118.583903 -277.270764)
			(xy 118.625919 -277.240238) (xy 118.672193 -277.21666) (xy 118.721586 -277.200612) (xy 118.772881 -277.192487)
			(xy 118.824815 -277.192487) (xy 118.87611 -277.200612) (xy 118.925503 -277.21666) (xy 118.971777 -277.240238)
			(xy 119.013793 -277.270764) (xy 119.050516 -277.307487) (xy 119.081042 -277.349503) (xy 119.10462 -277.395777)
			(xy 119.120668 -277.44517) (xy 119.128793 -277.496465) (xy 119.129302 -277.522432) (xy 119.128798 -277.548145)
			(xy 119.408703 -277.548145) (xy 119.408703 -277.496211) (xy 119.416828 -277.444916) (xy 119.432876 -277.395523)
			(xy 119.456454 -277.349249) (xy 119.48698 -277.307233) (xy 119.523703 -277.27051) (xy 119.565719 -277.239984)
			(xy 119.611993 -277.216406) (xy 119.661386 -277.200358) (xy 119.712681 -277.192233) (xy 119.764615 -277.192233)
			(xy 119.81591 -277.200358) (xy 119.865303 -277.216406) (xy 119.911577 -277.239984) (xy 119.953593 -277.27051)
			(xy 119.990316 -277.307233) (xy 120.020842 -277.349249) (xy 120.04442 -277.395523) (xy 120.060468 -277.444916)
			(xy 120.068593 -277.496211) (xy 120.069102 -277.522178) (xy 120.068593 -277.548145) (xy 120.348503 -277.548145)
			(xy 120.348503 -277.496211) (xy 120.356628 -277.444916) (xy 120.372676 -277.395523) (xy 120.396254 -277.349249)
			(xy 120.42678 -277.307233) (xy 120.463503 -277.27051) (xy 120.505519 -277.239984) (xy 120.551793 -277.216406)
			(xy 120.601186 -277.200358) (xy 120.652481 -277.192233) (xy 120.704415 -277.192233) (xy 120.75571 -277.200358)
			(xy 120.805103 -277.216406) (xy 120.851377 -277.239984) (xy 120.893393 -277.27051) (xy 120.930116 -277.307233)
			(xy 120.960642 -277.349249) (xy 120.98422 -277.395523) (xy 121.000268 -277.444916) (xy 121.008393 -277.496211)
			(xy 121.008902 -277.522178) (xy 121.008393 -277.548145) (xy 121.288303 -277.548145) (xy 121.288303 -277.496211)
			(xy 121.296428 -277.444916) (xy 121.312476 -277.395523) (xy 121.336054 -277.349249) (xy 121.36658 -277.307233)
			(xy 121.403303 -277.27051) (xy 121.445319 -277.239984) (xy 121.491593 -277.216406) (xy 121.540986 -277.200358)
			(xy 121.592281 -277.192233) (xy 121.644215 -277.192233) (xy 121.69551 -277.200358) (xy 121.744903 -277.216406)
			(xy 121.791177 -277.239984) (xy 121.833193 -277.27051) (xy 121.869916 -277.307233) (xy 121.900442 -277.349249)
			(xy 121.92402 -277.395523) (xy 121.940068 -277.444916) (xy 121.948193 -277.496211) (xy 121.948702 -277.522178)
			(xy 121.948193 -277.548145) (xy 122.228103 -277.548145) (xy 122.228103 -277.496211) (xy 122.236228 -277.444916)
			(xy 122.252276 -277.395523) (xy 122.275854 -277.349249) (xy 122.30638 -277.307233) (xy 122.343103 -277.27051)
			(xy 122.385119 -277.239984) (xy 122.431393 -277.216406) (xy 122.480786 -277.200358) (xy 122.532081 -277.192233)
			(xy 122.584015 -277.192233) (xy 122.63531 -277.200358) (xy 122.684703 -277.216406) (xy 122.730977 -277.239984)
			(xy 122.772993 -277.27051) (xy 122.809716 -277.307233) (xy 122.840242 -277.349249) (xy 122.86382 -277.395523)
			(xy 122.879868 -277.444916) (xy 122.887993 -277.496211) (xy 122.888502 -277.522178) (xy 122.887993 -277.548145)
			(xy 122.887953 -277.548399) (xy 123.167649 -277.548399) (xy 123.167649 -277.496465) (xy 123.175774 -277.44517)
			(xy 123.191822 -277.395777) (xy 123.2154 -277.349503) (xy 123.245926 -277.307487) (xy 123.282649 -277.270764)
			(xy 123.324665 -277.240238) (xy 123.370939 -277.21666) (xy 123.420332 -277.200612) (xy 123.471627 -277.192487)
			(xy 123.523561 -277.192487) (xy 123.574856 -277.200612) (xy 123.624249 -277.21666) (xy 123.670523 -277.240238)
			(xy 123.712539 -277.270764) (xy 123.749262 -277.307487) (xy 123.779788 -277.349503) (xy 123.803366 -277.395777)
			(xy 123.819414 -277.44517) (xy 123.827539 -277.496465) (xy 123.828048 -277.522432) (xy 123.827539 -277.548399)
			(xy 124.107449 -277.548399) (xy 124.107449 -277.496465) (xy 124.115574 -277.44517) (xy 124.131622 -277.395777)
			(xy 124.1552 -277.349503) (xy 124.185726 -277.307487) (xy 124.222449 -277.270764) (xy 124.264465 -277.240238)
			(xy 124.310739 -277.21666) (xy 124.360132 -277.200612) (xy 124.411427 -277.192487) (xy 124.463361 -277.192487)
			(xy 124.514656 -277.200612) (xy 124.564049 -277.21666) (xy 124.610323 -277.240238) (xy 124.652339 -277.270764)
			(xy 124.689062 -277.307487) (xy 124.719588 -277.349503) (xy 124.743166 -277.395777) (xy 124.759214 -277.44517)
			(xy 124.767339 -277.496465) (xy 124.767848 -277.522432) (xy 124.767339 -277.548399) (xy 125.047503 -277.548399)
			(xy 125.047503 -277.496465) (xy 125.055628 -277.44517) (xy 125.071676 -277.395777) (xy 125.095254 -277.349503)
			(xy 125.12578 -277.307487) (xy 125.162503 -277.270764) (xy 125.204519 -277.240238) (xy 125.250793 -277.21666)
			(xy 125.300186 -277.200612) (xy 125.351481 -277.192487) (xy 125.403415 -277.192487) (xy 125.45471 -277.200612)
			(xy 125.504103 -277.21666) (xy 125.550377 -277.240238) (xy 125.592393 -277.270764) (xy 125.629116 -277.307487)
			(xy 125.659642 -277.349503) (xy 125.68322 -277.395777) (xy 125.699268 -277.44517) (xy 125.707393 -277.496465)
			(xy 125.707902 -277.522432) (xy 125.707393 -277.548399) (xy 125.987049 -277.548399) (xy 125.987049 -277.496465)
			(xy 125.995174 -277.44517) (xy 126.011222 -277.395777) (xy 126.0348 -277.349503) (xy 126.065326 -277.307487)
			(xy 126.102049 -277.270764) (xy 126.144065 -277.240238) (xy 126.190339 -277.21666) (xy 126.239732 -277.200612)
			(xy 126.291027 -277.192487) (xy 126.342961 -277.192487) (xy 126.394256 -277.200612) (xy 126.443649 -277.21666)
			(xy 126.489923 -277.240238) (xy 126.531939 -277.270764) (xy 126.568662 -277.307487) (xy 126.599188 -277.349503)
			(xy 126.622766 -277.395777) (xy 126.638814 -277.44517) (xy 126.646939 -277.496465) (xy 126.647448 -277.522432)
			(xy 126.646939 -277.548399) (xy 126.926849 -277.548399) (xy 126.926849 -277.496465) (xy 126.934974 -277.44517)
			(xy 126.951022 -277.395777) (xy 126.9746 -277.349503) (xy 127.005126 -277.307487) (xy 127.041849 -277.270764)
			(xy 127.083865 -277.240238) (xy 127.130139 -277.21666) (xy 127.179532 -277.200612) (xy 127.230827 -277.192487)
			(xy 127.282761 -277.192487) (xy 127.334056 -277.200612) (xy 127.383449 -277.21666) (xy 127.429723 -277.240238)
			(xy 127.471739 -277.270764) (xy 127.508462 -277.307487) (xy 127.538988 -277.349503) (xy 127.562566 -277.395777)
			(xy 127.578614 -277.44517) (xy 127.586739 -277.496465) (xy 127.587248 -277.522432) (xy 127.586739 -277.548399)
			(xy 127.866649 -277.548399) (xy 127.866649 -277.496465) (xy 127.874774 -277.44517) (xy 127.890822 -277.395777)
			(xy 127.9144 -277.349503) (xy 127.944926 -277.307487) (xy 127.981649 -277.270764) (xy 128.023665 -277.240238)
			(xy 128.069939 -277.21666) (xy 128.119332 -277.200612) (xy 128.170627 -277.192487) (xy 128.222561 -277.192487)
			(xy 128.273856 -277.200612) (xy 128.323249 -277.21666) (xy 128.369523 -277.240238) (xy 128.411539 -277.270764)
			(xy 128.448262 -277.307487) (xy 128.478788 -277.349503) (xy 128.502366 -277.395777) (xy 128.518414 -277.44517)
			(xy 128.526539 -277.496465) (xy 128.527048 -277.522432) (xy 128.526539 -277.548399) (xy 128.518414 -277.599694)
			(xy 128.502366 -277.649087) (xy 128.478788 -277.695361) (xy 128.448262 -277.737377) (xy 128.411539 -277.7741)
			(xy 128.369523 -277.804626) (xy 128.323249 -277.828204) (xy 128.273856 -277.844252) (xy 128.222561 -277.852377)
			(xy 128.170627 -277.852377) (xy 128.119332 -277.844252) (xy 128.069939 -277.828204) (xy 128.023665 -277.804626)
			(xy 127.981649 -277.7741) (xy 127.944926 -277.737377) (xy 127.9144 -277.695361) (xy 127.890822 -277.649087)
			(xy 127.874774 -277.599694) (xy 127.866649 -277.548399) (xy 127.586739 -277.548399) (xy 127.578614 -277.599694)
			(xy 127.562566 -277.649087) (xy 127.538988 -277.695361) (xy 127.508462 -277.737377) (xy 127.471739 -277.7741)
			(xy 127.429723 -277.804626) (xy 127.383449 -277.828204) (xy 127.334056 -277.844252) (xy 127.282761 -277.852377)
			(xy 127.230827 -277.852377) (xy 127.179532 -277.844252) (xy 127.130139 -277.828204) (xy 127.083865 -277.804626)
			(xy 127.041849 -277.7741) (xy 127.005126 -277.737377) (xy 126.9746 -277.695361) (xy 126.951022 -277.649087)
			(xy 126.934974 -277.599694) (xy 126.926849 -277.548399) (xy 126.646939 -277.548399) (xy 126.638814 -277.599694)
			(xy 126.622766 -277.649087) (xy 126.599188 -277.695361) (xy 126.568662 -277.737377) (xy 126.531939 -277.7741)
			(xy 126.489923 -277.804626) (xy 126.443649 -277.828204) (xy 126.394256 -277.844252) (xy 126.342961 -277.852377)
			(xy 126.291027 -277.852377) (xy 126.239732 -277.844252) (xy 126.190339 -277.828204) (xy 126.144065 -277.804626)
			(xy 126.102049 -277.7741) (xy 126.065326 -277.737377) (xy 126.0348 -277.695361) (xy 126.011222 -277.649087)
			(xy 125.995174 -277.599694) (xy 125.987049 -277.548399) (xy 125.707393 -277.548399) (xy 125.699268 -277.599694)
			(xy 125.68322 -277.649087) (xy 125.659642 -277.695361) (xy 125.629116 -277.737377) (xy 125.592393 -277.7741)
			(xy 125.550377 -277.804626) (xy 125.504103 -277.828204) (xy 125.45471 -277.844252) (xy 125.403415 -277.852377)
			(xy 125.351481 -277.852377) (xy 125.300186 -277.844252) (xy 125.250793 -277.828204) (xy 125.204519 -277.804626)
			(xy 125.162503 -277.7741) (xy 125.12578 -277.737377) (xy 125.095254 -277.695361) (xy 125.071676 -277.649087)
			(xy 125.055628 -277.599694) (xy 125.047503 -277.548399) (xy 124.767339 -277.548399) (xy 124.759214 -277.599694)
			(xy 124.743166 -277.649087) (xy 124.719588 -277.695361) (xy 124.689062 -277.737377) (xy 124.652339 -277.7741)
			(xy 124.610323 -277.804626) (xy 124.564049 -277.828204) (xy 124.514656 -277.844252) (xy 124.463361 -277.852377)
			(xy 124.411427 -277.852377) (xy 124.360132 -277.844252) (xy 124.310739 -277.828204) (xy 124.264465 -277.804626)
			(xy 124.222449 -277.7741) (xy 124.185726 -277.737377) (xy 124.1552 -277.695361) (xy 124.131622 -277.649087)
			(xy 124.115574 -277.599694) (xy 124.107449 -277.548399) (xy 123.827539 -277.548399) (xy 123.819414 -277.599694)
			(xy 123.803366 -277.649087) (xy 123.779788 -277.695361) (xy 123.749262 -277.737377) (xy 123.712539 -277.7741)
			(xy 123.670523 -277.804626) (xy 123.624249 -277.828204) (xy 123.574856 -277.844252) (xy 123.523561 -277.852377)
			(xy 123.471627 -277.852377) (xy 123.420332 -277.844252) (xy 123.370939 -277.828204) (xy 123.324665 -277.804626)
			(xy 123.282649 -277.7741) (xy 123.245926 -277.737377) (xy 123.2154 -277.695361) (xy 123.191822 -277.649087)
			(xy 123.175774 -277.599694) (xy 123.167649 -277.548399) (xy 122.887953 -277.548399) (xy 122.879868 -277.59944)
			(xy 122.86382 -277.648833) (xy 122.840242 -277.695107) (xy 122.809716 -277.737123) (xy 122.772993 -277.773846)
			(xy 122.730977 -277.804372) (xy 122.684703 -277.82795) (xy 122.63531 -277.843998) (xy 122.584015 -277.852123)
			(xy 122.532081 -277.852123) (xy 122.480786 -277.843998) (xy 122.431393 -277.82795) (xy 122.385119 -277.804372)
			(xy 122.343103 -277.773846) (xy 122.30638 -277.737123) (xy 122.275854 -277.695107) (xy 122.252276 -277.648833)
			(xy 122.236228 -277.59944) (xy 122.228103 -277.548145) (xy 121.948193 -277.548145) (xy 121.940068 -277.59944)
			(xy 121.92402 -277.648833) (xy 121.900442 -277.695107) (xy 121.869916 -277.737123) (xy 121.833193 -277.773846)
			(xy 121.791177 -277.804372) (xy 121.744903 -277.82795) (xy 121.69551 -277.843998) (xy 121.644215 -277.852123)
			(xy 121.592281 -277.852123) (xy 121.540986 -277.843998) (xy 121.491593 -277.82795) (xy 121.445319 -277.804372)
			(xy 121.403303 -277.773846) (xy 121.36658 -277.737123) (xy 121.336054 -277.695107) (xy 121.312476 -277.648833)
			(xy 121.296428 -277.59944) (xy 121.288303 -277.548145) (xy 121.008393 -277.548145) (xy 121.000268 -277.59944)
			(xy 120.98422 -277.648833) (xy 120.960642 -277.695107) (xy 120.930116 -277.737123) (xy 120.893393 -277.773846)
			(xy 120.851377 -277.804372) (xy 120.805103 -277.82795) (xy 120.75571 -277.843998) (xy 120.704415 -277.852123)
			(xy 120.652481 -277.852123) (xy 120.601186 -277.843998) (xy 120.551793 -277.82795) (xy 120.505519 -277.804372)
			(xy 120.463503 -277.773846) (xy 120.42678 -277.737123) (xy 120.396254 -277.695107) (xy 120.372676 -277.648833)
			(xy 120.356628 -277.59944) (xy 120.348503 -277.548145) (xy 120.068593 -277.548145) (xy 120.060468 -277.59944)
			(xy 120.04442 -277.648833) (xy 120.020842 -277.695107) (xy 119.990316 -277.737123) (xy 119.953593 -277.773846)
			(xy 119.911577 -277.804372) (xy 119.865303 -277.82795) (xy 119.81591 -277.843998) (xy 119.764615 -277.852123)
			(xy 119.712681 -277.852123) (xy 119.661386 -277.843998) (xy 119.611993 -277.82795) (xy 119.565719 -277.804372)
			(xy 119.523703 -277.773846) (xy 119.48698 -277.737123) (xy 119.456454 -277.695107) (xy 119.432876 -277.648833)
			(xy 119.416828 -277.59944) (xy 119.408703 -277.548145) (xy 119.128798 -277.548145) (xy 119.128793 -277.548399)
			(xy 119.120668 -277.599694) (xy 119.10462 -277.649087) (xy 119.081042 -277.695361) (xy 119.050516 -277.737377)
			(xy 119.013793 -277.7741) (xy 118.971777 -277.804626) (xy 118.925503 -277.828204) (xy 118.87611 -277.844252)
			(xy 118.824815 -277.852377) (xy 118.772881 -277.852377) (xy 118.721586 -277.844252) (xy 118.672193 -277.828204)
			(xy 118.625919 -277.804626) (xy 118.583903 -277.7741) (xy 118.54718 -277.737377) (xy 118.516654 -277.695361)
			(xy 118.493076 -277.649087) (xy 118.477028 -277.599694) (xy 118.468903 -277.548399) (xy 118.188953 -277.548399)
			(xy 118.180868 -277.59944) (xy 118.16482 -277.648833) (xy 118.141242 -277.695107) (xy 118.110716 -277.737123)
			(xy 118.073993 -277.773846) (xy 118.031977 -277.804372) (xy 117.985703 -277.82795) (xy 117.93631 -277.843998)
			(xy 117.885015 -277.852123) (xy 117.833081 -277.852123) (xy 117.781786 -277.843998) (xy 117.732393 -277.82795)
			(xy 117.686119 -277.804372) (xy 117.644103 -277.773846) (xy 117.60738 -277.737123) (xy 117.576854 -277.695107)
			(xy 117.553276 -277.648833) (xy 117.537228 -277.59944) (xy 117.529103 -277.548145) (xy 117.248944 -277.548145)
			(xy 117.248939 -277.548399) (xy 117.240814 -277.599694) (xy 117.224766 -277.649087) (xy 117.201188 -277.695361)
			(xy 117.170662 -277.737377) (xy 117.133939 -277.7741) (xy 117.091923 -277.804626) (xy 117.045649 -277.828204)
			(xy 116.996256 -277.844252) (xy 116.944961 -277.852377) (xy 116.893027 -277.852377) (xy 116.841732 -277.844252)
			(xy 116.792339 -277.828204) (xy 116.746065 -277.804626) (xy 116.704049 -277.7741) (xy 116.667326 -277.737377)
			(xy 116.6368 -277.695361) (xy 116.613222 -277.649087) (xy 116.597174 -277.599694) (xy 116.589049 -277.548399)
			(xy 116.309353 -277.548399) (xy 116.301268 -277.59944) (xy 116.28522 -277.648833) (xy 116.261642 -277.695107)
			(xy 116.231116 -277.737123) (xy 116.194393 -277.773846) (xy 116.152377 -277.804372) (xy 116.106103 -277.82795)
			(xy 116.05671 -277.843998) (xy 116.005415 -277.852123) (xy 115.953481 -277.852123) (xy 115.902186 -277.843998)
			(xy 115.852793 -277.82795) (xy 115.806519 -277.804372) (xy 115.764503 -277.773846) (xy 115.72778 -277.737123)
			(xy 115.697254 -277.695107) (xy 115.673676 -277.648833) (xy 115.657628 -277.59944) (xy 115.649503 -277.548145)
			(xy 115.369359 -277.548145) (xy 115.369357 -277.548236) (xy 115.361342 -277.599217) (xy 115.345497 -277.648332)
			(xy 115.322207 -277.694386) (xy 115.292038 -277.736257) (xy 115.255726 -277.772928) (xy 115.214153 -277.803506)
			(xy 115.16833 -277.827247) (xy 115.119373 -277.843573) (xy 115.094004 -277.848314) (xy 115.080351 -277.851053)
			(xy 115.055172 -277.862922) (xy 115.034133 -277.88115) (xy 115.018798 -277.904382) (xy 115.010306 -277.930892)
			(xy 115.009288 -277.95871) (xy 115.01582 -277.985769) (xy 115.029416 -278.010059) (xy 115.038886 -278.020272)
			(xy 115.126516 -278.107902) (xy 115.136335 -278.117154) (xy 115.15972 -278.13059) (xy 115.185808 -278.137428)
			(xy 115.212777 -278.13719) (xy 115.238741 -278.129892) (xy 115.261885 -278.116046) (xy 115.27155 -278.106632)
			(xy 115.29038 -278.087915) (xy 115.332906 -278.056133) (xy 115.379962 -278.031554) (xy 115.430342 -278.014807)
			(xy 115.482749 -278.006325) (xy 115.509294 -278.005794) (xy 115.535262 -278.006276) (xy 115.586559 -278.014401)
			(xy 115.635954 -278.030451) (xy 115.682229 -278.054031) (xy 115.724245 -278.08456) (xy 115.760967 -278.121287)
			(xy 115.791491 -278.163307) (xy 115.815065 -278.209585) (xy 115.831109 -278.258982) (xy 115.839227 -278.31028)
			(xy 115.839748 -278.336248) (xy 115.839236 -278.362215) (xy 116.119149 -278.362215) (xy 116.119149 -278.310281)
			(xy 116.127274 -278.258986) (xy 116.143322 -278.209593) (xy 116.1669 -278.163319) (xy 116.197426 -278.121303)
			(xy 116.234149 -278.08458) (xy 116.276165 -278.054054) (xy 116.322439 -278.030476) (xy 116.371832 -278.014428)
			(xy 116.423127 -278.006303) (xy 116.475061 -278.006303) (xy 116.526356 -278.014428) (xy 116.575749 -278.030476)
			(xy 116.622023 -278.054054) (xy 116.664039 -278.08458) (xy 116.700762 -278.121303) (xy 116.731288 -278.163319)
			(xy 116.754866 -278.209593) (xy 116.770914 -278.258986) (xy 116.779039 -278.310281) (xy 116.779548 -278.336248)
			(xy 116.779039 -278.362215) (xy 117.058949 -278.362215) (xy 117.058949 -278.310281) (xy 117.067074 -278.258986)
			(xy 117.083122 -278.209593) (xy 117.1067 -278.163319) (xy 117.137226 -278.121303) (xy 117.173949 -278.08458)
			(xy 117.215965 -278.054054) (xy 117.262239 -278.030476) (xy 117.311632 -278.014428) (xy 117.362927 -278.006303)
			(xy 117.414861 -278.006303) (xy 117.466156 -278.014428) (xy 117.515549 -278.030476) (xy 117.561823 -278.054054)
			(xy 117.603839 -278.08458) (xy 117.640562 -278.121303) (xy 117.671088 -278.163319) (xy 117.694666 -278.209593)
			(xy 117.710714 -278.258986) (xy 117.718839 -278.310281) (xy 117.719348 -278.336248) (xy 117.718839 -278.362215)
			(xy 117.998749 -278.362215) (xy 117.998749 -278.310281) (xy 118.006874 -278.258986) (xy 118.022922 -278.209593)
			(xy 118.0465 -278.163319) (xy 118.077026 -278.121303) (xy 118.113749 -278.08458) (xy 118.155765 -278.054054)
			(xy 118.202039 -278.030476) (xy 118.251432 -278.014428) (xy 118.302727 -278.006303) (xy 118.354661 -278.006303)
			(xy 118.405956 -278.014428) (xy 118.455349 -278.030476) (xy 118.501623 -278.054054) (xy 118.543639 -278.08458)
			(xy 118.580362 -278.121303) (xy 118.610888 -278.163319) (xy 118.634466 -278.209593) (xy 118.650514 -278.258986)
			(xy 118.658639 -278.310281) (xy 118.659148 -278.336248) (xy 118.658639 -278.362215) (xy 118.658599 -278.362469)
			(xy 118.938803 -278.362469) (xy 118.938803 -278.310535) (xy 118.946928 -278.25924) (xy 118.962976 -278.209847)
			(xy 118.986554 -278.163573) (xy 119.01708 -278.121557) (xy 119.053803 -278.084834) (xy 119.095819 -278.054308)
			(xy 119.142093 -278.03073) (xy 119.191486 -278.014682) (xy 119.242781 -278.006557) (xy 119.294715 -278.006557)
			(xy 119.34601 -278.014682) (xy 119.395403 -278.03073) (xy 119.441677 -278.054308) (xy 119.483693 -278.084834)
			(xy 119.520416 -278.121557) (xy 119.550942 -278.163573) (xy 119.57452 -278.209847) (xy 119.590568 -278.25924)
			(xy 119.598693 -278.310535) (xy 119.599202 -278.336502) (xy 119.598698 -278.362215) (xy 120.818149 -278.362215)
			(xy 120.818149 -278.310281) (xy 120.826274 -278.258986) (xy 120.842322 -278.209593) (xy 120.8659 -278.163319)
			(xy 120.896426 -278.121303) (xy 120.933149 -278.08458) (xy 120.975165 -278.054054) (xy 121.021439 -278.030476)
			(xy 121.070832 -278.014428) (xy 121.122127 -278.006303) (xy 121.174061 -278.006303) (xy 121.225356 -278.014428)
			(xy 121.274749 -278.030476) (xy 121.321023 -278.054054) (xy 121.363039 -278.08458) (xy 121.399762 -278.121303)
			(xy 121.430288 -278.163319) (xy 121.453866 -278.209593) (xy 121.469914 -278.258986) (xy 121.478039 -278.310281)
			(xy 121.478548 -278.336248) (xy 121.478039 -278.362215) (xy 121.477999 -278.362469) (xy 121.757949 -278.362469)
			(xy 121.757949 -278.310535) (xy 121.766074 -278.25924) (xy 121.782122 -278.209847) (xy 121.8057 -278.163573)
			(xy 121.836226 -278.121557) (xy 121.872949 -278.084834) (xy 121.914965 -278.054308) (xy 121.961239 -278.03073)
			(xy 122.010632 -278.014682) (xy 122.061927 -278.006557) (xy 122.113861 -278.006557) (xy 122.165156 -278.014682)
			(xy 122.214549 -278.03073) (xy 122.260823 -278.054308) (xy 122.302839 -278.084834) (xy 122.339562 -278.121557)
			(xy 122.370088 -278.163573) (xy 122.393666 -278.209847) (xy 122.409714 -278.25924) (xy 122.417839 -278.310535)
			(xy 122.418348 -278.336502) (xy 122.417839 -278.362469) (xy 122.698003 -278.362469) (xy 122.698003 -278.310535)
			(xy 122.706128 -278.25924) (xy 122.722176 -278.209847) (xy 122.745754 -278.163573) (xy 122.77628 -278.121557)
			(xy 122.813003 -278.084834) (xy 122.855019 -278.054308) (xy 122.901293 -278.03073) (xy 122.950686 -278.014682)
			(xy 123.001981 -278.006557) (xy 123.053915 -278.006557) (xy 123.10521 -278.014682) (xy 123.154603 -278.03073)
			(xy 123.200877 -278.054308) (xy 123.242893 -278.084834) (xy 123.279616 -278.121557) (xy 123.310142 -278.163573)
			(xy 123.33372 -278.209847) (xy 123.349768 -278.25924) (xy 123.357893 -278.310535) (xy 123.358402 -278.336502)
			(xy 123.357893 -278.362469) (xy 124.577603 -278.362469) (xy 124.577603 -278.310535) (xy 124.585728 -278.25924)
			(xy 124.601776 -278.209847) (xy 124.625354 -278.163573) (xy 124.65588 -278.121557) (xy 124.692603 -278.084834)
			(xy 124.734619 -278.054308) (xy 124.780893 -278.03073) (xy 124.830286 -278.014682) (xy 124.881581 -278.006557)
			(xy 124.933515 -278.006557) (xy 124.98481 -278.014682) (xy 125.034203 -278.03073) (xy 125.080477 -278.054308)
			(xy 125.122493 -278.084834) (xy 125.159216 -278.121557) (xy 125.189742 -278.163573) (xy 125.21332 -278.209847)
			(xy 125.229368 -278.25924) (xy 125.237493 -278.310535) (xy 125.238002 -278.336502) (xy 125.237493 -278.362469)
			(xy 125.517403 -278.362469) (xy 125.517403 -278.310535) (xy 125.525528 -278.25924) (xy 125.541576 -278.209847)
			(xy 125.565154 -278.163573) (xy 125.59568 -278.121557) (xy 125.632403 -278.084834) (xy 125.674419 -278.054308)
			(xy 125.720693 -278.03073) (xy 125.770086 -278.014682) (xy 125.821381 -278.006557) (xy 125.873315 -278.006557)
			(xy 125.92461 -278.014682) (xy 125.974003 -278.03073) (xy 126.020277 -278.054308) (xy 126.062293 -278.084834)
			(xy 126.099016 -278.121557) (xy 126.129542 -278.163573) (xy 126.15312 -278.209847) (xy 126.169168 -278.25924)
			(xy 126.177293 -278.310535) (xy 126.177802 -278.336502) (xy 126.177293 -278.362469) (xy 126.457203 -278.362469)
			(xy 126.457203 -278.310535) (xy 126.465328 -278.25924) (xy 126.481376 -278.209847) (xy 126.504954 -278.163573)
			(xy 126.53548 -278.121557) (xy 126.572203 -278.084834) (xy 126.614219 -278.054308) (xy 126.660493 -278.03073)
			(xy 126.709886 -278.014682) (xy 126.761181 -278.006557) (xy 126.813115 -278.006557) (xy 126.86441 -278.014682)
			(xy 126.913803 -278.03073) (xy 126.960077 -278.054308) (xy 127.002093 -278.084834) (xy 127.038816 -278.121557)
			(xy 127.069342 -278.163573) (xy 127.09292 -278.209847) (xy 127.108968 -278.25924) (xy 127.117093 -278.310535)
			(xy 127.117602 -278.336502) (xy 127.117093 -278.362469) (xy 127.397003 -278.362469) (xy 127.397003 -278.310535)
			(xy 127.405128 -278.25924) (xy 127.421176 -278.209847) (xy 127.444754 -278.163573) (xy 127.47528 -278.121557)
			(xy 127.512003 -278.084834) (xy 127.554019 -278.054308) (xy 127.600293 -278.03073) (xy 127.649686 -278.014682)
			(xy 127.700981 -278.006557) (xy 127.752915 -278.006557) (xy 127.80421 -278.014682) (xy 127.853603 -278.03073)
			(xy 127.899877 -278.054308) (xy 127.941893 -278.084834) (xy 127.978616 -278.121557) (xy 128.009142 -278.163573)
			(xy 128.03272 -278.209847) (xy 128.048768 -278.25924) (xy 128.056893 -278.310535) (xy 128.057402 -278.336502)
			(xy 128.056893 -278.362469) (xy 128.336549 -278.362469) (xy 128.336549 -278.310535) (xy 128.344674 -278.25924)
			(xy 128.360722 -278.209847) (xy 128.3843 -278.163573) (xy 128.414826 -278.121557) (xy 128.451549 -278.084834)
			(xy 128.493565 -278.054308) (xy 128.539839 -278.03073) (xy 128.589232 -278.014682) (xy 128.640527 -278.006557)
			(xy 128.692461 -278.006557) (xy 128.743756 -278.014682) (xy 128.793149 -278.03073) (xy 128.839423 -278.054308)
			(xy 128.881439 -278.084834) (xy 128.918162 -278.121557) (xy 128.948688 -278.163573) (xy 128.972266 -278.209847)
			(xy 128.988314 -278.25924) (xy 128.996439 -278.310535) (xy 128.996948 -278.336502) (xy 128.996439 -278.362469)
			(xy 129.276603 -278.362469) (xy 129.276603 -278.310535) (xy 129.284728 -278.25924) (xy 129.300776 -278.209847)
			(xy 129.324354 -278.163573) (xy 129.35488 -278.121557) (xy 129.391603 -278.084834) (xy 129.433619 -278.054308)
			(xy 129.479893 -278.03073) (xy 129.529286 -278.014682) (xy 129.580581 -278.006557) (xy 129.632515 -278.006557)
			(xy 129.68381 -278.014682) (xy 129.733203 -278.03073) (xy 129.779477 -278.054308) (xy 129.821493 -278.084834)
			(xy 129.858216 -278.121557) (xy 129.888742 -278.163573) (xy 129.91232 -278.209847) (xy 129.928368 -278.25924)
			(xy 129.936493 -278.310535) (xy 129.937002 -278.336502) (xy 129.936493 -278.362469) (xy 129.928368 -278.413764)
			(xy 129.91232 -278.463157) (xy 129.888742 -278.509431) (xy 129.858216 -278.551447) (xy 129.821493 -278.58817)
			(xy 129.779477 -278.618696) (xy 129.733203 -278.642274) (xy 129.68381 -278.658322) (xy 129.632515 -278.666447)
			(xy 129.580581 -278.666447) (xy 129.529286 -278.658322) (xy 129.479893 -278.642274) (xy 129.433619 -278.618696)
			(xy 129.391603 -278.58817) (xy 129.35488 -278.551447) (xy 129.324354 -278.509431) (xy 129.300776 -278.463157)
			(xy 129.284728 -278.413764) (xy 129.276603 -278.362469) (xy 128.996439 -278.362469) (xy 128.988314 -278.413764)
			(xy 128.972266 -278.463157) (xy 128.948688 -278.509431) (xy 128.918162 -278.551447) (xy 128.881439 -278.58817)
			(xy 128.839423 -278.618696) (xy 128.793149 -278.642274) (xy 128.743756 -278.658322) (xy 128.692461 -278.666447)
			(xy 128.640527 -278.666447) (xy 128.589232 -278.658322) (xy 128.539839 -278.642274) (xy 128.493565 -278.618696)
			(xy 128.451549 -278.58817) (xy 128.414826 -278.551447) (xy 128.3843 -278.509431) (xy 128.360722 -278.463157)
			(xy 128.344674 -278.413764) (xy 128.336549 -278.362469) (xy 128.056893 -278.362469) (xy 128.048768 -278.413764)
			(xy 128.03272 -278.463157) (xy 128.009142 -278.509431) (xy 127.978616 -278.551447) (xy 127.941893 -278.58817)
			(xy 127.899877 -278.618696) (xy 127.853603 -278.642274) (xy 127.80421 -278.658322) (xy 127.752915 -278.666447)
			(xy 127.700981 -278.666447) (xy 127.649686 -278.658322) (xy 127.600293 -278.642274) (xy 127.554019 -278.618696)
			(xy 127.512003 -278.58817) (xy 127.47528 -278.551447) (xy 127.444754 -278.509431) (xy 127.421176 -278.463157)
			(xy 127.405128 -278.413764) (xy 127.397003 -278.362469) (xy 127.117093 -278.362469) (xy 127.108968 -278.413764)
			(xy 127.09292 -278.463157) (xy 127.069342 -278.509431) (xy 127.038816 -278.551447) (xy 127.002093 -278.58817)
			(xy 126.960077 -278.618696) (xy 126.913803 -278.642274) (xy 126.86441 -278.658322) (xy 126.813115 -278.666447)
			(xy 126.761181 -278.666447) (xy 126.709886 -278.658322) (xy 126.660493 -278.642274) (xy 126.614219 -278.618696)
			(xy 126.572203 -278.58817) (xy 126.53548 -278.551447) (xy 126.504954 -278.509431) (xy 126.481376 -278.463157)
			(xy 126.465328 -278.413764) (xy 126.457203 -278.362469) (xy 126.177293 -278.362469) (xy 126.169168 -278.413764)
			(xy 126.15312 -278.463157) (xy 126.129542 -278.509431) (xy 126.099016 -278.551447) (xy 126.062293 -278.58817)
			(xy 126.020277 -278.618696) (xy 125.974003 -278.642274) (xy 125.92461 -278.658322) (xy 125.873315 -278.666447)
			(xy 125.821381 -278.666447) (xy 125.770086 -278.658322) (xy 125.720693 -278.642274) (xy 125.674419 -278.618696)
			(xy 125.632403 -278.58817) (xy 125.59568 -278.551447) (xy 125.565154 -278.509431) (xy 125.541576 -278.463157)
			(xy 125.525528 -278.413764) (xy 125.517403 -278.362469) (xy 125.237493 -278.362469) (xy 125.229368 -278.413764)
			(xy 125.21332 -278.463157) (xy 125.189742 -278.509431) (xy 125.159216 -278.551447) (xy 125.122493 -278.58817)
			(xy 125.080477 -278.618696) (xy 125.034203 -278.642274) (xy 124.98481 -278.658322) (xy 124.933515 -278.666447)
			(xy 124.881581 -278.666447) (xy 124.830286 -278.658322) (xy 124.780893 -278.642274) (xy 124.734619 -278.618696)
			(xy 124.692603 -278.58817) (xy 124.65588 -278.551447) (xy 124.625354 -278.509431) (xy 124.601776 -278.463157)
			(xy 124.585728 -278.413764) (xy 124.577603 -278.362469) (xy 123.357893 -278.362469) (xy 123.349768 -278.413764)
			(xy 123.33372 -278.463157) (xy 123.310142 -278.509431) (xy 123.279616 -278.551447) (xy 123.242893 -278.58817)
			(xy 123.200877 -278.618696) (xy 123.154603 -278.642274) (xy 123.10521 -278.658322) (xy 123.053915 -278.666447)
			(xy 123.001981 -278.666447) (xy 122.950686 -278.658322) (xy 122.901293 -278.642274) (xy 122.855019 -278.618696)
			(xy 122.813003 -278.58817) (xy 122.77628 -278.551447) (xy 122.745754 -278.509431) (xy 122.722176 -278.463157)
			(xy 122.706128 -278.413764) (xy 122.698003 -278.362469) (xy 122.417839 -278.362469) (xy 122.409714 -278.413764)
			(xy 122.393666 -278.463157) (xy 122.370088 -278.509431) (xy 122.339562 -278.551447) (xy 122.302839 -278.58817)
			(xy 122.260823 -278.618696) (xy 122.214549 -278.642274) (xy 122.165156 -278.658322) (xy 122.113861 -278.666447)
			(xy 122.061927 -278.666447) (xy 122.010632 -278.658322) (xy 121.961239 -278.642274) (xy 121.914965 -278.618696)
			(xy 121.872949 -278.58817) (xy 121.836226 -278.551447) (xy 121.8057 -278.509431) (xy 121.782122 -278.463157)
			(xy 121.766074 -278.413764) (xy 121.757949 -278.362469) (xy 121.477999 -278.362469) (xy 121.469914 -278.41351)
			(xy 121.453866 -278.462903) (xy 121.430288 -278.509177) (xy 121.399762 -278.551193) (xy 121.363039 -278.587916)
			(xy 121.321023 -278.618442) (xy 121.274749 -278.64202) (xy 121.225356 -278.658068) (xy 121.174061 -278.666193)
			(xy 121.122127 -278.666193) (xy 121.070832 -278.658068) (xy 121.021439 -278.64202) (xy 120.975165 -278.618442)
			(xy 120.933149 -278.587916) (xy 120.896426 -278.551193) (xy 120.8659 -278.509177) (xy 120.842322 -278.462903)
			(xy 120.826274 -278.41351) (xy 120.818149 -278.362215) (xy 119.598698 -278.362215) (xy 119.598693 -278.362469)
			(xy 119.590568 -278.413764) (xy 119.57452 -278.463157) (xy 119.550942 -278.509431) (xy 119.520416 -278.551447)
			(xy 119.483693 -278.58817) (xy 119.441677 -278.618696) (xy 119.395403 -278.642274) (xy 119.34601 -278.658322)
			(xy 119.294715 -278.666447) (xy 119.242781 -278.666447) (xy 119.191486 -278.658322) (xy 119.142093 -278.642274)
			(xy 119.095819 -278.618696) (xy 119.053803 -278.58817) (xy 119.01708 -278.551447) (xy 118.986554 -278.509431)
			(xy 118.962976 -278.463157) (xy 118.946928 -278.413764) (xy 118.938803 -278.362469) (xy 118.658599 -278.362469)
			(xy 118.650514 -278.41351) (xy 118.634466 -278.462903) (xy 118.610888 -278.509177) (xy 118.580362 -278.551193)
			(xy 118.543639 -278.587916) (xy 118.501623 -278.618442) (xy 118.455349 -278.64202) (xy 118.405956 -278.658068)
			(xy 118.354661 -278.666193) (xy 118.302727 -278.666193) (xy 118.251432 -278.658068) (xy 118.202039 -278.64202)
			(xy 118.155765 -278.618442) (xy 118.113749 -278.587916) (xy 118.077026 -278.551193) (xy 118.0465 -278.509177)
			(xy 118.022922 -278.462903) (xy 118.006874 -278.41351) (xy 117.998749 -278.362215) (xy 117.718839 -278.362215)
			(xy 117.710714 -278.41351) (xy 117.694666 -278.462903) (xy 117.671088 -278.509177) (xy 117.640562 -278.551193)
			(xy 117.603839 -278.587916) (xy 117.561823 -278.618442) (xy 117.515549 -278.64202) (xy 117.466156 -278.658068)
			(xy 117.414861 -278.666193) (xy 117.362927 -278.666193) (xy 117.311632 -278.658068) (xy 117.262239 -278.64202)
			(xy 117.215965 -278.618442) (xy 117.173949 -278.587916) (xy 117.137226 -278.551193) (xy 117.1067 -278.509177)
			(xy 117.083122 -278.462903) (xy 117.067074 -278.41351) (xy 117.058949 -278.362215) (xy 116.779039 -278.362215)
			(xy 116.770914 -278.41351) (xy 116.754866 -278.462903) (xy 116.731288 -278.509177) (xy 116.700762 -278.551193)
			(xy 116.664039 -278.587916) (xy 116.622023 -278.618442) (xy 116.575749 -278.64202) (xy 116.526356 -278.658068)
			(xy 116.475061 -278.666193) (xy 116.423127 -278.666193) (xy 116.371832 -278.658068) (xy 116.322439 -278.64202)
			(xy 116.276165 -278.618442) (xy 116.234149 -278.587916) (xy 116.197426 -278.551193) (xy 116.1669 -278.509177)
			(xy 116.143322 -278.462903) (xy 116.127274 -278.41351) (xy 116.119149 -278.362215) (xy 115.839236 -278.362215)
			(xy 115.839225 -278.362794) (xy 115.830749 -278.415206) (xy 115.814007 -278.46559) (xy 115.789429 -278.512651)
			(xy 115.757647 -278.55518) (xy 115.73891 -278.573992) (xy 115.729479 -278.583642) (xy 115.715622 -278.606784)
			(xy 115.708322 -278.63275) (xy 115.708091 -278.659723) (xy 115.714946 -278.685811) (xy 115.728406 -278.709186)
			(xy 115.73764 -278.719026) (xy 115.85956 -278.840946) (xy 115.888262 -278.832564) (xy 115.910525 -278.826628)
			(xy 115.956157 -278.820255) (xy 115.979194 -278.819864) (xy 116.005163 -278.820346) (xy 116.056462 -278.828471)
			(xy 116.105858 -278.84452) (xy 116.152135 -278.8681) (xy 116.194154 -278.898629) (xy 116.230879 -278.935355)
			(xy 116.261406 -278.977375) (xy 116.284984 -279.023653) (xy 116.301032 -279.07305) (xy 116.309155 -279.124349)
			(xy 116.309648 -279.150318) (xy 116.309284 -279.173357) (xy 116.30891 -279.176031) (xy 116.589303 -279.176031)
			(xy 116.589303 -279.124097) (xy 116.597428 -279.072802) (xy 116.613476 -279.023409) (xy 116.637054 -278.977135)
			(xy 116.66758 -278.935119) (xy 116.704303 -278.898396) (xy 116.746319 -278.86787) (xy 116.792593 -278.844292)
			(xy 116.841986 -278.828244) (xy 116.893281 -278.820119) (xy 116.945215 -278.820119) (xy 116.99651 -278.828244)
			(xy 117.045903 -278.844292) (xy 117.092177 -278.86787) (xy 117.134193 -278.898396) (xy 117.170916 -278.935119)
			(xy 117.201442 -278.977135) (xy 117.22502 -279.023409) (xy 117.241068 -279.072802) (xy 117.249193 -279.124097)
			(xy 117.249702 -279.150064) (xy 117.249193 -279.176031) (xy 117.249153 -279.176285) (xy 117.529103 -279.176285)
			(xy 117.529103 -279.124351) (xy 117.537228 -279.073056) (xy 117.553276 -279.023663) (xy 117.576854 -278.977389)
			(xy 117.60738 -278.935373) (xy 117.644103 -278.89865) (xy 117.686119 -278.868124) (xy 117.732393 -278.844546)
			(xy 117.781786 -278.828498) (xy 117.833081 -278.820373) (xy 117.885015 -278.820373) (xy 117.93631 -278.828498)
			(xy 117.985703 -278.844546) (xy 118.031977 -278.868124) (xy 118.073993 -278.89865) (xy 118.110716 -278.935373)
			(xy 118.141242 -278.977389) (xy 118.16482 -279.023663) (xy 118.180868 -279.073056) (xy 118.188993 -279.124351)
			(xy 118.189502 -279.150318) (xy 118.188993 -279.176285) (xy 119.408449 -279.176285) (xy 119.408449 -279.124351)
			(xy 119.416574 -279.073056) (xy 119.432622 -279.023663) (xy 119.4562 -278.977389) (xy 119.486726 -278.935373)
			(xy 119.523449 -278.89865) (xy 119.565465 -278.868124) (xy 119.611739 -278.844546) (xy 119.661132 -278.828498)
			(xy 119.712427 -278.820373) (xy 119.764361 -278.820373) (xy 119.815656 -278.828498) (xy 119.865049 -278.844546)
			(xy 119.911323 -278.868124) (xy 119.953339 -278.89865) (xy 119.990062 -278.935373) (xy 120.020588 -278.977389)
			(xy 120.044166 -279.023663) (xy 120.060214 -279.073056) (xy 120.068339 -279.124351) (xy 120.068848 -279.150318)
			(xy 120.068339 -279.176285) (xy 120.348503 -279.176285) (xy 120.348503 -279.124351) (xy 120.356628 -279.073056)
			(xy 120.372676 -279.023663) (xy 120.396254 -278.977389) (xy 120.42678 -278.935373) (xy 120.463503 -278.89865)
			(xy 120.505519 -278.868124) (xy 120.551793 -278.844546) (xy 120.601186 -278.828498) (xy 120.652481 -278.820373)
			(xy 120.704415 -278.820373) (xy 120.75571 -278.828498) (xy 120.805103 -278.844546) (xy 120.851377 -278.868124)
			(xy 120.893393 -278.89865) (xy 120.930116 -278.935373) (xy 120.960642 -278.977389) (xy 120.98422 -279.023663)
			(xy 121.000268 -279.073056) (xy 121.008393 -279.124351) (xy 121.008902 -279.150318) (xy 121.008393 -279.176285)
			(xy 121.288049 -279.176285) (xy 121.288049 -279.124351) (xy 121.296174 -279.073056) (xy 121.312222 -279.023663)
			(xy 121.3358 -278.977389) (xy 121.366326 -278.935373) (xy 121.403049 -278.89865) (xy 121.445065 -278.868124)
			(xy 121.491339 -278.844546) (xy 121.540732 -278.828498) (xy 121.592027 -278.820373) (xy 121.643961 -278.820373)
			(xy 121.695256 -278.828498) (xy 121.744649 -278.844546) (xy 121.790923 -278.868124) (xy 121.832939 -278.89865)
			(xy 121.869662 -278.935373) (xy 121.900188 -278.977389) (xy 121.923766 -279.023663) (xy 121.939814 -279.073056)
			(xy 121.947939 -279.124351) (xy 121.948448 -279.150318) (xy 121.947939 -279.176285) (xy 122.227849 -279.176285)
			(xy 122.227849 -279.124351) (xy 122.235974 -279.073056) (xy 122.252022 -279.023663) (xy 122.2756 -278.977389)
			(xy 122.306126 -278.935373) (xy 122.342849 -278.89865) (xy 122.384865 -278.868124) (xy 122.431139 -278.844546)
			(xy 122.480532 -278.828498) (xy 122.531827 -278.820373) (xy 122.583761 -278.820373) (xy 122.635056 -278.828498)
			(xy 122.684449 -278.844546) (xy 122.730723 -278.868124) (xy 122.772739 -278.89865) (xy 122.809462 -278.935373)
			(xy 122.839988 -278.977389) (xy 122.863566 -279.023663) (xy 122.879614 -279.073056) (xy 122.887739 -279.124351)
			(xy 122.888248 -279.150318) (xy 122.887739 -279.176285) (xy 123.167903 -279.176285) (xy 123.167903 -279.124351)
			(xy 123.176028 -279.073056) (xy 123.192076 -279.023663) (xy 123.215654 -278.977389) (xy 123.24618 -278.935373)
			(xy 123.282903 -278.89865) (xy 123.324919 -278.868124) (xy 123.371193 -278.844546) (xy 123.420586 -278.828498)
			(xy 123.471881 -278.820373) (xy 123.523815 -278.820373) (xy 123.57511 -278.828498) (xy 123.624503 -278.844546)
			(xy 123.670777 -278.868124) (xy 123.712793 -278.89865) (xy 123.749516 -278.935373) (xy 123.780042 -278.977389)
			(xy 123.80362 -279.023663) (xy 123.819668 -279.073056) (xy 123.827793 -279.124351) (xy 123.828302 -279.150318)
			(xy 123.827793 -279.176285) (xy 124.107449 -279.176285) (xy 124.107449 -279.124351) (xy 124.115574 -279.073056)
			(xy 124.131622 -279.023663) (xy 124.1552 -278.977389) (xy 124.185726 -278.935373) (xy 124.222449 -278.89865)
			(xy 124.264465 -278.868124) (xy 124.310739 -278.844546) (xy 124.360132 -278.828498) (xy 124.411427 -278.820373)
			(xy 124.463361 -278.820373) (xy 124.514656 -278.828498) (xy 124.564049 -278.844546) (xy 124.610323 -278.868124)
			(xy 124.652339 -278.89865) (xy 124.689062 -278.935373) (xy 124.719588 -278.977389) (xy 124.743166 -279.023663)
			(xy 124.759214 -279.073056) (xy 124.767339 -279.124351) (xy 124.767848 -279.150318) (xy 124.767339 -279.176285)
			(xy 125.047249 -279.176285) (xy 125.047249 -279.124351) (xy 125.055374 -279.073056) (xy 125.071422 -279.023663)
			(xy 125.095 -278.977389) (xy 125.125526 -278.935373) (xy 125.162249 -278.89865) (xy 125.204265 -278.868124)
			(xy 125.250539 -278.844546) (xy 125.299932 -278.828498) (xy 125.351227 -278.820373) (xy 125.403161 -278.820373)
			(xy 125.454456 -278.828498) (xy 125.503849 -278.844546) (xy 125.550123 -278.868124) (xy 125.592139 -278.89865)
			(xy 125.628862 -278.935373) (xy 125.659388 -278.977389) (xy 125.682966 -279.023663) (xy 125.699014 -279.073056)
			(xy 125.707139 -279.124351) (xy 125.707648 -279.150318) (xy 125.707139 -279.176285) (xy 125.987049 -279.176285)
			(xy 125.987049 -279.124351) (xy 125.995174 -279.073056) (xy 126.011222 -279.023663) (xy 126.0348 -278.977389)
			(xy 126.065326 -278.935373) (xy 126.102049 -278.89865) (xy 126.144065 -278.868124) (xy 126.190339 -278.844546)
			(xy 126.239732 -278.828498) (xy 126.291027 -278.820373) (xy 126.342961 -278.820373) (xy 126.394256 -278.828498)
			(xy 126.443649 -278.844546) (xy 126.489923 -278.868124) (xy 126.531939 -278.89865) (xy 126.568662 -278.935373)
			(xy 126.599188 -278.977389) (xy 126.622766 -279.023663) (xy 126.638814 -279.073056) (xy 126.646939 -279.124351)
			(xy 126.647448 -279.150318) (xy 126.646939 -279.176285) (xy 126.926849 -279.176285) (xy 126.926849 -279.124351)
			(xy 126.934974 -279.073056) (xy 126.951022 -279.023663) (xy 126.9746 -278.977389) (xy 127.005126 -278.935373)
			(xy 127.041849 -278.89865) (xy 127.083865 -278.868124) (xy 127.130139 -278.844546) (xy 127.179532 -278.828498)
			(xy 127.230827 -278.820373) (xy 127.282761 -278.820373) (xy 127.334056 -278.828498) (xy 127.383449 -278.844546)
			(xy 127.429723 -278.868124) (xy 127.471739 -278.89865) (xy 127.508462 -278.935373) (xy 127.538988 -278.977389)
			(xy 127.562566 -279.023663) (xy 127.578614 -279.073056) (xy 127.586739 -279.124351) (xy 127.587248 -279.150318)
			(xy 127.586739 -279.176285) (xy 127.866649 -279.176285) (xy 127.866649 -279.124351) (xy 127.874774 -279.073056)
			(xy 127.890822 -279.023663) (xy 127.9144 -278.977389) (xy 127.944926 -278.935373) (xy 127.981649 -278.89865)
			(xy 128.023665 -278.868124) (xy 128.069939 -278.844546) (xy 128.119332 -278.828498) (xy 128.170627 -278.820373)
			(xy 128.222561 -278.820373) (xy 128.273856 -278.828498) (xy 128.323249 -278.844546) (xy 128.369523 -278.868124)
			(xy 128.411539 -278.89865) (xy 128.448262 -278.935373) (xy 128.478788 -278.977389) (xy 128.502366 -279.023663)
			(xy 128.518414 -279.073056) (xy 128.526539 -279.124351) (xy 128.527048 -279.150318) (xy 128.526539 -279.176285)
			(xy 128.806449 -279.176285) (xy 128.806449 -279.124351) (xy 128.814574 -279.073056) (xy 128.830622 -279.023663)
			(xy 128.8542 -278.977389) (xy 128.884726 -278.935373) (xy 128.921449 -278.89865) (xy 128.963465 -278.868124)
			(xy 129.009739 -278.844546) (xy 129.059132 -278.828498) (xy 129.110427 -278.820373) (xy 129.162361 -278.820373)
			(xy 129.213656 -278.828498) (xy 129.263049 -278.844546) (xy 129.309323 -278.868124) (xy 129.351339 -278.89865)
			(xy 129.388062 -278.935373) (xy 129.418588 -278.977389) (xy 129.442166 -279.023663) (xy 129.458214 -279.073056)
			(xy 129.466339 -279.124351) (xy 129.466848 -279.150318) (xy 129.466339 -279.176285) (xy 129.746503 -279.176285)
			(xy 129.746503 -279.124351) (xy 129.754628 -279.073056) (xy 129.770676 -279.023663) (xy 129.794254 -278.977389)
			(xy 129.82478 -278.935373) (xy 129.861503 -278.89865) (xy 129.903519 -278.868124) (xy 129.949793 -278.844546)
			(xy 129.999186 -278.828498) (xy 130.050481 -278.820373) (xy 130.102415 -278.820373) (xy 130.15371 -278.828498)
			(xy 130.203103 -278.844546) (xy 130.249377 -278.868124) (xy 130.291393 -278.89865) (xy 130.328116 -278.935373)
			(xy 130.358642 -278.977389) (xy 130.38222 -279.023663) (xy 130.398268 -279.073056) (xy 130.406393 -279.124351)
			(xy 130.406902 -279.150318) (xy 130.406393 -279.176285) (xy 130.398268 -279.22758) (xy 130.38222 -279.276973)
			(xy 130.358642 -279.323247) (xy 130.328116 -279.365263) (xy 130.291393 -279.401986) (xy 130.249377 -279.432512)
			(xy 130.203103 -279.45609) (xy 130.15371 -279.472138) (xy 130.102415 -279.480263) (xy 130.050481 -279.480263)
			(xy 129.999186 -279.472138) (xy 129.949793 -279.45609) (xy 129.903519 -279.432512) (xy 129.861503 -279.401986)
			(xy 129.82478 -279.365263) (xy 129.794254 -279.323247) (xy 129.770676 -279.276973) (xy 129.754628 -279.22758)
			(xy 129.746503 -279.176285) (xy 129.466339 -279.176285) (xy 129.458214 -279.22758) (xy 129.442166 -279.276973)
			(xy 129.418588 -279.323247) (xy 129.388062 -279.365263) (xy 129.351339 -279.401986) (xy 129.309323 -279.432512)
			(xy 129.263049 -279.45609) (xy 129.213656 -279.472138) (xy 129.162361 -279.480263) (xy 129.110427 -279.480263)
			(xy 129.059132 -279.472138) (xy 129.009739 -279.45609) (xy 128.963465 -279.432512) (xy 128.921449 -279.401986)
			(xy 128.884726 -279.365263) (xy 128.8542 -279.323247) (xy 128.830622 -279.276973) (xy 128.814574 -279.22758)
			(xy 128.806449 -279.176285) (xy 128.526539 -279.176285) (xy 128.518414 -279.22758) (xy 128.502366 -279.276973)
			(xy 128.478788 -279.323247) (xy 128.448262 -279.365263) (xy 128.411539 -279.401986) (xy 128.369523 -279.432512)
			(xy 128.323249 -279.45609) (xy 128.273856 -279.472138) (xy 128.222561 -279.480263) (xy 128.170627 -279.480263)
			(xy 128.119332 -279.472138) (xy 128.069939 -279.45609) (xy 128.023665 -279.432512) (xy 127.981649 -279.401986)
			(xy 127.944926 -279.365263) (xy 127.9144 -279.323247) (xy 127.890822 -279.276973) (xy 127.874774 -279.22758)
			(xy 127.866649 -279.176285) (xy 127.586739 -279.176285) (xy 127.578614 -279.22758) (xy 127.562566 -279.276973)
			(xy 127.538988 -279.323247) (xy 127.508462 -279.365263) (xy 127.471739 -279.401986) (xy 127.429723 -279.432512)
			(xy 127.383449 -279.45609) (xy 127.334056 -279.472138) (xy 127.282761 -279.480263) (xy 127.230827 -279.480263)
			(xy 127.179532 -279.472138) (xy 127.130139 -279.45609) (xy 127.083865 -279.432512) (xy 127.041849 -279.401986)
			(xy 127.005126 -279.365263) (xy 126.9746 -279.323247) (xy 126.951022 -279.276973) (xy 126.934974 -279.22758)
			(xy 126.926849 -279.176285) (xy 126.646939 -279.176285) (xy 126.638814 -279.22758) (xy 126.622766 -279.276973)
			(xy 126.599188 -279.323247) (xy 126.568662 -279.365263) (xy 126.531939 -279.401986) (xy 126.489923 -279.432512)
			(xy 126.443649 -279.45609) (xy 126.394256 -279.472138) (xy 126.342961 -279.480263) (xy 126.291027 -279.480263)
			(xy 126.239732 -279.472138) (xy 126.190339 -279.45609) (xy 126.144065 -279.432512) (xy 126.102049 -279.401986)
			(xy 126.065326 -279.365263) (xy 126.0348 -279.323247) (xy 126.011222 -279.276973) (xy 125.995174 -279.22758)
			(xy 125.987049 -279.176285) (xy 125.707139 -279.176285) (xy 125.699014 -279.22758) (xy 125.682966 -279.276973)
			(xy 125.659388 -279.323247) (xy 125.628862 -279.365263) (xy 125.592139 -279.401986) (xy 125.550123 -279.432512)
			(xy 125.503849 -279.45609) (xy 125.454456 -279.472138) (xy 125.403161 -279.480263) (xy 125.351227 -279.480263)
			(xy 125.299932 -279.472138) (xy 125.250539 -279.45609) (xy 125.204265 -279.432512) (xy 125.162249 -279.401986)
			(xy 125.125526 -279.365263) (xy 125.095 -279.323247) (xy 125.071422 -279.276973) (xy 125.055374 -279.22758)
			(xy 125.047249 -279.176285) (xy 124.767339 -279.176285) (xy 124.759214 -279.22758) (xy 124.743166 -279.276973)
			(xy 124.719588 -279.323247) (xy 124.689062 -279.365263) (xy 124.652339 -279.401986) (xy 124.610323 -279.432512)
			(xy 124.564049 -279.45609) (xy 124.514656 -279.472138) (xy 124.463361 -279.480263) (xy 124.411427 -279.480263)
			(xy 124.360132 -279.472138) (xy 124.310739 -279.45609) (xy 124.264465 -279.432512) (xy 124.222449 -279.401986)
			(xy 124.185726 -279.365263) (xy 124.1552 -279.323247) (xy 124.131622 -279.276973) (xy 124.115574 -279.22758)
			(xy 124.107449 -279.176285) (xy 123.827793 -279.176285) (xy 123.819668 -279.22758) (xy 123.80362 -279.276973)
			(xy 123.780042 -279.323247) (xy 123.749516 -279.365263) (xy 123.712793 -279.401986) (xy 123.670777 -279.432512)
			(xy 123.624503 -279.45609) (xy 123.57511 -279.472138) (xy 123.523815 -279.480263) (xy 123.471881 -279.480263)
			(xy 123.420586 -279.472138) (xy 123.371193 -279.45609) (xy 123.324919 -279.432512) (xy 123.282903 -279.401986)
			(xy 123.24618 -279.365263) (xy 123.215654 -279.323247) (xy 123.192076 -279.276973) (xy 123.176028 -279.22758)
			(xy 123.167903 -279.176285) (xy 122.887739 -279.176285) (xy 122.879614 -279.22758) (xy 122.863566 -279.276973)
			(xy 122.839988 -279.323247) (xy 122.809462 -279.365263) (xy 122.772739 -279.401986) (xy 122.730723 -279.432512)
			(xy 122.684449 -279.45609) (xy 122.635056 -279.472138) (xy 122.583761 -279.480263) (xy 122.531827 -279.480263)
			(xy 122.480532 -279.472138) (xy 122.431139 -279.45609) (xy 122.384865 -279.432512) (xy 122.342849 -279.401986)
			(xy 122.306126 -279.365263) (xy 122.2756 -279.323247) (xy 122.252022 -279.276973) (xy 122.235974 -279.22758)
			(xy 122.227849 -279.176285) (xy 121.947939 -279.176285) (xy 121.939814 -279.22758) (xy 121.923766 -279.276973)
			(xy 121.900188 -279.323247) (xy 121.869662 -279.365263) (xy 121.832939 -279.401986) (xy 121.790923 -279.432512)
			(xy 121.744649 -279.45609) (xy 121.695256 -279.472138) (xy 121.643961 -279.480263) (xy 121.592027 -279.480263)
			(xy 121.540732 -279.472138) (xy 121.491339 -279.45609) (xy 121.445065 -279.432512) (xy 121.403049 -279.401986)
			(xy 121.366326 -279.365263) (xy 121.3358 -279.323247) (xy 121.312222 -279.276973) (xy 121.296174 -279.22758)
			(xy 121.288049 -279.176285) (xy 121.008393 -279.176285) (xy 121.000268 -279.22758) (xy 120.98422 -279.276973)
			(xy 120.960642 -279.323247) (xy 120.930116 -279.365263) (xy 120.893393 -279.401986) (xy 120.851377 -279.432512)
			(xy 120.805103 -279.45609) (xy 120.75571 -279.472138) (xy 120.704415 -279.480263) (xy 120.652481 -279.480263)
			(xy 120.601186 -279.472138) (xy 120.551793 -279.45609) (xy 120.505519 -279.432512) (xy 120.463503 -279.401986)
			(xy 120.42678 -279.365263) (xy 120.396254 -279.323247) (xy 120.372676 -279.276973) (xy 120.356628 -279.22758)
			(xy 120.348503 -279.176285) (xy 120.068339 -279.176285) (xy 120.060214 -279.22758) (xy 120.044166 -279.276973)
			(xy 120.020588 -279.323247) (xy 119.990062 -279.365263) (xy 119.953339 -279.401986) (xy 119.911323 -279.432512)
			(xy 119.865049 -279.45609) (xy 119.815656 -279.472138) (xy 119.764361 -279.480263) (xy 119.712427 -279.480263)
			(xy 119.661132 -279.472138) (xy 119.611739 -279.45609) (xy 119.565465 -279.432512) (xy 119.523449 -279.401986)
			(xy 119.486726 -279.365263) (xy 119.4562 -279.323247) (xy 119.432622 -279.276973) (xy 119.416574 -279.22758)
			(xy 119.408449 -279.176285) (xy 118.188993 -279.176285) (xy 118.180868 -279.22758) (xy 118.16482 -279.276973)
			(xy 118.141242 -279.323247) (xy 118.110716 -279.365263) (xy 118.073993 -279.401986) (xy 118.031977 -279.432512)
			(xy 117.985703 -279.45609) (xy 117.93631 -279.472138) (xy 117.885015 -279.480263) (xy 117.833081 -279.480263)
			(xy 117.781786 -279.472138) (xy 117.732393 -279.45609) (xy 117.686119 -279.432512) (xy 117.644103 -279.401986)
			(xy 117.60738 -279.365263) (xy 117.576854 -279.323247) (xy 117.553276 -279.276973) (xy 117.537228 -279.22758)
			(xy 117.529103 -279.176285) (xy 117.249153 -279.176285) (xy 117.241068 -279.227326) (xy 117.22502 -279.276719)
			(xy 117.201442 -279.322993) (xy 117.170916 -279.365009) (xy 117.134193 -279.401732) (xy 117.092177 -279.432258)
			(xy 117.045903 -279.455836) (xy 116.99651 -279.471884) (xy 116.945215 -279.480009) (xy 116.893281 -279.480009)
			(xy 116.841986 -279.471884) (xy 116.792593 -279.455836) (xy 116.746319 -279.432258) (xy 116.704303 -279.401732)
			(xy 116.66758 -279.365009) (xy 116.637054 -279.322993) (xy 116.613476 -279.276719) (xy 116.597428 -279.227326)
			(xy 116.589303 -279.176031) (xy 116.30891 -279.176031) (xy 116.302906 -279.218991) (xy 116.296948 -279.24125)
			(xy 116.288566 -279.269952) (xy 117.008715 -279.990101) (xy 117.998749 -279.990101) (xy 117.998749 -279.938167)
			(xy 118.006874 -279.886872) (xy 118.022922 -279.837479) (xy 118.0465 -279.791205) (xy 118.077026 -279.749189)
			(xy 118.113749 -279.712466) (xy 118.155765 -279.68194) (xy 118.202039 -279.658362) (xy 118.251432 -279.642314)
			(xy 118.302727 -279.634189) (xy 118.354661 -279.634189) (xy 118.405956 -279.642314) (xy 118.455349 -279.658362)
			(xy 118.501623 -279.68194) (xy 118.543639 -279.712466) (xy 118.580362 -279.749189) (xy 118.610888 -279.791205)
			(xy 118.634466 -279.837479) (xy 118.650514 -279.886872) (xy 118.658639 -279.938167) (xy 118.659148 -279.964134)
			(xy 118.658639 -279.990101) (xy 118.938803 -279.990101) (xy 118.938803 -279.938167) (xy 118.946928 -279.886872)
			(xy 118.962976 -279.837479) (xy 118.986554 -279.791205) (xy 119.01708 -279.749189) (xy 119.053803 -279.712466)
			(xy 119.095819 -279.68194) (xy 119.142093 -279.658362) (xy 119.191486 -279.642314) (xy 119.242781 -279.634189)
			(xy 119.294715 -279.634189) (xy 119.34601 -279.642314) (xy 119.395403 -279.658362) (xy 119.441677 -279.68194)
			(xy 119.483693 -279.712466) (xy 119.520416 -279.749189) (xy 119.550942 -279.791205) (xy 119.57452 -279.837479)
			(xy 119.590568 -279.886872) (xy 119.598693 -279.938167) (xy 119.599202 -279.964134) (xy 119.598693 -279.990101)
			(xy 119.878603 -279.990101) (xy 119.878603 -279.938167) (xy 119.886728 -279.886872) (xy 119.902776 -279.837479)
			(xy 119.926354 -279.791205) (xy 119.95688 -279.749189) (xy 119.993603 -279.712466) (xy 120.035619 -279.68194)
			(xy 120.081893 -279.658362) (xy 120.131286 -279.642314) (xy 120.182581 -279.634189) (xy 120.234515 -279.634189)
			(xy 120.28581 -279.642314) (xy 120.335203 -279.658362) (xy 120.381477 -279.68194) (xy 120.423493 -279.712466)
			(xy 120.460216 -279.749189) (xy 120.490742 -279.791205) (xy 120.51432 -279.837479) (xy 120.530368 -279.886872)
			(xy 120.538493 -279.938167) (xy 120.539002 -279.964134) (xy 120.538493 -279.990101) (xy 120.818403 -279.990101)
			(xy 120.818403 -279.938167) (xy 120.826528 -279.886872) (xy 120.842576 -279.837479) (xy 120.866154 -279.791205)
			(xy 120.89668 -279.749189) (xy 120.933403 -279.712466) (xy 120.975419 -279.68194) (xy 121.021693 -279.658362)
			(xy 121.071086 -279.642314) (xy 121.122381 -279.634189) (xy 121.174315 -279.634189) (xy 121.22561 -279.642314)
			(xy 121.275003 -279.658362) (xy 121.321277 -279.68194) (xy 121.363293 -279.712466) (xy 121.400016 -279.749189)
			(xy 121.430542 -279.791205) (xy 121.45412 -279.837479) (xy 121.470168 -279.886872) (xy 121.478293 -279.938167)
			(xy 121.478802 -279.964134) (xy 121.478293 -279.990101) (xy 122.698003 -279.990101) (xy 122.698003 -279.938167)
			(xy 122.706128 -279.886872) (xy 122.722176 -279.837479) (xy 122.745754 -279.791205) (xy 122.77628 -279.749189)
			(xy 122.813003 -279.712466) (xy 122.855019 -279.68194) (xy 122.901293 -279.658362) (xy 122.950686 -279.642314)
			(xy 123.001981 -279.634189) (xy 123.053915 -279.634189) (xy 123.10521 -279.642314) (xy 123.154603 -279.658362)
			(xy 123.200877 -279.68194) (xy 123.242893 -279.712466) (xy 123.279616 -279.749189) (xy 123.310142 -279.791205)
			(xy 123.33372 -279.837479) (xy 123.349768 -279.886872) (xy 123.357893 -279.938167) (xy 123.358402 -279.964134)
			(xy 123.357893 -279.990101) (xy 123.637549 -279.990101) (xy 123.637549 -279.938167) (xy 123.645674 -279.886872)
			(xy 123.661722 -279.837479) (xy 123.6853 -279.791205) (xy 123.715826 -279.749189) (xy 123.752549 -279.712466)
			(xy 123.794565 -279.68194) (xy 123.840839 -279.658362) (xy 123.890232 -279.642314) (xy 123.941527 -279.634189)
			(xy 123.993461 -279.634189) (xy 124.044756 -279.642314) (xy 124.094149 -279.658362) (xy 124.140423 -279.68194)
			(xy 124.182439 -279.712466) (xy 124.219162 -279.749189) (xy 124.249688 -279.791205) (xy 124.273266 -279.837479)
			(xy 124.289314 -279.886872) (xy 124.297439 -279.938167) (xy 124.297948 -279.964134) (xy 124.297439 -279.990101)
			(xy 124.577603 -279.990101) (xy 124.577603 -279.938167) (xy 124.585728 -279.886872) (xy 124.601776 -279.837479)
			(xy 124.625354 -279.791205) (xy 124.65588 -279.749189) (xy 124.692603 -279.712466) (xy 124.734619 -279.68194)
			(xy 124.780893 -279.658362) (xy 124.830286 -279.642314) (xy 124.881581 -279.634189) (xy 124.933515 -279.634189)
			(xy 124.98481 -279.642314) (xy 125.034203 -279.658362) (xy 125.080477 -279.68194) (xy 125.122493 -279.712466)
			(xy 125.159216 -279.749189) (xy 125.189742 -279.791205) (xy 125.21332 -279.837479) (xy 125.229368 -279.886872)
			(xy 125.237493 -279.938167) (xy 125.238002 -279.964134) (xy 125.237493 -279.990101) (xy 125.517403 -279.990101)
			(xy 125.517403 -279.938167) (xy 125.525528 -279.886872) (xy 125.541576 -279.837479) (xy 125.565154 -279.791205)
			(xy 125.59568 -279.749189) (xy 125.632403 -279.712466) (xy 125.674419 -279.68194) (xy 125.720693 -279.658362)
			(xy 125.770086 -279.642314) (xy 125.821381 -279.634189) (xy 125.873315 -279.634189) (xy 125.92461 -279.642314)
			(xy 125.974003 -279.658362) (xy 126.020277 -279.68194) (xy 126.062293 -279.712466) (xy 126.099016 -279.749189)
			(xy 126.129542 -279.791205) (xy 126.15312 -279.837479) (xy 126.169168 -279.886872) (xy 126.177293 -279.938167)
			(xy 126.177802 -279.964134) (xy 126.177293 -279.990101) (xy 126.456949 -279.990101) (xy 126.456949 -279.938167)
			(xy 126.465074 -279.886872) (xy 126.481122 -279.837479) (xy 126.5047 -279.791205) (xy 126.535226 -279.749189)
			(xy 126.571949 -279.712466) (xy 126.613965 -279.68194) (xy 126.660239 -279.658362) (xy 126.709632 -279.642314)
			(xy 126.760927 -279.634189) (xy 126.812861 -279.634189) (xy 126.864156 -279.642314) (xy 126.913549 -279.658362)
			(xy 126.959823 -279.68194) (xy 127.001839 -279.712466) (xy 127.038562 -279.749189) (xy 127.069088 -279.791205)
			(xy 127.092666 -279.837479) (xy 127.108714 -279.886872) (xy 127.116839 -279.938167) (xy 127.117348 -279.964134)
			(xy 127.116839 -279.990101) (xy 127.397003 -279.990101) (xy 127.397003 -279.938167) (xy 127.405128 -279.886872)
			(xy 127.421176 -279.837479) (xy 127.444754 -279.791205) (xy 127.47528 -279.749189) (xy 127.512003 -279.712466)
			(xy 127.554019 -279.68194) (xy 127.600293 -279.658362) (xy 127.649686 -279.642314) (xy 127.700981 -279.634189)
			(xy 127.752915 -279.634189) (xy 127.80421 -279.642314) (xy 127.853603 -279.658362) (xy 127.899877 -279.68194)
			(xy 127.941893 -279.712466) (xy 127.978616 -279.749189) (xy 128.009142 -279.791205) (xy 128.03272 -279.837479)
			(xy 128.048768 -279.886872) (xy 128.056893 -279.938167) (xy 128.057402 -279.964134) (xy 128.056898 -279.989847)
			(xy 128.336549 -279.989847) (xy 128.336549 -279.937913) (xy 128.344674 -279.886618) (xy 128.360722 -279.837225)
			(xy 128.3843 -279.790951) (xy 128.414826 -279.748935) (xy 128.451549 -279.712212) (xy 128.493565 -279.681686)
			(xy 128.539839 -279.658108) (xy 128.589232 -279.64206) (xy 128.640527 -279.633935) (xy 128.692461 -279.633935)
			(xy 128.743756 -279.64206) (xy 128.793149 -279.658108) (xy 128.839423 -279.681686) (xy 128.881439 -279.712212)
			(xy 128.918162 -279.748935) (xy 128.948688 -279.790951) (xy 128.972266 -279.837225) (xy 128.988314 -279.886618)
			(xy 128.996439 -279.937913) (xy 128.996948 -279.96388) (xy 128.996439 -279.989847) (xy 128.996399 -279.990101)
			(xy 130.216403 -279.990101) (xy 130.216403 -279.938167) (xy 130.224528 -279.886872) (xy 130.240576 -279.837479)
			(xy 130.264154 -279.791205) (xy 130.29468 -279.749189) (xy 130.331403 -279.712466) (xy 130.373419 -279.68194)
			(xy 130.419693 -279.658362) (xy 130.469086 -279.642314) (xy 130.520381 -279.634189) (xy 130.572315 -279.634189)
			(xy 130.62361 -279.642314) (xy 130.673003 -279.658362) (xy 130.719277 -279.68194) (xy 130.761293 -279.712466)
			(xy 130.798016 -279.749189) (xy 130.828542 -279.791205) (xy 130.85212 -279.837479) (xy 130.868168 -279.886872)
			(xy 130.876293 -279.938167) (xy 130.876802 -279.964134) (xy 130.876293 -279.990101) (xy 131.156203 -279.990101)
			(xy 131.156203 -279.938167) (xy 131.164328 -279.886872) (xy 131.180376 -279.837479) (xy 131.203954 -279.791205)
			(xy 131.23448 -279.749189) (xy 131.271203 -279.712466) (xy 131.313219 -279.68194) (xy 131.359493 -279.658362)
			(xy 131.408886 -279.642314) (xy 131.460181 -279.634189) (xy 131.512115 -279.634189) (xy 131.56341 -279.642314)
			(xy 131.612803 -279.658362) (xy 131.659077 -279.68194) (xy 131.701093 -279.712466) (xy 131.737816 -279.749189)
			(xy 131.768342 -279.791205) (xy 131.79192 -279.837479) (xy 131.807968 -279.886872) (xy 131.816093 -279.938167)
			(xy 131.816602 -279.964134) (xy 131.816093 -279.990101) (xy 132.095749 -279.990101) (xy 132.095749 -279.938167)
			(xy 132.103874 -279.886872) (xy 132.119922 -279.837479) (xy 132.1435 -279.791205) (xy 132.174026 -279.749189)
			(xy 132.210749 -279.712466) (xy 132.252765 -279.68194) (xy 132.299039 -279.658362) (xy 132.348432 -279.642314)
			(xy 132.399727 -279.634189) (xy 132.451661 -279.634189) (xy 132.502956 -279.642314) (xy 132.552349 -279.658362)
			(xy 132.598623 -279.68194) (xy 132.640639 -279.712466) (xy 132.677362 -279.749189) (xy 132.707888 -279.791205)
			(xy 132.731466 -279.837479) (xy 132.747514 -279.886872) (xy 132.755639 -279.938167) (xy 132.756148 -279.964134)
			(xy 132.755639 -279.990101) (xy 132.747514 -280.041396) (xy 132.731466 -280.090789) (xy 132.707888 -280.137063)
			(xy 132.677362 -280.179079) (xy 132.640639 -280.215802) (xy 132.598623 -280.246328) (xy 132.552349 -280.269906)
			(xy 132.502956 -280.285954) (xy 132.451661 -280.294079) (xy 132.399727 -280.294079) (xy 132.348432 -280.285954)
			(xy 132.299039 -280.269906) (xy 132.252765 -280.246328) (xy 132.210749 -280.215802) (xy 132.174026 -280.179079)
			(xy 132.1435 -280.137063) (xy 132.119922 -280.090789) (xy 132.103874 -280.041396) (xy 132.095749 -279.990101)
			(xy 131.816093 -279.990101) (xy 131.807968 -280.041396) (xy 131.79192 -280.090789) (xy 131.768342 -280.137063)
			(xy 131.737816 -280.179079) (xy 131.701093 -280.215802) (xy 131.659077 -280.246328) (xy 131.612803 -280.269906)
			(xy 131.56341 -280.285954) (xy 131.512115 -280.294079) (xy 131.460181 -280.294079) (xy 131.408886 -280.285954)
			(xy 131.359493 -280.269906) (xy 131.313219 -280.246328) (xy 131.271203 -280.215802) (xy 131.23448 -280.179079)
			(xy 131.203954 -280.137063) (xy 131.180376 -280.090789) (xy 131.164328 -280.041396) (xy 131.156203 -279.990101)
			(xy 130.876293 -279.990101) (xy 130.868168 -280.041396) (xy 130.85212 -280.090789) (xy 130.828542 -280.137063)
			(xy 130.798016 -280.179079) (xy 130.761293 -280.215802) (xy 130.719277 -280.246328) (xy 130.673003 -280.269906)
			(xy 130.62361 -280.285954) (xy 130.572315 -280.294079) (xy 130.520381 -280.294079) (xy 130.469086 -280.285954)
			(xy 130.419693 -280.269906) (xy 130.373419 -280.246328) (xy 130.331403 -280.215802) (xy 130.29468 -280.179079)
			(xy 130.264154 -280.137063) (xy 130.240576 -280.090789) (xy 130.224528 -280.041396) (xy 130.216403 -279.990101)
			(xy 128.996399 -279.990101) (xy 128.988314 -280.041142) (xy 128.972266 -280.090535) (xy 128.948688 -280.136809)
			(xy 128.918162 -280.178825) (xy 128.881439 -280.215548) (xy 128.839423 -280.246074) (xy 128.793149 -280.269652)
			(xy 128.743756 -280.2857) (xy 128.692461 -280.293825) (xy 128.640527 -280.293825) (xy 128.589232 -280.2857)
			(xy 128.539839 -280.269652) (xy 128.493565 -280.246074) (xy 128.451549 -280.215548) (xy 128.414826 -280.178825)
			(xy 128.3843 -280.136809) (xy 128.360722 -280.090535) (xy 128.344674 -280.041142) (xy 128.336549 -279.989847)
			(xy 128.056898 -279.989847) (xy 128.056893 -279.990101) (xy 128.048768 -280.041396) (xy 128.03272 -280.090789)
			(xy 128.009142 -280.137063) (xy 127.978616 -280.179079) (xy 127.941893 -280.215802) (xy 127.899877 -280.246328)
			(xy 127.853603 -280.269906) (xy 127.80421 -280.285954) (xy 127.752915 -280.294079) (xy 127.700981 -280.294079)
			(xy 127.649686 -280.285954) (xy 127.600293 -280.269906) (xy 127.554019 -280.246328) (xy 127.512003 -280.215802)
			(xy 127.47528 -280.179079) (xy 127.444754 -280.137063) (xy 127.421176 -280.090789) (xy 127.405128 -280.041396)
			(xy 127.397003 -279.990101) (xy 127.116839 -279.990101) (xy 127.108714 -280.041396) (xy 127.092666 -280.090789)
			(xy 127.069088 -280.137063) (xy 127.038562 -280.179079) (xy 127.001839 -280.215802) (xy 126.959823 -280.246328)
			(xy 126.913549 -280.269906) (xy 126.864156 -280.285954) (xy 126.812861 -280.294079) (xy 126.760927 -280.294079)
			(xy 126.709632 -280.285954) (xy 126.660239 -280.269906) (xy 126.613965 -280.246328) (xy 126.571949 -280.215802)
			(xy 126.535226 -280.179079) (xy 126.5047 -280.137063) (xy 126.481122 -280.090789) (xy 126.465074 -280.041396)
			(xy 126.456949 -279.990101) (xy 126.177293 -279.990101) (xy 126.169168 -280.041396) (xy 126.15312 -280.090789)
			(xy 126.129542 -280.137063) (xy 126.099016 -280.179079) (xy 126.062293 -280.215802) (xy 126.020277 -280.246328)
			(xy 125.974003 -280.269906) (xy 125.92461 -280.285954) (xy 125.873315 -280.294079) (xy 125.821381 -280.294079)
			(xy 125.770086 -280.285954) (xy 125.720693 -280.269906) (xy 125.674419 -280.246328) (xy 125.632403 -280.215802)
			(xy 125.59568 -280.179079) (xy 125.565154 -280.137063) (xy 125.541576 -280.090789) (xy 125.525528 -280.041396)
			(xy 125.517403 -279.990101) (xy 125.237493 -279.990101) (xy 125.229368 -280.041396) (xy 125.21332 -280.090789)
			(xy 125.189742 -280.137063) (xy 125.159216 -280.179079) (xy 125.122493 -280.215802) (xy 125.080477 -280.246328)
			(xy 125.034203 -280.269906) (xy 124.98481 -280.285954) (xy 124.933515 -280.294079) (xy 124.881581 -280.294079)
			(xy 124.830286 -280.285954) (xy 124.780893 -280.269906) (xy 124.734619 -280.246328) (xy 124.692603 -280.215802)
			(xy 124.65588 -280.179079) (xy 124.625354 -280.137063) (xy 124.601776 -280.090789) (xy 124.585728 -280.041396)
			(xy 124.577603 -279.990101) (xy 124.297439 -279.990101) (xy 124.289314 -280.041396) (xy 124.273266 -280.090789)
			(xy 124.249688 -280.137063) (xy 124.219162 -280.179079) (xy 124.182439 -280.215802) (xy 124.140423 -280.246328)
			(xy 124.094149 -280.269906) (xy 124.044756 -280.285954) (xy 123.993461 -280.294079) (xy 123.941527 -280.294079)
			(xy 123.890232 -280.285954) (xy 123.840839 -280.269906) (xy 123.794565 -280.246328) (xy 123.752549 -280.215802)
			(xy 123.715826 -280.179079) (xy 123.6853 -280.137063) (xy 123.661722 -280.090789) (xy 123.645674 -280.041396)
			(xy 123.637549 -279.990101) (xy 123.357893 -279.990101) (xy 123.349768 -280.041396) (xy 123.33372 -280.090789)
			(xy 123.310142 -280.137063) (xy 123.279616 -280.179079) (xy 123.242893 -280.215802) (xy 123.200877 -280.246328)
			(xy 123.154603 -280.269906) (xy 123.10521 -280.285954) (xy 123.053915 -280.294079) (xy 123.001981 -280.294079)
			(xy 122.950686 -280.285954) (xy 122.901293 -280.269906) (xy 122.855019 -280.246328) (xy 122.813003 -280.215802)
			(xy 122.77628 -280.179079) (xy 122.745754 -280.137063) (xy 122.722176 -280.090789) (xy 122.706128 -280.041396)
			(xy 122.698003 -279.990101) (xy 121.478293 -279.990101) (xy 121.470168 -280.041396) (xy 121.45412 -280.090789)
			(xy 121.430542 -280.137063) (xy 121.400016 -280.179079) (xy 121.363293 -280.215802) (xy 121.321277 -280.246328)
			(xy 121.275003 -280.269906) (xy 121.22561 -280.285954) (xy 121.174315 -280.294079) (xy 121.122381 -280.294079)
			(xy 121.071086 -280.285954) (xy 121.021693 -280.269906) (xy 120.975419 -280.246328) (xy 120.933403 -280.215802)
			(xy 120.89668 -280.179079) (xy 120.866154 -280.137063) (xy 120.842576 -280.090789) (xy 120.826528 -280.041396)
			(xy 120.818403 -279.990101) (xy 120.538493 -279.990101) (xy 120.530368 -280.041396) (xy 120.51432 -280.090789)
			(xy 120.490742 -280.137063) (xy 120.460216 -280.179079) (xy 120.423493 -280.215802) (xy 120.381477 -280.246328)
			(xy 120.335203 -280.269906) (xy 120.28581 -280.285954) (xy 120.234515 -280.294079) (xy 120.182581 -280.294079)
			(xy 120.131286 -280.285954) (xy 120.081893 -280.269906) (xy 120.035619 -280.246328) (xy 119.993603 -280.215802)
			(xy 119.95688 -280.179079) (xy 119.926354 -280.137063) (xy 119.902776 -280.090789) (xy 119.886728 -280.041396)
			(xy 119.878603 -279.990101) (xy 119.598693 -279.990101) (xy 119.590568 -280.041396) (xy 119.57452 -280.090789)
			(xy 119.550942 -280.137063) (xy 119.520416 -280.179079) (xy 119.483693 -280.215802) (xy 119.441677 -280.246328)
			(xy 119.395403 -280.269906) (xy 119.34601 -280.285954) (xy 119.294715 -280.294079) (xy 119.242781 -280.294079)
			(xy 119.191486 -280.285954) (xy 119.142093 -280.269906) (xy 119.095819 -280.246328) (xy 119.053803 -280.215802)
			(xy 119.01708 -280.179079) (xy 118.986554 -280.137063) (xy 118.962976 -280.090789) (xy 118.946928 -280.041396)
			(xy 118.938803 -279.990101) (xy 118.658639 -279.990101) (xy 118.650514 -280.041396) (xy 118.634466 -280.090789)
			(xy 118.610888 -280.137063) (xy 118.580362 -280.179079) (xy 118.543639 -280.215802) (xy 118.501623 -280.246328)
			(xy 118.455349 -280.269906) (xy 118.405956 -280.285954) (xy 118.354661 -280.294079) (xy 118.302727 -280.294079)
			(xy 118.251432 -280.285954) (xy 118.202039 -280.269906) (xy 118.155765 -280.246328) (xy 118.113749 -280.215802)
			(xy 118.077026 -280.179079) (xy 118.0465 -280.137063) (xy 118.022922 -280.090789) (xy 118.006874 -280.041396)
			(xy 117.998749 -279.990101) (xy 117.008715 -279.990101) (xy 117.593618 -280.575004) (xy 117.629686 -280.54046)
			(xy 117.648255 -280.523165) (xy 117.689714 -280.493908) (xy 117.735163 -280.471342) (xy 117.783531 -280.455998)
			(xy 117.833677 -280.448238) (xy 117.859048 -280.44775) (xy 117.885013 -280.448263) (xy 117.936302 -280.456393)
			(xy 117.985688 -280.472446) (xy 118.031954 -280.496026) (xy 118.073963 -280.526554) (xy 118.11068 -280.563276)
			(xy 118.141201 -280.60529) (xy 118.164774 -280.651561) (xy 118.180819 -280.700949) (xy 118.188941 -280.752239)
			(xy 118.189502 -280.778204) (xy 118.189018 -280.803574) (xy 118.188925 -280.804171) (xy 118.468649 -280.804171)
			(xy 118.468649 -280.752237) (xy 118.476774 -280.700942) (xy 118.492822 -280.651549) (xy 118.5164 -280.605275)
			(xy 118.546926 -280.563259) (xy 118.583649 -280.526536) (xy 118.625665 -280.49601) (xy 118.671939 -280.472432)
			(xy 118.721332 -280.456384) (xy 118.772627 -280.448259) (xy 118.824561 -280.448259) (xy 118.875856 -280.456384)
			(xy 118.925249 -280.472432) (xy 118.971523 -280.49601) (xy 119.013539 -280.526536) (xy 119.050262 -280.563259)
			(xy 119.080788 -280.605275) (xy 119.104366 -280.651549) (xy 119.120414 -280.700942) (xy 119.128539 -280.752237)
			(xy 119.129048 -280.778204) (xy 119.128539 -280.804171) (xy 119.408449 -280.804171) (xy 119.408449 -280.752237)
			(xy 119.416574 -280.700942) (xy 119.432622 -280.651549) (xy 119.4562 -280.605275) (xy 119.486726 -280.563259)
			(xy 119.523449 -280.526536) (xy 119.565465 -280.49601) (xy 119.611739 -280.472432) (xy 119.661132 -280.456384)
			(xy 119.712427 -280.448259) (xy 119.764361 -280.448259) (xy 119.815656 -280.456384) (xy 119.865049 -280.472432)
			(xy 119.911323 -280.49601) (xy 119.953339 -280.526536) (xy 119.990062 -280.563259) (xy 120.020588 -280.605275)
			(xy 120.044166 -280.651549) (xy 120.060214 -280.700942) (xy 120.068339 -280.752237) (xy 120.068848 -280.778204)
			(xy 120.068339 -280.804171) (xy 120.348249 -280.804171) (xy 120.348249 -280.752237) (xy 120.356374 -280.700942)
			(xy 120.372422 -280.651549) (xy 120.396 -280.605275) (xy 120.426526 -280.563259) (xy 120.463249 -280.526536)
			(xy 120.505265 -280.49601) (xy 120.551539 -280.472432) (xy 120.600932 -280.456384) (xy 120.652227 -280.448259)
			(xy 120.704161 -280.448259) (xy 120.755456 -280.456384) (xy 120.804849 -280.472432) (xy 120.851123 -280.49601)
			(xy 120.893139 -280.526536) (xy 120.929862 -280.563259) (xy 120.960388 -280.605275) (xy 120.983966 -280.651549)
			(xy 121.000014 -280.700942) (xy 121.008139 -280.752237) (xy 121.008648 -280.778204) (xy 121.008139 -280.804171)
			(xy 121.288049 -280.804171) (xy 121.288049 -280.752237) (xy 121.296174 -280.700942) (xy 121.312222 -280.651549)
			(xy 121.3358 -280.605275) (xy 121.366326 -280.563259) (xy 121.403049 -280.526536) (xy 121.445065 -280.49601)
			(xy 121.491339 -280.472432) (xy 121.540732 -280.456384) (xy 121.592027 -280.448259) (xy 121.643961 -280.448259)
			(xy 121.695256 -280.456384) (xy 121.744649 -280.472432) (xy 121.790923 -280.49601) (xy 121.832939 -280.526536)
			(xy 121.869662 -280.563259) (xy 121.900188 -280.605275) (xy 121.923766 -280.651549) (xy 121.939814 -280.700942)
			(xy 121.947939 -280.752237) (xy 121.948448 -280.778204) (xy 121.947939 -280.804171) (xy 122.227849 -280.804171)
			(xy 122.227849 -280.752237) (xy 122.235974 -280.700942) (xy 122.252022 -280.651549) (xy 122.2756 -280.605275)
			(xy 122.306126 -280.563259) (xy 122.342849 -280.526536) (xy 122.384865 -280.49601) (xy 122.431139 -280.472432)
			(xy 122.480532 -280.456384) (xy 122.531827 -280.448259) (xy 122.583761 -280.448259) (xy 122.635056 -280.456384)
			(xy 122.684449 -280.472432) (xy 122.730723 -280.49601) (xy 122.772739 -280.526536) (xy 122.809462 -280.563259)
			(xy 122.839988 -280.605275) (xy 122.863566 -280.651549) (xy 122.879614 -280.700942) (xy 122.887739 -280.752237)
			(xy 122.888248 -280.778204) (xy 122.887739 -280.804171) (xy 123.167649 -280.804171) (xy 123.167649 -280.752237)
			(xy 123.175774 -280.700942) (xy 123.191822 -280.651549) (xy 123.2154 -280.605275) (xy 123.245926 -280.563259)
			(xy 123.282649 -280.526536) (xy 123.324665 -280.49601) (xy 123.370939 -280.472432) (xy 123.420332 -280.456384)
			(xy 123.471627 -280.448259) (xy 123.523561 -280.448259) (xy 123.574856 -280.456384) (xy 123.624249 -280.472432)
			(xy 123.670523 -280.49601) (xy 123.712539 -280.526536) (xy 123.749262 -280.563259) (xy 123.779788 -280.605275)
			(xy 123.803366 -280.651549) (xy 123.819414 -280.700942) (xy 123.827539 -280.752237) (xy 123.828048 -280.778204)
			(xy 123.827539 -280.804171) (xy 124.107449 -280.804171) (xy 124.107449 -280.752237) (xy 124.115574 -280.700942)
			(xy 124.131622 -280.651549) (xy 124.1552 -280.605275) (xy 124.185726 -280.563259) (xy 124.222449 -280.526536)
			(xy 124.264465 -280.49601) (xy 124.310739 -280.472432) (xy 124.360132 -280.456384) (xy 124.411427 -280.448259)
			(xy 124.463361 -280.448259) (xy 124.514656 -280.456384) (xy 124.564049 -280.472432) (xy 124.610323 -280.49601)
			(xy 124.652339 -280.526536) (xy 124.689062 -280.563259) (xy 124.719588 -280.605275) (xy 124.743166 -280.651549)
			(xy 124.759214 -280.700942) (xy 124.767339 -280.752237) (xy 124.767848 -280.778204) (xy 124.767339 -280.804171)
			(xy 125.047249 -280.804171) (xy 125.047249 -280.752237) (xy 125.055374 -280.700942) (xy 125.071422 -280.651549)
			(xy 125.095 -280.605275) (xy 125.125526 -280.563259) (xy 125.162249 -280.526536) (xy 125.204265 -280.49601)
			(xy 125.250539 -280.472432) (xy 125.299932 -280.456384) (xy 125.351227 -280.448259) (xy 125.403161 -280.448259)
			(xy 125.454456 -280.456384) (xy 125.503849 -280.472432) (xy 125.550123 -280.49601) (xy 125.592139 -280.526536)
			(xy 125.628862 -280.563259) (xy 125.659388 -280.605275) (xy 125.682966 -280.651549) (xy 125.699014 -280.700942)
			(xy 125.707139 -280.752237) (xy 125.707648 -280.778204) (xy 125.707139 -280.804171) (xy 125.987303 -280.804171)
			(xy 125.987303 -280.752237) (xy 125.995428 -280.700942) (xy 126.011476 -280.651549) (xy 126.035054 -280.605275)
			(xy 126.06558 -280.563259) (xy 126.102303 -280.526536) (xy 126.144319 -280.49601) (xy 126.190593 -280.472432)
			(xy 126.239986 -280.456384) (xy 126.291281 -280.448259) (xy 126.343215 -280.448259) (xy 126.39451 -280.456384)
			(xy 126.443903 -280.472432) (xy 126.490177 -280.49601) (xy 126.532193 -280.526536) (xy 126.568916 -280.563259)
			(xy 126.599442 -280.605275) (xy 126.62302 -280.651549) (xy 126.639068 -280.700942) (xy 126.647193 -280.752237)
			(xy 126.647702 -280.778204) (xy 126.647193 -280.804171) (xy 126.927103 -280.804171) (xy 126.927103 -280.752237)
			(xy 126.935228 -280.700942) (xy 126.951276 -280.651549) (xy 126.974854 -280.605275) (xy 127.00538 -280.563259)
			(xy 127.042103 -280.526536) (xy 127.084119 -280.49601) (xy 127.130393 -280.472432) (xy 127.179786 -280.456384)
			(xy 127.231081 -280.448259) (xy 127.283015 -280.448259) (xy 127.33431 -280.456384) (xy 127.383703 -280.472432)
			(xy 127.429977 -280.49601) (xy 127.471993 -280.526536) (xy 127.508716 -280.563259) (xy 127.539242 -280.605275)
			(xy 127.56282 -280.651549) (xy 127.578868 -280.700942) (xy 127.586993 -280.752237) (xy 127.587502 -280.778204)
			(xy 127.586993 -280.804171) (xy 127.866903 -280.804171) (xy 127.866903 -280.752237) (xy 127.875028 -280.700942)
			(xy 127.891076 -280.651549) (xy 127.914654 -280.605275) (xy 127.94518 -280.563259) (xy 127.981903 -280.526536)
			(xy 128.023919 -280.49601) (xy 128.070193 -280.472432) (xy 128.119586 -280.456384) (xy 128.170881 -280.448259)
			(xy 128.222815 -280.448259) (xy 128.27411 -280.456384) (xy 128.323503 -280.472432) (xy 128.369777 -280.49601)
			(xy 128.411793 -280.526536) (xy 128.448516 -280.563259) (xy 128.479042 -280.605275) (xy 128.50262 -280.651549)
			(xy 128.518668 -280.700942) (xy 128.526793 -280.752237) (xy 128.527302 -280.778204) (xy 128.526793 -280.804171)
			(xy 128.806703 -280.804171) (xy 128.806703 -280.752237) (xy 128.814828 -280.700942) (xy 128.830876 -280.651549)
			(xy 128.854454 -280.605275) (xy 128.88498 -280.563259) (xy 128.921703 -280.526536) (xy 128.963719 -280.49601)
			(xy 129.009993 -280.472432) (xy 129.059386 -280.456384) (xy 129.110681 -280.448259) (xy 129.162615 -280.448259)
			(xy 129.21391 -280.456384) (xy 129.263303 -280.472432) (xy 129.309577 -280.49601) (xy 129.351593 -280.526536)
			(xy 129.388316 -280.563259) (xy 129.418842 -280.605275) (xy 129.44242 -280.651549) (xy 129.458468 -280.700942)
			(xy 129.466593 -280.752237) (xy 129.467102 -280.778204) (xy 129.466593 -280.804171) (xy 129.746503 -280.804171)
			(xy 129.746503 -280.752237) (xy 129.754628 -280.700942) (xy 129.770676 -280.651549) (xy 129.794254 -280.605275)
			(xy 129.82478 -280.563259) (xy 129.861503 -280.526536) (xy 129.903519 -280.49601) (xy 129.949793 -280.472432)
			(xy 129.999186 -280.456384) (xy 130.050481 -280.448259) (xy 130.102415 -280.448259) (xy 130.15371 -280.456384)
			(xy 130.203103 -280.472432) (xy 130.249377 -280.49601) (xy 130.291393 -280.526536) (xy 130.328116 -280.563259)
			(xy 130.358642 -280.605275) (xy 130.38222 -280.651549) (xy 130.398268 -280.700942) (xy 130.406393 -280.752237)
			(xy 130.406902 -280.778204) (xy 130.406393 -280.804171) (xy 130.686049 -280.804171) (xy 130.686049 -280.752237)
			(xy 130.694174 -280.700942) (xy 130.710222 -280.651549) (xy 130.7338 -280.605275) (xy 130.764326 -280.563259)
			(xy 130.801049 -280.526536) (xy 130.843065 -280.49601) (xy 130.889339 -280.472432) (xy 130.938732 -280.456384)
			(xy 130.990027 -280.448259) (xy 131.041961 -280.448259) (xy 131.093256 -280.456384) (xy 131.142649 -280.472432)
			(xy 131.188923 -280.49601) (xy 131.230939 -280.526536) (xy 131.267662 -280.563259) (xy 131.298188 -280.605275)
			(xy 131.321766 -280.651549) (xy 131.337814 -280.700942) (xy 131.345939 -280.752237) (xy 131.346448 -280.778204)
			(xy 131.345939 -280.804171) (xy 131.625849 -280.804171) (xy 131.625849 -280.752237) (xy 131.633974 -280.700942)
			(xy 131.650022 -280.651549) (xy 131.6736 -280.605275) (xy 131.704126 -280.563259) (xy 131.740849 -280.526536)
			(xy 131.782865 -280.49601) (xy 131.829139 -280.472432) (xy 131.878532 -280.456384) (xy 131.929827 -280.448259)
			(xy 131.981761 -280.448259) (xy 132.033056 -280.456384) (xy 132.082449 -280.472432) (xy 132.128723 -280.49601)
			(xy 132.170739 -280.526536) (xy 132.207462 -280.563259) (xy 132.237988 -280.605275) (xy 132.261566 -280.651549)
			(xy 132.277614 -280.700942) (xy 132.285739 -280.752237) (xy 132.286248 -280.778204) (xy 132.285739 -280.804171)
			(xy 132.565649 -280.804171) (xy 132.565649 -280.752237) (xy 132.573774 -280.700942) (xy 132.589822 -280.651549)
			(xy 132.6134 -280.605275) (xy 132.643926 -280.563259) (xy 132.680649 -280.526536) (xy 132.722665 -280.49601)
			(xy 132.768939 -280.472432) (xy 132.818332 -280.456384) (xy 132.869627 -280.448259) (xy 132.921561 -280.448259)
			(xy 132.972856 -280.456384) (xy 133.022249 -280.472432) (xy 133.068523 -280.49601) (xy 133.110539 -280.526536)
			(xy 133.147262 -280.563259) (xy 133.177788 -280.605275) (xy 133.201366 -280.651549) (xy 133.217414 -280.700942)
			(xy 133.225539 -280.752237) (xy 133.226048 -280.778204) (xy 133.225539 -280.804171) (xy 133.505449 -280.804171)
			(xy 133.505449 -280.752237) (xy 133.513574 -280.700942) (xy 133.529622 -280.651549) (xy 133.5532 -280.605275)
			(xy 133.583726 -280.563259) (xy 133.620449 -280.526536) (xy 133.662465 -280.49601) (xy 133.708739 -280.472432)
			(xy 133.758132 -280.456384) (xy 133.809427 -280.448259) (xy 133.861361 -280.448259) (xy 133.912656 -280.456384)
			(xy 133.962049 -280.472432) (xy 134.008323 -280.49601) (xy 134.050339 -280.526536) (xy 134.087062 -280.563259)
			(xy 134.117588 -280.605275) (xy 134.141166 -280.651549) (xy 134.157214 -280.700942) (xy 134.165339 -280.752237)
			(xy 134.165848 -280.778204) (xy 134.165339 -280.804171) (xy 134.157214 -280.855466) (xy 134.141166 -280.904859)
			(xy 134.117588 -280.951133) (xy 134.087062 -280.993149) (xy 134.050339 -281.029872) (xy 134.008323 -281.060398)
			(xy 133.962049 -281.083976) (xy 133.912656 -281.100024) (xy 133.861361 -281.108149) (xy 133.809427 -281.108149)
			(xy 133.758132 -281.100024) (xy 133.708739 -281.083976) (xy 133.662465 -281.060398) (xy 133.620449 -281.029872)
			(xy 133.583726 -280.993149) (xy 133.5532 -280.951133) (xy 133.529622 -280.904859) (xy 133.513574 -280.855466)
			(xy 133.505449 -280.804171) (xy 133.225539 -280.804171) (xy 133.217414 -280.855466) (xy 133.201366 -280.904859)
			(xy 133.177788 -280.951133) (xy 133.147262 -280.993149) (xy 133.110539 -281.029872) (xy 133.068523 -281.060398)
			(xy 133.022249 -281.083976) (xy 132.972856 -281.100024) (xy 132.921561 -281.108149) (xy 132.869627 -281.108149)
			(xy 132.818332 -281.100024) (xy 132.768939 -281.083976) (xy 132.722665 -281.060398) (xy 132.680649 -281.029872)
			(xy 132.643926 -280.993149) (xy 132.6134 -280.951133) (xy 132.589822 -280.904859) (xy 132.573774 -280.855466)
			(xy 132.565649 -280.804171) (xy 132.285739 -280.804171) (xy 132.277614 -280.855466) (xy 132.261566 -280.904859)
			(xy 132.237988 -280.951133) (xy 132.207462 -280.993149) (xy 132.170739 -281.029872) (xy 132.128723 -281.060398)
			(xy 132.082449 -281.083976) (xy 132.033056 -281.100024) (xy 131.981761 -281.108149) (xy 131.929827 -281.108149)
			(xy 131.878532 -281.100024) (xy 131.829139 -281.083976) (xy 131.782865 -281.060398) (xy 131.740849 -281.029872)
			(xy 131.704126 -280.993149) (xy 131.6736 -280.951133) (xy 131.650022 -280.904859) (xy 131.633974 -280.855466)
			(xy 131.625849 -280.804171) (xy 131.345939 -280.804171) (xy 131.337814 -280.855466) (xy 131.321766 -280.904859)
			(xy 131.298188 -280.951133) (xy 131.267662 -280.993149) (xy 131.230939 -281.029872) (xy 131.188923 -281.060398)
			(xy 131.142649 -281.083976) (xy 131.093256 -281.100024) (xy 131.041961 -281.108149) (xy 130.990027 -281.108149)
			(xy 130.938732 -281.100024) (xy 130.889339 -281.083976) (xy 130.843065 -281.060398) (xy 130.801049 -281.029872)
			(xy 130.764326 -280.993149) (xy 130.7338 -280.951133) (xy 130.710222 -280.904859) (xy 130.694174 -280.855466)
			(xy 130.686049 -280.804171) (xy 130.406393 -280.804171) (xy 130.398268 -280.855466) (xy 130.38222 -280.904859)
			(xy 130.358642 -280.951133) (xy 130.328116 -280.993149) (xy 130.291393 -281.029872) (xy 130.249377 -281.060398)
			(xy 130.203103 -281.083976) (xy 130.15371 -281.100024) (xy 130.102415 -281.108149) (xy 130.050481 -281.108149)
			(xy 129.999186 -281.100024) (xy 129.949793 -281.083976) (xy 129.903519 -281.060398) (xy 129.861503 -281.029872)
			(xy 129.82478 -280.993149) (xy 129.794254 -280.951133) (xy 129.770676 -280.904859) (xy 129.754628 -280.855466)
			(xy 129.746503 -280.804171) (xy 129.466593 -280.804171) (xy 129.458468 -280.855466) (xy 129.44242 -280.904859)
			(xy 129.418842 -280.951133) (xy 129.388316 -280.993149) (xy 129.351593 -281.029872) (xy 129.309577 -281.060398)
			(xy 129.263303 -281.083976) (xy 129.21391 -281.100024) (xy 129.162615 -281.108149) (xy 129.110681 -281.108149)
			(xy 129.059386 -281.100024) (xy 129.009993 -281.083976) (xy 128.963719 -281.060398) (xy 128.921703 -281.029872)
			(xy 128.88498 -280.993149) (xy 128.854454 -280.951133) (xy 128.830876 -280.904859) (xy 128.814828 -280.855466)
			(xy 128.806703 -280.804171) (xy 128.526793 -280.804171) (xy 128.518668 -280.855466) (xy 128.50262 -280.904859)
			(xy 128.479042 -280.951133) (xy 128.448516 -280.993149) (xy 128.411793 -281.029872) (xy 128.369777 -281.060398)
			(xy 128.323503 -281.083976) (xy 128.27411 -281.100024) (xy 128.222815 -281.108149) (xy 128.170881 -281.108149)
			(xy 128.119586 -281.100024) (xy 128.070193 -281.083976) (xy 128.023919 -281.060398) (xy 127.981903 -281.029872)
			(xy 127.94518 -280.993149) (xy 127.914654 -280.951133) (xy 127.891076 -280.904859) (xy 127.875028 -280.855466)
			(xy 127.866903 -280.804171) (xy 127.586993 -280.804171) (xy 127.578868 -280.855466) (xy 127.56282 -280.904859)
			(xy 127.539242 -280.951133) (xy 127.508716 -280.993149) (xy 127.471993 -281.029872) (xy 127.429977 -281.060398)
			(xy 127.383703 -281.083976) (xy 127.33431 -281.100024) (xy 127.283015 -281.108149) (xy 127.231081 -281.108149)
			(xy 127.179786 -281.100024) (xy 127.130393 -281.083976) (xy 127.084119 -281.060398) (xy 127.042103 -281.029872)
			(xy 127.00538 -280.993149) (xy 126.974854 -280.951133) (xy 126.951276 -280.904859) (xy 126.935228 -280.855466)
			(xy 126.927103 -280.804171) (xy 126.647193 -280.804171) (xy 126.639068 -280.855466) (xy 126.62302 -280.904859)
			(xy 126.599442 -280.951133) (xy 126.568916 -280.993149) (xy 126.532193 -281.029872) (xy 126.490177 -281.060398)
			(xy 126.443903 -281.083976) (xy 126.39451 -281.100024) (xy 126.343215 -281.108149) (xy 126.291281 -281.108149)
			(xy 126.239986 -281.100024) (xy 126.190593 -281.083976) (xy 126.144319 -281.060398) (xy 126.102303 -281.029872)
			(xy 126.06558 -280.993149) (xy 126.035054 -280.951133) (xy 126.011476 -280.904859) (xy 125.995428 -280.855466)
			(xy 125.987303 -280.804171) (xy 125.707139 -280.804171) (xy 125.699014 -280.855466) (xy 125.682966 -280.904859)
			(xy 125.659388 -280.951133) (xy 125.628862 -280.993149) (xy 125.592139 -281.029872) (xy 125.550123 -281.060398)
			(xy 125.503849 -281.083976) (xy 125.454456 -281.100024) (xy 125.403161 -281.108149) (xy 125.351227 -281.108149)
			(xy 125.299932 -281.100024) (xy 125.250539 -281.083976) (xy 125.204265 -281.060398) (xy 125.162249 -281.029872)
			(xy 125.125526 -280.993149) (xy 125.095 -280.951133) (xy 125.071422 -280.904859) (xy 125.055374 -280.855466)
			(xy 125.047249 -280.804171) (xy 124.767339 -280.804171) (xy 124.759214 -280.855466) (xy 124.743166 -280.904859)
			(xy 124.719588 -280.951133) (xy 124.689062 -280.993149) (xy 124.652339 -281.029872) (xy 124.610323 -281.060398)
			(xy 124.564049 -281.083976) (xy 124.514656 -281.100024) (xy 124.463361 -281.108149) (xy 124.411427 -281.108149)
			(xy 124.360132 -281.100024) (xy 124.310739 -281.083976) (xy 124.264465 -281.060398) (xy 124.222449 -281.029872)
			(xy 124.185726 -280.993149) (xy 124.1552 -280.951133) (xy 124.131622 -280.904859) (xy 124.115574 -280.855466)
			(xy 124.107449 -280.804171) (xy 123.827539 -280.804171) (xy 123.819414 -280.855466) (xy 123.803366 -280.904859)
			(xy 123.779788 -280.951133) (xy 123.749262 -280.993149) (xy 123.712539 -281.029872) (xy 123.670523 -281.060398)
			(xy 123.624249 -281.083976) (xy 123.574856 -281.100024) (xy 123.523561 -281.108149) (xy 123.471627 -281.108149)
			(xy 123.420332 -281.100024) (xy 123.370939 -281.083976) (xy 123.324665 -281.060398) (xy 123.282649 -281.029872)
			(xy 123.245926 -280.993149) (xy 123.2154 -280.951133) (xy 123.191822 -280.904859) (xy 123.175774 -280.855466)
			(xy 123.167649 -280.804171) (xy 122.887739 -280.804171) (xy 122.879614 -280.855466) (xy 122.863566 -280.904859)
			(xy 122.839988 -280.951133) (xy 122.809462 -280.993149) (xy 122.772739 -281.029872) (xy 122.730723 -281.060398)
			(xy 122.684449 -281.083976) (xy 122.635056 -281.100024) (xy 122.583761 -281.108149) (xy 122.531827 -281.108149)
			(xy 122.480532 -281.100024) (xy 122.431139 -281.083976) (xy 122.384865 -281.060398) (xy 122.342849 -281.029872)
			(xy 122.306126 -280.993149) (xy 122.2756 -280.951133) (xy 122.252022 -280.904859) (xy 122.235974 -280.855466)
			(xy 122.227849 -280.804171) (xy 121.947939 -280.804171) (xy 121.939814 -280.855466) (xy 121.923766 -280.904859)
			(xy 121.900188 -280.951133) (xy 121.869662 -280.993149) (xy 121.832939 -281.029872) (xy 121.790923 -281.060398)
			(xy 121.744649 -281.083976) (xy 121.695256 -281.100024) (xy 121.643961 -281.108149) (xy 121.592027 -281.108149)
			(xy 121.540732 -281.100024) (xy 121.491339 -281.083976) (xy 121.445065 -281.060398) (xy 121.403049 -281.029872)
			(xy 121.366326 -280.993149) (xy 121.3358 -280.951133) (xy 121.312222 -280.904859) (xy 121.296174 -280.855466)
			(xy 121.288049 -280.804171) (xy 121.008139 -280.804171) (xy 121.000014 -280.855466) (xy 120.983966 -280.904859)
			(xy 120.960388 -280.951133) (xy 120.929862 -280.993149) (xy 120.893139 -281.029872) (xy 120.851123 -281.060398)
			(xy 120.804849 -281.083976) (xy 120.755456 -281.100024) (xy 120.704161 -281.108149) (xy 120.652227 -281.108149)
			(xy 120.600932 -281.100024) (xy 120.551539 -281.083976) (xy 120.505265 -281.060398) (xy 120.463249 -281.029872)
			(xy 120.426526 -280.993149) (xy 120.396 -280.951133) (xy 120.372422 -280.904859) (xy 120.356374 -280.855466)
			(xy 120.348249 -280.804171) (xy 120.068339 -280.804171) (xy 120.060214 -280.855466) (xy 120.044166 -280.904859)
			(xy 120.020588 -280.951133) (xy 119.990062 -280.993149) (xy 119.953339 -281.029872) (xy 119.911323 -281.060398)
			(xy 119.865049 -281.083976) (xy 119.815656 -281.100024) (xy 119.764361 -281.108149) (xy 119.712427 -281.108149)
			(xy 119.661132 -281.100024) (xy 119.611739 -281.083976) (xy 119.565465 -281.060398) (xy 119.523449 -281.029872)
			(xy 119.486726 -280.993149) (xy 119.4562 -280.951133) (xy 119.432622 -280.904859) (xy 119.416574 -280.855466)
			(xy 119.408449 -280.804171) (xy 119.128539 -280.804171) (xy 119.120414 -280.855466) (xy 119.104366 -280.904859)
			(xy 119.080788 -280.951133) (xy 119.050262 -280.993149) (xy 119.013539 -281.029872) (xy 118.971523 -281.060398)
			(xy 118.925249 -281.083976) (xy 118.875856 -281.100024) (xy 118.824561 -281.108149) (xy 118.772627 -281.108149)
			(xy 118.721332 -281.100024) (xy 118.671939 -281.083976) (xy 118.625665 -281.060398) (xy 118.583649 -281.029872)
			(xy 118.546926 -280.993149) (xy 118.5164 -280.951133) (xy 118.492822 -280.904859) (xy 118.476774 -280.855466)
			(xy 118.468649 -280.804171) (xy 118.188925 -280.804171) (xy 118.181226 -280.853712) (xy 118.165872 -280.902073)
			(xy 118.143315 -280.947523) (xy 118.114085 -280.988998) (xy 118.096792 -281.007566) (xy 118.062248 -281.043634)
			(xy 118.28272 -281.264106) (xy 118.30558 -281.262328) (xy 118.328694 -281.261566) (xy 118.354663 -281.262048)
			(xy 118.405962 -281.270173) (xy 118.455358 -281.286222) (xy 118.501635 -281.309802) (xy 118.543653 -281.340331)
			(xy 118.580378 -281.377058) (xy 118.610905 -281.419077) (xy 118.634483 -281.465355) (xy 118.65053 -281.514752)
			(xy 118.658653 -281.566051) (xy 118.659148 -281.59202) (xy 118.658386 -281.615134) (xy 118.658164 -281.617987)
			(xy 118.938803 -281.617987) (xy 118.938803 -281.566053) (xy 118.946928 -281.514758) (xy 118.962976 -281.465365)
			(xy 118.986554 -281.419091) (xy 119.01708 -281.377075) (xy 119.053803 -281.340352) (xy 119.095819 -281.309826)
			(xy 119.142093 -281.286248) (xy 119.191486 -281.2702) (xy 119.242781 -281.262075) (xy 119.294715 -281.262075)
			(xy 119.34601 -281.2702) (xy 119.395403 -281.286248) (xy 119.441677 -281.309826) (xy 119.483693 -281.340352)
			(xy 119.520416 -281.377075) (xy 119.550942 -281.419091) (xy 119.57452 -281.465365) (xy 119.590568 -281.514758)
			(xy 119.598693 -281.566053) (xy 119.599202 -281.59202) (xy 119.598693 -281.617987) (xy 119.878603 -281.617987)
			(xy 119.878603 -281.566053) (xy 119.886728 -281.514758) (xy 119.902776 -281.465365) (xy 119.926354 -281.419091)
			(xy 119.95688 -281.377075) (xy 119.993603 -281.340352) (xy 120.035619 -281.309826) (xy 120.081893 -281.286248)
			(xy 120.131286 -281.2702) (xy 120.182581 -281.262075) (xy 120.234515 -281.262075) (xy 120.28581 -281.2702)
			(xy 120.335203 -281.286248) (xy 120.381477 -281.309826) (xy 120.423493 -281.340352) (xy 120.460216 -281.377075)
			(xy 120.490742 -281.419091) (xy 120.51432 -281.465365) (xy 120.530368 -281.514758) (xy 120.538493 -281.566053)
			(xy 120.539002 -281.59202) (xy 120.538493 -281.617987) (xy 120.818403 -281.617987) (xy 120.818403 -281.566053)
			(xy 120.826528 -281.514758) (xy 120.842576 -281.465365) (xy 120.866154 -281.419091) (xy 120.89668 -281.377075)
			(xy 120.933403 -281.340352) (xy 120.975419 -281.309826) (xy 121.021693 -281.286248) (xy 121.071086 -281.2702)
			(xy 121.122381 -281.262075) (xy 121.174315 -281.262075) (xy 121.22561 -281.2702) (xy 121.275003 -281.286248)
			(xy 121.321277 -281.309826) (xy 121.363293 -281.340352) (xy 121.400016 -281.377075) (xy 121.430542 -281.419091)
			(xy 121.45412 -281.465365) (xy 121.470168 -281.514758) (xy 121.478293 -281.566053) (xy 121.478802 -281.59202)
			(xy 121.478293 -281.617987) (xy 121.758203 -281.617987) (xy 121.758203 -281.566053) (xy 121.766328 -281.514758)
			(xy 121.782376 -281.465365) (xy 121.805954 -281.419091) (xy 121.83648 -281.377075) (xy 121.873203 -281.340352)
			(xy 121.915219 -281.309826) (xy 121.961493 -281.286248) (xy 122.010886 -281.2702) (xy 122.062181 -281.262075)
			(xy 122.114115 -281.262075) (xy 122.16541 -281.2702) (xy 122.214803 -281.286248) (xy 122.261077 -281.309826)
			(xy 122.303093 -281.340352) (xy 122.339816 -281.377075) (xy 122.370342 -281.419091) (xy 122.39392 -281.465365)
			(xy 122.409968 -281.514758) (xy 122.418093 -281.566053) (xy 122.418602 -281.59202) (xy 122.418093 -281.617987)
			(xy 122.698003 -281.617987) (xy 122.698003 -281.566053) (xy 122.706128 -281.514758) (xy 122.722176 -281.465365)
			(xy 122.745754 -281.419091) (xy 122.77628 -281.377075) (xy 122.813003 -281.340352) (xy 122.855019 -281.309826)
			(xy 122.901293 -281.286248) (xy 122.950686 -281.2702) (xy 123.001981 -281.262075) (xy 123.053915 -281.262075)
			(xy 123.10521 -281.2702) (xy 123.154603 -281.286248) (xy 123.200877 -281.309826) (xy 123.242893 -281.340352)
			(xy 123.279616 -281.377075) (xy 123.310142 -281.419091) (xy 123.33372 -281.465365) (xy 123.349768 -281.514758)
			(xy 123.357893 -281.566053) (xy 123.358402 -281.59202) (xy 123.357893 -281.617987) (xy 123.637803 -281.617987)
			(xy 123.637803 -281.566053) (xy 123.645928 -281.514758) (xy 123.661976 -281.465365) (xy 123.685554 -281.419091)
			(xy 123.71608 -281.377075) (xy 123.752803 -281.340352) (xy 123.794819 -281.309826) (xy 123.841093 -281.286248)
			(xy 123.890486 -281.2702) (xy 123.941781 -281.262075) (xy 123.993715 -281.262075) (xy 124.04501 -281.2702)
			(xy 124.094403 -281.286248) (xy 124.140677 -281.309826) (xy 124.182693 -281.340352) (xy 124.219416 -281.377075)
			(xy 124.249942 -281.419091) (xy 124.27352 -281.465365) (xy 124.289568 -281.514758) (xy 124.297693 -281.566053)
			(xy 124.298202 -281.59202) (xy 124.297693 -281.617987) (xy 124.577603 -281.617987) (xy 124.577603 -281.566053)
			(xy 124.585728 -281.514758) (xy 124.601776 -281.465365) (xy 124.625354 -281.419091) (xy 124.65588 -281.377075)
			(xy 124.692603 -281.340352) (xy 124.734619 -281.309826) (xy 124.780893 -281.286248) (xy 124.830286 -281.2702)
			(xy 124.881581 -281.262075) (xy 124.933515 -281.262075) (xy 124.98481 -281.2702) (xy 125.034203 -281.286248)
			(xy 125.080477 -281.309826) (xy 125.122493 -281.340352) (xy 125.159216 -281.377075) (xy 125.189742 -281.419091)
			(xy 125.21332 -281.465365) (xy 125.229368 -281.514758) (xy 125.237493 -281.566053) (xy 125.238002 -281.59202)
			(xy 125.237493 -281.617987) (xy 125.517403 -281.617987) (xy 125.517403 -281.566053) (xy 125.525528 -281.514758)
			(xy 125.541576 -281.465365) (xy 125.565154 -281.419091) (xy 125.59568 -281.377075) (xy 125.632403 -281.340352)
			(xy 125.674419 -281.309826) (xy 125.720693 -281.286248) (xy 125.770086 -281.2702) (xy 125.821381 -281.262075)
			(xy 125.873315 -281.262075) (xy 125.92461 -281.2702) (xy 125.974003 -281.286248) (xy 126.020277 -281.309826)
			(xy 126.062293 -281.340352) (xy 126.099016 -281.377075) (xy 126.129542 -281.419091) (xy 126.15312 -281.465365)
			(xy 126.169168 -281.514758) (xy 126.177293 -281.566053) (xy 126.177802 -281.59202) (xy 126.177293 -281.617987)
			(xy 126.456949 -281.617987) (xy 126.456949 -281.566053) (xy 126.465074 -281.514758) (xy 126.481122 -281.465365)
			(xy 126.5047 -281.419091) (xy 126.535226 -281.377075) (xy 126.571949 -281.340352) (xy 126.613965 -281.309826)
			(xy 126.660239 -281.286248) (xy 126.709632 -281.2702) (xy 126.760927 -281.262075) (xy 126.812861 -281.262075)
			(xy 126.864156 -281.2702) (xy 126.913549 -281.286248) (xy 126.959823 -281.309826) (xy 127.001839 -281.340352)
			(xy 127.038562 -281.377075) (xy 127.069088 -281.419091) (xy 127.092666 -281.465365) (xy 127.108714 -281.514758)
			(xy 127.116839 -281.566053) (xy 127.117348 -281.59202) (xy 127.116844 -281.617733) (xy 127.396749 -281.617733)
			(xy 127.396749 -281.565799) (xy 127.404874 -281.514504) (xy 127.420922 -281.465111) (xy 127.4445 -281.418837)
			(xy 127.475026 -281.376821) (xy 127.511749 -281.340098) (xy 127.553765 -281.309572) (xy 127.600039 -281.285994)
			(xy 127.649432 -281.269946) (xy 127.700727 -281.261821) (xy 127.752661 -281.261821) (xy 127.803956 -281.269946)
			(xy 127.853349 -281.285994) (xy 127.899623 -281.309572) (xy 127.941639 -281.340098) (xy 127.978362 -281.376821)
			(xy 128.008888 -281.418837) (xy 128.032466 -281.465111) (xy 128.048514 -281.514504) (xy 128.056639 -281.565799)
			(xy 128.057148 -281.591766) (xy 128.056639 -281.617733) (xy 128.056599 -281.617987) (xy 128.336803 -281.617987)
			(xy 128.336803 -281.566053) (xy 128.344928 -281.514758) (xy 128.360976 -281.465365) (xy 128.384554 -281.419091)
			(xy 128.41508 -281.377075) (xy 128.451803 -281.340352) (xy 128.493819 -281.309826) (xy 128.540093 -281.286248)
			(xy 128.589486 -281.2702) (xy 128.640781 -281.262075) (xy 128.692715 -281.262075) (xy 128.74401 -281.2702)
			(xy 128.793403 -281.286248) (xy 128.839677 -281.309826) (xy 128.881693 -281.340352) (xy 128.918416 -281.377075)
			(xy 128.948942 -281.419091) (xy 128.97252 -281.465365) (xy 128.988568 -281.514758) (xy 128.996693 -281.566053)
			(xy 128.997202 -281.59202) (xy 128.996693 -281.617987) (xy 129.276349 -281.617987) (xy 129.276349 -281.566053)
			(xy 129.284474 -281.514758) (xy 129.300522 -281.465365) (xy 129.3241 -281.419091) (xy 129.354626 -281.377075)
			(xy 129.391349 -281.340352) (xy 129.433365 -281.309826) (xy 129.479639 -281.286248) (xy 129.529032 -281.2702)
			(xy 129.580327 -281.262075) (xy 129.632261 -281.262075) (xy 129.683556 -281.2702) (xy 129.732949 -281.286248)
			(xy 129.779223 -281.309826) (xy 129.821239 -281.340352) (xy 129.857962 -281.377075) (xy 129.888488 -281.419091)
			(xy 129.912066 -281.465365) (xy 129.928114 -281.514758) (xy 129.936239 -281.566053) (xy 129.936748 -281.59202)
			(xy 129.936239 -281.617987) (xy 130.216403 -281.617987) (xy 130.216403 -281.566053) (xy 130.224528 -281.514758)
			(xy 130.240576 -281.465365) (xy 130.264154 -281.419091) (xy 130.29468 -281.377075) (xy 130.331403 -281.340352)
			(xy 130.373419 -281.309826) (xy 130.419693 -281.286248) (xy 130.469086 -281.2702) (xy 130.520381 -281.262075)
			(xy 130.572315 -281.262075) (xy 130.62361 -281.2702) (xy 130.673003 -281.286248) (xy 130.719277 -281.309826)
			(xy 130.761293 -281.340352) (xy 130.798016 -281.377075) (xy 130.828542 -281.419091) (xy 130.85212 -281.465365)
			(xy 130.868168 -281.514758) (xy 130.876293 -281.566053) (xy 130.876802 -281.59202) (xy 130.876293 -281.617987)
			(xy 131.156203 -281.617987) (xy 131.156203 -281.566053) (xy 131.164328 -281.514758) (xy 131.180376 -281.465365)
			(xy 131.203954 -281.419091) (xy 131.23448 -281.377075) (xy 131.271203 -281.340352) (xy 131.313219 -281.309826)
			(xy 131.359493 -281.286248) (xy 131.408886 -281.2702) (xy 131.460181 -281.262075) (xy 131.512115 -281.262075)
			(xy 131.56341 -281.2702) (xy 131.612803 -281.286248) (xy 131.659077 -281.309826) (xy 131.701093 -281.340352)
			(xy 131.737816 -281.377075) (xy 131.768342 -281.419091) (xy 131.79192 -281.465365) (xy 131.807968 -281.514758)
			(xy 131.816093 -281.566053) (xy 131.816602 -281.59202) (xy 131.816093 -281.617987) (xy 132.096003 -281.617987)
			(xy 132.096003 -281.566053) (xy 132.104128 -281.514758) (xy 132.120176 -281.465365) (xy 132.143754 -281.419091)
			(xy 132.17428 -281.377075) (xy 132.211003 -281.340352) (xy 132.253019 -281.309826) (xy 132.299293 -281.286248)
			(xy 132.348686 -281.2702) (xy 132.399981 -281.262075) (xy 132.451915 -281.262075) (xy 132.50321 -281.2702)
			(xy 132.552603 -281.286248) (xy 132.598877 -281.309826) (xy 132.640893 -281.340352) (xy 132.677616 -281.377075)
			(xy 132.708142 -281.419091) (xy 132.73172 -281.465365) (xy 132.747768 -281.514758) (xy 132.755893 -281.566053)
			(xy 132.756402 -281.59202) (xy 132.755893 -281.617987) (xy 133.035803 -281.617987) (xy 133.035803 -281.566053)
			(xy 133.043928 -281.514758) (xy 133.059976 -281.465365) (xy 133.083554 -281.419091) (xy 133.11408 -281.377075)
			(xy 133.150803 -281.340352) (xy 133.192819 -281.309826) (xy 133.239093 -281.286248) (xy 133.288486 -281.2702)
			(xy 133.339781 -281.262075) (xy 133.391715 -281.262075) (xy 133.44301 -281.2702) (xy 133.492403 -281.286248)
			(xy 133.538677 -281.309826) (xy 133.580693 -281.340352) (xy 133.617416 -281.377075) (xy 133.647942 -281.419091)
			(xy 133.67152 -281.465365) (xy 133.687568 -281.514758) (xy 133.695693 -281.566053) (xy 133.696202 -281.59202)
			(xy 133.695693 -281.617987) (xy 133.975603 -281.617987) (xy 133.975603 -281.566053) (xy 133.983728 -281.514758)
			(xy 133.999776 -281.465365) (xy 134.023354 -281.419091) (xy 134.05388 -281.377075) (xy 134.090603 -281.340352)
			(xy 134.132619 -281.309826) (xy 134.178893 -281.286248) (xy 134.228286 -281.2702) (xy 134.279581 -281.262075)
			(xy 134.331515 -281.262075) (xy 134.38281 -281.2702) (xy 134.432203 -281.286248) (xy 134.478477 -281.309826)
			(xy 134.520493 -281.340352) (xy 134.557216 -281.377075) (xy 134.587742 -281.419091) (xy 134.61132 -281.465365)
			(xy 134.627368 -281.514758) (xy 134.635493 -281.566053) (xy 134.636002 -281.59202) (xy 134.635493 -281.617987)
			(xy 134.915149 -281.617987) (xy 134.915149 -281.566053) (xy 134.923274 -281.514758) (xy 134.939322 -281.465365)
			(xy 134.9629 -281.419091) (xy 134.993426 -281.377075) (xy 135.030149 -281.340352) (xy 135.072165 -281.309826)
			(xy 135.118439 -281.286248) (xy 135.167832 -281.2702) (xy 135.219127 -281.262075) (xy 135.271061 -281.262075)
			(xy 135.322356 -281.2702) (xy 135.371749 -281.286248) (xy 135.418023 -281.309826) (xy 135.460039 -281.340352)
			(xy 135.496762 -281.377075) (xy 135.527288 -281.419091) (xy 135.550866 -281.465365) (xy 135.566914 -281.514758)
			(xy 135.575039 -281.566053) (xy 135.575548 -281.59202) (xy 135.575039 -281.617987) (xy 135.566914 -281.669282)
			(xy 135.550866 -281.718675) (xy 135.527288 -281.764949) (xy 135.496762 -281.806965) (xy 135.460039 -281.843688)
			(xy 135.418023 -281.874214) (xy 135.371749 -281.897792) (xy 135.322356 -281.91384) (xy 135.271061 -281.921965)
			(xy 135.219127 -281.921965) (xy 135.167832 -281.91384) (xy 135.118439 -281.897792) (xy 135.072165 -281.874214)
			(xy 135.030149 -281.843688) (xy 134.993426 -281.806965) (xy 134.9629 -281.764949) (xy 134.939322 -281.718675)
			(xy 134.923274 -281.669282) (xy 134.915149 -281.617987) (xy 134.635493 -281.617987) (xy 134.627368 -281.669282)
			(xy 134.61132 -281.718675) (xy 134.587742 -281.764949) (xy 134.557216 -281.806965) (xy 134.520493 -281.843688)
			(xy 134.478477 -281.874214) (xy 134.432203 -281.897792) (xy 134.38281 -281.91384) (xy 134.331515 -281.921965)
			(xy 134.279581 -281.921965) (xy 134.228286 -281.91384) (xy 134.178893 -281.897792) (xy 134.132619 -281.874214)
			(xy 134.090603 -281.843688) (xy 134.05388 -281.806965) (xy 134.023354 -281.764949) (xy 133.999776 -281.718675)
			(xy 133.983728 -281.669282) (xy 133.975603 -281.617987) (xy 133.695693 -281.617987) (xy 133.687568 -281.669282)
			(xy 133.67152 -281.718675) (xy 133.647942 -281.764949) (xy 133.617416 -281.806965) (xy 133.580693 -281.843688)
			(xy 133.538677 -281.874214) (xy 133.492403 -281.897792) (xy 133.44301 -281.91384) (xy 133.391715 -281.921965)
			(xy 133.339781 -281.921965) (xy 133.288486 -281.91384) (xy 133.239093 -281.897792) (xy 133.192819 -281.874214)
			(xy 133.150803 -281.843688) (xy 133.11408 -281.806965) (xy 133.083554 -281.764949) (xy 133.059976 -281.718675)
			(xy 133.043928 -281.669282) (xy 133.035803 -281.617987) (xy 132.755893 -281.617987) (xy 132.747768 -281.669282)
			(xy 132.73172 -281.718675) (xy 132.708142 -281.764949) (xy 132.677616 -281.806965) (xy 132.640893 -281.843688)
			(xy 132.598877 -281.874214) (xy 132.552603 -281.897792) (xy 132.50321 -281.91384) (xy 132.451915 -281.921965)
			(xy 132.399981 -281.921965) (xy 132.348686 -281.91384) (xy 132.299293 -281.897792) (xy 132.253019 -281.874214)
			(xy 132.211003 -281.843688) (xy 132.17428 -281.806965) (xy 132.143754 -281.764949) (xy 132.120176 -281.718675)
			(xy 132.104128 -281.669282) (xy 132.096003 -281.617987) (xy 131.816093 -281.617987) (xy 131.807968 -281.669282)
			(xy 131.79192 -281.718675) (xy 131.768342 -281.764949) (xy 131.737816 -281.806965) (xy 131.701093 -281.843688)
			(xy 131.659077 -281.874214) (xy 131.612803 -281.897792) (xy 131.56341 -281.91384) (xy 131.512115 -281.921965)
			(xy 131.460181 -281.921965) (xy 131.408886 -281.91384) (xy 131.359493 -281.897792) (xy 131.313219 -281.874214)
			(xy 131.271203 -281.843688) (xy 131.23448 -281.806965) (xy 131.203954 -281.764949) (xy 131.180376 -281.718675)
			(xy 131.164328 -281.669282) (xy 131.156203 -281.617987) (xy 130.876293 -281.617987) (xy 130.868168 -281.669282)
			(xy 130.85212 -281.718675) (xy 130.828542 -281.764949) (xy 130.798016 -281.806965) (xy 130.761293 -281.843688)
			(xy 130.719277 -281.874214) (xy 130.673003 -281.897792) (xy 130.62361 -281.91384) (xy 130.572315 -281.921965)
			(xy 130.520381 -281.921965) (xy 130.469086 -281.91384) (xy 130.419693 -281.897792) (xy 130.373419 -281.874214)
			(xy 130.331403 -281.843688) (xy 130.29468 -281.806965) (xy 130.264154 -281.764949) (xy 130.240576 -281.718675)
			(xy 130.224528 -281.669282) (xy 130.216403 -281.617987) (xy 129.936239 -281.617987) (xy 129.928114 -281.669282)
			(xy 129.912066 -281.718675) (xy 129.888488 -281.764949) (xy 129.857962 -281.806965) (xy 129.821239 -281.843688)
			(xy 129.779223 -281.874214) (xy 129.732949 -281.897792) (xy 129.683556 -281.91384) (xy 129.632261 -281.921965)
			(xy 129.580327 -281.921965) (xy 129.529032 -281.91384) (xy 129.479639 -281.897792) (xy 129.433365 -281.874214)
			(xy 129.391349 -281.843688) (xy 129.354626 -281.806965) (xy 129.3241 -281.764949) (xy 129.300522 -281.718675)
			(xy 129.284474 -281.669282) (xy 129.276349 -281.617987) (xy 128.996693 -281.617987) (xy 128.988568 -281.669282)
			(xy 128.97252 -281.718675) (xy 128.948942 -281.764949) (xy 128.918416 -281.806965) (xy 128.881693 -281.843688)
			(xy 128.839677 -281.874214) (xy 128.793403 -281.897792) (xy 128.74401 -281.91384) (xy 128.692715 -281.921965)
			(xy 128.640781 -281.921965) (xy 128.589486 -281.91384) (xy 128.540093 -281.897792) (xy 128.493819 -281.874214)
			(xy 128.451803 -281.843688) (xy 128.41508 -281.806965) (xy 128.384554 -281.764949) (xy 128.360976 -281.718675)
			(xy 128.344928 -281.669282) (xy 128.336803 -281.617987) (xy 128.056599 -281.617987) (xy 128.048514 -281.669028)
			(xy 128.032466 -281.718421) (xy 128.008888 -281.764695) (xy 127.978362 -281.806711) (xy 127.941639 -281.843434)
			(xy 127.899623 -281.87396) (xy 127.853349 -281.897538) (xy 127.803956 -281.913586) (xy 127.752661 -281.921711)
			(xy 127.700727 -281.921711) (xy 127.649432 -281.913586) (xy 127.600039 -281.897538) (xy 127.553765 -281.87396)
			(xy 127.511749 -281.843434) (xy 127.475026 -281.806711) (xy 127.4445 -281.764695) (xy 127.420922 -281.718421)
			(xy 127.404874 -281.669028) (xy 127.396749 -281.617733) (xy 127.116844 -281.617733) (xy 127.116839 -281.617987)
			(xy 127.108714 -281.669282) (xy 127.092666 -281.718675) (xy 127.069088 -281.764949) (xy 127.038562 -281.806965)
			(xy 127.001839 -281.843688) (xy 126.959823 -281.874214) (xy 126.913549 -281.897792) (xy 126.864156 -281.91384)
			(xy 126.812861 -281.921965) (xy 126.760927 -281.921965) (xy 126.709632 -281.91384) (xy 126.660239 -281.897792)
			(xy 126.613965 -281.874214) (xy 126.571949 -281.843688) (xy 126.535226 -281.806965) (xy 126.5047 -281.764949)
			(xy 126.481122 -281.718675) (xy 126.465074 -281.669282) (xy 126.456949 -281.617987) (xy 126.177293 -281.617987)
			(xy 126.169168 -281.669282) (xy 126.15312 -281.718675) (xy 126.129542 -281.764949) (xy 126.099016 -281.806965)
			(xy 126.062293 -281.843688) (xy 126.020277 -281.874214) (xy 125.974003 -281.897792) (xy 125.92461 -281.91384)
			(xy 125.873315 -281.921965) (xy 125.821381 -281.921965) (xy 125.770086 -281.91384) (xy 125.720693 -281.897792)
			(xy 125.674419 -281.874214) (xy 125.632403 -281.843688) (xy 125.59568 -281.806965) (xy 125.565154 -281.764949)
			(xy 125.541576 -281.718675) (xy 125.525528 -281.669282) (xy 125.517403 -281.617987) (xy 125.237493 -281.617987)
			(xy 125.229368 -281.669282) (xy 125.21332 -281.718675) (xy 125.189742 -281.764949) (xy 125.159216 -281.806965)
			(xy 125.122493 -281.843688) (xy 125.080477 -281.874214) (xy 125.034203 -281.897792) (xy 124.98481 -281.91384)
			(xy 124.933515 -281.921965) (xy 124.881581 -281.921965) (xy 124.830286 -281.91384) (xy 124.780893 -281.897792)
			(xy 124.734619 -281.874214) (xy 124.692603 -281.843688) (xy 124.65588 -281.806965) (xy 124.625354 -281.764949)
			(xy 124.601776 -281.718675) (xy 124.585728 -281.669282) (xy 124.577603 -281.617987) (xy 124.297693 -281.617987)
			(xy 124.289568 -281.669282) (xy 124.27352 -281.718675) (xy 124.249942 -281.764949) (xy 124.219416 -281.806965)
			(xy 124.182693 -281.843688) (xy 124.140677 -281.874214) (xy 124.094403 -281.897792) (xy 124.04501 -281.91384)
			(xy 123.993715 -281.921965) (xy 123.941781 -281.921965) (xy 123.890486 -281.91384) (xy 123.841093 -281.897792)
			(xy 123.794819 -281.874214) (xy 123.752803 -281.843688) (xy 123.71608 -281.806965) (xy 123.685554 -281.764949)
			(xy 123.661976 -281.718675) (xy 123.645928 -281.669282) (xy 123.637803 -281.617987) (xy 123.357893 -281.617987)
			(xy 123.349768 -281.669282) (xy 123.33372 -281.718675) (xy 123.310142 -281.764949) (xy 123.279616 -281.806965)
			(xy 123.242893 -281.843688) (xy 123.200877 -281.874214) (xy 123.154603 -281.897792) (xy 123.10521 -281.91384)
			(xy 123.053915 -281.921965) (xy 123.001981 -281.921965) (xy 122.950686 -281.91384) (xy 122.901293 -281.897792)
			(xy 122.855019 -281.874214) (xy 122.813003 -281.843688) (xy 122.77628 -281.806965) (xy 122.745754 -281.764949)
			(xy 122.722176 -281.718675) (xy 122.706128 -281.669282) (xy 122.698003 -281.617987) (xy 122.418093 -281.617987)
			(xy 122.409968 -281.669282) (xy 122.39392 -281.718675) (xy 122.370342 -281.764949) (xy 122.339816 -281.806965)
			(xy 122.303093 -281.843688) (xy 122.261077 -281.874214) (xy 122.214803 -281.897792) (xy 122.16541 -281.91384)
			(xy 122.114115 -281.921965) (xy 122.062181 -281.921965) (xy 122.010886 -281.91384) (xy 121.961493 -281.897792)
			(xy 121.915219 -281.874214) (xy 121.873203 -281.843688) (xy 121.83648 -281.806965) (xy 121.805954 -281.764949)
			(xy 121.782376 -281.718675) (xy 121.766328 -281.669282) (xy 121.758203 -281.617987) (xy 121.478293 -281.617987)
			(xy 121.470168 -281.669282) (xy 121.45412 -281.718675) (xy 121.430542 -281.764949) (xy 121.400016 -281.806965)
			(xy 121.363293 -281.843688) (xy 121.321277 -281.874214) (xy 121.275003 -281.897792) (xy 121.22561 -281.91384)
			(xy 121.174315 -281.921965) (xy 121.122381 -281.921965) (xy 121.071086 -281.91384) (xy 121.021693 -281.897792)
			(xy 120.975419 -281.874214) (xy 120.933403 -281.843688) (xy 120.89668 -281.806965) (xy 120.866154 -281.764949)
			(xy 120.842576 -281.718675) (xy 120.826528 -281.669282) (xy 120.818403 -281.617987) (xy 120.538493 -281.617987)
			(xy 120.530368 -281.669282) (xy 120.51432 -281.718675) (xy 120.490742 -281.764949) (xy 120.460216 -281.806965)
			(xy 120.423493 -281.843688) (xy 120.381477 -281.874214) (xy 120.335203 -281.897792) (xy 120.28581 -281.91384)
			(xy 120.234515 -281.921965) (xy 120.182581 -281.921965) (xy 120.131286 -281.91384) (xy 120.081893 -281.897792)
			(xy 120.035619 -281.874214) (xy 119.993603 -281.843688) (xy 119.95688 -281.806965) (xy 119.926354 -281.764949)
			(xy 119.902776 -281.718675) (xy 119.886728 -281.669282) (xy 119.878603 -281.617987) (xy 119.598693 -281.617987)
			(xy 119.590568 -281.669282) (xy 119.57452 -281.718675) (xy 119.550942 -281.764949) (xy 119.520416 -281.806965)
			(xy 119.483693 -281.843688) (xy 119.441677 -281.874214) (xy 119.395403 -281.897792) (xy 119.34601 -281.91384)
			(xy 119.294715 -281.921965) (xy 119.242781 -281.921965) (xy 119.191486 -281.91384) (xy 119.142093 -281.897792)
			(xy 119.095819 -281.874214) (xy 119.053803 -281.843688) (xy 119.01708 -281.806965) (xy 118.986554 -281.764949)
			(xy 118.962976 -281.718675) (xy 118.946928 -281.669282) (xy 118.938803 -281.617987) (xy 118.658164 -281.617987)
			(xy 118.656608 -281.637994) (xy 119.288052 -282.269438) (xy 119.297866 -282.278678) (xy 119.321232 -282.292095)
			(xy 119.347297 -282.298927) (xy 119.37424 -282.298695) (xy 119.400184 -282.291417) (xy 119.423316 -282.2776)
			(xy 119.442024 -282.258208) (xy 119.448834 -282.246578) (xy 119.461404 -282.224706) (xy 119.492146 -282.18471)
			(xy 119.528609 -282.149852) (xy 119.569947 -282.12094) (xy 119.615199 -282.098647) (xy 119.663313 -282.08349)
			(xy 119.713172 -282.075823) (xy 119.738394 -282.075382) (xy 119.764363 -282.075864) (xy 119.81566 -282.083989)
			(xy 119.865055 -282.100039) (xy 119.911331 -282.123619) (xy 119.953348 -282.154148) (xy 119.990072 -282.190875)
			(xy 120.020597 -282.232894) (xy 120.044173 -282.279172) (xy 120.060218 -282.328569) (xy 120.068338 -282.379867)
			(xy 120.068848 -282.405836) (xy 120.06837 -282.431056) (xy 120.068255 -282.431803) (xy 120.348249 -282.431803)
			(xy 120.348249 -282.379869) (xy 120.356374 -282.328574) (xy 120.372422 -282.279181) (xy 120.396 -282.232907)
			(xy 120.426526 -282.190891) (xy 120.463249 -282.154168) (xy 120.505265 -282.123642) (xy 120.551539 -282.100064)
			(xy 120.600932 -282.084016) (xy 120.652227 -282.075891) (xy 120.704161 -282.075891) (xy 120.755456 -282.084016)
			(xy 120.804849 -282.100064) (xy 120.851123 -282.123642) (xy 120.893139 -282.154168) (xy 120.929862 -282.190891)
			(xy 120.960388 -282.232907) (xy 120.983966 -282.279181) (xy 121.000014 -282.328574) (xy 121.008139 -282.379869)
			(xy 121.008648 -282.405836) (xy 121.008139 -282.431803) (xy 121.288049 -282.431803) (xy 121.288049 -282.379869)
			(xy 121.296174 -282.328574) (xy 121.312222 -282.279181) (xy 121.3358 -282.232907) (xy 121.366326 -282.190891)
			(xy 121.403049 -282.154168) (xy 121.445065 -282.123642) (xy 121.491339 -282.100064) (xy 121.540732 -282.084016)
			(xy 121.592027 -282.075891) (xy 121.643961 -282.075891) (xy 121.695256 -282.084016) (xy 121.744649 -282.100064)
			(xy 121.790923 -282.123642) (xy 121.832939 -282.154168) (xy 121.869662 -282.190891) (xy 121.900188 -282.232907)
			(xy 121.923766 -282.279181) (xy 121.939814 -282.328574) (xy 121.947939 -282.379869) (xy 121.948448 -282.405836)
			(xy 121.947939 -282.431803) (xy 122.227849 -282.431803) (xy 122.227849 -282.379869) (xy 122.235974 -282.328574)
			(xy 122.252022 -282.279181) (xy 122.2756 -282.232907) (xy 122.306126 -282.190891) (xy 122.342849 -282.154168)
			(xy 122.384865 -282.123642) (xy 122.431139 -282.100064) (xy 122.480532 -282.084016) (xy 122.531827 -282.075891)
			(xy 122.583761 -282.075891) (xy 122.635056 -282.084016) (xy 122.684449 -282.100064) (xy 122.730723 -282.123642)
			(xy 122.772739 -282.154168) (xy 122.809462 -282.190891) (xy 122.839988 -282.232907) (xy 122.863566 -282.279181)
			(xy 122.879614 -282.328574) (xy 122.887739 -282.379869) (xy 122.888248 -282.405836) (xy 122.887739 -282.431803)
			(xy 123.167649 -282.431803) (xy 123.167649 -282.379869) (xy 123.175774 -282.328574) (xy 123.191822 -282.279181)
			(xy 123.2154 -282.232907) (xy 123.245926 -282.190891) (xy 123.282649 -282.154168) (xy 123.324665 -282.123642)
			(xy 123.370939 -282.100064) (xy 123.420332 -282.084016) (xy 123.471627 -282.075891) (xy 123.523561 -282.075891)
			(xy 123.574856 -282.084016) (xy 123.624249 -282.100064) (xy 123.670523 -282.123642) (xy 123.712539 -282.154168)
			(xy 123.749262 -282.190891) (xy 123.779788 -282.232907) (xy 123.803366 -282.279181) (xy 123.819414 -282.328574)
			(xy 123.827539 -282.379869) (xy 123.828048 -282.405836) (xy 123.827539 -282.431803) (xy 124.107449 -282.431803)
			(xy 124.107449 -282.379869) (xy 124.115574 -282.328574) (xy 124.131622 -282.279181) (xy 124.1552 -282.232907)
			(xy 124.185726 -282.190891) (xy 124.222449 -282.154168) (xy 124.264465 -282.123642) (xy 124.310739 -282.100064)
			(xy 124.360132 -282.084016) (xy 124.411427 -282.075891) (xy 124.463361 -282.075891) (xy 124.514656 -282.084016)
			(xy 124.564049 -282.100064) (xy 124.610323 -282.123642) (xy 124.652339 -282.154168) (xy 124.689062 -282.190891)
			(xy 124.719588 -282.232907) (xy 124.743166 -282.279181) (xy 124.759214 -282.328574) (xy 124.767339 -282.379869)
			(xy 124.767848 -282.405836) (xy 124.767339 -282.431803) (xy 125.047249 -282.431803) (xy 125.047249 -282.379869)
			(xy 125.055374 -282.328574) (xy 125.071422 -282.279181) (xy 125.095 -282.232907) (xy 125.125526 -282.190891)
			(xy 125.162249 -282.154168) (xy 125.204265 -282.123642) (xy 125.250539 -282.100064) (xy 125.299932 -282.084016)
			(xy 125.351227 -282.075891) (xy 125.403161 -282.075891) (xy 125.454456 -282.084016) (xy 125.503849 -282.100064)
			(xy 125.550123 -282.123642) (xy 125.592139 -282.154168) (xy 125.628862 -282.190891) (xy 125.659388 -282.232907)
			(xy 125.682966 -282.279181) (xy 125.699014 -282.328574) (xy 125.707139 -282.379869) (xy 125.707648 -282.405836)
			(xy 125.707139 -282.431803) (xy 125.987303 -282.431803) (xy 125.987303 -282.379869) (xy 125.995428 -282.328574)
			(xy 126.011476 -282.279181) (xy 126.035054 -282.232907) (xy 126.06558 -282.190891) (xy 126.102303 -282.154168)
			(xy 126.144319 -282.123642) (xy 126.190593 -282.100064) (xy 126.239986 -282.084016) (xy 126.291281 -282.075891)
			(xy 126.343215 -282.075891) (xy 126.39451 -282.084016) (xy 126.443903 -282.100064) (xy 126.490177 -282.123642)
			(xy 126.532193 -282.154168) (xy 126.568916 -282.190891) (xy 126.599442 -282.232907) (xy 126.62302 -282.279181)
			(xy 126.639068 -282.328574) (xy 126.647193 -282.379869) (xy 126.647702 -282.405836) (xy 126.647198 -282.431549)
			(xy 126.927103 -282.431549) (xy 126.927103 -282.379615) (xy 126.935228 -282.32832) (xy 126.951276 -282.278927)
			(xy 126.974854 -282.232653) (xy 127.00538 -282.190637) (xy 127.042103 -282.153914) (xy 127.084119 -282.123388)
			(xy 127.130393 -282.09981) (xy 127.179786 -282.083762) (xy 127.231081 -282.075637) (xy 127.283015 -282.075637)
			(xy 127.33431 -282.083762) (xy 127.383703 -282.09981) (xy 127.429977 -282.123388) (xy 127.471993 -282.153914)
			(xy 127.508716 -282.190637) (xy 127.539242 -282.232653) (xy 127.56282 -282.278927) (xy 127.578868 -282.32832)
			(xy 127.586993 -282.379615) (xy 127.587502 -282.405582) (xy 127.586993 -282.431549) (xy 127.866903 -282.431549)
			(xy 127.866903 -282.379615) (xy 127.875028 -282.32832) (xy 127.891076 -282.278927) (xy 127.914654 -282.232653)
			(xy 127.94518 -282.190637) (xy 127.981903 -282.153914) (xy 128.023919 -282.123388) (xy 128.070193 -282.09981)
			(xy 128.119586 -282.083762) (xy 128.170881 -282.075637) (xy 128.222815 -282.075637) (xy 128.27411 -282.083762)
			(xy 128.323503 -282.09981) (xy 128.369777 -282.123388) (xy 128.411793 -282.153914) (xy 128.448516 -282.190637)
			(xy 128.479042 -282.232653) (xy 128.50262 -282.278927) (xy 128.518668 -282.32832) (xy 128.526793 -282.379615)
			(xy 128.527302 -282.405582) (xy 128.526793 -282.431549) (xy 128.806703 -282.431549) (xy 128.806703 -282.379615)
			(xy 128.814828 -282.32832) (xy 128.830876 -282.278927) (xy 128.854454 -282.232653) (xy 128.88498 -282.190637)
			(xy 128.921703 -282.153914) (xy 128.963719 -282.123388) (xy 129.009993 -282.09981) (xy 129.059386 -282.083762)
			(xy 129.110681 -282.075637) (xy 129.162615 -282.075637) (xy 129.21391 -282.083762) (xy 129.263303 -282.09981)
			(xy 129.309577 -282.123388) (xy 129.351593 -282.153914) (xy 129.388316 -282.190637) (xy 129.418842 -282.232653)
			(xy 129.44242 -282.278927) (xy 129.458468 -282.32832) (xy 129.466593 -282.379615) (xy 129.467102 -282.405582)
			(xy 129.466593 -282.431549) (xy 129.746503 -282.431549) (xy 129.746503 -282.379615) (xy 129.754628 -282.32832)
			(xy 129.770676 -282.278927) (xy 129.794254 -282.232653) (xy 129.82478 -282.190637) (xy 129.861503 -282.153914)
			(xy 129.903519 -282.123388) (xy 129.949793 -282.09981) (xy 129.999186 -282.083762) (xy 130.050481 -282.075637)
			(xy 130.102415 -282.075637) (xy 130.15371 -282.083762) (xy 130.203103 -282.09981) (xy 130.249377 -282.123388)
			(xy 130.291393 -282.153914) (xy 130.328116 -282.190637) (xy 130.358642 -282.232653) (xy 130.38222 -282.278927)
			(xy 130.398268 -282.32832) (xy 130.406393 -282.379615) (xy 130.406902 -282.405582) (xy 130.406393 -282.431549)
			(xy 130.406353 -282.431803) (xy 130.686049 -282.431803) (xy 130.686049 -282.379869) (xy 130.694174 -282.328574)
			(xy 130.710222 -282.279181) (xy 130.7338 -282.232907) (xy 130.764326 -282.190891) (xy 130.801049 -282.154168)
			(xy 130.843065 -282.123642) (xy 130.889339 -282.100064) (xy 130.938732 -282.084016) (xy 130.990027 -282.075891)
			(xy 131.041961 -282.075891) (xy 131.093256 -282.084016) (xy 131.142649 -282.100064) (xy 131.188923 -282.123642)
			(xy 131.230939 -282.154168) (xy 131.267662 -282.190891) (xy 131.298188 -282.232907) (xy 131.321766 -282.279181)
			(xy 131.337814 -282.328574) (xy 131.345939 -282.379869) (xy 131.346448 -282.405836) (xy 131.345939 -282.431803)
			(xy 131.625849 -282.431803) (xy 131.625849 -282.379869) (xy 131.633974 -282.328574) (xy 131.650022 -282.279181)
			(xy 131.6736 -282.232907) (xy 131.704126 -282.190891) (xy 131.740849 -282.154168) (xy 131.782865 -282.123642)
			(xy 131.829139 -282.100064) (xy 131.878532 -282.084016) (xy 131.929827 -282.075891) (xy 131.981761 -282.075891)
			(xy 132.033056 -282.084016) (xy 132.082449 -282.100064) (xy 132.128723 -282.123642) (xy 132.170739 -282.154168)
			(xy 132.207462 -282.190891) (xy 132.237988 -282.232907) (xy 132.261566 -282.279181) (xy 132.277614 -282.328574)
			(xy 132.285739 -282.379869) (xy 132.286248 -282.405836) (xy 132.285739 -282.431803) (xy 132.565649 -282.431803)
			(xy 132.565649 -282.379869) (xy 132.573774 -282.328574) (xy 132.589822 -282.279181) (xy 132.6134 -282.232907)
			(xy 132.643926 -282.190891) (xy 132.680649 -282.154168) (xy 132.722665 -282.123642) (xy 132.768939 -282.100064)
			(xy 132.818332 -282.084016) (xy 132.869627 -282.075891) (xy 132.921561 -282.075891) (xy 132.972856 -282.084016)
			(xy 133.022249 -282.100064) (xy 133.068523 -282.123642) (xy 133.110539 -282.154168) (xy 133.147262 -282.190891)
			(xy 133.177788 -282.232907) (xy 133.201366 -282.279181) (xy 133.217414 -282.328574) (xy 133.225539 -282.379869)
			(xy 133.226048 -282.405836) (xy 133.225539 -282.431803) (xy 133.505449 -282.431803) (xy 133.505449 -282.379869)
			(xy 133.513574 -282.328574) (xy 133.529622 -282.279181) (xy 133.5532 -282.232907) (xy 133.583726 -282.190891)
			(xy 133.620449 -282.154168) (xy 133.662465 -282.123642) (xy 133.708739 -282.100064) (xy 133.758132 -282.084016)
			(xy 133.809427 -282.075891) (xy 133.861361 -282.075891) (xy 133.912656 -282.084016) (xy 133.962049 -282.100064)
			(xy 134.008323 -282.123642) (xy 134.050339 -282.154168) (xy 134.087062 -282.190891) (xy 134.117588 -282.232907)
			(xy 134.141166 -282.279181) (xy 134.157214 -282.328574) (xy 134.165339 -282.379869) (xy 134.165848 -282.405836)
			(xy 134.165339 -282.431803) (xy 134.445503 -282.431803) (xy 134.445503 -282.379869) (xy 134.453628 -282.328574)
			(xy 134.469676 -282.279181) (xy 134.493254 -282.232907) (xy 134.52378 -282.190891) (xy 134.560503 -282.154168)
			(xy 134.602519 -282.123642) (xy 134.648793 -282.100064) (xy 134.698186 -282.084016) (xy 134.749481 -282.075891)
			(xy 134.801415 -282.075891) (xy 134.85271 -282.084016) (xy 134.902103 -282.100064) (xy 134.948377 -282.123642)
			(xy 134.990393 -282.154168) (xy 135.027116 -282.190891) (xy 135.057642 -282.232907) (xy 135.08122 -282.279181)
			(xy 135.097268 -282.328574) (xy 135.105393 -282.379869) (xy 135.105902 -282.405836) (xy 135.105393 -282.431803)
			(xy 135.385049 -282.431803) (xy 135.385049 -282.379869) (xy 135.393174 -282.328574) (xy 135.409222 -282.279181)
			(xy 135.4328 -282.232907) (xy 135.463326 -282.190891) (xy 135.500049 -282.154168) (xy 135.542065 -282.123642)
			(xy 135.588339 -282.100064) (xy 135.637732 -282.084016) (xy 135.689027 -282.075891) (xy 135.740961 -282.075891)
			(xy 135.792256 -282.084016) (xy 135.841649 -282.100064) (xy 135.887923 -282.123642) (xy 135.929939 -282.154168)
			(xy 135.966662 -282.190891) (xy 135.997188 -282.232907) (xy 136.020766 -282.279181) (xy 136.036814 -282.328574)
			(xy 136.044939 -282.379869) (xy 136.045448 -282.405836) (xy 136.044939 -282.431803) (xy 136.036814 -282.483098)
			(xy 136.020766 -282.532491) (xy 135.997188 -282.578765) (xy 135.966662 -282.620781) (xy 135.929939 -282.657504)
			(xy 135.887923 -282.68803) (xy 135.841649 -282.711608) (xy 135.792256 -282.727656) (xy 135.740961 -282.735781)
			(xy 135.689027 -282.735781) (xy 135.637732 -282.727656) (xy 135.588339 -282.711608) (xy 135.542065 -282.68803)
			(xy 135.500049 -282.657504) (xy 135.463326 -282.620781) (xy 135.4328 -282.578765) (xy 135.409222 -282.532491)
			(xy 135.393174 -282.483098) (xy 135.385049 -282.431803) (xy 135.105393 -282.431803) (xy 135.097268 -282.483098)
			(xy 135.08122 -282.532491) (xy 135.057642 -282.578765) (xy 135.027116 -282.620781) (xy 134.990393 -282.657504)
			(xy 134.948377 -282.68803) (xy 134.902103 -282.711608) (xy 134.85271 -282.727656) (xy 134.801415 -282.735781)
			(xy 134.749481 -282.735781) (xy 134.698186 -282.727656) (xy 134.648793 -282.711608) (xy 134.602519 -282.68803)
			(xy 134.560503 -282.657504) (xy 134.52378 -282.620781) (xy 134.493254 -282.578765) (xy 134.469676 -282.532491)
			(xy 134.453628 -282.483098) (xy 134.445503 -282.431803) (xy 134.165339 -282.431803) (xy 134.157214 -282.483098)
			(xy 134.141166 -282.532491) (xy 134.117588 -282.578765) (xy 134.087062 -282.620781) (xy 134.050339 -282.657504)
			(xy 134.008323 -282.68803) (xy 133.962049 -282.711608) (xy 133.912656 -282.727656) (xy 133.861361 -282.735781)
			(xy 133.809427 -282.735781) (xy 133.758132 -282.727656) (xy 133.708739 -282.711608) (xy 133.662465 -282.68803)
			(xy 133.620449 -282.657504) (xy 133.583726 -282.620781) (xy 133.5532 -282.578765) (xy 133.529622 -282.532491)
			(xy 133.513574 -282.483098) (xy 133.505449 -282.431803) (xy 133.225539 -282.431803) (xy 133.217414 -282.483098)
			(xy 133.201366 -282.532491) (xy 133.177788 -282.578765) (xy 133.147262 -282.620781) (xy 133.110539 -282.657504)
			(xy 133.068523 -282.68803) (xy 133.022249 -282.711608) (xy 132.972856 -282.727656) (xy 132.921561 -282.735781)
			(xy 132.869627 -282.735781) (xy 132.818332 -282.727656) (xy 132.768939 -282.711608) (xy 132.722665 -282.68803)
			(xy 132.680649 -282.657504) (xy 132.643926 -282.620781) (xy 132.6134 -282.578765) (xy 132.589822 -282.532491)
			(xy 132.573774 -282.483098) (xy 132.565649 -282.431803) (xy 132.285739 -282.431803) (xy 132.277614 -282.483098)
			(xy 132.261566 -282.532491) (xy 132.237988 -282.578765) (xy 132.207462 -282.620781) (xy 132.170739 -282.657504)
			(xy 132.128723 -282.68803) (xy 132.082449 -282.711608) (xy 132.033056 -282.727656) (xy 131.981761 -282.735781)
			(xy 131.929827 -282.735781) (xy 131.878532 -282.727656) (xy 131.829139 -282.711608) (xy 131.782865 -282.68803)
			(xy 131.740849 -282.657504) (xy 131.704126 -282.620781) (xy 131.6736 -282.578765) (xy 131.650022 -282.532491)
			(xy 131.633974 -282.483098) (xy 131.625849 -282.431803) (xy 131.345939 -282.431803) (xy 131.337814 -282.483098)
			(xy 131.321766 -282.532491) (xy 131.298188 -282.578765) (xy 131.267662 -282.620781) (xy 131.230939 -282.657504)
			(xy 131.188923 -282.68803) (xy 131.142649 -282.711608) (xy 131.093256 -282.727656) (xy 131.041961 -282.735781)
			(xy 130.990027 -282.735781) (xy 130.938732 -282.727656) (xy 130.889339 -282.711608) (xy 130.843065 -282.68803)
			(xy 130.801049 -282.657504) (xy 130.764326 -282.620781) (xy 130.7338 -282.578765) (xy 130.710222 -282.532491)
			(xy 130.694174 -282.483098) (xy 130.686049 -282.431803) (xy 130.406353 -282.431803) (xy 130.398268 -282.482844)
			(xy 130.38222 -282.532237) (xy 130.358642 -282.578511) (xy 130.328116 -282.620527) (xy 130.291393 -282.65725)
			(xy 130.249377 -282.687776) (xy 130.203103 -282.711354) (xy 130.15371 -282.727402) (xy 130.102415 -282.735527)
			(xy 130.050481 -282.735527) (xy 129.999186 -282.727402) (xy 129.949793 -282.711354) (xy 129.903519 -282.687776)
			(xy 129.861503 -282.65725) (xy 129.82478 -282.620527) (xy 129.794254 -282.578511) (xy 129.770676 -282.532237)
			(xy 129.754628 -282.482844) (xy 129.746503 -282.431549) (xy 129.466593 -282.431549) (xy 129.458468 -282.482844)
			(xy 129.44242 -282.532237) (xy 129.418842 -282.578511) (xy 129.388316 -282.620527) (xy 129.351593 -282.65725)
			(xy 129.309577 -282.687776) (xy 129.263303 -282.711354) (xy 129.21391 -282.727402) (xy 129.162615 -282.735527)
			(xy 129.110681 -282.735527) (xy 129.059386 -282.727402) (xy 129.009993 -282.711354) (xy 128.963719 -282.687776)
			(xy 128.921703 -282.65725) (xy 128.88498 -282.620527) (xy 128.854454 -282.578511) (xy 128.830876 -282.532237)
			(xy 128.814828 -282.482844) (xy 128.806703 -282.431549) (xy 128.526793 -282.431549) (xy 128.518668 -282.482844)
			(xy 128.50262 -282.532237) (xy 128.479042 -282.578511) (xy 128.448516 -282.620527) (xy 128.411793 -282.65725)
			(xy 128.369777 -282.687776) (xy 128.323503 -282.711354) (xy 128.27411 -282.727402) (xy 128.222815 -282.735527)
			(xy 128.170881 -282.735527) (xy 128.119586 -282.727402) (xy 128.070193 -282.711354) (xy 128.023919 -282.687776)
			(xy 127.981903 -282.65725) (xy 127.94518 -282.620527) (xy 127.914654 -282.578511) (xy 127.891076 -282.532237)
			(xy 127.875028 -282.482844) (xy 127.866903 -282.431549) (xy 127.586993 -282.431549) (xy 127.578868 -282.482844)
			(xy 127.56282 -282.532237) (xy 127.539242 -282.578511) (xy 127.508716 -282.620527) (xy 127.471993 -282.65725)
			(xy 127.429977 -282.687776) (xy 127.383703 -282.711354) (xy 127.33431 -282.727402) (xy 127.283015 -282.735527)
			(xy 127.231081 -282.735527) (xy 127.179786 -282.727402) (xy 127.130393 -282.711354) (xy 127.084119 -282.687776)
			(xy 127.042103 -282.65725) (xy 127.00538 -282.620527) (xy 126.974854 -282.578511) (xy 126.951276 -282.532237)
			(xy 126.935228 -282.482844) (xy 126.927103 -282.431549) (xy 126.647198 -282.431549) (xy 126.647193 -282.431803)
			(xy 126.639068 -282.483098) (xy 126.62302 -282.532491) (xy 126.599442 -282.578765) (xy 126.568916 -282.620781)
			(xy 126.532193 -282.657504) (xy 126.490177 -282.68803) (xy 126.443903 -282.711608) (xy 126.39451 -282.727656)
			(xy 126.343215 -282.735781) (xy 126.291281 -282.735781) (xy 126.239986 -282.727656) (xy 126.190593 -282.711608)
			(xy 126.144319 -282.68803) (xy 126.102303 -282.657504) (xy 126.06558 -282.620781) (xy 126.035054 -282.578765)
			(xy 126.011476 -282.532491) (xy 125.995428 -282.483098) (xy 125.987303 -282.431803) (xy 125.707139 -282.431803)
			(xy 125.699014 -282.483098) (xy 125.682966 -282.532491) (xy 125.659388 -282.578765) (xy 125.628862 -282.620781)
			(xy 125.592139 -282.657504) (xy 125.550123 -282.68803) (xy 125.503849 -282.711608) (xy 125.454456 -282.727656)
			(xy 125.403161 -282.735781) (xy 125.351227 -282.735781) (xy 125.299932 -282.727656) (xy 125.250539 -282.711608)
			(xy 125.204265 -282.68803) (xy 125.162249 -282.657504) (xy 125.125526 -282.620781) (xy 125.095 -282.578765)
			(xy 125.071422 -282.532491) (xy 125.055374 -282.483098) (xy 125.047249 -282.431803) (xy 124.767339 -282.431803)
			(xy 124.759214 -282.483098) (xy 124.743166 -282.532491) (xy 124.719588 -282.578765) (xy 124.689062 -282.620781)
			(xy 124.652339 -282.657504) (xy 124.610323 -282.68803) (xy 124.564049 -282.711608) (xy 124.514656 -282.727656)
			(xy 124.463361 -282.735781) (xy 124.411427 -282.735781) (xy 124.360132 -282.727656) (xy 124.310739 -282.711608)
			(xy 124.264465 -282.68803) (xy 124.222449 -282.657504) (xy 124.185726 -282.620781) (xy 124.1552 -282.578765)
			(xy 124.131622 -282.532491) (xy 124.115574 -282.483098) (xy 124.107449 -282.431803) (xy 123.827539 -282.431803)
			(xy 123.819414 -282.483098) (xy 123.803366 -282.532491) (xy 123.779788 -282.578765) (xy 123.749262 -282.620781)
			(xy 123.712539 -282.657504) (xy 123.670523 -282.68803) (xy 123.624249 -282.711608) (xy 123.574856 -282.727656)
			(xy 123.523561 -282.735781) (xy 123.471627 -282.735781) (xy 123.420332 -282.727656) (xy 123.370939 -282.711608)
			(xy 123.324665 -282.68803) (xy 123.282649 -282.657504) (xy 123.245926 -282.620781) (xy 123.2154 -282.578765)
			(xy 123.191822 -282.532491) (xy 123.175774 -282.483098) (xy 123.167649 -282.431803) (xy 122.887739 -282.431803)
			(xy 122.879614 -282.483098) (xy 122.863566 -282.532491) (xy 122.839988 -282.578765) (xy 122.809462 -282.620781)
			(xy 122.772739 -282.657504) (xy 122.730723 -282.68803) (xy 122.684449 -282.711608) (xy 122.635056 -282.727656)
			(xy 122.583761 -282.735781) (xy 122.531827 -282.735781) (xy 122.480532 -282.727656) (xy 122.431139 -282.711608)
			(xy 122.384865 -282.68803) (xy 122.342849 -282.657504) (xy 122.306126 -282.620781) (xy 122.2756 -282.578765)
			(xy 122.252022 -282.532491) (xy 122.235974 -282.483098) (xy 122.227849 -282.431803) (xy 121.947939 -282.431803)
			(xy 121.939814 -282.483098) (xy 121.923766 -282.532491) (xy 121.900188 -282.578765) (xy 121.869662 -282.620781)
			(xy 121.832939 -282.657504) (xy 121.790923 -282.68803) (xy 121.744649 -282.711608) (xy 121.695256 -282.727656)
			(xy 121.643961 -282.735781) (xy 121.592027 -282.735781) (xy 121.540732 -282.727656) (xy 121.491339 -282.711608)
			(xy 121.445065 -282.68803) (xy 121.403049 -282.657504) (xy 121.366326 -282.620781) (xy 121.3358 -282.578765)
			(xy 121.312222 -282.532491) (xy 121.296174 -282.483098) (xy 121.288049 -282.431803) (xy 121.008139 -282.431803)
			(xy 121.000014 -282.483098) (xy 120.983966 -282.532491) (xy 120.960388 -282.578765) (xy 120.929862 -282.620781)
			(xy 120.893139 -282.657504) (xy 120.851123 -282.68803) (xy 120.804849 -282.711608) (xy 120.755456 -282.727656)
			(xy 120.704161 -282.735781) (xy 120.652227 -282.735781) (xy 120.600932 -282.727656) (xy 120.551539 -282.711608)
			(xy 120.505265 -282.68803) (xy 120.463249 -282.657504) (xy 120.426526 -282.620781) (xy 120.396 -282.578765)
			(xy 120.372422 -282.532491) (xy 120.356374 -282.483098) (xy 120.348249 -282.431803) (xy 120.068255 -282.431803)
			(xy 120.060701 -282.480911) (xy 120.045546 -282.529021) (xy 120.023259 -282.574271) (xy 119.994355 -282.615609)
			(xy 119.959506 -282.652076) (xy 119.919521 -282.682825) (xy 119.897652 -282.695396) (xy 119.886069 -282.702264)
			(xy 119.866721 -282.72098) (xy 119.852935 -282.744101) (xy 119.845667 -282.770021) (xy 119.845422 -282.796939)
			(xy 119.852218 -282.822986) (xy 119.865582 -282.846354) (xy 119.874792 -282.856178) (xy 119.988584 -282.96997)
			(xy 120.023128 -282.946348) (xy 120.043765 -282.932919) (xy 120.088173 -282.911657) (xy 120.135241 -282.897209)
			(xy 120.18393 -282.889892) (xy 120.208548 -282.889452) (xy 120.234512 -282.889965) (xy 120.285801 -282.898095)
			(xy 120.335186 -282.914148) (xy 120.381452 -282.937727) (xy 120.423461 -282.968254) (xy 120.460177 -283.004976)
			(xy 120.490698 -283.046989) (xy 120.514271 -283.093259) (xy 120.530316 -283.142646) (xy 120.538439 -283.193936)
			(xy 120.538439 -283.245864) (xy 120.538438 -283.245873) (xy 120.818149 -283.245873) (xy 120.818149 -283.193939)
			(xy 120.826274 -283.142644) (xy 120.842322 -283.093251) (xy 120.8659 -283.046977) (xy 120.896426 -283.004961)
			(xy 120.933149 -282.968238) (xy 120.975165 -282.937712) (xy 121.021439 -282.914134) (xy 121.070832 -282.898086)
			(xy 121.122127 -282.889961) (xy 121.174061 -282.889961) (xy 121.225356 -282.898086) (xy 121.274749 -282.914134)
			(xy 121.321023 -282.937712) (xy 121.363039 -282.968238) (xy 121.399762 -283.004961) (xy 121.430288 -283.046977)
			(xy 121.453866 -283.093251) (xy 121.469914 -283.142644) (xy 121.478039 -283.193939) (xy 121.478548 -283.219906)
			(xy 121.478039 -283.245873) (xy 121.757949 -283.245873) (xy 121.757949 -283.193939) (xy 121.766074 -283.142644)
			(xy 121.782122 -283.093251) (xy 121.8057 -283.046977) (xy 121.836226 -283.004961) (xy 121.872949 -282.968238)
			(xy 121.914965 -282.937712) (xy 121.961239 -282.914134) (xy 122.010632 -282.898086) (xy 122.061927 -282.889961)
			(xy 122.113861 -282.889961) (xy 122.165156 -282.898086) (xy 122.214549 -282.914134) (xy 122.260823 -282.937712)
			(xy 122.302839 -282.968238) (xy 122.339562 -283.004961) (xy 122.370088 -283.046977) (xy 122.393666 -283.093251)
			(xy 122.409714 -283.142644) (xy 122.417839 -283.193939) (xy 122.418348 -283.219906) (xy 122.417839 -283.245873)
			(xy 122.698003 -283.245873) (xy 122.698003 -283.193939) (xy 122.706128 -283.142644) (xy 122.722176 -283.093251)
			(xy 122.745754 -283.046977) (xy 122.77628 -283.004961) (xy 122.813003 -282.968238) (xy 122.855019 -282.937712)
			(xy 122.901293 -282.914134) (xy 122.950686 -282.898086) (xy 123.001981 -282.889961) (xy 123.053915 -282.889961)
			(xy 123.10521 -282.898086) (xy 123.154603 -282.914134) (xy 123.200877 -282.937712) (xy 123.242893 -282.968238)
			(xy 123.279616 -283.004961) (xy 123.310142 -283.046977) (xy 123.33372 -283.093251) (xy 123.349768 -283.142644)
			(xy 123.357893 -283.193939) (xy 123.358402 -283.219906) (xy 123.357893 -283.245873) (xy 124.577603 -283.245873)
			(xy 124.577603 -283.193939) (xy 124.585728 -283.142644) (xy 124.601776 -283.093251) (xy 124.625354 -283.046977)
			(xy 124.65588 -283.004961) (xy 124.692603 -282.968238) (xy 124.734619 -282.937712) (xy 124.780893 -282.914134)
			(xy 124.830286 -282.898086) (xy 124.881581 -282.889961) (xy 124.933515 -282.889961) (xy 124.98481 -282.898086)
			(xy 125.034203 -282.914134) (xy 125.080477 -282.937712) (xy 125.122493 -282.968238) (xy 125.159216 -283.004961)
			(xy 125.189742 -283.046977) (xy 125.21332 -283.093251) (xy 125.229368 -283.142644) (xy 125.237493 -283.193939)
			(xy 125.238002 -283.219906) (xy 125.237493 -283.245873) (xy 125.517403 -283.245873) (xy 125.517403 -283.193939)
			(xy 125.525528 -283.142644) (xy 125.541576 -283.093251) (xy 125.565154 -283.046977) (xy 125.59568 -283.004961)
			(xy 125.632403 -282.968238) (xy 125.674419 -282.937712) (xy 125.720693 -282.914134) (xy 125.770086 -282.898086)
			(xy 125.821381 -282.889961) (xy 125.873315 -282.889961) (xy 125.92461 -282.898086) (xy 125.974003 -282.914134)
			(xy 126.020277 -282.937712) (xy 126.062293 -282.968238) (xy 126.099016 -283.004961) (xy 126.129542 -283.046977)
			(xy 126.15312 -283.093251) (xy 126.169168 -283.142644) (xy 126.177293 -283.193939) (xy 126.177802 -283.219906)
			(xy 126.177293 -283.245873) (xy 126.456949 -283.245873) (xy 126.456949 -283.193939) (xy 126.465074 -283.142644)
			(xy 126.481122 -283.093251) (xy 126.5047 -283.046977) (xy 126.535226 -283.004961) (xy 126.571949 -282.968238)
			(xy 126.613965 -282.937712) (xy 126.660239 -282.914134) (xy 126.709632 -282.898086) (xy 126.760927 -282.889961)
			(xy 126.812861 -282.889961) (xy 126.864156 -282.898086) (xy 126.913549 -282.914134) (xy 126.959823 -282.937712)
			(xy 127.001839 -282.968238) (xy 127.038562 -283.004961) (xy 127.069088 -283.046977) (xy 127.092666 -283.093251)
			(xy 127.108714 -283.142644) (xy 127.116839 -283.193939) (xy 127.117348 -283.219906) (xy 127.116844 -283.245619)
			(xy 128.336549 -283.245619) (xy 128.336549 -283.193685) (xy 128.344674 -283.14239) (xy 128.360722 -283.092997)
			(xy 128.3843 -283.046723) (xy 128.414826 -283.004707) (xy 128.451549 -282.967984) (xy 128.493565 -282.937458)
			(xy 128.539839 -282.91388) (xy 128.589232 -282.897832) (xy 128.640527 -282.889707) (xy 128.692461 -282.889707)
			(xy 128.743756 -282.897832) (xy 128.793149 -282.91388) (xy 128.839423 -282.937458) (xy 128.881439 -282.967984)
			(xy 128.918162 -283.004707) (xy 128.948688 -283.046723) (xy 128.972266 -283.092997) (xy 128.988314 -283.14239)
			(xy 128.996439 -283.193685) (xy 128.996948 -283.219652) (xy 128.996439 -283.245619) (xy 128.996399 -283.245873)
			(xy 129.276349 -283.245873) (xy 129.276349 -283.193939) (xy 129.284474 -283.142644) (xy 129.300522 -283.093251)
			(xy 129.3241 -283.046977) (xy 129.354626 -283.004961) (xy 129.391349 -282.968238) (xy 129.433365 -282.937712)
			(xy 129.479639 -282.914134) (xy 129.529032 -282.898086) (xy 129.580327 -282.889961) (xy 129.632261 -282.889961)
			(xy 129.683556 -282.898086) (xy 129.732949 -282.914134) (xy 129.779223 -282.937712) (xy 129.821239 -282.968238)
			(xy 129.857962 -283.004961) (xy 129.888488 -283.046977) (xy 129.912066 -283.093251) (xy 129.928114 -283.142644)
			(xy 129.936239 -283.193939) (xy 129.936748 -283.219906) (xy 129.936239 -283.245873) (xy 130.216149 -283.245873)
			(xy 130.216149 -283.193939) (xy 130.224274 -283.142644) (xy 130.240322 -283.093251) (xy 130.2639 -283.046977)
			(xy 130.294426 -283.004961) (xy 130.331149 -282.968238) (xy 130.373165 -282.937712) (xy 130.419439 -282.914134)
			(xy 130.468832 -282.898086) (xy 130.520127 -282.889961) (xy 130.572061 -282.889961) (xy 130.623356 -282.898086)
			(xy 130.672749 -282.914134) (xy 130.719023 -282.937712) (xy 130.761039 -282.968238) (xy 130.797762 -283.004961)
			(xy 130.828288 -283.046977) (xy 130.851866 -283.093251) (xy 130.867914 -283.142644) (xy 130.876039 -283.193939)
			(xy 130.876548 -283.219906) (xy 130.876039 -283.245873) (xy 131.156203 -283.245873) (xy 131.156203 -283.193939)
			(xy 131.164328 -283.142644) (xy 131.180376 -283.093251) (xy 131.203954 -283.046977) (xy 131.23448 -283.004961)
			(xy 131.271203 -282.968238) (xy 131.313219 -282.937712) (xy 131.359493 -282.914134) (xy 131.408886 -282.898086)
			(xy 131.460181 -282.889961) (xy 131.512115 -282.889961) (xy 131.56341 -282.898086) (xy 131.612803 -282.914134)
			(xy 131.659077 -282.937712) (xy 131.701093 -282.968238) (xy 131.737816 -283.004961) (xy 131.768342 -283.046977)
			(xy 131.79192 -283.093251) (xy 131.807968 -283.142644) (xy 131.816093 -283.193939) (xy 131.816602 -283.219906)
			(xy 131.816093 -283.245873) (xy 132.095749 -283.245873) (xy 132.095749 -283.193939) (xy 132.103874 -283.142644)
			(xy 132.119922 -283.093251) (xy 132.1435 -283.046977) (xy 132.174026 -283.004961) (xy 132.210749 -282.968238)
			(xy 132.252765 -282.937712) (xy 132.299039 -282.914134) (xy 132.348432 -282.898086) (xy 132.399727 -282.889961)
			(xy 132.451661 -282.889961) (xy 132.502956 -282.898086) (xy 132.552349 -282.914134) (xy 132.598623 -282.937712)
			(xy 132.640639 -282.968238) (xy 132.677362 -283.004961) (xy 132.707888 -283.046977) (xy 132.731466 -283.093251)
			(xy 132.747514 -283.142644) (xy 132.755639 -283.193939) (xy 132.756148 -283.219906) (xy 132.755639 -283.245873)
			(xy 133.035803 -283.245873) (xy 133.035803 -283.193939) (xy 133.043928 -283.142644) (xy 133.059976 -283.093251)
			(xy 133.083554 -283.046977) (xy 133.11408 -283.004961) (xy 133.150803 -282.968238) (xy 133.192819 -282.937712)
			(xy 133.239093 -282.914134) (xy 133.288486 -282.898086) (xy 133.339781 -282.889961) (xy 133.391715 -282.889961)
			(xy 133.44301 -282.898086) (xy 133.492403 -282.914134) (xy 133.538677 -282.937712) (xy 133.580693 -282.968238)
			(xy 133.617416 -283.004961) (xy 133.647942 -283.046977) (xy 133.67152 -283.093251) (xy 133.687568 -283.142644)
			(xy 133.695693 -283.193939) (xy 133.696202 -283.219906) (xy 133.695693 -283.245873) (xy 133.975603 -283.245873)
			(xy 133.975603 -283.193939) (xy 133.983728 -283.142644) (xy 133.999776 -283.093251) (xy 134.023354 -283.046977)
			(xy 134.05388 -283.004961) (xy 134.090603 -282.968238) (xy 134.132619 -282.937712) (xy 134.178893 -282.914134)
			(xy 134.228286 -282.898086) (xy 134.279581 -282.889961) (xy 134.331515 -282.889961) (xy 134.38281 -282.898086)
			(xy 134.432203 -282.914134) (xy 134.478477 -282.937712) (xy 134.520493 -282.968238) (xy 134.557216 -283.004961)
			(xy 134.587742 -283.046977) (xy 134.61132 -283.093251) (xy 134.627368 -283.142644) (xy 134.635493 -283.193939)
			(xy 134.636002 -283.219906) (xy 134.635493 -283.245873) (xy 134.915149 -283.245873) (xy 134.915149 -283.193939)
			(xy 134.923274 -283.142644) (xy 134.939322 -283.093251) (xy 134.9629 -283.046977) (xy 134.993426 -283.004961)
			(xy 135.030149 -282.968238) (xy 135.072165 -282.937712) (xy 135.118439 -282.914134) (xy 135.167832 -282.898086)
			(xy 135.219127 -282.889961) (xy 135.271061 -282.889961) (xy 135.322356 -282.898086) (xy 135.371749 -282.914134)
			(xy 135.418023 -282.937712) (xy 135.460039 -282.968238) (xy 135.496762 -283.004961) (xy 135.527288 -283.046977)
			(xy 135.550866 -283.093251) (xy 135.566914 -283.142644) (xy 135.575039 -283.193939) (xy 135.575548 -283.219906)
			(xy 135.575039 -283.245873) (xy 135.854949 -283.245873) (xy 135.854949 -283.193939) (xy 135.863074 -283.142644)
			(xy 135.879122 -283.093251) (xy 135.9027 -283.046977) (xy 135.933226 -283.004961) (xy 135.969949 -282.968238)
			(xy 136.011965 -282.937712) (xy 136.058239 -282.914134) (xy 136.107632 -282.898086) (xy 136.158927 -282.889961)
			(xy 136.210861 -282.889961) (xy 136.262156 -282.898086) (xy 136.311549 -282.914134) (xy 136.357823 -282.937712)
			(xy 136.399839 -282.968238) (xy 136.436562 -283.004961) (xy 136.467088 -283.046977) (xy 136.490666 -283.093251)
			(xy 136.506714 -283.142644) (xy 136.514839 -283.193939) (xy 136.515348 -283.219906) (xy 136.514839 -283.245873)
			(xy 136.506714 -283.297168) (xy 136.490666 -283.346561) (xy 136.467088 -283.392835) (xy 136.436562 -283.434851)
			(xy 136.399839 -283.471574) (xy 136.357823 -283.5021) (xy 136.311549 -283.525678) (xy 136.262156 -283.541726)
			(xy 136.210861 -283.549851) (xy 136.158927 -283.549851) (xy 136.107632 -283.541726) (xy 136.058239 -283.525678)
			(xy 136.011965 -283.5021) (xy 135.969949 -283.471574) (xy 135.933226 -283.434851) (xy 135.9027 -283.392835)
			(xy 135.879122 -283.346561) (xy 135.863074 -283.297168) (xy 135.854949 -283.245873) (xy 135.575039 -283.245873)
			(xy 135.566914 -283.297168) (xy 135.550866 -283.346561) (xy 135.527288 -283.392835) (xy 135.496762 -283.434851)
			(xy 135.460039 -283.471574) (xy 135.418023 -283.5021) (xy 135.371749 -283.525678) (xy 135.322356 -283.541726)
			(xy 135.271061 -283.549851) (xy 135.219127 -283.549851) (xy 135.167832 -283.541726) (xy 135.118439 -283.525678)
			(xy 135.072165 -283.5021) (xy 135.030149 -283.471574) (xy 134.993426 -283.434851) (xy 134.9629 -283.392835)
			(xy 134.939322 -283.346561) (xy 134.923274 -283.297168) (xy 134.915149 -283.245873) (xy 134.635493 -283.245873)
			(xy 134.627368 -283.297168) (xy 134.61132 -283.346561) (xy 134.587742 -283.392835) (xy 134.557216 -283.434851)
			(xy 134.520493 -283.471574) (xy 134.478477 -283.5021) (xy 134.432203 -283.525678) (xy 134.38281 -283.541726)
			(xy 134.331515 -283.549851) (xy 134.279581 -283.549851) (xy 134.228286 -283.541726) (xy 134.178893 -283.525678)
			(xy 134.132619 -283.5021) (xy 134.090603 -283.471574) (xy 134.05388 -283.434851) (xy 134.023354 -283.392835)
			(xy 133.999776 -283.346561) (xy 133.983728 -283.297168) (xy 133.975603 -283.245873) (xy 133.695693 -283.245873)
			(xy 133.687568 -283.297168) (xy 133.67152 -283.346561) (xy 133.647942 -283.392835) (xy 133.617416 -283.434851)
			(xy 133.580693 -283.471574) (xy 133.538677 -283.5021) (xy 133.492403 -283.525678) (xy 133.44301 -283.541726)
			(xy 133.391715 -283.549851) (xy 133.339781 -283.549851) (xy 133.288486 -283.541726) (xy 133.239093 -283.525678)
			(xy 133.192819 -283.5021) (xy 133.150803 -283.471574) (xy 133.11408 -283.434851) (xy 133.083554 -283.392835)
			(xy 133.059976 -283.346561) (xy 133.043928 -283.297168) (xy 133.035803 -283.245873) (xy 132.755639 -283.245873)
			(xy 132.747514 -283.297168) (xy 132.731466 -283.346561) (xy 132.707888 -283.392835) (xy 132.677362 -283.434851)
			(xy 132.640639 -283.471574) (xy 132.598623 -283.5021) (xy 132.552349 -283.525678) (xy 132.502956 -283.541726)
			(xy 132.451661 -283.549851) (xy 132.399727 -283.549851) (xy 132.348432 -283.541726) (xy 132.299039 -283.525678)
			(xy 132.252765 -283.5021) (xy 132.210749 -283.471574) (xy 132.174026 -283.434851) (xy 132.1435 -283.392835)
			(xy 132.119922 -283.346561) (xy 132.103874 -283.297168) (xy 132.095749 -283.245873) (xy 131.816093 -283.245873)
			(xy 131.807968 -283.297168) (xy 131.79192 -283.346561) (xy 131.768342 -283.392835) (xy 131.737816 -283.434851)
			(xy 131.701093 -283.471574) (xy 131.659077 -283.5021) (xy 131.612803 -283.525678) (xy 131.56341 -283.541726)
			(xy 131.512115 -283.549851) (xy 131.460181 -283.549851) (xy 131.408886 -283.541726) (xy 131.359493 -283.525678)
			(xy 131.313219 -283.5021) (xy 131.271203 -283.471574) (xy 131.23448 -283.434851) (xy 131.203954 -283.392835)
			(xy 131.180376 -283.346561) (xy 131.164328 -283.297168) (xy 131.156203 -283.245873) (xy 130.876039 -283.245873)
			(xy 130.867914 -283.297168) (xy 130.851866 -283.346561) (xy 130.828288 -283.392835) (xy 130.797762 -283.434851)
			(xy 130.761039 -283.471574) (xy 130.719023 -283.5021) (xy 130.672749 -283.525678) (xy 130.623356 -283.541726)
			(xy 130.572061 -283.549851) (xy 130.520127 -283.549851) (xy 130.468832 -283.541726) (xy 130.419439 -283.525678)
			(xy 130.373165 -283.5021) (xy 130.331149 -283.471574) (xy 130.294426 -283.434851) (xy 130.2639 -283.392835)
			(xy 130.240322 -283.346561) (xy 130.224274 -283.297168) (xy 130.216149 -283.245873) (xy 129.936239 -283.245873)
			(xy 129.928114 -283.297168) (xy 129.912066 -283.346561) (xy 129.888488 -283.392835) (xy 129.857962 -283.434851)
			(xy 129.821239 -283.471574) (xy 129.779223 -283.5021) (xy 129.732949 -283.525678) (xy 129.683556 -283.541726)
			(xy 129.632261 -283.549851) (xy 129.580327 -283.549851) (xy 129.529032 -283.541726) (xy 129.479639 -283.525678)
			(xy 129.433365 -283.5021) (xy 129.391349 -283.471574) (xy 129.354626 -283.434851) (xy 129.3241 -283.392835)
			(xy 129.300522 -283.346561) (xy 129.284474 -283.297168) (xy 129.276349 -283.245873) (xy 128.996399 -283.245873)
			(xy 128.988314 -283.296914) (xy 128.972266 -283.346307) (xy 128.948688 -283.392581) (xy 128.918162 -283.434597)
			(xy 128.881439 -283.47132) (xy 128.839423 -283.501846) (xy 128.793149 -283.525424) (xy 128.743756 -283.541472)
			(xy 128.692461 -283.549597) (xy 128.640527 -283.549597) (xy 128.589232 -283.541472) (xy 128.539839 -283.525424)
			(xy 128.493565 -283.501846) (xy 128.451549 -283.47132) (xy 128.414826 -283.434597) (xy 128.3843 -283.392581)
			(xy 128.360722 -283.346307) (xy 128.344674 -283.296914) (xy 128.336549 -283.245619) (xy 127.116844 -283.245619)
			(xy 127.116839 -283.245873) (xy 127.108714 -283.297168) (xy 127.092666 -283.346561) (xy 127.069088 -283.392835)
			(xy 127.038562 -283.434851) (xy 127.001839 -283.471574) (xy 126.959823 -283.5021) (xy 126.913549 -283.525678)
			(xy 126.864156 -283.541726) (xy 126.812861 -283.549851) (xy 126.760927 -283.549851) (xy 126.709632 -283.541726)
			(xy 126.660239 -283.525678) (xy 126.613965 -283.5021) (xy 126.571949 -283.471574) (xy 126.535226 -283.434851)
			(xy 126.5047 -283.392835) (xy 126.481122 -283.346561) (xy 126.465074 -283.297168) (xy 126.456949 -283.245873)
			(xy 126.177293 -283.245873) (xy 126.169168 -283.297168) (xy 126.15312 -283.346561) (xy 126.129542 -283.392835)
			(xy 126.099016 -283.434851) (xy 126.062293 -283.471574) (xy 126.020277 -283.5021) (xy 125.974003 -283.525678)
			(xy 125.92461 -283.541726) (xy 125.873315 -283.549851) (xy 125.821381 -283.549851) (xy 125.770086 -283.541726)
			(xy 125.720693 -283.525678) (xy 125.674419 -283.5021) (xy 125.632403 -283.471574) (xy 125.59568 -283.434851)
			(xy 125.565154 -283.392835) (xy 125.541576 -283.346561) (xy 125.525528 -283.297168) (xy 125.517403 -283.245873)
			(xy 125.237493 -283.245873) (xy 125.229368 -283.297168) (xy 125.21332 -283.346561) (xy 125.189742 -283.392835)
			(xy 125.159216 -283.434851) (xy 125.122493 -283.471574) (xy 125.080477 -283.5021) (xy 125.034203 -283.525678)
			(xy 124.98481 -283.541726) (xy 124.933515 -283.549851) (xy 124.881581 -283.549851) (xy 124.830286 -283.541726)
			(xy 124.780893 -283.525678) (xy 124.734619 -283.5021) (xy 124.692603 -283.471574) (xy 124.65588 -283.434851)
			(xy 124.625354 -283.392835) (xy 124.601776 -283.346561) (xy 124.585728 -283.297168) (xy 124.577603 -283.245873)
			(xy 123.357893 -283.245873) (xy 123.349768 -283.297168) (xy 123.33372 -283.346561) (xy 123.310142 -283.392835)
			(xy 123.279616 -283.434851) (xy 123.242893 -283.471574) (xy 123.200877 -283.5021) (xy 123.154603 -283.525678)
			(xy 123.10521 -283.541726) (xy 123.053915 -283.549851) (xy 123.001981 -283.549851) (xy 122.950686 -283.541726)
			(xy 122.901293 -283.525678) (xy 122.855019 -283.5021) (xy 122.813003 -283.471574) (xy 122.77628 -283.434851)
			(xy 122.745754 -283.392835) (xy 122.722176 -283.346561) (xy 122.706128 -283.297168) (xy 122.698003 -283.245873)
			(xy 122.417839 -283.245873) (xy 122.409714 -283.297168) (xy 122.393666 -283.346561) (xy 122.370088 -283.392835)
			(xy 122.339562 -283.434851) (xy 122.302839 -283.471574) (xy 122.260823 -283.5021) (xy 122.214549 -283.525678)
			(xy 122.165156 -283.541726) (xy 122.113861 -283.549851) (xy 122.061927 -283.549851) (xy 122.010632 -283.541726)
			(xy 121.961239 -283.525678) (xy 121.914965 -283.5021) (xy 121.872949 -283.471574) (xy 121.836226 -283.434851)
			(xy 121.8057 -283.392835) (xy 121.782122 -283.346561) (xy 121.766074 -283.297168) (xy 121.757949 -283.245873)
			(xy 121.478039 -283.245873) (xy 121.469914 -283.297168) (xy 121.453866 -283.346561) (xy 121.430288 -283.392835)
			(xy 121.399762 -283.434851) (xy 121.363039 -283.471574) (xy 121.321023 -283.5021) (xy 121.274749 -283.525678)
			(xy 121.225356 -283.541726) (xy 121.174061 -283.549851) (xy 121.122127 -283.549851) (xy 121.070832 -283.541726)
			(xy 121.021439 -283.525678) (xy 120.975165 -283.5021) (xy 120.933149 -283.471574) (xy 120.896426 -283.434851)
			(xy 120.8659 -283.392835) (xy 120.842322 -283.346561) (xy 120.826274 -283.297168) (xy 120.818149 -283.245873)
			(xy 120.538438 -283.245873) (xy 120.530316 -283.297154) (xy 120.514271 -283.346541) (xy 120.490698 -283.392811)
			(xy 120.460177 -283.434824) (xy 120.423461 -283.471546) (xy 120.381452 -283.502073) (xy 120.335186 -283.525652)
			(xy 120.285801 -283.541705) (xy 120.234512 -283.549835) (xy 120.208548 -283.55036) (xy 120.18801 -283.550045)
			(xy 120.147253 -283.544945) (xy 120.127268 -283.5402) (xy 120.112152 -283.536895) (xy 120.081268 -283.538545)
			(xy 120.052292 -283.549358) (xy 120.027878 -283.568343) (xy 120.01026 -283.593762) (xy 120.001053 -283.623287)
			(xy 120.000522 -283.638752) (xy 120.000522 -283.832554) (xy 120.01657 -283.85434) (xy 120.042089 -283.90205)
			(xy 120.059489 -283.953282) (xy 120.068306 -284.006664) (xy 120.068303 -284.059689) (xy 120.348249 -284.059689)
			(xy 120.348249 -284.007755) (xy 120.356374 -283.95646) (xy 120.372422 -283.907067) (xy 120.396 -283.860793)
			(xy 120.426526 -283.818777) (xy 120.463249 -283.782054) (xy 120.505265 -283.751528) (xy 120.551539 -283.72795)
			(xy 120.600932 -283.711902) (xy 120.652227 -283.703777) (xy 120.704161 -283.703777) (xy 120.755456 -283.711902)
			(xy 120.804849 -283.72795) (xy 120.851123 -283.751528) (xy 120.893139 -283.782054) (xy 120.929862 -283.818777)
			(xy 120.960388 -283.860793) (xy 120.983966 -283.907067) (xy 121.000014 -283.95646) (xy 121.008139 -284.007755)
			(xy 121.008648 -284.033722) (xy 121.008139 -284.059689) (xy 121.288049 -284.059689) (xy 121.288049 -284.007755)
			(xy 121.296174 -283.95646) (xy 121.312222 -283.907067) (xy 121.3358 -283.860793) (xy 121.366326 -283.818777)
			(xy 121.403049 -283.782054) (xy 121.445065 -283.751528) (xy 121.491339 -283.72795) (xy 121.540732 -283.711902)
			(xy 121.592027 -283.703777) (xy 121.643961 -283.703777) (xy 121.695256 -283.711902) (xy 121.744649 -283.72795)
			(xy 121.790923 -283.751528) (xy 121.832939 -283.782054) (xy 121.869662 -283.818777) (xy 121.900188 -283.860793)
			(xy 121.923766 -283.907067) (xy 121.939814 -283.95646) (xy 121.947939 -284.007755) (xy 121.948448 -284.033722)
			(xy 121.947939 -284.059689) (xy 122.227849 -284.059689) (xy 122.227849 -284.007755) (xy 122.235974 -283.95646)
			(xy 122.252022 -283.907067) (xy 122.2756 -283.860793) (xy 122.306126 -283.818777) (xy 122.342849 -283.782054)
			(xy 122.384865 -283.751528) (xy 122.431139 -283.72795) (xy 122.480532 -283.711902) (xy 122.531827 -283.703777)
			(xy 122.583761 -283.703777) (xy 122.635056 -283.711902) (xy 122.684449 -283.72795) (xy 122.730723 -283.751528)
			(xy 122.772739 -283.782054) (xy 122.809462 -283.818777) (xy 122.839988 -283.860793) (xy 122.863566 -283.907067)
			(xy 122.879614 -283.95646) (xy 122.887739 -284.007755) (xy 122.888248 -284.033722) (xy 122.887739 -284.059689)
			(xy 123.167649 -284.059689) (xy 123.167649 -284.007755) (xy 123.175774 -283.95646) (xy 123.191822 -283.907067)
			(xy 123.2154 -283.860793) (xy 123.245926 -283.818777) (xy 123.282649 -283.782054) (xy 123.324665 -283.751528)
			(xy 123.370939 -283.72795) (xy 123.420332 -283.711902) (xy 123.471627 -283.703777) (xy 123.523561 -283.703777)
			(xy 123.574856 -283.711902) (xy 123.624249 -283.72795) (xy 123.670523 -283.751528) (xy 123.712539 -283.782054)
			(xy 123.749262 -283.818777) (xy 123.779788 -283.860793) (xy 123.803366 -283.907067) (xy 123.819414 -283.95646)
			(xy 123.827539 -284.007755) (xy 123.828048 -284.033722) (xy 123.827539 -284.059689) (xy 124.107449 -284.059689)
			(xy 124.107449 -284.007755) (xy 124.115574 -283.95646) (xy 124.131622 -283.907067) (xy 124.1552 -283.860793)
			(xy 124.185726 -283.818777) (xy 124.222449 -283.782054) (xy 124.264465 -283.751528) (xy 124.310739 -283.72795)
			(xy 124.360132 -283.711902) (xy 124.411427 -283.703777) (xy 124.463361 -283.703777) (xy 124.514656 -283.711902)
			(xy 124.564049 -283.72795) (xy 124.610323 -283.751528) (xy 124.652339 -283.782054) (xy 124.689062 -283.818777)
			(xy 124.719588 -283.860793) (xy 124.743166 -283.907067) (xy 124.759214 -283.95646) (xy 124.767339 -284.007755)
			(xy 124.767848 -284.033722) (xy 124.767339 -284.059689) (xy 125.047503 -284.059689) (xy 125.047503 -284.007755)
			(xy 125.055628 -283.95646) (xy 125.071676 -283.907067) (xy 125.095254 -283.860793) (xy 125.12578 -283.818777)
			(xy 125.162503 -283.782054) (xy 125.204519 -283.751528) (xy 125.250793 -283.72795) (xy 125.300186 -283.711902)
			(xy 125.351481 -283.703777) (xy 125.403415 -283.703777) (xy 125.45471 -283.711902) (xy 125.504103 -283.72795)
			(xy 125.550377 -283.751528) (xy 125.592393 -283.782054) (xy 125.629116 -283.818777) (xy 125.659642 -283.860793)
			(xy 125.68322 -283.907067) (xy 125.699268 -283.95646) (xy 125.707393 -284.007755) (xy 125.707902 -284.033722)
			(xy 125.707393 -284.059689) (xy 125.987049 -284.059689) (xy 125.987049 -284.007755) (xy 125.995174 -283.95646)
			(xy 126.011222 -283.907067) (xy 126.0348 -283.860793) (xy 126.065326 -283.818777) (xy 126.102049 -283.782054)
			(xy 126.144065 -283.751528) (xy 126.190339 -283.72795) (xy 126.239732 -283.711902) (xy 126.291027 -283.703777)
			(xy 126.342961 -283.703777) (xy 126.394256 -283.711902) (xy 126.443649 -283.72795) (xy 126.489923 -283.751528)
			(xy 126.531939 -283.782054) (xy 126.568662 -283.818777) (xy 126.599188 -283.860793) (xy 126.622766 -283.907067)
			(xy 126.638814 -283.95646) (xy 126.646939 -284.007755) (xy 126.647448 -284.033722) (xy 126.646939 -284.059689)
			(xy 126.926849 -284.059689) (xy 126.926849 -284.007755) (xy 126.934974 -283.95646) (xy 126.951022 -283.907067)
			(xy 126.9746 -283.860793) (xy 127.005126 -283.818777) (xy 127.041849 -283.782054) (xy 127.083865 -283.751528)
			(xy 127.130139 -283.72795) (xy 127.179532 -283.711902) (xy 127.230827 -283.703777) (xy 127.282761 -283.703777)
			(xy 127.334056 -283.711902) (xy 127.383449 -283.72795) (xy 127.429723 -283.751528) (xy 127.471739 -283.782054)
			(xy 127.508462 -283.818777) (xy 127.538988 -283.860793) (xy 127.562566 -283.907067) (xy 127.578614 -283.95646)
			(xy 127.586739 -284.007755) (xy 127.587248 -284.033722) (xy 127.586739 -284.059689) (xy 127.866649 -284.059689)
			(xy 127.866649 -284.007755) (xy 127.874774 -283.95646) (xy 127.890822 -283.907067) (xy 127.9144 -283.860793)
			(xy 127.944926 -283.818777) (xy 127.981649 -283.782054) (xy 128.023665 -283.751528) (xy 128.069939 -283.72795)
			(xy 128.119332 -283.711902) (xy 128.170627 -283.703777) (xy 128.222561 -283.703777) (xy 128.273856 -283.711902)
			(xy 128.323249 -283.72795) (xy 128.369523 -283.751528) (xy 128.411539 -283.782054) (xy 128.448262 -283.818777)
			(xy 128.478788 -283.860793) (xy 128.502366 -283.907067) (xy 128.518414 -283.95646) (xy 128.526539 -284.007755)
			(xy 128.527048 -284.033722) (xy 128.526539 -284.059689) (xy 128.806449 -284.059689) (xy 128.806449 -284.007755)
			(xy 128.814574 -283.95646) (xy 128.830622 -283.907067) (xy 128.8542 -283.860793) (xy 128.884726 -283.818777)
			(xy 128.921449 -283.782054) (xy 128.963465 -283.751528) (xy 129.009739 -283.72795) (xy 129.059132 -283.711902)
			(xy 129.110427 -283.703777) (xy 129.162361 -283.703777) (xy 129.213656 -283.711902) (xy 129.263049 -283.72795)
			(xy 129.309323 -283.751528) (xy 129.351339 -283.782054) (xy 129.388062 -283.818777) (xy 129.418588 -283.860793)
			(xy 129.442166 -283.907067) (xy 129.458214 -283.95646) (xy 129.466339 -284.007755) (xy 129.466848 -284.033722)
			(xy 129.466339 -284.059689) (xy 129.746249 -284.059689) (xy 129.746249 -284.007755) (xy 129.754374 -283.95646)
			(xy 129.770422 -283.907067) (xy 129.794 -283.860793) (xy 129.824526 -283.818777) (xy 129.861249 -283.782054)
			(xy 129.903265 -283.751528) (xy 129.949539 -283.72795) (xy 129.998932 -283.711902) (xy 130.050227 -283.703777)
			(xy 130.102161 -283.703777) (xy 130.153456 -283.711902) (xy 130.202849 -283.72795) (xy 130.249123 -283.751528)
			(xy 130.291139 -283.782054) (xy 130.327862 -283.818777) (xy 130.358388 -283.860793) (xy 130.381966 -283.907067)
			(xy 130.398014 -283.95646) (xy 130.406139 -284.007755) (xy 130.406648 -284.033722) (xy 130.406139 -284.059689)
			(xy 130.686049 -284.059689) (xy 130.686049 -284.007755) (xy 130.694174 -283.95646) (xy 130.710222 -283.907067)
			(xy 130.7338 -283.860793) (xy 130.764326 -283.818777) (xy 130.801049 -283.782054) (xy 130.843065 -283.751528)
			(xy 130.889339 -283.72795) (xy 130.938732 -283.711902) (xy 130.990027 -283.703777) (xy 131.041961 -283.703777)
			(xy 131.093256 -283.711902) (xy 131.142649 -283.72795) (xy 131.188923 -283.751528) (xy 131.230939 -283.782054)
			(xy 131.267662 -283.818777) (xy 131.298188 -283.860793) (xy 131.321766 -283.907067) (xy 131.337814 -283.95646)
			(xy 131.345939 -284.007755) (xy 131.346448 -284.033722) (xy 131.345939 -284.059689) (xy 131.625849 -284.059689)
			(xy 131.625849 -284.007755) (xy 131.633974 -283.95646) (xy 131.650022 -283.907067) (xy 131.6736 -283.860793)
			(xy 131.704126 -283.818777) (xy 131.740849 -283.782054) (xy 131.782865 -283.751528) (xy 131.829139 -283.72795)
			(xy 131.878532 -283.711902) (xy 131.929827 -283.703777) (xy 131.981761 -283.703777) (xy 132.033056 -283.711902)
			(xy 132.082449 -283.72795) (xy 132.128723 -283.751528) (xy 132.170739 -283.782054) (xy 132.207462 -283.818777)
			(xy 132.237988 -283.860793) (xy 132.261566 -283.907067) (xy 132.277614 -283.95646) (xy 132.285739 -284.007755)
			(xy 132.286248 -284.033722) (xy 132.285739 -284.059689) (xy 132.565649 -284.059689) (xy 132.565649 -284.007755)
			(xy 132.573774 -283.95646) (xy 132.589822 -283.907067) (xy 132.6134 -283.860793) (xy 132.643926 -283.818777)
			(xy 132.680649 -283.782054) (xy 132.722665 -283.751528) (xy 132.768939 -283.72795) (xy 132.818332 -283.711902)
			(xy 132.869627 -283.703777) (xy 132.921561 -283.703777) (xy 132.972856 -283.711902) (xy 133.022249 -283.72795)
			(xy 133.068523 -283.751528) (xy 133.110539 -283.782054) (xy 133.147262 -283.818777) (xy 133.177788 -283.860793)
			(xy 133.201366 -283.907067) (xy 133.217414 -283.95646) (xy 133.225539 -284.007755) (xy 133.226048 -284.033722)
			(xy 133.225539 -284.059689) (xy 134.445249 -284.059689) (xy 134.445249 -284.007755) (xy 134.453374 -283.95646)
			(xy 134.469422 -283.907067) (xy 134.493 -283.860793) (xy 134.523526 -283.818777) (xy 134.560249 -283.782054)
			(xy 134.602265 -283.751528) (xy 134.648539 -283.72795) (xy 134.697932 -283.711902) (xy 134.749227 -283.703777)
			(xy 134.801161 -283.703777) (xy 134.852456 -283.711902) (xy 134.901849 -283.72795) (xy 134.948123 -283.751528)
			(xy 134.990139 -283.782054) (xy 135.026862 -283.818777) (xy 135.057388 -283.860793) (xy 135.080966 -283.907067)
			(xy 135.097014 -283.95646) (xy 135.105139 -284.007755) (xy 135.105648 -284.033722) (xy 135.105144 -284.059435)
			(xy 136.324595 -284.059435) (xy 136.324595 -284.007501) (xy 136.33272 -283.956206) (xy 136.348768 -283.906813)
			(xy 136.372346 -283.860539) (xy 136.402872 -283.818523) (xy 136.439595 -283.7818) (xy 136.481611 -283.751274)
			(xy 136.527885 -283.727696) (xy 136.577278 -283.711648) (xy 136.628573 -283.703523) (xy 136.680507 -283.703523)
			(xy 136.731802 -283.711648) (xy 136.781195 -283.727696) (xy 136.827469 -283.751274) (xy 136.869485 -283.7818)
			(xy 136.906208 -283.818523) (xy 136.936734 -283.860539) (xy 136.960312 -283.906813) (xy 136.97636 -283.956206)
			(xy 136.984485 -284.007501) (xy 136.984994 -284.033468) (xy 136.984485 -284.059435) (xy 136.97636 -284.11073)
			(xy 136.960312 -284.160123) (xy 136.936734 -284.206397) (xy 136.906208 -284.248413) (xy 136.869485 -284.285136)
			(xy 136.827469 -284.315662) (xy 136.781195 -284.33924) (xy 136.731802 -284.355288) (xy 136.680507 -284.363413)
			(xy 136.628573 -284.363413) (xy 136.577278 -284.355288) (xy 136.527885 -284.33924) (xy 136.481611 -284.315662)
			(xy 136.439595 -284.285136) (xy 136.402872 -284.248413) (xy 136.372346 -284.206397) (xy 136.348768 -284.160123)
			(xy 136.33272 -284.11073) (xy 136.324595 -284.059435) (xy 135.105144 -284.059435) (xy 135.105139 -284.059689)
			(xy 135.097014 -284.110984) (xy 135.080966 -284.160377) (xy 135.057388 -284.206651) (xy 135.026862 -284.248667)
			(xy 134.990139 -284.28539) (xy 134.948123 -284.315916) (xy 134.901849 -284.339494) (xy 134.852456 -284.355542)
			(xy 134.801161 -284.363667) (xy 134.749227 -284.363667) (xy 134.697932 -284.355542) (xy 134.648539 -284.339494)
			(xy 134.602265 -284.315916) (xy 134.560249 -284.28539) (xy 134.523526 -284.248667) (xy 134.493 -284.206651)
			(xy 134.469422 -284.160377) (xy 134.453374 -284.110984) (xy 134.445249 -284.059689) (xy 133.225539 -284.059689)
			(xy 133.217414 -284.110984) (xy 133.201366 -284.160377) (xy 133.177788 -284.206651) (xy 133.147262 -284.248667)
			(xy 133.110539 -284.28539) (xy 133.068523 -284.315916) (xy 133.022249 -284.339494) (xy 132.972856 -284.355542)
			(xy 132.921561 -284.363667) (xy 132.869627 -284.363667) (xy 132.818332 -284.355542) (xy 132.768939 -284.339494)
			(xy 132.722665 -284.315916) (xy 132.680649 -284.28539) (xy 132.643926 -284.248667) (xy 132.6134 -284.206651)
			(xy 132.589822 -284.160377) (xy 132.573774 -284.110984) (xy 132.565649 -284.059689) (xy 132.285739 -284.059689)
			(xy 132.277614 -284.110984) (xy 132.261566 -284.160377) (xy 132.237988 -284.206651) (xy 132.207462 -284.248667)
			(xy 132.170739 -284.28539) (xy 132.128723 -284.315916) (xy 132.082449 -284.339494) (xy 132.033056 -284.355542)
			(xy 131.981761 -284.363667) (xy 131.929827 -284.363667) (xy 131.878532 -284.355542) (xy 131.829139 -284.339494)
			(xy 131.782865 -284.315916) (xy 131.740849 -284.28539) (xy 131.704126 -284.248667) (xy 131.6736 -284.206651)
			(xy 131.650022 -284.160377) (xy 131.633974 -284.110984) (xy 131.625849 -284.059689) (xy 131.345939 -284.059689)
			(xy 131.337814 -284.110984) (xy 131.321766 -284.160377) (xy 131.298188 -284.206651) (xy 131.267662 -284.248667)
			(xy 131.230939 -284.28539) (xy 131.188923 -284.315916) (xy 131.142649 -284.339494) (xy 131.093256 -284.355542)
			(xy 131.041961 -284.363667) (xy 130.990027 -284.363667) (xy 130.938732 -284.355542) (xy 130.889339 -284.339494)
			(xy 130.843065 -284.315916) (xy 130.801049 -284.28539) (xy 130.764326 -284.248667) (xy 130.7338 -284.206651)
			(xy 130.710222 -284.160377) (xy 130.694174 -284.110984) (xy 130.686049 -284.059689) (xy 130.406139 -284.059689)
			(xy 130.398014 -284.110984) (xy 130.381966 -284.160377) (xy 130.358388 -284.206651) (xy 130.327862 -284.248667)
			(xy 130.291139 -284.28539) (xy 130.249123 -284.315916) (xy 130.202849 -284.339494) (xy 130.153456 -284.355542)
			(xy 130.102161 -284.363667) (xy 130.050227 -284.363667) (xy 129.998932 -284.355542) (xy 129.949539 -284.339494)
			(xy 129.903265 -284.315916) (xy 129.861249 -284.28539) (xy 129.824526 -284.248667) (xy 129.794 -284.206651)
			(xy 129.770422 -284.160377) (xy 129.754374 -284.110984) (xy 129.746249 -284.059689) (xy 129.466339 -284.059689)
			(xy 129.458214 -284.110984) (xy 129.442166 -284.160377) (xy 129.418588 -284.206651) (xy 129.388062 -284.248667)
			(xy 129.351339 -284.28539) (xy 129.309323 -284.315916) (xy 129.263049 -284.339494) (xy 129.213656 -284.355542)
			(xy 129.162361 -284.363667) (xy 129.110427 -284.363667) (xy 129.059132 -284.355542) (xy 129.009739 -284.339494)
			(xy 128.963465 -284.315916) (xy 128.921449 -284.28539) (xy 128.884726 -284.248667) (xy 128.8542 -284.206651)
			(xy 128.830622 -284.160377) (xy 128.814574 -284.110984) (xy 128.806449 -284.059689) (xy 128.526539 -284.059689)
			(xy 128.518414 -284.110984) (xy 128.502366 -284.160377) (xy 128.478788 -284.206651) (xy 128.448262 -284.248667)
			(xy 128.411539 -284.28539) (xy 128.369523 -284.315916) (xy 128.323249 -284.339494) (xy 128.273856 -284.355542)
			(xy 128.222561 -284.363667) (xy 128.170627 -284.363667) (xy 128.119332 -284.355542) (xy 128.069939 -284.339494)
			(xy 128.023665 -284.315916) (xy 127.981649 -284.28539) (xy 127.944926 -284.248667) (xy 127.9144 -284.206651)
			(xy 127.890822 -284.160377) (xy 127.874774 -284.110984) (xy 127.866649 -284.059689) (xy 127.586739 -284.059689)
			(xy 127.578614 -284.110984) (xy 127.562566 -284.160377) (xy 127.538988 -284.206651) (xy 127.508462 -284.248667)
			(xy 127.471739 -284.28539) (xy 127.429723 -284.315916) (xy 127.383449 -284.339494) (xy 127.334056 -284.355542)
			(xy 127.282761 -284.363667) (xy 127.230827 -284.363667) (xy 127.179532 -284.355542) (xy 127.130139 -284.339494)
			(xy 127.083865 -284.315916) (xy 127.041849 -284.28539) (xy 127.005126 -284.248667) (xy 126.9746 -284.206651)
			(xy 126.951022 -284.160377) (xy 126.934974 -284.110984) (xy 126.926849 -284.059689) (xy 126.646939 -284.059689)
			(xy 126.638814 -284.110984) (xy 126.622766 -284.160377) (xy 126.599188 -284.206651) (xy 126.568662 -284.248667)
			(xy 126.531939 -284.28539) (xy 126.489923 -284.315916) (xy 126.443649 -284.339494) (xy 126.394256 -284.355542)
			(xy 126.342961 -284.363667) (xy 126.291027 -284.363667) (xy 126.239732 -284.355542) (xy 126.190339 -284.339494)
			(xy 126.144065 -284.315916) (xy 126.102049 -284.28539) (xy 126.065326 -284.248667) (xy 126.0348 -284.206651)
			(xy 126.011222 -284.160377) (xy 125.995174 -284.110984) (xy 125.987049 -284.059689) (xy 125.707393 -284.059689)
			(xy 125.699268 -284.110984) (xy 125.68322 -284.160377) (xy 125.659642 -284.206651) (xy 125.629116 -284.248667)
			(xy 125.592393 -284.28539) (xy 125.550377 -284.315916) (xy 125.504103 -284.339494) (xy 125.45471 -284.355542)
			(xy 125.403415 -284.363667) (xy 125.351481 -284.363667) (xy 125.300186 -284.355542) (xy 125.250793 -284.339494)
			(xy 125.204519 -284.315916) (xy 125.162503 -284.28539) (xy 125.12578 -284.248667) (xy 125.095254 -284.206651)
			(xy 125.071676 -284.160377) (xy 125.055628 -284.110984) (xy 125.047503 -284.059689) (xy 124.767339 -284.059689)
			(xy 124.759214 -284.110984) (xy 124.743166 -284.160377) (xy 124.719588 -284.206651) (xy 124.689062 -284.248667)
			(xy 124.652339 -284.28539) (xy 124.610323 -284.315916) (xy 124.564049 -284.339494) (xy 124.514656 -284.355542)
			(xy 124.463361 -284.363667) (xy 124.411427 -284.363667) (xy 124.360132 -284.355542) (xy 124.310739 -284.339494)
			(xy 124.264465 -284.315916) (xy 124.222449 -284.28539) (xy 124.185726 -284.248667) (xy 124.1552 -284.206651)
			(xy 124.131622 -284.160377) (xy 124.115574 -284.110984) (xy 124.107449 -284.059689) (xy 123.827539 -284.059689)
			(xy 123.819414 -284.110984) (xy 123.803366 -284.160377) (xy 123.779788 -284.206651) (xy 123.749262 -284.248667)
			(xy 123.712539 -284.28539) (xy 123.670523 -284.315916) (xy 123.624249 -284.339494) (xy 123.574856 -284.355542)
			(xy 123.523561 -284.363667) (xy 123.471627 -284.363667) (xy 123.420332 -284.355542) (xy 123.370939 -284.339494)
			(xy 123.324665 -284.315916) (xy 123.282649 -284.28539) (xy 123.245926 -284.248667) (xy 123.2154 -284.206651)
			(xy 123.191822 -284.160377) (xy 123.175774 -284.110984) (xy 123.167649 -284.059689) (xy 122.887739 -284.059689)
			(xy 122.879614 -284.110984) (xy 122.863566 -284.160377) (xy 122.839988 -284.206651) (xy 122.809462 -284.248667)
			(xy 122.772739 -284.28539) (xy 122.730723 -284.315916) (xy 122.684449 -284.339494) (xy 122.635056 -284.355542)
			(xy 122.583761 -284.363667) (xy 122.531827 -284.363667) (xy 122.480532 -284.355542) (xy 122.431139 -284.339494)
			(xy 122.384865 -284.315916) (xy 122.342849 -284.28539) (xy 122.306126 -284.248667) (xy 122.2756 -284.206651)
			(xy 122.252022 -284.160377) (xy 122.235974 -284.110984) (xy 122.227849 -284.059689) (xy 121.947939 -284.059689)
			(xy 121.939814 -284.110984) (xy 121.923766 -284.160377) (xy 121.900188 -284.206651) (xy 121.869662 -284.248667)
			(xy 121.832939 -284.28539) (xy 121.790923 -284.315916) (xy 121.744649 -284.339494) (xy 121.695256 -284.355542)
			(xy 121.643961 -284.363667) (xy 121.592027 -284.363667) (xy 121.540732 -284.355542) (xy 121.491339 -284.339494)
			(xy 121.445065 -284.315916) (xy 121.403049 -284.28539) (xy 121.366326 -284.248667) (xy 121.3358 -284.206651)
			(xy 121.312222 -284.160377) (xy 121.296174 -284.110984) (xy 121.288049 -284.059689) (xy 121.008139 -284.059689)
			(xy 121.000014 -284.110984) (xy 120.983966 -284.160377) (xy 120.960388 -284.206651) (xy 120.929862 -284.248667)
			(xy 120.893139 -284.28539) (xy 120.851123 -284.315916) (xy 120.804849 -284.339494) (xy 120.755456 -284.355542)
			(xy 120.704161 -284.363667) (xy 120.652227 -284.363667) (xy 120.600932 -284.355542) (xy 120.551539 -284.339494)
			(xy 120.505265 -284.315916) (xy 120.463249 -284.28539) (xy 120.426526 -284.248667) (xy 120.396 -284.206651)
			(xy 120.372422 -284.160377) (xy 120.356374 -284.110984) (xy 120.348249 -284.059689) (xy 120.068303 -284.059689)
			(xy 120.068303 -284.06077) (xy 120.059481 -284.114152) (xy 120.042075 -284.165382) (xy 120.016551 -284.213089)
			(xy 120.000522 -284.23489) (xy 120.000522 -284.847538) (xy 120.817894 -284.847538) (xy 120.818403 -284.821571)
			(xy 120.826528 -284.770276) (xy 120.842576 -284.720883) (xy 120.866154 -284.674609) (xy 120.89668 -284.632593)
			(xy 120.933403 -284.59587) (xy 120.975419 -284.565344) (xy 121.021693 -284.541766) (xy 121.071086 -284.525718)
			(xy 121.122381 -284.517593) (xy 121.174315 -284.517593) (xy 121.22561 -284.525718) (xy 121.275003 -284.541766)
			(xy 121.321277 -284.565344) (xy 121.363293 -284.59587) (xy 121.400016 -284.632593) (xy 121.430542 -284.674609)
			(xy 121.45412 -284.720883) (xy 121.470168 -284.770276) (xy 121.478293 -284.821571) (xy 121.478802 -284.847538)
			(xy 122.697494 -284.847538) (xy 122.698003 -284.821571) (xy 122.706128 -284.770276) (xy 122.722176 -284.720883)
			(xy 122.745754 -284.674609) (xy 122.77628 -284.632593) (xy 122.813003 -284.59587) (xy 122.855019 -284.565344)
			(xy 122.901293 -284.541766) (xy 122.950686 -284.525718) (xy 123.001981 -284.517593) (xy 123.053915 -284.517593)
			(xy 123.10521 -284.525718) (xy 123.154603 -284.541766) (xy 123.200877 -284.565344) (xy 123.242893 -284.59587)
			(xy 123.279616 -284.632593) (xy 123.310142 -284.674609) (xy 123.33372 -284.720883) (xy 123.349768 -284.770276)
			(xy 123.357893 -284.821571) (xy 123.358402 -284.847538) (xy 124.577094 -284.847538) (xy 124.577603 -284.821571)
			(xy 124.585728 -284.770276) (xy 124.601776 -284.720883) (xy 124.625354 -284.674609) (xy 124.65588 -284.632593)
			(xy 124.692603 -284.59587) (xy 124.734619 -284.565344) (xy 124.780893 -284.541766) (xy 124.830286 -284.525718)
			(xy 124.881581 -284.517593) (xy 124.933515 -284.517593) (xy 124.98481 -284.525718) (xy 125.034203 -284.541766)
			(xy 125.080477 -284.565344) (xy 125.122493 -284.59587) (xy 125.159216 -284.632593) (xy 125.189742 -284.674609)
			(xy 125.21332 -284.720883) (xy 125.229368 -284.770276) (xy 125.237493 -284.821571) (xy 125.238002 -284.847538)
			(xy 125.237498 -284.873505) (xy 125.517403 -284.873505) (xy 125.517403 -284.821571) (xy 125.525528 -284.770276)
			(xy 125.541576 -284.720883) (xy 125.565154 -284.674609) (xy 125.59568 -284.632593) (xy 125.632403 -284.59587)
			(xy 125.674419 -284.565344) (xy 125.720693 -284.541766) (xy 125.770086 -284.525718) (xy 125.821381 -284.517593)
			(xy 125.873315 -284.517593) (xy 125.92461 -284.525718) (xy 125.974003 -284.541766) (xy 126.020277 -284.565344)
			(xy 126.062293 -284.59587) (xy 126.099016 -284.632593) (xy 126.129542 -284.674609) (xy 126.15312 -284.720883)
			(xy 126.169168 -284.770276) (xy 126.177293 -284.821571) (xy 126.177802 -284.847538) (xy 126.456694 -284.847538)
			(xy 126.457203 -284.821571) (xy 126.465328 -284.770276) (xy 126.481376 -284.720883) (xy 126.504954 -284.674609)
			(xy 126.53548 -284.632593) (xy 126.572203 -284.59587) (xy 126.614219 -284.565344) (xy 126.660493 -284.541766)
			(xy 126.709886 -284.525718) (xy 126.761181 -284.517593) (xy 126.813115 -284.517593) (xy 126.86441 -284.525718)
			(xy 126.913803 -284.541766) (xy 126.960077 -284.565344) (xy 127.002093 -284.59587) (xy 127.038816 -284.632593)
			(xy 127.069342 -284.674609) (xy 127.09292 -284.720883) (xy 127.108968 -284.770276) (xy 127.117093 -284.821571)
			(xy 127.117602 -284.847538) (xy 128.336294 -284.847538) (xy 128.336803 -284.821571) (xy 128.344928 -284.770276)
			(xy 128.360976 -284.720883) (xy 128.384554 -284.674609) (xy 128.41508 -284.632593) (xy 128.451803 -284.59587)
			(xy 128.493819 -284.565344) (xy 128.540093 -284.541766) (xy 128.589486 -284.525718) (xy 128.640781 -284.517593)
			(xy 128.692715 -284.517593) (xy 128.74401 -284.525718) (xy 128.793403 -284.541766) (xy 128.839677 -284.565344)
			(xy 128.881693 -284.59587) (xy 128.918416 -284.632593) (xy 128.948942 -284.674609) (xy 128.97252 -284.720883)
			(xy 128.988568 -284.770276) (xy 128.996693 -284.821571) (xy 128.997202 -284.847538) (xy 130.215894 -284.847538)
			(xy 130.216403 -284.821571) (xy 130.224528 -284.770276) (xy 130.240576 -284.720883) (xy 130.264154 -284.674609)
			(xy 130.29468 -284.632593) (xy 130.331403 -284.59587) (xy 130.373419 -284.565344) (xy 130.419693 -284.541766)
			(xy 130.469086 -284.525718) (xy 130.520381 -284.517593) (xy 130.572315 -284.517593) (xy 130.62361 -284.525718)
			(xy 130.673003 -284.541766) (xy 130.719277 -284.565344) (xy 130.761293 -284.59587) (xy 130.798016 -284.632593)
			(xy 130.828542 -284.674609) (xy 130.85212 -284.720883) (xy 130.868168 -284.770276) (xy 130.876293 -284.821571)
			(xy 130.876802 -284.847538) (xy 132.095494 -284.847538) (xy 132.096003 -284.821571) (xy 132.104128 -284.770276)
			(xy 132.120176 -284.720883) (xy 132.143754 -284.674609) (xy 132.17428 -284.632593) (xy 132.211003 -284.59587)
			(xy 132.253019 -284.565344) (xy 132.299293 -284.541766) (xy 132.348686 -284.525718) (xy 132.399981 -284.517593)
			(xy 132.451915 -284.517593) (xy 132.50321 -284.525718) (xy 132.552603 -284.541766) (xy 132.598877 -284.565344)
			(xy 132.640893 -284.59587) (xy 132.677616 -284.632593) (xy 132.708142 -284.674609) (xy 132.73172 -284.720883)
			(xy 132.747768 -284.770276) (xy 132.755893 -284.821571) (xy 132.756402 -284.847538) (xy 132.755898 -284.873505)
			(xy 133.975603 -284.873505) (xy 133.975603 -284.821571) (xy 133.983728 -284.770276) (xy 133.999776 -284.720883)
			(xy 134.023354 -284.674609) (xy 134.05388 -284.632593) (xy 134.090603 -284.59587) (xy 134.132619 -284.565344)
			(xy 134.178893 -284.541766) (xy 134.228286 -284.525718) (xy 134.279581 -284.517593) (xy 134.331515 -284.517593)
			(xy 134.38281 -284.525718) (xy 134.432203 -284.541766) (xy 134.478477 -284.565344) (xy 134.520493 -284.59587)
			(xy 134.557216 -284.632593) (xy 134.587742 -284.674609) (xy 134.61132 -284.720883) (xy 134.627368 -284.770276)
			(xy 134.635493 -284.821571) (xy 134.636002 -284.847538) (xy 134.635498 -284.873251) (xy 134.915149 -284.873251)
			(xy 134.915149 -284.821317) (xy 134.923274 -284.770022) (xy 134.939322 -284.720629) (xy 134.9629 -284.674355)
			(xy 134.993426 -284.632339) (xy 135.030149 -284.595616) (xy 135.072165 -284.56509) (xy 135.118439 -284.541512)
			(xy 135.167832 -284.525464) (xy 135.219127 -284.517339) (xy 135.271061 -284.517339) (xy 135.322356 -284.525464)
			(xy 135.371749 -284.541512) (xy 135.418023 -284.56509) (xy 135.460039 -284.595616) (xy 135.496762 -284.632339)
			(xy 135.527288 -284.674355) (xy 135.550866 -284.720629) (xy 135.566914 -284.770022) (xy 135.575039 -284.821317)
			(xy 135.575548 -284.847284) (xy 135.575039 -284.873251) (xy 135.854949 -284.873251) (xy 135.854949 -284.821317)
			(xy 135.863074 -284.770022) (xy 135.879122 -284.720629) (xy 135.9027 -284.674355) (xy 135.933226 -284.632339)
			(xy 135.969949 -284.595616) (xy 136.011965 -284.56509) (xy 136.058239 -284.541512) (xy 136.107632 -284.525464)
			(xy 136.158927 -284.517339) (xy 136.210861 -284.517339) (xy 136.262156 -284.525464) (xy 136.311549 -284.541512)
			(xy 136.357823 -284.56509) (xy 136.399839 -284.595616) (xy 136.436562 -284.632339) (xy 136.467088 -284.674355)
			(xy 136.490666 -284.720629) (xy 136.506714 -284.770022) (xy 136.514839 -284.821317) (xy 136.515348 -284.847284)
			(xy 136.514839 -284.873251) (xy 136.794749 -284.873251) (xy 136.794749 -284.821317) (xy 136.802874 -284.770022)
			(xy 136.818922 -284.720629) (xy 136.8425 -284.674355) (xy 136.873026 -284.632339) (xy 136.909749 -284.595616)
			(xy 136.951765 -284.56509) (xy 136.998039 -284.541512) (xy 137.047432 -284.525464) (xy 137.098727 -284.517339)
			(xy 137.150661 -284.517339) (xy 137.201956 -284.525464) (xy 137.251349 -284.541512) (xy 137.297623 -284.56509)
			(xy 137.339639 -284.595616) (xy 137.376362 -284.632339) (xy 137.406888 -284.674355) (xy 137.430466 -284.720629)
			(xy 137.446514 -284.770022) (xy 137.454639 -284.821317) (xy 137.455148 -284.847284) (xy 137.454639 -284.873251)
			(xy 137.446514 -284.924546) (xy 137.430466 -284.973939) (xy 137.406888 -285.020213) (xy 137.376362 -285.062229)
			(xy 137.339639 -285.098952) (xy 137.297623 -285.129478) (xy 137.251349 -285.153056) (xy 137.201956 -285.169104)
			(xy 137.150661 -285.177229) (xy 137.098727 -285.177229) (xy 137.047432 -285.169104) (xy 136.998039 -285.153056)
			(xy 136.951765 -285.129478) (xy 136.909749 -285.098952) (xy 136.873026 -285.062229) (xy 136.8425 -285.020213)
			(xy 136.818922 -284.973939) (xy 136.802874 -284.924546) (xy 136.794749 -284.873251) (xy 136.514839 -284.873251)
			(xy 136.506714 -284.924546) (xy 136.490666 -284.973939) (xy 136.467088 -285.020213) (xy 136.436562 -285.062229)
			(xy 136.399839 -285.098952) (xy 136.357823 -285.129478) (xy 136.311549 -285.153056) (xy 136.262156 -285.169104)
			(xy 136.210861 -285.177229) (xy 136.158927 -285.177229) (xy 136.107632 -285.169104) (xy 136.058239 -285.153056)
			(xy 136.011965 -285.129478) (xy 135.969949 -285.098952) (xy 135.933226 -285.062229) (xy 135.9027 -285.020213)
			(xy 135.879122 -284.973939) (xy 135.863074 -284.924546) (xy 135.854949 -284.873251) (xy 135.575039 -284.873251)
			(xy 135.566914 -284.924546) (xy 135.550866 -284.973939) (xy 135.527288 -285.020213) (xy 135.496762 -285.062229)
			(xy 135.460039 -285.098952) (xy 135.418023 -285.129478) (xy 135.371749 -285.153056) (xy 135.322356 -285.169104)
			(xy 135.271061 -285.177229) (xy 135.219127 -285.177229) (xy 135.167832 -285.169104) (xy 135.118439 -285.153056)
			(xy 135.072165 -285.129478) (xy 135.030149 -285.098952) (xy 134.993426 -285.062229) (xy 134.9629 -285.020213)
			(xy 134.939322 -284.973939) (xy 134.923274 -284.924546) (xy 134.915149 -284.873251) (xy 134.635498 -284.873251)
			(xy 134.635493 -284.873505) (xy 134.627368 -284.9248) (xy 134.61132 -284.974193) (xy 134.587742 -285.020467)
			(xy 134.557216 -285.062483) (xy 134.520493 -285.099206) (xy 134.478477 -285.129732) (xy 134.432203 -285.15331)
			(xy 134.38281 -285.169358) (xy 134.331515 -285.177483) (xy 134.279581 -285.177483) (xy 134.228286 -285.169358)
			(xy 134.178893 -285.15331) (xy 134.132619 -285.129732) (xy 134.090603 -285.099206) (xy 134.05388 -285.062483)
			(xy 134.023354 -285.020467) (xy 133.999776 -284.974193) (xy 133.983728 -284.9248) (xy 133.975603 -284.873505)
			(xy 132.755898 -284.873505) (xy 132.755859 -284.875524) (xy 132.746402 -284.930692) (xy 132.737606 -284.957266)
			(xy 132.729986 -284.979364) (xy 132.933694 -285.33217) (xy 132.956554 -285.336488) (xy 132.981483 -285.341625)
			(xy 133.029468 -285.358593) (xy 133.074287 -285.382714) (xy 133.11488 -285.413418) (xy 133.150288 -285.449981)
			(xy 133.179676 -285.491537) (xy 133.202348 -285.537105) (xy 133.21777 -285.58561) (xy 133.225576 -285.635905)
			(xy 133.226048 -285.661354) (xy 133.225539 -285.687321) (xy 133.217414 -285.738616) (xy 133.201366 -285.788009)
			(xy 133.177788 -285.834283) (xy 133.147262 -285.876299) (xy 133.110539 -285.913022) (xy 133.068523 -285.943548)
			(xy 133.022249 -285.967126) (xy 132.972856 -285.983174) (xy 132.921561 -285.991299) (xy 132.869627 -285.991299)
			(xy 132.818332 -285.983174) (xy 132.768939 -285.967126) (xy 132.722665 -285.943548) (xy 132.680649 -285.913022)
			(xy 132.643926 -285.876299) (xy 132.6134 -285.834283) (xy 132.589822 -285.788009) (xy 132.573774 -285.738616)
			(xy 132.565649 -285.687321) (xy 132.56514 -285.661354) (xy 132.565679 -285.633367) (xy 132.575138 -285.5782)
			(xy 132.583936 -285.551626) (xy 132.591556 -285.529528) (xy 132.387848 -285.176722) (xy 132.364988 -285.172404)
			(xy 132.340064 -285.167244) (xy 132.292078 -285.150281) (xy 132.247258 -285.126165) (xy 132.206664 -285.095464)
			(xy 132.171254 -285.058905) (xy 132.141866 -285.017351) (xy 132.119193 -284.971784) (xy 132.103771 -284.92328)
			(xy 132.095965 -284.872986) (xy 132.095494 -284.847538) (xy 130.876802 -284.847538) (xy 130.876259 -284.875524)
			(xy 130.866802 -284.930692) (xy 130.858006 -284.957266) (xy 130.850386 -284.979364) (xy 131.054094 -285.33217)
			(xy 131.076954 -285.336488) (xy 131.101883 -285.341625) (xy 131.149868 -285.358593) (xy 131.194687 -285.382714)
			(xy 131.23528 -285.413418) (xy 131.270688 -285.449981) (xy 131.300076 -285.491537) (xy 131.322748 -285.537105)
			(xy 131.33817 -285.58561) (xy 131.345976 -285.635905) (xy 131.346448 -285.661354) (xy 131.345939 -285.687321)
			(xy 131.337814 -285.738616) (xy 131.321766 -285.788009) (xy 131.298188 -285.834283) (xy 131.267662 -285.876299)
			(xy 131.230939 -285.913022) (xy 131.188923 -285.943548) (xy 131.142649 -285.967126) (xy 131.093256 -285.983174)
			(xy 131.041961 -285.991299) (xy 130.990027 -285.991299) (xy 130.938732 -285.983174) (xy 130.889339 -285.967126)
			(xy 130.843065 -285.943548) (xy 130.801049 -285.913022) (xy 130.764326 -285.876299) (xy 130.7338 -285.834283)
			(xy 130.710222 -285.788009) (xy 130.694174 -285.738616) (xy 130.686049 -285.687321) (xy 130.68554 -285.661354)
			(xy 130.686079 -285.633367) (xy 130.695538 -285.5782) (xy 130.704336 -285.551626) (xy 130.711956 -285.529528)
			(xy 130.508248 -285.176722) (xy 130.485388 -285.172404) (xy 130.460464 -285.167244) (xy 130.412478 -285.150281)
			(xy 130.367658 -285.126165) (xy 130.327064 -285.095464) (xy 130.291654 -285.058905) (xy 130.262266 -285.017351)
			(xy 130.239593 -284.971784) (xy 130.224171 -284.92328) (xy 130.216365 -284.872986) (xy 130.215894 -284.847538)
			(xy 128.997202 -284.847538) (xy 128.996659 -284.875524) (xy 128.987202 -284.930692) (xy 128.978406 -284.957266)
			(xy 128.970786 -284.979364) (xy 129.174494 -285.33217) (xy 129.197354 -285.336488) (xy 129.222283 -285.341625)
			(xy 129.270268 -285.358593) (xy 129.315087 -285.382714) (xy 129.35568 -285.413418) (xy 129.391088 -285.449981)
			(xy 129.420476 -285.491537) (xy 129.443148 -285.537105) (xy 129.45857 -285.58561) (xy 129.466376 -285.635905)
			(xy 129.466848 -285.661354) (xy 129.466339 -285.687321) (xy 129.458214 -285.738616) (xy 129.442166 -285.788009)
			(xy 129.418588 -285.834283) (xy 129.388062 -285.876299) (xy 129.351339 -285.913022) (xy 129.309323 -285.943548)
			(xy 129.263049 -285.967126) (xy 129.213656 -285.983174) (xy 129.162361 -285.991299) (xy 129.110427 -285.991299)
			(xy 129.059132 -285.983174) (xy 129.009739 -285.967126) (xy 128.963465 -285.943548) (xy 128.921449 -285.913022)
			(xy 128.884726 -285.876299) (xy 128.8542 -285.834283) (xy 128.830622 -285.788009) (xy 128.814574 -285.738616)
			(xy 128.806449 -285.687321) (xy 128.80594 -285.661354) (xy 128.806479 -285.633367) (xy 128.815938 -285.5782)
			(xy 128.824736 -285.551626) (xy 128.832356 -285.529528) (xy 128.628648 -285.176722) (xy 128.605788 -285.172404)
			(xy 128.580864 -285.167244) (xy 128.532878 -285.150281) (xy 128.488058 -285.126165) (xy 128.447464 -285.095464)
			(xy 128.412054 -285.058905) (xy 128.382666 -285.017351) (xy 128.359993 -284.971784) (xy 128.344571 -284.92328)
			(xy 128.336765 -284.872986) (xy 128.336294 -284.847538) (xy 127.117602 -284.847538) (xy 127.117059 -284.875524)
			(xy 127.107602 -284.930692) (xy 127.098806 -284.957266) (xy 127.091186 -284.979364) (xy 127.294894 -285.33217)
			(xy 127.317754 -285.336488) (xy 127.342683 -285.341625) (xy 127.390668 -285.358593) (xy 127.435487 -285.382714)
			(xy 127.47608 -285.413418) (xy 127.511488 -285.449981) (xy 127.540876 -285.491537) (xy 127.563548 -285.537105)
			(xy 127.57897 -285.58561) (xy 127.586776 -285.635905) (xy 127.587248 -285.661354) (xy 127.586739 -285.687321)
			(xy 127.578614 -285.738616) (xy 127.562566 -285.788009) (xy 127.538988 -285.834283) (xy 127.508462 -285.876299)
			(xy 127.471739 -285.913022) (xy 127.429723 -285.943548) (xy 127.383449 -285.967126) (xy 127.334056 -285.983174)
			(xy 127.282761 -285.991299) (xy 127.230827 -285.991299) (xy 127.179532 -285.983174) (xy 127.130139 -285.967126)
			(xy 127.083865 -285.943548) (xy 127.041849 -285.913022) (xy 127.005126 -285.876299) (xy 126.9746 -285.834283)
			(xy 126.951022 -285.788009) (xy 126.934974 -285.738616) (xy 126.926849 -285.687321) (xy 126.92634 -285.661354)
			(xy 126.926879 -285.633367) (xy 126.936338 -285.5782) (xy 126.945136 -285.551626) (xy 126.952756 -285.529528)
			(xy 126.749048 -285.176722) (xy 126.726188 -285.172404) (xy 126.701264 -285.167244) (xy 126.653278 -285.150281)
			(xy 126.608458 -285.126165) (xy 126.567864 -285.095464) (xy 126.532454 -285.058905) (xy 126.503066 -285.017351)
			(xy 126.480393 -284.971784) (xy 126.464971 -284.92328) (xy 126.457165 -284.872986) (xy 126.456694 -284.847538)
			(xy 126.177802 -284.847538) (xy 126.177293 -284.873505) (xy 126.169168 -284.9248) (xy 126.15312 -284.974193)
			(xy 126.129542 -285.020467) (xy 126.099016 -285.062483) (xy 126.062293 -285.099206) (xy 126.020277 -285.129732)
			(xy 125.974003 -285.15331) (xy 125.92461 -285.169358) (xy 125.873315 -285.177483) (xy 125.821381 -285.177483)
			(xy 125.770086 -285.169358) (xy 125.720693 -285.15331) (xy 125.674419 -285.129732) (xy 125.632403 -285.099206)
			(xy 125.59568 -285.062483) (xy 125.565154 -285.020467) (xy 125.541576 -284.974193) (xy 125.525528 -284.9248)
			(xy 125.517403 -284.873505) (xy 125.237498 -284.873505) (xy 125.237459 -284.875524) (xy 125.228002 -284.930692)
			(xy 125.219206 -284.957266) (xy 125.211586 -284.979364) (xy 125.415294 -285.33217) (xy 125.438154 -285.336488)
			(xy 125.463083 -285.341625) (xy 125.511068 -285.358593) (xy 125.555887 -285.382714) (xy 125.59648 -285.413418)
			(xy 125.631888 -285.449981) (xy 125.661276 -285.491537) (xy 125.683948 -285.537105) (xy 125.69937 -285.58561)
			(xy 125.707176 -285.635905) (xy 125.707648 -285.661354) (xy 125.707139 -285.687321) (xy 125.699014 -285.738616)
			(xy 125.682966 -285.788009) (xy 125.659388 -285.834283) (xy 125.628862 -285.876299) (xy 125.592139 -285.913022)
			(xy 125.550123 -285.943548) (xy 125.503849 -285.967126) (xy 125.454456 -285.983174) (xy 125.403161 -285.991299)
			(xy 125.351227 -285.991299) (xy 125.299932 -285.983174) (xy 125.250539 -285.967126) (xy 125.204265 -285.943548)
			(xy 125.162249 -285.913022) (xy 125.125526 -285.876299) (xy 125.095 -285.834283) (xy 125.071422 -285.788009)
			(xy 125.055374 -285.738616) (xy 125.047249 -285.687321) (xy 125.04674 -285.661354) (xy 125.047279 -285.633367)
			(xy 125.056738 -285.5782) (xy 125.065536 -285.551626) (xy 125.073156 -285.529528) (xy 124.869448 -285.176722)
			(xy 124.846588 -285.172404) (xy 124.821664 -285.167244) (xy 124.773678 -285.150281) (xy 124.728858 -285.126165)
			(xy 124.688264 -285.095464) (xy 124.652854 -285.058905) (xy 124.623466 -285.017351) (xy 124.600793 -284.971784)
			(xy 124.585371 -284.92328) (xy 124.577565 -284.872986) (xy 124.577094 -284.847538) (xy 123.358402 -284.847538)
			(xy 123.357859 -284.875524) (xy 123.348402 -284.930692) (xy 123.339606 -284.957266) (xy 123.331986 -284.979364)
			(xy 123.535694 -285.33217) (xy 123.558554 -285.336488) (xy 123.583483 -285.341625) (xy 123.631468 -285.358593)
			(xy 123.676287 -285.382714) (xy 123.71688 -285.413418) (xy 123.752288 -285.449981) (xy 123.781676 -285.491537)
			(xy 123.804348 -285.537105) (xy 123.81977 -285.58561) (xy 123.827576 -285.635905) (xy 123.828048 -285.661354)
			(xy 123.827539 -285.687321) (xy 123.819414 -285.738616) (xy 123.803366 -285.788009) (xy 123.779788 -285.834283)
			(xy 123.749262 -285.876299) (xy 123.712539 -285.913022) (xy 123.670523 -285.943548) (xy 123.624249 -285.967126)
			(xy 123.574856 -285.983174) (xy 123.523561 -285.991299) (xy 123.471627 -285.991299) (xy 123.420332 -285.983174)
			(xy 123.370939 -285.967126) (xy 123.324665 -285.943548) (xy 123.282649 -285.913022) (xy 123.245926 -285.876299)
			(xy 123.2154 -285.834283) (xy 123.191822 -285.788009) (xy 123.175774 -285.738616) (xy 123.167649 -285.687321)
			(xy 123.16714 -285.661354) (xy 123.167679 -285.633367) (xy 123.177138 -285.5782) (xy 123.185936 -285.551626)
			(xy 123.193556 -285.529528) (xy 122.989848 -285.176722) (xy 122.966988 -285.172404) (xy 122.942064 -285.167244)
			(xy 122.894078 -285.150281) (xy 122.849258 -285.126165) (xy 122.808664 -285.095464) (xy 122.773254 -285.058905)
			(xy 122.743866 -285.017351) (xy 122.721193 -284.971784) (xy 122.705771 -284.92328) (xy 122.697965 -284.872986)
			(xy 122.697494 -284.847538) (xy 121.478802 -284.847538) (xy 121.478259 -284.875524) (xy 121.468802 -284.930692)
			(xy 121.460006 -284.957266) (xy 121.452386 -284.979364) (xy 121.656094 -285.33217) (xy 121.678954 -285.336488)
			(xy 121.703883 -285.341625) (xy 121.751868 -285.358593) (xy 121.796687 -285.382714) (xy 121.83728 -285.413418)
			(xy 121.872688 -285.449981) (xy 121.902076 -285.491537) (xy 121.924748 -285.537105) (xy 121.94017 -285.58561)
			(xy 121.947976 -285.635905) (xy 121.948448 -285.661354) (xy 121.947939 -285.687321) (xy 121.939814 -285.738616)
			(xy 121.923766 -285.788009) (xy 121.900188 -285.834283) (xy 121.869662 -285.876299) (xy 121.832939 -285.913022)
			(xy 121.790923 -285.943548) (xy 121.744649 -285.967126) (xy 121.695256 -285.983174) (xy 121.643961 -285.991299)
			(xy 121.592027 -285.991299) (xy 121.540732 -285.983174) (xy 121.491339 -285.967126) (xy 121.445065 -285.943548)
			(xy 121.403049 -285.913022) (xy 121.366326 -285.876299) (xy 121.3358 -285.834283) (xy 121.312222 -285.788009)
			(xy 121.296174 -285.738616) (xy 121.288049 -285.687321) (xy 121.28754 -285.661354) (xy 121.288079 -285.633367)
			(xy 121.297538 -285.5782) (xy 121.306336 -285.551626) (xy 121.313956 -285.529528) (xy 121.110248 -285.176722)
			(xy 121.087388 -285.172404) (xy 121.062464 -285.167244) (xy 121.014478 -285.150281) (xy 120.969658 -285.126165)
			(xy 120.929064 -285.095464) (xy 120.893654 -285.058905) (xy 120.864266 -285.017351) (xy 120.841593 -284.971784)
			(xy 120.826171 -284.92328) (xy 120.818365 -284.872986) (xy 120.817894 -284.847538) (xy 120.000522 -284.847538)
			(xy 120.000522 -285.460186) (xy 120.016575 -285.481972) (xy 120.042105 -285.529684) (xy 120.059516 -285.580919)
			(xy 120.068343 -285.634307) (xy 120.068349 -285.68842) (xy 120.059534 -285.74181) (xy 120.042134 -285.793049)
			(xy 120.016615 -285.840766) (xy 120.000522 -285.862522) (xy 120.000522 -286.056578) (xy 120.001072 -286.072034)
			(xy 120.010318 -286.10153) (xy 120.027945 -286.126924) (xy 120.052345 -286.145903) (xy 120.081296 -286.156736)
			(xy 120.112162 -286.158437) (xy 120.127268 -286.15513) (xy 120.147588 -286.150558) (xy 120.170448 -286.14624)
			(xy 120.374156 -285.79318) (xy 120.366536 -285.771082) (xy 120.357746 -285.744507) (xy 120.348302 -285.689339)
			(xy 120.34774 -285.661354) (xy 120.348249 -285.635387) (xy 120.356374 -285.584092) (xy 120.372422 -285.534699)
			(xy 120.396 -285.488425) (xy 120.426526 -285.446409) (xy 120.463249 -285.409686) (xy 120.505265 -285.37916)
			(xy 120.551539 -285.355582) (xy 120.600932 -285.339534) (xy 120.652227 -285.331409) (xy 120.704161 -285.331409)
			(xy 120.755456 -285.339534) (xy 120.804849 -285.355582) (xy 120.851123 -285.37916) (xy 120.893139 -285.409686)
			(xy 120.929862 -285.446409) (xy 120.960388 -285.488425) (xy 120.983966 -285.534699) (xy 121.000014 -285.584092)
			(xy 121.008139 -285.635387) (xy 121.008648 -285.661354) (xy 121.008176 -285.686802) (xy 121.000368 -285.737096)
			(xy 120.984946 -285.7856) (xy 120.962273 -285.831168) (xy 120.932885 -285.872723) (xy 120.897477 -285.909284)
			(xy 120.856884 -285.939988) (xy 120.812066 -285.964108) (xy 120.764081 -285.981075) (xy 120.739154 -285.98622)
			(xy 120.716294 -285.990538) (xy 120.512586 -286.343598) (xy 120.520206 -286.365696) (xy 120.528997 -286.392271)
			(xy 120.538443 -286.447438) (xy 120.539002 -286.475424) (xy 120.538491 -286.501391) (xy 120.818149 -286.501391)
			(xy 120.818149 -286.449457) (xy 120.826274 -286.398162) (xy 120.842322 -286.348769) (xy 120.8659 -286.302495)
			(xy 120.896426 -286.260479) (xy 120.933149 -286.223756) (xy 120.975165 -286.19323) (xy 121.021439 -286.169652)
			(xy 121.070832 -286.153604) (xy 121.122127 -286.145479) (xy 121.174061 -286.145479) (xy 121.225356 -286.153604)
			(xy 121.274749 -286.169652) (xy 121.321023 -286.19323) (xy 121.363039 -286.223756) (xy 121.399762 -286.260479)
			(xy 121.430288 -286.302495) (xy 121.453866 -286.348769) (xy 121.469914 -286.398162) (xy 121.478039 -286.449457)
			(xy 121.478548 -286.475424) (xy 121.757694 -286.475424) (xy 121.758154 -286.449973) (xy 121.765942 -286.39967)
			(xy 121.781352 -286.351157) (xy 121.80402 -286.305582) (xy 121.83341 -286.264021) (xy 121.868826 -286.22746)
			(xy 121.90943 -286.196763) (xy 121.954262 -286.172657) (xy 122.00226 -286.155711) (xy 122.027188 -286.150558)
			(xy 122.050048 -286.14624) (xy 122.253756 -285.79318) (xy 122.246136 -285.771082) (xy 122.237395 -285.744495)
			(xy 122.227949 -285.689335) (xy 122.22734 -285.661354) (xy 122.227849 -285.635387) (xy 122.235974 -285.584092)
			(xy 122.252022 -285.534699) (xy 122.2756 -285.488425) (xy 122.306126 -285.446409) (xy 122.342849 -285.409686)
			(xy 122.384865 -285.37916) (xy 122.431139 -285.355582) (xy 122.480532 -285.339534) (xy 122.531827 -285.331409)
			(xy 122.583761 -285.331409) (xy 122.635056 -285.339534) (xy 122.684449 -285.355582) (xy 122.730723 -285.37916)
			(xy 122.772739 -285.409686) (xy 122.809462 -285.446409) (xy 122.839988 -285.488425) (xy 122.863566 -285.534699)
			(xy 122.879614 -285.584092) (xy 122.887739 -285.635387) (xy 122.888248 -285.661354) (xy 122.887815 -285.686807)
			(xy 122.880029 -285.737113) (xy 122.864618 -285.785629) (xy 122.841948 -285.831208) (xy 122.812555 -285.87277)
			(xy 122.777135 -285.909331) (xy 122.736525 -285.940027) (xy 122.691688 -285.96413) (xy 122.643685 -285.98107)
			(xy 122.618754 -285.98622) (xy 122.595894 -285.990538) (xy 122.392186 -286.343598) (xy 122.399806 -286.365696)
			(xy 122.408543 -286.392284) (xy 122.417991 -286.447444) (xy 122.418602 -286.475424) (xy 122.418093 -286.501391)
			(xy 122.697749 -286.501391) (xy 122.697749 -286.449457) (xy 122.705874 -286.398162) (xy 122.721922 -286.348769)
			(xy 122.7455 -286.302495) (xy 122.776026 -286.260479) (xy 122.812749 -286.223756) (xy 122.854765 -286.19323)
			(xy 122.901039 -286.169652) (xy 122.950432 -286.153604) (xy 123.001727 -286.145479) (xy 123.053661 -286.145479)
			(xy 123.104956 -286.153604) (xy 123.154349 -286.169652) (xy 123.200623 -286.19323) (xy 123.242639 -286.223756)
			(xy 123.279362 -286.260479) (xy 123.309888 -286.302495) (xy 123.333466 -286.348769) (xy 123.349514 -286.398162)
			(xy 123.357639 -286.449457) (xy 123.358148 -286.475424) (xy 123.637294 -286.475424) (xy 123.637754 -286.449973)
			(xy 123.645542 -286.39967) (xy 123.660952 -286.351157) (xy 123.68362 -286.305582) (xy 123.71301 -286.264021)
			(xy 123.748426 -286.22746) (xy 123.78903 -286.196763) (xy 123.833862 -286.172657) (xy 123.88186 -286.155711)
			(xy 123.906788 -286.150558) (xy 123.929648 -286.14624) (xy 124.133356 -285.79318) (xy 124.125736 -285.771082)
			(xy 124.116995 -285.744495) (xy 124.107549 -285.689335) (xy 124.10694 -285.661354) (xy 124.107449 -285.635387)
			(xy 124.115574 -285.584092) (xy 124.131622 -285.534699) (xy 124.1552 -285.488425) (xy 124.185726 -285.446409)
			(xy 124.222449 -285.409686) (xy 124.264465 -285.37916) (xy 124.310739 -285.355582) (xy 124.360132 -285.339534)
			(xy 124.411427 -285.331409) (xy 124.463361 -285.331409) (xy 124.514656 -285.339534) (xy 124.564049 -285.355582)
			(xy 124.610323 -285.37916) (xy 124.652339 -285.409686) (xy 124.689062 -285.446409) (xy 124.719588 -285.488425)
			(xy 124.743166 -285.534699) (xy 124.759214 -285.584092) (xy 124.767339 -285.635387) (xy 124.767848 -285.661354)
			(xy 124.767415 -285.686807) (xy 124.759629 -285.737113) (xy 124.744218 -285.785629) (xy 124.721548 -285.831208)
			(xy 124.692155 -285.87277) (xy 124.656735 -285.909331) (xy 124.616125 -285.940027) (xy 124.571288 -285.96413)
			(xy 124.523285 -285.98107) (xy 124.498354 -285.98622) (xy 124.475494 -285.990538) (xy 124.271786 -286.343598)
			(xy 124.279406 -286.365696) (xy 124.288143 -286.392284) (xy 124.297591 -286.447444) (xy 124.298202 -286.475424)
			(xy 124.297693 -286.501391) (xy 124.577349 -286.501391) (xy 124.577349 -286.449457) (xy 124.585474 -286.398162)
			(xy 124.601522 -286.348769) (xy 124.6251 -286.302495) (xy 124.655626 -286.260479) (xy 124.692349 -286.223756)
			(xy 124.734365 -286.19323) (xy 124.780639 -286.169652) (xy 124.830032 -286.153604) (xy 124.881327 -286.145479)
			(xy 124.933261 -286.145479) (xy 124.984556 -286.153604) (xy 125.033949 -286.169652) (xy 125.080223 -286.19323)
			(xy 125.122239 -286.223756) (xy 125.158962 -286.260479) (xy 125.189488 -286.302495) (xy 125.213066 -286.348769)
			(xy 125.229114 -286.398162) (xy 125.237239 -286.449457) (xy 125.237748 -286.475424) (xy 125.516894 -286.475424)
			(xy 125.517354 -286.449973) (xy 125.525142 -286.39967) (xy 125.540552 -286.351157) (xy 125.56322 -286.305582)
			(xy 125.59261 -286.264021) (xy 125.628026 -286.22746) (xy 125.66863 -286.196763) (xy 125.713462 -286.172657)
			(xy 125.76146 -286.155711) (xy 125.786388 -286.150558) (xy 125.809248 -286.14624) (xy 126.012956 -285.79318)
			(xy 126.005336 -285.771082) (xy 125.996595 -285.744495) (xy 125.987149 -285.689335) (xy 125.98654 -285.661354)
			(xy 125.987049 -285.635387) (xy 125.995174 -285.584092) (xy 126.011222 -285.534699) (xy 126.0348 -285.488425)
			(xy 126.065326 -285.446409) (xy 126.102049 -285.409686) (xy 126.144065 -285.37916) (xy 126.190339 -285.355582)
			(xy 126.239732 -285.339534) (xy 126.291027 -285.331409) (xy 126.342961 -285.331409) (xy 126.394256 -285.339534)
			(xy 126.443649 -285.355582) (xy 126.489923 -285.37916) (xy 126.531939 -285.409686) (xy 126.568662 -285.446409)
			(xy 126.599188 -285.488425) (xy 126.622766 -285.534699) (xy 126.638814 -285.584092) (xy 126.646939 -285.635387)
			(xy 126.647448 -285.661354) (xy 126.647015 -285.686807) (xy 126.639229 -285.737113) (xy 126.623818 -285.785629)
			(xy 126.601148 -285.831208) (xy 126.571755 -285.87277) (xy 126.536335 -285.909331) (xy 126.495725 -285.940027)
			(xy 126.450888 -285.96413) (xy 126.402885 -285.98107) (xy 126.377954 -285.98622) (xy 126.355094 -285.990538)
			(xy 126.151386 -286.343598) (xy 126.159006 -286.365696) (xy 126.167743 -286.392284) (xy 126.177191 -286.447444)
			(xy 126.177802 -286.475424) (xy 126.177293 -286.501391) (xy 126.456949 -286.501391) (xy 126.456949 -286.449457)
			(xy 126.465074 -286.398162) (xy 126.481122 -286.348769) (xy 126.5047 -286.302495) (xy 126.535226 -286.260479)
			(xy 126.571949 -286.223756) (xy 126.613965 -286.19323) (xy 126.660239 -286.169652) (xy 126.709632 -286.153604)
			(xy 126.760927 -286.145479) (xy 126.812861 -286.145479) (xy 126.864156 -286.153604) (xy 126.913549 -286.169652)
			(xy 126.959823 -286.19323) (xy 127.001839 -286.223756) (xy 127.038562 -286.260479) (xy 127.069088 -286.302495)
			(xy 127.092666 -286.348769) (xy 127.108714 -286.398162) (xy 127.116839 -286.449457) (xy 127.117348 -286.475424)
			(xy 127.396494 -286.475424) (xy 127.396954 -286.449973) (xy 127.404742 -286.39967) (xy 127.420152 -286.351157)
			(xy 127.44282 -286.305582) (xy 127.47221 -286.264021) (xy 127.507626 -286.22746) (xy 127.54823 -286.196763)
			(xy 127.593062 -286.172657) (xy 127.64106 -286.155711) (xy 127.665988 -286.150558) (xy 127.688848 -286.14624)
			(xy 127.892556 -285.79318) (xy 127.884936 -285.771082) (xy 127.876195 -285.744495) (xy 127.866749 -285.689335)
			(xy 127.86614 -285.661354) (xy 127.866649 -285.635387) (xy 127.874774 -285.584092) (xy 127.890822 -285.534699)
			(xy 127.9144 -285.488425) (xy 127.944926 -285.446409) (xy 127.981649 -285.409686) (xy 128.023665 -285.37916)
			(xy 128.069939 -285.355582) (xy 128.119332 -285.339534) (xy 128.170627 -285.331409) (xy 128.222561 -285.331409)
			(xy 128.273856 -285.339534) (xy 128.323249 -285.355582) (xy 128.369523 -285.37916) (xy 128.411539 -285.409686)
			(xy 128.448262 -285.446409) (xy 128.478788 -285.488425) (xy 128.502366 -285.534699) (xy 128.518414 -285.584092)
			(xy 128.526539 -285.635387) (xy 128.527048 -285.661354) (xy 128.526615 -285.686807) (xy 128.518829 -285.737113)
			(xy 128.503418 -285.785629) (xy 128.480748 -285.831208) (xy 128.451355 -285.87277) (xy 128.415935 -285.909331)
			(xy 128.375325 -285.940027) (xy 128.330488 -285.96413) (xy 128.282485 -285.98107) (xy 128.257554 -285.98622)
			(xy 128.234694 -285.990538) (xy 128.030986 -286.343598) (xy 128.038606 -286.365696) (xy 128.047343 -286.392284)
			(xy 128.056791 -286.447444) (xy 128.057402 -286.475424) (xy 128.056893 -286.501391) (xy 128.336549 -286.501391)
			(xy 128.336549 -286.449457) (xy 128.344674 -286.398162) (xy 128.360722 -286.348769) (xy 128.3843 -286.302495)
			(xy 128.414826 -286.260479) (xy 128.451549 -286.223756) (xy 128.493565 -286.19323) (xy 128.539839 -286.169652)
			(xy 128.589232 -286.153604) (xy 128.640527 -286.145479) (xy 128.692461 -286.145479) (xy 128.743756 -286.153604)
			(xy 128.793149 -286.169652) (xy 128.839423 -286.19323) (xy 128.881439 -286.223756) (xy 128.918162 -286.260479)
			(xy 128.948688 -286.302495) (xy 128.972266 -286.348769) (xy 128.988314 -286.398162) (xy 128.996439 -286.449457)
			(xy 128.996948 -286.475424) (xy 129.276094 -286.475424) (xy 129.276554 -286.449973) (xy 129.284342 -286.39967)
			(xy 129.299752 -286.351157) (xy 129.32242 -286.305582) (xy 129.35181 -286.264021) (xy 129.387226 -286.22746)
			(xy 129.42783 -286.196763) (xy 129.472662 -286.172657) (xy 129.52066 -286.155711) (xy 129.545588 -286.150558)
			(xy 129.568448 -286.14624) (xy 129.772156 -285.79318) (xy 129.764536 -285.771082) (xy 129.755795 -285.744495)
			(xy 129.746349 -285.689335) (xy 129.74574 -285.661354) (xy 129.746249 -285.635387) (xy 129.754374 -285.584092)
			(xy 129.770422 -285.534699) (xy 129.794 -285.488425) (xy 129.824526 -285.446409) (xy 129.861249 -285.409686)
			(xy 129.903265 -285.37916) (xy 129.949539 -285.355582) (xy 129.998932 -285.339534) (xy 130.050227 -285.331409)
			(xy 130.102161 -285.331409) (xy 130.153456 -285.339534) (xy 130.202849 -285.355582) (xy 130.249123 -285.37916)
			(xy 130.291139 -285.409686) (xy 130.327862 -285.446409) (xy 130.358388 -285.488425) (xy 130.381966 -285.534699)
			(xy 130.398014 -285.584092) (xy 130.406139 -285.635387) (xy 130.406648 -285.661354) (xy 130.406215 -285.686807)
			(xy 130.398429 -285.737113) (xy 130.383018 -285.785629) (xy 130.360348 -285.831208) (xy 130.330955 -285.87277)
			(xy 130.295535 -285.909331) (xy 130.254925 -285.940027) (xy 130.210088 -285.96413) (xy 130.162085 -285.98107)
			(xy 130.137154 -285.98622) (xy 130.114294 -285.990538) (xy 129.910586 -286.343598) (xy 129.918206 -286.365696)
			(xy 129.926943 -286.392284) (xy 129.936391 -286.447444) (xy 129.937002 -286.475424) (xy 129.936493 -286.501391)
			(xy 130.216149 -286.501391) (xy 130.216149 -286.449457) (xy 130.224274 -286.398162) (xy 130.240322 -286.348769)
			(xy 130.2639 -286.302495) (xy 130.294426 -286.260479) (xy 130.331149 -286.223756) (xy 130.373165 -286.19323)
			(xy 130.419439 -286.169652) (xy 130.468832 -286.153604) (xy 130.520127 -286.145479) (xy 130.572061 -286.145479)
			(xy 130.623356 -286.153604) (xy 130.672749 -286.169652) (xy 130.719023 -286.19323) (xy 130.761039 -286.223756)
			(xy 130.797762 -286.260479) (xy 130.828288 -286.302495) (xy 130.851866 -286.348769) (xy 130.867914 -286.398162)
			(xy 130.876039 -286.449457) (xy 130.876548 -286.475424) (xy 131.155694 -286.475424) (xy 131.156154 -286.449973)
			(xy 131.163942 -286.39967) (xy 131.179352 -286.351157) (xy 131.20202 -286.305582) (xy 131.23141 -286.264021)
			(xy 131.266826 -286.22746) (xy 131.30743 -286.196763) (xy 131.352262 -286.172657) (xy 131.40026 -286.155711)
			(xy 131.425188 -286.150558) (xy 131.448048 -286.14624) (xy 131.651756 -285.79318) (xy 131.644136 -285.771082)
			(xy 131.635395 -285.744495) (xy 131.625949 -285.689335) (xy 131.62534 -285.661354) (xy 131.625849 -285.635387)
			(xy 131.633974 -285.584092) (xy 131.650022 -285.534699) (xy 131.6736 -285.488425) (xy 131.704126 -285.446409)
			(xy 131.740849 -285.409686) (xy 131.782865 -285.37916) (xy 131.829139 -285.355582) (xy 131.878532 -285.339534)
			(xy 131.929827 -285.331409) (xy 131.981761 -285.331409) (xy 132.033056 -285.339534) (xy 132.082449 -285.355582)
			(xy 132.128723 -285.37916) (xy 132.170739 -285.409686) (xy 132.207462 -285.446409) (xy 132.237988 -285.488425)
			(xy 132.261566 -285.534699) (xy 132.277614 -285.584092) (xy 132.285739 -285.635387) (xy 132.286248 -285.661354)
			(xy 132.285815 -285.686807) (xy 132.278029 -285.737113) (xy 132.262618 -285.785629) (xy 132.239948 -285.831208)
			(xy 132.210555 -285.87277) (xy 132.175135 -285.909331) (xy 132.134525 -285.940027) (xy 132.089688 -285.96413)
			(xy 132.041685 -285.98107) (xy 132.016754 -285.98622) (xy 131.993894 -285.990538) (xy 131.790186 -286.343598)
			(xy 131.797806 -286.365696) (xy 131.806543 -286.392284) (xy 131.815991 -286.447444) (xy 131.816602 -286.475424)
			(xy 131.816093 -286.501391) (xy 132.095749 -286.501391) (xy 132.095749 -286.449457) (xy 132.103874 -286.398162)
			(xy 132.119922 -286.348769) (xy 132.1435 -286.302495) (xy 132.174026 -286.260479) (xy 132.210749 -286.223756)
			(xy 132.252765 -286.19323) (xy 132.299039 -286.169652) (xy 132.348432 -286.153604) (xy 132.399727 -286.145479)
			(xy 132.451661 -286.145479) (xy 132.502956 -286.153604) (xy 132.552349 -286.169652) (xy 132.598623 -286.19323)
			(xy 132.640639 -286.223756) (xy 132.677362 -286.260479) (xy 132.707888 -286.302495) (xy 132.731466 -286.348769)
			(xy 132.747514 -286.398162) (xy 132.755639 -286.449457) (xy 132.756148 -286.475424) (xy 133.035294 -286.475424)
			(xy 133.035754 -286.449973) (xy 133.043542 -286.39967) (xy 133.058952 -286.351157) (xy 133.08162 -286.305582)
			(xy 133.11101 -286.264021) (xy 133.146426 -286.22746) (xy 133.18703 -286.196763) (xy 133.231862 -286.172657)
			(xy 133.27986 -286.155711) (xy 133.304788 -286.150558) (xy 133.327648 -286.14624) (xy 133.531356 -285.79318)
			(xy 133.523736 -285.771082) (xy 133.514995 -285.744495) (xy 133.505549 -285.689335) (xy 133.50494 -285.661354)
			(xy 133.505449 -285.635387) (xy 133.513574 -285.584092) (xy 133.529622 -285.534699) (xy 133.5532 -285.488425)
			(xy 133.583726 -285.446409) (xy 133.620449 -285.409686) (xy 133.662465 -285.37916) (xy 133.708739 -285.355582)
			(xy 133.758132 -285.339534) (xy 133.809427 -285.331409) (xy 133.861361 -285.331409) (xy 133.912656 -285.339534)
			(xy 133.962049 -285.355582) (xy 134.008323 -285.37916) (xy 134.050339 -285.409686) (xy 134.087062 -285.446409)
			(xy 134.117588 -285.488425) (xy 134.141166 -285.534699) (xy 134.157214 -285.584092) (xy 134.165339 -285.635387)
			(xy 134.165848 -285.661354) (xy 134.165415 -285.686807) (xy 134.165335 -285.687321) (xy 134.445249 -285.687321)
			(xy 134.445249 -285.635387) (xy 134.453374 -285.584092) (xy 134.469422 -285.534699) (xy 134.493 -285.488425)
			(xy 134.523526 -285.446409) (xy 134.560249 -285.409686) (xy 134.602265 -285.37916) (xy 134.648539 -285.355582)
			(xy 134.697932 -285.339534) (xy 134.749227 -285.331409) (xy 134.801161 -285.331409) (xy 134.852456 -285.339534)
			(xy 134.901849 -285.355582) (xy 134.948123 -285.37916) (xy 134.990139 -285.409686) (xy 135.026862 -285.446409)
			(xy 135.057388 -285.488425) (xy 135.080966 -285.534699) (xy 135.097014 -285.584092) (xy 135.105139 -285.635387)
			(xy 135.105648 -285.661354) (xy 135.105144 -285.687067) (xy 135.385049 -285.687067) (xy 135.385049 -285.635133)
			(xy 135.393174 -285.583838) (xy 135.409222 -285.534445) (xy 135.4328 -285.488171) (xy 135.463326 -285.446155)
			(xy 135.500049 -285.409432) (xy 135.542065 -285.378906) (xy 135.588339 -285.355328) (xy 135.637732 -285.33928)
			(xy 135.689027 -285.331155) (xy 135.740961 -285.331155) (xy 135.792256 -285.33928) (xy 135.841649 -285.355328)
			(xy 135.887923 -285.378906) (xy 135.929939 -285.409432) (xy 135.966662 -285.446155) (xy 135.997188 -285.488171)
			(xy 136.020766 -285.534445) (xy 136.036814 -285.583838) (xy 136.044939 -285.635133) (xy 136.045448 -285.6611)
			(xy 136.044939 -285.687067) (xy 136.044899 -285.687321) (xy 136.324849 -285.687321) (xy 136.324849 -285.635387)
			(xy 136.332974 -285.584092) (xy 136.349022 -285.534699) (xy 136.3726 -285.488425) (xy 136.403126 -285.446409)
			(xy 136.439849 -285.409686) (xy 136.481865 -285.37916) (xy 136.528139 -285.355582) (xy 136.577532 -285.339534)
			(xy 136.628827 -285.331409) (xy 136.680761 -285.331409) (xy 136.732056 -285.339534) (xy 136.781449 -285.355582)
			(xy 136.827723 -285.37916) (xy 136.869739 -285.409686) (xy 136.906462 -285.446409) (xy 136.936988 -285.488425)
			(xy 136.960566 -285.534699) (xy 136.976614 -285.584092) (xy 136.984739 -285.635387) (xy 136.985248 -285.661354)
			(xy 136.984739 -285.687321) (xy 136.976614 -285.738616) (xy 136.960566 -285.788009) (xy 136.936988 -285.834283)
			(xy 136.906462 -285.876299) (xy 136.869739 -285.913022) (xy 136.827723 -285.943548) (xy 136.781449 -285.967126)
			(xy 136.732056 -285.983174) (xy 136.680761 -285.991299) (xy 136.628827 -285.991299) (xy 136.577532 -285.983174)
			(xy 136.528139 -285.967126) (xy 136.481865 -285.943548) (xy 136.439849 -285.913022) (xy 136.403126 -285.876299)
			(xy 136.3726 -285.834283) (xy 136.349022 -285.788009) (xy 136.332974 -285.738616) (xy 136.324849 -285.687321)
			(xy 136.044899 -285.687321) (xy 136.036814 -285.738362) (xy 136.020766 -285.787755) (xy 135.997188 -285.834029)
			(xy 135.966662 -285.876045) (xy 135.929939 -285.912768) (xy 135.887923 -285.943294) (xy 135.841649 -285.966872)
			(xy 135.792256 -285.98292) (xy 135.740961 -285.991045) (xy 135.689027 -285.991045) (xy 135.637732 -285.98292)
			(xy 135.588339 -285.966872) (xy 135.542065 -285.943294) (xy 135.500049 -285.912768) (xy 135.463326 -285.876045)
			(xy 135.4328 -285.834029) (xy 135.409222 -285.787755) (xy 135.393174 -285.738362) (xy 135.385049 -285.687067)
			(xy 135.105144 -285.687067) (xy 135.105139 -285.687321) (xy 135.097014 -285.738616) (xy 135.080966 -285.788009)
			(xy 135.057388 -285.834283) (xy 135.026862 -285.876299) (xy 134.990139 -285.913022) (xy 134.948123 -285.943548)
			(xy 134.901849 -285.967126) (xy 134.852456 -285.983174) (xy 134.801161 -285.991299) (xy 134.749227 -285.991299)
			(xy 134.697932 -285.983174) (xy 134.648539 -285.967126) (xy 134.602265 -285.943548) (xy 134.560249 -285.913022)
			(xy 134.523526 -285.876299) (xy 134.493 -285.834283) (xy 134.469422 -285.788009) (xy 134.453374 -285.738616)
			(xy 134.445249 -285.687321) (xy 134.165335 -285.687321) (xy 134.157629 -285.737113) (xy 134.142218 -285.785629)
			(xy 134.119548 -285.831208) (xy 134.090155 -285.87277) (xy 134.054735 -285.909331) (xy 134.014125 -285.940027)
			(xy 133.969288 -285.96413) (xy 133.921285 -285.98107) (xy 133.896354 -285.98622) (xy 133.873494 -285.990538)
			(xy 133.669786 -286.343598) (xy 133.677406 -286.365696) (xy 133.686143 -286.392284) (xy 133.695591 -286.447444)
			(xy 133.696202 -286.475424) (xy 133.695693 -286.501391) (xy 133.975349 -286.501391) (xy 133.975349 -286.449457)
			(xy 133.983474 -286.398162) (xy 133.999522 -286.348769) (xy 134.0231 -286.302495) (xy 134.053626 -286.260479)
			(xy 134.090349 -286.223756) (xy 134.132365 -286.19323) (xy 134.178639 -286.169652) (xy 134.228032 -286.153604)
			(xy 134.279327 -286.145479) (xy 134.331261 -286.145479) (xy 134.382556 -286.153604) (xy 134.431949 -286.169652)
			(xy 134.478223 -286.19323) (xy 134.520239 -286.223756) (xy 134.556962 -286.260479) (xy 134.587488 -286.302495)
			(xy 134.611066 -286.348769) (xy 134.627114 -286.398162) (xy 134.635239 -286.449457) (xy 134.635748 -286.475424)
			(xy 134.635244 -286.501137) (xy 134.915149 -286.501137) (xy 134.915149 -286.449203) (xy 134.923274 -286.397908)
			(xy 134.939322 -286.348515) (xy 134.9629 -286.302241) (xy 134.993426 -286.260225) (xy 135.030149 -286.223502)
			(xy 135.072165 -286.192976) (xy 135.118439 -286.169398) (xy 135.167832 -286.15335) (xy 135.219127 -286.145225)
			(xy 135.271061 -286.145225) (xy 135.322356 -286.15335) (xy 135.371749 -286.169398) (xy 135.418023 -286.192976)
			(xy 135.460039 -286.223502) (xy 135.496762 -286.260225) (xy 135.527288 -286.302241) (xy 135.550866 -286.348515)
			(xy 135.566914 -286.397908) (xy 135.575039 -286.449203) (xy 135.575548 -286.47517) (xy 135.575039 -286.501137)
			(xy 135.854949 -286.501137) (xy 135.854949 -286.449203) (xy 135.863074 -286.397908) (xy 135.879122 -286.348515)
			(xy 135.9027 -286.302241) (xy 135.933226 -286.260225) (xy 135.969949 -286.223502) (xy 136.011965 -286.192976)
			(xy 136.058239 -286.169398) (xy 136.107632 -286.15335) (xy 136.158927 -286.145225) (xy 136.210861 -286.145225)
			(xy 136.262156 -286.15335) (xy 136.311549 -286.169398) (xy 136.357823 -286.192976) (xy 136.399839 -286.223502)
			(xy 136.436562 -286.260225) (xy 136.467088 -286.302241) (xy 136.490666 -286.348515) (xy 136.506714 -286.397908)
			(xy 136.514839 -286.449203) (xy 136.515348 -286.47517) (xy 136.514839 -286.501137) (xy 136.506714 -286.552432)
			(xy 136.490666 -286.601825) (xy 136.467088 -286.648099) (xy 136.436562 -286.690115) (xy 136.399839 -286.726838)
			(xy 136.357823 -286.757364) (xy 136.311549 -286.780942) (xy 136.262156 -286.79699) (xy 136.210861 -286.805115)
			(xy 136.158927 -286.805115) (xy 136.107632 -286.79699) (xy 136.058239 -286.780942) (xy 136.011965 -286.757364)
			(xy 135.969949 -286.726838) (xy 135.933226 -286.690115) (xy 135.9027 -286.648099) (xy 135.879122 -286.601825)
			(xy 135.863074 -286.552432) (xy 135.854949 -286.501137) (xy 135.575039 -286.501137) (xy 135.566914 -286.552432)
			(xy 135.550866 -286.601825) (xy 135.527288 -286.648099) (xy 135.496762 -286.690115) (xy 135.460039 -286.726838)
			(xy 135.418023 -286.757364) (xy 135.371749 -286.780942) (xy 135.322356 -286.79699) (xy 135.271061 -286.805115)
			(xy 135.219127 -286.805115) (xy 135.167832 -286.79699) (xy 135.118439 -286.780942) (xy 135.072165 -286.757364)
			(xy 135.030149 -286.726838) (xy 134.993426 -286.690115) (xy 134.9629 -286.648099) (xy 134.939322 -286.601825)
			(xy 134.923274 -286.552432) (xy 134.915149 -286.501137) (xy 134.635244 -286.501137) (xy 134.635239 -286.501391)
			(xy 134.627114 -286.552686) (xy 134.611066 -286.602079) (xy 134.587488 -286.648353) (xy 134.556962 -286.690369)
			(xy 134.520239 -286.727092) (xy 134.478223 -286.757618) (xy 134.431949 -286.781196) (xy 134.382556 -286.797244)
			(xy 134.331261 -286.805369) (xy 134.279327 -286.805369) (xy 134.228032 -286.797244) (xy 134.178639 -286.781196)
			(xy 134.132365 -286.757618) (xy 134.090349 -286.727092) (xy 134.053626 -286.690369) (xy 134.0231 -286.648353)
			(xy 133.999522 -286.602079) (xy 133.983474 -286.552686) (xy 133.975349 -286.501391) (xy 133.695693 -286.501391)
			(xy 133.687568 -286.552686) (xy 133.67152 -286.602079) (xy 133.647942 -286.648353) (xy 133.617416 -286.690369)
			(xy 133.580693 -286.727092) (xy 133.538677 -286.757618) (xy 133.492403 -286.781196) (xy 133.44301 -286.797244)
			(xy 133.391715 -286.805369) (xy 133.339781 -286.805369) (xy 133.288486 -286.797244) (xy 133.239093 -286.781196)
			(xy 133.192819 -286.757618) (xy 133.150803 -286.727092) (xy 133.11408 -286.690369) (xy 133.083554 -286.648353)
			(xy 133.059976 -286.602079) (xy 133.043928 -286.552686) (xy 133.035803 -286.501391) (xy 133.035294 -286.475424)
			(xy 132.756148 -286.475424) (xy 132.755639 -286.501391) (xy 132.747514 -286.552686) (xy 132.731466 -286.602079)
			(xy 132.707888 -286.648353) (xy 132.677362 -286.690369) (xy 132.640639 -286.727092) (xy 132.598623 -286.757618)
			(xy 132.552349 -286.781196) (xy 132.502956 -286.797244) (xy 132.451661 -286.805369) (xy 132.399727 -286.805369)
			(xy 132.348432 -286.797244) (xy 132.299039 -286.781196) (xy 132.252765 -286.757618) (xy 132.210749 -286.727092)
			(xy 132.174026 -286.690369) (xy 132.1435 -286.648353) (xy 132.119922 -286.602079) (xy 132.103874 -286.552686)
			(xy 132.095749 -286.501391) (xy 131.816093 -286.501391) (xy 131.807968 -286.552686) (xy 131.79192 -286.602079)
			(xy 131.768342 -286.648353) (xy 131.737816 -286.690369) (xy 131.701093 -286.727092) (xy 131.659077 -286.757618)
			(xy 131.612803 -286.781196) (xy 131.56341 -286.797244) (xy 131.512115 -286.805369) (xy 131.460181 -286.805369)
			(xy 131.408886 -286.797244) (xy 131.359493 -286.781196) (xy 131.313219 -286.757618) (xy 131.271203 -286.727092)
			(xy 131.23448 -286.690369) (xy 131.203954 -286.648353) (xy 131.180376 -286.602079) (xy 131.164328 -286.552686)
			(xy 131.156203 -286.501391) (xy 131.155694 -286.475424) (xy 130.876548 -286.475424) (xy 130.876039 -286.501391)
			(xy 130.867914 -286.552686) (xy 130.851866 -286.602079) (xy 130.828288 -286.648353) (xy 130.797762 -286.690369)
			(xy 130.761039 -286.727092) (xy 130.719023 -286.757618) (xy 130.672749 -286.781196) (xy 130.623356 -286.797244)
			(xy 130.572061 -286.805369) (xy 130.520127 -286.805369) (xy 130.468832 -286.797244) (xy 130.419439 -286.781196)
			(xy 130.373165 -286.757618) (xy 130.331149 -286.727092) (xy 130.294426 -286.690369) (xy 130.2639 -286.648353)
			(xy 130.240322 -286.602079) (xy 130.224274 -286.552686) (xy 130.216149 -286.501391) (xy 129.936493 -286.501391)
			(xy 129.928368 -286.552686) (xy 129.91232 -286.602079) (xy 129.888742 -286.648353) (xy 129.858216 -286.690369)
			(xy 129.821493 -286.727092) (xy 129.779477 -286.757618) (xy 129.733203 -286.781196) (xy 129.68381 -286.797244)
			(xy 129.632515 -286.805369) (xy 129.580581 -286.805369) (xy 129.529286 -286.797244) (xy 129.479893 -286.781196)
			(xy 129.433619 -286.757618) (xy 129.391603 -286.727092) (xy 129.35488 -286.690369) (xy 129.324354 -286.648353)
			(xy 129.300776 -286.602079) (xy 129.284728 -286.552686) (xy 129.276603 -286.501391) (xy 129.276094 -286.475424)
			(xy 128.996948 -286.475424) (xy 128.996439 -286.501391) (xy 128.988314 -286.552686) (xy 128.972266 -286.602079)
			(xy 128.948688 -286.648353) (xy 128.918162 -286.690369) (xy 128.881439 -286.727092) (xy 128.839423 -286.757618)
			(xy 128.793149 -286.781196) (xy 128.743756 -286.797244) (xy 128.692461 -286.805369) (xy 128.640527 -286.805369)
			(xy 128.589232 -286.797244) (xy 128.539839 -286.781196) (xy 128.493565 -286.757618) (xy 128.451549 -286.727092)
			(xy 128.414826 -286.690369) (xy 128.3843 -286.648353) (xy 128.360722 -286.602079) (xy 128.344674 -286.552686)
			(xy 128.336549 -286.501391) (xy 128.056893 -286.501391) (xy 128.048768 -286.552686) (xy 128.03272 -286.602079)
			(xy 128.009142 -286.648353) (xy 127.978616 -286.690369) (xy 127.941893 -286.727092) (xy 127.899877 -286.757618)
			(xy 127.853603 -286.781196) (xy 127.80421 -286.797244) (xy 127.752915 -286.805369) (xy 127.700981 -286.805369)
			(xy 127.649686 -286.797244) (xy 127.600293 -286.781196) (xy 127.554019 -286.757618) (xy 127.512003 -286.727092)
			(xy 127.47528 -286.690369) (xy 127.444754 -286.648353) (xy 127.421176 -286.602079) (xy 127.405128 -286.552686)
			(xy 127.397003 -286.501391) (xy 127.396494 -286.475424) (xy 127.117348 -286.475424) (xy 127.116839 -286.501391)
			(xy 127.108714 -286.552686) (xy 127.092666 -286.602079) (xy 127.069088 -286.648353) (xy 127.038562 -286.690369)
			(xy 127.001839 -286.727092) (xy 126.959823 -286.757618) (xy 126.913549 -286.781196) (xy 126.864156 -286.797244)
			(xy 126.812861 -286.805369) (xy 126.760927 -286.805369) (xy 126.709632 -286.797244) (xy 126.660239 -286.781196)
			(xy 126.613965 -286.757618) (xy 126.571949 -286.727092) (xy 126.535226 -286.690369) (xy 126.5047 -286.648353)
			(xy 126.481122 -286.602079) (xy 126.465074 -286.552686) (xy 126.456949 -286.501391) (xy 126.177293 -286.501391)
			(xy 126.169168 -286.552686) (xy 126.15312 -286.602079) (xy 126.129542 -286.648353) (xy 126.099016 -286.690369)
			(xy 126.062293 -286.727092) (xy 126.020277 -286.757618) (xy 125.974003 -286.781196) (xy 125.92461 -286.797244)
			(xy 125.873315 -286.805369) (xy 125.821381 -286.805369) (xy 125.770086 -286.797244) (xy 125.720693 -286.781196)
			(xy 125.674419 -286.757618) (xy 125.632403 -286.727092) (xy 125.59568 -286.690369) (xy 125.565154 -286.648353)
			(xy 125.541576 -286.602079) (xy 125.525528 -286.552686) (xy 125.517403 -286.501391) (xy 125.516894 -286.475424)
			(xy 125.237748 -286.475424) (xy 125.237239 -286.501391) (xy 125.229114 -286.552686) (xy 125.213066 -286.602079)
			(xy 125.189488 -286.648353) (xy 125.158962 -286.690369) (xy 125.122239 -286.727092) (xy 125.080223 -286.757618)
			(xy 125.033949 -286.781196) (xy 124.984556 -286.797244) (xy 124.933261 -286.805369) (xy 124.881327 -286.805369)
			(xy 124.830032 -286.797244) (xy 124.780639 -286.781196) (xy 124.734365 -286.757618) (xy 124.692349 -286.727092)
			(xy 124.655626 -286.690369) (xy 124.6251 -286.648353) (xy 124.601522 -286.602079) (xy 124.585474 -286.552686)
			(xy 124.577349 -286.501391) (xy 124.297693 -286.501391) (xy 124.289568 -286.552686) (xy 124.27352 -286.602079)
			(xy 124.249942 -286.648353) (xy 124.219416 -286.690369) (xy 124.182693 -286.727092) (xy 124.140677 -286.757618)
			(xy 124.094403 -286.781196) (xy 124.04501 -286.797244) (xy 123.993715 -286.805369) (xy 123.941781 -286.805369)
			(xy 123.890486 -286.797244) (xy 123.841093 -286.781196) (xy 123.794819 -286.757618) (xy 123.752803 -286.727092)
			(xy 123.71608 -286.690369) (xy 123.685554 -286.648353) (xy 123.661976 -286.602079) (xy 123.645928 -286.552686)
			(xy 123.637803 -286.501391) (xy 123.637294 -286.475424) (xy 123.358148 -286.475424) (xy 123.357639 -286.501391)
			(xy 123.349514 -286.552686) (xy 123.333466 -286.602079) (xy 123.309888 -286.648353) (xy 123.279362 -286.690369)
			(xy 123.242639 -286.727092) (xy 123.200623 -286.757618) (xy 123.154349 -286.781196) (xy 123.104956 -286.797244)
			(xy 123.053661 -286.805369) (xy 123.001727 -286.805369) (xy 122.950432 -286.797244) (xy 122.901039 -286.781196)
			(xy 122.854765 -286.757618) (xy 122.812749 -286.727092) (xy 122.776026 -286.690369) (xy 122.7455 -286.648353)
			(xy 122.721922 -286.602079) (xy 122.705874 -286.552686) (xy 122.697749 -286.501391) (xy 122.418093 -286.501391)
			(xy 122.409968 -286.552686) (xy 122.39392 -286.602079) (xy 122.370342 -286.648353) (xy 122.339816 -286.690369)
			(xy 122.303093 -286.727092) (xy 122.261077 -286.757618) (xy 122.214803 -286.781196) (xy 122.16541 -286.797244)
			(xy 122.114115 -286.805369) (xy 122.062181 -286.805369) (xy 122.010886 -286.797244) (xy 121.961493 -286.781196)
			(xy 121.915219 -286.757618) (xy 121.873203 -286.727092) (xy 121.83648 -286.690369) (xy 121.805954 -286.648353)
			(xy 121.782376 -286.602079) (xy 121.766328 -286.552686) (xy 121.758203 -286.501391) (xy 121.757694 -286.475424)
			(xy 121.478548 -286.475424) (xy 121.478039 -286.501391) (xy 121.469914 -286.552686) (xy 121.453866 -286.602079)
			(xy 121.430288 -286.648353) (xy 121.399762 -286.690369) (xy 121.363039 -286.727092) (xy 121.321023 -286.757618)
			(xy 121.274749 -286.781196) (xy 121.225356 -286.797244) (xy 121.174061 -286.805369) (xy 121.122127 -286.805369)
			(xy 121.070832 -286.797244) (xy 121.021439 -286.781196) (xy 120.975165 -286.757618) (xy 120.933149 -286.727092)
			(xy 120.896426 -286.690369) (xy 120.8659 -286.648353) (xy 120.842322 -286.602079) (xy 120.826274 -286.552686)
			(xy 120.818149 -286.501391) (xy 120.538491 -286.501391) (xy 120.530364 -286.552686) (xy 120.514314 -286.602079)
			(xy 120.490736 -286.648353) (xy 120.46021 -286.690369) (xy 120.423488 -286.727094) (xy 120.381473 -286.757623)
			(xy 120.335201 -286.781205) (xy 120.28581 -286.797258) (xy 120.234515 -286.805389) (xy 120.208548 -286.805878)
			(xy 120.18801 -286.805563) (xy 120.147253 -286.800461) (xy 120.127268 -286.795718) (xy 120.112153 -286.792412)
			(xy 120.081271 -286.794062) (xy 120.052297 -286.804875) (xy 120.027885 -286.823861) (xy 120.01027 -286.849281)
			(xy 120.001068 -286.878806) (xy 120.000522 -286.89427) (xy 120.000522 -287.087818) (xy 120.016604 -287.109629)
			(xy 120.042191 -287.157396) (xy 120.059658 -287.208692) (xy 120.068539 -287.262147) (xy 120.069102 -287.28924)
			(xy 120.068567 -287.316339) (xy 120.059729 -287.36981) (xy 120.042265 -287.421116) (xy 120.016645 -287.468875)
			(xy 120.000522 -287.490662) (xy 120.000522 -287.767522) (xy 120.045988 -287.812988) (xy 120.077738 -287.799526)
			(xy 120.098443 -287.791025) (xy 120.141569 -287.779043) (xy 120.185915 -287.772976) (xy 120.208294 -287.772602)
			(xy 120.217969 -287.77268) (xy 120.237285 -287.773823) (xy 120.246902 -287.774888) (xy 120.261638 -287.735772)
			(xy 120.296986 -287.660019) (xy 120.338795 -287.587631) (xy 120.386748 -287.519158) (xy 120.413272 -287.486852)
			(xy 120.397858 -287.465301) (xy 120.373369 -287.418319) (xy 120.356685 -287.368033) (xy 120.348231 -287.315731)
			(xy 120.34774 -287.28924) (xy 120.34822 -287.263268) (xy 120.35634 -287.211964) (xy 120.372386 -287.162562)
			(xy 120.395964 -287.116278) (xy 120.426491 -287.074253) (xy 120.463218 -287.037521) (xy 120.505239 -287.006988)
			(xy 120.551519 -286.983404) (xy 120.600919 -286.967351) (xy 120.652223 -286.959223) (xy 120.678194 -286.958786)
			(xy 120.705683 -286.959339) (xy 120.759901 -286.968449) (xy 120.811865 -286.986402) (xy 120.860143 -287.012703)
			(xy 120.903406 -287.046628) (xy 120.940461 -287.087242) (xy 120.970287 -287.133426) (xy 120.981724 -287.15843)
			(xy 121.023041 -287.151613) (xy 121.106474 -287.14436) (xy 121.148348 -287.143952) (xy 121.190093 -287.144407)
			(xy 121.273269 -287.151659) (xy 121.314464 -287.15843) (xy 121.325844 -287.133396) (xy 121.355661 -287.087196)
			(xy 121.392718 -287.046571) (xy 121.435991 -287.012644) (xy 121.484286 -286.986353) (xy 121.536267 -286.968422)
			(xy 121.5905 -286.959347) (xy 121.617994 -286.958786) (xy 121.643962 -286.959268) (xy 121.69526 -286.967393)
			(xy 121.744655 -286.983443) (xy 121.79093 -287.007023) (xy 121.832947 -287.037552) (xy 121.86967 -287.074279)
			(xy 121.900195 -287.116299) (xy 121.92377 -287.162577) (xy 121.939815 -287.211973) (xy 121.947934 -287.263271)
			(xy 121.948448 -287.28924) (xy 121.948365 -287.300515) (xy 121.946842 -287.323015) (xy 121.9454 -287.334198)
			(xy 121.943902 -287.348793) (xy 121.948359 -287.377779) (xy 121.960856 -287.404309) (xy 121.980366 -287.426204)
			(xy 122.005287 -287.441664) (xy 122.019314 -287.445958) (xy 122.040168 -287.45173) (xy 122.081576 -287.464306)
			(xy 122.102118 -287.471104) (xy 122.116721 -287.475403) (xy 122.147136 -287.476147) (xy 122.176422 -287.4679)
			(xy 122.201979 -287.451393) (xy 122.22154 -287.428091) (xy 122.233371 -287.400062) (xy 122.236421 -287.369791)
			(xy 122.233944 -287.354772) (xy 122.230853 -287.338565) (xy 122.227541 -287.305737) (xy 122.22734 -287.28924)
			(xy 122.22782 -287.263268) (xy 122.23594 -287.211964) (xy 122.251986 -287.162562) (xy 122.275564 -287.116278)
			(xy 122.306091 -287.074253) (xy 122.342818 -287.037521) (xy 122.384839 -287.006988) (xy 122.431119 -286.983404)
			(xy 122.480519 -286.967351) (xy 122.531823 -286.959223) (xy 122.557794 -286.958786) (xy 122.585283 -286.959339)
			(xy 122.639501 -286.968449) (xy 122.691465 -286.986402) (xy 122.739743 -287.012703) (xy 122.783006 -287.046628)
			(xy 122.820061 -287.087242) (xy 122.849887 -287.133426) (xy 122.861324 -287.15843) (xy 122.902641 -287.151613)
			(xy 122.986074 -287.14436) (xy 123.027948 -287.143952) (xy 123.069693 -287.144407) (xy 123.152869 -287.151659)
			(xy 123.194064 -287.15843) (xy 123.205444 -287.133396) (xy 123.235261 -287.087196) (xy 123.272318 -287.046571)
			(xy 123.315591 -287.012644) (xy 123.363886 -286.986353) (xy 123.415867 -286.968422) (xy 123.4701 -286.959347)
			(xy 123.497594 -286.958786) (xy 123.523562 -286.959268) (xy 123.57486 -286.967393) (xy 123.624255 -286.983443)
			(xy 123.67053 -287.007023) (xy 123.712547 -287.037552) (xy 123.74927 -287.074279) (xy 123.779795 -287.116299)
			(xy 123.80337 -287.162577) (xy 123.819415 -287.211973) (xy 123.827534 -287.263271) (xy 123.828048 -287.28924)
			(xy 123.827965 -287.300515) (xy 123.826442 -287.323015) (xy 123.825 -287.334198) (xy 123.823502 -287.348793)
			(xy 123.827959 -287.377779) (xy 123.840456 -287.404309) (xy 123.859966 -287.426204) (xy 123.884887 -287.441664)
			(xy 123.898914 -287.445958) (xy 123.919768 -287.45173) (xy 123.961176 -287.464306) (xy 123.981718 -287.471104)
			(xy 123.996321 -287.475403) (xy 124.026736 -287.476147) (xy 124.056022 -287.4679) (xy 124.081579 -287.451393)
			(xy 124.10114 -287.428091) (xy 124.112971 -287.400062) (xy 124.116021 -287.369791) (xy 124.113544 -287.354772)
			(xy 124.110453 -287.338565) (xy 124.107141 -287.305737) (xy 124.10694 -287.28924) (xy 124.10742 -287.263268)
			(xy 124.11554 -287.211964) (xy 124.131586 -287.162562) (xy 124.155164 -287.116278) (xy 124.185691 -287.074253)
			(xy 124.222418 -287.037521) (xy 124.264439 -287.006988) (xy 124.310719 -286.983404) (xy 124.360119 -286.967351)
			(xy 124.411423 -286.959223) (xy 124.437394 -286.958786) (xy 124.464883 -286.959339) (xy 124.519101 -286.968449)
			(xy 124.571065 -286.986402) (xy 124.619343 -287.012703) (xy 124.662606 -287.046628) (xy 124.699661 -287.087242)
			(xy 124.729487 -287.133426) (xy 124.740924 -287.15843) (xy 124.782241 -287.151613) (xy 124.865674 -287.14436)
			(xy 124.907548 -287.143952) (xy 124.949293 -287.144407) (xy 125.032469 -287.151659) (xy 125.073664 -287.15843)
			(xy 125.085044 -287.133396) (xy 125.114861 -287.087196) (xy 125.151918 -287.046571) (xy 125.195191 -287.012644)
			(xy 125.243486 -286.986353) (xy 125.295467 -286.968422) (xy 125.3497 -286.959347) (xy 125.377194 -286.958786)
			(xy 125.403162 -286.959268) (xy 125.45446 -286.967393) (xy 125.503855 -286.983443) (xy 125.55013 -287.007023)
			(xy 125.592147 -287.037552) (xy 125.62887 -287.074279) (xy 125.659395 -287.116299) (xy 125.68297 -287.162577)
			(xy 125.699015 -287.211973) (xy 125.707134 -287.263271) (xy 125.707648 -287.28924) (xy 125.707565 -287.300515)
			(xy 125.706042 -287.323015) (xy 125.7046 -287.334198) (xy 125.703102 -287.348793) (xy 125.707559 -287.377779)
			(xy 125.720056 -287.404309) (xy 125.739566 -287.426204) (xy 125.764487 -287.441664) (xy 125.778514 -287.445958)
			(xy 125.799368 -287.45173) (xy 125.840776 -287.464306) (xy 125.861318 -287.471104) (xy 125.875921 -287.475403)
			(xy 125.906336 -287.476147) (xy 125.935622 -287.4679) (xy 125.961179 -287.451393) (xy 125.98074 -287.428091)
			(xy 125.992571 -287.400062) (xy 125.995621 -287.369791) (xy 125.993144 -287.354772) (xy 125.990053 -287.338565)
			(xy 125.986741 -287.305737) (xy 125.98654 -287.28924) (xy 125.98702 -287.263268) (xy 125.99514 -287.211964)
			(xy 126.011186 -287.162562) (xy 126.034764 -287.116278) (xy 126.065291 -287.074253) (xy 126.102018 -287.037521)
			(xy 126.144039 -287.006988) (xy 126.190319 -286.983404) (xy 126.239719 -286.967351) (xy 126.291023 -286.959223)
			(xy 126.316994 -286.958786) (xy 126.344483 -286.959339) (xy 126.398701 -286.968449) (xy 126.450665 -286.986402)
			(xy 126.498943 -287.012703) (xy 126.542206 -287.046628) (xy 126.579261 -287.087242) (xy 126.609087 -287.133426)
			(xy 126.620524 -287.15843) (xy 126.661841 -287.151613) (xy 126.745274 -287.14436) (xy 126.787148 -287.143952)
			(xy 126.828893 -287.144407) (xy 126.912069 -287.151659) (xy 126.953264 -287.15843) (xy 126.964644 -287.133396)
			(xy 126.994461 -287.087196) (xy 127.031518 -287.046571) (xy 127.074791 -287.012644) (xy 127.123086 -286.986353)
			(xy 127.175067 -286.968422) (xy 127.2293 -286.959347) (xy 127.256794 -286.958786) (xy 127.282762 -286.959268)
			(xy 127.33406 -286.967393) (xy 127.383455 -286.983443) (xy 127.42973 -287.007023) (xy 127.471747 -287.037552)
			(xy 127.50847 -287.074279) (xy 127.538995 -287.116299) (xy 127.56257 -287.162577) (xy 127.578615 -287.211973)
			(xy 127.586734 -287.263271) (xy 127.587248 -287.28924) (xy 127.587165 -287.300515) (xy 127.585642 -287.323015)
			(xy 127.5842 -287.334198) (xy 127.582702 -287.348793) (xy 127.587159 -287.377779) (xy 127.599656 -287.404309)
			(xy 127.619166 -287.426204) (xy 127.644087 -287.441664) (xy 127.658114 -287.445958) (xy 127.678968 -287.45173)
			(xy 127.720376 -287.464306) (xy 127.740918 -287.471104) (xy 127.755521 -287.475403) (xy 127.785936 -287.476147)
			(xy 127.815222 -287.4679) (xy 127.840779 -287.451393) (xy 127.86034 -287.428091) (xy 127.872171 -287.400062)
			(xy 127.875221 -287.369791) (xy 127.872744 -287.354772) (xy 127.869653 -287.338565) (xy 127.866341 -287.305737)
			(xy 127.86614 -287.28924) (xy 127.86662 -287.263268) (xy 127.87474 -287.211964) (xy 127.890786 -287.162562)
			(xy 127.914364 -287.116278) (xy 127.944891 -287.074253) (xy 127.981618 -287.037521) (xy 128.023639 -287.006988)
			(xy 128.069919 -286.983404) (xy 128.119319 -286.967351) (xy 128.170623 -286.959223) (xy 128.196594 -286.958786)
			(xy 128.224083 -286.959339) (xy 128.278301 -286.968449) (xy 128.330265 -286.986402) (xy 128.378543 -287.012703)
			(xy 128.421806 -287.046628) (xy 128.458861 -287.087242) (xy 128.488687 -287.133426) (xy 128.500124 -287.15843)
			(xy 128.541441 -287.151613) (xy 128.624874 -287.14436) (xy 128.666748 -287.143952) (xy 128.708493 -287.144407)
			(xy 128.791669 -287.151659) (xy 128.832864 -287.15843) (xy 128.844244 -287.133396) (xy 128.874061 -287.087196)
			(xy 128.911118 -287.046571) (xy 128.954391 -287.012644) (xy 129.002686 -286.986353) (xy 129.054667 -286.968422)
			(xy 129.1089 -286.959347) (xy 129.136394 -286.958786) (xy 129.162362 -286.959268) (xy 129.21366 -286.967393)
			(xy 129.263055 -286.983443) (xy 129.30933 -287.007023) (xy 129.351347 -287.037552) (xy 129.38807 -287.074279)
			(xy 129.418595 -287.116299) (xy 129.44217 -287.162577) (xy 129.458215 -287.211973) (xy 129.466334 -287.263271)
			(xy 129.466848 -287.28924) (xy 129.466765 -287.300515) (xy 129.465242 -287.323015) (xy 129.4638 -287.334198)
			(xy 129.462302 -287.348793) (xy 129.466759 -287.377779) (xy 129.479256 -287.404309) (xy 129.498766 -287.426204)
			(xy 129.523687 -287.441664) (xy 129.537714 -287.445958) (xy 129.558568 -287.45173) (xy 129.599976 -287.464306)
			(xy 129.620518 -287.471104) (xy 129.635121 -287.475403) (xy 129.665536 -287.476147) (xy 129.694822 -287.4679)
			(xy 129.720379 -287.451393) (xy 129.73994 -287.428091) (xy 129.751771 -287.400062) (xy 129.754821 -287.369791)
			(xy 129.752344 -287.354772) (xy 129.749253 -287.338565) (xy 129.745941 -287.305737) (xy 129.74574 -287.28924)
			(xy 129.74622 -287.263268) (xy 129.75434 -287.211964) (xy 129.770386 -287.162562) (xy 129.793964 -287.116278)
			(xy 129.824491 -287.074253) (xy 129.861218 -287.037521) (xy 129.903239 -287.006988) (xy 129.949519 -286.983404)
			(xy 129.998919 -286.967351) (xy 130.050223 -286.959223) (xy 130.076194 -286.958786) (xy 130.103683 -286.959339)
			(xy 130.157901 -286.968449) (xy 130.209865 -286.986402) (xy 130.258143 -287.012703) (xy 130.301406 -287.046628)
			(xy 130.338461 -287.087242) (xy 130.368287 -287.133426) (xy 130.379724 -287.15843) (xy 130.421041 -287.151613)
			(xy 130.504474 -287.14436) (xy 130.546348 -287.143952) (xy 130.588093 -287.144407) (xy 130.671269 -287.151659)
			(xy 130.712464 -287.15843) (xy 130.723844 -287.133396) (xy 130.753661 -287.087196) (xy 130.790718 -287.046571)
			(xy 130.833991 -287.012644) (xy 130.882286 -286.986353) (xy 130.934267 -286.968422) (xy 130.9885 -286.959347)
			(xy 131.015994 -286.958786) (xy 131.041962 -286.959268) (xy 131.09326 -286.967393) (xy 131.142655 -286.983443)
			(xy 131.18893 -287.007023) (xy 131.230947 -287.037552) (xy 131.26767 -287.074279) (xy 131.298195 -287.116299)
			(xy 131.32177 -287.162577) (xy 131.337815 -287.211973) (xy 131.345934 -287.263271) (xy 131.346448 -287.28924)
			(xy 131.346365 -287.300515) (xy 131.344842 -287.323015) (xy 131.3434 -287.334198) (xy 131.341902 -287.348793)
			(xy 131.346359 -287.377779) (xy 131.358856 -287.404309) (xy 131.378366 -287.426204) (xy 131.403287 -287.441664)
			(xy 131.417314 -287.445958) (xy 131.438168 -287.45173) (xy 131.479576 -287.464306) (xy 131.500118 -287.471104)
			(xy 131.514721 -287.475403) (xy 131.545136 -287.476147) (xy 131.574422 -287.4679) (xy 131.599979 -287.451393)
			(xy 131.61954 -287.428091) (xy 131.631371 -287.400062) (xy 131.634421 -287.369791) (xy 131.631944 -287.354772)
			(xy 131.628853 -287.338565) (xy 131.625541 -287.305737) (xy 131.62534 -287.28924) (xy 131.62582 -287.263268)
			(xy 131.63394 -287.211964) (xy 131.649986 -287.162562) (xy 131.673564 -287.116278) (xy 131.704091 -287.074253)
			(xy 131.740818 -287.037521) (xy 131.782839 -287.006988) (xy 131.829119 -286.983404) (xy 131.878519 -286.967351)
			(xy 131.929823 -286.959223) (xy 131.955794 -286.958786) (xy 131.983283 -286.959339) (xy 132.037501 -286.968449)
			(xy 132.089465 -286.986402) (xy 132.137743 -287.012703) (xy 132.181006 -287.046628) (xy 132.218061 -287.087242)
			(xy 132.247887 -287.133426) (xy 132.259324 -287.15843) (xy 132.300641 -287.151613) (xy 132.384074 -287.14436)
			(xy 132.425948 -287.143952) (xy 132.467693 -287.144407) (xy 132.550869 -287.151659) (xy 132.592064 -287.15843)
			(xy 132.603444 -287.133396) (xy 132.633261 -287.087196) (xy 132.670318 -287.046571) (xy 132.713591 -287.012644)
			(xy 132.761886 -286.986353) (xy 132.813867 -286.968422) (xy 132.8681 -286.959347) (xy 132.895594 -286.958786)
			(xy 132.921562 -286.959268) (xy 132.97286 -286.967393) (xy 133.022255 -286.983443) (xy 133.06853 -287.007023)
			(xy 133.110547 -287.037552) (xy 133.14727 -287.074279) (xy 133.177795 -287.116299) (xy 133.20137 -287.162577)
			(xy 133.217415 -287.211973) (xy 133.225534 -287.263271) (xy 133.226048 -287.28924) (xy 133.225965 -287.300515)
			(xy 133.224442 -287.323015) (xy 133.223 -287.334198) (xy 133.221502 -287.348793) (xy 133.225959 -287.377779)
			(xy 133.238456 -287.404309) (xy 133.257966 -287.426204) (xy 133.282887 -287.441664) (xy 133.296914 -287.445958)
			(xy 133.317833 -287.451791) (xy 133.359369 -287.464493) (xy 133.379972 -287.471358) (xy 133.394584 -287.475727)
			(xy 133.425059 -287.476475) (xy 133.454399 -287.468198) (xy 133.479991 -287.451635) (xy 133.499558 -287.428258)
			(xy 133.511357 -287.400149) (xy 133.514338 -287.36981) (xy 133.511798 -287.354772) (xy 133.508707 -287.338566)
			(xy 133.505394 -287.305737) (xy 133.505194 -287.28924) (xy 133.505703 -287.263273) (xy 133.513828 -287.211978)
			(xy 133.529876 -287.162585) (xy 133.553454 -287.116311) (xy 133.58398 -287.074295) (xy 133.620703 -287.037572)
			(xy 133.662719 -287.007046) (xy 133.708993 -286.983468) (xy 133.758386 -286.96742) (xy 133.809681 -286.959295)
			(xy 133.861615 -286.959295) (xy 133.91291 -286.96742) (xy 133.962303 -286.983468) (xy 134.008577 -287.007046)
			(xy 134.050593 -287.037572) (xy 134.087316 -287.074295) (xy 134.117842 -287.116311) (xy 134.14142 -287.162585)
			(xy 134.157468 -287.211978) (xy 134.165593 -287.263273) (xy 134.166102 -287.28924) (xy 134.165605 -287.315003)
			(xy 134.157601 -287.365903) (xy 134.141791 -287.414943) (xy 134.118561 -287.460935) (xy 134.088473 -287.502763)
			(xy 134.052256 -287.539414) (xy 134.010789 -287.569998) (xy 133.965077 -287.593774) (xy 133.940804 -287.602422)
			(xy 133.926555 -287.607808) (xy 133.901831 -287.625576) (xy 133.883435 -287.649835) (xy 133.872997 -287.678435)
			(xy 133.871443 -287.708841) (xy 133.87891 -287.738357) (xy 133.894737 -287.764365) (xy 133.905752 -287.774888)
			(xy 133.921863 -287.789227) (xy 133.953363 -287.818697)
		)
		(stroke
			(width 0)
			(type solid)
		)
		(fill yes)
		(layer "In4.Cu")
		(net "PVCCFA_EHV_FIVRA_CPU1")
	)
	(gr_poly
		(pts
			(xy 95.673672 -362.14939) (xy 95.674228 -362.120415) (xy 95.68333 -362.063184) (xy 95.701277 -362.008084)
			(xy 95.727627 -361.95647) (xy 95.76173 -361.909617) (xy 95.781876 -361.888786) (xy 98.961956 -358.708452)
			(xy 98.965258 -358.703118) (xy 98.980147 -358.679325) (xy 99.015805 -358.635982) (xy 99.057428 -358.59833)
			(xy 99.104116 -358.56718) (xy 99.154864 -358.543205) (xy 99.208576 -358.52692) (xy 99.264093 -358.518679)
			(xy 99.292156 -358.518206) (xy 99.319411 -358.518666) (xy 99.373365 -358.526418) (xy 99.425668 -358.541771)
			(xy 99.475253 -358.564411) (xy 99.52111 -358.593878) (xy 99.562307 -358.629572) (xy 99.598004 -358.670766)
			(xy 99.627475 -358.716621) (xy 99.650119 -358.766204) (xy 99.665475 -358.818505) (xy 99.673232 -358.872459)
			(xy 99.673664 -358.899714) (xy 99.673172 -358.92778) (xy 99.664957 -358.983306) (xy 99.648691 -359.037029)
			(xy 99.624726 -359.087787) (xy 99.59358 -359.134484) (xy 99.555926 -359.176111) (xy 99.512576 -359.21177)
			(xy 99.488752 -359.226612) (xy 99.483418 -359.229914) (xy 98.283522 -360.42981) (xy 99.3173 -360.42981)
			(xy 99.321371 -360.374188) (xy 99.333497 -360.319751) (xy 99.35342 -360.26766) (xy 99.380716 -360.219025)
			(xy 99.414802 -360.174882) (xy 99.454951 -360.136173) (xy 99.500309 -360.103722) (xy 99.549909 -360.078221)
			(xy 99.602693 -360.060214) (xy 99.657536 -360.050084) (xy 99.71327 -360.048047) (xy 99.768707 -360.054147)
			(xy 99.822664 -360.068253) (xy 99.873993 -360.090065) (xy 99.921599 -360.119119) (xy 99.964467 -360.154794)
			(xy 100.001684 -360.196331) (xy 100.032457 -360.242844) (xy 100.056129 -360.293341) (xy 100.072197 -360.346748)
			(xy 100.080317 -360.401924) (xy 100.080826 -360.42981) (xy 100.080317 -360.457696) (xy 100.072197 -360.512872)
			(xy 100.056129 -360.566279) (xy 100.032457 -360.616776) (xy 100.001684 -360.663289) (xy 99.964467 -360.704826)
			(xy 99.921599 -360.740501) (xy 99.873993 -360.769555) (xy 99.822664 -360.791367) (xy 99.768707 -360.805473)
			(xy 99.71327 -360.811573) (xy 99.657536 -360.809536) (xy 99.602693 -360.799406) (xy 99.549909 -360.781399)
			(xy 99.500309 -360.755898) (xy 99.454951 -360.723447) (xy 99.414802 -360.684738) (xy 99.380716 -360.640595)
			(xy 99.35342 -360.59196) (xy 99.333497 -360.539869) (xy 99.321371 -360.485432) (xy 99.3173 -360.42981)
			(xy 98.283522 -360.42981) (xy 96.411288 -362.302044) (xy 96.411288 -362.833412) (xy 96.770188 -362.833412)
			(xy 96.774259 -362.77779) (xy 96.786385 -362.723353) (xy 96.806308 -362.671262) (xy 96.833604 -362.622627)
			(xy 96.86769 -362.578484) (xy 96.907839 -362.539775) (xy 96.953197 -362.507324) (xy 97.002797 -362.481823)
			(xy 97.055581 -362.463816) (xy 97.110424 -362.453686) (xy 97.166158 -362.451649) (xy 97.221595 -362.457749)
			(xy 97.275552 -362.471855) (xy 97.326881 -362.493667) (xy 97.374487 -362.522721) (xy 97.417355 -362.558396)
			(xy 97.454572 -362.599933) (xy 97.485345 -362.646446) (xy 97.509017 -362.696943) (xy 97.525085 -362.75035)
			(xy 97.533205 -362.805526) (xy 97.533714 -362.833412) (xy 97.533205 -362.861298) (xy 97.525085 -362.916474)
			(xy 97.509017 -362.969881) (xy 97.485345 -363.020378) (xy 97.454572 -363.066891) (xy 97.425489 -363.09935)
			(xy 97.87204 -363.09935) (xy 97.876111 -363.043728) (xy 97.888237 -362.989291) (xy 97.90816 -362.9372)
			(xy 97.935456 -362.888565) (xy 97.969542 -362.844422) (xy 98.009691 -362.805713) (xy 98.055049 -362.773262)
			(xy 98.104649 -362.747761) (xy 98.157433 -362.729754) (xy 98.212276 -362.719624) (xy 98.26801 -362.717587)
			(xy 98.323447 -362.723687) (xy 98.377404 -362.737793) (xy 98.428733 -362.759605) (xy 98.476339 -362.788659)
			(xy 98.519207 -362.824334) (xy 98.556424 -362.865871) (xy 98.587197 -362.912384) (xy 98.610869 -362.962881)
			(xy 98.626937 -363.016288) (xy 98.635057 -363.071464) (xy 98.635566 -363.09935) (xy 98.635057 -363.127236)
			(xy 98.626937 -363.182412) (xy 98.610869 -363.235819) (xy 98.587197 -363.286316) (xy 98.556424 -363.332829)
			(xy 98.519207 -363.374366) (xy 98.476339 -363.410041) (xy 98.428733 -363.439095) (xy 98.377404 -363.460907)
			(xy 98.323447 -363.475013) (xy 98.26801 -363.481113) (xy 98.212276 -363.479076) (xy 98.157433 -363.468946)
			(xy 98.104649 -363.450939) (xy 98.055049 -363.425438) (xy 98.009691 -363.392987) (xy 97.969542 -363.354278)
			(xy 97.935456 -363.310135) (xy 97.90816 -363.2615) (xy 97.888237 -363.209409) (xy 97.876111 -363.154972)
			(xy 97.87204 -363.09935) (xy 97.425489 -363.09935) (xy 97.417355 -363.108428) (xy 97.374487 -363.144103)
			(xy 97.326881 -363.173157) (xy 97.275552 -363.194969) (xy 97.221595 -363.209075) (xy 97.166158 -363.215175)
			(xy 97.110424 -363.213138) (xy 97.055581 -363.203008) (xy 97.002797 -363.185001) (xy 96.953197 -363.1595)
			(xy 96.907839 -363.127049) (xy 96.86769 -363.08834) (xy 96.833604 -363.044197) (xy 96.806308 -362.995562)
			(xy 96.786385 -362.943471) (xy 96.774259 -362.889034) (xy 96.770188 -362.833412) (xy 96.411288 -362.833412)
			(xy 96.411288 -363.655102) (xy 98.85248 -363.655102) (xy 98.856551 -363.59948) (xy 98.868677 -363.545043)
			(xy 98.8886 -363.492952) (xy 98.915896 -363.444317) (xy 98.949982 -363.400174) (xy 98.990131 -363.361465)
			(xy 99.035489 -363.329014) (xy 99.085089 -363.303513) (xy 99.137873 -363.285506) (xy 99.192716 -363.275376)
			(xy 99.24845 -363.273339) (xy 99.303887 -363.279439) (xy 99.357844 -363.293545) (xy 99.409173 -363.315357)
			(xy 99.456779 -363.344411) (xy 99.499647 -363.380086) (xy 99.536864 -363.421623) (xy 99.567637 -363.468136)
			(xy 99.591309 -363.518633) (xy 99.607377 -363.57204) (xy 99.615497 -363.627216) (xy 99.616006 -363.655102)
			(xy 99.615497 -363.682988) (xy 99.607377 -363.738164) (xy 99.591309 -363.791571) (xy 99.567637 -363.842068)
			(xy 99.536864 -363.888581) (xy 99.499647 -363.930118) (xy 99.456779 -363.965793) (xy 99.409173 -363.994847)
			(xy 99.357844 -364.016659) (xy 99.303887 -364.030765) (xy 99.24845 -364.036865) (xy 99.192716 -364.034828)
			(xy 99.137873 -364.024698) (xy 99.085089 -364.006691) (xy 99.035489 -363.98119) (xy 98.990131 -363.948739)
			(xy 98.949982 -363.91003) (xy 98.915896 -363.865887) (xy 98.8886 -363.817252) (xy 98.868677 -363.765161)
			(xy 98.856551 -363.710724) (xy 98.85248 -363.655102) (xy 96.411288 -363.655102) (xy 96.411288 -364.08995)
			(xy 97.5774 -364.08995) (xy 97.581471 -364.034328) (xy 97.593597 -363.979891) (xy 97.61352 -363.9278)
			(xy 97.640816 -363.879165) (xy 97.674902 -363.835022) (xy 97.715051 -363.796313) (xy 97.760409 -363.763862)
			(xy 97.810009 -363.738361) (xy 97.862793 -363.720354) (xy 97.917636 -363.710224) (xy 97.97337 -363.708187)
			(xy 98.028807 -363.714287) (xy 98.082764 -363.728393) (xy 98.134093 -363.750205) (xy 98.181699 -363.779259)
			(xy 98.224567 -363.814934) (xy 98.261784 -363.856471) (xy 98.292557 -363.902984) (xy 98.316229 -363.953481)
			(xy 98.332297 -364.006888) (xy 98.340417 -364.062064) (xy 98.340926 -364.08995) (xy 98.340417 -364.117836)
			(xy 98.332297 -364.173012) (xy 98.316229 -364.226419) (xy 98.292557 -364.276916) (xy 98.261784 -364.323429)
			(xy 98.224567 -364.364966) (xy 98.181699 -364.400641) (xy 98.134093 -364.429695) (xy 98.082764 -364.451507)
			(xy 98.028807 -364.465613) (xy 97.97337 -364.471713) (xy 97.917636 -364.469676) (xy 97.862793 -364.459546)
			(xy 97.810009 -364.441539) (xy 97.760409 -364.416038) (xy 97.715051 -364.383587) (xy 97.674902 -364.344878)
			(xy 97.640816 -364.300735) (xy 97.61352 -364.2521) (xy 97.593597 -364.200009) (xy 97.581471 -364.145572)
			(xy 97.5774 -364.08995) (xy 96.411288 -364.08995) (xy 96.411288 -364.555849) (xy 98.876386 -364.555849)
			(xy 98.876386 -364.501351) (xy 98.884141 -364.447408) (xy 98.899494 -364.395118) (xy 98.922131 -364.345545)
			(xy 98.951593 -364.299697) (xy 98.987279 -364.258509) (xy 99.028464 -364.222818) (xy 99.074308 -364.193351)
			(xy 99.123879 -364.170708) (xy 99.176167 -364.15535) (xy 99.230109 -364.147589) (xy 99.257358 -364.1471)
			(xy 99.283582 -364.147509) (xy 99.335533 -364.154713) (xy 99.386009 -364.168963) (xy 99.434058 -364.189991)
			(xy 99.478774 -364.2174) (xy 99.519316 -364.250675) (xy 99.554919 -364.289188) (xy 99.584913 -364.332214)
			(xy 99.59721 -364.35538) (xy 99.604539 -364.368759) (xy 99.625777 -364.390643) (xy 99.652525 -364.405289)
			(xy 99.682403 -364.411393) (xy 99.712753 -364.408413) (xy 99.740873 -364.396614) (xy 99.764262 -364.377045)
			(xy 99.772978 -364.364524) (xy 99.788181 -364.342039) (xy 99.823848 -364.301132) (xy 99.864955 -364.265695)
			(xy 99.91067 -364.236444) (xy 99.960071 -364.213969) (xy 100.012159 -364.198724) (xy 100.065882 -364.191018)
			(xy 100.093018 -364.190534) (xy 100.120271 -364.190937) (xy 100.174223 -364.198697) (xy 100.226521 -364.214055)
			(xy 100.276102 -364.2367) (xy 100.321955 -364.26617) (xy 100.363148 -364.301865) (xy 100.398841 -364.343059)
			(xy 100.428309 -364.388914) (xy 100.450951 -364.438495) (xy 100.466307 -364.490794) (xy 100.474064 -364.544747)
			(xy 100.474064 -364.599253) (xy 100.466307 -364.653206) (xy 100.450951 -364.705505) (xy 100.428309 -364.755086)
			(xy 100.398841 -364.800941) (xy 100.363148 -364.842135) (xy 100.321955 -364.87783) (xy 100.276102 -364.9073)
			(xy 100.226521 -364.929945) (xy 100.174223 -364.945303) (xy 100.120271 -364.953063) (xy 100.093018 -364.95355)
			(xy 100.066795 -364.953133) (xy 100.014845 -364.945928) (xy 99.964371 -364.931677) (xy 99.916323 -364.910649)
			(xy 99.871607 -364.883241) (xy 99.831065 -364.849968) (xy 99.795461 -364.811457) (xy 99.765465 -364.768435)
			(xy 99.753166 -364.74527) (xy 99.745729 -364.731955) (xy 99.724517 -364.710068) (xy 99.697791 -364.695415)
			(xy 99.667931 -364.6893) (xy 99.637597 -364.692269) (xy 99.609489 -364.704056) (xy 99.58611 -364.723612)
			(xy 99.577398 -364.736126) (xy 99.562228 -364.758633) (xy 99.526553 -364.799537) (xy 99.48544 -364.834971)
			(xy 99.439719 -364.864219) (xy 99.390314 -364.886691) (xy 99.338222 -364.901931) (xy 99.284496 -364.909633)
			(xy 99.257358 -364.910116) (xy 99.230109 -364.909611) (xy 99.176167 -364.90185) (xy 99.123879 -364.886492)
			(xy 99.074308 -364.863849) (xy 99.028464 -364.834382) (xy 98.987279 -364.798691) (xy 98.951593 -364.757503)
			(xy 98.922131 -364.711655) (xy 98.899494 -364.662082) (xy 98.884141 -364.609792) (xy 98.876386 -364.555849)
			(xy 96.411288 -364.555849) (xy 96.411288 -365.59236) (xy 100.41128 -365.59236) (xy 100.411766 -365.565109)
			(xy 100.419522 -365.511161) (xy 100.434877 -365.458866) (xy 100.457519 -365.409289) (xy 100.486985 -365.363439)
			(xy 100.522676 -365.322248) (xy 100.563867 -365.286557) (xy 100.609717 -365.257091) (xy 100.659294 -365.234449)
			(xy 100.711589 -365.219094) (xy 100.765537 -365.211338) (xy 100.820039 -365.211338) (xy 100.873987 -365.219094)
			(xy 100.926282 -365.234449) (xy 100.975859 -365.257091) (xy 101.021709 -365.286557) (xy 101.0629 -365.322248)
			(xy 101.098591 -365.363439) (xy 101.128057 -365.409289) (xy 101.150699 -365.458866) (xy 101.166054 -365.511161)
			(xy 101.17381 -365.565109) (xy 101.174296 -365.59236) (xy 101.17387 -365.619096) (xy 101.166407 -365.672043)
			(xy 101.151623 -365.72343) (xy 101.129806 -365.772248) (xy 101.101385 -365.81754) (xy 101.066916 -365.858419)
			(xy 101.047296 -365.876586) (xy 101.047296 -365.956342) (xy 101.533958 -365.956342) (xy 101.538029 -365.90072)
			(xy 101.550155 -365.846283) (xy 101.570078 -365.794192) (xy 101.597374 -365.745557) (xy 101.63146 -365.701414)
			(xy 101.671609 -365.662705) (xy 101.716967 -365.630254) (xy 101.766567 -365.604753) (xy 101.819351 -365.586746)
			(xy 101.874194 -365.576616) (xy 101.929928 -365.574579) (xy 101.985365 -365.580679) (xy 102.039322 -365.594785)
			(xy 102.090651 -365.616597) (xy 102.138257 -365.645651) (xy 102.181125 -365.681326) (xy 102.218342 -365.722863)
			(xy 102.249115 -365.769376) (xy 102.272787 -365.819873) (xy 102.288855 -365.87328) (xy 102.296975 -365.928456)
			(xy 102.297484 -365.956342) (xy 102.296975 -365.984228) (xy 102.288855 -366.039404) (xy 102.272787 -366.092811)
			(xy 102.249115 -366.143308) (xy 102.218342 -366.189821) (xy 102.181125 -366.231358) (xy 102.138257 -366.267033)
			(xy 102.090651 -366.296087) (xy 102.039322 -366.317899) (xy 101.985365 -366.332005) (xy 101.929928 -366.338105)
			(xy 101.874194 -366.336068) (xy 101.819351 -366.325938) (xy 101.766567 -366.307931) (xy 101.716967 -366.28243)
			(xy 101.671609 -366.249979) (xy 101.63146 -366.21127) (xy 101.597374 -366.167127) (xy 101.570078 -366.118492)
			(xy 101.550155 -366.066401) (xy 101.538029 -366.011964) (xy 101.533958 -365.956342) (xy 101.047296 -365.956342)
			(xy 101.047296 -366.451896) (xy 101.8667 -367.2713) (xy 111.128302 -367.2713) (xy 113.557812 -364.84179)
			(xy 113.557812 -363.75594) (xy 113.558475 -363.730945) (xy 113.568272 -363.681924) (xy 113.587437 -363.635754)
			(xy 113.615237 -363.594206) (xy 113.632488 -363.576108) (xy 114.086132 -363.12221) (xy 114.086132 -360.269282)
			(xy 113.674906 -359.858056) (xy 113.39322 -359.858056) (xy 113.375127 -359.876498) (xy 113.334873 -359.908882)
			(xy 113.290614 -359.93553) (xy 113.24316 -359.955954) (xy 113.193381 -359.96978) (xy 113.142191 -359.976754)
			(xy 113.11636 -359.977182) (xy 113.116106 -359.977182) (xy 113.088851 -359.976772) (xy 113.034896 -359.969015)
			(xy 112.982593 -359.953658) (xy 112.933009 -359.931014) (xy 112.887152 -359.901545) (xy 112.845956 -359.865848)
			(xy 112.810259 -359.824653) (xy 112.780788 -359.778796) (xy 112.758144 -359.729212) (xy 112.742787 -359.67691)
			(xy 112.735029 -359.622955) (xy 112.735029 -359.568445) (xy 112.742787 -359.51449) (xy 112.758144 -359.462188)
			(xy 112.780788 -359.412604) (xy 112.810259 -359.366747) (xy 112.845956 -359.325552) (xy 112.887152 -359.289855)
			(xy 112.933009 -359.260386) (xy 112.982593 -359.237742) (xy 113.034896 -359.222385) (xy 113.088851 -359.214628)
			(xy 113.116106 -359.214166) (xy 113.14371 -359.214681) (xy 113.198344 -359.222627) (xy 113.251261 -359.238368)
			(xy 113.301356 -359.261574) (xy 113.347582 -359.29176) (xy 113.388972 -359.328295) (xy 113.40719 -359.34904)
			(xy 113.780316 -359.34904) (xy 113.805313 -359.349661) (xy 113.854336 -359.35947) (xy 113.900507 -359.378647)
			(xy 113.906744 -359.382822) (xy 116.061996 -359.382822) (xy 116.066067 -359.3272) (xy 116.078193 -359.272763)
			(xy 116.098116 -359.220672) (xy 116.125412 -359.172037) (xy 116.159498 -359.127894) (xy 116.199647 -359.089185)
			(xy 116.245005 -359.056734) (xy 116.294605 -359.031233) (xy 116.347389 -359.013226) (xy 116.402232 -359.003096)
			(xy 116.457966 -359.001059) (xy 116.513403 -359.007159) (xy 116.56736 -359.021265) (xy 116.618689 -359.043077)
			(xy 116.666295 -359.072131) (xy 116.709163 -359.107806) (xy 116.74638 -359.149343) (xy 116.777153 -359.195856)
			(xy 116.800825 -359.246353) (xy 116.816893 -359.29976) (xy 116.825013 -359.354936) (xy 116.825522 -359.382822)
			(xy 116.825013 -359.410708) (xy 116.816893 -359.465884) (xy 116.800825 -359.519291) (xy 116.777153 -359.569788)
			(xy 116.74638 -359.616301) (xy 116.709163 -359.657838) (xy 116.666295 -359.693513) (xy 116.618689 -359.722567)
			(xy 116.56736 -359.744379) (xy 116.513403 -359.758485) (xy 116.457966 -359.764585) (xy 116.402232 -359.762548)
			(xy 116.347389 -359.752418) (xy 116.294605 -359.734411) (xy 116.245005 -359.70891) (xy 116.199647 -359.676459)
			(xy 116.159498 -359.63775) (xy 116.125412 -359.593607) (xy 116.098116 -359.544972) (xy 116.078193 -359.492881)
			(xy 116.066067 -359.438444) (xy 116.061996 -359.382822) (xy 113.906744 -359.382822) (xy 113.942052 -359.406459)
			(xy 113.960148 -359.423716) (xy 114.520472 -359.98404) (xy 114.537735 -360.002129) (xy 114.565545 -360.043676)
			(xy 114.584717 -360.089849) (xy 114.594513 -360.138875) (xy 114.595148 -360.163872) (xy 114.595148 -360.2736)
			(xy 118.713248 -360.2736) (xy 118.717321 -360.217941) (xy 118.729456 -360.163468) (xy 118.749392 -360.111342)
			(xy 118.776706 -360.062674) (xy 118.810814 -360.018502) (xy 118.850991 -359.979767) (xy 118.896379 -359.947295)
			(xy 118.946011 -359.921777) (xy 118.998831 -359.903758) (xy 119.05371 -359.893621) (xy 119.109481 -359.891583)
			(xy 119.164955 -359.897686) (xy 119.218948 -359.911802) (xy 119.270311 -359.933629) (xy 119.317949 -359.962702)
			(xy 119.360845 -359.998401) (xy 119.398087 -360.039965) (xy 119.428881 -360.086509) (xy 119.452569 -360.13704)
			(xy 119.468647 -360.190482) (xy 119.476773 -360.245696) (xy 119.477282 -360.2736) (xy 119.476773 -360.301504)
			(xy 119.468647 -360.356718) (xy 119.452569 -360.41016) (xy 119.428881 -360.460691) (xy 119.398087 -360.507235)
			(xy 119.360845 -360.548799) (xy 119.317949 -360.584498) (xy 119.270311 -360.613571) (xy 119.218948 -360.635398)
			(xy 119.164955 -360.649514) (xy 119.109481 -360.655617) (xy 119.05371 -360.653579) (xy 118.998831 -360.643442)
			(xy 118.946011 -360.625423) (xy 118.896379 -360.599905) (xy 118.850991 -360.567433) (xy 118.810814 -360.528698)
			(xy 118.776706 -360.484526) (xy 118.749392 -360.435858) (xy 118.729456 -360.383732) (xy 118.717321 -360.329259)
			(xy 118.713248 -360.2736) (xy 114.595148 -360.2736) (xy 114.595148 -361.133136) (xy 121.446286 -361.133136)
			(xy 121.450375 -361.077254) (xy 121.462558 -361.022564) (xy 121.482574 -360.97023) (xy 121.509997 -360.921368)
			(xy 121.544242 -360.87702) (xy 121.584578 -360.83813) (xy 121.630148 -360.805528) (xy 121.679979 -360.779909)
			(xy 121.733009 -360.761817) (xy 121.788107 -360.75164) (xy 121.844101 -360.749594) (xy 121.899796 -360.755722)
			(xy 121.954005 -360.769894) (xy 122.005573 -360.791808) (xy 122.053401 -360.820997) (xy 122.096469 -360.856838)
			(xy 122.133859 -360.898568) (xy 122.164775 -360.945298) (xy 122.188558 -360.996031) (xy 122.2047 -361.049687)
			(xy 122.212859 -361.105121) (xy 122.21337 -361.133136) (xy 122.212859 -361.161151) (xy 122.2047 -361.216585)
			(xy 122.188558 -361.270241) (xy 122.164775 -361.320974) (xy 122.133859 -361.367704) (xy 122.096469 -361.409434)
			(xy 122.053401 -361.445275) (xy 122.005573 -361.474464) (xy 121.954005 -361.496378) (xy 121.899796 -361.51055)
			(xy 121.844101 -361.516678) (xy 121.788107 -361.514632) (xy 121.733009 -361.504455) (xy 121.679979 -361.486363)
			(xy 121.630148 -361.460744) (xy 121.584578 -361.428142) (xy 121.544242 -361.389252) (xy 121.509997 -361.344904)
			(xy 121.482574 -361.296042) (xy 121.462558 -361.243708) (xy 121.450375 -361.189018) (xy 121.446286 -361.133136)
			(xy 114.595148 -361.133136) (xy 114.595148 -362.097066) (xy 128.08534 -362.097066) (xy 128.089411 -362.041444)
			(xy 128.101537 -361.987007) (xy 128.12146 -361.934916) (xy 128.148756 -361.886281) (xy 128.182842 -361.842138)
			(xy 128.222991 -361.803429) (xy 128.268349 -361.770978) (xy 128.317949 -361.745477) (xy 128.370733 -361.72747)
			(xy 128.425576 -361.71734) (xy 128.48131 -361.715303) (xy 128.536747 -361.721403) (xy 128.590704 -361.735509)
			(xy 128.642033 -361.757321) (xy 128.689639 -361.786375) (xy 128.732507 -361.82205) (xy 128.769724 -361.863587)
			(xy 128.800497 -361.9101) (xy 128.824169 -361.960597) (xy 128.840237 -362.014004) (xy 128.848357 -362.06918)
			(xy 128.848866 -362.097066) (xy 128.848357 -362.124952) (xy 128.840237 -362.180128) (xy 128.824169 -362.233535)
			(xy 128.800497 -362.284032) (xy 128.769724 -362.330545) (xy 128.732507 -362.372082) (xy 128.689639 -362.407757)
			(xy 128.642033 -362.436811) (xy 128.590704 -362.458623) (xy 128.536747 -362.472729) (xy 128.48131 -362.478829)
			(xy 128.425576 -362.476792) (xy 128.370733 -362.466662) (xy 128.317949 -362.448655) (xy 128.268349 -362.423154)
			(xy 128.222991 -362.390703) (xy 128.182842 -362.351994) (xy 128.148756 -362.307851) (xy 128.12146 -362.259216)
			(xy 128.101537 -362.207125) (xy 128.089411 -362.152688) (xy 128.08534 -362.097066) (xy 114.595148 -362.097066)
			(xy 114.595148 -363.22762) (xy 114.594533 -363.252617) (xy 114.584723 -363.301641) (xy 114.565544 -363.347812)
			(xy 114.53773 -363.389357) (xy 114.520472 -363.407452) (xy 114.405982 -363.522006) (xy 115.599208 -363.522006)
			(xy 115.603279 -363.466384) (xy 115.615405 -363.411947) (xy 115.635328 -363.359856) (xy 115.662624 -363.311221)
			(xy 115.69671 -363.267078) (xy 115.736859 -363.228369) (xy 115.782217 -363.195918) (xy 115.831817 -363.170417)
			(xy 115.884601 -363.15241) (xy 115.939444 -363.14228) (xy 115.995178 -363.140243) (xy 116.050615 -363.146343)
			(xy 116.104572 -363.160449) (xy 116.155901 -363.182261) (xy 116.203507 -363.211315) (xy 116.246375 -363.24699)
			(xy 116.283592 -363.288527) (xy 116.314365 -363.33504) (xy 116.338037 -363.385537) (xy 116.354105 -363.438944)
			(xy 116.362225 -363.49412) (xy 116.362734 -363.522006) (xy 116.362225 -363.549892) (xy 116.354105 -363.605068)
			(xy 116.338037 -363.658475) (xy 116.314365 -363.708972) (xy 116.283592 -363.755485) (xy 116.246375 -363.797022)
			(xy 116.203507 -363.832697) (xy 116.155901 -363.861751) (xy 116.104572 -363.883563) (xy 116.050615 -363.897669)
			(xy 115.995178 -363.903769) (xy 115.939444 -363.901732) (xy 115.884601 -363.891602) (xy 115.831817 -363.873595)
			(xy 115.782217 -363.848094) (xy 115.736859 -363.815643) (xy 115.69671 -363.776934) (xy 115.662624 -363.732791)
			(xy 115.635328 -363.684156) (xy 115.615405 -363.632065) (xy 115.603279 -363.577628) (xy 115.599208 -363.522006)
			(xy 114.405982 -363.522006) (xy 114.066828 -363.86135) (xy 114.066828 -364.16996) (xy 114.192302 -364.16996)
			(xy 114.196373 -364.114338) (xy 114.208499 -364.059901) (xy 114.228422 -364.00781) (xy 114.255718 -363.959175)
			(xy 114.289804 -363.915032) (xy 114.329953 -363.876323) (xy 114.375311 -363.843872) (xy 114.424911 -363.818371)
			(xy 114.477695 -363.800364) (xy 114.532538 -363.790234) (xy 114.588272 -363.788197) (xy 114.643709 -363.794297)
			(xy 114.697666 -363.808403) (xy 114.748995 -363.830215) (xy 114.796601 -363.859269) (xy 114.839469 -363.894944)
			(xy 114.876686 -363.936481) (xy 114.907459 -363.982994) (xy 114.931131 -364.033491) (xy 114.947199 -364.086898)
			(xy 114.955319 -364.142074) (xy 114.955828 -364.16996) (xy 114.955319 -364.197846) (xy 114.947199 -364.253022)
			(xy 114.931131 -364.306429) (xy 114.907459 -364.356926) (xy 114.876686 -364.403439) (xy 114.839469 -364.444976)
			(xy 114.796601 -364.480651) (xy 114.748995 -364.509705) (xy 114.697666 -364.531517) (xy 114.643709 -364.545623)
			(xy 114.588272 -364.551723) (xy 114.532538 -364.549686) (xy 114.477695 -364.539556) (xy 114.424911 -364.521549)
			(xy 114.375311 -364.496048) (xy 114.329953 -364.463597) (xy 114.289804 -364.424888) (xy 114.255718 -364.380745)
			(xy 114.228422 -364.33211) (xy 114.208499 -364.280019) (xy 114.196373 -364.225582) (xy 114.192302 -364.16996)
			(xy 114.066828 -364.16996) (xy 114.066828 -364.9472) (xy 114.066206 -364.972197) (xy 114.0564 -365.021221)
			(xy 114.037222 -365.067392) (xy 114.00941 -365.108937) (xy 113.992152 -365.127032) (xy 111.413544 -367.70564)
			(xy 111.395482 -367.722937) (xy 111.353929 -367.750752) (xy 111.307748 -367.769927) (xy 111.258713 -367.779723)
			(xy 111.233712 -367.780316) (xy 101.76129 -367.780316) (xy 101.736293 -367.779704) (xy 101.687268 -367.769895)
			(xy 101.641097 -367.750715) (xy 101.599552 -367.722899) (xy 101.581458 -367.70564) (xy 100.612956 -366.737138)
			(xy 100.595656 -366.719079) (xy 100.567841 -366.677525) (xy 100.548668 -366.631343) (xy 100.538873 -366.582308)
			(xy 100.53828 -366.557306) (xy 100.53828 -365.876586) (xy 100.51868 -365.8584) (xy 100.484222 -365.817519)
			(xy 100.455807 -365.772229) (xy 100.433992 -365.723415) (xy 100.419204 -365.672035) (xy 100.411733 -365.619093)
			(xy 100.41128 -365.59236) (xy 96.411288 -365.59236) (xy 96.411288 -370.378228) (xy 118.063772 -370.378228)
			(xy 118.063772 -369.644168) (xy 117.446552 -369.026948) (xy 117.440964 -369.023646) (xy 117.417174 -369.008755)
			(xy 117.373836 -368.973094) (xy 117.336189 -368.93147) (xy 117.305043 -368.884781) (xy 117.281071 -368.834035)
			(xy 117.264789 -368.780325) (xy 117.256548 -368.72481) (xy 117.256052 -368.696748) (xy 117.256512 -368.669492)
			(xy 117.264263 -368.615534) (xy 117.279614 -368.563228) (xy 117.302253 -368.513639) (xy 117.33172 -368.467777)
			(xy 117.367413 -368.426575) (xy 117.408606 -368.390872) (xy 117.454461 -368.361396) (xy 117.504045 -368.338745)
			(xy 117.556347 -368.323381) (xy 117.610304 -368.315618) (xy 117.63756 -368.31524) (xy 117.665624 -368.315735)
			(xy 117.721146 -368.323956) (xy 117.774864 -368.340227) (xy 117.825617 -368.364195) (xy 117.872309 -368.395344)
			(xy 117.91393 -368.433) (xy 117.949583 -368.47635) (xy 117.964458 -368.500152) (xy 117.96776 -368.505486)
			(xy 118.162832 -368.700558) (xy 118.69293 -369.23091) (xy 118.713005 -369.251791) (xy 118.747046 -369.298652)
			(xy 118.773338 -369.35026) (xy 118.791233 -369.405347) (xy 118.800292 -369.462554) (xy 118.80088 -369.491514)
			(xy 118.80088 -370.378228) (xy 119.288052 -370.378228) (xy 119.288052 -364.913926) (xy 119.273123 -364.890502)
			(xy 119.249471 -364.840242) (xy 119.233366 -364.787082) (xy 119.225148 -364.732147) (xy 119.224552 -364.704376)
			(xy 119.224552 -364.693962) (xy 119.225709 -364.665846) (xy 119.235267 -364.610394) (xy 119.252864 -364.556946)
			(xy 119.278119 -364.506662) (xy 119.310484 -364.460631) (xy 119.349258 -364.419852) (xy 119.3936 -364.38521)
			(xy 119.442548 -364.357454) (xy 119.495042 -364.337187) (xy 119.549943 -364.324848) (xy 119.60606 -364.320705)
			(xy 119.662177 -364.324848) (xy 119.717078 -364.337187) (xy 119.769572 -364.357454) (xy 119.81852 -364.38521)
			(xy 119.862862 -364.419852) (xy 119.901636 -364.460631) (xy 119.934001 -364.506662) (xy 119.959256 -364.556946)
			(xy 119.976853 -364.610394) (xy 119.986411 -364.665846) (xy 119.987568 -364.693962) (xy 119.987568 -364.704376)
			(xy 119.986969 -364.732145) (xy 119.978724 -364.787072) (xy 119.96261 -364.840225) (xy 119.938965 -364.890483)
			(xy 119.924068 -364.913926) (xy 119.924068 -365.747808) (xy 132.860799 -365.747808) (xy 132.864835 -365.664361)
			(xy 132.876907 -365.581693) (xy 132.8969 -365.500576) (xy 132.924629 -365.421767) (xy 132.959835 -365.346002)
			(xy 133.002189 -365.273989) (xy 133.051295 -365.2064) (xy 133.106696 -365.143866) (xy 133.167873 -365.086971)
			(xy 133.234256 -365.036245) (xy 133.305224 -364.992164) (xy 133.380116 -364.955138) (xy 133.458232 -364.925512)
			(xy 133.538842 -364.903564) (xy 133.621194 -364.889499) (xy 133.70452 -364.883447) (xy 133.78804 -364.885466)
			(xy 133.870976 -364.895536) (xy 133.952552 -364.913564) (xy 134.032008 -364.939381) (xy 134.108601 -364.972746)
			(xy 134.181617 -365.013347) (xy 134.250373 -365.060806) (xy 134.314227 -365.114679) (xy 134.372584 -365.174464)
			(xy 134.424899 -365.239601) (xy 134.470682 -365.309484) (xy 134.509507 -365.383459) (xy 134.541012 -365.460836)
			(xy 134.564901 -365.540893) (xy 134.580952 -365.622881) (xy 134.589015 -365.706036) (xy 134.58952 -365.747808)
			(xy 134.589015 -365.78958) (xy 134.580952 -365.872735) (xy 134.564901 -365.954723) (xy 134.541012 -366.03478)
			(xy 134.509507 -366.112157) (xy 134.470682 -366.186132) (xy 134.424899 -366.256015) (xy 134.372584 -366.321152)
			(xy 134.314227 -366.380937) (xy 134.250373 -366.43481) (xy 134.181617 -366.482269) (xy 134.108601 -366.52287)
			(xy 134.032008 -366.556235) (xy 133.952552 -366.582052) (xy 133.870976 -366.60008) (xy 133.78804 -366.61015)
			(xy 133.70452 -366.612169) (xy 133.621194 -366.606117) (xy 133.538842 -366.592052) (xy 133.458232 -366.570104)
			(xy 133.380116 -366.540478) (xy 133.305224 -366.503452) (xy 133.234256 -366.459371) (xy 133.167873 -366.408645)
			(xy 133.106696 -366.35175) (xy 133.051295 -366.289216) (xy 133.002189 -366.221627) (xy 132.959835 -366.149614)
			(xy 132.924629 -366.073849) (xy 132.8969 -365.99504) (xy 132.876907 -365.913923) (xy 132.864835 -365.831255)
			(xy 132.860799 -365.747808) (xy 119.924068 -365.747808) (xy 119.924068 -367.832132) (xy 121.144028 -367.832132)
			(xy 121.148099 -367.77651) (xy 121.160225 -367.722073) (xy 121.180148 -367.669982) (xy 121.207444 -367.621347)
			(xy 121.24153 -367.577204) (xy 121.281679 -367.538495) (xy 121.327037 -367.506044) (xy 121.376637 -367.480543)
			(xy 121.429421 -367.462536) (xy 121.484264 -367.452406) (xy 121.539998 -367.450369) (xy 121.595435 -367.456469)
			(xy 121.649392 -367.470575) (xy 121.700721 -367.492387) (xy 121.748327 -367.521441) (xy 121.791195 -367.557116)
			(xy 121.828412 -367.598653) (xy 121.859185 -367.645166) (xy 121.882857 -367.695663) (xy 121.898925 -367.74907)
			(xy 121.907045 -367.804246) (xy 121.907554 -367.832132) (xy 121.907045 -367.860018) (xy 121.898925 -367.915194)
			(xy 121.882857 -367.968601) (xy 121.859185 -368.019098) (xy 121.828412 -368.065611) (xy 121.825273 -368.069114)
			(xy 122.207274 -368.069114) (xy 122.207774 -368.040196) (xy 122.216503 -367.983023) (xy 122.233763 -367.927822)
			(xy 122.259158 -367.87586) (xy 122.292106 -367.828327) (xy 122.331852 -367.786312) (xy 122.35434 -367.768124)
			(xy 122.366136 -367.758214) (xy 122.383662 -367.732896) (xy 122.392843 -367.703505) (xy 122.392846 -367.672712)
			(xy 122.383669 -367.64332) (xy 122.366148 -367.617999) (xy 122.35434 -367.608104) (xy 122.331867 -367.589901)
			(xy 122.292129 -367.547885) (xy 122.259188 -367.500353) (xy 122.233797 -367.448394) (xy 122.216539 -367.393198)
			(xy 122.207809 -367.336029) (xy 122.207274 -367.307114) (xy 122.20776 -367.279863) (xy 122.215516 -367.225915)
			(xy 122.230871 -367.17362) (xy 122.253513 -367.124043) (xy 122.282979 -367.078193) (xy 122.31867 -367.037002)
			(xy 122.359861 -367.001311) (xy 122.405711 -366.971845) (xy 122.455288 -366.949203) (xy 122.507583 -366.933848)
			(xy 122.561531 -366.926092) (xy 122.616033 -366.926092) (xy 122.669981 -366.933848) (xy 122.722276 -366.949203)
			(xy 122.771853 -366.971845) (xy 122.817703 -367.001311) (xy 122.858894 -367.037002) (xy 122.894585 -367.078193)
			(xy 122.924051 -367.124043) (xy 122.946693 -367.17362) (xy 122.962048 -367.225915) (xy 122.969804 -367.279863)
			(xy 122.97029 -367.307114) (xy 122.969714 -367.336029) (xy 122.960997 -367.393198) (xy 122.943751 -367.448395)
			(xy 122.91837 -367.500357) (xy 122.885437 -367.547893) (xy 122.845705 -367.589912) (xy 122.823224 -367.608104)
			(xy 122.811404 -367.617986) (xy 122.793885 -367.643313) (xy 122.784709 -367.672711) (xy 122.784712 -367.703507)
			(xy 122.793892 -367.732903) (xy 122.811416 -367.758227) (xy 122.823224 -367.768124) (xy 122.845724 -367.786295)
			(xy 122.885457 -367.82832) (xy 122.918393 -367.875859) (xy 122.943779 -367.927824) (xy 122.961032 -367.983025)
			(xy 122.969757 -368.040197) (xy 122.97029 -368.069114) (xy 124.355098 -368.069114) (xy 124.355627 -368.040198)
			(xy 124.364354 -367.983027) (xy 124.38161 -367.927828) (xy 124.407 -367.875867) (xy 124.439941 -367.828332)
			(xy 124.47968 -367.786315) (xy 124.502164 -367.768124) (xy 124.513957 -367.758212) (xy 124.531479 -367.732894)
			(xy 124.540659 -367.703504) (xy 124.540661 -367.672713) (xy 124.531487 -367.643322) (xy 124.513969 -367.618)
			(xy 124.502164 -367.608104) (xy 124.479675 -367.58992) (xy 124.439942 -367.547898) (xy 124.407004 -367.500361)
			(xy 124.381617 -367.448398) (xy 124.364362 -367.3932) (xy 124.355633 -367.33603) (xy 124.355098 -367.307114)
			(xy 124.355584 -367.279863) (xy 124.36334 -367.225915) (xy 124.378695 -367.17362) (xy 124.401337 -367.124043)
			(xy 124.430803 -367.078193) (xy 124.466494 -367.037002) (xy 124.507685 -367.001311) (xy 124.553535 -366.971845)
			(xy 124.603112 -366.949203) (xy 124.655407 -366.933848) (xy 124.709355 -366.926092) (xy 124.763857 -366.926092)
			(xy 124.817805 -366.933848) (xy 124.8701 -366.949203) (xy 124.919677 -366.971845) (xy 124.965527 -367.001311)
			(xy 125.006718 -367.037002) (xy 125.042409 -367.078193) (xy 125.071875 -367.124043) (xy 125.094517 -367.17362)
			(xy 125.109872 -367.225915) (xy 125.117628 -367.279863) (xy 125.118114 -367.307114) (xy 125.117566 -367.33603)
			(xy 125.108848 -367.393202) (xy 125.091598 -367.448401) (xy 125.066212 -367.500364) (xy 125.033272 -367.547898)
			(xy 124.993533 -367.589914) (xy 124.971048 -367.608104) (xy 124.959226 -367.617984) (xy 124.941702 -367.643311)
			(xy 124.932525 -367.67271) (xy 124.932527 -367.703508) (xy 124.94171 -367.732905) (xy 124.959237 -367.758228)
			(xy 124.971048 -367.768124) (xy 124.993553 -367.786289) (xy 125.033285 -367.828316) (xy 125.06622 -367.875857)
			(xy 125.091604 -367.927823) (xy 125.108856 -367.983024) (xy 125.117581 -368.040197) (xy 125.118114 -368.069114)
			(xy 126.488698 -368.069114) (xy 126.489227 -368.040198) (xy 126.497954 -367.983027) (xy 126.51521 -367.927828)
			(xy 126.5406 -367.875867) (xy 126.573541 -367.828332) (xy 126.61328 -367.786315) (xy 126.635764 -367.768124)
			(xy 126.647557 -367.758212) (xy 126.665079 -367.732894) (xy 126.674259 -367.703504) (xy 126.674261 -367.672713)
			(xy 126.665087 -367.643322) (xy 126.647569 -367.618) (xy 126.635764 -367.608104) (xy 126.613275 -367.58992)
			(xy 126.573542 -367.547898) (xy 126.540604 -367.500361) (xy 126.515217 -367.448398) (xy 126.497962 -367.3932)
			(xy 126.489233 -367.33603) (xy 126.488698 -367.307114) (xy 126.489184 -367.279863) (xy 126.49694 -367.225915)
			(xy 126.512295 -367.17362) (xy 126.534937 -367.124043) (xy 126.564403 -367.078193) (xy 126.600094 -367.037002)
			(xy 126.641285 -367.001311) (xy 126.687135 -366.971845) (xy 126.736712 -366.949203) (xy 126.789007 -366.933848)
			(xy 126.842955 -366.926092) (xy 126.897457 -366.926092) (xy 126.951405 -366.933848) (xy 127.0037 -366.949203)
			(xy 127.053277 -366.971845) (xy 127.099127 -367.001311) (xy 127.140318 -367.037002) (xy 127.176009 -367.078193)
			(xy 127.205475 -367.124043) (xy 127.228117 -367.17362) (xy 127.243472 -367.225915) (xy 127.251228 -367.279863)
			(xy 127.251714 -367.307114) (xy 127.251166 -367.33603) (xy 127.242448 -367.393202) (xy 127.225198 -367.448401)
			(xy 127.199812 -367.500364) (xy 127.166872 -367.547898) (xy 127.127133 -367.589914) (xy 127.104648 -367.608104)
			(xy 127.092826 -367.617984) (xy 127.075302 -367.643311) (xy 127.066125 -367.67271) (xy 127.066127 -367.703508)
			(xy 127.07531 -367.732905) (xy 127.092837 -367.758228) (xy 127.104648 -367.768124) (xy 127.127153 -367.786289)
			(xy 127.166885 -367.828316) (xy 127.19982 -367.875857) (xy 127.225204 -367.927823) (xy 127.242456 -367.983024)
			(xy 127.251181 -368.040197) (xy 127.25119 -368.040666) (xy 128.641348 -368.040666) (xy 128.641896 -368.01175)
			(xy 128.650616 -367.954579) (xy 128.667867 -367.89938) (xy 128.693253 -367.847418) (xy 128.726193 -367.799884)
			(xy 128.76593 -367.757867) (xy 128.788414 -367.739676) (xy 128.800251 -367.729814) (xy 128.817763 -367.70448)
			(xy 128.826932 -367.675078) (xy 128.826926 -367.64428) (xy 128.817744 -367.614882) (xy 128.800222 -367.589555)
			(xy 128.788414 -367.579656) (xy 128.765912 -367.561486) (xy 128.726178 -367.519463) (xy 128.69324 -367.471923)
			(xy 128.667855 -367.419958) (xy 128.650603 -367.364756) (xy 128.64188 -367.307583) (xy 128.641348 -367.278666)
			(xy 128.641834 -367.251415) (xy 128.64959 -367.197467) (xy 128.664945 -367.145172) (xy 128.687587 -367.095595)
			(xy 128.717053 -367.049745) (xy 128.752744 -367.008554) (xy 128.793935 -366.972863) (xy 128.839785 -366.943397)
			(xy 128.889362 -366.920755) (xy 128.941657 -366.9054) (xy 128.995605 -366.897644) (xy 129.050107 -366.897644)
			(xy 129.104055 -366.9054) (xy 129.15635 -366.920755) (xy 129.205927 -366.943397) (xy 129.251777 -366.972863)
			(xy 129.292968 -367.008554) (xy 129.328659 -367.049745) (xy 129.358125 -367.095595) (xy 129.380767 -367.145172)
			(xy 129.396122 -367.197467) (xy 129.403878 -367.251415) (xy 129.404364 -367.278666) (xy 129.403835 -367.307583)
			(xy 129.39511 -367.364754) (xy 129.377855 -367.419953) (xy 129.352466 -367.471915) (xy 129.319523 -367.519449)
			(xy 129.279783 -367.561466) (xy 129.257298 -367.579656) (xy 129.245528 -367.589592) (xy 129.228013 -367.614905)
			(xy 129.218835 -367.644288) (xy 129.218829 -367.675071) (xy 129.227994 -367.704457) (xy 129.2455 -367.729778)
			(xy 129.257298 -367.739676) (xy 129.27977 -367.757881) (xy 129.319506 -367.799898) (xy 129.352446 -367.84743)
			(xy 129.377836 -367.899388) (xy 129.395095 -367.954583) (xy 129.403827 -368.011751) (xy 129.404364 -368.040666)
			(xy 129.403878 -368.067917) (xy 129.396122 -368.121865) (xy 129.380767 -368.17416) (xy 129.358125 -368.223737)
			(xy 129.328659 -368.269587) (xy 129.292968 -368.310778) (xy 129.251777 -368.346469) (xy 129.205927 -368.375935)
			(xy 129.15635 -368.398577) (xy 129.104055 -368.413932) (xy 129.050107 -368.421688) (xy 128.995605 -368.421688)
			(xy 128.941657 -368.413932) (xy 128.889362 -368.398577) (xy 128.839785 -368.375935) (xy 128.793935 -368.346469)
			(xy 128.752744 -368.310778) (xy 128.717053 -368.269587) (xy 128.687587 -368.223737) (xy 128.664945 -368.17416)
			(xy 128.64959 -368.121865) (xy 128.641834 -368.067917) (xy 128.641348 -368.040666) (xy 127.25119 -368.040666)
			(xy 127.251714 -368.069114) (xy 127.251228 -368.096365) (xy 127.243472 -368.150313) (xy 127.228117 -368.202608)
			(xy 127.205475 -368.252185) (xy 127.176009 -368.298035) (xy 127.140318 -368.339226) (xy 127.099127 -368.374917)
			(xy 127.053277 -368.404383) (xy 127.0037 -368.427025) (xy 126.951405 -368.44238) (xy 126.897457 -368.450136)
			(xy 126.842955 -368.450136) (xy 126.789007 -368.44238) (xy 126.736712 -368.427025) (xy 126.687135 -368.404383)
			(xy 126.641285 -368.374917) (xy 126.600094 -368.339226) (xy 126.564403 -368.298035) (xy 126.534937 -368.252185)
			(xy 126.512295 -368.202608) (xy 126.49694 -368.150313) (xy 126.489184 -368.096365) (xy 126.488698 -368.069114)
			(xy 125.118114 -368.069114) (xy 125.117628 -368.096365) (xy 125.109872 -368.150313) (xy 125.094517 -368.202608)
			(xy 125.071875 -368.252185) (xy 125.042409 -368.298035) (xy 125.006718 -368.339226) (xy 124.965527 -368.374917)
			(xy 124.919677 -368.404383) (xy 124.8701 -368.427025) (xy 124.817805 -368.44238) (xy 124.763857 -368.450136)
			(xy 124.709355 -368.450136) (xy 124.655407 -368.44238) (xy 124.603112 -368.427025) (xy 124.553535 -368.404383)
			(xy 124.507685 -368.374917) (xy 124.466494 -368.339226) (xy 124.430803 -368.298035) (xy 124.401337 -368.252185)
			(xy 124.378695 -368.202608) (xy 124.36334 -368.150313) (xy 124.355584 -368.096365) (xy 124.355098 -368.069114)
			(xy 122.97029 -368.069114) (xy 122.969804 -368.096365) (xy 122.962048 -368.150313) (xy 122.946693 -368.202608)
			(xy 122.924051 -368.252185) (xy 122.894585 -368.298035) (xy 122.858894 -368.339226) (xy 122.817703 -368.374917)
			(xy 122.771853 -368.404383) (xy 122.722276 -368.427025) (xy 122.669981 -368.44238) (xy 122.616033 -368.450136)
			(xy 122.561531 -368.450136) (xy 122.507583 -368.44238) (xy 122.455288 -368.427025) (xy 122.405711 -368.404383)
			(xy 122.359861 -368.374917) (xy 122.31867 -368.339226) (xy 122.282979 -368.298035) (xy 122.253513 -368.252185)
			(xy 122.230871 -368.202608) (xy 122.215516 -368.150313) (xy 122.20776 -368.096365) (xy 122.207274 -368.069114)
			(xy 121.825273 -368.069114) (xy 121.791195 -368.107148) (xy 121.748327 -368.142823) (xy 121.700721 -368.171877)
			(xy 121.649392 -368.193689) (xy 121.595435 -368.207795) (xy 121.539998 -368.213895) (xy 121.484264 -368.211858)
			(xy 121.429421 -368.201728) (xy 121.376637 -368.183721) (xy 121.327037 -368.15822) (xy 121.281679 -368.125769)
			(xy 121.24153 -368.08706) (xy 121.207444 -368.042917) (xy 121.180148 -367.994282) (xy 121.160225 -367.942191)
			(xy 121.148099 -367.887754) (xy 121.144028 -367.832132) (xy 119.924068 -367.832132) (xy 119.924068 -370.378228)
			(xy 132.87756 -370.378228) (xy 133.958076 -369.297712) (xy 133.967762 -369.287293) (xy 133.981466 -369.262377)
			(xy 133.987767 -369.234647) (xy 133.986179 -369.206256) (xy 133.976824 -369.179402) (xy 133.960427 -369.15617)
			(xy 133.93826 -369.138359) (xy 133.912041 -369.12735) (xy 133.883803 -369.123998) (xy 133.869684 -369.125754)
			(xy 133.834122 -369.131217) (xy 133.762405 -369.137067) (xy 133.726428 -369.137438) (xy 133.725412 -369.137438)
			(xy 133.683485 -369.136955) (xy 133.600003 -369.129065) (xy 133.517633 -369.113353) (xy 133.437108 -369.089959)
			(xy 133.359142 -369.059091) (xy 133.284427 -369.021023) (xy 133.213626 -368.976092) (xy 133.147368 -368.924697)
			(xy 133.08624 -368.867295) (xy 133.030786 -368.804396) (xy 132.981498 -368.736556) (xy 132.938812 -368.664379)
			(xy 132.903109 -368.588506) (xy 132.874704 -368.509609) (xy 132.85385 -368.428389) (xy 132.840732 -368.345567)
			(xy 132.835467 -368.261878) (xy 132.838101 -368.178065) (xy 132.848611 -368.094872) (xy 132.866904 -368.013038)
			(xy 132.892817 -367.933287) (xy 132.92612 -367.85633) (xy 132.966518 -367.782848) (xy 133.013651 -367.713494)
			(xy 133.067103 -367.648884) (xy 133.126397 -367.589591) (xy 133.191009 -367.536141) (xy 133.260364 -367.489008)
			(xy 133.333846 -367.448612) (xy 133.410804 -367.415311) (xy 133.490555 -367.389399) (xy 133.57239 -367.371108)
			(xy 133.655583 -367.3606) (xy 133.739396 -367.357968) (xy 133.823085 -367.363234) (xy 133.905907 -367.376354)
			(xy 133.987126 -367.397209) (xy 134.066023 -367.425615) (xy 134.141895 -367.461321) (xy 134.214071 -367.504008)
			(xy 134.28191 -367.553298) (xy 134.344808 -367.608753) (xy 134.402209 -367.669882) (xy 134.453602 -367.736141)
			(xy 134.498532 -367.806943) (xy 134.536598 -367.881659) (xy 134.567465 -367.959625) (xy 134.590857 -368.040151)
			(xy 134.606567 -368.12252) (xy 134.614456 -368.206003) (xy 134.61492 -368.24793) (xy 134.61492 -368.248946)
			(xy 134.614543 -368.284923) (xy 134.608696 -368.35664) (xy 134.603236 -368.392202) (xy 134.601378 -368.406331)
			(xy 134.60467 -368.434626) (xy 134.615655 -368.460909) (xy 134.633476 -368.483132) (xy 134.656745 -368.499563)
			(xy 134.68365 -368.508922) (xy 134.712093 -368.510481) (xy 134.739859 -368.504117) (xy 134.764784 -368.490327)
			(xy 134.775194 -368.480594) (xy 136.179814 -367.075974) (xy 136.17829 -367.053114) (xy 136.177528 -367.029238)
			(xy 136.177528 -363.895894) (xy 133.34365 -361.062016) (xy 129.348484 -361.062016) (xy 129.321233 -361.061529)
			(xy 129.267286 -361.053771) (xy 129.214992 -361.038414) (xy 129.165416 -361.015771) (xy 129.119566 -360.986304)
			(xy 129.078377 -360.950612) (xy 129.042687 -360.909421) (xy 129.013221 -360.86357) (xy 128.990581 -360.813993)
			(xy 128.975226 -360.761699) (xy 128.96747 -360.707751) (xy 128.96747 -360.653249) (xy 128.975226 -360.599301)
			(xy 128.990581 -360.547007) (xy 129.013221 -360.49743) (xy 129.042687 -360.451579) (xy 129.078377 -360.410388)
			(xy 129.119566 -360.374696) (xy 129.165416 -360.345229) (xy 129.214992 -360.322586) (xy 129.267286 -360.307229)
			(xy 129.321233 -360.299471) (xy 129.348484 -360.299) (xy 133.501638 -360.299) (xy 133.53162 -360.299554)
			(xy 133.590845 -360.30893) (xy 133.647874 -360.32746) (xy 133.701298 -360.354688) (xy 133.749803 -360.389942)
			(xy 133.771386 -360.41076) (xy 136.828784 -363.468158) (xy 136.849564 -363.489772) (xy 136.884804 -363.538277)
			(xy 136.912026 -363.591696) (xy 136.930559 -363.648714) (xy 136.939949 -363.707929) (xy 136.940544 -363.737906)
			(xy 136.940544 -366.070134) (xy 136.941066 -366.085107) (xy 136.949741 -366.113769) (xy 136.966364 -366.138677)
			(xy 136.989503 -366.157687) (xy 137.017164 -366.16916) (xy 137.046964 -366.172108) (xy 137.076337 -366.166278)
			(xy 137.102752 -366.15217) (xy 137.113772 -366.142016) (xy 146.74342 -356.512368) (xy 146.74342 -338.529168)
			(xy 140.31722 -332.102968) (xy 133.85546 -332.102968) (xy 133.38937 -331.636878) (xy 133.375908 -331.633322)
			(xy 133.347506 -331.625149) (xy 133.2943 -331.599438) (xy 133.270244 -331.582268) (xy 133.261477 -331.575629)
			(xy 133.244822 -331.561265) (xy 133.23697 -331.553566) (xy 131.646168 -329.962764) (xy 127.074168 -329.962764)
			(xy 127.047752 -329.936348) (xy 126.74092 -329.936348) (xy 123.27382 -326.469248) (xy 95.35922 -326.469248)
			(xy 92.03944 -329.789028) (xy 86.47684 -329.789028) (xy 85.32114 -330.944728) (xy 85.32114 -332.496668)
			(xy 84.52612 -333.291688) (xy 77.23378 -333.291688) (xy 75.89774 -334.627728) (xy 75.89774 -344.386662)
			(xy 76.764134 -344.386662) (xy 76.76463 -344.358787) (xy 76.772738 -344.30363) (xy 76.78879 -344.250241)
			(xy 76.812445 -344.199758) (xy 76.843197 -344.153257) (xy 76.861416 -344.132154) (xy 76.870925 -344.1207)
			(xy 76.883559 -344.093762) (xy 76.887897 -344.064327) (xy 76.883574 -344.03489) (xy 76.870955 -344.007945)
			(xy 76.861416 -343.996518) (xy 76.843252 -343.975445) (xy 76.812577 -343.929035) (xy 76.788984 -343.878654)
			(xy 76.772974 -343.825375) (xy 76.764889 -343.770334) (xy 76.764388 -343.742518) (xy 76.764388 -343.742264)
			(xy 76.764843 -343.715024) (xy 76.772598 -343.661097) (xy 76.787945 -343.608823) (xy 76.810571 -343.559262)
			(xy 76.840017 -343.513425) (xy 76.875684 -343.472241) (xy 76.916847 -343.436551) (xy 76.962667 -343.407078)
			(xy 77.012214 -343.384423) (xy 77.06448 -343.369045) (xy 77.118402 -343.361259) (xy 77.145642 -343.360756)
			(xy 77.812138 -343.360756) (xy 77.842116 -343.361323) (xy 77.901332 -343.37072) (xy 77.958351 -343.38926)
			(xy 78.011769 -343.416488) (xy 78.060273 -343.451733) (xy 78.081886 -343.472516) (xy 78.417928 -343.808812)
			(xy 80.500728 -343.808812) (xy 81.0387 -343.270586) (xy 81.060313 -343.249893) (xy 81.108731 -343.214747)
			(xy 81.162042 -343.187589) (xy 81.218938 -343.169086) (xy 81.278026 -343.159691) (xy 81.30794 -343.15908)
			(xy 83.32851 -343.15908) (xy 83.875372 -342.612218) (xy 83.875372 -341.009986) (xy 83.875767 -340.985043)
			(xy 83.882272 -340.935584) (xy 83.895169 -340.887394) (xy 83.904328 -340.86419) (xy 84.160614 -340.244938)
			(xy 84.168004 -340.227698) (xy 84.185691 -340.19462) (xy 84.19592 -340.178898) (xy 84.687918 -339.442552)
			(xy 84.69845 -339.427076) (xy 84.722119 -339.398068) (xy 84.735162 -339.38464) (xy 84.94268 -339.177376)
			(xy 84.952137 -339.1673) (xy 84.96569 -339.143226) (xy 84.972298 -339.116402) (xy 84.971478 -339.088788)
			(xy 84.96329 -339.062404) (xy 84.948333 -339.039177) (xy 84.9277 -339.020806) (xy 84.915502 -339.014308)
			(xy 84.891792 -339.002207) (xy 84.847687 -338.972404) (xy 84.808155 -338.936757) (xy 84.773964 -338.895959)
			(xy 84.745779 -338.850802) (xy 84.724149 -338.802165) (xy 84.709492 -338.750991) (xy 84.702095 -338.698277)
			(xy 84.701634 -338.671662) (xy 84.702116 -338.644941) (xy 84.709579 -338.592022) (xy 84.724354 -338.540663)
			(xy 84.746151 -338.491868) (xy 84.774545 -338.446593) (xy 84.808979 -338.405722) (xy 84.84878 -338.370057)
			(xy 84.893168 -338.340296) (xy 84.917026 -338.328254) (xy 84.930122 -338.321249) (xy 84.951952 -338.301138)
			(xy 84.967085 -338.275603) (xy 84.974245 -338.246798) (xy 84.972829 -338.21715) (xy 84.962956 -338.189158)
			(xy 84.954618 -338.17687) (xy 84.937361 -338.152277) (xy 84.909988 -338.098797) (xy 84.891321 -338.041693)
			(xy 84.881821 -337.982372) (xy 84.881212 -337.952334) (xy 84.881212 -337.951572) (xy 84.881651 -337.924331)
			(xy 84.889405 -337.870403) (xy 84.904752 -337.818126) (xy 84.927379 -337.768564) (xy 84.956827 -337.722725)
			(xy 84.992496 -337.681541) (xy 85.03366 -337.64585) (xy 85.079483 -337.616378) (xy 85.129033 -337.593724)
			(xy 85.181301 -337.578349) (xy 85.235225 -337.570566) (xy 85.262466 -337.570064) (xy 86.054946 -337.570064)
			(xy 86.084925 -337.570624) (xy 86.144141 -337.580022) (xy 86.20116 -337.598564) (xy 86.254578 -337.625793)
			(xy 86.303081 -337.66104) (xy 86.324694 -337.681824) (xy 86.74481 -338.10194) (xy 88.583516 -338.10194)
			(xy 89.26322 -337.422236) (xy 89.284796 -337.401411) (xy 89.333303 -337.366158) (xy 89.38673 -337.338932)
			(xy 89.443759 -337.320403) (xy 89.502986 -337.311029) (xy 89.532968 -337.310476) (xy 91.28125 -337.310476)
			(xy 92.688664 -335.903062) (xy 92.706594 -335.885699) (xy 92.746207 -335.855335) (xy 92.789448 -335.830406)
			(xy 92.812362 -335.820512) (xy 93.18498 -335.66608) (xy 93.197399 -335.660504) (xy 93.218914 -335.643842)
			(xy 93.235254 -335.622081) (xy 93.245255 -335.596773) (xy 93.248204 -335.56972) (xy 93.24389 -335.542851)
			(xy 93.232621 -335.518081) (xy 93.215201 -335.497175) (xy 93.204284 -335.489042) (xy 93.183088 -335.47366)
			(xy 93.144685 -335.438052) (xy 93.111513 -335.397526) (xy 93.084196 -335.352844) (xy 93.063246 -335.304846)
			(xy 93.049059 -335.254433) (xy 93.0419 -335.202554) (xy 93.04147 -335.176368) (xy 93.041915 -335.150684)
			(xy 93.048829 -335.099783) (xy 93.062514 -335.050271) (xy 93.082722 -335.003045) (xy 93.109087 -334.958959)
			(xy 93.124782 -334.938624) (xy 93.133538 -334.926889) (xy 93.144561 -334.899776) (xy 93.147434 -334.870649)
			(xy 93.14192 -334.841905) (xy 93.128475 -334.815909) (xy 93.118686 -334.80502) (xy 93.098966 -334.783577)
			(xy 93.065559 -334.735854) (xy 93.039787 -334.683613) (xy 93.022246 -334.628063) (xy 93.013345 -334.570494)
			(xy 93.012768 -334.541368) (xy 93.013248 -334.514117) (xy 93.021008 -334.46017) (xy 93.036366 -334.407877)
			(xy 93.059009 -334.358301) (xy 93.088477 -334.312452) (xy 93.124169 -334.271263) (xy 93.165359 -334.235572)
			(xy 93.211208 -334.206105) (xy 93.260784 -334.183463) (xy 93.313078 -334.168107) (xy 93.367025 -334.160347)
			(xy 93.394276 -334.15986) (xy 94.215458 -334.15986) (xy 94.245434 -334.160476) (xy 94.304648 -334.169861)
			(xy 94.361666 -334.188389) (xy 94.415085 -334.215606) (xy 94.463591 -334.250842) (xy 94.485206 -334.27162)
			(xy 94.867476 -334.654144) (xy 96.770444 -334.654144) (xy 97.152714 -334.27162) (xy 97.17429 -334.250795)
			(xy 97.222797 -334.215543) (xy 97.276224 -334.188317) (xy 97.333253 -334.169788) (xy 97.39248 -334.160413)
			(xy 97.422462 -334.15986) (xy 102.212902 -334.15986) (xy 102.242879 -334.160449) (xy 102.302095 -334.16984)
			(xy 102.359113 -334.188375) (xy 102.412532 -334.215598) (xy 102.461036 -334.250839) (xy 102.48265 -334.27162)
			(xy 102.786434 -334.575404) (xy 105.038652 -334.575404) (xy 105.342436 -334.27162) (xy 105.364046 -334.250832)
			(xy 105.412544 -334.215575) (xy 105.465962 -334.188343) (xy 105.522984 -334.169805) (xy 105.582204 -334.160419)
			(xy 105.612184 -334.15986) (xy 110.328202 -334.15986) (xy 110.358179 -334.160449) (xy 110.417395 -334.16984)
			(xy 110.474413 -334.188375) (xy 110.527832 -334.215598) (xy 110.576336 -334.250839) (xy 110.59795 -334.27162)
			(xy 110.98022 -334.654144) (xy 113.107724 -334.654144) (xy 113.489994 -334.27162) (xy 113.511579 -334.250804)
			(xy 113.560084 -334.215551) (xy 113.613508 -334.188324) (xy 113.670536 -334.169792) (xy 113.729761 -334.160415)
			(xy 113.759742 -334.15986) (xy 117.904514 -334.15986) (xy 117.929419 -334.160253) (xy 117.978803 -334.166742)
			(xy 118.026925 -334.179596) (xy 118.072968 -334.198596) (xy 118.09476 -334.21066) (xy 118.658386 -334.21066)
			(xy 118.684362 -334.211194) (xy 118.735665 -334.219385) (xy 118.785059 -334.235489) (xy 118.831331 -334.259112)
			(xy 118.873345 -334.289672) (xy 118.892066 -334.307688) (xy 119.501666 -334.917288) (xy 119.519653 -334.936023)
			(xy 119.550176 -334.978041) (xy 119.573752 -335.024315) (xy 119.589801 -335.073707) (xy 119.597929 -335.125001)
			(xy 119.59844 -335.150968) (xy 119.59844 -335.502504) (xy 119.630127 -335.579) (xy 121.771617 -335.579)
			(xy 121.775785 -335.523381) (xy 121.788196 -335.469004) (xy 121.808573 -335.417085) (xy 121.83646 -335.368782)
			(xy 121.871235 -335.325175) (xy 121.91212 -335.287238) (xy 121.958203 -335.255818) (xy 122.008454 -335.231617)
			(xy 122.061751 -335.215176) (xy 122.116903 -335.206862) (xy 122.14479 -335.20634) (xy 122.172123 -335.206784)
			(xy 122.226204 -335.214758) (xy 122.278539 -335.230551) (xy 122.328004 -335.253823) (xy 122.373536 -335.284075)
			(xy 122.414157 -335.320657) (xy 122.448995 -335.362784) (xy 122.46356 -335.385918) (xy 122.471444 -335.39817)
			(xy 122.492927 -335.417839) (xy 122.519091 -335.430639) (xy 122.547805 -335.435527) (xy 122.57673 -335.432105)
			(xy 122.590306 -335.426812) (xy 122.613518 -335.417329) (xy 122.66185 -335.403975) (xy 122.711539 -335.397245)
			(xy 122.73661 -335.39684) (xy 122.761679 -335.397272) (xy 122.811362 -335.404018) (xy 122.859696 -335.417347)
			(xy 122.882914 -335.426812) (xy 122.89651 -335.432003) (xy 122.925401 -335.435379) (xy 122.954073 -335.430481)
			(xy 122.980204 -335.417706) (xy 123.001678 -335.398087) (xy 123.00966 -335.385918) (xy 123.024229 -335.362787)
			(xy 123.059072 -335.320666) (xy 123.099695 -335.284087) (xy 123.145226 -335.253836) (xy 123.194688 -335.23056)
			(xy 123.247019 -335.21476) (xy 123.301098 -335.206774) (xy 123.355762 -335.206774) (xy 123.409841 -335.21476)
			(xy 123.462172 -335.23056) (xy 123.511634 -335.253836) (xy 123.557165 -335.284087) (xy 123.597788 -335.320666)
			(xy 123.632631 -335.362787) (xy 123.6472 -335.385918) (xy 123.655141 -335.398129) (xy 123.676608 -335.417798)
			(xy 123.702757 -335.430603) (xy 123.731457 -335.435502) (xy 123.760373 -335.432096) (xy 123.773946 -335.426812)
			(xy 123.797154 -335.417317) (xy 123.845488 -335.403968) (xy 123.895178 -335.397242) (xy 123.92025 -335.39684)
			(xy 123.948136 -335.397416) (xy 124.003286 -335.405721) (xy 124.056582 -335.422155) (xy 124.106833 -335.446348)
			(xy 124.152917 -335.477762) (xy 124.193803 -335.515694) (xy 124.228579 -335.559296) (xy 124.256467 -335.607595)
			(xy 124.276844 -335.659511) (xy 124.289256 -335.713884) (xy 124.293424 -335.7695) (xy 124.289256 -335.825116)
			(xy 124.276844 -335.879489) (xy 124.256467 -335.931405) (xy 124.228579 -335.979704) (xy 124.193803 -336.023306)
			(xy 124.152917 -336.061238) (xy 124.106833 -336.092652) (xy 124.056582 -336.116845) (xy 124.003286 -336.133279)
			(xy 123.948136 -336.141584) (xy 123.92025 -336.142076) (xy 123.892918 -336.141593) (xy 123.838839 -336.133625)
			(xy 123.786506 -336.117839) (xy 123.737042 -336.094572) (xy 123.691509 -336.064327) (xy 123.650887 -336.02775)
			(xy 123.616046 -335.985629) (xy 123.60148 -335.962498) (xy 123.593554 -335.950276) (xy 123.572084 -335.930605)
			(xy 123.545931 -335.9178) (xy 123.517226 -335.912904) (xy 123.488308 -335.916316) (xy 123.474734 -335.921604)
			(xy 123.451517 -335.931076) (xy 123.403188 -335.944433) (xy 123.353501 -335.951169) (xy 123.32843 -335.951576)
			(xy 123.30336 -335.951163) (xy 123.253677 -335.944409) (xy 123.205343 -335.931072) (xy 123.182126 -335.921604)
			(xy 123.168553 -335.916343) (xy 123.13965 -335.912979) (xy 123.110969 -335.917892) (xy 123.084834 -335.930685)
			(xy 123.063359 -335.950321) (xy 123.05538 -335.962498) (xy 123.040811 -335.985629) (xy 123.005968 -336.02775)
			(xy 122.965345 -336.064329) (xy 122.919814 -336.09458) (xy 122.870352 -336.117856) (xy 122.818021 -336.133656)
			(xy 122.763942 -336.141642) (xy 122.709278 -336.141642) (xy 122.655199 -336.133656) (xy 122.602868 -336.117856)
			(xy 122.553406 -336.09458) (xy 122.507875 -336.064329) (xy 122.467252 -336.02775) (xy 122.432409 -335.985629)
			(xy 122.41784 -335.962498) (xy 122.409952 -335.950248) (xy 122.388471 -335.930577) (xy 122.362308 -335.917776)
			(xy 122.333594 -335.912888) (xy 122.304669 -335.91631) (xy 122.291094 -335.921604) (xy 122.267882 -335.931088)
			(xy 122.21955 -335.944441) (xy 122.169861 -335.951171) (xy 122.14479 -335.951576) (xy 122.116903 -335.951138)
			(xy 122.061751 -335.942824) (xy 122.008454 -335.926383) (xy 121.958203 -335.902182) (xy 121.91212 -335.870762)
			(xy 121.871235 -335.832825) (xy 121.83646 -335.789218) (xy 121.808573 -335.740915) (xy 121.788196 -335.688996)
			(xy 121.775785 -335.634619) (xy 121.771617 -335.579) (xy 119.630127 -335.579) (xy 119.753634 -335.877154)
			(xy 120.00865 -336.131916) (xy 121.01068 -336.131916) (xy 121.032327 -336.132328) (xy 121.075242 -336.138062)
			(xy 121.117046 -336.149333) (xy 121.137172 -336.157316) (xy 121.898664 -336.472784) (xy 121.918521 -336.481375)
			(xy 121.955986 -336.503017) (xy 121.990307 -336.529363) (xy 122.005852 -336.544412) (xy 122.944223 -337.482688)
			(xy 123.707398 -337.482688) (xy 123.707925 -337.455116) (xy 123.715865 -337.400546) (xy 123.731578 -337.347687)
			(xy 123.754737 -337.297641) (xy 123.784858 -337.251449) (xy 123.821316 -337.210076) (xy 123.842018 -337.191858)
			(xy 123.852925 -337.18197) (xy 123.868994 -337.157316) (xy 123.877374 -337.129106) (xy 123.877372 -337.099678)
			(xy 123.868987 -337.071469) (xy 123.852915 -337.046818) (xy 123.842018 -337.036918) (xy 123.821316 -337.018697)
			(xy 123.784844 -336.977331) (xy 123.75471 -336.931143) (xy 123.731543 -336.881097) (xy 123.715825 -336.828236)
			(xy 123.707884 -336.773662) (xy 123.707398 -336.746088) (xy 123.707867 -336.718836) (xy 123.715625 -336.664888)
			(xy 123.730982 -336.612592) (xy 123.753625 -336.563014) (xy 123.783093 -336.517164) (xy 123.818786 -336.475974)
			(xy 123.859978 -336.440282) (xy 123.90583 -336.410816) (xy 123.955409 -336.388176) (xy 124.007705 -336.372821)
			(xy 124.061654 -336.365065) (xy 124.088906 -336.36458) (xy 124.089668 -336.36458) (xy 124.101639 -336.364688)
			(xy 124.125532 -336.366216) (xy 124.13742 -336.367628) (xy 124.151183 -336.36885) (xy 124.178509 -336.364881)
			(xy 124.203774 -336.353739) (xy 124.225132 -336.336237) (xy 124.241022 -336.313655) (xy 124.250284 -336.287641)
			(xy 124.25172 -336.273902) (xy 124.254288 -336.245371) (xy 124.26677 -336.189468) (xy 124.287472 -336.136059)
			(xy 124.315929 -336.086348) (xy 124.351502 -336.041452) (xy 124.393389 -336.002382) (xy 124.440649 -335.970016)
			(xy 124.492218 -335.945083) (xy 124.546936 -335.928143) (xy 124.603572 -335.919578) (xy 124.632212 -335.919064)
			(xy 124.650231 -335.919288) (xy 124.686106 -335.92272) (xy 124.70384 -335.925922) (xy 124.719042 -335.928328)
			(xy 124.749605 -335.924788) (xy 124.77773 -335.912312) (xy 124.800866 -335.89203) (xy 124.816917 -335.865781)
			(xy 124.821188 -335.850992) (xy 124.828636 -335.823962) (xy 124.850258 -335.772237) (xy 124.879215 -335.724232)
			(xy 124.914884 -335.68098) (xy 124.956497 -335.643411) (xy 125.003158 -335.612335) (xy 125.053864 -335.588419)
			(xy 125.107523 -335.57218) (xy 125.162981 -335.563965) (xy 125.191012 -335.563464) (xy 125.218262 -335.563967)
			(xy 125.272208 -335.571724) (xy 125.324501 -335.587079) (xy 125.374076 -335.60972) (xy 125.419925 -335.639185)
			(xy 125.461114 -335.674874) (xy 125.496806 -335.716062) (xy 125.526273 -335.76191) (xy 125.548915 -335.811484)
			(xy 125.564273 -335.863776) (xy 125.572032 -335.917722) (xy 125.57252 -335.944972) (xy 125.572028 -335.972546)
			(xy 125.56408 -336.027117) (xy 125.54836 -336.079976) (xy 125.525194 -336.130022) (xy 125.495067 -336.176212)
			(xy 125.458605 -336.217585) (xy 125.4379 -336.235802) (xy 125.427031 -336.245729) (xy 125.410958 -336.270371)
			(xy 125.402572 -336.298572) (xy 125.402566 -336.327992) (xy 125.410943 -336.356195) (xy 125.427007 -336.380843)
			(xy 125.4379 -336.390742) (xy 125.458577 -336.408988) (xy 125.495041 -336.450356) (xy 125.525168 -336.496542)
			(xy 125.548331 -336.546585) (xy 125.564048 -336.599441) (xy 125.57199 -336.65401) (xy 125.571993 -336.709154)
			(xy 125.564056 -336.763723) (xy 125.548344 -336.816581) (xy 125.525186 -336.866626) (xy 125.495063 -336.912816)
			(xy 125.458603 -336.954186) (xy 125.4379 -336.972402) (xy 125.427031 -336.982329) (xy 125.410958 -337.006971)
			(xy 125.402572 -337.035172) (xy 125.402566 -337.064592) (xy 125.410943 -337.092795) (xy 125.427007 -337.117443)
			(xy 125.4379 -337.127342) (xy 125.458586 -337.14558) (xy 125.495059 -337.186943) (xy 125.525194 -337.233127)
			(xy 125.548364 -337.28317) (xy 125.564086 -337.336028) (xy 125.572031 -337.390599) (xy 125.57252 -337.418172)
			(xy 125.572019 -337.445424) (xy 125.564266 -337.499373) (xy 125.548914 -337.551669) (xy 125.526276 -337.601248)
			(xy 125.496812 -337.647101) (xy 125.461122 -337.688294) (xy 125.419933 -337.723988) (xy 125.374083 -337.753456)
			(xy 125.324506 -337.7761) (xy 125.272212 -337.791457) (xy 125.218264 -337.799216) (xy 125.191012 -337.79968)
			(xy 125.163156 -337.799161) (xy 125.10804 -337.791038) (xy 125.054689 -337.774993) (xy 125.004235 -337.751367)
			(xy 124.95775 -337.720659) (xy 124.916221 -337.683523) (xy 124.880528 -337.640747) (xy 124.85143 -337.593238)
			(xy 124.829543 -337.542006) (xy 124.82195 -337.5152) (xy 124.817696 -337.501077) (xy 124.802301 -337.475931)
			(xy 124.780378 -337.456216) (xy 124.753745 -337.443567) (xy 124.724611 -337.439033) (xy 124.709936 -337.440524)
			(xy 124.697109 -337.442177) (xy 124.671306 -337.443953) (xy 124.658374 -337.44408) (xy 124.657612 -337.44408)
			(xy 124.639981 -337.443844) (xy 124.604873 -337.440538) (xy 124.587508 -337.437476) (xy 124.573734 -337.435253)
			(xy 124.545948 -337.437699) (xy 124.519864 -337.447584) (xy 124.497434 -337.464166) (xy 124.480337 -337.486207)
			(xy 124.469852 -337.512055) (xy 124.467874 -337.525868) (xy 124.464232 -337.553444) (xy 124.450001 -337.607215)
			(xy 124.428107 -337.658348) (xy 124.399017 -337.705757) (xy 124.363347 -337.748436) (xy 124.321855 -337.78548)
			(xy 124.27542 -337.816102) (xy 124.225029 -337.839652) (xy 124.171752 -337.85563) (xy 124.116717 -337.863699)
			(xy 124.088906 -337.864196) (xy 124.061653 -337.863739) (xy 124.007701 -337.855983) (xy 123.955402 -337.840627)
			(xy 123.905821 -337.817984) (xy 123.859968 -337.788516) (xy 123.818775 -337.752821) (xy 123.783081 -337.711628)
			(xy 123.753613 -337.665773) (xy 123.730971 -337.616192) (xy 123.715616 -337.563893) (xy 123.707861 -337.509941)
			(xy 123.707398 -337.482688) (xy 122.944223 -337.482688) (xy 124.515118 -339.053424) (xy 125.741938 -339.053424)
			(xy 125.755533 -339.052918) (xy 125.781744 -339.045676) (xy 125.805111 -339.03177) (xy 125.823978 -339.012186)
			(xy 125.837003 -338.988317) (xy 125.843263 -338.961854) (xy 125.842313 -338.934678) (xy 125.834221 -338.908718)
			(xy 125.81956 -338.885816) (xy 125.809756 -338.876386) (xy 125.790255 -338.858229) (xy 125.756003 -338.817411)
			(xy 125.727766 -338.772225) (xy 125.706092 -338.723548) (xy 125.691402 -338.672329) (xy 125.683984 -338.619564)
			(xy 125.683518 -338.592922) (xy 125.684017 -338.56487) (xy 125.692248 -338.509373) (xy 125.70852 -338.455681)
			(xy 125.732483 -338.404952) (xy 125.76362 -338.35828) (xy 125.78207 -338.337144) (xy 125.791719 -338.325713)
			(xy 125.80446 -338.298661) (xy 125.808827 -338.269079) (xy 125.804448 -338.239499) (xy 125.791696 -338.212452)
			(xy 125.78207 -338.201) (xy 125.76367 -338.179899) (xy 125.732629 -338.133309) (xy 125.708735 -338.082679)
			(xy 125.692503 -338.029099) (xy 125.684282 -337.973722) (xy 125.683772 -337.94573) (xy 125.683772 -337.945222)
			(xy 125.684229 -337.917987) (xy 125.691979 -337.86407) (xy 125.707323 -337.811805) (xy 125.72995 -337.762256)
			(xy 125.759398 -337.716432) (xy 125.795069 -337.675266) (xy 125.836236 -337.639596) (xy 125.88206 -337.610148)
			(xy 125.931609 -337.587522) (xy 125.983874 -337.572178) (xy 126.037791 -337.564429) (xy 126.065026 -337.563968)
			(xy 126.586234 -337.563968) (xy 126.616151 -337.564599) (xy 126.675249 -337.573958) (xy 126.732157 -337.59244)
			(xy 126.785476 -337.619591) (xy 126.833896 -337.654744) (xy 126.855474 -337.675474) (xy 127.363474 -338.183474)
			(xy 127.384213 -338.205044) (xy 127.419351 -338.253475) (xy 127.446499 -338.306797) (xy 127.464991 -338.363702)
			(xy 127.474375 -338.422797) (xy 127.47498 -338.452714) (xy 127.47498 -338.835746) (xy 127.628434 -338.9892)
			(xy 129.932095 -338.9892) (xy 129.936264 -338.933577) (xy 129.948676 -338.879196) (xy 129.969055 -338.827272)
			(xy 129.996944 -338.778966) (xy 130.031722 -338.735356) (xy 130.072612 -338.697416) (xy 130.118699 -338.665995)
			(xy 130.168955 -338.641793) (xy 130.222256 -338.625352) (xy 130.277412 -338.617039) (xy 130.305302 -338.616544)
			(xy 130.332635 -338.616977) (xy 130.386717 -338.624953) (xy 130.439052 -338.640747) (xy 130.488517 -338.664021)
			(xy 130.534049 -338.694275) (xy 130.57467 -338.730859) (xy 130.609508 -338.772987) (xy 130.624072 -338.796122)
			(xy 130.631944 -338.808383) (xy 130.65343 -338.828052) (xy 130.679597 -338.84085) (xy 130.708314 -338.845736)
			(xy 130.737242 -338.842311) (xy 130.750818 -338.837016) (xy 130.774029 -338.827529) (xy 130.822361 -338.814177)
			(xy 130.87205 -338.807448) (xy 130.897122 -338.807044) (xy 130.922191 -338.807471) (xy 130.971874 -338.814219)
			(xy 131.020209 -338.82755) (xy 131.043426 -338.837016) (xy 131.057019 -338.842218) (xy 131.085911 -338.845591)
			(xy 131.114584 -338.840691) (xy 131.140716 -338.827912) (xy 131.16219 -338.808292) (xy 131.170172 -338.796122)
			(xy 131.184741 -338.772991) (xy 131.219584 -338.73087) (xy 131.260207 -338.694291) (xy 131.305738 -338.66404)
			(xy 131.3552 -338.640764) (xy 131.407531 -338.624964) (xy 131.46161 -338.616978) (xy 131.516274 -338.616978)
			(xy 131.570353 -338.624964) (xy 131.622684 -338.640764) (xy 131.672146 -338.66404) (xy 131.717677 -338.694291)
			(xy 131.7583 -338.73087) (xy 131.793143 -338.772991) (xy 131.807712 -338.796122) (xy 131.815641 -338.808342)
			(xy 131.837112 -338.82801) (xy 131.863263 -338.840814) (xy 131.891967 -338.845711) (xy 131.920884 -338.842302)
			(xy 131.934458 -338.837016) (xy 131.957664 -338.827517) (xy 132.005999 -338.814169) (xy 132.05569 -338.807445)
			(xy 132.080762 -338.807044) (xy 132.105703 -338.807423) (xy 132.15514 -338.81407) (xy 132.203249 -338.827251)
			(xy 132.249171 -338.84673) (xy 132.292085 -338.872159) (xy 132.311902 -338.887308) (xy 132.3234 -338.89589)
			(xy 132.34993 -338.906786) (xy 132.378445 -338.909859) (xy 132.406688 -338.904866) (xy 132.432421 -338.892202)
			(xy 132.453607 -338.87287) (xy 132.461508 -338.860892) (xy 132.476508 -338.837421) (xy 132.512171 -338.794638)
			(xy 132.553678 -338.757497) (xy 132.600146 -338.726789) (xy 132.650587 -338.703166) (xy 132.703928 -338.687133)
			(xy 132.759033 -338.679028) (xy 132.786882 -338.67852) (xy 132.815037 -338.678965) (xy 132.870737 -338.687226)
			(xy 132.924618 -338.703587) (xy 132.975508 -338.727691) (xy 133.0223 -338.759016) (xy 133.06398 -338.796879)
			(xy 133.099639 -338.840459) (xy 133.128504 -338.888807) (xy 133.149947 -338.940874) (xy 133.157214 -338.96808)
			(xy 133.161562 -338.983021) (xy 133.177813 -339.009536) (xy 133.201287 -339.029935) (xy 133.229809 -339.042329)
			(xy 133.260739 -339.04557) (xy 133.276086 -339.04301) (xy 133.294808 -339.039458) (xy 133.332724 -339.035641)
			(xy 133.351778 -339.03539) (xy 133.352032 -339.03539) (xy 133.379282 -339.035882) (xy 133.433226 -339.043642)
			(xy 133.485516 -339.059) (xy 133.535089 -339.081643) (xy 133.580935 -339.11111) (xy 133.622122 -339.146801)
			(xy 133.657809 -339.18799) (xy 133.687273 -339.233839) (xy 133.709911 -339.283414) (xy 133.725265 -339.335706)
			(xy 133.73302 -339.38965) (xy 133.73302 -339.44415) (xy 133.725265 -339.498094) (xy 133.709911 -339.550386)
			(xy 133.687273 -339.599961) (xy 133.657809 -339.64581) (xy 133.622122 -339.686999) (xy 133.580935 -339.72269)
			(xy 133.535089 -339.752157) (xy 133.485516 -339.7748) (xy 133.433226 -339.790158) (xy 133.379282 -339.797918)
			(xy 133.352032 -339.798406) (xy 133.323878 -339.797929) (xy 133.26818 -339.78967) (xy 133.214302 -339.773313)
			(xy 133.163413 -339.749212) (xy 133.116621 -339.717892) (xy 133.074942 -339.680033) (xy 133.039281 -339.636457)
			(xy 133.010414 -339.588113) (xy 132.988968 -339.53605) (xy 132.9817 -339.508846) (xy 132.977428 -339.493877)
			(xy 132.961165 -339.467351) (xy 132.937673 -339.446949) (xy 132.909129 -339.434563) (xy 132.878181 -339.431342)
			(xy 132.862828 -339.433916) (xy 132.844045 -339.437484) (xy 132.806 -339.441301) (xy 132.786882 -339.441536)
			(xy 132.786628 -339.441536) (xy 132.760488 -339.441082) (xy 132.708697 -339.433949) (xy 132.658368 -339.419801)
			(xy 132.610447 -339.398902) (xy 132.565834 -339.371646) (xy 132.545328 -339.35543) (xy 132.533921 -339.346707)
			(xy 132.507553 -339.33537) (xy 132.47907 -339.331838) (xy 132.450732 -339.336391) (xy 132.424788 -339.348667)
			(xy 132.403298 -339.367692) (xy 132.395214 -339.37956) (xy 132.389483 -339.388432) (xy 132.377156 -339.405587)
			(xy 132.370576 -339.41385) (xy 132.361312 -339.426139) (xy 132.349909 -339.454705) (xy 132.347517 -339.485371)
			(xy 132.354353 -339.515361) (xy 132.369797 -339.541961) (xy 132.392453 -339.562764) (xy 132.406136 -339.569806)
			(xy 132.429267 -339.581168) (xy 132.472506 -339.609205) (xy 132.51157 -339.642817) (xy 132.545746 -339.681389)
			(xy 132.574408 -339.724217) (xy 132.597033 -339.770519) (xy 132.605526 -339.79485) (xy 132.610638 -339.808596)
			(xy 132.627402 -339.832642) (xy 132.650295 -339.850949) (xy 132.67744 -339.862015) (xy 132.706607 -339.864932)
			(xy 132.721096 -339.862668) (xy 132.738833 -339.859485) (xy 132.774706 -339.856046) (xy 132.792724 -339.85581)
			(xy 132.793486 -339.85581) (xy 132.820739 -339.856268) (xy 132.874691 -339.864024) (xy 132.92699 -339.879379)
			(xy 132.976572 -339.902021) (xy 133.022426 -339.931489) (xy 133.063619 -339.967184) (xy 133.099313 -340.008377)
			(xy 133.128781 -340.054232) (xy 133.151422 -340.103813) (xy 133.166777 -340.156113) (xy 133.174532 -340.210065)
			(xy 133.174994 -340.237318) (xy 133.17474 -340.247732) (xy 133.174877 -340.262098) (xy 133.18214 -340.28988)
			(xy 133.196844 -340.314545) (xy 133.21783 -340.334145) (xy 133.24344 -340.347133) (xy 133.271652 -340.352484)
			(xy 133.285992 -340.351618) (xy 133.322568 -340.34984) (xy 133.349826 -340.350205) (xy 133.403787 -340.357959)
			(xy 133.456095 -340.373314) (xy 133.505686 -340.395958) (xy 133.551549 -340.425429) (xy 133.59275 -340.461127)
			(xy 133.628452 -340.502326) (xy 133.657927 -340.548186) (xy 133.680575 -340.597775) (xy 133.695934 -340.650082)
			(xy 133.703693 -340.704042) (xy 133.703693 -340.758558) (xy 133.695934 -340.812518) (xy 133.680575 -340.864825)
			(xy 133.657927 -340.914414) (xy 133.628452 -340.960274) (xy 133.59275 -341.001473) (xy 133.551549 -341.037171)
			(xy 133.505686 -341.066642) (xy 133.456095 -341.089286) (xy 133.403787 -341.104641) (xy 133.349826 -341.112395)
			(xy 133.322568 -341.112856) (xy 133.311557 -341.112774) (xy 133.289572 -341.111506) (xy 133.278626 -341.110316)
			(xy 133.263768 -341.109077) (xy 133.234433 -341.114331) (xy 133.207865 -341.127834) (xy 133.18633 -341.148435)
			(xy 133.171663 -341.174379) (xy 133.167882 -341.188802) (xy 133.161046 -341.216549) (xy 133.140188 -341.269751)
			(xy 133.111632 -341.31925) (xy 133.076016 -341.363938) (xy 133.034138 -341.402819) (xy 132.986931 -341.435023)
			(xy 132.935451 -341.45983) (xy 132.880849 -341.476686) (xy 132.824344 -341.485215) (xy 132.795772 -341.485728)
			(xy 132.766784 -341.485202) (xy 132.709477 -341.476427) (xy 132.654157 -341.459083) (xy 132.602097 -341.433569)
			(xy 132.554497 -341.400472) (xy 132.512452 -341.360556) (xy 132.476929 -341.314737) (xy 132.448748 -341.264073)
			(xy 132.428556 -341.209727) (xy 132.416818 -341.152952) (xy 132.414772 -341.124032) (xy 132.413612 -341.109956)
			(xy 132.40452 -341.083227) (xy 132.388444 -341.060018) (xy 132.366618 -341.042109) (xy 132.340716 -341.030875)
			(xy 132.312727 -341.027177) (xy 132.298694 -341.028782) (xy 132.28493 -341.030679) (xy 132.257216 -341.032711)
			(xy 132.243322 -341.032846) (xy 132.216073 -341.032301) (xy 132.162129 -341.024549) (xy 132.109838 -341.009198)
			(xy 132.060264 -340.986563) (xy 132.014415 -340.957102) (xy 131.973226 -340.921417) (xy 131.937534 -340.880233)
			(xy 131.908066 -340.834389) (xy 131.885423 -340.784818) (xy 131.870064 -340.732529) (xy 131.862303 -340.678587)
			(xy 131.861814 -340.651338) (xy 131.862301 -340.623764) (xy 131.870248 -340.569192) (xy 131.885969 -340.516332)
			(xy 131.909135 -340.466286) (xy 131.939264 -340.420096) (xy 131.975728 -340.378724) (xy 131.996434 -340.360508)
			(xy 132.00729 -340.350569) (xy 132.023358 -340.325929) (xy 132.031742 -340.297733) (xy 132.03175 -340.268316)
			(xy 132.023378 -340.240116) (xy 132.007322 -340.215468) (xy 131.996434 -340.205568) (xy 131.975711 -340.18737)
			(xy 131.93924 -340.145999) (xy 131.909109 -340.099807) (xy 131.885945 -340.049756) (xy 131.870231 -339.996891)
			(xy 131.862296 -339.942314) (xy 131.861814 -339.914738) (xy 131.862248 -339.888236) (xy 131.869597 -339.835744)
			(xy 131.884146 -339.784776) (xy 131.905614 -339.736314) (xy 131.933586 -339.691292) (xy 131.950206 -339.670644)
			(xy 131.959669 -339.658512) (xy 131.971464 -339.630107) (xy 131.974288 -339.599481) (xy 131.967888 -339.569398)
			(xy 131.95284 -339.542574) (xy 131.930504 -339.521431) (xy 131.916932 -339.51418) (xy 131.893237 -339.502088)
			(xy 131.849257 -339.472162) (xy 131.809977 -339.436289) (xy 131.776195 -339.395196) (xy 131.761992 -339.372702)
			(xy 131.754054 -339.360488) (xy 131.732587 -339.340817) (xy 131.706437 -339.328011) (xy 131.677736 -339.323113)
			(xy 131.648819 -339.326522) (xy 131.635246 -339.331808) (xy 131.61204 -339.341307) (xy 131.563705 -339.354654)
			(xy 131.514014 -339.361379) (xy 131.488942 -339.36178) (xy 131.463872 -339.361362) (xy 131.414189 -339.35461)
			(xy 131.365855 -339.341275) (xy 131.342638 -339.331808) (xy 131.329062 -339.326558) (xy 131.30016 -339.323191)
			(xy 131.27148 -339.328102) (xy 131.245345 -339.340892) (xy 131.223871 -339.360526) (xy 131.215892 -339.372702)
			(xy 131.201323 -339.395833) (xy 131.16648 -339.437954) (xy 131.125857 -339.474533) (xy 131.080326 -339.504784)
			(xy 131.030864 -339.52806) (xy 130.978533 -339.54386) (xy 130.924454 -339.551846) (xy 130.86979 -339.551846)
			(xy 130.815711 -339.54386) (xy 130.76338 -339.52806) (xy 130.713918 -339.504784) (xy 130.668387 -339.474533)
			(xy 130.627764 -339.437954) (xy 130.592921 -339.395833) (xy 130.578352 -339.372702) (xy 130.570452 -339.360461)
			(xy 130.548974 -339.34079) (xy 130.522815 -339.327987) (xy 130.494104 -339.323096) (xy 130.465181 -339.326516)
			(xy 130.451606 -339.331808) (xy 130.428393 -339.341288) (xy 130.380061 -339.354643) (xy 130.330373 -339.361375)
			(xy 130.305302 -339.36178) (xy 130.277412 -339.361361) (xy 130.222256 -339.353048) (xy 130.168955 -339.336607)
			(xy 130.118699 -339.312405) (xy 130.072612 -339.280984) (xy 130.031722 -339.243044) (xy 129.996944 -339.199434)
			(xy 129.969055 -339.151128) (xy 129.948676 -339.099204) (xy 129.936264 -339.044823) (xy 129.932095 -338.9892)
			(xy 127.628434 -338.9892) (xy 128.381506 -339.742272) (xy 128.71831 -339.881464) (xy 129.948432 -339.881464)
			(xy 129.974406 -339.882031) (xy 130.025708 -339.890213) (xy 130.075102 -339.90631) (xy 130.121375 -339.929925)
			(xy 130.16339 -339.960479) (xy 130.182112 -339.978492) (xy 133.61543 -343.411556) (xy 134.01675 -343.411556)
			(xy 134.038369 -343.390884) (xy 134.086798 -343.355785) (xy 134.140114 -343.328678) (xy 134.197008 -343.310228)
			(xy 134.256085 -343.300888) (xy 134.28599 -343.300304) (xy 134.883398 -343.300304) (xy 134.913375 -343.300911)
			(xy 134.972588 -343.3103) (xy 135.029606 -343.328832) (xy 135.083024 -343.35605) (xy 135.131531 -343.391286)
			(xy 135.153146 -343.412064) (xy 135.511286 -343.770204) (xy 137.666222 -343.770204) (xy 138.243056 -343.19337)
			(xy 138.264641 -343.172648) (xy 138.313067 -343.137506) (xy 138.366385 -343.110354) (xy 138.423288 -343.091858)
			(xy 138.48238 -343.082471) (xy 138.512296 -343.081864) (xy 143.89354 -343.081864) (xy 143.920773 -343.082316)
			(xy 143.974683 -343.090073) (xy 144.02694 -343.105422) (xy 144.076482 -343.128051) (xy 144.122299 -343.1575)
			(xy 144.163459 -343.19317) (xy 144.199124 -343.234333) (xy 144.228568 -343.280154) (xy 144.251192 -343.329697)
			(xy 144.266536 -343.381957) (xy 144.274286 -343.435867) (xy 144.274286 -343.490333) (xy 144.268339 -343.531698)
			(xy 144.792952 -343.531698) (xy 144.797023 -343.476076) (xy 144.809149 -343.421639) (xy 144.829072 -343.369548)
			(xy 144.856368 -343.320913) (xy 144.890454 -343.27677) (xy 144.930603 -343.238061) (xy 144.975961 -343.20561)
			(xy 145.025561 -343.180109) (xy 145.078345 -343.162102) (xy 145.133188 -343.151972) (xy 145.188922 -343.149935)
			(xy 145.244359 -343.156035) (xy 145.298316 -343.170141) (xy 145.349645 -343.191953) (xy 145.397251 -343.221007)
			(xy 145.440119 -343.256682) (xy 145.477336 -343.298219) (xy 145.508109 -343.344732) (xy 145.531781 -343.395229)
			(xy 145.547849 -343.448636) (xy 145.555969 -343.503812) (xy 145.556478 -343.531698) (xy 145.555969 -343.559584)
			(xy 145.547849 -343.61476) (xy 145.531781 -343.668167) (xy 145.508109 -343.718664) (xy 145.477336 -343.765177)
			(xy 145.440119 -343.806714) (xy 145.397251 -343.842389) (xy 145.349645 -343.871443) (xy 145.298316 -343.893255)
			(xy 145.244359 -343.907361) (xy 145.188922 -343.913461) (xy 145.133188 -343.911424) (xy 145.078345 -343.901294)
			(xy 145.025561 -343.883287) (xy 144.975961 -343.857786) (xy 144.930603 -343.825335) (xy 144.890454 -343.786626)
			(xy 144.856368 -343.742483) (xy 144.829072 -343.693848) (xy 144.809149 -343.641757) (xy 144.797023 -343.58732)
			(xy 144.792952 -343.531698) (xy 144.268339 -343.531698) (xy 144.266536 -343.544243) (xy 144.251192 -343.596503)
			(xy 144.228568 -343.646046) (xy 144.199124 -343.691867) (xy 144.163459 -343.73303) (xy 144.122299 -343.7687)
			(xy 144.076482 -343.798149) (xy 144.02694 -343.820778) (xy 143.974683 -343.836127) (xy 143.920773 -343.843884)
			(xy 143.89354 -343.844372) (xy 138.670792 -343.844372) (xy 138.093958 -344.42146) (xy 138.072347 -344.442247)
			(xy 138.02385 -344.477505) (xy 137.970432 -344.504738) (xy 137.91341 -344.523276) (xy 137.85419 -344.532661)
			(xy 137.82421 -344.53322) (xy 135.353298 -344.53322) (xy 135.32332 -344.532637) (xy 135.264104 -344.523246)
			(xy 135.207086 -344.504709) (xy 135.153667 -344.477485) (xy 135.105163 -344.442242) (xy 135.08355 -344.42146)
			(xy 134.72541 -344.06332) (xy 134.65937 -344.06332) (xy 134.644662 -344.063765) (xy 134.616481 -344.072205)
			(xy 134.591871 -344.088322) (xy 134.572868 -344.110778) (xy 134.561048 -344.137717) (xy 134.557387 -344.166906)
			(xy 134.56219 -344.195929) (xy 134.568184 -344.20937) (xy 134.580443 -344.235597) (xy 134.597761 -344.290838)
			(xy 134.606514 -344.348064) (xy 134.607046 -344.37701) (xy 134.607046 -344.377264) (xy 134.606564 -344.404257)
			(xy 134.598963 -344.457704) (xy 134.583907 -344.509547) (xy 134.561698 -344.558752) (xy 134.532778 -344.604337)
			(xy 134.515606 -344.625168) (xy 134.506553 -344.6365) (xy 134.494658 -344.662939) (xy 134.490671 -344.691655)
			(xy 134.494913 -344.720334) (xy 134.507043 -344.746666) (xy 134.526084 -344.768528) (xy 134.543848 -344.7799)
			(xy 138.092587 -344.7799) (xy 138.096756 -344.724274) (xy 138.109169 -344.669891) (xy 138.129549 -344.617966)
			(xy 138.15744 -344.569658) (xy 138.19222 -344.526046) (xy 138.233112 -344.488106) (xy 138.279202 -344.456684)
			(xy 138.32946 -344.432482) (xy 138.382764 -344.416042) (xy 138.437923 -344.40773) (xy 138.465814 -344.407236)
			(xy 138.493148 -344.407663) (xy 138.547229 -344.41564) (xy 138.599565 -344.431436) (xy 138.649029 -344.454711)
			(xy 138.694561 -344.484966) (xy 138.735182 -344.52155) (xy 138.77002 -344.563679) (xy 138.784584 -344.586814)
			(xy 138.792541 -344.599014) (xy 138.814004 -344.618683) (xy 138.840148 -344.63149) (xy 138.868845 -344.636392)
			(xy 138.897758 -344.63299) (xy 138.91133 -344.627708) (xy 138.934539 -344.618217) (xy 138.982873 -344.604867)
			(xy 139.032562 -344.598139) (xy 139.057634 -344.597736) (xy 139.082703 -344.59816) (xy 139.132386 -344.604909)
			(xy 139.180721 -344.618242) (xy 139.203938 -344.627708) (xy 139.217525 -344.632926) (xy 139.246421 -344.636297)
			(xy 139.275096 -344.631393) (xy 139.301229 -344.618611) (xy 139.322703 -344.598986) (xy 139.330684 -344.586814)
			(xy 139.345253 -344.563683) (xy 139.380096 -344.521562) (xy 139.420719 -344.484983) (xy 139.46625 -344.454732)
			(xy 139.515712 -344.431456) (xy 139.568043 -344.415656) (xy 139.622122 -344.40767) (xy 139.676786 -344.40767)
			(xy 139.730865 -344.415656) (xy 139.783196 -344.431456) (xy 139.832658 -344.454732) (xy 139.878189 -344.484983)
			(xy 139.918812 -344.521562) (xy 139.953655 -344.563683) (xy 139.968224 -344.586814) (xy 139.976143 -344.599041)
			(xy 139.997616 -344.61871) (xy 140.023771 -344.631514) (xy 140.052476 -344.636408) (xy 140.081396 -344.632996)
			(xy 140.09497 -344.627708) (xy 140.118187 -344.618236) (xy 140.166516 -344.604878) (xy 140.216203 -344.598143)
			(xy 140.241274 -344.597736) (xy 140.268118 -344.598183) (xy 140.32125 -344.605885) (xy 140.372727 -344.621134)
			(xy 140.421482 -344.643612) (xy 140.466505 -344.672856) (xy 140.506866 -344.70826) (xy 140.541726 -344.74909)
			(xy 140.570366 -344.7945) (xy 140.592192 -344.843551) (xy 140.599922 -344.869262) (xy 140.604566 -344.883766)
			(xy 140.621088 -344.909332) (xy 140.644408 -344.928897) (xy 140.672456 -344.940726) (xy 140.702743 -344.943768)
			(xy 140.732583 -344.937755) (xy 140.746226 -344.930984) (xy 140.774377 -344.916361) (xy 140.834326 -344.89563)
			(xy 140.896882 -344.885128) (xy 140.928598 -344.884502) (xy 140.946617 -344.884727) (xy 140.982492 -344.888158)
			(xy 141.000226 -344.89136) (xy 141.015432 -344.893723) (xy 141.045988 -344.890188) (xy 141.074107 -344.877721)
			(xy 141.097243 -344.85745) (xy 141.113299 -344.831213) (xy 141.117574 -344.81643) (xy 141.124994 -344.789393)
			(xy 141.146623 -344.737669) (xy 141.175586 -344.689666) (xy 141.21126 -344.646416) (xy 141.252876 -344.608849)
			(xy 141.29954 -344.577774) (xy 141.350247 -344.55386) (xy 141.403907 -344.53762) (xy 141.459366 -344.529404)
			(xy 141.487398 -344.528902) (xy 141.514651 -344.529357) (xy 141.568603 -344.537114) (xy 141.620902 -344.55247)
			(xy 141.670482 -344.575113) (xy 141.716336 -344.604582) (xy 141.757529 -344.640277) (xy 141.793223 -344.68147)
			(xy 141.82269 -344.727325) (xy 141.845332 -344.776906) (xy 141.860688 -344.829205) (xy 141.868443 -344.883157)
			(xy 141.868906 -344.91041) (xy 141.868376 -344.937982) (xy 141.860437 -344.992552) (xy 141.844724 -345.045411)
			(xy 141.821566 -345.095457) (xy 141.791445 -345.141648) (xy 141.754988 -345.183022) (xy 141.734286 -345.20124)
			(xy 141.72338 -345.211129) (xy 141.707311 -345.235783) (xy 141.69893 -345.263992) (xy 141.698932 -345.293421)
			(xy 141.707317 -345.321629) (xy 141.723389 -345.34628) (xy 141.734286 -345.35618) (xy 141.755002 -345.374385)
			(xy 141.791467 -345.415757) (xy 141.821594 -345.461948) (xy 141.844757 -345.511997) (xy 141.860472 -345.564859)
			(xy 141.868412 -345.619432) (xy 141.868411 -345.674581) (xy 141.860469 -345.729154) (xy 141.844752 -345.782016)
			(xy 141.843402 -345.784932) (xy 144.561812 -345.784932) (xy 144.565883 -345.72931) (xy 144.578009 -345.674873)
			(xy 144.597932 -345.622782) (xy 144.625228 -345.574147) (xy 144.659314 -345.530004) (xy 144.699463 -345.491295)
			(xy 144.744821 -345.458844) (xy 144.794421 -345.433343) (xy 144.847205 -345.415336) (xy 144.902048 -345.405206)
			(xy 144.957782 -345.403169) (xy 145.013219 -345.409269) (xy 145.067176 -345.423375) (xy 145.118505 -345.445187)
			(xy 145.166111 -345.474241) (xy 145.208979 -345.509916) (xy 145.246196 -345.551453) (xy 145.276969 -345.597966)
			(xy 145.300641 -345.648463) (xy 145.316709 -345.70187) (xy 145.324829 -345.757046) (xy 145.325338 -345.784932)
			(xy 145.324829 -345.812818) (xy 145.316709 -345.867994) (xy 145.300641 -345.921401) (xy 145.276969 -345.971898)
			(xy 145.246196 -346.018411) (xy 145.208979 -346.059948) (xy 145.166111 -346.095623) (xy 145.118505 -346.124677)
			(xy 145.067176 -346.146489) (xy 145.013219 -346.160595) (xy 144.957782 -346.166695) (xy 144.902048 -346.164658)
			(xy 144.847205 -346.154528) (xy 144.794421 -346.136521) (xy 144.744821 -346.11102) (xy 144.699463 -346.078569)
			(xy 144.659314 -346.03986) (xy 144.625228 -345.995717) (xy 144.597932 -345.947082) (xy 144.578009 -345.894991)
			(xy 144.565883 -345.840554) (xy 144.561812 -345.784932) (xy 141.843402 -345.784932) (xy 141.821588 -345.832063)
			(xy 141.791459 -345.878254) (xy 141.754993 -345.919625) (xy 141.734286 -345.93784) (xy 141.72338 -345.947729)
			(xy 141.707311 -345.972383) (xy 141.69893 -346.000592) (xy 141.698932 -346.030021) (xy 141.707317 -346.058229)
			(xy 141.723389 -346.08288) (xy 141.734286 -346.09278) (xy 141.754988 -346.111001) (xy 141.791459 -346.152368)
			(xy 141.821593 -346.198555) (xy 141.844761 -346.248601) (xy 141.860479 -346.301462) (xy 141.86842 -346.356036)
			(xy 141.868906 -346.38361) (xy 141.868432 -346.410862) (xy 141.860674 -346.46481) (xy 141.845317 -346.517105)
			(xy 141.822675 -346.566682) (xy 141.793207 -346.612533) (xy 141.757514 -346.653723) (xy 141.716323 -346.689414)
			(xy 141.670472 -346.71888) (xy 141.620894 -346.741521) (xy 141.568598 -346.756876) (xy 141.51465 -346.764632)
			(xy 141.487398 -346.765118) (xy 141.459543 -346.764584) (xy 141.404429 -346.75646) (xy 141.35108 -346.740415)
			(xy 141.300628 -346.716789) (xy 141.254143 -346.686084) (xy 141.212614 -346.64895) (xy 141.17692 -346.606177)
			(xy 141.14782 -346.558672) (xy 141.125931 -346.507442) (xy 141.118336 -346.480638) (xy 141.114074 -346.466517)
			(xy 141.098685 -346.441368) (xy 141.076764 -346.42165) (xy 141.050131 -346.409) (xy 141.020997 -346.404469)
			(xy 141.006322 -346.405962) (xy 140.993305 -346.407627) (xy 140.967121 -346.40941) (xy 140.953998 -346.409518)
			(xy 140.939849 -346.409424) (xy 140.911626 -346.40739) (xy 140.89761 -346.405454) (xy 140.884268 -346.403791)
			(xy 140.857565 -346.406899) (xy 140.832604 -346.416882) (xy 140.811121 -346.433043) (xy 140.794611 -346.454258)
			(xy 140.784222 -346.479052) (xy 140.78204 -346.492322) (xy 140.777912 -346.519469) (xy 140.762943 -346.572297)
			(xy 140.740556 -346.622434) (xy 140.711213 -346.668844) (xy 140.67552 -346.710569) (xy 140.634215 -346.746746)
			(xy 140.588151 -346.776628) (xy 140.538278 -346.799598) (xy 140.485628 -346.815183) (xy 140.431288 -346.823058)
			(xy 140.403834 -346.823538) (xy 140.376583 -346.823013) (xy 140.322636 -346.815262) (xy 140.270341 -346.799911)
			(xy 140.220763 -346.777275) (xy 140.174911 -346.747813) (xy 140.133719 -346.712126) (xy 140.098025 -346.67094)
			(xy 140.068556 -346.625093) (xy 140.045911 -346.575519) (xy 140.030552 -346.523226) (xy 140.022791 -346.469281)
			(xy 140.022326 -346.44203) (xy 140.022803 -346.414456) (xy 140.030752 -346.359883) (xy 140.046474 -346.307023)
			(xy 140.069642 -346.256977) (xy 140.099773 -346.210787) (xy 140.136239 -346.169416) (xy 140.156946 -346.1512)
			(xy 140.167817 -346.141273) (xy 140.183899 -346.116633) (xy 140.192291 -346.088431) (xy 140.192296 -346.059007)
			(xy 140.183915 -346.030802) (xy 140.167843 -346.006156) (xy 140.156946 -345.99626) (xy 140.13627 -345.978011)
			(xy 140.099795 -345.936651) (xy 140.069657 -345.89047) (xy 140.046485 -345.840429) (xy 140.030762 -345.787573)
			(xy 140.022815 -345.733003) (xy 140.022326 -345.70543) (xy 140.022752 -345.678928) (xy 140.030103 -345.626435)
			(xy 140.044654 -345.575467) (xy 140.066123 -345.527005) (xy 140.094098 -345.481984) (xy 140.110718 -345.461336)
			(xy 140.120186 -345.449208) (xy 140.131978 -345.420802) (xy 140.1348 -345.390175) (xy 140.128399 -345.360092)
			(xy 140.113351 -345.333268) (xy 140.091015 -345.312124) (xy 140.077444 -345.304872) (xy 140.05375 -345.292778)
			(xy 140.009769 -345.262853) (xy 139.970489 -345.22698) (xy 139.936707 -345.185888) (xy 139.922504 -345.163394)
			(xy 139.914556 -345.151187) (xy 139.893091 -345.131517) (xy 139.866945 -345.11871) (xy 139.838245 -345.11381)
			(xy 139.809331 -345.117216) (xy 139.795758 -345.1225) (xy 139.77255 -345.131995) (xy 139.724216 -345.145344)
			(xy 139.674526 -345.15207) (xy 139.649454 -345.152472) (xy 139.624385 -345.152051) (xy 139.574701 -345.1453)
			(xy 139.526367 -345.131967) (xy 139.50315 -345.1225) (xy 139.489568 -345.117266) (xy 139.46067 -345.113897)
			(xy 139.431992 -345.118804) (xy 139.405858 -345.13159) (xy 139.384384 -345.15122) (xy 139.376404 -345.163394)
			(xy 139.361835 -345.186525) (xy 139.326992 -345.228646) (xy 139.286369 -345.265225) (xy 139.240838 -345.295476)
			(xy 139.191376 -345.318752) (xy 139.139045 -345.334552) (xy 139.084966 -345.342538) (xy 139.030302 -345.342538)
			(xy 138.976223 -345.334552) (xy 138.923892 -345.318752) (xy 138.87443 -345.295476) (xy 138.828899 -345.265225)
			(xy 138.788276 -345.228646) (xy 138.753433 -345.186525) (xy 138.738864 -345.163394) (xy 138.730954 -345.15116)
			(xy 138.709479 -345.13149) (xy 138.683322 -345.118687) (xy 138.654614 -345.113794) (xy 138.625692 -345.11721)
			(xy 138.612118 -345.1225) (xy 138.588903 -345.131976) (xy 138.540573 -345.145332) (xy 138.490885 -345.152066)
			(xy 138.465814 -345.152472) (xy 138.437923 -345.15207) (xy 138.382764 -345.143758) (xy 138.32946 -345.127318)
			(xy 138.279202 -345.103116) (xy 138.233112 -345.071694) (xy 138.19222 -345.033754) (xy 138.15744 -344.990143)
			(xy 138.129549 -344.941834) (xy 138.109169 -344.889909) (xy 138.096756 -344.835526) (xy 138.092587 -344.7799)
			(xy 134.543848 -344.7799) (xy 134.550501 -344.784159) (xy 134.578326 -344.7923) (xy 134.592822 -344.792808)
			(xy 135.453882 -344.792808) (xy 135.478863 -344.793461) (xy 135.527869 -344.803193) (xy 135.574038 -344.822289)
			(xy 135.615601 -344.850015) (xy 135.633714 -344.86723) (xy 137.01903 -346.252546) (xy 137.0357 -346.270054)
			(xy 137.062814 -346.310068) (xy 137.072878 -346.332048) (xy 137.079165 -346.34544) (xy 137.098145 -346.368118)
			(xy 137.122817 -346.384422) (xy 137.151122 -346.392989) (xy 137.180694 -346.393104) (xy 137.209064 -346.384756)
			(xy 137.233862 -346.368644) (xy 137.24382 -346.357702) (xy 137.262018 -346.336978) (xy 137.303389 -346.300509)
			(xy 137.349582 -346.270378) (xy 137.399633 -346.247215) (xy 137.452498 -346.231501) (xy 137.507074 -346.223565)
			(xy 137.53465 -346.223082) (xy 137.561901 -346.223602) (xy 137.61585 -346.231352) (xy 137.668146 -346.246701)
			(xy 137.717725 -346.269337) (xy 137.763578 -346.298799) (xy 137.804771 -346.334487) (xy 137.840465 -346.375674)
			(xy 137.869934 -346.421522) (xy 137.892578 -346.471098) (xy 137.907936 -346.523392) (xy 137.915694 -346.577339)
			(xy 137.916158 -346.60459) (xy 137.916158 -346.604844) (xy 137.915584 -346.634683) (xy 137.906268 -346.693629)
			(xy 137.897616 -346.722192) (xy 137.893528 -346.736087) (xy 137.892626 -346.765028) (xy 137.8999 -346.793054)
			(xy 137.914763 -346.817903) (xy 137.936014 -346.837569) (xy 137.961939 -346.850464) (xy 137.976102 -346.85351)
			(xy 138.002169 -346.858706) (xy 138.052672 -346.875273) (xy 138.100385 -346.898693) (xy 138.144384 -346.928511)
			(xy 138.183815 -346.964151) (xy 138.217914 -347.004921) (xy 138.246022 -347.050032) (xy 138.267593 -347.098609)
			(xy 138.282209 -347.14971) (xy 138.289587 -347.202347) (xy 138.290046 -347.228922) (xy 138.28956 -347.256173)
			(xy 138.281804 -347.310121) (xy 138.266449 -347.362416) (xy 138.243807 -347.411993) (xy 138.214341 -347.457843)
			(xy 138.17865 -347.499034) (xy 138.137459 -347.534725) (xy 138.091609 -347.564191) (xy 138.042032 -347.586833)
			(xy 137.989737 -347.602188) (xy 137.935789 -347.609944) (xy 137.881287 -347.609944) (xy 137.827339 -347.602188)
			(xy 137.775044 -347.586833) (xy 137.725467 -347.564191) (xy 137.679617 -347.534725) (xy 137.638426 -347.499034)
			(xy 137.602735 -347.457843) (xy 137.573269 -347.411993) (xy 137.550627 -347.362416) (xy 137.535272 -347.310121)
			(xy 137.527516 -347.256173) (xy 137.52703 -347.228922) (xy 137.52703 -347.228668) (xy 137.527607 -347.198829)
			(xy 137.536922 -347.139883) (xy 137.545572 -347.11132) (xy 137.549656 -347.097423) (xy 137.550561 -347.068483)
			(xy 137.543289 -347.040456) (xy 137.528427 -347.015606) (xy 137.507175 -346.995941) (xy 137.481249 -346.983047)
			(xy 137.467086 -346.980002) (xy 137.434246 -346.973424) (xy 137.371394 -346.950298) (xy 137.342118 -346.934028)
			(xy 137.329125 -346.927047) (xy 137.3005 -346.920009) (xy 137.271058 -346.921446) (xy 137.243253 -346.931237)
			(xy 137.219407 -346.948565) (xy 137.201508 -346.971986) (xy 137.195814 -346.98559) (xy 137.184459 -347.013849)
			(xy 137.154104 -347.066642) (xy 137.115748 -347.113942) (xy 137.093452 -347.134688) (xy 137.093452 -348.4499)
			(xy 137.092822 -348.474883) (xy 137.083084 -348.52389) (xy 137.063982 -348.570059) (xy 137.036249 -348.611621)
			(xy 137.01903 -348.629732) (xy 136.543288 -349.105474) (xy 136.525168 -349.122701) (xy 136.483595 -349.150461)
			(xy 136.460738 -349.160592) (xy 134.65429 -349.908876) (xy 134.631034 -349.917824) (xy 134.582172 -349.927547)
			(xy 134.557262 -349.92818) (xy 125.479556 -349.92818) (xy 123.066556 -352.34118) (xy 123.04847 -352.358447)
			(xy 123.006922 -352.386256) (xy 122.960748 -352.405426) (xy 122.911721 -352.415222) (xy 122.886724 -352.415856)
			(xy 116.675662 -352.415856) (xy 115.989608 -353.10191) (xy 115.989608 -354.687886) (xy 116.286026 -354.687886)
			(xy 116.286472 -354.661506) (xy 116.293727 -354.609248) (xy 116.30811 -354.558488) (xy 116.329348 -354.510192)
			(xy 116.357036 -354.465282) (xy 116.390646 -354.424613) (xy 116.429536 -354.388961) (xy 116.472967 -354.359006)
			(xy 116.496338 -354.346764) (xy 116.508712 -354.340085) (xy 116.529447 -354.321108) (xy 116.544213 -354.29719)
			(xy 116.551887 -354.270148) (xy 116.551885 -354.242039) (xy 116.544208 -354.214999) (xy 116.529439 -354.191082)
			(xy 116.508701 -354.172108) (xy 116.496338 -354.165408) (xy 116.472948 -354.153203) (xy 116.429525 -354.123234)
			(xy 116.390642 -354.087572) (xy 116.357039 -354.046897) (xy 116.329355 -354.001983) (xy 116.308118 -353.953686)
			(xy 116.293731 -353.902924) (xy 116.28647 -353.850666) (xy 116.286026 -353.824286) (xy 116.286512 -353.797035)
			(xy 116.294268 -353.743087) (xy 116.309623 -353.690792) (xy 116.332265 -353.641215) (xy 116.361731 -353.595365)
			(xy 116.397422 -353.554174) (xy 116.438613 -353.518483) (xy 116.484463 -353.489017) (xy 116.53404 -353.466375)
			(xy 116.586335 -353.45102) (xy 116.640283 -353.443264) (xy 116.694785 -353.443264) (xy 116.748733 -353.45102)
			(xy 116.801028 -353.466375) (xy 116.850605 -353.489017) (xy 116.896455 -353.518483) (xy 116.937646 -353.554174)
			(xy 116.973337 -353.595365) (xy 117.002803 -353.641215) (xy 117.025445 -353.690792) (xy 117.0408 -353.743087)
			(xy 117.048556 -353.797035) (xy 117.049042 -353.824286) (xy 117.048618 -353.850666) (xy 117.041355 -353.902923)
			(xy 117.026965 -353.953683) (xy 117.005723 -354.001977) (xy 116.978032 -354.046886) (xy 116.944421 -354.087554)
			(xy 116.90553 -354.123207) (xy 116.862101 -354.153164) (xy 116.83873 -354.165408) (xy 116.826384 -354.172131)
			(xy 116.805657 -354.191103) (xy 116.790897 -354.215013) (xy 116.783225 -354.242044) (xy 116.783223 -354.270143)
			(xy 116.790892 -354.297175) (xy 116.805649 -354.321087) (xy 116.826374 -354.340062) (xy 116.83873 -354.346764)
			(xy 116.862101 -354.359004) (xy 116.905524 -354.388967) (xy 116.944409 -354.424623) (xy 116.978014 -354.465293)
			(xy 117.005701 -354.510202) (xy 117.026941 -354.558495) (xy 117.041331 -354.609252) (xy 117.048596 -354.661507)
			(xy 117.049042 -354.687886) (xy 117.048556 -354.715137) (xy 117.0408 -354.769085) (xy 117.025445 -354.82138)
			(xy 117.002803 -354.870957) (xy 116.973337 -354.916807) (xy 116.937646 -354.957998) (xy 116.896455 -354.993689)
			(xy 116.850605 -355.023155) (xy 116.801028 -355.045797) (xy 116.748733 -355.061152) (xy 116.694785 -355.068908)
			(xy 116.640283 -355.068908) (xy 116.586335 -355.061152) (xy 116.53404 -355.045797) (xy 116.484463 -355.023155)
			(xy 116.438613 -354.993689) (xy 116.397422 -354.957998) (xy 116.361731 -354.916807) (xy 116.332265 -354.870957)
			(xy 116.309623 -354.82138) (xy 116.294268 -354.769085) (xy 116.286512 -354.715137) (xy 116.286026 -354.687886)
			(xy 115.989608 -354.687886) (xy 115.989608 -355.18217) (xy 117.96852 -355.18217) (xy 117.972591 -355.126548)
			(xy 117.984717 -355.072111) (xy 118.00464 -355.02002) (xy 118.031936 -354.971385) (xy 118.066022 -354.927242)
			(xy 118.106171 -354.888533) (xy 118.151529 -354.856082) (xy 118.201129 -354.830581) (xy 118.253913 -354.812574)
			(xy 118.308756 -354.802444) (xy 118.36449 -354.800407) (xy 118.419927 -354.806507) (xy 118.473884 -354.820613)
			(xy 118.525213 -354.842425) (xy 118.572819 -354.871479) (xy 118.615687 -354.907154) (xy 118.652904 -354.948691)
			(xy 118.683677 -354.995204) (xy 118.707349 -355.045701) (xy 118.723417 -355.099108) (xy 118.731537 -355.154284)
			(xy 118.732046 -355.18217) (xy 118.731537 -355.210056) (xy 118.723417 -355.265232) (xy 118.707349 -355.318639)
			(xy 118.683677 -355.369136) (xy 118.652904 -355.415649) (xy 118.615687 -355.457186) (xy 118.572819 -355.492861)
			(xy 118.525213 -355.521915) (xy 118.473884 -355.543727) (xy 118.419927 -355.557833) (xy 118.36449 -355.563933)
			(xy 118.308756 -355.561896) (xy 118.253913 -355.551766) (xy 118.201129 -355.533759) (xy 118.151529 -355.508258)
			(xy 118.106171 -355.475807) (xy 118.066022 -355.437098) (xy 118.031936 -355.392955) (xy 118.00464 -355.34432)
			(xy 117.984717 -355.292229) (xy 117.972591 -355.237792) (xy 117.96852 -355.18217) (xy 115.989608 -355.18217)
			(xy 115.989608 -355.942392) (xy 116.343682 -355.942392) (xy 116.347753 -355.88677) (xy 116.359879 -355.832333)
			(xy 116.379802 -355.780242) (xy 116.407098 -355.731607) (xy 116.441184 -355.687464) (xy 116.481333 -355.648755)
			(xy 116.526691 -355.616304) (xy 116.576291 -355.590803) (xy 116.629075 -355.572796) (xy 116.683918 -355.562666)
			(xy 116.739652 -355.560629) (xy 116.795089 -355.566729) (xy 116.849046 -355.580835) (xy 116.900375 -355.602647)
			(xy 116.947981 -355.631701) (xy 116.990849 -355.667376) (xy 117.0181 -355.69779) (xy 120.263664 -355.69779)
			(xy 120.267735 -355.642168) (xy 120.279861 -355.587731) (xy 120.299784 -355.53564) (xy 120.32708 -355.487005)
			(xy 120.361166 -355.442862) (xy 120.401315 -355.404153) (xy 120.446673 -355.371702) (xy 120.496273 -355.346201)
			(xy 120.549057 -355.328194) (xy 120.6039 -355.318064) (xy 120.659634 -355.316027) (xy 120.715071 -355.322127)
			(xy 120.769028 -355.336233) (xy 120.820357 -355.358045) (xy 120.867963 -355.387099) (xy 120.910831 -355.422774)
			(xy 120.948048 -355.464311) (xy 120.978821 -355.510824) (xy 121.002493 -355.561321) (xy 121.018561 -355.614728)
			(xy 121.026681 -355.669904) (xy 121.02719 -355.69779) (xy 121.026681 -355.725676) (xy 121.018561 -355.780852)
			(xy 121.002493 -355.834259) (xy 120.978821 -355.884756) (xy 120.948048 -355.931269) (xy 120.910831 -355.972806)
			(xy 120.867963 -356.008481) (xy 120.82476 -356.034848) (xy 122.442222 -356.034848) (xy 122.446293 -355.979226)
			(xy 122.458419 -355.924789) (xy 122.478342 -355.872698) (xy 122.505638 -355.824063) (xy 122.539724 -355.77992)
			(xy 122.579873 -355.741211) (xy 122.625231 -355.70876) (xy 122.674831 -355.683259) (xy 122.727615 -355.665252)
			(xy 122.782458 -355.655122) (xy 122.838192 -355.653085) (xy 122.893629 -355.659185) (xy 122.947586 -355.673291)
			(xy 122.998915 -355.695103) (xy 123.046521 -355.724157) (xy 123.089389 -355.759832) (xy 123.126606 -355.801369)
			(xy 123.157379 -355.847882) (xy 123.181051 -355.898379) (xy 123.197119 -355.951786) (xy 123.205239 -356.006962)
			(xy 123.205748 -356.034848) (xy 123.205239 -356.062734) (xy 123.197119 -356.11791) (xy 123.181051 -356.171317)
			(xy 123.157379 -356.221814) (xy 123.126606 -356.268327) (xy 123.089389 -356.309864) (xy 123.046521 -356.345539)
			(xy 122.998915 -356.374593) (xy 122.947586 -356.396405) (xy 122.893629 -356.410511) (xy 122.838192 -356.416611)
			(xy 122.782458 -356.414574) (xy 122.727615 -356.404444) (xy 122.674831 -356.386437) (xy 122.625231 -356.360936)
			(xy 122.579873 -356.328485) (xy 122.539724 -356.289776) (xy 122.505638 -356.245633) (xy 122.478342 -356.196998)
			(xy 122.458419 -356.144907) (xy 122.446293 -356.09047) (xy 122.442222 -356.034848) (xy 120.82476 -356.034848)
			(xy 120.820357 -356.037535) (xy 120.769028 -356.059347) (xy 120.715071 -356.073453) (xy 120.659634 -356.079553)
			(xy 120.6039 -356.077516) (xy 120.549057 -356.067386) (xy 120.496273 -356.049379) (xy 120.446673 -356.023878)
			(xy 120.401315 -355.991427) (xy 120.361166 -355.952718) (xy 120.32708 -355.908575) (xy 120.299784 -355.85994)
			(xy 120.279861 -355.807849) (xy 120.267735 -355.753412) (xy 120.263664 -355.69779) (xy 117.0181 -355.69779)
			(xy 117.028066 -355.708913) (xy 117.058839 -355.755426) (xy 117.082511 -355.805923) (xy 117.098579 -355.85933)
			(xy 117.106699 -355.914506) (xy 117.107208 -355.942392) (xy 117.106699 -355.970278) (xy 117.098579 -356.025454)
			(xy 117.082511 -356.078861) (xy 117.058839 -356.129358) (xy 117.028066 -356.175871) (xy 116.990849 -356.217408)
			(xy 116.947981 -356.253083) (xy 116.900375 -356.282137) (xy 116.849046 -356.303949) (xy 116.795089 -356.318055)
			(xy 116.739652 -356.324155) (xy 116.683918 -356.322118) (xy 116.629075 -356.311988) (xy 116.576291 -356.293981)
			(xy 116.526691 -356.26848) (xy 116.481333 -356.236029) (xy 116.441184 -356.19732) (xy 116.407098 -356.153177)
			(xy 116.379802 -356.104542) (xy 116.359879 -356.052451) (xy 116.347753 -355.998014) (xy 116.343682 -355.942392)
			(xy 115.989608 -355.942392) (xy 115.989608 -356.97922) (xy 122.843796 -356.97922) (xy 122.847867 -356.923598)
			(xy 122.859993 -356.869161) (xy 122.879916 -356.81707) (xy 122.907212 -356.768435) (xy 122.941298 -356.724292)
			(xy 122.981447 -356.685583) (xy 123.026805 -356.653132) (xy 123.076405 -356.627631) (xy 123.129189 -356.609624)
			(xy 123.184032 -356.599494) (xy 123.239766 -356.597457) (xy 123.295203 -356.603557) (xy 123.34916 -356.617663)
			(xy 123.400489 -356.639475) (xy 123.448095 -356.668529) (xy 123.490963 -356.704204) (xy 123.52818 -356.745741)
			(xy 123.558953 -356.792254) (xy 123.582625 -356.842751) (xy 123.598693 -356.896158) (xy 123.606813 -356.951334)
			(xy 123.607322 -356.97922) (xy 123.606813 -357.007106) (xy 123.598693 -357.062282) (xy 123.582625 -357.115689)
			(xy 123.558953 -357.166186) (xy 123.52818 -357.212699) (xy 123.490963 -357.254236) (xy 123.448095 -357.289911)
			(xy 123.400489 -357.318965) (xy 123.34916 -357.340777) (xy 123.295203 -357.354883) (xy 123.239766 -357.360983)
			(xy 123.184032 -357.358946) (xy 123.129189 -357.348816) (xy 123.076405 -357.330809) (xy 123.026805 -357.305308)
			(xy 122.981447 -357.272857) (xy 122.941298 -357.234148) (xy 122.907212 -357.190005) (xy 122.879916 -357.14137)
			(xy 122.859993 -357.089279) (xy 122.847867 -357.034842) (xy 122.843796 -356.97922) (xy 115.989608 -356.97922)
			(xy 115.989608 -357.043228) (xy 115.989009 -357.068226) (xy 115.979196 -357.117252) (xy 115.960012 -357.163423)
			(xy 115.932193 -357.204966) (xy 115.914932 -357.22306) (xy 115.006882 -358.13111) (xy 119.24868 -358.13111)
			(xy 119.252751 -358.075488) (xy 119.264877 -358.021051) (xy 119.2848 -357.96896) (xy 119.312096 -357.920325)
			(xy 119.346182 -357.876182) (xy 119.386331 -357.837473) (xy 119.431689 -357.805022) (xy 119.481289 -357.779521)
			(xy 119.534073 -357.761514) (xy 119.588916 -357.751384) (xy 119.64465 -357.749347) (xy 119.700087 -357.755447)
			(xy 119.754044 -357.769553) (xy 119.805373 -357.791365) (xy 119.852979 -357.820419) (xy 119.895847 -357.856094)
			(xy 119.933064 -357.897631) (xy 119.963837 -357.944144) (xy 119.987509 -357.994641) (xy 120.003577 -358.048048)
			(xy 120.011697 -358.103224) (xy 120.01216 -358.12857) (xy 122.04522 -358.12857) (xy 122.049291 -358.072948)
			(xy 122.061417 -358.018511) (xy 122.08134 -357.96642) (xy 122.108636 -357.917785) (xy 122.142722 -357.873642)
			(xy 122.182871 -357.834933) (xy 122.228229 -357.802482) (xy 122.277829 -357.776981) (xy 122.330613 -357.758974)
			(xy 122.385456 -357.748844) (xy 122.44119 -357.746807) (xy 122.496627 -357.752907) (xy 122.550584 -357.767013)
			(xy 122.601913 -357.788825) (xy 122.649519 -357.817879) (xy 122.692387 -357.853554) (xy 122.729604 -357.895091)
			(xy 122.760377 -357.941604) (xy 122.784049 -357.992101) (xy 122.800117 -358.045508) (xy 122.808237 -358.100684)
			(xy 122.808746 -358.12857) (xy 122.808237 -358.156456) (xy 122.800117 -358.211632) (xy 122.784049 -358.265039)
			(xy 122.760377 -358.315536) (xy 122.729604 -358.362049) (xy 122.692387 -358.403586) (xy 122.649519 -358.439261)
			(xy 122.601913 -358.468315) (xy 122.550584 -358.490127) (xy 122.496627 -358.504233) (xy 122.44119 -358.510333)
			(xy 122.385456 -358.508296) (xy 122.330613 -358.498166) (xy 122.277829 -358.480159) (xy 122.228229 -358.454658)
			(xy 122.182871 -358.422207) (xy 122.142722 -358.383498) (xy 122.108636 -358.339355) (xy 122.08134 -358.29072)
			(xy 122.061417 -358.238629) (xy 122.049291 -358.184192) (xy 122.04522 -358.12857) (xy 120.01216 -358.12857)
			(xy 120.012206 -358.13111) (xy 120.011697 -358.158996) (xy 120.003577 -358.214172) (xy 119.987509 -358.267579)
			(xy 119.963837 -358.318076) (xy 119.933064 -358.364589) (xy 119.895847 -358.406126) (xy 119.852979 -358.441801)
			(xy 119.805373 -358.470855) (xy 119.754044 -358.492667) (xy 119.700087 -358.506773) (xy 119.64465 -358.512873)
			(xy 119.588916 -358.510836) (xy 119.534073 -358.500706) (xy 119.481289 -358.482699) (xy 119.431689 -358.457198)
			(xy 119.386331 -358.424747) (xy 119.346182 -358.386038) (xy 119.312096 -358.341895) (xy 119.2848 -358.29326)
			(xy 119.264877 -358.241169) (xy 119.252751 -358.186732) (xy 119.24868 -358.13111) (xy 115.006882 -358.13111)
			(xy 114.251232 -358.88676) (xy 114.233153 -358.904035) (xy 114.191603 -358.931843) (xy 114.145427 -358.951012)
			(xy 114.096398 -358.960804) (xy 114.0714 -358.961436) (xy 113.218722 -358.961436) (xy 113.202075 -358.961093)
			(xy 113.169077 -358.956635) (xy 113.152936 -358.952546) (xy 113.136933 -358.955142) (xy 113.104631 -358.957943)
			(xy 113.08842 -358.958134) (xy 113.06117 -358.957603) (xy 113.007226 -358.94985) (xy 112.954933 -358.934499)
			(xy 112.905358 -358.911862) (xy 112.859509 -358.8824) (xy 112.818319 -358.846713) (xy 112.782627 -358.805528)
			(xy 112.75316 -358.759682) (xy 112.730517 -358.71011) (xy 112.71516 -358.657819) (xy 112.7074 -358.603875)
			(xy 112.706912 -358.576626) (xy 112.707384 -358.550676) (xy 112.714427 -358.499255) (xy 112.728374 -358.449263)
			(xy 112.748966 -358.401623) (xy 112.775825 -358.357212) (xy 112.808454 -358.316851) (xy 112.827054 -358.29875)
			(xy 112.837759 -358.287971) (xy 112.852784 -358.261584) (xy 112.859387 -358.231945) (xy 112.856985 -358.201675)
			(xy 112.84579 -358.173449) (xy 112.826791 -358.149761) (xy 112.801668 -358.132706) (xy 112.772641 -358.123791)
			(xy 112.757458 -358.123236) (xy 110.71479 -358.123236) (xy 110.260892 -357.669338) (xy 110.260892 -357.221536)
			(xy 110.240439 -357.204514) (xy 110.204311 -357.165449) (xy 110.174395 -357.121446) (xy 110.151355 -357.073483)
			(xy 110.135705 -357.022627) (xy 110.127791 -356.970009) (xy 110.127791 -356.916799) (xy 110.135703 -356.864181)
			(xy 110.151353 -356.813324) (xy 110.174391 -356.765361) (xy 110.204307 -356.721357) (xy 110.240433 -356.682291)
			(xy 110.260892 -356.665276) (xy 110.260892 -356.591108) (xy 110.260296 -356.576162) (xy 110.251531 -356.54758)
			(xy 110.234866 -356.52276) (xy 110.21173 -356.503827) (xy 110.184103 -356.492403) (xy 110.154352 -356.489466)
			(xy 110.125025 -356.495268) (xy 110.098633 -356.509312) (xy 110.087664 -356.51948) (xy 109.93628 -356.67061)
			(xy 109.93628 -358.964484) (xy 122.787916 -358.964484) (xy 122.791987 -358.908862) (xy 122.804113 -358.854425)
			(xy 122.824036 -358.802334) (xy 122.851332 -358.753699) (xy 122.885418 -358.709556) (xy 122.925567 -358.670847)
			(xy 122.970925 -358.638396) (xy 123.020525 -358.612895) (xy 123.073309 -358.594888) (xy 123.128152 -358.584758)
			(xy 123.183886 -358.582721) (xy 123.239323 -358.588821) (xy 123.29328 -358.602927) (xy 123.344609 -358.624739)
			(xy 123.392215 -358.653793) (xy 123.435083 -358.689468) (xy 123.4723 -358.731005) (xy 123.503073 -358.777518)
			(xy 123.526745 -358.828015) (xy 123.542813 -358.881422) (xy 123.550933 -358.936598) (xy 123.551442 -358.964484)
			(xy 123.550933 -358.99237) (xy 123.542813 -359.047546) (xy 123.526745 -359.100953) (xy 123.503073 -359.15145)
			(xy 123.4723 -359.197963) (xy 123.435083 -359.2395) (xy 123.392215 -359.275175) (xy 123.344609 -359.304229)
			(xy 123.29328 -359.326041) (xy 123.239323 -359.340147) (xy 123.183886 -359.346247) (xy 123.128152 -359.34421)
			(xy 123.073309 -359.33408) (xy 123.020525 -359.316073) (xy 122.970925 -359.290572) (xy 122.925567 -359.258121)
			(xy 122.885418 -359.219412) (xy 122.851332 -359.175269) (xy 122.824036 -359.126634) (xy 122.804113 -359.074543)
			(xy 122.791987 -359.020106) (xy 122.787916 -358.964484) (xy 109.93628 -358.964484) (xy 109.93628 -360.61142)
			(xy 112.831624 -360.61142) (xy 112.835695 -360.555798) (xy 112.847821 -360.501361) (xy 112.867744 -360.44927)
			(xy 112.89504 -360.400635) (xy 112.929126 -360.356492) (xy 112.969275 -360.317783) (xy 113.014633 -360.285332)
			(xy 113.064233 -360.259831) (xy 113.117017 -360.241824) (xy 113.17186 -360.231694) (xy 113.227594 -360.229657)
			(xy 113.283031 -360.235757) (xy 113.336988 -360.249863) (xy 113.388317 -360.271675) (xy 113.435923 -360.300729)
			(xy 113.478791 -360.336404) (xy 113.516008 -360.377941) (xy 113.546781 -360.424454) (xy 113.570453 -360.474951)
			(xy 113.586521 -360.528358) (xy 113.594641 -360.583534) (xy 113.59515 -360.61142) (xy 113.594641 -360.639306)
			(xy 113.586521 -360.694482) (xy 113.570453 -360.747889) (xy 113.546781 -360.798386) (xy 113.516008 -360.844899)
			(xy 113.478791 -360.886436) (xy 113.435923 -360.922111) (xy 113.388317 -360.951165) (xy 113.336988 -360.972977)
			(xy 113.283031 -360.987083) (xy 113.227594 -360.993183) (xy 113.17186 -360.991146) (xy 113.117017 -360.981016)
			(xy 113.064233 -360.963009) (xy 113.014633 -360.937508) (xy 112.969275 -360.905057) (xy 112.929126 -360.866348)
			(xy 112.89504 -360.822205) (xy 112.867744 -360.77357) (xy 112.847821 -360.721479) (xy 112.835695 -360.667042)
			(xy 112.831624 -360.61142) (xy 109.93628 -360.61142) (xy 109.93628 -361.544616) (xy 112.355882 -361.544616)
			(xy 112.359953 -361.488994) (xy 112.372079 -361.434557) (xy 112.392002 -361.382466) (xy 112.419298 -361.333831)
			(xy 112.453384 -361.289688) (xy 112.493533 -361.250979) (xy 112.538891 -361.218528) (xy 112.588491 -361.193027)
			(xy 112.641275 -361.17502) (xy 112.696118 -361.16489) (xy 112.751852 -361.162853) (xy 112.807289 -361.168953)
			(xy 112.861246 -361.183059) (xy 112.912575 -361.204871) (xy 112.960181 -361.233925) (xy 113.003049 -361.2696)
			(xy 113.040266 -361.311137) (xy 113.071039 -361.35765) (xy 113.094711 -361.408147) (xy 113.110779 -361.461554)
			(xy 113.118899 -361.51673) (xy 113.119408 -361.544616) (xy 113.118899 -361.572502) (xy 113.110779 -361.627678)
			(xy 113.094711 -361.681085) (xy 113.071039 -361.731582) (xy 113.040266 -361.778095) (xy 113.003049 -361.819632)
			(xy 112.960181 -361.855307) (xy 112.912575 -361.884361) (xy 112.861246 -361.906173) (xy 112.807289 -361.920279)
			(xy 112.751852 -361.926379) (xy 112.696118 -361.924342) (xy 112.641275 -361.914212) (xy 112.588491 -361.896205)
			(xy 112.538891 -361.870704) (xy 112.493533 -361.838253) (xy 112.453384 -361.799544) (xy 112.419298 -361.755401)
			(xy 112.392002 -361.706766) (xy 112.372079 -361.654675) (xy 112.359953 -361.600238) (xy 112.355882 -361.544616)
			(xy 109.93628 -361.544616) (xy 109.93628 -362.17098) (xy 109.935629 -362.195961) (xy 109.925897 -362.244967)
			(xy 109.906801 -362.291137) (xy 109.879074 -362.3327) (xy 109.861858 -362.350812) (xy 109.78261 -362.43006)
			(xy 111.033812 -362.43006) (xy 111.037883 -362.374438) (xy 111.050009 -362.320001) (xy 111.069932 -362.26791)
			(xy 111.097228 -362.219275) (xy 111.131314 -362.175132) (xy 111.171463 -362.136423) (xy 111.216821 -362.103972)
			(xy 111.266421 -362.078471) (xy 111.319205 -362.060464) (xy 111.374048 -362.050334) (xy 111.429782 -362.048297)
			(xy 111.485219 -362.054397) (xy 111.539176 -362.068503) (xy 111.590505 -362.090315) (xy 111.638111 -362.119369)
			(xy 111.680979 -362.155044) (xy 111.718196 -362.196581) (xy 111.748969 -362.243094) (xy 111.772641 -362.293591)
			(xy 111.788709 -362.346998) (xy 111.796829 -362.402174) (xy 111.797338 -362.43006) (xy 111.796829 -362.457946)
			(xy 111.788709 -362.513122) (xy 111.772641 -362.566529) (xy 111.748969 -362.617026) (xy 111.718196 -362.663539)
			(xy 111.680979 -362.705076) (xy 111.638111 -362.740751) (xy 111.590505 -362.769805) (xy 111.539176 -362.791617)
			(xy 111.485219 -362.805723) (xy 111.429782 -362.811823) (xy 111.374048 -362.809786) (xy 111.319205 -362.799656)
			(xy 111.266421 -362.781649) (xy 111.216821 -362.756148) (xy 111.171463 -362.723697) (xy 111.131314 -362.684988)
			(xy 111.097228 -362.640845) (xy 111.069932 -362.59221) (xy 111.050009 -362.540119) (xy 111.037883 -362.485682)
			(xy 111.033812 -362.43006) (xy 109.78261 -362.43006) (xy 109.3851 -362.82757) (xy 109.3851 -363.375702)
			(xy 109.736888 -363.375702) (xy 109.740959 -363.32008) (xy 109.753085 -363.265643) (xy 109.773008 -363.213552)
			(xy 109.800304 -363.164917) (xy 109.83439 -363.120774) (xy 109.874539 -363.082065) (xy 109.919897 -363.049614)
			(xy 109.969497 -363.024113) (xy 110.022281 -363.006106) (xy 110.077124 -362.995976) (xy 110.132858 -362.993939)
			(xy 110.188295 -363.000039) (xy 110.242252 -363.014145) (xy 110.293581 -363.035957) (xy 110.341187 -363.065011)
			(xy 110.384055 -363.100686) (xy 110.421272 -363.142223) (xy 110.452045 -363.188736) (xy 110.475717 -363.239233)
			(xy 110.491785 -363.29264) (xy 110.496608 -363.32541) (xy 112.722658 -363.32541) (xy 112.726729 -363.269788)
			(xy 112.738855 -363.215351) (xy 112.758778 -363.16326) (xy 112.786074 -363.114625) (xy 112.82016 -363.070482)
			(xy 112.860309 -363.031773) (xy 112.905667 -362.999322) (xy 112.955267 -362.973821) (xy 113.008051 -362.955814)
			(xy 113.062894 -362.945684) (xy 113.118628 -362.943647) (xy 113.174065 -362.949747) (xy 113.228022 -362.963853)
			(xy 113.279351 -362.985665) (xy 113.326957 -363.014719) (xy 113.369825 -363.050394) (xy 113.407042 -363.091931)
			(xy 113.437815 -363.138444) (xy 113.461487 -363.188941) (xy 113.477555 -363.242348) (xy 113.485675 -363.297524)
			(xy 113.486184 -363.32541) (xy 113.485675 -363.353296) (xy 113.477555 -363.408472) (xy 113.461487 -363.461879)
			(xy 113.437815 -363.512376) (xy 113.407042 -363.558889) (xy 113.369825 -363.600426) (xy 113.326957 -363.636101)
			(xy 113.279351 -363.665155) (xy 113.228022 -363.686967) (xy 113.174065 -363.701073) (xy 113.118628 -363.707173)
			(xy 113.062894 -363.705136) (xy 113.008051 -363.695006) (xy 112.955267 -363.676999) (xy 112.905667 -363.651498)
			(xy 112.860309 -363.619047) (xy 112.82016 -363.580338) (xy 112.786074 -363.536195) (xy 112.758778 -363.48756)
			(xy 112.738855 -363.435469) (xy 112.726729 -363.381032) (xy 112.722658 -363.32541) (xy 110.496608 -363.32541)
			(xy 110.499905 -363.347816) (xy 110.500414 -363.375702) (xy 110.499905 -363.403588) (xy 110.491785 -363.458764)
			(xy 110.475717 -363.512171) (xy 110.452045 -363.562668) (xy 110.421272 -363.609181) (xy 110.384055 -363.650718)
			(xy 110.341187 -363.686393) (xy 110.293581 -363.715447) (xy 110.242252 -363.737259) (xy 110.188295 -363.751365)
			(xy 110.132858 -363.757465) (xy 110.077124 -363.755428) (xy 110.022281 -363.745298) (xy 109.969497 -363.727291)
			(xy 109.919897 -363.70179) (xy 109.874539 -363.669339) (xy 109.83439 -363.63063) (xy 109.800304 -363.586487)
			(xy 109.773008 -363.537852) (xy 109.753085 -363.485761) (xy 109.740959 -363.431324) (xy 109.736888 -363.375702)
			(xy 109.3851 -363.375702) (xy 109.3851 -364.40618) (xy 109.82782 -364.40618) (xy 109.831891 -364.350558)
			(xy 109.844017 -364.296121) (xy 109.86394 -364.24403) (xy 109.891236 -364.195395) (xy 109.925322 -364.151252)
			(xy 109.965471 -364.112543) (xy 110.010829 -364.080092) (xy 110.060429 -364.054591) (xy 110.113213 -364.036584)
			(xy 110.168056 -364.026454) (xy 110.22379 -364.024417) (xy 110.279227 -364.030517) (xy 110.333184 -364.044623)
			(xy 110.384513 -364.066435) (xy 110.432119 -364.095489) (xy 110.474987 -364.131164) (xy 110.512204 -364.172701)
			(xy 110.542977 -364.219214) (xy 110.548703 -364.231428) (xy 111.419638 -364.231428) (xy 111.423709 -364.175806)
			(xy 111.435835 -364.121369) (xy 111.455758 -364.069278) (xy 111.483054 -364.020643) (xy 111.51714 -363.9765)
			(xy 111.557289 -363.937791) (xy 111.602647 -363.90534) (xy 111.652247 -363.879839) (xy 111.705031 -363.861832)
			(xy 111.759874 -363.851702) (xy 111.815608 -363.849665) (xy 111.871045 -363.855765) (xy 111.925002 -363.869871)
			(xy 111.976331 -363.891683) (xy 112.023937 -363.920737) (xy 112.066805 -363.956412) (xy 112.104022 -363.997949)
			(xy 112.134795 -364.044462) (xy 112.158467 -364.094959) (xy 112.174535 -364.148366) (xy 112.182655 -364.203542)
			(xy 112.183164 -364.231428) (xy 112.182655 -364.259314) (xy 112.174535 -364.31449) (xy 112.158467 -364.367897)
			(xy 112.134795 -364.418394) (xy 112.104022 -364.464907) (xy 112.066805 -364.506444) (xy 112.023937 -364.542119)
			(xy 111.976331 -364.571173) (xy 111.925002 -364.592985) (xy 111.871045 -364.607091) (xy 111.815608 -364.613191)
			(xy 111.759874 -364.611154) (xy 111.705031 -364.601024) (xy 111.652247 -364.583017) (xy 111.602647 -364.557516)
			(xy 111.557289 -364.525065) (xy 111.51714 -364.486356) (xy 111.483054 -364.442213) (xy 111.455758 -364.393578)
			(xy 111.435835 -364.341487) (xy 111.423709 -364.28705) (xy 111.419638 -364.231428) (xy 110.548703 -364.231428)
			(xy 110.566649 -364.269711) (xy 110.582717 -364.323118) (xy 110.590837 -364.378294) (xy 110.591346 -364.40618)
			(xy 110.590837 -364.434066) (xy 110.582717 -364.489242) (xy 110.566649 -364.542649) (xy 110.542977 -364.593146)
			(xy 110.512204 -364.639659) (xy 110.474987 -364.681196) (xy 110.432119 -364.716871) (xy 110.384513 -364.745925)
			(xy 110.333184 -364.767737) (xy 110.279227 -364.781843) (xy 110.22379 -364.787943) (xy 110.168056 -364.785906)
			(xy 110.113213 -364.775776) (xy 110.060429 -364.757769) (xy 110.010829 -364.732268) (xy 109.965471 -364.699817)
			(xy 109.925322 -364.661108) (xy 109.891236 -364.616965) (xy 109.86394 -364.56833) (xy 109.844017 -364.516239)
			(xy 109.831891 -364.461802) (xy 109.82782 -364.40618) (xy 109.3851 -364.40618) (xy 109.3851 -364.940596)
			(xy 110.691928 -364.940596) (xy 110.695999 -364.884974) (xy 110.708125 -364.830537) (xy 110.728048 -364.778446)
			(xy 110.755344 -364.729811) (xy 110.78943 -364.685668) (xy 110.829579 -364.646959) (xy 110.874937 -364.614508)
			(xy 110.924537 -364.589007) (xy 110.977321 -364.571) (xy 111.032164 -364.56087) (xy 111.087898 -364.558833)
			(xy 111.143335 -364.564933) (xy 111.197292 -364.579039) (xy 111.248621 -364.600851) (xy 111.296227 -364.629905)
			(xy 111.339095 -364.66558) (xy 111.376312 -364.707117) (xy 111.407085 -364.75363) (xy 111.408762 -364.757208)
			(xy 112.321592 -364.757208) (xy 112.325663 -364.701586) (xy 112.337789 -364.647149) (xy 112.357712 -364.595058)
			(xy 112.385008 -364.546423) (xy 112.419094 -364.50228) (xy 112.459243 -364.463571) (xy 112.504601 -364.43112)
			(xy 112.554201 -364.405619) (xy 112.606985 -364.387612) (xy 112.661828 -364.377482) (xy 112.717562 -364.375445)
			(xy 112.772999 -364.381545) (xy 112.826956 -364.395651) (xy 112.878285 -364.417463) (xy 112.925891 -364.446517)
			(xy 112.968759 -364.482192) (xy 113.005976 -364.523729) (xy 113.036749 -364.570242) (xy 113.060421 -364.620739)
			(xy 113.076489 -364.674146) (xy 113.084609 -364.729322) (xy 113.085118 -364.757208) (xy 113.084609 -364.785094)
			(xy 113.076489 -364.84027) (xy 113.060421 -364.893677) (xy 113.036749 -364.944174) (xy 113.005976 -364.990687)
			(xy 112.968759 -365.032224) (xy 112.925891 -365.067899) (xy 112.878285 -365.096953) (xy 112.826956 -365.118765)
			(xy 112.772999 -365.132871) (xy 112.717562 -365.138971) (xy 112.661828 -365.136934) (xy 112.606985 -365.126804)
			(xy 112.554201 -365.108797) (xy 112.504601 -365.083296) (xy 112.459243 -365.050845) (xy 112.419094 -365.012136)
			(xy 112.385008 -364.967993) (xy 112.357712 -364.919358) (xy 112.337789 -364.867267) (xy 112.325663 -364.81283)
			(xy 112.321592 -364.757208) (xy 111.408762 -364.757208) (xy 111.430757 -364.804127) (xy 111.446825 -364.857534)
			(xy 111.454945 -364.91271) (xy 111.455454 -364.940596) (xy 111.454945 -364.968482) (xy 111.446825 -365.023658)
			(xy 111.430757 -365.077065) (xy 111.407085 -365.127562) (xy 111.376312 -365.174075) (xy 111.339095 -365.215612)
			(xy 111.296227 -365.251287) (xy 111.248621 -365.280341) (xy 111.197292 -365.302153) (xy 111.143335 -365.316259)
			(xy 111.087898 -365.322359) (xy 111.032164 -365.320322) (xy 110.977321 -365.310192) (xy 110.924537 -365.292185)
			(xy 110.874937 -365.266684) (xy 110.829579 -365.234233) (xy 110.78943 -365.195524) (xy 110.755344 -365.151381)
			(xy 110.728048 -365.102746) (xy 110.708125 -365.050655) (xy 110.695999 -364.996218) (xy 110.691928 -364.940596)
			(xy 109.3851 -364.940596) (xy 109.3851 -365.2139) (xy 109.384456 -365.238882) (xy 109.37472 -365.287887)
			(xy 109.355622 -365.334057) (xy 109.327894 -365.37562) (xy 109.310678 -365.393732) (xy 109.191044 -365.513366)
			(xy 109.842298 -365.513366) (xy 109.846369 -365.457744) (xy 109.858495 -365.403307) (xy 109.878418 -365.351216)
			(xy 109.905714 -365.302581) (xy 109.9398 -365.258438) (xy 109.979949 -365.219729) (xy 110.025307 -365.187278)
			(xy 110.074907 -365.161777) (xy 110.127691 -365.14377) (xy 110.182534 -365.13364) (xy 110.238268 -365.131603)
			(xy 110.293705 -365.137703) (xy 110.347662 -365.151809) (xy 110.398991 -365.173621) (xy 110.446597 -365.202675)
			(xy 110.489465 -365.23835) (xy 110.526682 -365.279887) (xy 110.557455 -365.3264) (xy 110.581127 -365.376897)
			(xy 110.597195 -365.430304) (xy 110.605315 -365.48548) (xy 110.605824 -365.513366) (xy 110.605315 -365.541252)
			(xy 110.597195 -365.596428) (xy 110.581127 -365.649835) (xy 110.557455 -365.700332) (xy 110.526682 -365.746845)
			(xy 110.489465 -365.788382) (xy 110.446597 -365.824057) (xy 110.398991 -365.853111) (xy 110.347662 -365.874923)
			(xy 110.293705 -365.889029) (xy 110.238268 -365.895129) (xy 110.182534 -365.893092) (xy 110.127691 -365.882962)
			(xy 110.074907 -365.864955) (xy 110.025307 -365.839454) (xy 109.979949 -365.807003) (xy 109.9398 -365.768294)
			(xy 109.905714 -365.724151) (xy 109.878418 -365.675516) (xy 109.858495 -365.623425) (xy 109.846369 -365.568988)
			(xy 109.842298 -365.513366) (xy 109.191044 -365.513366) (xy 108.639864 -366.064546) (xy 108.639864 -366.24514)
			(xy 108.679742 -366.25403) (xy 108.707593 -366.260794) (xy 108.761036 -366.281496) (xy 108.81078 -366.30996)
			(xy 108.855707 -366.345544) (xy 108.894805 -366.387448) (xy 108.927196 -366.43473) (xy 108.952149 -366.486324)
			(xy 108.969103 -366.541071) (xy 108.977677 -366.597738) (xy 108.978192 -366.626394) (xy 108.977739 -366.653647)
			(xy 108.969982 -366.7076) (xy 108.954626 -366.759899) (xy 108.931983 -366.80948) (xy 108.902515 -366.855334)
			(xy 108.86682 -366.896527) (xy 108.825626 -366.932221) (xy 108.779771 -366.961688) (xy 108.730189 -366.98433)
			(xy 108.67789 -366.999685) (xy 108.623937 -367.00744) (xy 108.596684 -367.007902) (xy 108.570305 -367.007443)
			(xy 108.518048 -367.000188) (xy 108.467289 -366.985805) (xy 108.418994 -366.964569) (xy 108.374084 -366.936883)
			(xy 108.333415 -366.903276) (xy 108.297762 -366.864388) (xy 108.267805 -366.82096) (xy 108.255562 -366.79759)
			(xy 108.24886 -366.785231) (xy 108.229885 -366.764503) (xy 108.205971 -366.749741) (xy 108.178935 -366.742069)
			(xy 108.150833 -366.742069) (xy 108.123797 -366.749741) (xy 108.099883 -366.764503) (xy 108.080908 -366.785231)
			(xy 108.074206 -366.79759) (xy 108.061972 -366.820965) (xy 108.032009 -366.86439) (xy 107.996354 -366.903276)
			(xy 107.955683 -366.936882) (xy 107.910773 -366.964569) (xy 107.862479 -366.985808) (xy 107.81172 -367.000196)
			(xy 107.759463 -367.007458) (xy 107.733084 -367.007902) (xy 107.705832 -367.007437) (xy 107.651883 -366.999678)
			(xy 107.599588 -366.984321) (xy 107.55001 -366.961677) (xy 107.504159 -366.932209) (xy 107.462969 -366.896515)
			(xy 107.427278 -366.855323) (xy 107.397812 -366.809471) (xy 107.375172 -366.759892) (xy 107.359817 -366.707595)
			(xy 107.352061 -366.653646) (xy 107.351576 -366.626394) (xy 107.35208 -366.597976) (xy 107.36054 -366.541772)
			(xy 107.37724 -366.487445) (xy 107.401813 -366.436195) (xy 107.433714 -366.389156) (xy 107.472239 -366.347367)
			(xy 107.516535 -366.311754) (xy 107.565622 -366.283104) (xy 107.618416 -366.262051) (xy 107.645962 -366.255046)
			(xy 107.685332 -366.245648) (xy 107.685332 -365.866172) (xy 107.68595 -365.841189) (xy 107.695692 -365.792181)
			(xy 107.714798 -365.746012) (xy 107.742534 -365.704451) (xy 107.759754 -365.68634) (xy 108.495592 -364.950502)
			(xy 108.495592 -362.564172) (xy 108.496193 -362.539188) (xy 108.505937 -362.490179) (xy 108.525048 -362.444009)
			(xy 108.55279 -362.402449) (xy 108.570014 -362.38434) (xy 109.046772 -361.907582) (xy 109.046772 -356.407212)
			(xy 109.047403 -356.382229) (xy 109.05714 -356.333222) (xy 109.076241 -356.287052) (xy 109.103975 -356.245491)
			(xy 109.121194 -356.22738) (xy 109.761274 -355.5873) (xy 109.779344 -355.570016) (xy 109.820898 -355.542211)
			(xy 109.867077 -355.523045) (xy 109.916107 -355.513255) (xy 109.941106 -355.512624) (xy 110.260892 -355.512624)
			(xy 110.260892 -355.370638) (xy 109.413802 -354.523548) (xy 108.998258 -354.523548) (xy 108.973263 -354.522885)
			(xy 108.924241 -354.513091) (xy 108.87807 -354.493925) (xy 108.836523 -354.466124) (xy 108.818426 -354.448872)
			(xy 107.57154 -353.20224) (xy 102.338124 -353.20224) (xy 101.41712 -354.12299) (xy 101.41712 -354.266754)
			(xy 101.494844 -354.266754) (xy 101.510084 -354.244656) (xy 101.52538 -354.222953) (xy 101.561013 -354.183588)
			(xy 101.601761 -354.149547) (xy 101.646838 -354.121488) (xy 101.695371 -354.099953) (xy 101.746422 -354.085358)
			(xy 101.799004 -354.077986) (xy 101.825552 -354.077524) (xy 101.852809 -354.07792) (xy 101.90677 -354.085672)
			(xy 101.959078 -354.101025) (xy 102.008669 -354.123667) (xy 102.054532 -354.153136) (xy 102.095734 -354.188833)
			(xy 102.131435 -354.23003) (xy 102.16091 -354.275889) (xy 102.183558 -354.325477) (xy 102.198918 -354.377783)
			(xy 102.206677 -354.431743) (xy 102.206677 -354.486257) (xy 102.205113 -354.497132) (xy 105.004868 -354.497132)
			(xy 105.008939 -354.44151) (xy 105.021065 -354.387073) (xy 105.040988 -354.334982) (xy 105.068284 -354.286347)
			(xy 105.10237 -354.242204) (xy 105.142519 -354.203495) (xy 105.187877 -354.171044) (xy 105.237477 -354.145543)
			(xy 105.290261 -354.127536) (xy 105.345104 -354.117406) (xy 105.400838 -354.115369) (xy 105.456275 -354.121469)
			(xy 105.510232 -354.135575) (xy 105.561561 -354.157387) (xy 105.609167 -354.186441) (xy 105.652035 -354.222116)
			(xy 105.689252 -354.263653) (xy 105.720025 -354.310166) (xy 105.743697 -354.360663) (xy 105.759765 -354.41407)
			(xy 105.767885 -354.469246) (xy 105.768394 -354.497132) (xy 105.767885 -354.525018) (xy 105.759765 -354.580194)
			(xy 105.743697 -354.633601) (xy 105.720025 -354.684098) (xy 105.689252 -354.730611) (xy 105.652035 -354.772148)
			(xy 105.609167 -354.807823) (xy 105.561561 -354.836877) (xy 105.510232 -354.858689) (xy 105.456275 -354.872795)
			(xy 105.400838 -354.878895) (xy 105.345104 -354.876858) (xy 105.290261 -354.866728) (xy 105.237477 -354.848721)
			(xy 105.187877 -354.82322) (xy 105.142519 -354.790769) (xy 105.10237 -354.75206) (xy 105.068284 -354.707917)
			(xy 105.040988 -354.659282) (xy 105.021065 -354.607191) (xy 105.008939 -354.552754) (xy 105.004868 -354.497132)
			(xy 102.205113 -354.497132) (xy 102.198918 -354.540217) (xy 102.183558 -354.592523) (xy 102.16091 -354.642111)
			(xy 102.131435 -354.68797) (xy 102.095734 -354.729167) (xy 102.054532 -354.764864) (xy 102.008669 -354.794333)
			(xy 101.959078 -354.816975) (xy 101.90677 -354.832328) (xy 101.852809 -354.84008) (xy 101.825552 -354.84054)
			(xy 101.799284 -354.840109) (xy 101.747247 -354.832885) (xy 101.696692 -354.818593) (xy 101.648575 -354.797505)
			(xy 101.603804 -354.770017) (xy 101.583236 -354.753672) (xy 101.571786 -354.744983) (xy 101.54539 -354.733648)
			(xy 101.516882 -354.730114) (xy 101.488517 -354.734661) (xy 101.462542 -354.746929) (xy 101.441012 -354.765946)
			(xy 101.425632 -354.790209) (xy 101.417619 -354.817795) (xy 101.41712 -354.832158) (xy 101.41712 -355.07168)
			(xy 101.417667 -355.085237) (xy 101.424828 -355.11139) (xy 101.438625 -355.134734) (xy 101.458082 -355.15362)
			(xy 101.481826 -355.166715) (xy 101.508181 -355.173095) (xy 101.535285 -355.172308) (xy 101.561225 -355.164412)
			(xy 101.58417 -355.149962) (xy 101.59365 -355.14026) (xy 101.611788 -355.121257) (xy 101.652347 -355.087871)
			(xy 101.697105 -355.06037) (xy 101.745215 -355.039274) (xy 101.795766 -355.024982) (xy 101.8478 -355.017766)
			(xy 101.874066 -355.017324) (xy 101.901323 -355.017721) (xy 101.955282 -355.025474) (xy 102.007588 -355.040829)
			(xy 102.057177 -355.063471) (xy 102.103038 -355.092941) (xy 102.144238 -355.128637) (xy 102.179939 -355.169835)
			(xy 102.209413 -355.215693) (xy 102.232059 -355.26528) (xy 102.247418 -355.317585) (xy 102.255177 -355.371543)
			(xy 102.255177 -355.426057) (xy 102.247418 -355.480015) (xy 102.232059 -355.53232) (xy 102.209413 -355.581907)
			(xy 102.179939 -355.627765) (xy 102.144238 -355.668963) (xy 102.103038 -355.704659) (xy 102.057177 -355.734129)
			(xy 102.007588 -355.756771) (xy 101.955282 -355.772126) (xy 101.901323 -355.779879) (xy 101.874066 -355.78034)
			(xy 101.8478 -355.77987) (xy 101.795764 -355.772666) (xy 101.745211 -355.758385) (xy 101.697097 -355.737297)
			(xy 101.652334 -355.709803) (xy 101.611771 -355.676423) (xy 101.59365 -355.657404) (xy 101.584124 -355.647756)
			(xy 101.561175 -355.633344) (xy 101.535243 -355.625474) (xy 101.508155 -355.624698) (xy 101.481815 -355.631071)
			(xy 101.458079 -355.644146) (xy 101.438615 -355.663002) (xy 101.424793 -355.686312) (xy 101.417587 -355.712436)
			(xy 101.41712 -355.725984) (xy 101.41712 -356.261924) (xy 103.482392 -356.261924) (xy 103.486463 -356.206302)
			(xy 103.498589 -356.151865) (xy 103.518512 -356.099774) (xy 103.545808 -356.051139) (xy 103.579894 -356.006996)
			(xy 103.620043 -355.968287) (xy 103.665401 -355.935836) (xy 103.715001 -355.910335) (xy 103.767785 -355.892328)
			(xy 103.822628 -355.882198) (xy 103.878362 -355.880161) (xy 103.933799 -355.886261) (xy 103.987756 -355.900367)
			(xy 104.039085 -355.922179) (xy 104.086691 -355.951233) (xy 104.129559 -355.986908) (xy 104.166776 -356.028445)
			(xy 104.197549 -356.074958) (xy 104.221221 -356.125455) (xy 104.237289 -356.178862) (xy 104.245409 -356.234038)
			(xy 104.245918 -356.261924) (xy 104.245409 -356.28981) (xy 104.237289 -356.344986) (xy 104.221221 -356.398393)
			(xy 104.197549 -356.44889) (xy 104.166776 -356.495403) (xy 104.129559 -356.53694) (xy 104.086691 -356.572615)
			(xy 104.039085 -356.601669) (xy 103.987756 -356.623481) (xy 103.933799 -356.637587) (xy 103.878362 -356.643687)
			(xy 103.822628 -356.64165) (xy 103.767785 -356.63152) (xy 103.715001 -356.613513) (xy 103.665401 -356.588012)
			(xy 103.620043 -356.555561) (xy 103.579894 -356.516852) (xy 103.545808 -356.472709) (xy 103.518512 -356.424074)
			(xy 103.498589 -356.371983) (xy 103.486463 -356.317546) (xy 103.482392 -356.261924) (xy 101.41712 -356.261924)
			(xy 101.41712 -356.43058) (xy 101.417603 -356.445113) (xy 101.425812 -356.472997) (xy 101.441543 -356.49744)
			(xy 101.463521 -356.516462) (xy 101.489968 -356.528524) (xy 101.518741 -356.532648) (xy 101.547511 -356.5285)
			(xy 101.573948 -356.516418) (xy 101.585268 -356.507288) (xy 101.60618 -356.489789) (xy 101.652051 -356.460308)
			(xy 101.70165 -356.437656) (xy 101.753968 -356.422293) (xy 101.80794 -356.414533) (xy 101.835204 -356.41407)
			(xy 101.862453 -356.4146) (xy 101.916398 -356.422357) (xy 101.968689 -356.437712) (xy 102.018263 -356.460352)
			(xy 102.06411 -356.489816) (xy 102.105297 -356.525506) (xy 102.140986 -356.566693) (xy 102.17045 -356.612541)
			(xy 102.19309 -356.662115) (xy 102.208444 -356.714406) (xy 102.2162 -356.768351) (xy 102.2162 -356.822849)
			(xy 102.208444 -356.876794) (xy 102.19309 -356.929085) (xy 102.17045 -356.978659) (xy 102.140986 -357.024507)
			(xy 102.105297 -357.065694) (xy 102.06411 -357.101384) (xy 102.018263 -357.130848) (xy 101.968689 -357.153488)
			(xy 101.916398 -357.168843) (xy 101.862453 -357.1766) (xy 101.835204 -357.177086) (xy 101.807942 -357.176605)
			(xy 101.753975 -357.168837) (xy 101.701661 -357.153472) (xy 101.652064 -357.130823) (xy 101.606192 -357.10135)
			(xy 101.585268 -357.083868) (xy 101.574024 -357.074624) (xy 101.547565 -357.062509) (xy 101.518763 -357.058346)
			(xy 101.489956 -357.062474) (xy 101.463482 -357.074556) (xy 101.441489 -357.093614) (xy 101.425762 -357.118099)
			(xy 101.417577 -357.146025) (xy 101.41712 -357.160576) (xy 101.41712 -357.324152) (xy 101.417502 -357.338709)
			(xy 101.425669 -357.366654) (xy 101.441382 -357.391163) (xy 101.463368 -357.410248) (xy 101.489842 -357.422361)
			(xy 101.518658 -357.426519) (xy 101.547477 -357.422385) (xy 101.573961 -357.410294) (xy 101.585268 -357.401114)
			(xy 101.606145 -357.38367) (xy 101.651943 -357.354305) (xy 101.701444 -357.331733) (xy 101.753647 -357.316413)
			(xy 101.807494 -357.308652) (xy 101.834696 -357.30815) (xy 101.861946 -357.308697) (xy 101.915891 -357.316453)
			(xy 101.968184 -357.331807) (xy 102.017759 -357.354446) (xy 102.063608 -357.383911) (xy 102.104796 -357.419601)
			(xy 102.140487 -357.460789) (xy 102.169952 -357.506637) (xy 102.192592 -357.556212) (xy 102.207947 -357.608505)
			(xy 102.215703 -357.66245) (xy 102.215703 -357.71695) (xy 102.207947 -357.770895) (xy 102.192592 -357.823188)
			(xy 102.169952 -357.872763) (xy 102.140487 -357.918611) (xy 102.104796 -357.959799) (xy 102.063608 -357.995489)
			(xy 102.017759 -358.024954) (xy 101.968184 -358.047593) (xy 101.915891 -358.062947) (xy 101.861946 -358.070703)
			(xy 101.834696 -358.071166) (xy 101.807492 -358.070691) (xy 101.753637 -358.062952) (xy 101.70143 -358.047632)
			(xy 101.651933 -358.025042) (xy 101.606152 -357.995642) (xy 101.585268 -357.978202) (xy 101.573907 -357.969126)
			(xy 101.547452 -357.957095) (xy 101.51868 -357.952997) (xy 101.489918 -357.957163) (xy 101.463492 -357.969255)
			(xy 101.441537 -357.988298) (xy 101.42583 -358.012749) (xy 101.41764 -358.040633) (xy 101.41712 -358.055164)
			(xy 101.41712 -358.221277) (xy 103.496811 -358.221277) (xy 103.504564 -358.167319) (xy 103.519917 -358.115013)
			(xy 103.542559 -358.065425) (xy 103.572026 -358.019564) (xy 103.607721 -357.978364) (xy 103.648916 -357.942663)
			(xy 103.694772 -357.913188) (xy 103.744356 -357.890539) (xy 103.796659 -357.875177) (xy 103.850616 -357.867415)
			(xy 103.877872 -357.86695) (xy 103.894015 -357.867093) (xy 103.926189 -357.869764) (xy 103.942134 -357.872284)
			(xy 103.956157 -357.874251) (xy 103.9843 -357.871191) (xy 104.01052 -357.860522) (xy 104.032803 -357.843063)
			(xy 104.049435 -357.820157) (xy 104.059139 -357.793564) (xy 104.061168 -357.765328) (xy 104.05872 -357.75138)
			(xy 104.054913 -357.732111) (xy 104.050845 -357.693042) (xy 104.050592 -357.673402) (xy 104.051053 -357.646149)
			(xy 104.05881 -357.592198) (xy 104.074166 -357.539899) (xy 104.096808 -357.490319) (xy 104.126276 -357.444465)
			(xy 104.16197 -357.403272) (xy 104.203163 -357.367578) (xy 104.249016 -357.33811) (xy 104.298596 -357.315467)
			(xy 104.350894 -357.300111) (xy 104.404846 -357.292353) (xy 104.459352 -357.292353) (xy 104.513303 -357.30011)
			(xy 104.565601 -357.315466) (xy 104.615182 -357.338109) (xy 104.661035 -357.367577) (xy 104.702228 -357.40327)
			(xy 104.737922 -357.444463) (xy 104.767391 -357.490317) (xy 104.790033 -357.539897) (xy 104.805389 -357.592195)
			(xy 104.813147 -357.646146) (xy 104.813147 -357.700652) (xy 104.80539 -357.754604) (xy 104.790034 -357.806902)
			(xy 104.767391 -357.856482) (xy 104.737923 -357.902336) (xy 104.702229 -357.943529) (xy 104.661036 -357.979223)
			(xy 104.615183 -358.008691) (xy 104.565602 -358.031333) (xy 104.513304 -358.04669) (xy 104.459353 -358.054447)
			(xy 104.4321 -358.05491) (xy 104.415957 -358.054772) (xy 104.383783 -358.052097) (xy 104.367838 -358.049576)
			(xy 104.353814 -358.047629) (xy 104.325679 -358.050694) (xy 104.299465 -358.061365) (xy 104.277187 -358.07882)
			(xy 104.260555 -358.10172) (xy 104.250848 -358.128305) (xy 104.248811 -358.156533) (xy 104.251252 -358.17048)
			(xy 104.255053 -358.18975) (xy 104.259125 -358.228818) (xy 104.25938 -358.248458) (xy 104.25899 -358.275714)
			(xy 104.251238 -358.329672) (xy 104.235886 -358.381978) (xy 104.213246 -358.431566) (xy 104.183779 -358.477428)
			(xy 104.148086 -358.518629) (xy 104.106892 -358.554332) (xy 104.061036 -358.583808) (xy 104.011452 -358.606458)
			(xy 103.95915 -358.621821) (xy 103.905193 -358.629584) (xy 103.850681 -358.62959) (xy 103.796723 -358.621837)
			(xy 103.744418 -358.606484) (xy 103.694829 -358.583844) (xy 103.648968 -358.554376) (xy 103.607767 -358.518682)
			(xy 103.572066 -358.477488) (xy 103.54259 -358.431632) (xy 103.51994 -358.382048) (xy 103.504578 -358.329745)
			(xy 103.496815 -358.275789) (xy 103.496811 -358.221277) (xy 101.41712 -358.221277) (xy 101.41712 -359.188004)
			(xy 104.05313 -359.188004) (xy 104.057201 -359.132382) (xy 104.069327 -359.077945) (xy 104.08925 -359.025854)
			(xy 104.116546 -358.977219) (xy 104.150632 -358.933076) (xy 104.190781 -358.894367) (xy 104.236139 -358.861916)
			(xy 104.285739 -358.836415) (xy 104.338523 -358.818408) (xy 104.393366 -358.808278) (xy 104.4491 -358.806241)
			(xy 104.504537 -358.812341) (xy 104.558494 -358.826447) (xy 104.609823 -358.848259) (xy 104.657429 -358.877313)
			(xy 104.700297 -358.912988) (xy 104.737514 -358.954525) (xy 104.768287 -359.001038) (xy 104.791959 -359.051535)
			(xy 104.808027 -359.104942) (xy 104.816147 -359.160118) (xy 104.816656 -359.188004) (xy 104.816147 -359.21589)
			(xy 104.808027 -359.271066) (xy 104.791959 -359.324473) (xy 104.768287 -359.37497) (xy 104.737514 -359.421483)
			(xy 104.700297 -359.46302) (xy 104.657429 -359.498695) (xy 104.609823 -359.527749) (xy 104.558494 -359.549561)
			(xy 104.504537 -359.563667) (xy 104.4491 -359.569767) (xy 104.393366 -359.56773) (xy 104.338523 -359.5576)
			(xy 104.285739 -359.539593) (xy 104.236139 -359.514092) (xy 104.190781 -359.481641) (xy 104.150632 -359.442932)
			(xy 104.116546 -359.398789) (xy 104.08925 -359.350154) (xy 104.069327 -359.298063) (xy 104.057201 -359.243626)
			(xy 104.05313 -359.188004) (xy 101.41712 -359.188004) (xy 101.41712 -359.635044) (xy 101.417608 -359.649879)
			(xy 101.426172 -359.678288) (xy 101.442535 -359.703039) (xy 101.465319 -359.722046) (xy 101.492603 -359.733707)
			(xy 101.522086 -359.73704) (xy 101.551284 -359.731762) (xy 101.577736 -359.718319) (xy 101.588824 -359.70845)
			(xy 101.610217 -359.688847) (xy 101.657866 -359.655734) (xy 101.709975 -359.63021) (xy 101.765345 -359.612861)
			(xy 101.822702 -359.604087) (xy 101.851714 -359.603548) (xy 101.878961 -359.604123) (xy 101.932901 -359.61188)
			(xy 101.985188 -359.627235) (xy 102.034758 -359.649874) (xy 102.080601 -359.679337) (xy 102.121785 -359.715025)
			(xy 102.157471 -359.75621) (xy 102.186933 -359.802054) (xy 102.20957 -359.851625) (xy 102.224923 -359.903912)
			(xy 102.232678 -359.957853) (xy 102.232678 -360.012347) (xy 102.224923 -360.066288) (xy 102.20957 -360.118575)
			(xy 102.186933 -360.168146) (xy 102.157471 -360.21399) (xy 102.154899 -360.216958) (xy 103.98963 -360.216958)
			(xy 103.993701 -360.161336) (xy 104.005827 -360.106899) (xy 104.02575 -360.054808) (xy 104.053046 -360.006173)
			(xy 104.087132 -359.96203) (xy 104.127281 -359.923321) (xy 104.172639 -359.89087) (xy 104.222239 -359.865369)
			(xy 104.275023 -359.847362) (xy 104.329866 -359.837232) (xy 104.3856 -359.835195) (xy 104.441037 -359.841295)
			(xy 104.494994 -359.855401) (xy 104.546323 -359.877213) (xy 104.593929 -359.906267) (xy 104.636797 -359.941942)
			(xy 104.674014 -359.983479) (xy 104.704787 -360.029992) (xy 104.728459 -360.080489) (xy 104.744527 -360.133896)
			(xy 104.752647 -360.189072) (xy 104.753156 -360.216958) (xy 104.752647 -360.244844) (xy 104.744527 -360.30002)
			(xy 104.728459 -360.353427) (xy 104.704787 -360.403924) (xy 104.674014 -360.450437) (xy 104.636797 -360.491974)
			(xy 104.593929 -360.527649) (xy 104.546323 -360.556703) (xy 104.494994 -360.578515) (xy 104.441037 -360.592621)
			(xy 104.3856 -360.598721) (xy 104.329866 -360.596684) (xy 104.275023 -360.586554) (xy 104.222239 -360.568547)
			(xy 104.172639 -360.543046) (xy 104.127281 -360.510595) (xy 104.087132 -360.471886) (xy 104.053046 -360.427743)
			(xy 104.02575 -360.379108) (xy 104.005827 -360.327017) (xy 103.993701 -360.27258) (xy 103.98963 -360.216958)
			(xy 102.154899 -360.216958) (xy 102.121785 -360.255175) (xy 102.080601 -360.290863) (xy 102.034758 -360.320326)
			(xy 101.985188 -360.342965) (xy 101.932901 -360.35832) (xy 101.878961 -360.366077) (xy 101.851714 -360.366564)
			(xy 101.822702 -360.366034) (xy 101.765343 -360.357266) (xy 101.709974 -360.339914) (xy 101.65787 -360.314379)
			(xy 101.610233 -360.28125) (xy 101.588824 -360.261662) (xy 101.577724 -360.251829) (xy 101.55128 -360.238441)
			(xy 101.522107 -360.233198) (xy 101.492657 -360.236543) (xy 101.465403 -360.248194) (xy 101.442635 -360.267172)
			(xy 101.426267 -360.291883) (xy 101.417674 -360.32025) (xy 101.41712 -360.335068) (xy 101.41712 -361.952032)
			(xy 102.011732 -361.952032) (xy 102.015803 -361.89641) (xy 102.027929 -361.841973) (xy 102.047852 -361.789882)
			(xy 102.075148 -361.741247) (xy 102.109234 -361.697104) (xy 102.149383 -361.658395) (xy 102.194741 -361.625944)
			(xy 102.244341 -361.600443) (xy 102.297125 -361.582436) (xy 102.351968 -361.572306) (xy 102.407702 -361.570269)
			(xy 102.463139 -361.576369) (xy 102.517096 -361.590475) (xy 102.568425 -361.612287) (xy 102.616031 -361.641341)
			(xy 102.658899 -361.677016) (xy 102.696116 -361.718553) (xy 102.726889 -361.765066) (xy 102.750561 -361.815563)
			(xy 102.766629 -361.86897) (xy 102.774749 -361.924146) (xy 102.775188 -361.948222) (xy 103.776778 -361.948222)
			(xy 103.780849 -361.8926) (xy 103.792975 -361.838163) (xy 103.812898 -361.786072) (xy 103.840194 -361.737437)
			(xy 103.87428 -361.693294) (xy 103.914429 -361.654585) (xy 103.959787 -361.622134) (xy 104.009387 -361.596633)
			(xy 104.062171 -361.578626) (xy 104.117014 -361.568496) (xy 104.172748 -361.566459) (xy 104.228185 -361.572559)
			(xy 104.282142 -361.586665) (xy 104.333471 -361.608477) (xy 104.381077 -361.637531) (xy 104.423945 -361.673206)
			(xy 104.461162 -361.714743) (xy 104.491935 -361.761256) (xy 104.515607 -361.811753) (xy 104.531675 -361.86516)
			(xy 104.539795 -361.920336) (xy 104.540304 -361.948222) (xy 104.539795 -361.976108) (xy 104.531675 -362.031284)
			(xy 104.515607 -362.084691) (xy 104.491935 -362.135188) (xy 104.461162 -362.181701) (xy 104.423945 -362.223238)
			(xy 104.381077 -362.258913) (xy 104.333471 -362.287967) (xy 104.282142 -362.309779) (xy 104.229145 -362.323634)
			(xy 105.517186 -362.323634) (xy 105.521257 -362.268012) (xy 105.533383 -362.213575) (xy 105.553306 -362.161484)
			(xy 105.580602 -362.112849) (xy 105.614688 -362.068706) (xy 105.654837 -362.029997) (xy 105.700195 -361.997546)
			(xy 105.749795 -361.972045) (xy 105.802579 -361.954038) (xy 105.857422 -361.943908) (xy 105.913156 -361.941871)
			(xy 105.968593 -361.947971) (xy 106.02255 -361.962077) (xy 106.073879 -361.983889) (xy 106.121485 -362.012943)
			(xy 106.164353 -362.048618) (xy 106.20157 -362.090155) (xy 106.232343 -362.136668) (xy 106.256015 -362.187165)
			(xy 106.272083 -362.240572) (xy 106.280203 -362.295748) (xy 106.280712 -362.323634) (xy 106.280203 -362.35152)
			(xy 106.272083 -362.406696) (xy 106.256015 -362.460103) (xy 106.232343 -362.5106) (xy 106.20157 -362.557113)
			(xy 106.164353 -362.59865) (xy 106.121485 -362.634325) (xy 106.073879 -362.663379) (xy 106.02255 -362.685191)
			(xy 105.968593 -362.699297) (xy 105.913156 -362.705397) (xy 105.857422 -362.70336) (xy 105.802579 -362.69323)
			(xy 105.749795 -362.675223) (xy 105.700195 -362.649722) (xy 105.654837 -362.617271) (xy 105.614688 -362.578562)
			(xy 105.580602 -362.534419) (xy 105.553306 -362.485784) (xy 105.533383 -362.433693) (xy 105.521257 -362.379256)
			(xy 105.517186 -362.323634) (xy 104.229145 -362.323634) (xy 104.228185 -362.323885) (xy 104.172748 -362.329985)
			(xy 104.117014 -362.327948) (xy 104.062171 -362.317818) (xy 104.009387 -362.299811) (xy 103.959787 -362.27431)
			(xy 103.914429 -362.241859) (xy 103.87428 -362.20315) (xy 103.840194 -362.159007) (xy 103.812898 -362.110372)
			(xy 103.792975 -362.058281) (xy 103.780849 -362.003844) (xy 103.776778 -361.948222) (xy 102.775188 -361.948222)
			(xy 102.775258 -361.952032) (xy 102.774749 -361.979918) (xy 102.766629 -362.035094) (xy 102.750561 -362.088501)
			(xy 102.726889 -362.138998) (xy 102.696116 -362.185511) (xy 102.658899 -362.227048) (xy 102.616031 -362.262723)
			(xy 102.568425 -362.291777) (xy 102.517096 -362.313589) (xy 102.463139 -362.327695) (xy 102.407702 -362.333795)
			(xy 102.351968 -362.331758) (xy 102.297125 -362.321628) (xy 102.244341 -362.303621) (xy 102.194741 -362.27812)
			(xy 102.149383 -362.245669) (xy 102.109234 -362.20696) (xy 102.075148 -362.162817) (xy 102.047852 -362.114182)
			(xy 102.027929 -362.062091) (xy 102.015803 -362.007654) (xy 102.011732 -361.952032) (xy 101.41712 -361.952032)
			(xy 101.41712 -362.689902) (xy 101.875661 -363.148372) (xy 106.262676 -363.148372) (xy 106.266747 -363.09275)
			(xy 106.278873 -363.038313) (xy 106.298796 -362.986222) (xy 106.326092 -362.937587) (xy 106.360178 -362.893444)
			(xy 106.400327 -362.854735) (xy 106.445685 -362.822284) (xy 106.495285 -362.796783) (xy 106.548069 -362.778776)
			(xy 106.602912 -362.768646) (xy 106.658646 -362.766609) (xy 106.714083 -362.772709) (xy 106.76804 -362.786815)
			(xy 106.819369 -362.808627) (xy 106.866975 -362.837681) (xy 106.909843 -362.873356) (xy 106.94706 -362.914893)
			(xy 106.977833 -362.961406) (xy 107.001505 -363.011903) (xy 107.017573 -363.06531) (xy 107.025693 -363.120486)
			(xy 107.026202 -363.148372) (xy 107.025693 -363.176258) (xy 107.017573 -363.231434) (xy 107.001505 -363.284841)
			(xy 106.977833 -363.335338) (xy 106.94706 -363.381851) (xy 106.909843 -363.423388) (xy 106.866975 -363.459063)
			(xy 106.819369 -363.488117) (xy 106.76804 -363.509929) (xy 106.714083 -363.524035) (xy 106.658646 -363.530135)
			(xy 106.602912 -363.528098) (xy 106.548069 -363.517968) (xy 106.495285 -363.499961) (xy 106.445685 -363.47446)
			(xy 106.400327 -363.442009) (xy 106.360178 -363.4033) (xy 106.326092 -363.359157) (xy 106.298796 -363.310522)
			(xy 106.278873 -363.258431) (xy 106.266747 -363.203994) (xy 106.262676 -363.148372) (xy 101.875661 -363.148372)
			(xy 102.365194 -363.63783) (xy 104.371646 -363.63783) (xy 104.375717 -363.582208) (xy 104.387843 -363.527771)
			(xy 104.407766 -363.47568) (xy 104.435062 -363.427045) (xy 104.469148 -363.382902) (xy 104.509297 -363.344193)
			(xy 104.554655 -363.311742) (xy 104.604255 -363.286241) (xy 104.657039 -363.268234) (xy 104.711882 -363.258104)
			(xy 104.767616 -363.256067) (xy 104.823053 -363.262167) (xy 104.87701 -363.276273) (xy 104.928339 -363.298085)
			(xy 104.975945 -363.327139) (xy 105.018813 -363.362814) (xy 105.05603 -363.404351) (xy 105.086803 -363.450864)
			(xy 105.110475 -363.501361) (xy 105.126543 -363.554768) (xy 105.134663 -363.609944) (xy 105.135172 -363.63783)
			(xy 105.134663 -363.665716) (xy 105.126543 -363.720892) (xy 105.110475 -363.774299) (xy 105.086803 -363.824796)
			(xy 105.05603 -363.871309) (xy 105.018813 -363.912846) (xy 104.975945 -363.948521) (xy 104.928339 -363.977575)
			(xy 104.87701 -363.999387) (xy 104.823053 -364.013493) (xy 104.767616 -364.019593) (xy 104.711882 -364.017556)
			(xy 104.657039 -364.007426) (xy 104.604255 -363.989419) (xy 104.554655 -363.963918) (xy 104.509297 -363.931467)
			(xy 104.469148 -363.892758) (xy 104.435062 -363.848615) (xy 104.407766 -363.79998) (xy 104.387843 -363.747889)
			(xy 104.375717 -363.693452) (xy 104.371646 -363.63783) (xy 102.365194 -363.63783) (xy 103.066596 -364.339124)
			(xy 104.802686 -364.339124) (xy 104.827682 -364.339768) (xy 104.876704 -364.34957) (xy 104.922874 -364.368741)
			(xy 104.964421 -364.396546) (xy 104.982518 -364.4138) (xy 106.12069 -364.4138) (xy 106.124761 -364.358178)
			(xy 106.136887 -364.303741) (xy 106.15681 -364.25165) (xy 106.184106 -364.203015) (xy 106.218192 -364.158872)
			(xy 106.258341 -364.120163) (xy 106.303699 -364.087712) (xy 106.353299 -364.062211) (xy 106.406083 -364.044204)
			(xy 106.460926 -364.034074) (xy 106.51666 -364.032037) (xy 106.572097 -364.038137) (xy 106.626054 -364.052243)
			(xy 106.677383 -364.074055) (xy 106.724989 -364.103109) (xy 106.767857 -364.138784) (xy 106.805074 -364.180321)
			(xy 106.835847 -364.226834) (xy 106.859519 -364.277331) (xy 106.869398 -364.310168) (xy 107.575602 -364.310168)
			(xy 107.579673 -364.254546) (xy 107.591799 -364.200109) (xy 107.611722 -364.148018) (xy 107.639018 -364.099383)
			(xy 107.673104 -364.05524) (xy 107.713253 -364.016531) (xy 107.758611 -363.98408) (xy 107.808211 -363.958579)
			(xy 107.860995 -363.940572) (xy 107.915838 -363.930442) (xy 107.971572 -363.928405) (xy 108.027009 -363.934505)
			(xy 108.080966 -363.948611) (xy 108.132295 -363.970423) (xy 108.179901 -363.999477) (xy 108.222769 -364.035152)
			(xy 108.259986 -364.076689) (xy 108.290759 -364.123202) (xy 108.314431 -364.173699) (xy 108.330499 -364.227106)
			(xy 108.338619 -364.282282) (xy 108.339128 -364.310168) (xy 108.338619 -364.338054) (xy 108.330499 -364.39323)
			(xy 108.314431 -364.446637) (xy 108.290759 -364.497134) (xy 108.259986 -364.543647) (xy 108.222769 -364.585184)
			(xy 108.179901 -364.620859) (xy 108.132295 -364.649913) (xy 108.080966 -364.671725) (xy 108.027009 -364.685831)
			(xy 107.971572 -364.691931) (xy 107.915838 -364.689894) (xy 107.860995 -364.679764) (xy 107.808211 -364.661757)
			(xy 107.758611 -364.636256) (xy 107.713253 -364.603805) (xy 107.673104 -364.565096) (xy 107.639018 -364.520953)
			(xy 107.611722 -364.472318) (xy 107.591799 -364.420227) (xy 107.579673 -364.36579) (xy 107.575602 -364.310168)
			(xy 106.869398 -364.310168) (xy 106.875587 -364.330738) (xy 106.883707 -364.385914) (xy 106.884216 -364.4138)
			(xy 106.883707 -364.441686) (xy 106.875587 -364.496862) (xy 106.859519 -364.550269) (xy 106.835847 -364.600766)
			(xy 106.805074 -364.647279) (xy 106.767857 -364.688816) (xy 106.724989 -364.724491) (xy 106.677383 -364.753545)
			(xy 106.626054 -364.775357) (xy 106.572097 -364.789463) (xy 106.51666 -364.795563) (xy 106.460926 -364.793526)
			(xy 106.406083 -364.783396) (xy 106.353299 -364.765389) (xy 106.303699 -364.739888) (xy 106.258341 -364.707437)
			(xy 106.218192 -364.668728) (xy 106.184106 -364.624585) (xy 106.15681 -364.57595) (xy 106.136887 -364.523859)
			(xy 106.124761 -364.469422) (xy 106.12069 -364.4138) (xy 104.982518 -364.4138) (xy 105.708958 -365.14024)
			(xy 106.985814 -365.14024) (xy 106.989885 -365.084618) (xy 107.002011 -365.030181) (xy 107.021934 -364.97809)
			(xy 107.04923 -364.929455) (xy 107.083316 -364.885312) (xy 107.123465 -364.846603) (xy 107.168823 -364.814152)
			(xy 107.218423 -364.788651) (xy 107.271207 -364.770644) (xy 107.32605 -364.760514) (xy 107.381784 -364.758477)
			(xy 107.437221 -364.764577) (xy 107.491178 -364.778683) (xy 107.542507 -364.800495) (xy 107.590113 -364.829549)
			(xy 107.632981 -364.865224) (xy 107.670198 -364.906761) (xy 107.700971 -364.953274) (xy 107.724643 -365.003771)
			(xy 107.740711 -365.057178) (xy 107.748831 -365.112354) (xy 107.74934 -365.14024) (xy 107.748831 -365.168126)
			(xy 107.740711 -365.223302) (xy 107.724643 -365.276709) (xy 107.700971 -365.327206) (xy 107.670198 -365.373719)
			(xy 107.632981 -365.415256) (xy 107.590113 -365.450931) (xy 107.542507 -365.479985) (xy 107.491178 -365.501797)
			(xy 107.437221 -365.515903) (xy 107.381784 -365.522003) (xy 107.32605 -365.519966) (xy 107.271207 -365.509836)
			(xy 107.218423 -365.491829) (xy 107.168823 -365.466328) (xy 107.123465 -365.433877) (xy 107.083316 -365.395168)
			(xy 107.04923 -365.351025) (xy 107.021934 -365.30239) (xy 107.002011 -365.250299) (xy 106.989885 -365.195862)
			(xy 106.985814 -365.14024) (xy 105.708958 -365.14024) (xy 105.841038 -365.27232) (xy 105.858282 -365.290411)
			(xy 105.88602 -365.331976) (xy 105.905121 -365.378152) (xy 105.914854 -365.427166) (xy 105.91546 -365.452152)
			(xy 105.91546 -365.86033) (xy 105.960672 -365.865664) (xy 105.988259 -365.869291) (xy 106.042052 -365.883511)
			(xy 106.093209 -365.905394) (xy 106.140643 -365.934478) (xy 106.183349 -365.970145) (xy 106.220419 -366.011638)
			(xy 106.251069 -366.058076) (xy 106.274646 -366.108474) (xy 106.290651 -366.161763) (xy 106.298745 -366.216812)
			(xy 106.299254 -366.244632) (xy 106.298752 -366.271882) (xy 106.290992 -366.325827) (xy 106.275636 -366.378118)
			(xy 106.252994 -366.427693) (xy 106.223529 -366.473541) (xy 106.187839 -366.514729) (xy 106.146652 -366.55042)
			(xy 106.100805 -366.579887) (xy 106.051231 -366.602531) (xy 105.99894 -366.617889) (xy 105.944996 -366.625651)
			(xy 105.917746 -366.62614) (xy 105.891367 -366.625691) (xy 105.839111 -366.618432) (xy 105.788352 -366.604046)
			(xy 105.740058 -366.582807) (xy 105.695148 -366.55512) (xy 105.65448 -366.521513) (xy 105.618826 -366.482625)
			(xy 105.588868 -366.439197) (xy 105.576624 -366.415828) (xy 105.569922 -366.403469) (xy 105.550947 -366.382741)
			(xy 105.527033 -366.367979) (xy 105.499997 -366.360307) (xy 105.471895 -366.360307) (xy 105.444859 -366.367979)
			(xy 105.420945 -366.382741) (xy 105.40197 -366.403469) (xy 105.395268 -366.415828) (xy 105.383003 -366.439186)
			(xy 105.353043 -366.482608) (xy 105.317391 -366.521493) (xy 105.276725 -366.555099) (xy 105.231819 -366.582787)
			(xy 105.18353 -366.60403) (xy 105.132776 -366.618423) (xy 105.080524 -366.625692) (xy 105.054146 -366.62614)
			(xy 105.026896 -366.625602) (xy 104.972949 -366.617852) (xy 104.920655 -366.602504) (xy 104.871077 -366.579869)
			(xy 104.825225 -366.550409) (xy 104.784033 -366.514723) (xy 104.748338 -366.473538) (xy 104.718869 -366.427692)
			(xy 104.696224 -366.378119) (xy 104.680864 -366.325827) (xy 104.673104 -366.271882) (xy 104.672638 -366.244632)
			(xy 104.673087 -366.218163) (xy 104.680377 -366.165729) (xy 104.694849 -366.114808) (xy 104.716226 -366.066378)
			(xy 104.744095 -366.02137) (xy 104.777922 -365.98065) (xy 104.817056 -365.944999) (xy 104.860745 -365.915104)
			(xy 104.908148 -365.891539) (xy 104.958356 -365.874757) (xy 104.984296 -365.869474) (xy 105.025952 -365.861854)
			(xy 105.025952 -365.71555) (xy 104.539288 -365.22914) (xy 102.802944 -365.22914) (xy 102.777949 -365.228488)
			(xy 102.728926 -365.21869) (xy 102.682755 -365.199522) (xy 102.641208 -365.171718) (xy 102.623112 -365.154464)
			(xy 100.602034 -363.133386) (xy 100.584789 -363.115297) (xy 100.557052 -363.07373) (xy 100.537951 -363.027554)
			(xy 100.528219 -362.97854) (xy 100.527612 -362.953554) (xy 100.527612 -353.859338) (xy 100.528215 -353.834354)
			(xy 100.537963 -353.785346) (xy 100.557073 -353.739177) (xy 100.584813 -353.697617) (xy 100.602034 -353.679506)
			(xy 101.89464 -352.3869) (xy 101.912725 -352.369632) (xy 101.954274 -352.341824) (xy 102.000448 -352.322654)
			(xy 102.049475 -352.312859) (xy 102.074472 -352.312224) (xy 104.904032 -352.312224) (xy 104.91908 -352.311599)
			(xy 104.94786 -352.302788) (xy 104.972822 -352.285972) (xy 104.991799 -352.262609) (xy 105.003142 -352.23473)
			(xy 105.005866 -352.204755) (xy 104.999735 -352.175288) (xy 104.98528 -352.148888) (xy 104.974898 -352.13798)
			(xy 104.956944 -352.119926) (xy 104.925447 -352.079924) (xy 104.899548 -352.036088) (xy 104.879708 -351.989198)
			(xy 104.86628 -351.940086) (xy 104.859501 -351.889625) (xy 104.859074 -351.864168) (xy 104.85956 -351.836917)
			(xy 104.867316 -351.782969) (xy 104.882671 -351.730674) (xy 104.905313 -351.681097) (xy 104.934779 -351.635247)
			(xy 104.97047 -351.594056) (xy 105.011661 -351.558365) (xy 105.057511 -351.528899) (xy 105.107088 -351.506257)
			(xy 105.159383 -351.490902) (xy 105.213331 -351.483146) (xy 105.267833 -351.483146) (xy 105.321781 -351.490902)
			(xy 105.355995 -351.500948) (xy 105.871262 -351.500948) (xy 105.875333 -351.445326) (xy 105.887459 -351.390889)
			(xy 105.907382 -351.338798) (xy 105.934678 -351.290163) (xy 105.968764 -351.24602) (xy 106.008913 -351.207311)
			(xy 106.054271 -351.17486) (xy 106.103871 -351.149359) (xy 106.156655 -351.131352) (xy 106.211498 -351.121222)
			(xy 106.267232 -351.119185) (xy 106.322669 -351.125285) (xy 106.376626 -351.139391) (xy 106.427955 -351.161203)
			(xy 106.475561 -351.190257) (xy 106.518429 -351.225932) (xy 106.555646 -351.267469) (xy 106.586419 -351.313982)
			(xy 106.610091 -351.364479) (xy 106.626159 -351.417886) (xy 106.634279 -351.473062) (xy 106.634788 -351.500948)
			(xy 106.887262 -351.500948) (xy 106.891333 -351.445326) (xy 106.903459 -351.390889) (xy 106.923382 -351.338798)
			(xy 106.950678 -351.290163) (xy 106.984764 -351.24602) (xy 107.024913 -351.207311) (xy 107.070271 -351.17486)
			(xy 107.119871 -351.149359) (xy 107.172655 -351.131352) (xy 107.227498 -351.121222) (xy 107.283232 -351.119185)
			(xy 107.338669 -351.125285) (xy 107.392626 -351.139391) (xy 107.443955 -351.161203) (xy 107.491561 -351.190257)
			(xy 107.534429 -351.225932) (xy 107.571646 -351.267469) (xy 107.602419 -351.313982) (xy 107.626091 -351.364479)
			(xy 107.642159 -351.417886) (xy 107.650279 -351.473062) (xy 107.650788 -351.500948) (xy 107.903262 -351.500948)
			(xy 107.907333 -351.445326) (xy 107.919459 -351.390889) (xy 107.939382 -351.338798) (xy 107.966678 -351.290163)
			(xy 108.000764 -351.24602) (xy 108.040913 -351.207311) (xy 108.086271 -351.17486) (xy 108.135871 -351.149359)
			(xy 108.188655 -351.131352) (xy 108.243498 -351.121222) (xy 108.299232 -351.119185) (xy 108.354669 -351.125285)
			(xy 108.408626 -351.139391) (xy 108.459955 -351.161203) (xy 108.507561 -351.190257) (xy 108.550429 -351.225932)
			(xy 108.587646 -351.267469) (xy 108.618419 -351.313982) (xy 108.642091 -351.364479) (xy 108.658159 -351.417886)
			(xy 108.666279 -351.473062) (xy 108.666788 -351.500948) (xy 108.919262 -351.500948) (xy 108.923333 -351.445326)
			(xy 108.935459 -351.390889) (xy 108.955382 -351.338798) (xy 108.982678 -351.290163) (xy 109.016764 -351.24602)
			(xy 109.056913 -351.207311) (xy 109.102271 -351.17486) (xy 109.151871 -351.149359) (xy 109.204655 -351.131352)
			(xy 109.259498 -351.121222) (xy 109.315232 -351.119185) (xy 109.370669 -351.125285) (xy 109.424626 -351.139391)
			(xy 109.475955 -351.161203) (xy 109.523561 -351.190257) (xy 109.566429 -351.225932) (xy 109.603646 -351.267469)
			(xy 109.634419 -351.313982) (xy 109.658091 -351.364479) (xy 109.674159 -351.417886) (xy 109.680028 -351.457768)
			(xy 111.131602 -351.457768) (xy 111.135673 -351.402146) (xy 111.147799 -351.347709) (xy 111.167722 -351.295618)
			(xy 111.195018 -351.246983) (xy 111.229104 -351.20284) (xy 111.269253 -351.164131) (xy 111.314611 -351.13168)
			(xy 111.364211 -351.106179) (xy 111.416995 -351.088172) (xy 111.471838 -351.078042) (xy 111.527572 -351.076005)
			(xy 111.583009 -351.082105) (xy 111.636966 -351.096211) (xy 111.688295 -351.118023) (xy 111.735901 -351.147077)
			(xy 111.778769 -351.182752) (xy 111.815986 -351.224289) (xy 111.846759 -351.270802) (xy 111.870431 -351.321299)
			(xy 111.886499 -351.374706) (xy 111.894619 -351.429882) (xy 111.895128 -351.457768) (xy 111.894619 -351.485654)
			(xy 111.886499 -351.54083) (xy 111.870431 -351.594237) (xy 111.846759 -351.644734) (xy 111.815986 -351.691247)
			(xy 111.778769 -351.732784) (xy 111.735901 -351.768459) (xy 111.688295 -351.797513) (xy 111.636966 -351.819325)
			(xy 111.583009 -351.833431) (xy 111.527572 -351.839531) (xy 111.471838 -351.837494) (xy 111.416995 -351.827364)
			(xy 111.364211 -351.809357) (xy 111.314611 -351.783856) (xy 111.269253 -351.751405) (xy 111.229104 -351.712696)
			(xy 111.195018 -351.668553) (xy 111.167722 -351.619918) (xy 111.147799 -351.567827) (xy 111.135673 -351.51339)
			(xy 111.131602 -351.457768) (xy 109.680028 -351.457768) (xy 109.682279 -351.473062) (xy 109.682788 -351.500948)
			(xy 109.682279 -351.528834) (xy 109.674159 -351.58401) (xy 109.658091 -351.637417) (xy 109.634419 -351.687914)
			(xy 109.603646 -351.734427) (xy 109.566429 -351.775964) (xy 109.523561 -351.811639) (xy 109.475955 -351.840693)
			(xy 109.424626 -351.862505) (xy 109.370669 -351.876611) (xy 109.315232 -351.882711) (xy 109.259498 -351.880674)
			(xy 109.204655 -351.870544) (xy 109.151871 -351.852537) (xy 109.102271 -351.827036) (xy 109.056913 -351.794585)
			(xy 109.016764 -351.755876) (xy 108.982678 -351.711733) (xy 108.955382 -351.663098) (xy 108.935459 -351.611007)
			(xy 108.923333 -351.55657) (xy 108.919262 -351.500948) (xy 108.666788 -351.500948) (xy 108.666279 -351.528834)
			(xy 108.658159 -351.58401) (xy 108.642091 -351.637417) (xy 108.618419 -351.687914) (xy 108.587646 -351.734427)
			(xy 108.550429 -351.775964) (xy 108.507561 -351.811639) (xy 108.459955 -351.840693) (xy 108.408626 -351.862505)
			(xy 108.354669 -351.876611) (xy 108.299232 -351.882711) (xy 108.243498 -351.880674) (xy 108.188655 -351.870544)
			(xy 108.135871 -351.852537) (xy 108.086271 -351.827036) (xy 108.040913 -351.794585) (xy 108.000764 -351.755876)
			(xy 107.966678 -351.711733) (xy 107.939382 -351.663098) (xy 107.919459 -351.611007) (xy 107.907333 -351.55657)
			(xy 107.903262 -351.500948) (xy 107.650788 -351.500948) (xy 107.650279 -351.528834) (xy 107.642159 -351.58401)
			(xy 107.626091 -351.637417) (xy 107.602419 -351.687914) (xy 107.571646 -351.734427) (xy 107.534429 -351.775964)
			(xy 107.491561 -351.811639) (xy 107.443955 -351.840693) (xy 107.392626 -351.862505) (xy 107.338669 -351.876611)
			(xy 107.283232 -351.882711) (xy 107.227498 -351.880674) (xy 107.172655 -351.870544) (xy 107.119871 -351.852537)
			(xy 107.070271 -351.827036) (xy 107.024913 -351.794585) (xy 106.984764 -351.755876) (xy 106.950678 -351.711733)
			(xy 106.923382 -351.663098) (xy 106.903459 -351.611007) (xy 106.891333 -351.55657) (xy 106.887262 -351.500948)
			(xy 106.634788 -351.500948) (xy 106.634279 -351.528834) (xy 106.626159 -351.58401) (xy 106.610091 -351.637417)
			(xy 106.586419 -351.687914) (xy 106.555646 -351.734427) (xy 106.518429 -351.775964) (xy 106.475561 -351.811639)
			(xy 106.427955 -351.840693) (xy 106.376626 -351.862505) (xy 106.322669 -351.876611) (xy 106.267232 -351.882711)
			(xy 106.211498 -351.880674) (xy 106.156655 -351.870544) (xy 106.103871 -351.852537) (xy 106.054271 -351.827036)
			(xy 106.008913 -351.794585) (xy 105.968764 -351.755876) (xy 105.934678 -351.711733) (xy 105.907382 -351.663098)
			(xy 105.887459 -351.611007) (xy 105.875333 -351.55657) (xy 105.871262 -351.500948) (xy 105.355995 -351.500948)
			(xy 105.374076 -351.506257) (xy 105.423653 -351.528899) (xy 105.469503 -351.558365) (xy 105.510694 -351.594056)
			(xy 105.546385 -351.635247) (xy 105.575851 -351.681097) (xy 105.598493 -351.730674) (xy 105.613848 -351.782969)
			(xy 105.621604 -351.836917) (xy 105.62209 -351.864168) (xy 105.621699 -351.889628) (xy 105.614928 -351.940096)
			(xy 105.601502 -351.989215) (xy 105.58166 -352.03611) (xy 105.555755 -352.079948) (xy 105.524247 -352.11995)
			(xy 105.506266 -352.13798) (xy 105.495849 -352.148877) (xy 105.481341 -352.175286) (xy 105.475174 -352.20478)
			(xy 105.477885 -352.234789) (xy 105.489237 -352.2627) (xy 105.508242 -352.286082) (xy 105.533244 -352.302898)
			(xy 105.562066 -352.311685) (xy 105.577132 -352.312224) (xy 107.834938 -352.312224) (xy 107.859932 -352.312897)
			(xy 107.908953 -352.32269) (xy 107.955124 -352.341853) (xy 107.996672 -352.36965) (xy 108.01477 -352.3869)
			(xy 109.261656 -353.633532) (xy 109.344968 -353.633532) (xy 109.344968 -353.040696) (xy 110.39729 -351.98812)
			(xy 115.03025 -351.98812) (xy 115.354608 -352.312478) (xy 115.354608 -356.941628) (xy 115.355111 -356.951605)
			(xy 115.362808 -356.970019) (xy 115.376949 -356.984104) (xy 115.395393 -356.991729) (xy 115.415352 -356.991739)
			(xy 115.433805 -356.984135) (xy 115.441222 -356.977442) (xy 115.480592 -356.937818) (xy 115.480592 -352.9965)
			(xy 115.481208 -352.971503) (xy 115.491015 -352.922478) (xy 115.510195 -352.876307) (xy 115.538009 -352.834762)
			(xy 115.555268 -352.816668) (xy 116.39042 -351.981516) (xy 116.408516 -351.96426) (xy 116.45006 -351.936449)
			(xy 116.496232 -351.917276) (xy 116.545256 -351.907477) (xy 116.570252 -351.90684) (xy 122.781314 -351.90684)
			(xy 125.194314 -349.494094) (xy 125.212412 -349.476859) (xy 125.253975 -349.449118) (xy 125.300148 -349.430013)
			(xy 125.349161 -349.420279) (xy 125.374146 -349.419672) (xy 134.506462 -349.419672) (xy 136.219438 -348.709996)
			(xy 136.584944 -348.34449) (xy 136.584944 -347.134688) (xy 136.565291 -347.116544) (xy 136.530792 -347.075669)
			(xy 136.502338 -347.030378) (xy 136.480485 -346.981558) (xy 136.465661 -346.930165) (xy 136.458158 -346.877206)
			(xy 136.45769 -346.850462) (xy 136.458137 -346.823717) (xy 136.465632 -346.770754) (xy 136.480455 -346.719359)
			(xy 136.502314 -346.670539) (xy 136.530782 -346.625254) (xy 136.5653 -346.584391) (xy 136.584944 -346.566236)
			(xy 136.584944 -346.537788) (xy 135.348472 -345.301316) (xy 130.27025 -345.301316) (xy 130.245265 -345.300726)
			(xy 130.196256 -345.290978) (xy 130.150086 -345.271864) (xy 130.108527 -345.244119) (xy 130.090418 -345.226894)
			(xy 128.498854 -343.63533) (xy 128.481633 -343.617219) (xy 128.453891 -343.57566) (xy 128.434783 -343.529491)
			(xy 128.425043 -343.480482) (xy 128.424432 -343.455498) (xy 128.424432 -343.2683) (xy 128.423836 -343.253321)
			(xy 128.415089 -343.224667) (xy 128.398407 -343.199781) (xy 128.375223 -343.180805) (xy 128.347531 -343.169369)
			(xy 128.317713 -343.166457) (xy 128.288333 -343.17232) (xy 128.261916 -343.186453) (xy 128.25095 -343.196672)
			(xy 127.737362 -343.710006) (xy 127.719232 -343.727206) (xy 127.67768 -343.754953) (xy 127.631517 -343.774067)
			(xy 127.582512 -343.783814) (xy 127.55753 -343.784428) (xy 125.78842 -343.784428) (xy 125.763438 -343.783792)
			(xy 125.71443 -343.774057) (xy 125.668261 -343.754957) (xy 125.626699 -343.727225) (xy 125.608588 -343.710006)
			(xy 123.034044 -341.135716) (xy 122.211338 -341.135716) (xy 122.186342 -341.135074) (xy 122.137319 -341.125274)
			(xy 122.091148 -341.106103) (xy 122.049602 -341.078295) (xy 122.031506 -341.06104) (xy 120.459754 -339.489288)
			(xy 120.449757 -339.479866) (xy 120.425841 -339.466361) (xy 120.399193 -339.459712) (xy 120.371737 -339.460399)
			(xy 120.345455 -339.468374) (xy 120.322245 -339.483059) (xy 120.303784 -339.503394) (xy 120.297194 -339.51545)
			(xy 120.287704 -339.533274) (xy 120.263971 -339.565942) (xy 120.24995 -339.580474) (xy 119.506492 -340.323932)
			(xy 119.488383 -340.341174) (xy 119.446844 -340.368989) (xy 119.400677 -340.388167) (xy 119.351655 -340.39797)
			(xy 119.32666 -340.398608) (xy 113.313718 -340.398608) (xy 113.288721 -340.397981) (xy 113.239697 -340.388177)
			(xy 113.193526 -340.369001) (xy 113.151981 -340.34119) (xy 113.133886 -340.323932) (xy 112.188498 -339.378544)
			(xy 112.14989 -339.417406) (xy 112.14735 -339.420454) (xy 112.141505 -339.428301) (xy 112.128791 -339.443177)
			(xy 112.12195 -339.450172) (xy 111.261652 -340.31047) (xy 111.243536 -340.327685) (xy 111.201978 -340.355427)
			(xy 111.15581 -340.374536) (xy 111.106803 -340.384279) (xy 111.08182 -340.384892) (xy 105.139744 -340.384892)
			(xy 105.11476 -340.384284) (xy 105.065753 -340.374538) (xy 105.019584 -340.355429) (xy 104.978023 -340.327691)
			(xy 104.959912 -340.31047) (xy 104.156256 -339.506814) (xy 104.145724 -339.496943) (xy 104.120429 -339.483059)
			(xy 104.092258 -339.476815) (xy 104.063466 -339.478713) (xy 104.036358 -339.488598) (xy 104.013104 -339.505681)
			(xy 103.995565 -339.528594) (xy 103.989886 -339.541866) (xy 103.979685 -339.566073) (xy 103.950871 -339.609984)
			(xy 103.932736 -339.628988) (xy 103.251508 -340.310216) (xy 103.233405 -340.327464) (xy 103.191862 -340.355275)
			(xy 103.145694 -340.37445) (xy 103.096672 -340.384253) (xy 103.071676 -340.384892) (xy 96.978978 -340.384892)
			(xy 96.953982 -340.384265) (xy 96.904959 -340.374457) (xy 96.858789 -340.355281) (xy 96.817242 -340.327472)
			(xy 96.799146 -340.310216) (xy 96.03232 -339.543644) (xy 96.021349 -339.533462) (xy 95.994957 -339.519374)
			(xy 95.965614 -339.513541) (xy 95.935841 -339.516466) (xy 95.908194 -339.527897) (xy 95.885048 -339.546852)
			(xy 95.868391 -339.571702) (xy 95.859654 -339.600315) (xy 95.859092 -339.615272) (xy 95.859092 -340.571328)
			(xy 95.858469 -340.596325) (xy 95.84866 -340.645348) (xy 95.829482 -340.691518) (xy 95.801672 -340.733064)
			(xy 95.784416 -340.75116) (xy 93.114876 -343.4207) (xy 93.096784 -343.43796) (xy 93.055238 -343.46577)
			(xy 93.009066 -343.484942) (xy 92.960041 -343.49474) (xy 92.935044 -343.495376) (xy 88.6333 -343.495376)
			(xy 88.608304 -343.49474) (xy 88.559281 -343.484936) (xy 88.513111 -343.465762) (xy 88.471564 -343.437955)
			(xy 88.453468 -343.4207) (xy 87.80272 -342.769952) (xy 87.795361 -342.763114) (xy 87.77683 -342.755392)
			(xy 87.756754 -342.755355) (xy 87.738194 -342.76301) (xy 87.723981 -342.777188) (xy 87.71628 -342.795728)
			(xy 87.715852 -342.805766) (xy 87.715852 -342.885776) (xy 87.715268 -342.910761) (xy 87.705516 -342.95977)
			(xy 87.6864 -343.00594) (xy 87.658655 -343.047499) (xy 87.64143 -343.065608) (xy 86.81212 -343.894918)
			(xy 86.81212 -344.071632) (xy 96.449892 -344.071632) (xy 96.449892 -343.986936) (xy 96.457943 -343.902622)
			(xy 96.473972 -343.819456) (xy 96.497833 -343.738189) (xy 96.529312 -343.659559) (xy 96.568123 -343.584278)
			(xy 96.613913 -343.513026) (xy 96.666269 -343.44645) (xy 96.724717 -343.385152) (xy 96.788727 -343.329687)
			(xy 96.857719 -343.280558) (xy 96.931069 -343.238209) (xy 97.008112 -343.203025) (xy 97.088151 -343.175323)
			(xy 97.17046 -343.155355) (xy 97.254295 -343.143302) (xy 97.338896 -343.139272) (xy 97.423497 -343.143302)
			(xy 97.507332 -343.155355) (xy 97.589641 -343.175323) (xy 97.66968 -343.203025) (xy 97.746723 -343.238209)
			(xy 97.820073 -343.280558) (xy 97.889065 -343.329687) (xy 97.953075 -343.385152) (xy 98.011523 -343.44645)
			(xy 98.063879 -343.513026) (xy 98.109669 -343.584278) (xy 98.14848 -343.659559) (xy 98.179959 -343.738189)
			(xy 98.20382 -343.819456) (xy 98.219849 -343.902622) (xy 98.2279 -343.986936) (xy 98.228404 -344.029284)
			(xy 98.974405 -344.029284) (xy 98.978441 -343.945837) (xy 98.990513 -343.863169) (xy 99.010506 -343.782052)
			(xy 99.038235 -343.703243) (xy 99.073441 -343.627478) (xy 99.115795 -343.555465) (xy 99.164901 -343.487876)
			(xy 99.220302 -343.425342) (xy 99.281479 -343.368447) (xy 99.347862 -343.317721) (xy 99.41883 -343.27364)
			(xy 99.493722 -343.236614) (xy 99.571838 -343.206988) (xy 99.652448 -343.18504) (xy 99.7348 -343.170975)
			(xy 99.818126 -343.164923) (xy 99.901646 -343.166942) (xy 99.984582 -343.177012) (xy 100.066158 -343.19504)
			(xy 100.145614 -343.220857) (xy 100.222207 -343.254222) (xy 100.295223 -343.294823) (xy 100.363979 -343.342282)
			(xy 100.427833 -343.396155) (xy 100.48619 -343.45594) (xy 100.538505 -343.521077) (xy 100.584288 -343.59096)
			(xy 100.623113 -343.664935) (xy 100.654618 -343.742312) (xy 100.678507 -343.822369) (xy 100.694558 -343.904357)
			(xy 100.702621 -343.987512) (xy 100.703126 -344.029284) (xy 100.702621 -344.071056) (xy 100.702565 -344.071632)
			(xy 104.010456 -344.071632) (xy 104.010456 -343.986936) (xy 104.018507 -343.902622) (xy 104.034536 -343.819456)
			(xy 104.058397 -343.738189) (xy 104.089876 -343.659559) (xy 104.128687 -343.584278) (xy 104.174477 -343.513026)
			(xy 104.226833 -343.44645) (xy 104.285281 -343.385152) (xy 104.349291 -343.329687) (xy 104.418283 -343.280558)
			(xy 104.491633 -343.238209) (xy 104.568676 -343.203025) (xy 104.648715 -343.175323) (xy 104.731024 -343.155355)
			(xy 104.814859 -343.143302) (xy 104.89946 -343.139272) (xy 104.984061 -343.143302) (xy 105.067896 -343.155355)
			(xy 105.150205 -343.175323) (xy 105.230244 -343.203025) (xy 105.307287 -343.238209) (xy 105.380637 -343.280558)
			(xy 105.449629 -343.329687) (xy 105.513639 -343.385152) (xy 105.572087 -343.44645) (xy 105.624443 -343.513026)
			(xy 105.670233 -343.584278) (xy 105.709044 -343.659559) (xy 105.740523 -343.738189) (xy 105.764384 -343.819456)
			(xy 105.780413 -343.902622) (xy 105.788464 -343.986936) (xy 105.788968 -344.029284) (xy 106.534969 -344.029284)
			(xy 106.539005 -343.945837) (xy 106.551077 -343.863169) (xy 106.57107 -343.782052) (xy 106.598799 -343.703243)
			(xy 106.634005 -343.627478) (xy 106.676359 -343.555465) (xy 106.725465 -343.487876) (xy 106.780866 -343.425342)
			(xy 106.842043 -343.368447) (xy 106.908426 -343.317721) (xy 106.979394 -343.27364) (xy 107.054286 -343.236614)
			(xy 107.132402 -343.206988) (xy 107.213012 -343.18504) (xy 107.295364 -343.170975) (xy 107.37869 -343.164923)
			(xy 107.46221 -343.166942) (xy 107.545146 -343.177012) (xy 107.626722 -343.19504) (xy 107.706178 -343.220857)
			(xy 107.782771 -343.254222) (xy 107.855787 -343.294823) (xy 107.924543 -343.342282) (xy 107.988397 -343.396155)
			(xy 108.046754 -343.45594) (xy 108.099069 -343.521077) (xy 108.144852 -343.59096) (xy 108.183677 -343.664935)
			(xy 108.215182 -343.742312) (xy 108.239071 -343.822369) (xy 108.255122 -343.904357) (xy 108.263185 -343.987512)
			(xy 108.26369 -344.029284) (xy 108.263185 -344.071056) (xy 108.263129 -344.071632) (xy 111.7158 -344.071632)
			(xy 111.7158 -343.986936) (xy 111.723851 -343.902622) (xy 111.73988 -343.819456) (xy 111.763741 -343.738189)
			(xy 111.79522 -343.659559) (xy 111.834031 -343.584278) (xy 111.879821 -343.513026) (xy 111.932177 -343.44645)
			(xy 111.990625 -343.385152) (xy 112.054635 -343.329687) (xy 112.123627 -343.280558) (xy 112.196977 -343.238209)
			(xy 112.27402 -343.203025) (xy 112.354059 -343.175323) (xy 112.436368 -343.155355) (xy 112.520203 -343.143302)
			(xy 112.604804 -343.139272) (xy 112.689405 -343.143302) (xy 112.77324 -343.155355) (xy 112.855549 -343.175323)
			(xy 112.935588 -343.203025) (xy 113.012631 -343.238209) (xy 113.085981 -343.280558) (xy 113.154973 -343.329687)
			(xy 113.218983 -343.385152) (xy 113.277431 -343.44645) (xy 113.329787 -343.513026) (xy 113.375577 -343.584278)
			(xy 113.414388 -343.659559) (xy 113.445867 -343.738189) (xy 113.469728 -343.819456) (xy 113.485757 -343.902622)
			(xy 113.493808 -343.986936) (xy 113.494312 -344.029284) (xy 114.240313 -344.029284) (xy 114.244349 -343.945837)
			(xy 114.256421 -343.863169) (xy 114.276414 -343.782052) (xy 114.304143 -343.703243) (xy 114.339349 -343.627478)
			(xy 114.381703 -343.555465) (xy 114.430809 -343.487876) (xy 114.48621 -343.425342) (xy 114.547387 -343.368447)
			(xy 114.61377 -343.317721) (xy 114.684738 -343.27364) (xy 114.75963 -343.236614) (xy 114.837746 -343.206988)
			(xy 114.918356 -343.18504) (xy 115.000708 -343.170975) (xy 115.084034 -343.164923) (xy 115.167554 -343.166942)
			(xy 115.25049 -343.177012) (xy 115.332066 -343.19504) (xy 115.411522 -343.220857) (xy 115.488115 -343.254222)
			(xy 115.561131 -343.294823) (xy 115.629887 -343.342282) (xy 115.693741 -343.396155) (xy 115.752098 -343.45594)
			(xy 115.804413 -343.521077) (xy 115.850196 -343.59096) (xy 115.889021 -343.664935) (xy 115.920526 -343.742312)
			(xy 115.944415 -343.822369) (xy 115.960466 -343.904357) (xy 115.964765 -343.948696) (xy 119.176796 -343.948696)
			(xy 119.176796 -343.864) (xy 119.184847 -343.779686) (xy 119.200876 -343.69652) (xy 119.224737 -343.615253)
			(xy 119.256216 -343.536623) (xy 119.295027 -343.461342) (xy 119.340817 -343.39009) (xy 119.393173 -343.323514)
			(xy 119.451621 -343.262216) (xy 119.515631 -343.206751) (xy 119.584623 -343.157622) (xy 119.657973 -343.115273)
			(xy 119.735016 -343.080089) (xy 119.815055 -343.052387) (xy 119.897364 -343.032419) (xy 119.981199 -343.020366)
			(xy 120.0658 -343.016336) (xy 120.150401 -343.020366) (xy 120.234236 -343.032419) (xy 120.316545 -343.052387)
			(xy 120.396584 -343.080089) (xy 120.473627 -343.115273) (xy 120.546977 -343.157622) (xy 120.615969 -343.206751)
			(xy 120.679979 -343.262216) (xy 120.738427 -343.323514) (xy 120.790783 -343.39009) (xy 120.836573 -343.461342)
			(xy 120.875384 -343.536623) (xy 120.906863 -343.615253) (xy 120.930724 -343.69652) (xy 120.946753 -343.779686)
			(xy 120.954804 -343.864) (xy 120.955308 -343.906348) (xy 121.701309 -343.906348) (xy 121.705345 -343.822901)
			(xy 121.717417 -343.740233) (xy 121.73741 -343.659116) (xy 121.765139 -343.580307) (xy 121.800345 -343.504542)
			(xy 121.842699 -343.432529) (xy 121.891805 -343.36494) (xy 121.947206 -343.302406) (xy 122.008383 -343.245511)
			(xy 122.074766 -343.194785) (xy 122.145734 -343.150704) (xy 122.220626 -343.113678) (xy 122.298742 -343.084052)
			(xy 122.379352 -343.062104) (xy 122.461704 -343.048039) (xy 122.54503 -343.041987) (xy 122.62855 -343.044006)
			(xy 122.711486 -343.054076) (xy 122.793062 -343.072104) (xy 122.872518 -343.097921) (xy 122.949111 -343.131286)
			(xy 123.022127 -343.171887) (xy 123.090883 -343.219346) (xy 123.154737 -343.273219) (xy 123.213094 -343.333004)
			(xy 123.265409 -343.398141) (xy 123.311192 -343.468024) (xy 123.350017 -343.541999) (xy 123.381522 -343.619376)
			(xy 123.405411 -343.699433) (xy 123.421462 -343.781421) (xy 123.429525 -343.864576) (xy 123.43003 -343.906348)
			(xy 123.429525 -343.94812) (xy 123.421462 -344.031275) (xy 123.405411 -344.113263) (xy 123.381522 -344.19332)
			(xy 123.350017 -344.270697) (xy 123.311192 -344.344672) (xy 123.265409 -344.414555) (xy 123.213094 -344.479692)
			(xy 123.154737 -344.539477) (xy 123.090883 -344.59335) (xy 123.022127 -344.640809) (xy 122.949111 -344.68141)
			(xy 122.872518 -344.714775) (xy 122.793062 -344.740592) (xy 122.711486 -344.75862) (xy 122.62855 -344.76869)
			(xy 122.54503 -344.770709) (xy 122.461704 -344.764657) (xy 122.379352 -344.750592) (xy 122.298742 -344.728644)
			(xy 122.220626 -344.699018) (xy 122.145734 -344.661992) (xy 122.074766 -344.617911) (xy 122.008383 -344.567185)
			(xy 121.947206 -344.51029) (xy 121.891805 -344.447756) (xy 121.842699 -344.380167) (xy 121.800345 -344.308154)
			(xy 121.765139 -344.232389) (xy 121.73741 -344.15358) (xy 121.717417 -344.072463) (xy 121.705345 -343.989795)
			(xy 121.701309 -343.906348) (xy 120.955308 -343.906348) (xy 120.954804 -343.948696) (xy 120.946753 -344.03301)
			(xy 120.930724 -344.116176) (xy 120.906863 -344.197443) (xy 120.875384 -344.276073) (xy 120.836573 -344.351354)
			(xy 120.790783 -344.422606) (xy 120.738427 -344.489182) (xy 120.679979 -344.55048) (xy 120.615969 -344.605945)
			(xy 120.546977 -344.655074) (xy 120.473627 -344.697423) (xy 120.396584 -344.732607) (xy 120.316545 -344.760309)
			(xy 120.234236 -344.780277) (xy 120.150401 -344.79233) (xy 120.0658 -344.796361) (xy 119.981199 -344.79233)
			(xy 119.897364 -344.780277) (xy 119.815055 -344.760309) (xy 119.735016 -344.732607) (xy 119.657973 -344.697423)
			(xy 119.584623 -344.655074) (xy 119.515631 -344.605945) (xy 119.451621 -344.55048) (xy 119.393173 -344.489182)
			(xy 119.340817 -344.422606) (xy 119.295027 -344.351354) (xy 119.256216 -344.276073) (xy 119.224737 -344.197443)
			(xy 119.200876 -344.116176) (xy 119.184847 -344.03301) (xy 119.176796 -343.948696) (xy 115.964765 -343.948696)
			(xy 115.968529 -343.987512) (xy 115.969034 -344.029284) (xy 115.968529 -344.071056) (xy 115.960466 -344.154211)
			(xy 115.944415 -344.236199) (xy 115.920526 -344.316256) (xy 115.889021 -344.393633) (xy 115.850196 -344.467608)
			(xy 115.804413 -344.537491) (xy 115.752098 -344.602628) (xy 115.693741 -344.662413) (xy 115.629887 -344.716286)
			(xy 115.561131 -344.763745) (xy 115.488115 -344.804346) (xy 115.411522 -344.837711) (xy 115.332066 -344.863528)
			(xy 115.25049 -344.881556) (xy 115.167554 -344.891626) (xy 115.084034 -344.893645) (xy 115.000708 -344.887593)
			(xy 114.918356 -344.873528) (xy 114.837746 -344.85158) (xy 114.75963 -344.821954) (xy 114.684738 -344.784928)
			(xy 114.61377 -344.740847) (xy 114.547387 -344.690121) (xy 114.48621 -344.633226) (xy 114.430809 -344.570692)
			(xy 114.381703 -344.503103) (xy 114.339349 -344.43109) (xy 114.304143 -344.355325) (xy 114.276414 -344.276516)
			(xy 114.256421 -344.195399) (xy 114.244349 -344.112731) (xy 114.240313 -344.029284) (xy 113.494312 -344.029284)
			(xy 113.493808 -344.071632) (xy 113.485757 -344.155946) (xy 113.469728 -344.239112) (xy 113.445867 -344.320379)
			(xy 113.414388 -344.399009) (xy 113.375577 -344.47429) (xy 113.329787 -344.545542) (xy 113.277431 -344.612118)
			(xy 113.218983 -344.673416) (xy 113.154973 -344.728881) (xy 113.085981 -344.77801) (xy 113.012631 -344.820359)
			(xy 112.935588 -344.855543) (xy 112.855549 -344.883245) (xy 112.77324 -344.903213) (xy 112.689405 -344.915266)
			(xy 112.604804 -344.919297) (xy 112.520203 -344.915266) (xy 112.436368 -344.903213) (xy 112.354059 -344.883245)
			(xy 112.27402 -344.855543) (xy 112.196977 -344.820359) (xy 112.123627 -344.77801) (xy 112.054635 -344.728881)
			(xy 111.990625 -344.673416) (xy 111.932177 -344.612118) (xy 111.879821 -344.545542) (xy 111.834031 -344.47429)
			(xy 111.79522 -344.399009) (xy 111.763741 -344.320379) (xy 111.73988 -344.239112) (xy 111.723851 -344.155946)
			(xy 111.7158 -344.071632) (xy 108.263129 -344.071632) (xy 108.255122 -344.154211) (xy 108.239071 -344.236199)
			(xy 108.215182 -344.316256) (xy 108.183677 -344.393633) (xy 108.144852 -344.467608) (xy 108.099069 -344.537491)
			(xy 108.046754 -344.602628) (xy 107.988397 -344.662413) (xy 107.924543 -344.716286) (xy 107.855787 -344.763745)
			(xy 107.782771 -344.804346) (xy 107.706178 -344.837711) (xy 107.626722 -344.863528) (xy 107.545146 -344.881556)
			(xy 107.46221 -344.891626) (xy 107.37869 -344.893645) (xy 107.295364 -344.887593) (xy 107.213012 -344.873528)
			(xy 107.132402 -344.85158) (xy 107.054286 -344.821954) (xy 106.979394 -344.784928) (xy 106.908426 -344.740847)
			(xy 106.842043 -344.690121) (xy 106.780866 -344.633226) (xy 106.725465 -344.570692) (xy 106.676359 -344.503103)
			(xy 106.634005 -344.43109) (xy 106.598799 -344.355325) (xy 106.57107 -344.276516) (xy 106.551077 -344.195399)
			(xy 106.539005 -344.112731) (xy 106.534969 -344.029284) (xy 105.788968 -344.029284) (xy 105.788464 -344.071632)
			(xy 105.780413 -344.155946) (xy 105.764384 -344.239112) (xy 105.740523 -344.320379) (xy 105.709044 -344.399009)
			(xy 105.670233 -344.47429) (xy 105.624443 -344.545542) (xy 105.572087 -344.612118) (xy 105.513639 -344.673416)
			(xy 105.449629 -344.728881) (xy 105.380637 -344.77801) (xy 105.307287 -344.820359) (xy 105.230244 -344.855543)
			(xy 105.150205 -344.883245) (xy 105.067896 -344.903213) (xy 104.984061 -344.915266) (xy 104.89946 -344.919297)
			(xy 104.814859 -344.915266) (xy 104.731024 -344.903213) (xy 104.648715 -344.883245) (xy 104.568676 -344.855543)
			(xy 104.491633 -344.820359) (xy 104.418283 -344.77801) (xy 104.349291 -344.728881) (xy 104.285281 -344.673416)
			(xy 104.226833 -344.612118) (xy 104.174477 -344.545542) (xy 104.128687 -344.47429) (xy 104.089876 -344.399009)
			(xy 104.058397 -344.320379) (xy 104.034536 -344.239112) (xy 104.018507 -344.155946) (xy 104.010456 -344.071632)
			(xy 100.702565 -344.071632) (xy 100.694558 -344.154211) (xy 100.678507 -344.236199) (xy 100.654618 -344.316256)
			(xy 100.623113 -344.393633) (xy 100.584288 -344.467608) (xy 100.538505 -344.537491) (xy 100.48619 -344.602628)
			(xy 100.427833 -344.662413) (xy 100.363979 -344.716286) (xy 100.295223 -344.763745) (xy 100.222207 -344.804346)
			(xy 100.145614 -344.837711) (xy 100.066158 -344.863528) (xy 99.984582 -344.881556) (xy 99.901646 -344.891626)
			(xy 99.818126 -344.893645) (xy 99.7348 -344.887593) (xy 99.652448 -344.873528) (xy 99.571838 -344.85158)
			(xy 99.493722 -344.821954) (xy 99.41883 -344.784928) (xy 99.347862 -344.740847) (xy 99.281479 -344.690121)
			(xy 99.220302 -344.633226) (xy 99.164901 -344.570692) (xy 99.115795 -344.503103) (xy 99.073441 -344.43109)
			(xy 99.038235 -344.355325) (xy 99.010506 -344.276516) (xy 98.990513 -344.195399) (xy 98.978441 -344.112731)
			(xy 98.974405 -344.029284) (xy 98.228404 -344.029284) (xy 98.2279 -344.071632) (xy 98.219849 -344.155946)
			(xy 98.20382 -344.239112) (xy 98.179959 -344.320379) (xy 98.14848 -344.399009) (xy 98.109669 -344.47429)
			(xy 98.063879 -344.545542) (xy 98.011523 -344.612118) (xy 97.953075 -344.673416) (xy 97.889065 -344.728881)
			(xy 97.820073 -344.77801) (xy 97.746723 -344.820359) (xy 97.66968 -344.855543) (xy 97.589641 -344.883245)
			(xy 97.507332 -344.903213) (xy 97.423497 -344.915266) (xy 97.338896 -344.919297) (xy 97.254295 -344.915266)
			(xy 97.17046 -344.903213) (xy 97.088151 -344.883245) (xy 97.008112 -344.855543) (xy 96.931069 -344.820359)
			(xy 96.857719 -344.77801) (xy 96.788727 -344.728881) (xy 96.724717 -344.673416) (xy 96.666269 -344.612118)
			(xy 96.613913 -344.545542) (xy 96.568123 -344.47429) (xy 96.529312 -344.399009) (xy 96.497833 -344.320379)
			(xy 96.473972 -344.239112) (xy 96.457943 -344.155946) (xy 96.449892 -344.071632) (xy 86.81212 -344.071632)
			(xy 86.81212 -345.845638) (xy 134.634984 -345.845638) (xy 134.639055 -345.790016) (xy 134.651181 -345.735579)
			(xy 134.671104 -345.683488) (xy 134.6984 -345.634853) (xy 134.732486 -345.59071) (xy 134.772635 -345.552001)
			(xy 134.817993 -345.51955) (xy 134.867593 -345.494049) (xy 134.920377 -345.476042) (xy 134.97522 -345.465912)
			(xy 135.030954 -345.463875) (xy 135.086391 -345.469975) (xy 135.140348 -345.484081) (xy 135.191677 -345.505893)
			(xy 135.239283 -345.534947) (xy 135.282151 -345.570622) (xy 135.319368 -345.612159) (xy 135.350141 -345.658672)
			(xy 135.373813 -345.709169) (xy 135.389881 -345.762576) (xy 135.398001 -345.817752) (xy 135.39851 -345.845638)
			(xy 135.398001 -345.873524) (xy 135.389881 -345.9287) (xy 135.373813 -345.982107) (xy 135.350141 -346.032604)
			(xy 135.319368 -346.079117) (xy 135.282151 -346.120654) (xy 135.239283 -346.156329) (xy 135.191677 -346.185383)
			(xy 135.140348 -346.207195) (xy 135.086391 -346.221301) (xy 135.030954 -346.227401) (xy 134.97522 -346.225364)
			(xy 134.920377 -346.215234) (xy 134.867593 -346.197227) (xy 134.817993 -346.171726) (xy 134.772635 -346.139275)
			(xy 134.732486 -346.100566) (xy 134.6984 -346.056423) (xy 134.671104 -346.007788) (xy 134.651181 -345.955697)
			(xy 134.639055 -345.90126) (xy 134.634984 -345.845638) (xy 86.81212 -345.845638) (xy 86.81212 -346.509848)
			(xy 133.965948 -346.509848) (xy 133.970019 -346.454226) (xy 133.982145 -346.399789) (xy 134.002068 -346.347698)
			(xy 134.029364 -346.299063) (xy 134.06345 -346.25492) (xy 134.103599 -346.216211) (xy 134.148957 -346.18376)
			(xy 134.198557 -346.158259) (xy 134.251341 -346.140252) (xy 134.306184 -346.130122) (xy 134.361918 -346.128085)
			(xy 134.417355 -346.134185) (xy 134.471312 -346.148291) (xy 134.522641 -346.170103) (xy 134.570247 -346.199157)
			(xy 134.613115 -346.234832) (xy 134.650332 -346.276369) (xy 134.681105 -346.322882) (xy 134.704777 -346.373379)
			(xy 134.720845 -346.426786) (xy 134.728965 -346.481962) (xy 134.729474 -346.509848) (xy 134.728965 -346.537734)
			(xy 134.720845 -346.59291) (xy 134.704777 -346.646317) (xy 134.681105 -346.696814) (xy 134.650332 -346.743327)
			(xy 134.613115 -346.784864) (xy 134.570247 -346.820539) (xy 134.522641 -346.849593) (xy 134.471312 -346.871405)
			(xy 134.417355 -346.885511) (xy 134.361918 -346.891611) (xy 134.306184 -346.889574) (xy 134.251341 -346.879444)
			(xy 134.198557 -346.861437) (xy 134.148957 -346.835936) (xy 134.103599 -346.803485) (xy 134.06345 -346.764776)
			(xy 134.029364 -346.720633) (xy 134.002068 -346.671998) (xy 133.982145 -346.619907) (xy 133.970019 -346.56547)
			(xy 133.965948 -346.509848) (xy 86.81212 -346.509848) (xy 86.81212 -346.884498) (xy 86.811497 -346.909481)
			(xy 86.801759 -346.958489) (xy 86.782655 -347.004659) (xy 86.754918 -347.04622) (xy 86.737698 -347.06433)
			(xy 86.362794 -347.439234) (xy 135.44169 -347.439234) (xy 135.442274 -347.409547) (xy 135.451467 -347.35089)
			(xy 135.469637 -347.294364) (xy 135.496345 -347.241337) (xy 135.530946 -347.193087) (xy 135.572604 -347.150781)
			(xy 135.596122 -347.132656) (xy 135.606706 -347.124204) (xy 135.623411 -347.102896) (xy 135.633929 -347.077948)
			(xy 135.637521 -347.051113) (xy 135.633936 -347.024277) (xy 135.623424 -346.999326) (xy 135.606725 -346.978015)
			(xy 135.596122 -346.969588) (xy 135.572611 -346.951453) (xy 135.530949 -346.90915) (xy 135.496344 -346.860903)
			(xy 135.469631 -346.807878) (xy 135.451455 -346.751354) (xy 135.442256 -346.692697) (xy 135.44169 -346.66301)
			(xy 135.442176 -346.635759) (xy 135.449932 -346.581811) (xy 135.465287 -346.529516) (xy 135.487929 -346.479939)
			(xy 135.517395 -346.434089) (xy 135.553086 -346.392898) (xy 135.594277 -346.357207) (xy 135.640127 -346.327741)
			(xy 135.689704 -346.305099) (xy 135.741999 -346.289744) (xy 135.795947 -346.281988) (xy 135.850449 -346.281988)
			(xy 135.904397 -346.289744) (xy 135.956692 -346.305099) (xy 136.006269 -346.327741) (xy 136.052119 -346.357207)
			(xy 136.09331 -346.392898) (xy 136.129001 -346.434089) (xy 136.158467 -346.479939) (xy 136.181109 -346.529516)
			(xy 136.196464 -346.581811) (xy 136.20422 -346.635759) (xy 136.204706 -346.66301) (xy 136.204156 -346.692698)
			(xy 136.194956 -346.751357) (xy 136.176779 -346.807883) (xy 136.150065 -346.860911) (xy 136.115458 -346.909159)
			(xy 136.073795 -346.951464) (xy 136.050274 -346.969588) (xy 136.039646 -346.97799) (xy 136.022942 -346.999309)
			(xy 136.012428 -347.024268) (xy 136.008841 -347.051113) (xy 136.012435 -347.077957) (xy 136.022956 -347.102914)
			(xy 136.039665 -347.124229) (xy 136.050274 -347.132656) (xy 136.073806 -347.150766) (xy 136.115466 -347.193074)
			(xy 136.150069 -347.241326) (xy 136.176779 -347.294357) (xy 136.19495 -347.350885) (xy 136.204144 -347.409546)
			(xy 136.204706 -347.439234) (xy 136.20422 -347.466485) (xy 136.196464 -347.520433) (xy 136.181109 -347.572728)
			(xy 136.158467 -347.622305) (xy 136.129001 -347.668155) (xy 136.09331 -347.709346) (xy 136.052119 -347.745037)
			(xy 136.006269 -347.774503) (xy 135.956692 -347.797145) (xy 135.904397 -347.8125) (xy 135.850449 -347.820256)
			(xy 135.795947 -347.820256) (xy 135.741999 -347.8125) (xy 135.689704 -347.797145) (xy 135.640127 -347.774503)
			(xy 135.594277 -347.745037) (xy 135.553086 -347.709346) (xy 135.517395 -347.668155) (xy 135.487929 -347.622305)
			(xy 135.465287 -347.572728) (xy 135.449932 -347.520433) (xy 135.442176 -347.466485) (xy 135.44169 -347.439234)
			(xy 86.362794 -347.439234) (xy 86.019386 -347.782642) (xy 86.001293 -347.799883) (xy 85.959728 -347.827622)
			(xy 85.913553 -347.846724) (xy 85.864539 -347.856457) (xy 85.839554 -347.857064) (xy 82.718402 -347.857064)
			(xy 82.69342 -347.856429) (xy 82.644413 -347.846692) (xy 82.598243 -347.827592) (xy 82.556681 -347.79986)
			(xy 82.53857 -347.782642) (xy 80.825594 -346.069666) (xy 80.509618 -345.938856) (xy 80.11541 -345.938856)
			(xy 79.969868 -346.084144) (xy 79.969868 -346.260928) (xy 79.970436 -346.275902) (xy 79.979099 -346.304568)
			(xy 79.995703 -346.32949) (xy 80.018821 -346.348527) (xy 80.046466 -346.360042) (xy 80.076261 -346.363046)
			(xy 80.105648 -346.357281) (xy 80.1321 -346.343241) (xy 80.143096 -346.333064) (xy 80.164627 -346.312558)
			(xy 80.212914 -346.277863) (xy 80.265999 -346.251082) (xy 80.322597 -346.232862) (xy 80.381337 -346.223646)
			(xy 80.411066 -346.223082) (xy 80.438318 -346.223587) (xy 80.492266 -346.231339) (xy 80.544563 -346.24669)
			(xy 80.594142 -346.269328) (xy 80.639995 -346.298792) (xy 80.681188 -346.334481) (xy 80.716882 -346.37567)
			(xy 80.746351 -346.421519) (xy 80.768994 -346.471096) (xy 80.784352 -346.52339) (xy 80.79211 -346.577338)
			(xy 80.792574 -346.60459) (xy 80.792574 -346.604844) (xy 80.792003 -346.634683) (xy 80.782685 -346.693629)
			(xy 80.774032 -346.722192) (xy 80.769931 -346.736084) (xy 80.769028 -346.765028) (xy 80.776304 -346.793057)
			(xy 80.791169 -346.817907) (xy 80.812425 -346.837573) (xy 80.838354 -346.850466) (xy 80.852518 -346.85351)
			(xy 80.878588 -346.858694) (xy 80.929091 -346.875263) (xy 80.976803 -346.898685) (xy 81.020801 -346.928505)
			(xy 81.060232 -346.964146) (xy 81.094332 -347.004918) (xy 81.122439 -347.050029) (xy 81.144009 -347.098607)
			(xy 81.158625 -347.149709) (xy 81.166003 -347.202346) (xy 81.166462 -347.228922) (xy 81.165976 -347.256173)
			(xy 81.15822 -347.310121) (xy 81.142865 -347.362416) (xy 81.120223 -347.411993) (xy 81.090757 -347.457843)
			(xy 81.055066 -347.499034) (xy 81.013875 -347.534725) (xy 80.968025 -347.564191) (xy 80.918448 -347.586833)
			(xy 80.866153 -347.602188) (xy 80.812205 -347.609944) (xy 80.757703 -347.609944) (xy 80.703755 -347.602188)
			(xy 80.65146 -347.586833) (xy 80.601883 -347.564191) (xy 80.556033 -347.534725) (xy 80.514842 -347.499034)
			(xy 80.479151 -347.457843) (xy 80.449685 -347.411993) (xy 80.427043 -347.362416) (xy 80.411688 -347.310121)
			(xy 80.403932 -347.256173) (xy 80.403446 -347.228922) (xy 80.403446 -347.228668) (xy 80.404023 -347.198829)
			(xy 80.413337 -347.139883) (xy 80.421988 -347.11132) (xy 80.426059 -347.097421) (xy 80.426964 -347.068483)
			(xy 80.419693 -347.040458) (xy 80.404833 -347.01561) (xy 80.383585 -346.995944) (xy 80.357663 -346.983049)
			(xy 80.343502 -346.980002) (xy 80.310662 -346.97342) (xy 80.24781 -346.950297) (xy 80.218534 -346.934028)
			(xy 80.205591 -346.926948) (xy 80.176946 -346.919925) (xy 80.147488 -346.921379) (xy 80.119674 -346.931189)
			(xy 80.095823 -346.948537) (xy 80.077923 -346.971977) (xy 80.07223 -346.98559) (xy 80.06152 -347.012361)
			(xy 80.033235 -347.062603) (xy 79.997708 -347.108013) (xy 79.955748 -347.147557) (xy 79.908313 -347.180331)
			(xy 79.856483 -347.20559) (xy 79.801441 -347.222757) (xy 79.744442 -347.23144) (xy 79.715614 -347.23197)
			(xy 79.68836 -347.231532) (xy 79.634406 -347.223775) (xy 79.582105 -347.208419) (xy 79.532523 -347.185776)
			(xy 79.486668 -347.156306) (xy 79.445474 -347.120609) (xy 79.40978 -347.079413) (xy 79.380313 -347.033556)
			(xy 79.357672 -346.983972) (xy 79.342319 -346.931671) (xy 79.334567 -346.877716) (xy 79.334106 -346.850462)
			(xy 79.334581 -346.823718) (xy 79.342074 -346.770758) (xy 79.356893 -346.719364) (xy 79.378748 -346.670545)
			(xy 79.407209 -346.625259) (xy 79.44172 -346.584393) (xy 79.46136 -346.566236) (xy 79.46136 -345.978734)
			(xy 79.461947 -345.953749) (xy 79.471697 -345.90474) (xy 79.490812 -345.85857) (xy 79.518557 -345.817011)
			(xy 79.535782 -345.798902) (xy 79.830168 -345.504516) (xy 79.848244 -345.487237) (xy 79.889795 -345.459431)
			(xy 79.935972 -345.440263) (xy 79.985002 -345.430472) (xy 80.01 -345.42984) (xy 80.560164 -345.42984)
			(xy 80.585149 -345.430515) (xy 80.634142 -345.440363) (xy 80.657446 -345.449398) (xy 81.066894 -345.61907)
			(xy 81.089773 -345.629162) (xy 81.13136 -345.656918) (xy 81.149444 -345.674188) (xy 82.823812 -347.348556)
			(xy 85.734144 -347.348556) (xy 86.303612 -346.779088) (xy 86.303612 -343.789508) (xy 86.304258 -343.764526)
			(xy 86.313992 -343.715521) (xy 86.33309 -343.669351) (xy 86.360818 -343.627788) (xy 86.378034 -343.609676)
			(xy 87.207344 -342.780366) (xy 87.207344 -342.064594) (xy 87.206746 -342.049281) (xy 87.19767 -342.02003)
			(xy 87.180335 -341.994782) (xy 87.156298 -341.975804) (xy 87.127717 -341.964799) (xy 87.097159 -341.962757)
			(xy 87.067368 -341.96986) (xy 87.053928 -341.977218) (xy 87.031836 -341.989729) (xy 86.985059 -342.009467)
			(xy 86.936082 -342.022839) (xy 86.885765 -342.02961) (xy 86.86038 -342.03005) (xy 86.860126 -342.03005)
			(xy 86.832877 -342.029498) (xy 86.778934 -342.021746) (xy 86.726643 -342.006396) (xy 86.677069 -341.983761)
			(xy 86.631221 -341.954301) (xy 86.590031 -341.918617) (xy 86.554339 -341.877434) (xy 86.524872 -341.831591)
			(xy 86.502228 -341.78202) (xy 86.486869 -341.729732) (xy 86.479107 -341.675791) (xy 86.478618 -341.648542)
			(xy 86.479196 -341.618855) (xy 86.488389 -341.560196) (xy 86.506559 -341.503671) (xy 86.533268 -341.450643)
			(xy 86.56787 -341.402394) (xy 86.609531 -341.360088) (xy 86.63305 -341.341964) (xy 86.643624 -341.333501)
			(xy 86.660324 -341.312195) (xy 86.670839 -341.28725) (xy 86.674432 -341.260418) (xy 86.670849 -341.233585)
			(xy 86.660342 -341.208636) (xy 86.64365 -341.187324) (xy 86.63305 -341.178896) (xy 86.609527 -341.160776)
			(xy 86.56787 -341.118467) (xy 86.533268 -341.070217) (xy 86.506558 -341.017189) (xy 86.488384 -340.960663)
			(xy 86.479184 -340.902005) (xy 86.478618 -340.872318) (xy 86.479104 -340.845067) (xy 86.48686 -340.791119)
			(xy 86.502215 -340.738824) (xy 86.524857 -340.689247) (xy 86.554323 -340.643397) (xy 86.590014 -340.602206)
			(xy 86.631205 -340.566515) (xy 86.677055 -340.537049) (xy 86.726632 -340.514407) (xy 86.778927 -340.499052)
			(xy 86.832875 -340.491296) (xy 86.887377 -340.491296) (xy 86.941325 -340.499052) (xy 86.99362 -340.514407)
			(xy 87.043197 -340.537049) (xy 87.089047 -340.566515) (xy 87.130238 -340.602206) (xy 87.165929 -340.643397)
			(xy 87.195395 -340.689247) (xy 87.218037 -340.738824) (xy 87.233392 -340.791119) (xy 87.241148 -340.845067)
			(xy 87.241634 -340.872318) (xy 87.241119 -340.902008) (xy 87.231915 -340.96067) (xy 87.213734 -341.017198)
			(xy 87.187013 -341.070226) (xy 87.152399 -341.118473) (xy 87.110727 -341.160775) (xy 87.087202 -341.178896)
			(xy 87.076564 -341.187287) (xy 87.059855 -341.208607) (xy 87.049338 -341.233569) (xy 87.045751 -341.260418)
			(xy 87.049347 -341.287266) (xy 87.059874 -341.312224) (xy 87.07659 -341.333538) (xy 87.087202 -341.341964)
			(xy 87.102188 -341.353648) (xy 87.113367 -341.362261) (xy 87.139249 -341.373489) (xy 87.167214 -341.377215)
			(xy 87.195132 -341.373154) (xy 87.220877 -341.361615) (xy 87.242487 -341.343479) (xy 87.250778 -341.332058)
			(xy 87.257714 -341.32202) (xy 87.273239 -341.303193) (xy 87.281766 -341.294466) (xy 87.494618 -341.081614)
			(xy 87.494618 -341.060278) (xy 87.494993 -341.033) (xy 87.502696 -340.97899) (xy 87.518013 -340.926629)
			(xy 87.540632 -340.876983) (xy 87.570091 -340.831065) (xy 87.605791 -340.789811) (xy 87.647002 -340.754063)
			(xy 87.692886 -340.724549) (xy 87.742505 -340.701871) (xy 87.794848 -340.686492) (xy 87.848848 -340.678725)
			(xy 87.876126 -340.678262) (xy 87.87638 -340.678262) (xy 87.901584 -340.678667) (xy 87.951551 -340.685305)
			(xy 88.000206 -340.698479) (xy 88.046696 -340.717961) (xy 88.068658 -340.730332) (xy 88.081597 -340.737424)
			(xy 88.110245 -340.744453) (xy 88.139706 -340.743) (xy 88.167523 -340.733188) (xy 88.191376 -340.715834)
			(xy 88.209273 -340.692386) (xy 88.214962 -340.67877) (xy 88.225657 -340.651993) (xy 88.253946 -340.601753)
			(xy 88.289477 -340.556344) (xy 88.331439 -340.516802) (xy 88.378876 -340.484029) (xy 88.430707 -340.458771)
			(xy 88.48575 -340.441604) (xy 88.542749 -340.43292) (xy 88.571578 -340.43239) (xy 88.59883 -340.432876)
			(xy 88.65278 -340.44063) (xy 88.705078 -340.455983) (xy 88.754657 -340.478623) (xy 88.800511 -340.508088)
			(xy 88.841703 -340.54378) (xy 88.877397 -340.58497) (xy 88.906866 -340.630821) (xy 88.929509 -340.6804)
			(xy 88.944865 -340.732696) (xy 88.952623 -340.786646) (xy 88.953086 -340.813898) (xy 88.953086 -340.814152)
			(xy 88.952517 -340.843991) (xy 88.943197 -340.902937) (xy 88.934544 -340.9315) (xy 88.930537 -340.945417)
			(xy 88.929613 -340.974348) (xy 88.936868 -341.00237) (xy 88.951716 -341.027217) (xy 88.972956 -341.046881)
			(xy 88.998872 -341.059774) (xy 89.01303 -341.062818) (xy 89.039103 -341.067986) (xy 89.089607 -341.084557)
			(xy 89.13732 -341.107981) (xy 89.181318 -341.137803) (xy 89.220748 -341.173446) (xy 89.254847 -341.214219)
			(xy 89.282954 -341.259332) (xy 89.304524 -341.307912) (xy 89.319139 -341.359015) (xy 89.326516 -341.411654)
			(xy 89.326974 -341.43823) (xy 89.326488 -341.465481) (xy 89.318732 -341.519429) (xy 89.303377 -341.571724)
			(xy 89.280735 -341.621301) (xy 89.251269 -341.667151) (xy 89.215578 -341.708342) (xy 89.174387 -341.744033)
			(xy 89.128537 -341.773499) (xy 89.07896 -341.796141) (xy 89.026665 -341.811496) (xy 88.972717 -341.819252)
			(xy 88.918215 -341.819252) (xy 88.864267 -341.811496) (xy 88.811972 -341.796141) (xy 88.762395 -341.773499)
			(xy 88.716545 -341.744033) (xy 88.675354 -341.708342) (xy 88.639663 -341.667151) (xy 88.610197 -341.621301)
			(xy 88.587555 -341.571724) (xy 88.5722 -341.519429) (xy 88.564444 -341.465481) (xy 88.563958 -341.43823)
			(xy 88.563958 -341.437976) (xy 88.564536 -341.408137) (xy 88.57385 -341.349191) (xy 88.5825 -341.320628)
			(xy 88.586553 -341.306724) (xy 88.587459 -341.277789) (xy 88.580191 -341.249768) (xy 88.565335 -341.224921)
			(xy 88.544091 -341.205255) (xy 88.518173 -341.192358) (xy 88.504014 -341.18931) (xy 88.471175 -341.182725)
			(xy 88.408323 -341.159603) (xy 88.379046 -341.143336) (xy 88.366097 -341.136266) (xy 88.337454 -341.12924)
			(xy 88.307998 -341.130691) (xy 88.280185 -341.140499) (xy 88.256334 -341.157846) (xy 88.238434 -341.181286)
			(xy 88.232742 -341.194898) (xy 88.221383 -341.223155) (xy 88.19103 -341.275949) (xy 88.152675 -341.323249)
			(xy 88.13038 -341.343996) (xy 88.13038 -342.378284) (xy 88.73871 -342.98636) (xy 92.829634 -342.98636)
			(xy 95.350076 -340.465918) (xy 95.350076 -338.664296) (xy 95.349569 -338.649314) (xy 95.340875 -338.620638)
			(xy 95.324236 -338.595718) (xy 95.301084 -338.576696) (xy 95.273409 -338.565209) (xy 95.243591 -338.562244)
			(xy 95.214196 -338.568057) (xy 95.200724 -338.574634) (xy 95.17285 -338.588839) (xy 95.113631 -338.608995)
			(xy 95.051916 -338.619213) (xy 95.020638 -338.619846) (xy 94.993389 -338.619287) (xy 94.939446 -338.611536)
			(xy 94.887155 -338.596188) (xy 94.837581 -338.573554) (xy 94.791732 -338.544095) (xy 94.750543 -338.508411)
			(xy 94.71485 -338.467229) (xy 94.685383 -338.421386) (xy 94.662739 -338.371816) (xy 94.64738 -338.319528)
			(xy 94.639619 -338.265586) (xy 94.63913 -338.238338) (xy 94.639701 -338.20865) (xy 94.648894 -338.149991)
			(xy 94.667066 -338.093465) (xy 94.693776 -338.040437) (xy 94.72838 -337.992188) (xy 94.770042 -337.949884)
			(xy 94.793562 -337.93176) (xy 94.804147 -337.923306) (xy 94.820861 -337.902002) (xy 94.831386 -337.877054)
			(xy 94.834982 -337.850216) (xy 94.831395 -337.823376) (xy 94.820877 -337.798425) (xy 94.80417 -337.777116)
			(xy 94.793562 -337.768692) (xy 94.77004 -337.750571) (xy 94.728382 -337.708263) (xy 94.69378 -337.660013)
			(xy 94.667069 -337.606985) (xy 94.648895 -337.55046) (xy 94.639696 -337.491801) (xy 94.63913 -337.462114)
			(xy 94.639616 -337.434863) (xy 94.647372 -337.380915) (xy 94.662727 -337.32862) (xy 94.685369 -337.279043)
			(xy 94.714835 -337.233193) (xy 94.750526 -337.192002) (xy 94.791717 -337.156311) (xy 94.837567 -337.126845)
			(xy 94.887144 -337.104203) (xy 94.939439 -337.088848) (xy 94.993387 -337.081092) (xy 95.047889 -337.081092)
			(xy 95.101837 -337.088848) (xy 95.154132 -337.104203) (xy 95.203709 -337.126845) (xy 95.249559 -337.156311)
			(xy 95.29075 -337.192002) (xy 95.326441 -337.233193) (xy 95.355907 -337.279043) (xy 95.378549 -337.32862)
			(xy 95.393904 -337.380915) (xy 95.40166 -337.434863) (xy 95.402146 -337.462114) (xy 95.401602 -337.489933)
			(xy 95.393453 -337.544972) (xy 95.377418 -337.59825) (xy 95.366078 -337.623658) (xy 95.351092 -337.655916)
			(xy 95.412306 -337.71713) (xy 95.520002 -337.609434) (xy 95.538058 -337.592217) (xy 95.579504 -337.564459)
			(xy 95.602298 -337.554316) (xy 95.675704 -337.523836) (xy 95.683832 -337.504278) (xy 95.69504 -337.478446)
			(xy 95.723911 -337.430104) (xy 95.759571 -337.386529) (xy 95.801247 -337.348666) (xy 95.848034 -337.317338)
			(xy 95.898917 -337.293224) (xy 95.95279 -337.276848) (xy 96.008485 -337.268566) (xy 96.036638 -337.268058)
			(xy 96.036892 -337.268058) (xy 96.062096 -337.268459) (xy 96.112064 -337.275098) (xy 96.160718 -337.288274)
			(xy 96.207208 -337.307756) (xy 96.22917 -337.320128) (xy 96.24216 -337.327118) (xy 96.270787 -337.334163)
			(xy 96.300234 -337.332729) (xy 96.328041 -337.322936) (xy 96.351888 -337.305602) (xy 96.369784 -337.282173)
			(xy 96.375474 -337.268566) (xy 96.386157 -337.241784) (xy 96.414448 -337.191543) (xy 96.44998 -337.146135)
			(xy 96.491944 -337.106593) (xy 96.539383 -337.07382) (xy 96.591215 -337.048563) (xy 96.64626 -337.031398)
			(xy 96.703261 -337.022716) (xy 96.73209 -337.022186) (xy 96.759342 -337.022665) (xy 96.813292 -337.03042)
			(xy 96.86559 -337.045775) (xy 96.915169 -337.068415) (xy 96.961022 -337.097882) (xy 97.002215 -337.133574)
			(xy 97.037909 -337.174765) (xy 97.067377 -337.220617) (xy 97.09002 -337.270195) (xy 97.105377 -337.322492)
			(xy 97.113134 -337.376442) (xy 97.113598 -337.403694) (xy 97.113598 -337.403948) (xy 97.113027 -337.433787)
			(xy 97.103709 -337.492733) (xy 97.095056 -337.521296) (xy 97.091124 -337.53523) (xy 97.090201 -337.564145)
			(xy 97.097449 -337.592153) (xy 97.112281 -337.616992) (xy 97.1335 -337.636657) (xy 97.159394 -337.64956)
			(xy 97.173542 -337.652614) (xy 97.199616 -337.657777) (xy 97.25012 -337.674349) (xy 97.297832 -337.697774)
			(xy 97.34183 -337.727597) (xy 97.38126 -337.763241) (xy 97.415359 -337.804014) (xy 97.443465 -337.849128)
			(xy 97.465035 -337.897707) (xy 97.47965 -337.948811) (xy 97.487027 -338.00145) (xy 97.487486 -338.028026)
			(xy 97.487 -338.055277) (xy 97.479244 -338.109225) (xy 97.463889 -338.16152) (xy 97.441247 -338.211097)
			(xy 97.411781 -338.256947) (xy 97.37609 -338.298138) (xy 97.334899 -338.333829) (xy 97.289049 -338.363295)
			(xy 97.239472 -338.385937) (xy 97.187177 -338.401292) (xy 97.133229 -338.409048) (xy 97.078727 -338.409048)
			(xy 97.024779 -338.401292) (xy 96.972484 -338.385937) (xy 96.922907 -338.363295) (xy 96.877057 -338.333829)
			(xy 96.835866 -338.298138) (xy 96.800175 -338.256947) (xy 96.770709 -338.211097) (xy 96.748067 -338.16152)
			(xy 96.732712 -338.109225) (xy 96.724956 -338.055277) (xy 96.72447 -338.028026) (xy 96.72447 -338.027772)
			(xy 96.725047 -337.997933) (xy 96.734361 -337.938987) (xy 96.743012 -337.910424) (xy 96.74706 -337.896519)
			(xy 96.747965 -337.867586) (xy 96.740696 -337.839565) (xy 96.725842 -337.81472) (xy 96.704599 -337.795054)
			(xy 96.678684 -337.782155) (xy 96.664526 -337.779106) (xy 96.631688 -337.772518) (xy 96.568835 -337.749399)
			(xy 96.539558 -337.733132) (xy 96.526602 -337.726078) (xy 96.497962 -337.71905) (xy 96.468508 -337.720499)
			(xy 96.440696 -337.730304) (xy 96.416846 -337.747648) (xy 96.398947 -337.771083) (xy 96.393254 -337.784694)
			(xy 96.381892 -337.81295) (xy 96.351539 -337.865743) (xy 96.313186 -337.913045) (xy 96.290892 -337.933792)
			(xy 96.290892 -339.082634) (xy 97.084388 -339.875876) (xy 102.966266 -339.875876) (xy 103.498396 -339.343746)
			(xy 103.498396 -338.670646) (xy 103.497894 -338.655872) (xy 103.489424 -338.627564) (xy 103.473207 -338.602863)
			(xy 103.4506 -338.583835) (xy 103.423493 -338.572073) (xy 103.394155 -338.568558) (xy 103.365037 -338.573587)
			(xy 103.351584 -338.579714) (xy 103.325007 -338.592337) (xy 103.268951 -338.610204) (xy 103.210821 -338.619275)
			(xy 103.181404 -338.619846) (xy 103.18115 -338.619846) (xy 103.1539 -338.619298) (xy 103.099954 -338.611549)
			(xy 103.04766 -338.596201) (xy 102.998083 -338.573567) (xy 102.952231 -338.544108) (xy 102.911039 -338.508423)
			(xy 102.875345 -338.467239) (xy 102.845875 -338.421395) (xy 102.823229 -338.371822) (xy 102.80787 -338.319532)
			(xy 102.800108 -338.265588) (xy 102.799642 -338.238338) (xy 102.800208 -338.20865) (xy 102.809402 -338.149991)
			(xy 102.827574 -338.093464) (xy 102.854285 -338.040436) (xy 102.88889 -337.992187) (xy 102.930553 -337.949883)
			(xy 102.954074 -337.93176) (xy 102.964658 -337.923305) (xy 102.98137 -337.902001) (xy 102.991894 -337.877053)
			(xy 102.995489 -337.850216) (xy 102.991902 -337.823377) (xy 102.981386 -337.798426) (xy 102.964681 -337.777116)
			(xy 102.954074 -337.768692) (xy 102.930554 -337.750568) (xy 102.888895 -337.708261) (xy 102.854293 -337.660011)
			(xy 102.827582 -337.606984) (xy 102.809407 -337.550459) (xy 102.800208 -337.491801) (xy 102.799642 -337.462114)
			(xy 102.800128 -337.434863) (xy 102.807884 -337.380915) (xy 102.823239 -337.32862) (xy 102.845881 -337.279043)
			(xy 102.875347 -337.233193) (xy 102.911038 -337.192002) (xy 102.952229 -337.156311) (xy 102.998079 -337.126845)
			(xy 103.047656 -337.104203) (xy 103.099951 -337.088848) (xy 103.153899 -337.081092) (xy 103.208401 -337.081092)
			(xy 103.262349 -337.088848) (xy 103.314644 -337.104203) (xy 103.364221 -337.126845) (xy 103.410071 -337.156311)
			(xy 103.451262 -337.192002) (xy 103.486953 -337.233193) (xy 103.516419 -337.279043) (xy 103.539061 -337.32862)
			(xy 103.554416 -337.380915) (xy 103.562172 -337.434863) (xy 103.562658 -337.462114) (xy 103.562154 -337.48869)
			(xy 103.554762 -337.541325) (xy 103.540137 -337.592426) (xy 103.518563 -337.641002) (xy 103.490456 -337.686115)
			(xy 103.456361 -337.72689) (xy 103.416937 -337.76254) (xy 103.372947 -337.792373) (xy 103.349298 -337.804506)
			(xy 103.340913 -337.808996) (xy 103.328049 -337.822993) (xy 103.321148 -337.840706) (xy 103.321152 -337.859717)
			(xy 103.328061 -337.877427) (xy 103.340932 -337.891418) (xy 103.349298 -337.895946) (xy 103.369872 -337.906868)
			(xy 103.382857 -337.913652) (xy 103.411375 -337.920301) (xy 103.440608 -337.918597) (xy 103.46816 -337.908679)
			(xy 103.491772 -337.891359) (xy 103.509509 -337.868059) (xy 103.51516 -337.854544) (xy 103.525359 -337.829689)
			(xy 103.554557 -337.784603) (xy 103.573072 -337.765136) (xy 103.763318 -337.57489) (xy 103.779603 -337.559244)
			(xy 103.816661 -337.533443) (xy 103.836978 -337.523582) (xy 103.846052 -337.499029) (xy 103.86994 -337.452451)
			(xy 103.899968 -337.409575) (xy 103.935575 -337.371206) (xy 103.976092 -337.338063) (xy 104.020758 -337.310768)
			(xy 104.068736 -337.289834) (xy 104.119124 -337.275654) (xy 104.170977 -337.268493) (xy 104.19715 -337.268058)
			(xy 104.197404 -337.268058) (xy 104.222608 -337.268453) (xy 104.272576 -337.275094) (xy 104.321231 -337.288271)
			(xy 104.36772 -337.307756) (xy 104.389682 -337.320128) (xy 104.402665 -337.327132) (xy 104.431295 -337.334175)
			(xy 104.460744 -337.332738) (xy 104.488552 -337.322943) (xy 104.5124 -337.305606) (xy 104.530296 -337.282174)
			(xy 104.535986 -337.268566) (xy 104.546659 -337.24178) (xy 104.574951 -337.191539) (xy 104.610485 -337.14613)
			(xy 104.65245 -337.106588) (xy 104.699891 -337.073816) (xy 104.751724 -337.04856) (xy 104.80677 -337.031396)
			(xy 104.863772 -337.022715) (xy 104.892602 -337.022186) (xy 104.919853 -337.022676) (xy 104.9738 -337.030433)
			(xy 105.026095 -337.045788) (xy 105.075671 -337.068429) (xy 105.121522 -337.097894) (xy 105.162712 -337.133586)
			(xy 105.198403 -337.174775) (xy 105.22787 -337.220625) (xy 105.250511 -337.270202) (xy 105.265867 -337.322496)
			(xy 105.273624 -337.376443) (xy 105.27411 -337.403694) (xy 105.27411 -337.403948) (xy 105.273539 -337.433787)
			(xy 105.26422 -337.492733) (xy 105.255568 -337.521296) (xy 105.251626 -337.535228) (xy 105.250703 -337.564145)
			(xy 105.257952 -337.592155) (xy 105.272786 -337.616995) (xy 105.294008 -337.63666) (xy 105.319904 -337.649562)
			(xy 105.334054 -337.652614) (xy 105.36013 -337.657768) (xy 105.410633 -337.674342) (xy 105.458346 -337.697768)
			(xy 105.502343 -337.727592) (xy 105.541773 -337.763237) (xy 105.575872 -337.804012) (xy 105.603978 -337.849126)
			(xy 105.625547 -337.897706) (xy 105.640162 -337.948811) (xy 105.647539 -338.001449) (xy 105.647998 -338.028026)
			(xy 105.647512 -338.055277) (xy 105.639756 -338.109225) (xy 105.624401 -338.16152) (xy 105.601759 -338.211097)
			(xy 105.572293 -338.256947) (xy 105.536602 -338.298138) (xy 105.495411 -338.333829) (xy 105.449561 -338.363295)
			(xy 105.399984 -338.385937) (xy 105.347689 -338.401292) (xy 105.293741 -338.409048) (xy 105.239239 -338.409048)
			(xy 105.185291 -338.401292) (xy 105.132996 -338.385937) (xy 105.083419 -338.363295) (xy 105.037569 -338.333829)
			(xy 104.996378 -338.298138) (xy 104.960687 -338.256947) (xy 104.931221 -338.211097) (xy 104.908579 -338.16152)
			(xy 104.893224 -338.109225) (xy 104.885468 -338.055277) (xy 104.884982 -338.028026) (xy 104.884982 -338.027772)
			(xy 104.885558 -337.997933) (xy 104.894873 -337.938987) (xy 104.903524 -337.910424) (xy 104.907562 -337.896517)
			(xy 104.908467 -337.867586) (xy 104.901199 -337.839567) (xy 104.886347 -337.814723) (xy 104.865107 -337.795057)
			(xy 104.839195 -337.782157) (xy 104.825038 -337.779106) (xy 104.7922 -337.772515) (xy 104.729347 -337.749398)
			(xy 104.70007 -337.733132) (xy 104.687106 -337.726092) (xy 104.65847 -337.719062) (xy 104.629018 -337.720509)
			(xy 104.601208 -337.730311) (xy 104.577358 -337.747652) (xy 104.559459 -337.771085) (xy 104.553766 -337.784694)
			(xy 104.542401 -337.812948) (xy 104.51205 -337.865742) (xy 104.473697 -337.913045) (xy 104.451404 -337.933792)
			(xy 104.451404 -339.082634) (xy 105.245154 -339.876384) (xy 110.97641 -339.876384) (xy 111.687864 -339.16493)
			(xy 111.687864 -338.654898) (xy 111.687403 -338.639587) (xy 111.678364 -338.61033) (xy 111.661067 -338.585063)
			(xy 111.637063 -338.56605) (xy 111.608505 -338.554999) (xy 111.577956 -338.552899) (xy 111.548155 -338.55994)
			(xy 111.534702 -338.567268) (xy 111.512667 -338.579737) (xy 111.466006 -338.599383) (xy 111.417156 -338.612687)
			(xy 111.366976 -338.619416) (xy 111.341662 -338.619846) (xy 111.314412 -338.619358) (xy 111.260466 -338.611597)
			(xy 111.208174 -338.596239) (xy 111.158599 -338.573596) (xy 111.11275 -338.544129) (xy 111.071562 -338.508438)
			(xy 111.035871 -338.46725) (xy 111.006404 -338.421401) (xy 110.983761 -338.371826) (xy 110.968403 -338.319534)
			(xy 110.960642 -338.265588) (xy 110.960154 -338.238338) (xy 110.960715 -338.20865) (xy 110.969909 -338.14999)
			(xy 110.988082 -338.093463) (xy 111.014794 -338.040435) (xy 111.0494 -337.992187) (xy 111.091064 -337.949883)
			(xy 111.114586 -337.93176) (xy 111.125169 -337.923305) (xy 111.141879 -337.902) (xy 111.152402 -337.877052)
			(xy 111.155996 -337.850216) (xy 111.15241 -337.823378) (xy 111.141895 -337.798427) (xy 111.125192 -337.777117)
			(xy 111.114586 -337.768692) (xy 111.091069 -337.750565) (xy 111.049409 -337.708259) (xy 111.014806 -337.66001)
			(xy 110.988095 -337.606983) (xy 110.96992 -337.550459) (xy 110.96072 -337.491801) (xy 110.960154 -337.462114)
			(xy 110.96064 -337.434863) (xy 110.968396 -337.380915) (xy 110.983751 -337.32862) (xy 111.006393 -337.279043)
			(xy 111.035859 -337.233193) (xy 111.07155 -337.192002) (xy 111.112741 -337.156311) (xy 111.158591 -337.126845)
			(xy 111.208168 -337.104203) (xy 111.260463 -337.088848) (xy 111.314411 -337.081092) (xy 111.368913 -337.081092)
			(xy 111.422861 -337.088848) (xy 111.475156 -337.104203) (xy 111.524733 -337.126845) (xy 111.570583 -337.156311)
			(xy 111.611774 -337.192002) (xy 111.647465 -337.233193) (xy 111.676931 -337.279043) (xy 111.699573 -337.32862)
			(xy 111.714928 -337.380915) (xy 111.722684 -337.434863) (xy 111.72317 -337.462114) (xy 111.722637 -337.491803)
			(xy 111.713435 -337.550464) (xy 111.695256 -337.606991) (xy 111.668539 -337.660018) (xy 111.633929 -337.708266)
			(xy 111.592261 -337.750569) (xy 111.568738 -337.768692) (xy 111.558101 -337.777085) (xy 111.541386 -337.798403)
			(xy 111.530865 -337.823365) (xy 111.527276 -337.850216) (xy 111.530873 -337.877065) (xy 111.541402 -337.902024)
			(xy 111.558123 -337.923336) (xy 111.568738 -337.93176) (xy 111.577464 -337.938321) (xy 111.594239 -337.952299)
			(xy 111.602266 -337.9597) (xy 111.616998 -337.973416) (xy 111.687864 -337.973416) (xy 111.687864 -337.916266)
			(xy 111.688469 -337.891282) (xy 111.698214 -337.842274) (xy 111.717323 -337.796104) (xy 111.745064 -337.754544)
			(xy 111.762286 -337.736434) (xy 111.92383 -337.57489) (xy 111.940128 -337.559259) (xy 111.977178 -337.533449)
			(xy 111.99749 -337.523582) (xy 112.006554 -337.499024) (xy 112.030442 -337.452446) (xy 112.060472 -337.40957)
			(xy 112.09608 -337.371201) (xy 112.136598 -337.338058) (xy 112.181266 -337.310764) (xy 112.229245 -337.289831)
			(xy 112.279634 -337.275652) (xy 112.331489 -337.268492) (xy 112.357662 -337.268058) (xy 112.357916 -337.268058)
			(xy 112.38312 -337.268448) (xy 112.433088 -337.27509) (xy 112.481743 -337.288269) (xy 112.528232 -337.307755)
			(xy 112.550194 -337.320128) (xy 112.56317 -337.327146) (xy 112.591803 -337.334187) (xy 112.621253 -337.332748)
			(xy 112.649064 -337.322949) (xy 112.672912 -337.30561) (xy 112.690808 -337.282176) (xy 112.696498 -337.268566)
			(xy 112.707161 -337.241776) (xy 112.735454 -337.191534) (xy 112.770989 -337.146125) (xy 112.812956 -337.106583)
			(xy 112.860398 -337.073812) (xy 112.912233 -337.048556) (xy 112.96728 -337.031393) (xy 113.024284 -337.022714)
			(xy 113.053114 -337.022186) (xy 113.080365 -337.022665) (xy 113.134313 -337.030423) (xy 113.186608 -337.04578)
			(xy 113.236184 -337.068422) (xy 113.282034 -337.097889) (xy 113.323224 -337.133581) (xy 113.358916 -337.174772)
			(xy 113.388382 -337.220623) (xy 113.411023 -337.2702) (xy 113.426379 -337.322495) (xy 113.434136 -337.376443)
			(xy 113.434622 -337.403694) (xy 113.434622 -337.403948) (xy 113.43405 -337.433787) (xy 113.424732 -337.492733)
			(xy 113.41608 -337.521296) (xy 113.412129 -337.535225) (xy 113.411206 -337.564145) (xy 113.418455 -337.592157)
			(xy 113.433291 -337.616998) (xy 113.454516 -337.636663) (xy 113.480415 -337.649563) (xy 113.494566 -337.652614)
			(xy 113.520644 -337.657759) (xy 113.571147 -337.674334) (xy 113.61886 -337.697762) (xy 113.662857 -337.727588)
			(xy 113.702286 -337.763233) (xy 113.736384 -337.804009) (xy 113.76449 -337.849124) (xy 113.78606 -337.897705)
			(xy 113.800674 -337.94881) (xy 113.808051 -338.001449) (xy 113.80851 -338.028026) (xy 113.808024 -338.055277)
			(xy 113.800268 -338.109225) (xy 113.784913 -338.16152) (xy 113.762271 -338.211097) (xy 113.732805 -338.256947)
			(xy 113.697114 -338.298138) (xy 113.655923 -338.333829) (xy 113.610073 -338.363295) (xy 113.560496 -338.385937)
			(xy 113.508201 -338.401292) (xy 113.454253 -338.409048) (xy 113.399751 -338.409048) (xy 113.345803 -338.401292)
			(xy 113.293508 -338.385937) (xy 113.243931 -338.363295) (xy 113.198081 -338.333829) (xy 113.15689 -338.298138)
			(xy 113.121199 -338.256947) (xy 113.091733 -338.211097) (xy 113.069091 -338.16152) (xy 113.053736 -338.109225)
			(xy 113.04598 -338.055277) (xy 113.045494 -338.028026) (xy 113.045494 -338.027772) (xy 113.04607 -337.997933)
			(xy 113.055385 -337.938987) (xy 113.064036 -337.910424) (xy 113.068065 -337.896515) (xy 113.068969 -337.867586)
			(xy 113.061702 -337.839569) (xy 113.046852 -337.814725) (xy 113.025615 -337.79506) (xy 112.999706 -337.782158)
			(xy 112.98555 -337.779106) (xy 112.952713 -337.772512) (xy 112.889859 -337.749397) (xy 112.860582 -337.733132)
			(xy 112.847611 -337.726106) (xy 112.818977 -337.719074) (xy 112.789528 -337.720518) (xy 112.761719 -337.730318)
			(xy 112.73787 -337.747656) (xy 112.719971 -337.771086) (xy 112.714278 -337.784694) (xy 112.702932 -337.812957)
			(xy 112.672574 -337.865749) (xy 112.634214 -337.913047) (xy 112.611916 -337.933792) (xy 112.611916 -339.082634)
			(xy 113.419128 -339.889592) (xy 119.22125 -339.889592) (xy 119.815864 -339.295232) (xy 119.815864 -338.672424)
			(xy 119.815433 -338.657685) (xy 119.807 -338.629439) (xy 119.790856 -338.604775) (xy 119.768344 -338.585744)
			(xy 119.741338 -338.573928) (xy 119.712083 -338.570311) (xy 119.683012 -338.575194) (xy 119.66956 -338.581238)
			(xy 119.643398 -338.593412) (xy 119.588321 -338.61062) (xy 119.531279 -338.619318) (xy 119.502428 -338.619846)
			(xy 119.502174 -338.619846) (xy 119.474924 -338.619347) (xy 119.420979 -338.611587) (xy 119.368686 -338.596231)
			(xy 119.319112 -338.57359) (xy 119.273263 -338.544124) (xy 119.232074 -338.508434) (xy 119.196383 -338.467246)
			(xy 119.166916 -338.421399) (xy 119.144273 -338.371825) (xy 119.128915 -338.319533) (xy 119.121154 -338.265588)
			(xy 119.120666 -338.238338) (xy 119.121223 -338.20865) (xy 119.130417 -338.149989) (xy 119.148591 -338.093463)
			(xy 119.175304 -338.040434) (xy 119.209911 -337.992186) (xy 119.251576 -337.949883) (xy 119.275098 -337.93176)
			(xy 119.28568 -337.923304) (xy 119.302388 -337.901999) (xy 119.312909 -337.877051) (xy 119.316503 -337.850216)
			(xy 119.312918 -337.823379) (xy 119.302404 -337.798428) (xy 119.285703 -337.777118) (xy 119.275098 -337.768692)
			(xy 119.251583 -337.750562) (xy 119.209923 -337.708256) (xy 119.175319 -337.660008) (xy 119.148607 -337.606982)
			(xy 119.130432 -337.550458) (xy 119.121232 -337.491801) (xy 119.120666 -337.462114) (xy 119.121152 -337.434863)
			(xy 119.128908 -337.380915) (xy 119.144263 -337.32862) (xy 119.166905 -337.279043) (xy 119.196371 -337.233193)
			(xy 119.232062 -337.192002) (xy 119.273253 -337.156311) (xy 119.319103 -337.126845) (xy 119.36868 -337.104203)
			(xy 119.420975 -337.088848) (xy 119.474923 -337.081092) (xy 119.529425 -337.081092) (xy 119.583373 -337.088848)
			(xy 119.635668 -337.104203) (xy 119.685245 -337.126845) (xy 119.731095 -337.156311) (xy 119.772286 -337.192002)
			(xy 119.807977 -337.233193) (xy 119.837443 -337.279043) (xy 119.860085 -337.32862) (xy 119.87544 -337.380915)
			(xy 119.883196 -337.434863) (xy 119.883682 -337.462114) (xy 119.883164 -337.488689) (xy 119.875773 -337.541324)
			(xy 119.86115 -337.592423) (xy 119.839577 -337.640999) (xy 119.811472 -337.686111) (xy 119.777379 -337.726887)
			(xy 119.737957 -337.762537) (xy 119.69397 -337.792372) (xy 119.670322 -337.804506) (xy 119.661934 -337.808993)
			(xy 119.649064 -337.822989) (xy 119.642159 -337.840705) (xy 119.642163 -337.859718) (xy 119.649076 -337.877431)
			(xy 119.661952 -337.891421) (xy 119.670322 -337.895946) (xy 119.689372 -337.905852) (xy 119.702217 -337.912549)
			(xy 119.730409 -337.919145) (xy 119.75932 -337.917549) (xy 119.786615 -337.907888) (xy 119.810092 -337.890942)
			(xy 119.827858 -337.868078) (xy 119.833644 -337.854798) (xy 119.843838 -337.830961) (xy 119.872375 -337.787689)
			(xy 119.890286 -337.768946) (xy 120.084342 -337.57489) (xy 120.100638 -337.559257) (xy 120.137689 -337.533448)
			(xy 120.158002 -337.523582) (xy 120.167056 -337.49902) (xy 120.190945 -337.452442) (xy 120.220976 -337.409566)
			(xy 120.256586 -337.371196) (xy 120.297105 -337.338054) (xy 120.341774 -337.31076) (xy 120.389754 -337.289828)
			(xy 120.440145 -337.275649) (xy 120.492 -337.268491) (xy 120.518174 -337.268058) (xy 120.518428 -337.268058)
			(xy 120.543632 -337.268443) (xy 120.593601 -337.275086) (xy 120.642255 -337.288267) (xy 120.688745 -337.307754)
			(xy 120.710706 -337.320128) (xy 120.723675 -337.32716) (xy 120.75231 -337.334199) (xy 120.781763 -337.332757)
			(xy 120.809575 -337.322956) (xy 120.833424 -337.305614) (xy 120.85132 -337.282177) (xy 120.85701 -337.268566)
			(xy 120.867268 -337.242865) (xy 120.89413 -337.194487) (xy 120.927695 -337.150493) (xy 120.967257 -337.111805)
			(xy 121.011991 -337.079232) (xy 121.060957 -337.053458) (xy 121.08688 -337.043776) (xy 121.099573 -337.03878)
			(xy 121.121984 -337.023255) (xy 121.139484 -337.002349) (xy 121.150823 -336.977555) (xy 121.155191 -336.950644)
			(xy 121.152276 -336.923537) (xy 121.142287 -336.898169) (xy 121.125937 -336.876353) (xy 121.104393 -336.859645)
			(xy 121.09196 -336.854038) (xy 120.944894 -336.793332) (xy 119.871744 -336.793332) (xy 119.845769 -336.792782)
			(xy 119.794466 -336.784595) (xy 119.745072 -336.768495) (xy 119.6988 -336.744876) (xy 119.656785 -336.714318)
			(xy 119.638064 -336.696304) (xy 119.239792 -336.298032) (xy 119.224733 -336.282496) (xy 119.198392 -336.248171)
			(xy 119.176756 -336.210701) (xy 119.168164 -336.190844) (xy 118.962678 -335.694782) (xy 118.954722 -335.674654)
			(xy 118.943528 -335.632844) (xy 118.937884 -335.589931) (xy 118.937532 -335.56829) (xy 118.937532 -335.287874)
			(xy 118.52148 -334.872076) (xy 118.342918 -334.872076) (xy 118.328371 -334.872546) (xy 118.300469 -334.880793)
			(xy 118.276021 -334.896567) (xy 118.257007 -334.918591) (xy 118.244968 -334.945079) (xy 118.240879 -334.973886)
			(xy 118.245073 -335.002677) (xy 118.250716 -335.016094) (xy 118.261851 -335.041332) (xy 118.277582 -335.094202)
			(xy 118.285533 -335.148787) (xy 118.286022 -335.176368) (xy 118.285536 -335.203619) (xy 118.27778 -335.257567)
			(xy 118.262425 -335.309862) (xy 118.239783 -335.359439) (xy 118.210317 -335.405289) (xy 118.174626 -335.44648)
			(xy 118.133435 -335.482171) (xy 118.087585 -335.511637) (xy 118.038008 -335.534279) (xy 117.985713 -335.549634)
			(xy 117.931765 -335.55739) (xy 117.877263 -335.55739) (xy 117.823315 -335.549634) (xy 117.77102 -335.534279)
			(xy 117.721443 -335.511637) (xy 117.675593 -335.482171) (xy 117.634402 -335.44648) (xy 117.598711 -335.405289)
			(xy 117.569245 -335.359439) (xy 117.546603 -335.309862) (xy 117.531248 -335.257567) (xy 117.523492 -335.203619)
			(xy 117.523006 -335.176368) (xy 117.523006 -335.17586) (xy 117.523612 -335.145418) (xy 117.533308 -335.085312)
			(xy 117.54231 -335.056226) (xy 117.546199 -335.043069) (xy 117.54752 -335.015675) (xy 117.541501 -334.988918)
			(xy 117.528577 -334.964728) (xy 117.509681 -334.94485) (xy 117.486175 -334.93072) (xy 117.459756 -334.923356)
			(xy 117.446044 -334.922876) (xy 113.91773 -334.922876) (xy 113.53546 -335.305146) (xy 113.51387 -335.325863)
			(xy 113.465445 -335.361005) (xy 113.412129 -335.388158) (xy 113.355227 -335.406655) (xy 113.296136 -335.416044)
			(xy 113.26622 -335.416652) (xy 110.821724 -335.416652) (xy 110.791805 -335.41607) (xy 110.732704 -335.406703)
			(xy 110.675794 -335.38821) (xy 110.622475 -335.361048) (xy 110.574059 -335.325883) (xy 110.552484 -335.305146)
			(xy 110.170214 -334.922876) (xy 110.074964 -334.922876) (xy 110.074964 -334.986122) (xy 110.080806 -334.997298)
			(xy 110.094898 -335.025018) (xy 110.114823 -335.08392) (xy 110.124906 -335.145277) (xy 110.12551 -335.176368)
			(xy 110.125024 -335.203619) (xy 110.117268 -335.257567) (xy 110.101913 -335.309862) (xy 110.079271 -335.359439)
			(xy 110.049805 -335.405289) (xy 110.014114 -335.44648) (xy 109.972923 -335.482171) (xy 109.927073 -335.511637)
			(xy 109.877496 -335.534279) (xy 109.825201 -335.549634) (xy 109.771253 -335.55739) (xy 109.716751 -335.55739)
			(xy 109.662803 -335.549634) (xy 109.610508 -335.534279) (xy 109.560931 -335.511637) (xy 109.515081 -335.482171)
			(xy 109.47389 -335.44648) (xy 109.438199 -335.405289) (xy 109.408733 -335.359439) (xy 109.386091 -335.309862)
			(xy 109.370736 -335.257567) (xy 109.36298 -335.203619) (xy 109.362494 -335.176368) (xy 109.362494 -335.17586)
			(xy 109.3631 -335.145418) (xy 109.372796 -335.085312) (xy 109.381798 -335.056226) (xy 109.385698 -335.043072)
			(xy 109.38702 -335.015676) (xy 109.381 -334.988916) (xy 109.368075 -334.964724) (xy 109.349176 -334.944847)
			(xy 109.325667 -334.930717) (xy 109.299245 -334.923355) (xy 109.285532 -334.922876) (xy 105.770172 -334.922876)
			(xy 105.466388 -335.22666) (xy 105.444808 -335.247481) (xy 105.396302 -335.282734) (xy 105.342876 -335.309961)
			(xy 105.285848 -335.328491) (xy 105.226622 -335.337867) (xy 105.19664 -335.33842) (xy 102.628446 -335.33842)
			(xy 102.598469 -335.337807) (xy 102.539255 -335.328423) (xy 102.482237 -335.309894) (xy 102.428818 -335.282676)
			(xy 102.380312 -335.247439) (xy 102.358698 -335.22666) (xy 102.054914 -334.922876) (xy 101.914452 -334.922876)
			(xy 101.914452 -334.986122) (xy 101.920294 -334.997298) (xy 101.934385 -335.025018) (xy 101.95431 -335.08392)
			(xy 101.964394 -335.145277) (xy 101.964998 -335.176368) (xy 101.964512 -335.203619) (xy 101.956756 -335.257567)
			(xy 101.941401 -335.309862) (xy 101.918759 -335.359439) (xy 101.889293 -335.405289) (xy 101.853602 -335.44648)
			(xy 101.812411 -335.482171) (xy 101.766561 -335.511637) (xy 101.716984 -335.534279) (xy 101.664689 -335.549634)
			(xy 101.610741 -335.55739) (xy 101.556239 -335.55739) (xy 101.502291 -335.549634) (xy 101.449996 -335.534279)
			(xy 101.400419 -335.511637) (xy 101.354569 -335.482171) (xy 101.313378 -335.44648) (xy 101.277687 -335.405289)
			(xy 101.248221 -335.359439) (xy 101.225579 -335.309862) (xy 101.210224 -335.257567) (xy 101.202468 -335.203619)
			(xy 101.201982 -335.176368) (xy 101.201982 -335.17586) (xy 101.202588 -335.145418) (xy 101.212284 -335.085312)
			(xy 101.221286 -335.056226) (xy 101.225198 -335.043075) (xy 101.22652 -335.015676) (xy 101.2205 -334.988914)
			(xy 101.207572 -334.964721) (xy 101.188671 -334.944843) (xy 101.165159 -334.930713) (xy 101.138734 -334.923354)
			(xy 101.12502 -334.922876) (xy 97.58045 -334.922876) (xy 97.19818 -335.305146) (xy 97.176581 -335.325854)
			(xy 97.128159 -335.360997) (xy 97.074844 -335.388151) (xy 97.017945 -335.406651) (xy 96.958855 -335.416043)
			(xy 96.92894 -335.416652) (xy 94.867476 -335.416652) (xy 94.705198 -335.579) (xy 97.290117 -335.579)
			(xy 97.294285 -335.523384) (xy 97.306694 -335.469011) (xy 97.327068 -335.417094) (xy 97.354952 -335.368793)
			(xy 97.389723 -335.325188) (xy 97.430604 -335.287251) (xy 97.476682 -335.25583) (xy 97.526928 -335.231627)
			(xy 97.580221 -335.215183) (xy 97.635368 -335.206864) (xy 97.663254 -335.20634) (xy 97.690586 -335.206812)
			(xy 97.744666 -335.214781) (xy 97.797 -335.230569) (xy 97.846465 -335.253837) (xy 97.891997 -335.284084)
			(xy 97.932619 -335.320663) (xy 97.967459 -335.362786) (xy 97.982024 -335.385918) (xy 97.989942 -335.398145)
			(xy 98.011416 -335.417814) (xy 98.03757 -335.430618) (xy 98.066276 -335.435512) (xy 98.095196 -335.4321)
			(xy 98.10877 -335.426812) (xy 98.131987 -335.41734) (xy 98.180316 -335.403982) (xy 98.230003 -335.397247)
			(xy 98.255074 -335.39684) (xy 98.280144 -335.397251) (xy 98.329827 -335.404006) (xy 98.378161 -335.417343)
			(xy 98.401378 -335.426812) (xy 98.414951 -335.43207) (xy 98.443854 -335.435432) (xy 98.472533 -335.430519)
			(xy 98.498669 -335.417728) (xy 98.520144 -335.398094) (xy 98.528124 -335.385918) (xy 98.542693 -335.362787)
			(xy 98.577536 -335.320666) (xy 98.618159 -335.284087) (xy 98.66369 -335.253836) (xy 98.713152 -335.23056)
			(xy 98.765483 -335.21476) (xy 98.819562 -335.206774) (xy 98.874226 -335.206774) (xy 98.928305 -335.21476)
			(xy 98.980636 -335.23056) (xy 99.030098 -335.253836) (xy 99.075629 -335.284087) (xy 99.116252 -335.320666)
			(xy 99.151095 -335.362787) (xy 99.165664 -335.385918) (xy 99.173544 -335.398173) (xy 99.195028 -335.417842)
			(xy 99.221193 -335.430641) (xy 99.249908 -335.435529) (xy 99.278834 -335.432106) (xy 99.29241 -335.426812)
			(xy 99.315622 -335.417328) (xy 99.363954 -335.403974) (xy 99.413643 -335.397244) (xy 99.438714 -335.39684)
			(xy 99.465556 -335.397321) (xy 99.518683 -335.405026) (xy 99.570155 -335.420275) (xy 99.618906 -335.442752)
			(xy 99.663928 -335.471992) (xy 99.704287 -335.50739) (xy 99.73915 -335.548213) (xy 99.767794 -335.593616)
			(xy 99.789627 -335.642659) (xy 99.797362 -335.668366) (xy 99.802083 -335.682841) (xy 99.818592 -335.708398)
			(xy 99.841895 -335.72796) (xy 99.869926 -335.739792) (xy 99.900198 -335.742845) (xy 99.930026 -335.736849)
			(xy 99.943666 -335.730088) (xy 99.97181 -335.715451) (xy 100.031762 -335.694725) (xy 100.094321 -335.684228)
			(xy 100.126038 -335.683606) (xy 100.144057 -335.683825) (xy 100.179932 -335.687261) (xy 100.197666 -335.690464)
			(xy 100.212879 -335.692764) (xy 100.243427 -335.689245) (xy 100.271544 -335.676793) (xy 100.294679 -335.656537)
			(xy 100.310737 -335.630312) (xy 100.315014 -335.615534) (xy 100.3224 -335.588487) (xy 100.344032 -335.536761)
			(xy 100.372998 -335.488756) (xy 100.408676 -335.445505) (xy 100.450296 -335.407938) (xy 100.496965 -335.376865)
			(xy 100.547677 -335.352952) (xy 100.601342 -335.336716) (xy 100.656805 -335.328505) (xy 100.684838 -335.328006)
			(xy 100.712091 -335.328443) (xy 100.766041 -335.336205) (xy 100.818338 -335.351565) (xy 100.867916 -335.374212)
			(xy 100.913767 -335.403683) (xy 100.954957 -335.43938) (xy 100.990648 -335.480575) (xy 101.020113 -335.52643)
			(xy 101.042753 -335.576011) (xy 101.043631 -335.579) (xy 105.450617 -335.579) (xy 105.454785 -335.523383)
			(xy 105.467195 -335.469009) (xy 105.48757 -335.417091) (xy 105.515455 -335.36879) (xy 105.550227 -335.325183)
			(xy 105.591109 -335.287246) (xy 105.637189 -335.255826) (xy 105.687437 -335.231624) (xy 105.740731 -335.21518)
			(xy 105.79588 -335.206863) (xy 105.823766 -335.20634) (xy 105.851098 -335.206803) (xy 105.905179 -335.214774)
			(xy 105.957513 -335.230563) (xy 106.006978 -335.253832) (xy 106.05251 -335.284081) (xy 106.093132 -335.320661)
			(xy 106.127971 -335.362785) (xy 106.142536 -335.385918) (xy 106.150443 -335.398154) (xy 106.17192 -335.417823)
			(xy 106.198077 -335.430625) (xy 106.226786 -335.435517) (xy 106.255707 -335.432101) (xy 106.269282 -335.426812)
			(xy 106.292497 -335.417336) (xy 106.340827 -335.40398) (xy 106.390515 -335.397246) (xy 106.415586 -335.39684)
			(xy 106.440655 -335.397279) (xy 106.490337 -335.404022) (xy 106.538672 -335.417349) (xy 106.56189 -335.426812)
			(xy 106.575495 -335.431977) (xy 106.604381 -335.435359) (xy 106.63305 -335.430467) (xy 106.65918 -335.417697)
			(xy 106.680654 -335.398084) (xy 106.688636 -335.385918) (xy 106.703205 -335.362787) (xy 106.738048 -335.320666)
			(xy 106.778671 -335.284087) (xy 106.824202 -335.253836) (xy 106.873664 -335.23056) (xy 106.925995 -335.21476)
			(xy 106.980074 -335.206774) (xy 107.034738 -335.206774) (xy 107.088817 -335.21476) (xy 107.141148 -335.23056)
			(xy 107.19061 -335.253836) (xy 107.236141 -335.284087) (xy 107.276764 -335.320666) (xy 107.311607 -335.362787)
			(xy 107.326176 -335.385918) (xy 107.33414 -335.398113) (xy 107.355601 -335.417782) (xy 107.381743 -335.430589)
			(xy 107.410438 -335.435492) (xy 107.43935 -335.432092) (xy 107.452922 -335.426812) (xy 107.476132 -335.417324)
			(xy 107.524465 -335.403972) (xy 107.574154 -335.397244) (xy 107.599226 -335.39684) (xy 107.626068 -335.39731)
			(xy 107.679196 -335.405017) (xy 107.730668 -335.420268) (xy 107.779419 -335.442746) (xy 107.824441 -335.471988)
			(xy 107.8648 -335.507387) (xy 107.899663 -335.548211) (xy 107.928307 -335.593614) (xy 107.950139 -335.642658)
			(xy 107.957874 -335.668366) (xy 107.962579 -335.682847) (xy 107.979091 -335.708406) (xy 108.002398 -335.727968)
			(xy 108.030432 -335.7398) (xy 108.060707 -335.742851) (xy 108.090538 -335.736851) (xy 108.104178 -335.730088)
			(xy 108.13232 -335.715447) (xy 108.192273 -335.694722) (xy 108.254833 -335.684227) (xy 108.28655 -335.683606)
			(xy 108.304569 -335.683824) (xy 108.340444 -335.68726) (xy 108.358178 -335.690464) (xy 108.37339 -335.692776)
			(xy 108.403939 -335.689254) (xy 108.432056 -335.676799) (xy 108.455192 -335.65654) (xy 108.471249 -335.630313)
			(xy 108.475526 -335.615534) (xy 108.482901 -335.588483) (xy 108.504534 -335.536757) (xy 108.533502 -335.488751)
			(xy 108.56918 -335.4455) (xy 108.610802 -335.407934) (xy 108.657472 -335.37686) (xy 108.708186 -335.352949)
			(xy 108.761852 -335.336714) (xy 108.817316 -335.328504) (xy 108.84535 -335.328006) (xy 108.872602 -335.328502)
			(xy 108.926553 -335.336252) (xy 108.978851 -335.351603) (xy 109.028432 -335.37424) (xy 109.074286 -335.403705)
			(xy 109.115479 -335.439395) (xy 109.151174 -335.480585) (xy 109.180642 -335.526437) (xy 109.203285 -335.576015)
			(xy 109.204161 -335.579) (xy 113.611117 -335.579) (xy 113.615285 -335.523382) (xy 113.627696 -335.469007)
			(xy 113.648071 -335.417088) (xy 113.675957 -335.368786) (xy 113.710731 -335.325179) (xy 113.751615 -335.287242)
			(xy 113.797696 -335.255822) (xy 113.847945 -335.23162) (xy 113.901241 -335.215178) (xy 113.956391 -335.206863)
			(xy 113.984278 -335.20634) (xy 114.011611 -335.206794) (xy 114.065691 -335.214766) (xy 114.118026 -335.230557)
			(xy 114.167491 -335.253828) (xy 114.213023 -335.284078) (xy 114.253644 -335.320659) (xy 114.288483 -335.362784)
			(xy 114.303048 -335.385918) (xy 114.310943 -335.398162) (xy 114.332423 -335.417831) (xy 114.358584 -335.430632)
			(xy 114.387295 -335.435522) (xy 114.416219 -335.432103) (xy 114.429794 -335.426812) (xy 114.453008 -335.417333)
			(xy 114.501339 -335.403978) (xy 114.551027 -335.397245) (xy 114.576098 -335.39684) (xy 114.601167 -335.397276)
			(xy 114.65085 -335.40402) (xy 114.699184 -335.417348) (xy 114.722402 -335.426812) (xy 114.736003 -335.43199)
			(xy 114.764891 -335.435369) (xy 114.793561 -335.430474) (xy 114.819692 -335.417701) (xy 114.841166 -335.398085)
			(xy 114.849148 -335.385918) (xy 114.863717 -335.362787) (xy 114.89856 -335.320666) (xy 114.939183 -335.284087)
			(xy 114.984714 -335.253836) (xy 115.034176 -335.23056) (xy 115.086507 -335.21476) (xy 115.140586 -335.206774)
			(xy 115.19525 -335.206774) (xy 115.249329 -335.21476) (xy 115.30166 -335.23056) (xy 115.351122 -335.253836)
			(xy 115.396653 -335.284087) (xy 115.437276 -335.320666) (xy 115.472119 -335.362787) (xy 115.486688 -335.385918)
			(xy 115.49464 -335.398121) (xy 115.516105 -335.41779) (xy 115.54225 -335.430596) (xy 115.570948 -335.435497)
			(xy 115.599861 -335.432094) (xy 115.613434 -335.426812) (xy 115.636643 -335.41732) (xy 115.684976 -335.40397)
			(xy 115.734666 -335.397243) (xy 115.759738 -335.39684) (xy 115.78658 -335.3973) (xy 115.839709 -335.405008)
			(xy 115.891181 -335.420261) (xy 115.939933 -335.442741) (xy 115.984954 -335.471983) (xy 116.025313 -335.507383)
			(xy 116.060175 -335.548208) (xy 116.088819 -335.593613) (xy 116.110651 -335.642658) (xy 116.118386 -335.668366)
			(xy 116.123076 -335.682853) (xy 116.13959 -335.708413) (xy 116.1629 -335.727976) (xy 116.190938 -335.739807)
			(xy 116.221216 -335.742856) (xy 116.251049 -335.736853) (xy 116.26469 -335.730088) (xy 116.29283 -335.715442)
			(xy 116.352784 -335.69472) (xy 116.415345 -335.684226) (xy 116.447062 -335.683606) (xy 116.465081 -335.683822)
			(xy 116.500956 -335.687259) (xy 116.51869 -335.690464) (xy 116.5339 -335.692788) (xy 116.564451 -335.689263)
			(xy 116.592569 -335.676805) (xy 116.615704 -335.656543) (xy 116.631761 -335.630314) (xy 116.636038 -335.615534)
			(xy 116.643402 -335.58848) (xy 116.665036 -335.536753) (xy 116.694005 -335.488747) (xy 116.729685 -335.445495)
			(xy 116.771308 -335.407929) (xy 116.81798 -335.376856) (xy 116.868695 -335.352946) (xy 116.922362 -335.336711)
			(xy 116.977827 -335.328503) (xy 117.005862 -335.328006) (xy 117.033115 -335.328491) (xy 117.087065 -335.336243)
			(xy 117.139364 -335.351595) (xy 117.188945 -335.374234) (xy 117.234799 -335.403699) (xy 117.275992 -335.439391)
			(xy 117.311686 -335.480582) (xy 117.341155 -335.526434) (xy 117.363797 -335.576014) (xy 117.379152 -335.628311)
			(xy 117.386908 -335.682261) (xy 117.38737 -335.709514) (xy 117.386856 -335.737087) (xy 117.378914 -335.791658)
			(xy 117.3632 -335.844517) (xy 117.340039 -335.894564) (xy 117.309915 -335.940755) (xy 117.273454 -335.982127)
			(xy 117.25275 -336.000344) (xy 117.241835 -336.010226) (xy 117.225755 -336.034879) (xy 117.217369 -336.063092)
			(xy 117.217371 -336.092526) (xy 117.225763 -336.120737) (xy 117.241847 -336.145388) (xy 117.25275 -336.155284)
			(xy 117.273472 -336.173483) (xy 117.30994 -336.214855) (xy 117.34007 -336.261046) (xy 117.363235 -336.311095)
			(xy 117.378951 -336.363959) (xy 117.386892 -336.418534) (xy 117.38689 -336.473684) (xy 117.378947 -336.528259)
			(xy 117.363229 -336.581121) (xy 117.340061 -336.631169) (xy 117.331207 -336.644742) (xy 118.31396 -336.644742)
			(xy 118.318031 -336.58912) (xy 118.330157 -336.534683) (xy 118.35008 -336.482592) (xy 118.377376 -336.433957)
			(xy 118.411462 -336.389814) (xy 118.451611 -336.351105) (xy 118.496969 -336.318654) (xy 118.546569 -336.293153)
			(xy 118.599353 -336.275146) (xy 118.654196 -336.265016) (xy 118.70993 -336.262979) (xy 118.765367 -336.269079)
			(xy 118.819324 -336.283185) (xy 118.870653 -336.304997) (xy 118.918259 -336.334051) (xy 118.961127 -336.369726)
			(xy 118.998344 -336.411263) (xy 119.029117 -336.457776) (xy 119.052789 -336.508273) (xy 119.068857 -336.56168)
			(xy 119.076977 -336.616856) (xy 119.077486 -336.644742) (xy 119.076977 -336.672628) (xy 119.068857 -336.727804)
			(xy 119.052789 -336.781211) (xy 119.029117 -336.831708) (xy 118.998344 -336.878221) (xy 118.961127 -336.919758)
			(xy 118.918259 -336.955433) (xy 118.870653 -336.984487) (xy 118.819324 -337.006299) (xy 118.765367 -337.020405)
			(xy 118.70993 -337.026505) (xy 118.654196 -337.024468) (xy 118.599353 -337.014338) (xy 118.546569 -336.996331)
			(xy 118.496969 -336.97083) (xy 118.451611 -336.938379) (xy 118.411462 -336.89967) (xy 118.377376 -336.855527)
			(xy 118.35008 -336.806892) (xy 118.330157 -336.754801) (xy 118.318031 -336.700364) (xy 118.31396 -336.644742)
			(xy 117.331207 -336.644742) (xy 117.309929 -336.67736) (xy 117.273459 -336.71873) (xy 117.25275 -336.736944)
			(xy 117.241835 -336.746826) (xy 117.225755 -336.771479) (xy 117.217369 -336.799692) (xy 117.217371 -336.829126)
			(xy 117.225763 -336.857337) (xy 117.241847 -336.881988) (xy 117.25275 -336.891884) (xy 117.273467 -336.910089)
			(xy 117.309934 -336.95146) (xy 117.340065 -336.997652) (xy 117.363229 -337.047701) (xy 117.378945 -337.100564)
			(xy 117.386884 -337.155139) (xy 117.38737 -337.182714) (xy 117.386958 -337.209969) (xy 117.379845 -337.259422)
			(xy 117.522496 -337.259422) (xy 117.526567 -337.2038) (xy 117.538693 -337.149363) (xy 117.558616 -337.097272)
			(xy 117.585912 -337.048637) (xy 117.619998 -337.004494) (xy 117.660147 -336.965785) (xy 117.705505 -336.933334)
			(xy 117.755105 -336.907833) (xy 117.807889 -336.889826) (xy 117.862732 -336.879696) (xy 117.918466 -336.877659)
			(xy 117.973903 -336.883759) (xy 118.02786 -336.897865) (xy 118.079189 -336.919677) (xy 118.126795 -336.948731)
			(xy 118.169663 -336.984406) (xy 118.20688 -337.025943) (xy 118.237653 -337.072456) (xy 118.261325 -337.122953)
			(xy 118.277393 -337.17636) (xy 118.285513 -337.231536) (xy 118.286022 -337.259422) (xy 118.285513 -337.287308)
			(xy 118.277393 -337.342484) (xy 118.261325 -337.395891) (xy 118.237653 -337.446388) (xy 118.20688 -337.492901)
			(xy 118.169663 -337.534438) (xy 118.126795 -337.570113) (xy 118.079189 -337.599167) (xy 118.02786 -337.620979)
			(xy 117.973903 -337.635085) (xy 117.918466 -337.641185) (xy 117.862732 -337.639148) (xy 117.807889 -337.629018)
			(xy 117.755105 -337.611011) (xy 117.705505 -337.58551) (xy 117.660147 -337.553059) (xy 117.619998 -337.51435)
			(xy 117.585912 -337.470207) (xy 117.558616 -337.421572) (xy 117.538693 -337.369481) (xy 117.526567 -337.315044)
			(xy 117.522496 -337.259422) (xy 117.379845 -337.259422) (xy 117.379198 -337.263924) (xy 117.363838 -337.316225)
			(xy 117.341192 -337.365808) (xy 117.311718 -337.411663) (xy 117.276019 -337.452856) (xy 117.234821 -337.48855)
			(xy 117.188962 -337.518016) (xy 117.139376 -337.540657) (xy 117.087073 -337.556009) (xy 117.033117 -337.563762)
			(xy 117.005862 -337.564222) (xy 116.978006 -337.563717) (xy 116.922891 -337.555588) (xy 116.869541 -337.539539)
			(xy 116.819089 -337.515909) (xy 116.772605 -337.4852) (xy 116.731076 -337.448063) (xy 116.695383 -337.405287)
			(xy 116.666284 -337.357779) (xy 116.644395 -337.306547) (xy 116.6368 -337.279742) (xy 116.632472 -337.265645)
			(xy 116.617096 -337.240501) (xy 116.595191 -337.220783) (xy 116.568575 -337.208127) (xy 116.539455 -337.203582)
			(xy 116.524786 -337.205066) (xy 116.511769 -337.206735) (xy 116.485585 -337.208515) (xy 116.472462 -337.208622)
			(xy 116.458313 -337.208532) (xy 116.43009 -337.206495) (xy 116.416074 -337.204558) (xy 116.402721 -337.203043)
			(xy 116.376039 -337.206134) (xy 116.351092 -337.216091) (xy 116.329615 -337.232222) (xy 116.313101 -337.253406)
			(xy 116.302698 -337.27817) (xy 116.300504 -337.291426) (xy 116.296414 -337.318579) (xy 116.281442 -337.37141)
			(xy 116.259052 -337.42155) (xy 116.229705 -337.467961) (xy 116.194009 -337.509686) (xy 116.152699 -337.545863)
			(xy 116.106629 -337.575744) (xy 116.056752 -337.598712) (xy 116.004098 -337.614293) (xy 115.949754 -337.622165)
			(xy 115.922298 -337.622642) (xy 115.895048 -337.622124) (xy 115.841103 -337.614368) (xy 115.788811 -337.599015)
			(xy 115.739236 -337.576376) (xy 115.693388 -337.546912) (xy 115.652198 -337.511224) (xy 115.616507 -337.470038)
			(xy 115.58704 -337.424192) (xy 115.564397 -337.374619) (xy 115.549039 -337.322328) (xy 115.541278 -337.268384)
			(xy 115.54079 -337.241134) (xy 115.541283 -337.21356) (xy 115.54923 -337.158989) (xy 115.56495 -337.10613)
			(xy 115.588115 -337.056084) (xy 115.618243 -337.009893) (xy 115.654705 -336.968521) (xy 115.67541 -336.950304)
			(xy 115.686272 -336.94037) (xy 115.702343 -336.915729) (xy 115.71073 -336.887531) (xy 115.710736 -336.858113)
			(xy 115.702362 -336.829911) (xy 115.686301 -336.805263) (xy 115.67541 -336.795364) (xy 115.65468 -336.777173)
			(xy 115.618211 -336.7358) (xy 115.588081 -336.689606) (xy 115.564918 -336.639554) (xy 115.549206 -336.586688)
			(xy 115.541272 -336.53211) (xy 115.54079 -336.504534) (xy 115.541227 -336.478032) (xy 115.548576 -336.425541)
			(xy 115.563125 -336.374573) (xy 115.584592 -336.326111) (xy 115.612563 -336.281089) (xy 115.629182 -336.26044)
			(xy 115.638623 -336.248295) (xy 115.650406 -336.219894) (xy 115.653226 -336.189276) (xy 115.646829 -336.159201)
			(xy 115.631793 -336.13238) (xy 115.609472 -336.111232) (xy 115.595908 -336.103976) (xy 115.572209 -336.091892)
			(xy 115.528229 -336.061964) (xy 115.48895 -336.026088) (xy 115.45517 -335.984993) (xy 115.440968 -335.962498)
			(xy 115.433053 -335.950267) (xy 115.41158 -335.930597) (xy 115.385424 -335.917793) (xy 115.356717 -335.912899)
			(xy 115.327796 -335.916314) (xy 115.314222 -335.921604) (xy 115.291007 -335.931079) (xy 115.242677 -335.944436)
			(xy 115.192989 -335.95117) (xy 115.167918 -335.951576) (xy 115.142849 -335.951134) (xy 115.093167 -335.944392)
			(xy 115.044832 -335.931067) (xy 115.021614 -335.921604) (xy 115.008009 -335.916436) (xy 114.979123 -335.913053)
			(xy 114.950453 -335.917945) (xy 114.924323 -335.930716) (xy 114.902849 -335.950331) (xy 114.894868 -335.962498)
			(xy 114.880299 -335.985629) (xy 114.845456 -336.02775) (xy 114.804833 -336.064329) (xy 114.759302 -336.09458)
			(xy 114.70984 -336.117856) (xy 114.657509 -336.133656) (xy 114.60343 -336.141642) (xy 114.548766 -336.141642)
			(xy 114.494687 -336.133656) (xy 114.442356 -336.117856) (xy 114.392894 -336.09458) (xy 114.347363 -336.064329)
			(xy 114.30674 -336.02775) (xy 114.271897 -335.985629) (xy 114.257328 -335.962498) (xy 114.249451 -335.95024)
			(xy 114.227967 -335.930569) (xy 114.201801 -335.917769) (xy 114.173085 -335.912883) (xy 114.144158 -335.916308)
			(xy 114.130582 -335.921604) (xy 114.107371 -335.931092) (xy 114.059039 -335.944443) (xy 114.00935 -335.951172)
			(xy 113.984278 -335.951576) (xy 113.956391 -335.951137) (xy 113.901241 -335.942822) (xy 113.847945 -335.92638)
			(xy 113.797696 -335.902178) (xy 113.751615 -335.870758) (xy 113.710731 -335.832821) (xy 113.675957 -335.789214)
			(xy 113.648071 -335.740912) (xy 113.627696 -335.688993) (xy 113.615285 -335.634618) (xy 113.611117 -335.579)
			(xy 109.204161 -335.579) (xy 109.21864 -335.628312) (xy 109.226396 -335.682262) (xy 109.226858 -335.709514)
			(xy 109.226348 -335.737087) (xy 109.218406 -335.791659) (xy 109.202691 -335.844518) (xy 109.17953 -335.894565)
			(xy 109.149404 -335.940755) (xy 109.112943 -335.982128) (xy 109.092238 -336.000344) (xy 109.081324 -336.010227)
			(xy 109.065246 -336.03488) (xy 109.056861 -336.063093) (xy 109.056864 -336.092525) (xy 109.065254 -336.120737)
			(xy 109.081336 -336.145387) (xy 109.092238 -336.155284) (xy 109.11296 -336.173483) (xy 109.149429 -336.214854)
			(xy 109.179561 -336.261046) (xy 109.202726 -336.311095) (xy 109.218443 -336.363958) (xy 109.226384 -336.418534)
			(xy 109.226383 -336.473684) (xy 109.218439 -336.52826) (xy 109.20272 -336.581122) (xy 109.179552 -336.63117)
			(xy 109.170698 -336.644742) (xy 110.153448 -336.644742) (xy 110.157519 -336.58912) (xy 110.169645 -336.534683)
			(xy 110.189568 -336.482592) (xy 110.216864 -336.433957) (xy 110.25095 -336.389814) (xy 110.291099 -336.351105)
			(xy 110.336457 -336.318654) (xy 110.386057 -336.293153) (xy 110.438841 -336.275146) (xy 110.493684 -336.265016)
			(xy 110.549418 -336.262979) (xy 110.604855 -336.269079) (xy 110.658812 -336.283185) (xy 110.710141 -336.304997)
			(xy 110.757747 -336.334051) (xy 110.800615 -336.369726) (xy 110.837832 -336.411263) (xy 110.868605 -336.457776)
			(xy 110.892277 -336.508273) (xy 110.908345 -336.56168) (xy 110.916465 -336.616856) (xy 110.916974 -336.644742)
			(xy 110.916465 -336.672628) (xy 110.908345 -336.727804) (xy 110.892277 -336.781211) (xy 110.868605 -336.831708)
			(xy 110.837832 -336.878221) (xy 110.800615 -336.919758) (xy 110.757747 -336.955433) (xy 110.710141 -336.984487)
			(xy 110.658812 -337.006299) (xy 110.604855 -337.020405) (xy 110.549418 -337.026505) (xy 110.493684 -337.024468)
			(xy 110.438841 -337.014338) (xy 110.386057 -336.996331) (xy 110.336457 -336.97083) (xy 110.291099 -336.938379)
			(xy 110.25095 -336.89967) (xy 110.216864 -336.855527) (xy 110.189568 -336.806892) (xy 110.169645 -336.754801)
			(xy 110.157519 -336.700364) (xy 110.153448 -336.644742) (xy 109.170698 -336.644742) (xy 109.149418 -336.677361)
			(xy 109.112947 -336.71873) (xy 109.092238 -336.736944) (xy 109.081324 -336.746827) (xy 109.065246 -336.77148)
			(xy 109.056861 -336.799693) (xy 109.056864 -336.829125) (xy 109.065254 -336.857337) (xy 109.081336 -336.881987)
			(xy 109.092238 -336.891884) (xy 109.112952 -336.910092) (xy 109.149421 -336.951462) (xy 109.179551 -336.997653)
			(xy 109.202716 -337.047702) (xy 109.218433 -337.100564) (xy 109.226372 -337.155139) (xy 109.226858 -337.182714)
			(xy 109.226458 -337.20997) (xy 109.218698 -337.263925) (xy 109.216141 -337.27263) (xy 109.505494 -337.27263)
			(xy 109.509565 -337.217008) (xy 109.521691 -337.162571) (xy 109.541614 -337.11048) (xy 109.56891 -337.061845)
			(xy 109.602996 -337.017702) (xy 109.643145 -336.978993) (xy 109.688503 -336.946542) (xy 109.738103 -336.921041)
			(xy 109.790887 -336.903034) (xy 109.84573 -336.892904) (xy 109.901464 -336.890867) (xy 109.956901 -336.896967)
			(xy 110.010858 -336.911073) (xy 110.062187 -336.932885) (xy 110.109793 -336.961939) (xy 110.152661 -336.997614)
			(xy 110.189878 -337.039151) (xy 110.220651 -337.085664) (xy 110.244323 -337.136161) (xy 110.260391 -337.189568)
			(xy 110.268511 -337.244744) (xy 110.26902 -337.27263) (xy 110.268511 -337.300516) (xy 110.260391 -337.355692)
			(xy 110.244323 -337.409099) (xy 110.220651 -337.459596) (xy 110.189878 -337.506109) (xy 110.152661 -337.547646)
			(xy 110.109793 -337.583321) (xy 110.062187 -337.612375) (xy 110.010858 -337.634187) (xy 109.956901 -337.648293)
			(xy 109.901464 -337.654393) (xy 109.84573 -337.652356) (xy 109.790887 -337.642226) (xy 109.738103 -337.624219)
			(xy 109.688503 -337.598718) (xy 109.643145 -337.566267) (xy 109.602996 -337.527558) (xy 109.56891 -337.483415)
			(xy 109.541614 -337.43478) (xy 109.521691 -337.382689) (xy 109.509565 -337.328252) (xy 109.505494 -337.27263)
			(xy 109.216141 -337.27263) (xy 109.203337 -337.316227) (xy 109.18069 -337.365811) (xy 109.151216 -337.411667)
			(xy 109.115515 -337.45286) (xy 109.074315 -337.488554) (xy 109.028455 -337.51802) (xy 108.978867 -337.54066)
			(xy 108.926563 -337.556011) (xy 108.872606 -337.563763) (xy 108.84535 -337.564222) (xy 108.817494 -337.563728)
			(xy 108.762378 -337.555598) (xy 108.709028 -337.539546) (xy 108.658576 -337.515915) (xy 108.612092 -337.485204)
			(xy 108.570563 -337.448066) (xy 108.534871 -337.405289) (xy 108.505771 -337.35778) (xy 108.483883 -337.306548)
			(xy 108.476288 -337.279742) (xy 108.471972 -337.26564) (xy 108.456594 -337.240496) (xy 108.434686 -337.220778)
			(xy 108.408067 -337.208123) (xy 108.378944 -337.20358) (xy 108.364274 -337.205066) (xy 108.351258 -337.206736)
			(xy 108.325073 -337.208515) (xy 108.31195 -337.208622) (xy 108.297801 -337.208523) (xy 108.269578 -337.206492)
			(xy 108.255562 -337.204558) (xy 108.24221 -337.203031) (xy 108.215527 -337.206124) (xy 108.19058 -337.216084)
			(xy 108.169103 -337.232218) (xy 108.152589 -337.253404) (xy 108.142186 -337.278169) (xy 108.139992 -337.291426)
			(xy 108.135913 -337.318581) (xy 108.120941 -337.371413) (xy 108.09855 -337.421553) (xy 108.069202 -337.467965)
			(xy 108.033504 -337.509691) (xy 107.992193 -337.545867) (xy 107.946122 -337.575748) (xy 107.896244 -337.598716)
			(xy 107.843588 -337.614295) (xy 107.789242 -337.622166) (xy 107.761786 -337.622642) (xy 107.734536 -337.622135)
			(xy 107.680591 -337.614378) (xy 107.628298 -337.599023) (xy 107.578723 -337.576382) (xy 107.532875 -337.546918)
			(xy 107.491686 -337.511229) (xy 107.455994 -337.470041) (xy 107.426527 -337.424194) (xy 107.403884 -337.37462)
			(xy 107.388526 -337.322329) (xy 107.380766 -337.268384) (xy 107.380278 -337.241134) (xy 107.380775 -337.213561)
			(xy 107.388722 -337.15899) (xy 107.404441 -337.106131) (xy 107.427606 -337.056085) (xy 107.457732 -337.009894)
			(xy 107.494194 -336.968521) (xy 107.514898 -336.950304) (xy 107.525761 -336.940371) (xy 107.541834 -336.91573)
			(xy 107.550222 -336.887532) (xy 107.550228 -336.858112) (xy 107.541853 -336.82991) (xy 107.52579 -336.805262)
			(xy 107.514898 -336.795364) (xy 107.494166 -336.777176) (xy 107.457697 -336.735802) (xy 107.427568 -336.689607)
			(xy 107.404406 -336.639555) (xy 107.388694 -336.586688) (xy 107.38076 -336.53211) (xy 107.380278 -336.504534)
			(xy 107.380717 -336.478032) (xy 107.388067 -336.425541) (xy 107.402615 -336.374573) (xy 107.424081 -336.326111)
			(xy 107.452052 -336.281089) (xy 107.46867 -336.26044) (xy 107.478115 -336.248298) (xy 107.489899 -336.219896)
			(xy 107.49272 -336.189276) (xy 107.486322 -336.1592) (xy 107.471284 -336.132379) (xy 107.448961 -336.111232)
			(xy 107.435396 -336.103976) (xy 107.411695 -336.091896) (xy 107.367716 -336.061966) (xy 107.328437 -336.026089)
			(xy 107.294658 -335.984993) (xy 107.280456 -335.962498) (xy 107.272553 -335.950259) (xy 107.251076 -335.930588)
			(xy 107.224917 -335.917786) (xy 107.196207 -335.912894) (xy 107.167285 -335.916313) (xy 107.15371 -335.921604)
			(xy 107.130496 -335.931083) (xy 107.082165 -335.944438) (xy 107.032477 -335.95117) (xy 107.007406 -335.951576)
			(xy 106.982337 -335.951138) (xy 106.932655 -335.944394) (xy 106.88432 -335.931067) (xy 106.861102 -335.921604)
			(xy 106.847502 -335.916424) (xy 106.818613 -335.913043) (xy 106.789942 -335.917938) (xy 106.763811 -335.930712)
			(xy 106.742337 -335.95033) (xy 106.734356 -335.962498) (xy 106.719787 -335.985629) (xy 106.684944 -336.02775)
			(xy 106.644321 -336.064329) (xy 106.59879 -336.09458) (xy 106.549328 -336.117856) (xy 106.496997 -336.133656)
			(xy 106.442918 -336.141642) (xy 106.388254 -336.141642) (xy 106.334175 -336.133656) (xy 106.281844 -336.117856)
			(xy 106.232382 -336.09458) (xy 106.186851 -336.064329) (xy 106.146228 -336.02775) (xy 106.111385 -335.985629)
			(xy 106.096816 -335.962498) (xy 106.088856 -335.9503) (xy 106.067395 -335.930629) (xy 106.041251 -335.917821)
			(xy 106.012555 -335.912919) (xy 105.983642 -335.916322) (xy 105.97007 -335.921604) (xy 105.946861 -335.931095)
			(xy 105.898528 -335.944446) (xy 105.848838 -335.951173) (xy 105.823766 -335.951576) (xy 105.79588 -335.951137)
			(xy 105.740731 -335.94282) (xy 105.687437 -335.926376) (xy 105.637189 -335.902174) (xy 105.591109 -335.870754)
			(xy 105.550227 -335.832817) (xy 105.515455 -335.78921) (xy 105.48757 -335.740909) (xy 105.467195 -335.688991)
			(xy 105.454785 -335.634617) (xy 105.450617 -335.579) (xy 101.043631 -335.579) (xy 101.058107 -335.62831)
			(xy 101.065861 -335.682261) (xy 101.066346 -335.709514) (xy 101.06584 -335.737087) (xy 101.057898 -335.791659)
			(xy 101.042183 -335.844519) (xy 101.01902 -335.894566) (xy 100.988894 -335.940756) (xy 100.952431 -335.982128)
			(xy 100.931726 -336.000344) (xy 100.920813 -336.010227) (xy 100.904737 -336.034881) (xy 100.896353 -336.063093)
			(xy 100.896356 -336.092525) (xy 100.904745 -336.120736) (xy 100.920825 -336.145386) (xy 100.931726 -336.155284)
			(xy 100.952444 -336.173485) (xy 100.988906 -336.214859) (xy 101.01903 -336.261052) (xy 101.04219 -336.311101)
			(xy 101.057903 -336.363962) (xy 101.065842 -336.418535) (xy 101.06584 -336.473683) (xy 101.057899 -336.528256)
			(xy 101.042184 -336.581116) (xy 101.019021 -336.631164) (xy 101.010165 -336.644742) (xy 101.992936 -336.644742)
			(xy 101.997007 -336.58912) (xy 102.009133 -336.534683) (xy 102.029056 -336.482592) (xy 102.056352 -336.433957)
			(xy 102.090438 -336.389814) (xy 102.130587 -336.351105) (xy 102.175945 -336.318654) (xy 102.225545 -336.293153)
			(xy 102.278329 -336.275146) (xy 102.333172 -336.265016) (xy 102.388906 -336.262979) (xy 102.444343 -336.269079)
			(xy 102.4983 -336.283185) (xy 102.549629 -336.304997) (xy 102.597235 -336.334051) (xy 102.640103 -336.369726)
			(xy 102.67732 -336.411263) (xy 102.708093 -336.457776) (xy 102.731765 -336.508273) (xy 102.747833 -336.56168)
			(xy 102.755953 -336.616856) (xy 102.756462 -336.644742) (xy 102.755953 -336.672628) (xy 102.747833 -336.727804)
			(xy 102.731765 -336.781211) (xy 102.708093 -336.831708) (xy 102.67732 -336.878221) (xy 102.640103 -336.919758)
			(xy 102.597235 -336.955433) (xy 102.549629 -336.984487) (xy 102.4983 -337.006299) (xy 102.444343 -337.020405)
			(xy 102.388906 -337.026505) (xy 102.333172 -337.024468) (xy 102.278329 -337.014338) (xy 102.225545 -336.996331)
			(xy 102.175945 -336.97083) (xy 102.130587 -336.938379) (xy 102.090438 -336.89967) (xy 102.056352 -336.855527)
			(xy 102.029056 -336.806892) (xy 102.009133 -336.754801) (xy 101.997007 -336.700364) (xy 101.992936 -336.644742)
			(xy 101.010165 -336.644742) (xy 100.988895 -336.677355) (xy 100.952431 -336.718728) (xy 100.931726 -336.736944)
			(xy 100.920813 -336.746827) (xy 100.904737 -336.771481) (xy 100.896353 -336.799693) (xy 100.896356 -336.829125)
			(xy 100.904745 -336.857336) (xy 100.920825 -336.881986) (xy 100.931726 -336.891884) (xy 100.952438 -336.910094)
			(xy 100.988907 -336.951464) (xy 101.019038 -336.997654) (xy 101.042204 -337.047702) (xy 101.05792 -337.100565)
			(xy 101.06586 -337.155139) (xy 101.066346 -337.182714) (xy 101.065835 -337.209964) (xy 101.063837 -337.223862)
			(xy 101.236524 -337.223862) (xy 101.240595 -337.16824) (xy 101.252721 -337.113803) (xy 101.272644 -337.061712)
			(xy 101.29994 -337.013077) (xy 101.334026 -336.968934) (xy 101.374175 -336.930225) (xy 101.419533 -336.897774)
			(xy 101.469133 -336.872273) (xy 101.521917 -336.854266) (xy 101.57676 -336.844136) (xy 101.632494 -336.842099)
			(xy 101.687931 -336.848199) (xy 101.741888 -336.862305) (xy 101.793217 -336.884117) (xy 101.840823 -336.913171)
			(xy 101.883691 -336.948846) (xy 101.920908 -336.990383) (xy 101.951681 -337.036896) (xy 101.975353 -337.087393)
			(xy 101.991421 -337.1408) (xy 101.999541 -337.195976) (xy 102.00005 -337.223862) (xy 101.999541 -337.251748)
			(xy 101.991421 -337.306924) (xy 101.975353 -337.360331) (xy 101.951681 -337.410828) (xy 101.920908 -337.457341)
			(xy 101.883691 -337.498878) (xy 101.840823 -337.534553) (xy 101.793217 -337.563607) (xy 101.741888 -337.585419)
			(xy 101.687931 -337.599525) (xy 101.632494 -337.605625) (xy 101.57676 -337.603588) (xy 101.521917 -337.593458)
			(xy 101.469133 -337.575451) (xy 101.419533 -337.54995) (xy 101.374175 -337.517499) (xy 101.334026 -337.47879)
			(xy 101.29994 -337.434647) (xy 101.272644 -337.386012) (xy 101.252721 -337.333921) (xy 101.240595 -337.279484)
			(xy 101.236524 -337.223862) (xy 101.063837 -337.223862) (xy 101.058078 -337.263909) (xy 101.042723 -337.316201)
			(xy 101.020083 -337.365775) (xy 100.990619 -337.411624) (xy 100.95493 -337.452813) (xy 100.913743 -337.488504)
			(xy 100.867897 -337.517971) (xy 100.818323 -337.540615) (xy 100.766032 -337.555973) (xy 100.712088 -337.563734)
			(xy 100.684838 -337.564222) (xy 100.656985 -337.563648) (xy 100.601872 -337.555531) (xy 100.548524 -337.539491)
			(xy 100.498072 -337.515871) (xy 100.451588 -337.48517) (xy 100.410058 -337.448041) (xy 100.374364 -337.405272)
			(xy 100.345263 -337.357771) (xy 100.323372 -337.306545) (xy 100.315776 -337.279742) (xy 100.311472 -337.265636)
			(xy 100.296091 -337.24049) (xy 100.274181 -337.220772) (xy 100.247558 -337.208119) (xy 100.218433 -337.203579)
			(xy 100.203762 -337.205066) (xy 100.190746 -337.206737) (xy 100.164561 -337.208516) (xy 100.151438 -337.208622)
			(xy 100.137289 -337.208524) (xy 100.109066 -337.206493) (xy 100.09505 -337.204558) (xy 100.081699 -337.203018)
			(xy 100.055015 -337.206115) (xy 100.030067 -337.216077) (xy 100.00859 -337.232213) (xy 99.992076 -337.253401)
			(xy 99.981673 -337.278168) (xy 99.97948 -337.291426) (xy 99.975413 -337.318584) (xy 99.96044 -337.371416)
			(xy 99.938048 -337.421557) (xy 99.908699 -337.46797) (xy 99.873 -337.509695) (xy 99.831687 -337.545872)
			(xy 99.785615 -337.575752) (xy 99.735735 -337.598719) (xy 99.683078 -337.614298) (xy 99.628731 -337.622166)
			(xy 99.601274 -337.622642) (xy 99.574024 -337.622146) (xy 99.520078 -337.614387) (xy 99.467786 -337.599031)
			(xy 99.418211 -337.576389) (xy 99.372362 -337.546923) (xy 99.331173 -337.511233) (xy 99.295482 -337.470045)
			(xy 99.266015 -337.424197) (xy 99.243372 -337.374622) (xy 99.228014 -337.32233) (xy 99.220254 -337.268384)
			(xy 99.219766 -337.241134) (xy 99.220232 -337.213559) (xy 99.228181 -337.158985) (xy 99.243905 -337.106124)
			(xy 99.267075 -337.056078) (xy 99.297208 -337.009889) (xy 99.333678 -336.968519) (xy 99.354386 -336.950304)
			(xy 99.36525 -336.940371) (xy 99.381326 -336.915731) (xy 99.389714 -336.887532) (xy 99.389721 -336.858112)
			(xy 99.381344 -336.829909) (xy 99.365279 -336.805262) (xy 99.354386 -336.795364) (xy 99.333651 -336.777178)
			(xy 99.297184 -336.735804) (xy 99.267055 -336.689609) (xy 99.243893 -336.639556) (xy 99.228182 -336.586689)
			(xy 99.220248 -336.53211) (xy 99.219766 -336.504534) (xy 99.220208 -336.478033) (xy 99.227557 -336.425541)
			(xy 99.242105 -336.374574) (xy 99.26357 -336.326112) (xy 99.29154 -336.281089) (xy 99.308158 -336.26044)
			(xy 99.317607 -336.2483) (xy 99.329393 -336.219898) (xy 99.332214 -336.189277) (xy 99.325816 -336.159199)
			(xy 99.310776 -336.132377) (xy 99.28845 -336.111231) (xy 99.274884 -336.103976) (xy 99.251197 -336.091869)
			(xy 99.207215 -336.061949) (xy 99.167932 -336.026079) (xy 99.134148 -335.98499) (xy 99.119944 -335.962498)
			(xy 99.112052 -335.950251) (xy 99.090572 -335.93058) (xy 99.06441 -335.917779) (xy 99.035698 -335.912889)
			(xy 99.006773 -335.916311) (xy 98.993198 -335.921604) (xy 98.969986 -335.931087) (xy 98.921654 -335.94444)
			(xy 98.871965 -335.951171) (xy 98.846894 -335.951576) (xy 98.821825 -335.951142) (xy 98.772142 -335.944396)
			(xy 98.723808 -335.931068) (xy 98.70059 -335.921604) (xy 98.686994 -335.916411) (xy 98.658103 -335.913032)
			(xy 98.62943 -335.91793) (xy 98.603298 -335.930707) (xy 98.581825 -335.950328) (xy 98.573844 -335.962498)
			(xy 98.559275 -335.985629) (xy 98.524432 -336.02775) (xy 98.483809 -336.064329) (xy 98.438278 -336.09458)
			(xy 98.388816 -336.117856) (xy 98.336485 -336.133656) (xy 98.282406 -336.141642) (xy 98.227742 -336.141642)
			(xy 98.173663 -336.133656) (xy 98.121332 -336.117856) (xy 98.07187 -336.09458) (xy 98.026339 -336.064329)
			(xy 97.985716 -336.02775) (xy 97.950873 -335.985629) (xy 97.936304 -335.962498) (xy 97.928355 -335.950292)
			(xy 97.906891 -335.930621) (xy 97.880744 -335.917814) (xy 97.852045 -335.912914) (xy 97.823131 -335.91632)
			(xy 97.809558 -335.921604) (xy 97.78635 -335.931099) (xy 97.738016 -335.944448) (xy 97.688326 -335.951174)
			(xy 97.663254 -335.951576) (xy 97.635368 -335.951136) (xy 97.580221 -335.942817) (xy 97.526928 -335.926373)
			(xy 97.476682 -335.90217) (xy 97.430604 -335.870749) (xy 97.389723 -335.832812) (xy 97.354952 -335.789207)
			(xy 97.327068 -335.740906) (xy 97.306694 -335.688989) (xy 97.294285 -335.634616) (xy 97.290117 -335.579)
			(xy 94.705198 -335.579) (xy 94.27591 -336.008472) (xy 94.257989 -336.025845) (xy 94.218372 -336.056205)
			(xy 94.175127 -336.08113) (xy 94.152212 -336.091022) (xy 93.174566 -336.496152) (xy 93.025976 -336.644742)
			(xy 93.832424 -336.644742) (xy 93.836495 -336.58912) (xy 93.848621 -336.534683) (xy 93.868544 -336.482592)
			(xy 93.89584 -336.433957) (xy 93.929926 -336.389814) (xy 93.970075 -336.351105) (xy 94.015433 -336.318654)
			(xy 94.065033 -336.293153) (xy 94.117817 -336.275146) (xy 94.17266 -336.265016) (xy 94.228394 -336.262979)
			(xy 94.283831 -336.269079) (xy 94.337788 -336.283185) (xy 94.389117 -336.304997) (xy 94.436723 -336.334051)
			(xy 94.479591 -336.369726) (xy 94.516808 -336.411263) (xy 94.547581 -336.457776) (xy 94.571253 -336.508273)
			(xy 94.587321 -336.56168) (xy 94.595441 -336.616856) (xy 94.59595 -336.644742) (xy 94.595441 -336.672628)
			(xy 94.587321 -336.727804) (xy 94.571253 -336.781211) (xy 94.547581 -336.831708) (xy 94.516808 -336.878221)
			(xy 94.479591 -336.919758) (xy 94.436723 -336.955433) (xy 94.389117 -336.984487) (xy 94.337788 -337.006299)
			(xy 94.283831 -337.020405) (xy 94.228394 -337.026505) (xy 94.17266 -337.024468) (xy 94.117817 -337.014338)
			(xy 94.065033 -336.996331) (xy 94.015433 -336.97083) (xy 93.970075 -336.938379) (xy 93.929926 -336.89967)
			(xy 93.89584 -336.855527) (xy 93.868544 -336.806892) (xy 93.848621 -336.754801) (xy 93.836495 -336.700364)
			(xy 93.832424 -336.644742) (xy 93.025976 -336.644742) (xy 92.317824 -337.352894) (xy 93.189296 -337.352894)
			(xy 93.193367 -337.297272) (xy 93.205493 -337.242835) (xy 93.225416 -337.190744) (xy 93.252712 -337.142109)
			(xy 93.286798 -337.097966) (xy 93.326947 -337.059257) (xy 93.372305 -337.026806) (xy 93.421905 -337.001305)
			(xy 93.474689 -336.983298) (xy 93.529532 -336.973168) (xy 93.585266 -336.971131) (xy 93.640703 -336.977231)
			(xy 93.69466 -336.991337) (xy 93.745989 -337.013149) (xy 93.793595 -337.042203) (xy 93.836463 -337.077878)
			(xy 93.87368 -337.119415) (xy 93.904453 -337.165928) (xy 93.928125 -337.216425) (xy 93.944193 -337.269832)
			(xy 93.952313 -337.325008) (xy 93.952822 -337.352894) (xy 93.952313 -337.38078) (xy 93.944193 -337.435956)
			(xy 93.928125 -337.489363) (xy 93.904453 -337.53986) (xy 93.87368 -337.586373) (xy 93.836463 -337.62791)
			(xy 93.793595 -337.663585) (xy 93.745989 -337.692639) (xy 93.69466 -337.714451) (xy 93.640703 -337.728557)
			(xy 93.585266 -337.734657) (xy 93.529532 -337.73262) (xy 93.474689 -337.72249) (xy 93.421905 -337.704483)
			(xy 93.372305 -337.678982) (xy 93.326947 -337.646531) (xy 93.286798 -337.607822) (xy 93.252712 -337.563679)
			(xy 93.225416 -337.515044) (xy 93.205493 -337.462953) (xy 93.193367 -337.408516) (xy 93.189296 -337.352894)
			(xy 92.317824 -337.352894) (xy 91.708986 -337.961732) (xy 91.687402 -337.982548) (xy 91.638898 -338.017803)
			(xy 91.585473 -338.045032) (xy 91.528445 -338.063562) (xy 91.46922 -338.072938) (xy 91.439238 -338.073492)
			(xy 89.690956 -338.073492) (xy 89.011252 -338.753196) (xy 88.98965 -338.773992) (xy 88.941149 -338.809247)
			(xy 88.887729 -338.836478) (xy 88.830706 -338.855014) (xy 88.771484 -338.864398) (xy 88.741504 -338.864956)
			(xy 86.586822 -338.864956) (xy 86.560026 -338.864473) (xy 86.506967 -338.856921) (xy 86.455491 -338.842005)
			(xy 86.430866 -338.831428) (xy 86.420706 -338.826856) (xy 86.371684 -338.826856) (xy 86.20934 -338.9892)
			(xy 89.129495 -338.9892) (xy 89.133664 -338.933573) (xy 89.146078 -338.879188) (xy 89.16646 -338.827262)
			(xy 89.194353 -338.778953) (xy 89.229135 -338.735342) (xy 89.27003 -338.697402) (xy 89.316122 -338.665981)
			(xy 89.366383 -338.641782) (xy 89.419689 -338.625344) (xy 89.47485 -338.617036) (xy 89.502742 -338.616544)
			(xy 89.530074 -338.617024) (xy 89.584153 -338.624991) (xy 89.636488 -338.640777) (xy 89.685952 -338.664044)
			(xy 89.731485 -338.69429) (xy 89.772107 -338.730868) (xy 89.806946 -338.77299) (xy 89.821512 -338.796122)
			(xy 89.829441 -338.808342) (xy 89.850912 -338.82801) (xy 89.877063 -338.840814) (xy 89.905767 -338.845711)
			(xy 89.934684 -338.842302) (xy 89.948258 -338.837016) (xy 89.971464 -338.827517) (xy 90.019799 -338.814169)
			(xy 90.06949 -338.807445) (xy 90.094562 -338.807044) (xy 90.119632 -338.807458) (xy 90.169315 -338.814212)
			(xy 90.217649 -338.827548) (xy 90.240866 -338.837016) (xy 90.254444 -338.84226) (xy 90.283344 -338.845625)
			(xy 90.312022 -338.840714) (xy 90.338156 -338.827926) (xy 90.359631 -338.808296) (xy 90.367612 -338.796122)
			(xy 90.382181 -338.772991) (xy 90.417024 -338.73087) (xy 90.457647 -338.694291) (xy 90.503178 -338.66404)
			(xy 90.55264 -338.640764) (xy 90.604971 -338.624964) (xy 90.65905 -338.616978) (xy 90.713714 -338.616978)
			(xy 90.767793 -338.624964) (xy 90.820124 -338.640764) (xy 90.869586 -338.66404) (xy 90.915117 -338.694291)
			(xy 90.95574 -338.73087) (xy 90.990583 -338.772991) (xy 91.005152 -338.796122) (xy 91.013043 -338.808369)
			(xy 91.034524 -338.828038) (xy 91.060686 -338.840838) (xy 91.089398 -338.845727) (xy 91.118322 -338.842308)
			(xy 91.131898 -338.837016) (xy 91.155111 -338.827536) (xy 91.203442 -338.814181) (xy 91.253131 -338.807449)
			(xy 91.278202 -338.807044) (xy 91.30584 -338.807554) (xy 91.360507 -338.815747) (xy 91.413365 -338.831923)
			(xy 91.463254 -338.855727) (xy 91.509081 -338.886638) (xy 91.549841 -338.923978) (xy 91.584639 -338.966928)
			(xy 91.612713 -339.014545) (xy 91.633448 -339.065787) (xy 91.640406 -339.09254) (xy 91.644031 -339.105642)
			(xy 91.657168 -339.129428) (xy 91.676113 -339.148908) (xy 91.699525 -339.162702) (xy 91.725746 -339.169834)
			(xy 91.752919 -339.169798) (xy 91.779121 -339.162598) (xy 91.791028 -339.15604) (xy 91.813174 -339.143407)
			(xy 91.860126 -339.123531) (xy 91.909309 -339.110095) (xy 91.959845 -339.103339) (xy 91.985338 -339.102954)
			(xy 91.993466 -339.102954) (xy 92.008325 -339.102719) (xy 92.036942 -339.094758) (xy 92.062067 -339.078913)
			(xy 92.081582 -339.056521) (xy 92.093844 -339.029466) (xy 92.096336 -339.014816) (xy 92.100451 -338.987679)
			(xy 92.115458 -338.934885) (xy 92.137872 -338.884785) (xy 92.167232 -338.838412) (xy 92.202933 -338.796724)
			(xy 92.244237 -338.76058) (xy 92.290293 -338.730725) (xy 92.34015 -338.707776) (xy 92.392781 -338.692205)
			(xy 92.447099 -338.684334) (xy 92.474542 -338.683854) (xy 92.501793 -338.684339) (xy 92.555738 -338.6921)
			(xy 92.608031 -338.707458) (xy 92.657606 -338.730102) (xy 92.703454 -338.759569) (xy 92.744643 -338.79526)
			(xy 92.780334 -338.836449) (xy 92.8098 -338.882298) (xy 92.832443 -338.931873) (xy 92.847801 -338.984166)
			(xy 92.855562 -339.038111) (xy 92.85605 -339.065362) (xy 92.855523 -339.093963) (xy 92.846994 -339.150525)
			(xy 92.83012 -339.205182) (xy 92.80528 -339.256709) (xy 92.77303 -339.303952) (xy 92.734092 -339.345855)
			(xy 92.712032 -339.364066) (xy 92.701416 -339.373139) (xy 92.685125 -339.395806) (xy 92.675581 -339.422039)
			(xy 92.6735 -339.449875) (xy 92.679035 -339.477235) (xy 92.691773 -339.502074) (xy 92.710763 -339.522534)
			(xy 92.722446 -339.530182) (xy 92.746065 -339.545126) (xy 92.789079 -339.580814) (xy 92.826427 -339.622394)
			(xy 92.857311 -339.668977) (xy 92.881071 -339.719566) (xy 92.897198 -339.773079) (xy 92.905347 -339.828373)
			(xy 92.905834 -339.856318) (xy 92.905414 -339.882211) (xy 92.898413 -339.933522) (xy 92.884529 -339.983413)
			(xy 92.864018 -340.030964) (xy 92.837257 -340.075301) (xy 92.80474 -340.115605) (xy 92.7862 -340.133686)
			(xy 92.776099 -340.143826) (xy 92.761486 -340.16842) (xy 92.754279 -340.196106) (xy 92.755045 -340.224704)
			(xy 92.763725 -340.251964) (xy 92.779634 -340.27574) (xy 92.790264 -340.285324) (xy 92.811084 -340.303523)
			(xy 92.847757 -340.344909) (xy 92.878062 -340.391161) (xy 92.901364 -340.441308) (xy 92.917173 -340.494297)
			(xy 92.925157 -340.549014) (xy 92.925646 -340.576662) (xy 92.925087 -340.603911) (xy 92.917336 -340.657854)
			(xy 92.901988 -340.710145) (xy 92.879354 -340.759719) (xy 92.849895 -340.805568) (xy 92.814211 -340.846757)
			(xy 92.773029 -340.88245) (xy 92.727186 -340.911917) (xy 92.677616 -340.934561) (xy 92.625328 -340.94992)
			(xy 92.571386 -340.957681) (xy 92.544138 -340.95817) (xy 92.515061 -340.957651) (xy 92.45758 -340.948831)
			(xy 92.402103 -340.931388) (xy 92.349916 -340.905728) (xy 92.302229 -340.872445) (xy 92.260145 -340.83231)
			(xy 92.22464 -340.786252) (xy 92.196536 -340.73534) (xy 92.185998 -340.708234) (xy 92.180456 -340.694696)
			(xy 92.162994 -340.671244) (xy 92.1396 -340.653705) (xy 92.112194 -340.643518) (xy 92.083024 -340.641518)
			(xy 92.06865 -340.644226) (xy 92.048216 -340.648497) (xy 92.00672 -340.653077) (xy 91.985846 -340.65337)
			(xy 91.985338 -340.65337) (xy 91.971122 -340.65321) (xy 91.942772 -340.65105) (xy 91.928696 -340.649052)
			(xy 91.913365 -340.647367) (xy 91.882917 -340.652173) (xy 91.855285 -340.665837) (xy 91.832982 -340.687116)
			(xy 91.818036 -340.714076) (xy 91.814396 -340.729062) (xy 91.807912 -340.757296) (xy 91.787671 -340.811571)
			(xy 91.759458 -340.862163) (xy 91.723922 -340.907908) (xy 91.68188 -340.947757) (xy 91.634297 -340.980792)
			(xy 91.582268 -341.006255) (xy 91.526987 -341.023561) (xy 91.469725 -341.032311) (xy 91.440762 -341.032846)
			(xy 91.413512 -341.032358) (xy 91.359566 -341.024597) (xy 91.307274 -341.009239) (xy 91.257699 -340.986596)
			(xy 91.21185 -340.957129) (xy 91.170662 -340.921438) (xy 91.134971 -340.88025) (xy 91.105504 -340.834401)
			(xy 91.082861 -340.784826) (xy 91.067503 -340.732534) (xy 91.059742 -340.678588) (xy 91.059254 -340.651338)
			(xy 91.059727 -340.623764) (xy 91.067675 -340.56919) (xy 91.083398 -340.51633) (xy 91.106566 -340.466283)
			(xy 91.136698 -340.420094) (xy 91.173166 -340.378723) (xy 91.193874 -340.360508) (xy 91.204735 -340.350572)
			(xy 91.220813 -340.325933) (xy 91.229203 -340.297735) (xy 91.22921 -340.268314) (xy 91.220833 -340.240112)
			(xy 91.204768 -340.215465) (xy 91.193874 -340.205568) (xy 91.173139 -340.187383) (xy 91.136672 -340.146008)
			(xy 91.106543 -340.099812) (xy 91.083382 -340.049759) (xy 91.06767 -339.996893) (xy 91.059736 -339.942314)
			(xy 91.059254 -339.914738) (xy 91.059701 -339.888237) (xy 91.06705 -339.835746) (xy 91.081596 -339.784778)
			(xy 91.10306 -339.736316) (xy 91.131029 -339.691293) (xy 91.147646 -339.670644) (xy 91.157095 -339.658503)
			(xy 91.168883 -339.630101) (xy 91.171706 -339.59948) (xy 91.165308 -339.569401) (xy 91.150267 -339.542579)
			(xy 91.127939 -339.521434) (xy 91.114372 -339.51418) (xy 91.090684 -339.502075) (xy 91.046702 -339.472154)
			(xy 91.00742 -339.436284) (xy 90.973636 -339.395194) (xy 90.959432 -339.372702) (xy 90.951551 -339.360448)
			(xy 90.930068 -339.340776) (xy 90.903903 -339.327975) (xy 90.875188 -339.323088) (xy 90.846262 -339.326513)
			(xy 90.832686 -339.331808) (xy 90.809475 -339.341295) (xy 90.761143 -339.354647) (xy 90.711454 -339.361376)
			(xy 90.686382 -339.36178) (xy 90.661313 -339.361349) (xy 90.61163 -339.354603) (xy 90.563296 -339.341273)
			(xy 90.540078 -339.331808) (xy 90.526487 -339.3266) (xy 90.497593 -339.323225) (xy 90.468919 -339.328125)
			(xy 90.442786 -339.340906) (xy 90.421312 -339.36053) (xy 90.413332 -339.372702) (xy 90.398763 -339.395833)
			(xy 90.36392 -339.437954) (xy 90.323297 -339.474533) (xy 90.277766 -339.504784) (xy 90.228304 -339.52806)
			(xy 90.175973 -339.54386) (xy 90.121894 -339.551846) (xy 90.06723 -339.551846) (xy 90.013151 -339.54386)
			(xy 89.96082 -339.52806) (xy 89.911358 -339.504784) (xy 89.865827 -339.474533) (xy 89.825204 -339.437954)
			(xy 89.790361 -339.395833) (xy 89.775792 -339.372702) (xy 89.767854 -339.360488) (xy 89.746387 -339.340817)
			(xy 89.720237 -339.328011) (xy 89.691536 -339.323113) (xy 89.662619 -339.326522) (xy 89.649046 -339.331808)
			(xy 89.62584 -339.341307) (xy 89.577505 -339.354654) (xy 89.527814 -339.361379) (xy 89.502742 -339.36178)
			(xy 89.47485 -339.361364) (xy 89.419689 -339.353056) (xy 89.366383 -339.336618) (xy 89.316122 -339.312419)
			(xy 89.27003 -339.280998) (xy 89.229135 -339.243058) (xy 89.194353 -339.199447) (xy 89.16646 -339.151138)
			(xy 89.146078 -339.099212) (xy 89.133664 -339.044827) (xy 89.129495 -338.9892) (xy 86.20934 -338.9892)
			(xy 85.301074 -339.897466) (xy 85.195889 -340.054946) (xy 85.671912 -340.054946) (xy 85.675983 -339.999324)
			(xy 85.688109 -339.944887) (xy 85.708032 -339.892796) (xy 85.735328 -339.844161) (xy 85.769414 -339.800018)
			(xy 85.809563 -339.761309) (xy 85.854921 -339.728858) (xy 85.904521 -339.703357) (xy 85.957305 -339.68535)
			(xy 86.012148 -339.67522) (xy 86.067882 -339.673183) (xy 86.123319 -339.679283) (xy 86.177276 -339.693389)
			(xy 86.228605 -339.715201) (xy 86.276211 -339.744255) (xy 86.319079 -339.77993) (xy 86.356296 -339.821467)
			(xy 86.387069 -339.86798) (xy 86.410741 -339.918477) (xy 86.426809 -339.971884) (xy 86.434929 -340.02706)
			(xy 86.435438 -340.054946) (xy 86.434929 -340.082832) (xy 86.426809 -340.138008) (xy 86.410741 -340.191415)
			(xy 86.387069 -340.241912) (xy 86.356296 -340.288425) (xy 86.319079 -340.329962) (xy 86.276211 -340.365637)
			(xy 86.228605 -340.394691) (xy 86.177276 -340.416503) (xy 86.123319 -340.430609) (xy 86.067882 -340.436709)
			(xy 86.012148 -340.434672) (xy 85.957305 -340.424542) (xy 85.904521 -340.406535) (xy 85.854921 -340.381034)
			(xy 85.809563 -340.348583) (xy 85.769414 -340.309874) (xy 85.735328 -340.265731) (xy 85.708032 -340.217096)
			(xy 85.688109 -340.165005) (xy 85.675983 -340.110568) (xy 85.671912 -340.054946) (xy 85.195889 -340.054946)
			(xy 84.850986 -340.571328) (xy 84.648825 -341.059262) (xy 85.007448 -341.059262) (xy 85.011519 -341.00364)
			(xy 85.023645 -340.949203) (xy 85.043568 -340.897112) (xy 85.070864 -340.848477) (xy 85.10495 -340.804334)
			(xy 85.145099 -340.765625) (xy 85.190457 -340.733174) (xy 85.240057 -340.707673) (xy 85.292841 -340.689666)
			(xy 85.347684 -340.679536) (xy 85.403418 -340.677499) (xy 85.458855 -340.683599) (xy 85.512812 -340.697705)
			(xy 85.564141 -340.719517) (xy 85.611747 -340.748571) (xy 85.654615 -340.784246) (xy 85.691832 -340.825783)
			(xy 85.722605 -340.872296) (xy 85.746277 -340.922793) (xy 85.762345 -340.9762) (xy 85.770465 -341.031376)
			(xy 85.770974 -341.059262) (xy 85.770465 -341.087148) (xy 85.762345 -341.142324) (xy 85.746277 -341.195731)
			(xy 85.722605 -341.246228) (xy 85.691832 -341.292741) (xy 85.654615 -341.334278) (xy 85.611747 -341.369953)
			(xy 85.564141 -341.399007) (xy 85.512812 -341.420819) (xy 85.458855 -341.434925) (xy 85.403418 -341.441025)
			(xy 85.347684 -341.438988) (xy 85.292841 -341.428858) (xy 85.240057 -341.410851) (xy 85.190457 -341.38535)
			(xy 85.145099 -341.352899) (xy 85.10495 -341.31419) (xy 85.070864 -341.270047) (xy 85.043568 -341.221412)
			(xy 85.023645 -341.169321) (xy 85.011519 -341.114884) (xy 85.007448 -341.059262) (xy 84.648825 -341.059262)
			(xy 84.63788 -341.085678) (xy 84.63788 -342.770714) (xy 84.637314 -342.800634) (xy 84.627942 -342.859735)
			(xy 84.609445 -342.916645) (xy 84.582279 -342.969963) (xy 84.547112 -343.018379) (xy 84.526374 -343.039954)
			(xy 83.756246 -343.810082) (xy 83.734668 -343.830812) (xy 83.686239 -343.865951) (xy 83.632919 -343.893101)
			(xy 83.576016 -343.911595) (xy 83.516922 -343.920981) (xy 83.487006 -343.921588) (xy 81.466436 -343.921588)
			(xy 80.928464 -344.459814) (xy 80.906867 -344.480524) (xy 80.858445 -344.515668) (xy 80.80513 -344.542823)
			(xy 80.74823 -344.561322) (xy 80.689139 -344.570712) (xy 80.659224 -344.57132) (xy 78.259432 -344.57132)
			(xy 78.229514 -344.570714) (xy 78.170415 -344.561349) (xy 78.113506 -344.542862) (xy 78.060187 -344.515705)
			(xy 78.011769 -344.480547) (xy 77.990192 -344.459814) (xy 77.65415 -344.123772) (xy 77.601064 -344.123772)
			(xy 77.587191 -344.124308) (xy 77.560474 -344.131792) (xy 77.536759 -344.146196) (xy 77.517802 -344.166455)
			(xy 77.505003 -344.191073) (xy 77.499308 -344.218228) (xy 77.501139 -344.245913) (xy 77.505306 -344.259154)
			(xy 77.515466 -344.289918) (xy 77.526445 -344.353763) (xy 77.52715 -344.386154) (xy 77.52715 -344.386662)
			(xy 77.526664 -344.413913) (xy 77.518908 -344.467861) (xy 77.503553 -344.520156) (xy 77.480911 -344.569733)
			(xy 77.451445 -344.615583) (xy 77.415754 -344.656774) (xy 77.374563 -344.692465) (xy 77.328713 -344.721931)
			(xy 77.279136 -344.744573) (xy 77.226841 -344.759928) (xy 77.172893 -344.767684) (xy 77.118391 -344.767684)
			(xy 77.064443 -344.759928) (xy 77.012148 -344.744573) (xy 76.962571 -344.721931) (xy 76.916721 -344.692465)
			(xy 76.87553 -344.656774) (xy 76.839839 -344.615583) (xy 76.810373 -344.569733) (xy 76.787731 -344.520156)
			(xy 76.772376 -344.467861) (xy 76.76462 -344.413913) (xy 76.764134 -344.386662) (xy 75.89774 -344.386662)
			(xy 75.89774 -344.7799) (xy 80.968987 -344.7799) (xy 80.973156 -344.724273) (xy 80.98557 -344.669888)
			(xy 81.005951 -344.617961) (xy 81.033844 -344.569652) (xy 81.068626 -344.526041) (xy 81.109519 -344.4881)
			(xy 81.155611 -344.456678) (xy 81.205871 -344.432478) (xy 81.259178 -344.416039) (xy 81.314338 -344.407729)
			(xy 81.34223 -344.407236) (xy 81.369561 -344.407729) (xy 81.42364 -344.415694) (xy 81.475974 -344.431479)
			(xy 81.525438 -344.454743) (xy 81.570971 -344.484988) (xy 81.611594 -344.521563) (xy 81.646434 -344.563683)
			(xy 81.661 -344.586814) (xy 81.668942 -344.599025) (xy 81.690409 -344.618694) (xy 81.716557 -344.631499)
			(xy 81.745257 -344.636399) (xy 81.774173 -344.632992) (xy 81.787746 -344.627708) (xy 81.810954 -344.618212)
			(xy 81.859288 -344.604863) (xy 81.908978 -344.598138) (xy 81.93405 -344.597736) (xy 81.95912 -344.598155)
			(xy 82.008803 -344.604906) (xy 82.057137 -344.618241) (xy 82.080354 -344.627708) (xy 82.093935 -344.632943)
			(xy 82.122834 -344.63631) (xy 82.151511 -344.631403) (xy 82.177645 -344.618617) (xy 82.199119 -344.598987)
			(xy 82.2071 -344.586814) (xy 82.221669 -344.563683) (xy 82.256512 -344.521562) (xy 82.297135 -344.484983)
			(xy 82.342666 -344.454732) (xy 82.392128 -344.431456) (xy 82.444459 -344.415656) (xy 82.498538 -344.40767)
			(xy 82.553202 -344.40767) (xy 82.607281 -344.415656) (xy 82.659612 -344.431456) (xy 82.709074 -344.454732)
			(xy 82.754605 -344.484983) (xy 82.795228 -344.521562) (xy 82.830071 -344.563683) (xy 82.84464 -344.586814)
			(xy 82.852544 -344.599052) (xy 82.874021 -344.618721) (xy 82.90018 -344.631523) (xy 82.928889 -344.636415)
			(xy 82.957811 -344.632998) (xy 82.971386 -344.627708) (xy 82.994601 -344.618231) (xy 83.042931 -344.604875)
			(xy 83.092619 -344.598142) (xy 83.11769 -344.597736) (xy 83.144534 -344.598169) (xy 83.197667 -344.605873)
			(xy 83.249144 -344.621124) (xy 83.297899 -344.643605) (xy 83.342923 -344.67285) (xy 83.383283 -344.708255)
			(xy 83.418143 -344.749087) (xy 83.446783 -344.794498) (xy 83.468608 -344.843551) (xy 83.476338 -344.869262)
			(xy 83.480962 -344.883774) (xy 83.497487 -344.909342) (xy 83.520811 -344.928908) (xy 83.548863 -344.940736)
			(xy 83.579155 -344.943775) (xy 83.608998 -344.937758) (xy 83.622642 -344.930984) (xy 83.65079 -344.916355)
			(xy 83.71074 -344.895627) (xy 83.773298 -344.885126) (xy 83.805014 -344.884502) (xy 83.805268 -344.884502)
			(xy 83.828344 -344.884849) (xy 83.874159 -344.890427) (xy 83.918962 -344.901503) (xy 83.94065 -344.909394)
			(xy 83.954434 -344.914181) (xy 83.983516 -344.916438) (xy 84.012051 -344.910385) (xy 84.037712 -344.896514)
			(xy 84.058407 -344.875956) (xy 84.072448 -344.850388) (xy 84.076032 -344.836242) (xy 84.082655 -344.808282)
			(xy 84.103249 -344.754639) (xy 84.131655 -344.704692) (xy 84.167231 -344.65957) (xy 84.209172 -344.620294)
			(xy 84.25653 -344.587753) (xy 84.308232 -344.562682) (xy 84.363109 -344.545649) (xy 84.41992 -344.537039)
			(xy 84.44865 -344.536522) (xy 84.475903 -344.537002) (xy 84.529855 -344.544753) (xy 84.582154 -344.560104)
			(xy 84.631736 -344.582743) (xy 84.677591 -344.612208) (xy 84.718785 -344.647901) (xy 84.75448 -344.689093)
			(xy 84.783947 -344.734946) (xy 84.806589 -344.784527) (xy 84.821943 -344.836826) (xy 84.829697 -344.890777)
			(xy 84.830158 -344.91803) (xy 84.82972 -344.945401) (xy 84.821897 -344.999582) (xy 84.806402 -345.052086)
			(xy 84.783554 -345.101832) (xy 84.753822 -345.147798) (xy 84.736178 -345.168728) (xy 84.726914 -345.180034)
			(xy 84.714743 -345.2066) (xy 84.710577 -345.235523) (xy 84.714756 -345.264444) (xy 84.726939 -345.291004)
			(xy 84.736178 -345.302332) (xy 84.753795 -345.323282) (xy 84.783511 -345.369249) (xy 84.806352 -345.418992)
			(xy 84.821848 -345.471489) (xy 84.829681 -345.525662) (xy 84.830158 -345.55303) (xy 84.829659 -345.580604)
			(xy 84.821715 -345.635176) (xy 84.805998 -345.688035) (xy 84.782834 -345.738082) (xy 84.752707 -345.784272)
			(xy 84.716243 -345.825644) (xy 84.695538 -345.84386) (xy 84.684608 -345.853726) (xy 84.668531 -345.878384)
			(xy 84.660147 -345.906601) (xy 84.660153 -345.936037) (xy 84.668547 -345.964251) (xy 84.684633 -345.988903)
			(xy 84.695538 -345.9988) (xy 84.71626 -346.016999) (xy 84.752728 -346.058371) (xy 84.782858 -346.104564)
			(xy 84.806021 -346.154614) (xy 84.821736 -346.207479) (xy 84.829674 -346.262055) (xy 84.830158 -346.28963)
			(xy 84.829773 -346.316886) (xy 84.822011 -346.370842) (xy 84.806648 -346.423145) (xy 84.783998 -346.472728)
			(xy 84.754523 -346.518584) (xy 84.718821 -346.559777) (xy 84.67762 -346.595471) (xy 84.631758 -346.624937)
			(xy 84.58217 -346.647576) (xy 84.529864 -346.662928) (xy 84.475906 -346.670679) (xy 84.44865 -346.671138)
			(xy 84.420776 -346.670626) (xy 84.365624 -346.662506) (xy 84.31224 -346.646446) (xy 84.261761 -346.622788)
			(xy 84.215263 -346.592036) (xy 84.173735 -346.554845) (xy 84.138062 -346.512006) (xy 84.109002 -346.464432)
			(xy 84.097622 -346.438982) (xy 84.090901 -346.424856) (xy 84.070496 -346.40117) (xy 84.043891 -346.384752)
			(xy 84.013571 -346.377136) (xy 83.982366 -346.379032) (xy 83.967574 -346.384118) (xy 83.945612 -346.392165)
			(xy 83.900228 -346.403485) (xy 83.853801 -346.409176) (xy 83.830414 -346.409518) (xy 83.816265 -346.409423)
			(xy 83.788042 -346.407389) (xy 83.774026 -346.405454) (xy 83.760682 -346.403807) (xy 83.733981 -346.406912)
			(xy 83.709021 -346.41689) (xy 83.687538 -346.433048) (xy 83.671028 -346.454261) (xy 83.660638 -346.479053)
			(xy 83.658456 -346.492322) (xy 83.654312 -346.519466) (xy 83.639344 -346.572293) (xy 83.616959 -346.622429)
			(xy 83.587617 -346.668838) (xy 83.551926 -346.710563) (xy 83.510623 -346.74674) (xy 83.464561 -346.776623)
			(xy 83.41469 -346.799594) (xy 83.362042 -346.81518) (xy 83.307703 -346.823057) (xy 83.28025 -346.823538)
			(xy 83.253 -346.822998) (xy 83.199053 -346.815249) (xy 83.146759 -346.799901) (xy 83.097181 -346.777266)
			(xy 83.051329 -346.747806) (xy 83.010136 -346.71212) (xy 82.974442 -346.670935) (xy 82.944972 -346.62509)
			(xy 82.922327 -346.575517) (xy 82.906968 -346.523225) (xy 82.899207 -346.46928) (xy 82.898742 -346.44203)
			(xy 82.899214 -346.414456) (xy 82.907163 -346.359882) (xy 82.922886 -346.307022) (xy 82.946055 -346.256976)
			(xy 82.976187 -346.210786) (xy 83.012655 -346.169415) (xy 83.033362 -346.1512) (xy 83.044232 -346.141273)
			(xy 83.060311 -346.116632) (xy 83.068702 -346.088431) (xy 83.068707 -346.059008) (xy 83.060328 -346.030803)
			(xy 83.044258 -346.006157) (xy 83.033362 -345.99626) (xy 83.012669 -345.978029) (xy 82.976199 -345.936664)
			(xy 82.946066 -345.890478) (xy 82.922897 -345.840434) (xy 82.907176 -345.787575) (xy 82.899231 -345.733003)
			(xy 82.898742 -345.70543) (xy 82.899165 -345.678928) (xy 82.906516 -345.626435) (xy 82.921067 -345.575466)
			(xy 82.942537 -345.527005) (xy 82.970513 -345.481984) (xy 82.987134 -345.461336) (xy 82.996597 -345.449205)
			(xy 83.008386 -345.420799) (xy 83.011207 -345.390174) (xy 83.004807 -345.360093) (xy 82.989762 -345.33327)
			(xy 82.96743 -345.312125) (xy 82.95386 -345.304872) (xy 82.930169 -345.292774) (xy 82.886187 -345.26285)
			(xy 82.846906 -345.226979) (xy 82.813123 -345.185887) (xy 82.79892 -345.163394) (xy 82.790957 -345.151198)
			(xy 82.769496 -345.131528) (xy 82.743354 -345.11872) (xy 82.714658 -345.113817) (xy 82.685746 -345.117219)
			(xy 82.672174 -345.1225) (xy 82.648964 -345.13199) (xy 82.600631 -345.145341) (xy 82.550942 -345.152069)
			(xy 82.52587 -345.152472) (xy 82.500801 -345.152046) (xy 82.451118 -345.145297) (xy 82.402783 -345.131966)
			(xy 82.379566 -345.1225) (xy 82.365978 -345.117283) (xy 82.337083 -345.11391) (xy 82.308408 -345.118814)
			(xy 82.282275 -345.131596) (xy 82.2608 -345.151222) (xy 82.25282 -345.163394) (xy 82.238251 -345.186525)
			(xy 82.203408 -345.228646) (xy 82.162785 -345.265225) (xy 82.117254 -345.295476) (xy 82.067792 -345.318752)
			(xy 82.015461 -345.334552) (xy 81.961382 -345.342538) (xy 81.906718 -345.342538) (xy 81.852639 -345.334552)
			(xy 81.800308 -345.318752) (xy 81.750846 -345.295476) (xy 81.705315 -345.265225) (xy 81.664692 -345.228646)
			(xy 81.629849 -345.186525) (xy 81.61528 -345.163394) (xy 81.607355 -345.151171) (xy 81.585884 -345.131501)
			(xy 81.559731 -345.118696) (xy 81.531026 -345.113801) (xy 81.502108 -345.117212) (xy 81.488534 -345.1225)
			(xy 81.465317 -345.131971) (xy 81.416988 -345.145329) (xy 81.367301 -345.152065) (xy 81.34223 -345.152472)
			(xy 81.314338 -345.152071) (xy 81.259178 -345.143761) (xy 81.205871 -345.127322) (xy 81.155611 -345.103122)
			(xy 81.109519 -345.0717) (xy 81.068626 -345.033759) (xy 81.033844 -344.990148) (xy 81.005951 -344.941839)
			(xy 80.98557 -344.889912) (xy 80.973156 -344.835527) (xy 80.968987 -344.7799) (xy 75.89774 -344.7799)
			(xy 75.89774 -345.845638) (xy 77.5114 -345.845638) (xy 77.515471 -345.790016) (xy 77.527597 -345.735579)
			(xy 77.54752 -345.683488) (xy 77.574816 -345.634853) (xy 77.608902 -345.59071) (xy 77.649051 -345.552001)
			(xy 77.694409 -345.51955) (xy 77.744009 -345.494049) (xy 77.796793 -345.476042) (xy 77.851636 -345.465912)
			(xy 77.90737 -345.463875) (xy 77.962807 -345.469975) (xy 78.016764 -345.484081) (xy 78.068093 -345.505893)
			(xy 78.115699 -345.534947) (xy 78.158567 -345.570622) (xy 78.195784 -345.612159) (xy 78.226557 -345.658672)
			(xy 78.250229 -345.709169) (xy 78.266297 -345.762576) (xy 78.274417 -345.817752) (xy 78.274926 -345.845638)
			(xy 78.274417 -345.873524) (xy 78.266297 -345.9287) (xy 78.250229 -345.982107) (xy 78.226557 -346.032604)
			(xy 78.195784 -346.079117) (xy 78.158567 -346.120654) (xy 78.115699 -346.156329) (xy 78.068093 -346.185383)
			(xy 78.016764 -346.207195) (xy 77.962807 -346.221301) (xy 77.90737 -346.227401) (xy 77.851636 -346.225364)
			(xy 77.796793 -346.215234) (xy 77.744009 -346.197227) (xy 77.694409 -346.171726) (xy 77.649051 -346.139275)
			(xy 77.608902 -346.100566) (xy 77.574816 -346.056423) (xy 77.54752 -346.007788) (xy 77.527597 -345.955697)
			(xy 77.515471 -345.90126) (xy 77.5114 -345.845638) (xy 75.89774 -345.845638) (xy 75.89774 -346.825062)
			(xy 76.846936 -346.825062) (xy 76.851007 -346.76944) (xy 76.863133 -346.715003) (xy 76.883056 -346.662912)
			(xy 76.910352 -346.614277) (xy 76.944438 -346.570134) (xy 76.984587 -346.531425) (xy 77.029945 -346.498974)
			(xy 77.079545 -346.473473) (xy 77.132329 -346.455466) (xy 77.187172 -346.445336) (xy 77.242906 -346.443299)
			(xy 77.298343 -346.449399) (xy 77.3523 -346.463505) (xy 77.403629 -346.485317) (xy 77.451235 -346.514371)
			(xy 77.494103 -346.550046) (xy 77.53132 -346.591583) (xy 77.562093 -346.638096) (xy 77.585765 -346.688593)
			(xy 77.601833 -346.742) (xy 77.609953 -346.797176) (xy 77.610462 -346.825062) (xy 77.609953 -346.852948)
			(xy 77.601833 -346.908124) (xy 77.585765 -346.961531) (xy 77.562093 -347.012028) (xy 77.53132 -347.058541)
			(xy 77.494103 -347.100078) (xy 77.451235 -347.135753) (xy 77.403629 -347.164807) (xy 77.3523 -347.186619)
			(xy 77.298343 -347.200725) (xy 77.242906 -347.206825) (xy 77.187172 -347.204788) (xy 77.132329 -347.194658)
			(xy 77.079545 -347.176651) (xy 77.029945 -347.15115) (xy 76.984587 -347.118699) (xy 76.944438 -347.07999)
			(xy 76.910352 -347.035847) (xy 76.883056 -346.987212) (xy 76.863133 -346.935121) (xy 76.851007 -346.880684)
			(xy 76.846936 -346.825062) (xy 75.89774 -346.825062) (xy 75.89774 -347.439234) (xy 78.318106 -347.439234)
			(xy 78.318683 -347.409547) (xy 78.327877 -347.350889) (xy 78.346048 -347.294363) (xy 78.372757 -347.241335)
			(xy 78.407359 -347.193086) (xy 78.449019 -347.15078) (xy 78.472538 -347.132656) (xy 78.483121 -347.124203)
			(xy 78.499823 -347.102895) (xy 78.510339 -347.077947) (xy 78.513931 -347.051113) (xy 78.510346 -347.024278)
			(xy 78.499836 -346.999328) (xy 78.48314 -346.978016) (xy 78.472538 -346.969588) (xy 78.44903 -346.951449)
			(xy 78.407367 -346.909147) (xy 78.372762 -346.860901) (xy 78.346048 -346.807876) (xy 78.327872 -346.751353)
			(xy 78.318672 -346.692697) (xy 78.318106 -346.66301) (xy 78.318592 -346.635759) (xy 78.326348 -346.581811)
			(xy 78.341703 -346.529516) (xy 78.364345 -346.479939) (xy 78.393811 -346.434089) (xy 78.429502 -346.392898)
			(xy 78.470693 -346.357207) (xy 78.516543 -346.327741) (xy 78.56612 -346.305099) (xy 78.618415 -346.289744)
			(xy 78.672363 -346.281988) (xy 78.726865 -346.281988) (xy 78.780813 -346.289744) (xy 78.833108 -346.305099)
			(xy 78.882685 -346.327741) (xy 78.928535 -346.357207) (xy 78.969726 -346.392898) (xy 79.005417 -346.434089)
			(xy 79.034883 -346.479939) (xy 79.057525 -346.529516) (xy 79.07288 -346.581811) (xy 79.080636 -346.635759)
			(xy 79.081122 -346.66301) (xy 79.080565 -346.692698) (xy 79.071366 -346.751356) (xy 79.05319 -346.807882)
			(xy 79.026477 -346.860909) (xy 78.991872 -346.909158) (xy 78.95021 -346.951464) (xy 78.92669 -346.969588)
			(xy 78.916061 -346.977989) (xy 78.899354 -346.999307) (xy 78.888838 -347.024267) (xy 78.885251 -347.051113)
			(xy 78.888845 -347.077958) (xy 78.899368 -347.102916) (xy 78.91608 -347.12423) (xy 78.92669 -347.132656)
			(xy 78.950225 -347.150762) (xy 78.991885 -347.193071) (xy 79.026487 -347.241324) (xy 79.053195 -347.294356)
			(xy 79.071366 -347.350884) (xy 79.08056 -347.409545) (xy 79.081122 -347.439234) (xy 79.080636 -347.466485)
			(xy 79.07288 -347.520433) (xy 79.057525 -347.572728) (xy 79.034883 -347.622305) (xy 79.005417 -347.668155)
			(xy 78.969726 -347.709346) (xy 78.928535 -347.745037) (xy 78.882685 -347.774503) (xy 78.833108 -347.797145)
			(xy 78.780813 -347.8125) (xy 78.726865 -347.820256) (xy 78.672363 -347.820256) (xy 78.618415 -347.8125)
			(xy 78.56612 -347.797145) (xy 78.516543 -347.774503) (xy 78.470693 -347.745037) (xy 78.429502 -347.709346)
			(xy 78.393811 -347.668155) (xy 78.364345 -347.622305) (xy 78.341703 -347.572728) (xy 78.326348 -347.520433)
			(xy 78.318592 -347.466485) (xy 78.318106 -347.439234) (xy 75.89774 -347.439234) (xy 75.89774 -350.505014)
			(xy 76.530962 -350.505014) (xy 76.531383 -350.478634) (xy 76.538647 -350.426376) (xy 76.553037 -350.375617)
			(xy 76.57428 -350.327322) (xy 76.601971 -350.282413) (xy 76.635582 -350.241745) (xy 76.674473 -350.206093)
			(xy 76.717903 -350.176136) (xy 76.741274 -350.163892) (xy 76.75362 -350.157169) (xy 76.774345 -350.138196)
			(xy 76.789105 -350.114286) (xy 76.796777 -350.087256) (xy 76.796779 -350.059157) (xy 76.78911 -350.032125)
			(xy 76.774353 -350.008213) (xy 76.75363 -349.989238) (xy 76.741274 -349.982536) (xy 76.717904 -349.970295)
			(xy 76.67448 -349.940332) (xy 76.635596 -349.904676) (xy 76.60199 -349.864006) (xy 76.574303 -349.819098)
			(xy 76.553063 -349.770805) (xy 76.538673 -349.720048) (xy 76.531408 -349.667793) (xy 76.530962 -349.641414)
			(xy 76.531448 -349.614163) (xy 76.539204 -349.560215) (xy 76.554559 -349.50792) (xy 76.577201 -349.458343)
			(xy 76.606667 -349.412493) (xy 76.642358 -349.371302) (xy 76.683549 -349.335611) (xy 76.729399 -349.306145)
			(xy 76.778976 -349.283503) (xy 76.831271 -349.268148) (xy 76.885219 -349.260392) (xy 76.939721 -349.260392)
			(xy 76.993669 -349.268148) (xy 77.045964 -349.283503) (xy 77.095541 -349.306145) (xy 77.141391 -349.335611)
			(xy 77.182582 -349.371302) (xy 77.218273 -349.412493) (xy 77.247739 -349.458343) (xy 77.270381 -349.50792)
			(xy 77.285736 -349.560215) (xy 77.293492 -349.614163) (xy 77.293978 -349.641414) (xy 77.29353 -349.667794)
			(xy 77.286275 -349.720051) (xy 77.271892 -349.770812) (xy 77.250654 -349.819107) (xy 77.222967 -349.864018)
			(xy 77.189357 -349.904686) (xy 77.150467 -349.940338) (xy 77.107037 -349.970294) (xy 77.083666 -349.982536)
			(xy 77.071292 -349.989214) (xy 77.050555 -350.008192) (xy 77.035789 -350.03211) (xy 77.028115 -350.059152)
			(xy 77.028117 -350.087261) (xy 77.035794 -350.114302) (xy 77.050563 -350.138218) (xy 77.071302 -350.157193)
			(xy 77.083666 -350.163892) (xy 77.107058 -350.176095) (xy 77.15048 -350.206064) (xy 77.189363 -350.241727)
			(xy 77.222966 -350.282402) (xy 77.25065 -350.327316) (xy 77.271887 -350.375614) (xy 77.286273 -350.426375)
			(xy 77.293534 -350.478634) (xy 77.29388 -350.499172) (xy 88.330532 -350.499172) (xy 88.33109 -350.470256)
			(xy 88.339809 -350.413086) (xy 88.357058 -350.357888) (xy 88.382442 -350.305926) (xy 88.41538 -350.258391)
			(xy 88.455115 -350.216373) (xy 88.477598 -350.198182) (xy 88.48943 -350.188315) (xy 88.506945 -350.162982)
			(xy 88.516117 -350.133582) (xy 88.516112 -350.102784) (xy 88.50693 -350.073387) (xy 88.489406 -350.04806)
			(xy 88.477598 -350.038162) (xy 88.455096 -350.019993) (xy 88.415362 -349.977969) (xy 88.382425 -349.930429)
			(xy 88.35704 -349.878463) (xy 88.339788 -349.823262) (xy 88.331064 -349.766089) (xy 88.330532 -349.737172)
			(xy 88.330929 -349.709917) (xy 88.338691 -349.655961) (xy 88.354052 -349.60366) (xy 88.376701 -349.554077)
			(xy 88.406176 -349.508222) (xy 88.441876 -349.467028) (xy 88.483076 -349.431335) (xy 88.528936 -349.401868)
			(xy 88.578523 -349.379229) (xy 88.630828 -349.363876) (xy 88.684785 -349.356124) (xy 88.71204 -349.355664)
			(xy 88.712294 -349.355664) (xy 88.738495 -349.356104) (xy 88.790401 -349.363294) (xy 88.840836 -349.377513)
			(xy 88.888855 -349.398493) (xy 88.91143 -349.411798) (xy 88.921042 -349.417123) (xy 88.942853 -349.419676)
			(xy 88.963746 -349.412914) (xy 88.979926 -349.398067) (xy 88.988453 -349.377831) (xy 88.988646 -349.36684)
			(xy 88.988392 -349.353632) (xy 88.988456 -349.342494) (xy 88.989728 -349.320255) (xy 88.990932 -349.309182)
			(xy 88.992189 -349.294211) (xy 88.986907 -349.264651) (xy 88.973257 -349.237904) (xy 88.952417 -349.216283)
			(xy 88.926191 -349.201657) (xy 88.896845 -349.19529) (xy 88.866916 -349.197734) (xy 88.852756 -349.202756)
			(xy 88.830293 -349.2113) (xy 88.78375 -349.223283) (xy 88.73607 -349.229319) (xy 88.71204 -349.22968)
			(xy 88.684783 -349.229276) (xy 88.630824 -349.221523) (xy 88.578517 -349.206169) (xy 88.528929 -349.183527)
			(xy 88.483067 -349.154058) (xy 88.441866 -349.118362) (xy 88.406166 -349.077165) (xy 88.376692 -349.031307)
			(xy 88.354045 -348.98172) (xy 88.338686 -348.929415) (xy 88.330927 -348.875457) (xy 88.330927 -348.820943)
			(xy 88.338686 -348.766985) (xy 88.354045 -348.71468) (xy 88.376692 -348.665093) (xy 88.406166 -348.619235)
			(xy 88.441866 -348.578038) (xy 88.483067 -348.542342) (xy 88.528929 -348.512873) (xy 88.578517 -348.490231)
			(xy 88.630824 -348.474877) (xy 88.684783 -348.467124) (xy 88.71204 -348.466664) (xy 88.736204 -348.467041)
			(xy 88.784147 -348.473135) (xy 88.830936 -348.485233) (xy 88.853518 -348.493842) (xy 88.868007 -348.499123)
			(xy 88.89874 -348.501541) (xy 88.928796 -348.494686) (xy 88.955441 -348.479182) (xy 88.976252 -348.456438)
			(xy 88.989334 -348.428524) (xy 88.991948 -348.413324) (xy 88.996023 -348.386221) (xy 89.011078 -348.333521)
			(xy 89.033522 -348.283519) (xy 89.062893 -348.237245) (xy 89.098585 -348.195651) (xy 89.139864 -348.159596)
			(xy 89.18588 -348.129821) (xy 89.235683 -348.106939) (xy 89.28825 -348.091423) (xy 89.342496 -348.083591)
			(xy 89.3699 -348.083124) (xy 89.398817 -348.083633) (xy 89.455989 -348.092363) (xy 89.511189 -348.109622)
			(xy 89.563151 -348.135015) (xy 89.610684 -348.167961) (xy 89.6527 -348.207704) (xy 89.67089 -348.23019)
			(xy 89.680787 -348.241995) (xy 89.706111 -348.259514) (xy 89.735504 -348.26869) (xy 89.766296 -348.26869)
			(xy 89.795689 -348.259514) (xy 89.821013 -348.241995) (xy 89.83091 -348.23019) (xy 89.849093 -348.2077)
			(xy 89.891115 -348.167965) (xy 89.938651 -348.135027) (xy 89.990614 -348.10964) (xy 90.045813 -348.092385)
			(xy 90.102984 -348.083658) (xy 90.1319 -348.083124) (xy 90.159154 -348.083546) (xy 90.213106 -348.091303)
			(xy 90.265405 -348.106659) (xy 90.314986 -348.129302) (xy 90.360841 -348.158771) (xy 90.402034 -348.194466)
			(xy 90.437729 -348.235659) (xy 90.467198 -348.281514) (xy 90.489841 -348.331095) (xy 90.505197 -348.383394)
			(xy 90.512954 -348.437346) (xy 90.512954 -348.491854) (xy 90.509949 -348.512757) (xy 90.715215 -348.512757)
			(xy 90.715215 -348.458243) (xy 90.722974 -348.404283) (xy 90.738333 -348.351976) (xy 90.760981 -348.302388)
			(xy 90.790456 -348.256528) (xy 90.826157 -348.21533) (xy 90.867359 -348.179633) (xy 90.913222 -348.150163)
			(xy 90.962812 -348.12752) (xy 91.01512 -348.112166) (xy 91.06908 -348.104412) (xy 91.096338 -348.103952)
			(xy 91.125254 -348.104495) (xy 91.182425 -348.113217) (xy 91.237624 -348.130468) (xy 91.289586 -348.155855)
			(xy 91.337121 -348.188795) (xy 91.379138 -348.228534) (xy 91.397328 -348.251018) (xy 91.407225 -348.262823)
			(xy 91.432549 -348.280342) (xy 91.461942 -348.289518) (xy 91.492734 -348.289518) (xy 91.522127 -348.280342)
			(xy 91.547451 -348.262823) (xy 91.557348 -348.251018) (xy 91.574101 -348.230235) (xy 91.612455 -348.193105)
			(xy 91.655609 -348.161683) (xy 91.702723 -348.136584) (xy 91.752875 -348.118298) (xy 91.805086 -348.107181)
			(xy 91.858338 -348.103451) (xy 91.91159 -348.107181) (xy 91.963801 -348.118298) (xy 92.013953 -348.136584)
			(xy 92.061067 -348.161683) (xy 92.104221 -348.193105) (xy 92.142575 -348.230235) (xy 92.159328 -348.251018)
			(xy 92.169225 -348.262823) (xy 92.194549 -348.280342) (xy 92.223942 -348.289518) (xy 92.254734 -348.289518)
			(xy 92.284127 -348.280342) (xy 92.309451 -348.262823) (xy 92.319348 -348.251018) (xy 92.336101 -348.230235)
			(xy 92.374455 -348.193105) (xy 92.417609 -348.161683) (xy 92.464723 -348.136584) (xy 92.514875 -348.118298)
			(xy 92.567086 -348.107181) (xy 92.620338 -348.103451) (xy 92.67359 -348.107181) (xy 92.725801 -348.118298)
			(xy 92.775953 -348.136584) (xy 92.823067 -348.161683) (xy 92.866221 -348.193105) (xy 92.904575 -348.230235)
			(xy 92.921328 -348.251018) (xy 92.931225 -348.262823) (xy 92.956549 -348.280342) (xy 92.985942 -348.289518)
			(xy 93.016734 -348.289518) (xy 93.046127 -348.280342) (xy 93.071451 -348.262823) (xy 93.081348 -348.251018)
			(xy 93.099573 -348.228563) (xy 93.141585 -348.188825) (xy 93.189113 -348.155882) (xy 93.241067 -348.130489)
			(xy 93.296259 -348.113227) (xy 93.353424 -348.104491) (xy 93.382338 -348.103952) (xy 93.410905 -348.104492)
			(xy 93.467399 -348.113024) (xy 93.521992 -348.129875) (xy 93.573466 -348.15467) (xy 93.620672 -348.186857)
			(xy 93.662557 -348.225716) (xy 93.680788 -348.247716) (xy 93.690372 -348.258945) (xy 93.714608 -348.275783)
			(xy 93.742643 -348.284996) (xy 93.772143 -348.285814) (xy 93.800646 -348.278172) (xy 93.825779 -348.262704)
			(xy 93.835982 -348.252034) (xy 93.854145 -348.232411) (xy 93.895029 -348.197953) (xy 93.940324 -348.16954)
			(xy 93.989143 -348.147728) (xy 94.040528 -348.132946) (xy 94.093473 -348.125482) (xy 94.120208 -348.125034)
			(xy 94.149123 -348.125606) (xy 94.206292 -348.134322) (xy 94.261491 -348.151568) (xy 94.313453 -348.17695)
			(xy 94.360988 -348.209885) (xy 94.403007 -348.249618) (xy 94.421198 -348.2721) (xy 94.431095 -348.283905)
			(xy 94.456419 -348.301424) (xy 94.485812 -348.3106) (xy 94.516604 -348.3106) (xy 94.545997 -348.301424)
			(xy 94.571321 -348.283905) (xy 94.581218 -348.2721) (xy 94.599399 -348.249608) (xy 94.641421 -348.209873)
			(xy 94.688958 -348.176935) (xy 94.740921 -348.151548) (xy 94.79612 -348.134294) (xy 94.853291 -348.125568)
			(xy 94.882208 -348.125034) (xy 94.909462 -348.125436) (xy 94.963415 -348.133195) (xy 95.015714 -348.148552)
			(xy 95.065296 -348.171196) (xy 95.11115 -348.200666) (xy 95.152344 -348.236362) (xy 95.188039 -348.277556)
			(xy 95.217508 -348.323411) (xy 95.240151 -348.372993) (xy 95.255507 -348.425293) (xy 95.263264 -348.479246)
			(xy 95.263264 -348.512752) (xy 95.383338 -348.512752) (xy 95.383338 -348.458248) (xy 95.391094 -348.404299)
			(xy 95.406448 -348.352003) (xy 95.429088 -348.302424) (xy 95.458553 -348.256571) (xy 95.494242 -348.215378)
			(xy 95.535431 -348.179683) (xy 95.58128 -348.150212) (xy 95.630856 -348.127565) (xy 95.68315 -348.112204)
			(xy 95.737098 -348.104441) (xy 95.76435 -348.103952) (xy 95.793267 -348.104486) (xy 95.850438 -348.113209)
			(xy 95.905637 -348.130463) (xy 95.9576 -348.155851) (xy 96.005134 -348.188793) (xy 96.04715 -348.228533)
			(xy 96.06534 -348.251018) (xy 96.075237 -348.262823) (xy 96.100561 -348.280342) (xy 96.129954 -348.289518)
			(xy 96.160746 -348.289518) (xy 96.190139 -348.280342) (xy 96.215463 -348.262823) (xy 96.22536 -348.251018)
			(xy 96.243578 -348.228557) (xy 96.285592 -348.18882) (xy 96.333121 -348.155878) (xy 96.385077 -348.130485)
			(xy 96.44027 -348.113224) (xy 96.497436 -348.10449) (xy 96.52635 -348.103952) (xy 96.553602 -348.104492)
			(xy 96.607553 -348.112242) (xy 96.659851 -348.127592) (xy 96.709433 -348.15023) (xy 96.755287 -348.179693)
			(xy 96.796482 -348.215383) (xy 96.832177 -348.256573) (xy 96.861646 -348.302423) (xy 96.88429 -348.352002)
			(xy 96.899647 -348.404298) (xy 96.907405 -348.458248) (xy 96.907405 -348.512752) (xy 96.899647 -348.566702)
			(xy 96.88429 -348.618998) (xy 96.861646 -348.668577) (xy 96.832177 -348.714427) (xy 96.796482 -348.755617)
			(xy 96.755287 -348.791307) (xy 96.709433 -348.82077) (xy 96.659851 -348.843408) (xy 96.607553 -348.858758)
			(xy 96.553602 -348.866508) (xy 96.52635 -348.866968) (xy 96.497434 -348.866426) (xy 96.440263 -348.857704)
			(xy 96.385064 -348.840451) (xy 96.333102 -348.815064) (xy 96.285568 -348.782124) (xy 96.24355 -348.742386)
			(xy 96.22536 -348.719902) (xy 96.215463 -348.708097) (xy 96.190139 -348.690578) (xy 96.160746 -348.681402)
			(xy 96.129954 -348.681402) (xy 96.100561 -348.690578) (xy 96.075237 -348.708097) (xy 96.06534 -348.719902)
			(xy 96.047127 -348.742367) (xy 96.005112 -348.782103) (xy 95.957581 -348.815044) (xy 95.905624 -348.840436)
			(xy 95.850431 -348.857696) (xy 95.793265 -348.86643) (xy 95.76435 -348.866968) (xy 95.737098 -348.866559)
			(xy 95.68315 -348.858796) (xy 95.630856 -348.843435) (xy 95.58128 -348.820788) (xy 95.535431 -348.791317)
			(xy 95.494242 -348.755622) (xy 95.458553 -348.714429) (xy 95.429088 -348.668576) (xy 95.406448 -348.618997)
			(xy 95.391094 -348.566701) (xy 95.383338 -348.512752) (xy 95.263264 -348.512752) (xy 95.263264 -348.533754)
			(xy 95.255507 -348.587707) (xy 95.240151 -348.640007) (xy 95.217508 -348.689589) (xy 95.188039 -348.735444)
			(xy 95.152344 -348.776638) (xy 95.11115 -348.812334) (xy 95.065296 -348.841804) (xy 95.015714 -348.864448)
			(xy 94.963415 -348.879805) (xy 94.909462 -348.887564) (xy 94.882208 -348.88805) (xy 94.85329 -348.887545)
			(xy 94.796118 -348.878816) (xy 94.740918 -348.861556) (xy 94.688956 -348.836162) (xy 94.641422 -348.803216)
			(xy 94.599407 -348.763471) (xy 94.581218 -348.740984) (xy 94.571321 -348.729179) (xy 94.545997 -348.71166)
			(xy 94.516604 -348.702484) (xy 94.485812 -348.702484) (xy 94.456419 -348.71166) (xy 94.431095 -348.729179)
			(xy 94.421198 -348.740984) (xy 94.403004 -348.763465) (xy 94.360985 -348.803201) (xy 94.313451 -348.836141)
			(xy 94.26149 -348.86153) (xy 94.206293 -348.878786) (xy 94.149124 -348.887515) (xy 94.120208 -348.88805)
			(xy 94.091642 -348.887476) (xy 94.03515 -348.878952) (xy 93.980557 -348.862107) (xy 93.929083 -348.837318)
			(xy 93.881876 -348.805137) (xy 93.83999 -348.766284) (xy 93.821758 -348.744286) (xy 93.812126 -348.733102)
			(xy 93.787903 -348.716262) (xy 93.75988 -348.707045) (xy 93.730391 -348.706217) (xy 93.701895 -348.713849)
			(xy 93.676767 -348.729304) (xy 93.666564 -348.739968) (xy 93.648379 -348.759569) (xy 93.607499 -348.794029)
			(xy 93.562209 -348.822445) (xy 93.513395 -348.84426) (xy 93.462014 -348.859047) (xy 93.409071 -348.866516)
			(xy 93.382338 -348.866968) (xy 93.353422 -348.866435) (xy 93.29625 -348.85771) (xy 93.241051 -348.840456)
			(xy 93.189089 -348.815068) (xy 93.141555 -348.782126) (xy 93.099538 -348.742387) (xy 93.081348 -348.719902)
			(xy 93.071451 -348.708097) (xy 93.046127 -348.690578) (xy 93.016734 -348.681402) (xy 92.985942 -348.681402)
			(xy 92.956549 -348.690578) (xy 92.931225 -348.708097) (xy 92.921328 -348.719902) (xy 92.904575 -348.740685)
			(xy 92.866221 -348.777815) (xy 92.823067 -348.809237) (xy 92.775953 -348.834336) (xy 92.725801 -348.852622)
			(xy 92.67359 -348.863739) (xy 92.620338 -348.867469) (xy 92.567086 -348.863739) (xy 92.514875 -348.852622)
			(xy 92.464723 -348.834336) (xy 92.417609 -348.809237) (xy 92.374455 -348.777815) (xy 92.336101 -348.740685)
			(xy 92.319348 -348.719902) (xy 92.309451 -348.708097) (xy 92.284127 -348.690578) (xy 92.254734 -348.681402)
			(xy 92.223942 -348.681402) (xy 92.194549 -348.690578) (xy 92.169225 -348.708097) (xy 92.159328 -348.719902)
			(xy 92.142575 -348.740685) (xy 92.104221 -348.777815) (xy 92.061067 -348.809237) (xy 92.013953 -348.834336)
			(xy 91.963801 -348.852622) (xy 91.91159 -348.863739) (xy 91.858338 -348.867469) (xy 91.805086 -348.863739)
			(xy 91.752875 -348.852622) (xy 91.702723 -348.834336) (xy 91.655609 -348.809237) (xy 91.612455 -348.777815)
			(xy 91.574101 -348.740685) (xy 91.557348 -348.719902) (xy 91.547451 -348.708097) (xy 91.522127 -348.690578)
			(xy 91.492734 -348.681402) (xy 91.461942 -348.681402) (xy 91.432549 -348.690578) (xy 91.407225 -348.708097)
			(xy 91.397328 -348.719902) (xy 91.379122 -348.742372) (xy 91.337105 -348.782108) (xy 91.289573 -348.815049)
			(xy 91.237615 -348.840439) (xy 91.18242 -348.857699) (xy 91.125253 -348.866431) (xy 91.096338 -348.866968)
			(xy 91.06908 -348.866588) (xy 91.01512 -348.858834) (xy 90.962812 -348.84348) (xy 90.913222 -348.820837)
			(xy 90.867359 -348.791367) (xy 90.826157 -348.75567) (xy 90.790456 -348.714472) (xy 90.760981 -348.668612)
			(xy 90.738333 -348.619024) (xy 90.722974 -348.566717) (xy 90.715215 -348.512757) (xy 90.509949 -348.512757)
			(xy 90.505197 -348.545806) (xy 90.489841 -348.598105) (xy 90.467198 -348.647686) (xy 90.437729 -348.693541)
			(xy 90.402034 -348.734734) (xy 90.360841 -348.770429) (xy 90.314986 -348.799898) (xy 90.265405 -348.822541)
			(xy 90.213106 -348.837897) (xy 90.159154 -348.845654) (xy 90.1319 -348.84614) (xy 90.102982 -348.845644)
			(xy 90.045809 -348.836914) (xy 89.990608 -348.819653) (xy 89.938646 -348.794257) (xy 89.891113 -348.761308)
			(xy 89.849098 -348.721562) (xy 89.83091 -348.699074) (xy 89.821013 -348.687269) (xy 89.795689 -348.66975)
			(xy 89.766296 -348.660574) (xy 89.735504 -348.660574) (xy 89.706111 -348.66975) (xy 89.680787 -348.687269)
			(xy 89.67089 -348.699074) (xy 89.652698 -348.721557) (xy 89.610679 -348.761293) (xy 89.563145 -348.794233)
			(xy 89.511184 -348.819622) (xy 89.455986 -348.836878) (xy 89.398816 -348.845606) (xy 89.3699 -348.84614)
			(xy 89.369646 -348.84614) (xy 89.343446 -348.845681) (xy 89.291541 -348.838497) (xy 89.241105 -348.824284)
			(xy 89.193086 -348.803309) (xy 89.17051 -348.790006) (xy 89.160875 -348.784726) (xy 89.139075 -348.782162)
			(xy 89.118188 -348.788913) (xy 89.102011 -348.80375) (xy 89.093486 -348.823978) (xy 89.093294 -348.834964)
			(xy 89.093548 -348.848172) (xy 89.093485 -348.85931) (xy 89.092212 -348.881549) (xy 89.091008 -348.892622)
			(xy 89.089693 -348.907591) (xy 89.094978 -348.937162) (xy 89.108636 -348.963917) (xy 89.129485 -348.985543)
			(xy 89.155724 -349.000168) (xy 89.185082 -349.00653) (xy 89.215021 -349.004077) (xy 89.229184 -348.999048)
			(xy 89.251653 -348.990521) (xy 89.298193 -348.978532) (xy 89.34587 -348.972489) (xy 89.3699 -348.972124)
			(xy 89.398817 -348.972633) (xy 89.455989 -348.981363) (xy 89.511189 -348.998622) (xy 89.563151 -349.024015)
			(xy 89.610684 -349.056961) (xy 89.6527 -349.096704) (xy 89.67089 -349.11919) (xy 89.680787 -349.130995)
			(xy 89.706111 -349.148514) (xy 89.735504 -349.15769) (xy 89.766296 -349.15769) (xy 89.795689 -349.148514)
			(xy 89.821013 -349.130995) (xy 89.83091 -349.11919) (xy 89.849093 -349.0967) (xy 89.891115 -349.056965)
			(xy 89.938651 -349.024027) (xy 89.990614 -348.99864) (xy 90.045813 -348.981385) (xy 90.102984 -348.972658)
			(xy 90.1319 -348.972124) (xy 90.159154 -348.972555) (xy 90.213108 -348.980313) (xy 90.265408 -348.995671)
			(xy 90.314991 -349.018316) (xy 90.360845 -349.047787) (xy 90.402039 -349.083484) (xy 90.437733 -349.12468)
			(xy 90.4672 -349.170537) (xy 90.48984 -349.220122) (xy 90.505194 -349.272423) (xy 90.512947 -349.326378)
			(xy 90.513408 -349.353632) (xy 90.512876 -349.382549) (xy 90.504154 -349.439721) (xy 90.486902 -349.494921)
			(xy 90.461513 -349.546884) (xy 90.42857 -349.594417) (xy 90.388828 -349.636433) (xy 90.366342 -349.654622)
			(xy 90.354502 -349.664483) (xy 90.33698 -349.689815) (xy 90.327805 -349.719219) (xy 90.327811 -349.750021)
			(xy 90.336997 -349.779421) (xy 90.354529 -349.804746) (xy 90.366342 -349.814642) (xy 90.387156 -349.831358)
			(xy 90.424287 -349.869715) (xy 90.455708 -349.912875) (xy 90.480807 -349.959992) (xy 90.499092 -350.010149)
			(xy 90.510206 -350.062365) (xy 90.513933 -350.11562) (xy 90.512473 -350.13646) (xy 90.71483 -350.13646)
			(xy 90.71538 -350.107544) (xy 90.724101 -350.050374) (xy 90.741352 -349.995175) (xy 90.766737 -349.943213)
			(xy 90.799676 -349.895678) (xy 90.839412 -349.853661) (xy 90.861896 -349.83547) (xy 90.87374 -349.825616)
			(xy 90.891256 -349.80028) (xy 90.900426 -349.770876) (xy 90.900419 -349.740075) (xy 90.891234 -349.710676)
			(xy 90.873706 -349.685348) (xy 90.861896 -349.67545) (xy 90.839436 -349.657232) (xy 90.799699 -349.615218)
			(xy 90.766758 -349.567688) (xy 90.741365 -349.515732) (xy 90.724104 -349.46054) (xy 90.715369 -349.403374)
			(xy 90.71483 -349.37446) (xy 90.715241 -349.347206) (xy 90.723004 -349.293254) (xy 90.738366 -349.240955)
			(xy 90.761014 -349.191375) (xy 90.790488 -349.145523) (xy 90.826188 -349.104332) (xy 90.867386 -349.068642)
			(xy 90.913244 -349.039177) (xy 90.962828 -349.016538) (xy 91.01513 -349.001187) (xy 91.069084 -348.993435)
			(xy 91.096338 -348.992952) (xy 91.125254 -348.993495) (xy 91.182425 -349.002217) (xy 91.237624 -349.019468)
			(xy 91.289586 -349.044855) (xy 91.337121 -349.077795) (xy 91.379138 -349.117534) (xy 91.397328 -349.140018)
			(xy 91.407225 -349.151823) (xy 91.432549 -349.169342) (xy 91.461942 -349.178518) (xy 91.492734 -349.178518)
			(xy 91.522127 -349.169342) (xy 91.547451 -349.151823) (xy 91.557348 -349.140018) (xy 91.574101 -349.119235)
			(xy 91.612455 -349.082105) (xy 91.655609 -349.050683) (xy 91.702723 -349.025584) (xy 91.752875 -349.007298)
			(xy 91.805086 -348.996181) (xy 91.858338 -348.992451) (xy 91.91159 -348.996181) (xy 91.963801 -349.007298)
			(xy 92.013953 -349.025584) (xy 92.061067 -349.050683) (xy 92.104221 -349.082105) (xy 92.142575 -349.119235)
			(xy 92.159328 -349.140018) (xy 92.169225 -349.151823) (xy 92.194549 -349.169342) (xy 92.223942 -349.178518)
			(xy 92.254734 -349.178518) (xy 92.284127 -349.169342) (xy 92.309451 -349.151823) (xy 92.319348 -349.140018)
			(xy 92.336101 -349.119235) (xy 92.374455 -349.082105) (xy 92.417609 -349.050683) (xy 92.464723 -349.025584)
			(xy 92.514875 -349.007298) (xy 92.567086 -348.996181) (xy 92.620338 -348.992451) (xy 92.67359 -348.996181)
			(xy 92.725801 -349.007298) (xy 92.775953 -349.025584) (xy 92.823067 -349.050683) (xy 92.866221 -349.082105)
			(xy 92.904575 -349.119235) (xy 92.921328 -349.140018) (xy 92.931225 -349.151823) (xy 92.956549 -349.169342)
			(xy 92.985942 -349.178518) (xy 93.016734 -349.178518) (xy 93.046127 -349.169342) (xy 93.071451 -349.151823)
			(xy 93.081348 -349.140018) (xy 93.099573 -349.117563) (xy 93.141585 -349.077825) (xy 93.189113 -349.044882)
			(xy 93.241067 -349.019489) (xy 93.296259 -349.002227) (xy 93.353424 -348.993491) (xy 93.382338 -348.992952)
			(xy 93.410905 -348.993492) (xy 93.467399 -349.002024) (xy 93.521992 -349.018875) (xy 93.573466 -349.04367)
			(xy 93.620672 -349.075857) (xy 93.662557 -349.114716) (xy 93.680788 -349.136716) (xy 93.690372 -349.147945)
			(xy 93.714608 -349.164783) (xy 93.742643 -349.173996) (xy 93.772143 -349.174814) (xy 93.800646 -349.167172)
			(xy 93.825779 -349.151704) (xy 93.835982 -349.141034) (xy 93.854145 -349.121411) (xy 93.895029 -349.086953)
			(xy 93.940324 -349.05854) (xy 93.989143 -349.036728) (xy 94.040528 -349.021946) (xy 94.093473 -349.014482)
			(xy 94.120208 -349.014034) (xy 94.149123 -349.014606) (xy 94.206292 -349.023322) (xy 94.261491 -349.040568)
			(xy 94.313453 -349.06595) (xy 94.360988 -349.098885) (xy 94.403007 -349.138618) (xy 94.421198 -349.1611)
			(xy 94.431095 -349.172905) (xy 94.456419 -349.190424) (xy 94.485812 -349.1996) (xy 94.516604 -349.1996)
			(xy 94.545997 -349.190424) (xy 94.571321 -349.172905) (xy 94.581218 -349.1611) (xy 94.599399 -349.138608)
			(xy 94.641421 -349.098873) (xy 94.688958 -349.065935) (xy 94.740921 -349.040548) (xy 94.79612 -349.023294)
			(xy 94.853291 -349.014568) (xy 94.882208 -349.014034) (xy 94.909463 -349.014448) (xy 94.963418 -349.022207)
			(xy 95.015719 -349.037566) (xy 95.065302 -349.060213) (xy 95.111157 -349.089686) (xy 95.152351 -349.125385)
			(xy 95.188044 -349.166583) (xy 95.217511 -349.212442) (xy 95.240151 -349.262028) (xy 95.255503 -349.314331)
			(xy 95.263256 -349.368287) (xy 95.263716 -349.395542) (xy 95.26314 -349.424984) (xy 95.254075 -349.483167)
			(xy 95.236182 -349.539267) (xy 95.209886 -349.591954) (xy 95.17581 -349.639978) (xy 95.134764 -349.682198)
			(xy 95.11157 -349.700342) (xy 95.101069 -349.708669) (xy 95.084553 -349.729767) (xy 95.074096 -349.754435)
			(xy 95.070417 -349.780975) (xy 95.073771 -349.807558) (xy 95.083926 -349.832353) (xy 95.100182 -349.853651)
			(xy 95.110554 -349.86214) (xy 95.133163 -349.880342) (xy 95.173168 -349.922394) (xy 95.20634 -349.970022)
			(xy 95.231914 -350.022125) (xy 95.249298 -350.077501) (xy 95.258093 -350.134872) (xy 95.258123 -350.136475)
			(xy 95.382291 -350.136475) (xy 95.386025 -350.083218) (xy 95.397148 -350.031001) (xy 95.415441 -349.980845)
			(xy 95.440549 -349.933729) (xy 95.471979 -349.890574) (xy 95.50912 -349.852222) (xy 95.529908 -349.83547)
			(xy 95.541751 -349.825615) (xy 95.559264 -349.800279) (xy 95.568434 -349.770875) (xy 95.568426 -349.740076)
			(xy 95.559243 -349.710677) (xy 95.541717 -349.685349) (xy 95.529908 -349.67545) (xy 95.50745 -349.657229)
			(xy 95.467713 -349.615216) (xy 95.434771 -349.567687) (xy 95.409378 -349.515732) (xy 95.392116 -349.460539)
			(xy 95.383381 -349.403374) (xy 95.382842 -349.37446) (xy 95.383218 -349.347204) (xy 95.390982 -349.293247)
			(xy 95.406345 -349.240945) (xy 95.428996 -349.191361) (xy 95.458473 -349.145506) (xy 95.494176 -349.104312)
			(xy 95.535378 -349.068619) (xy 95.58124 -349.039153) (xy 95.630829 -349.016514) (xy 95.683135 -349.001162)
			(xy 95.737094 -348.993411) (xy 95.76435 -348.992952) (xy 95.793267 -348.993486) (xy 95.850438 -349.002209)
			(xy 95.905637 -349.019463) (xy 95.9576 -349.044851) (xy 96.005134 -349.077793) (xy 96.04715 -349.117533)
			(xy 96.06534 -349.140018) (xy 96.075237 -349.151823) (xy 96.100561 -349.169342) (xy 96.129954 -349.178518)
			(xy 96.160746 -349.178518) (xy 96.190139 -349.169342) (xy 96.215463 -349.151823) (xy 96.22536 -349.140018)
			(xy 96.243578 -349.117557) (xy 96.285592 -349.07782) (xy 96.333121 -349.044878) (xy 96.385077 -349.019485)
			(xy 96.44027 -349.002224) (xy 96.497436 -348.99349) (xy 96.52635 -348.992952) (xy 96.5536 -348.993502)
			(xy 96.607546 -349.001251) (xy 96.659839 -349.016598) (xy 96.709417 -349.039232) (xy 96.755268 -349.068691)
			(xy 96.79646 -349.104376) (xy 96.832155 -349.14556) (xy 96.861625 -349.191404) (xy 96.88427 -349.240976)
			(xy 96.89963 -349.293266) (xy 96.907392 -349.34721) (xy 96.907858 -349.37446) (xy 96.907327 -349.403377)
			(xy 96.898603 -349.460548) (xy 96.881348 -349.515747) (xy 96.855959 -349.567709) (xy 96.823017 -349.615243)
			(xy 96.783277 -349.65726) (xy 96.760792 -349.67545) (xy 96.749029 -349.685392) (xy 96.731514 -349.710704)
			(xy 96.722336 -349.740085) (xy 96.722329 -349.770866) (xy 96.731493 -349.800251) (xy 96.748995 -349.825572)
			(xy 96.760792 -349.83547) (xy 96.781538 -349.852269) (xy 96.818672 -349.890615) (xy 96.850097 -349.933763)
			(xy 96.875201 -349.980871) (xy 96.893491 -350.031019) (xy 96.904612 -350.083227) (xy 96.908345 -350.136475)
			(xy 96.904619 -350.189724) (xy 96.893505 -350.241934) (xy 96.875221 -350.292084) (xy 96.850124 -350.339195)
			(xy 96.818704 -350.382347) (xy 96.781574 -350.420698) (xy 96.760792 -350.43745) (xy 96.749029 -350.447392)
			(xy 96.731514 -350.472704) (xy 96.730329 -350.476496) (xy 115.595396 -350.476496) (xy 115.595396 -350.3918)
			(xy 115.603447 -350.307486) (xy 115.619476 -350.22432) (xy 115.643337 -350.143053) (xy 115.674816 -350.064423)
			(xy 115.713627 -349.989142) (xy 115.759417 -349.91789) (xy 115.811773 -349.851314) (xy 115.870221 -349.790016)
			(xy 115.934231 -349.734551) (xy 116.003223 -349.685422) (xy 116.076573 -349.643073) (xy 116.153616 -349.607889)
			(xy 116.233655 -349.580187) (xy 116.315964 -349.560219) (xy 116.399799 -349.548166) (xy 116.4844 -349.544136)
			(xy 116.569001 -349.548166) (xy 116.652836 -349.560219) (xy 116.735145 -349.580187) (xy 116.815184 -349.607889)
			(xy 116.892227 -349.643073) (xy 116.965577 -349.685422) (xy 117.034569 -349.734551) (xy 117.098579 -349.790016)
			(xy 117.157027 -349.851314) (xy 117.209383 -349.91789) (xy 117.255173 -349.989142) (xy 117.293984 -350.064423)
			(xy 117.325463 -350.143053) (xy 117.349324 -350.22432) (xy 117.365353 -350.307486) (xy 117.373404 -350.3918)
			(xy 117.373908 -350.434148) (xy 118.119909 -350.434148) (xy 118.123945 -350.350701) (xy 118.136017 -350.268033)
			(xy 118.15601 -350.186916) (xy 118.183739 -350.108107) (xy 118.218945 -350.032342) (xy 118.261299 -349.960329)
			(xy 118.310405 -349.89274) (xy 118.365806 -349.830206) (xy 118.426983 -349.773311) (xy 118.493366 -349.722585)
			(xy 118.564334 -349.678504) (xy 118.639226 -349.641478) (xy 118.717342 -349.611852) (xy 118.797952 -349.589904)
			(xy 118.880304 -349.575839) (xy 118.96363 -349.569787) (xy 119.04715 -349.571806) (xy 119.130086 -349.581876)
			(xy 119.211662 -349.599904) (xy 119.291118 -349.625721) (xy 119.367711 -349.659086) (xy 119.440727 -349.699687)
			(xy 119.509483 -349.747146) (xy 119.573337 -349.801019) (xy 119.631694 -349.860804) (xy 119.684009 -349.925941)
			(xy 119.729792 -349.995824) (xy 119.768617 -350.069799) (xy 119.800122 -350.147176) (xy 119.824011 -350.227233)
			(xy 119.840062 -350.309221) (xy 119.848125 -350.392376) (xy 119.84863 -350.434148) (xy 119.848125 -350.47592)
			(xy 119.840062 -350.559075) (xy 119.824011 -350.641063) (xy 119.800122 -350.72112) (xy 119.768617 -350.798497)
			(xy 119.729792 -350.872472) (xy 119.684009 -350.942355) (xy 119.631694 -351.007492) (xy 119.573337 -351.067277)
			(xy 119.509483 -351.12115) (xy 119.440727 -351.168609) (xy 119.367711 -351.20921) (xy 119.291118 -351.242575)
			(xy 119.211662 -351.268392) (xy 119.130086 -351.28642) (xy 119.04715 -351.29649) (xy 118.96363 -351.298509)
			(xy 118.880304 -351.292457) (xy 118.797952 -351.278392) (xy 118.717342 -351.256444) (xy 118.639226 -351.226818)
			(xy 118.564334 -351.189792) (xy 118.493366 -351.145711) (xy 118.426983 -351.094985) (xy 118.365806 -351.03809)
			(xy 118.310405 -350.975556) (xy 118.261299 -350.907967) (xy 118.218945 -350.835954) (xy 118.183739 -350.760189)
			(xy 118.15601 -350.68138) (xy 118.136017 -350.600263) (xy 118.123945 -350.517595) (xy 118.119909 -350.434148)
			(xy 117.373908 -350.434148) (xy 117.373404 -350.476496) (xy 117.365353 -350.56081) (xy 117.349324 -350.643976)
			(xy 117.325463 -350.725243) (xy 117.293984 -350.803873) (xy 117.255173 -350.879154) (xy 117.209383 -350.950406)
			(xy 117.157027 -351.016982) (xy 117.098579 -351.07828) (xy 117.034569 -351.133745) (xy 116.965577 -351.182874)
			(xy 116.892227 -351.225223) (xy 116.815184 -351.260407) (xy 116.735145 -351.288109) (xy 116.652836 -351.308077)
			(xy 116.569001 -351.32013) (xy 116.4844 -351.324161) (xy 116.399799 -351.32013) (xy 116.315964 -351.308077)
			(xy 116.233655 -351.288109) (xy 116.153616 -351.260407) (xy 116.076573 -351.225223) (xy 116.003223 -351.182874)
			(xy 115.934231 -351.133745) (xy 115.870221 -351.07828) (xy 115.811773 -351.016982) (xy 115.759417 -350.950406)
			(xy 115.713627 -350.879154) (xy 115.674816 -350.803873) (xy 115.643337 -350.725243) (xy 115.619476 -350.643976)
			(xy 115.603447 -350.56081) (xy 115.595396 -350.476496) (xy 96.730329 -350.476496) (xy 96.722336 -350.502085)
			(xy 96.722329 -350.532866) (xy 96.731493 -350.562251) (xy 96.748995 -350.587572) (xy 96.760792 -350.59747)
			(xy 96.783259 -350.61568) (xy 96.822996 -350.657696) (xy 96.855937 -350.705226) (xy 96.881328 -350.757184)
			(xy 96.898588 -350.812378) (xy 96.907321 -350.869545) (xy 96.907858 -350.89846) (xy 96.907407 -350.925714)
			(xy 96.899655 -350.979668) (xy 96.884301 -351.031969) (xy 96.86166 -351.081553) (xy 96.832191 -351.127408)
			(xy 96.796496 -351.168603) (xy 96.7553 -351.204297) (xy 96.709444 -351.233764) (xy 96.65986 -351.256405)
			(xy 96.607558 -351.271757) (xy 96.553604 -351.279508) (xy 96.52635 -351.279968) (xy 96.497434 -351.279426)
			(xy 96.440263 -351.270704) (xy 96.385064 -351.253451) (xy 96.333102 -351.228064) (xy 96.285568 -351.195124)
			(xy 96.24355 -351.155386) (xy 96.22536 -351.132902) (xy 96.215463 -351.121097) (xy 96.190139 -351.103578)
			(xy 96.160746 -351.094402) (xy 96.129954 -351.094402) (xy 96.100561 -351.103578) (xy 96.075237 -351.121097)
			(xy 96.06534 -351.132902) (xy 96.047127 -351.155367) (xy 96.005112 -351.195103) (xy 95.957581 -351.228044)
			(xy 95.905624 -351.253436) (xy 95.850431 -351.270696) (xy 95.793265 -351.27943) (xy 95.76435 -351.279968)
			(xy 95.737097 -351.279498) (xy 95.683144 -351.271747) (xy 95.630844 -351.256395) (xy 95.581261 -351.233756)
			(xy 95.535406 -351.204289) (xy 95.494211 -351.168596) (xy 95.458517 -351.127402) (xy 95.429049 -351.081548)
			(xy 95.406408 -351.031966) (xy 95.391055 -350.979666) (xy 95.383303 -350.925713) (xy 95.382842 -350.89846)
			(xy 95.383387 -350.869544) (xy 95.392108 -350.812373) (xy 95.40936 -350.757174) (xy 95.434746 -350.705212)
			(xy 95.467686 -350.657678) (xy 95.507424 -350.61566) (xy 95.529908 -350.59747) (xy 95.541751 -350.587615)
			(xy 95.559264 -350.562279) (xy 95.568434 -350.532875) (xy 95.568426 -350.502076) (xy 95.559243 -350.472677)
			(xy 95.541717 -350.447349) (xy 95.529908 -350.43745) (xy 95.509083 -350.420745) (xy 95.471948 -350.382388)
			(xy 95.440522 -350.339229) (xy 95.415421 -350.29211) (xy 95.397134 -350.241951) (xy 95.386018 -350.189733)
			(xy 95.382291 -350.136475) (xy 95.258123 -350.136475) (xy 95.258636 -350.163892) (xy 95.25815 -350.191143)
			(xy 95.250394 -350.245091) (xy 95.235039 -350.297386) (xy 95.212397 -350.346963) (xy 95.182931 -350.392813)
			(xy 95.14724 -350.434004) (xy 95.106049 -350.469695) (xy 95.060199 -350.499161) (xy 95.010622 -350.521803)
			(xy 94.958327 -350.537158) (xy 94.904379 -350.544914) (xy 94.849877 -350.544914) (xy 94.795929 -350.537158)
			(xy 94.743634 -350.521803) (xy 94.694057 -350.499161) (xy 94.648207 -350.469695) (xy 94.607016 -350.434004)
			(xy 94.571325 -350.392813) (xy 94.541859 -350.346963) (xy 94.519217 -350.297386) (xy 94.503862 -350.245091)
			(xy 94.496106 -350.191143) (xy 94.49562 -350.163892) (xy 94.496134 -350.134447) (xy 94.50521 -350.076261)
			(xy 94.523114 -350.020159) (xy 94.549422 -349.967472) (xy 94.583509 -349.91945) (xy 94.624567 -349.877233)
			(xy 94.647766 -349.859092) (xy 94.65823 -349.850724) (xy 94.67474 -349.829634) (xy 94.685196 -349.804975)
			(xy 94.688878 -349.778445) (xy 94.685532 -349.751871) (xy 94.675388 -349.727082) (xy 94.659146 -349.705784)
			(xy 94.648782 -349.697294) (xy 94.63008 -349.682385) (xy 94.596195 -349.648631) (xy 94.581218 -349.629984)
			(xy 94.571321 -349.618179) (xy 94.545997 -349.60066) (xy 94.516604 -349.591484) (xy 94.485812 -349.591484)
			(xy 94.456419 -349.60066) (xy 94.431095 -349.618179) (xy 94.421198 -349.629984) (xy 94.403004 -349.652465)
			(xy 94.360985 -349.692201) (xy 94.313451 -349.725141) (xy 94.26149 -349.75053) (xy 94.206293 -349.767786)
			(xy 94.149124 -349.776515) (xy 94.120208 -349.77705) (xy 94.091642 -349.776476) (xy 94.03515 -349.767952)
			(xy 93.980557 -349.751107) (xy 93.929083 -349.726318) (xy 93.881876 -349.694137) (xy 93.83999 -349.655284)
			(xy 93.821758 -349.633286) (xy 93.812126 -349.622102) (xy 93.787903 -349.605262) (xy 93.75988 -349.596045)
			(xy 93.730391 -349.595217) (xy 93.701895 -349.602849) (xy 93.676767 -349.618304) (xy 93.666564 -349.628968)
			(xy 93.648379 -349.648569) (xy 93.607499 -349.683029) (xy 93.562209 -349.711445) (xy 93.513395 -349.73326)
			(xy 93.462014 -349.748047) (xy 93.409071 -349.755516) (xy 93.382338 -349.755968) (xy 93.353422 -349.755435)
			(xy 93.29625 -349.74671) (xy 93.241051 -349.729456) (xy 93.189089 -349.704068) (xy 93.141555 -349.671126)
			(xy 93.099538 -349.631387) (xy 93.081348 -349.608902) (xy 93.071451 -349.597097) (xy 93.046127 -349.579578)
			(xy 93.016734 -349.570402) (xy 92.985942 -349.570402) (xy 92.956549 -349.579578) (xy 92.931225 -349.597097)
			(xy 92.921328 -349.608902) (xy 92.904575 -349.629685) (xy 92.866221 -349.666815) (xy 92.823067 -349.698237)
			(xy 92.775953 -349.723336) (xy 92.725801 -349.741622) (xy 92.67359 -349.752739) (xy 92.620338 -349.756469)
			(xy 92.567086 -349.752739) (xy 92.514875 -349.741622) (xy 92.464723 -349.723336) (xy 92.417609 -349.698237)
			(xy 92.374455 -349.666815) (xy 92.336101 -349.629685) (xy 92.319348 -349.608902) (xy 92.309451 -349.597097)
			(xy 92.284127 -349.579578) (xy 92.254734 -349.570402) (xy 92.223942 -349.570402) (xy 92.194549 -349.579578)
			(xy 92.169225 -349.597097) (xy 92.159328 -349.608902) (xy 92.142575 -349.629685) (xy 92.104221 -349.666815)
			(xy 92.061067 -349.698237) (xy 92.013953 -349.723336) (xy 91.963801 -349.741622) (xy 91.91159 -349.752739)
			(xy 91.858338 -349.756469) (xy 91.805086 -349.752739) (xy 91.752875 -349.741622) (xy 91.702723 -349.723336)
			(xy 91.655609 -349.698237) (xy 91.612455 -349.666815) (xy 91.574101 -349.629685) (xy 91.557348 -349.608902)
			(xy 91.547451 -349.597097) (xy 91.522127 -349.579578) (xy 91.492734 -349.570402) (xy 91.461942 -349.570402)
			(xy 91.432549 -349.579578) (xy 91.407225 -349.597097) (xy 91.397328 -349.608902) (xy 91.382552 -349.627303)
			(xy 91.34918 -349.660673) (xy 91.33078 -349.67545) (xy 91.319018 -349.685393) (xy 91.301506 -349.710705)
			(xy 91.292329 -349.740086) (xy 91.292321 -349.770865) (xy 91.301484 -349.80025) (xy 91.318984 -349.825571)
			(xy 91.33078 -349.83547) (xy 91.353245 -349.853683) (xy 91.392982 -349.895698) (xy 91.425924 -349.943228)
			(xy 91.451316 -349.995185) (xy 91.468576 -350.050379) (xy 91.477309 -350.107545) (xy 91.477846 -350.13646)
			(xy 91.47736 -350.163711) (xy 91.469604 -350.217659) (xy 91.454249 -350.269954) (xy 91.431607 -350.319531)
			(xy 91.402141 -350.365381) (xy 91.36645 -350.406572) (xy 91.325259 -350.442263) (xy 91.279409 -350.471729)
			(xy 91.229832 -350.494371) (xy 91.177537 -350.509726) (xy 91.123589 -350.517482) (xy 91.069087 -350.517482)
			(xy 91.015139 -350.509726) (xy 90.962844 -350.494371) (xy 90.913267 -350.471729) (xy 90.867417 -350.442263)
			(xy 90.826226 -350.406572) (xy 90.790535 -350.365381) (xy 90.761069 -350.319531) (xy 90.738427 -350.269954)
			(xy 90.723072 -350.217659) (xy 90.715316 -350.163711) (xy 90.71483 -350.13646) (xy 90.512473 -350.13646)
			(xy 90.510201 -350.168874) (xy 90.499081 -350.221089) (xy 90.480791 -350.271244) (xy 90.455688 -350.318359)
			(xy 90.424262 -350.361515) (xy 90.387127 -350.399869) (xy 90.366342 -350.416622) (xy 90.354502 -350.426483)
			(xy 90.33698 -350.451815) (xy 90.327805 -350.481219) (xy 90.327811 -350.512021) (xy 90.336997 -350.541421)
			(xy 90.354529 -350.566746) (xy 90.366342 -350.576642) (xy 90.388854 -350.594799) (xy 90.428586 -350.636827)
			(xy 90.46152 -350.684369) (xy 90.486903 -350.736337) (xy 90.504154 -350.79154) (xy 90.512876 -350.848714)
			(xy 90.513408 -350.877632) (xy 90.512952 -350.904884) (xy 90.505191 -350.958833) (xy 90.489832 -351.011128)
			(xy 90.467187 -351.060705) (xy 90.437717 -351.106556) (xy 90.402023 -351.147746) (xy 90.36083 -351.183437)
			(xy 90.314977 -351.212902) (xy 90.265398 -351.235543) (xy 90.213102 -351.250898) (xy 90.159152 -351.258654)
			(xy 90.1319 -351.25914) (xy 90.102982 -351.258644) (xy 90.045809 -351.249914) (xy 89.990608 -351.232653)
			(xy 89.938646 -351.207257) (xy 89.891113 -351.174308) (xy 89.849098 -351.134562) (xy 89.83091 -351.112074)
			(xy 89.821013 -351.100269) (xy 89.795689 -351.08275) (xy 89.766296 -351.073574) (xy 89.735504 -351.073574)
			(xy 89.706111 -351.08275) (xy 89.680787 -351.100269) (xy 89.67089 -351.112074) (xy 89.652698 -351.134557)
			(xy 89.610679 -351.174293) (xy 89.563145 -351.207233) (xy 89.511184 -351.232622) (xy 89.455986 -351.249878)
			(xy 89.398816 -351.258606) (xy 89.3699 -351.25914) (xy 89.342694 -351.258661) (xy 89.288835 -351.250917)
			(xy 89.236622 -351.235599) (xy 89.187116 -351.21302) (xy 89.141319 -351.183636) (xy 89.100161 -351.148044)
			(xy 89.064477 -351.106966) (xy 89.03499 -351.061235) (xy 89.0123 -351.011779) (xy 88.996866 -350.959601)
			(xy 88.992456 -350.93275) (xy 88.989721 -350.91765) (xy 88.976444 -350.889996) (xy 88.955567 -350.867522)
			(xy 88.928965 -350.852247) (xy 88.89903 -350.845546) (xy 88.868455 -350.84802) (xy 88.854026 -350.853248)
			(xy 88.831378 -350.861945) (xy 88.784423 -350.874154) (xy 88.736298 -350.880304) (xy 88.71204 -350.88068)
			(xy 88.684787 -350.880207) (xy 88.630835 -350.872455) (xy 88.578535 -350.857103) (xy 88.528954 -350.834463)
			(xy 88.483099 -350.804996) (xy 88.441905 -350.769303) (xy 88.406211 -350.728111) (xy 88.376743 -350.682257)
			(xy 88.354101 -350.632676) (xy 88.338747 -350.580377) (xy 88.330993 -350.526425) (xy 88.330532 -350.499172)
			(xy 77.29388 -350.499172) (xy 77.293978 -350.505014) (xy 77.293492 -350.532265) (xy 77.285736 -350.586213)
			(xy 77.270381 -350.638508) (xy 77.247739 -350.688085) (xy 77.218273 -350.733935) (xy 77.182582 -350.775126)
			(xy 77.141391 -350.810817) (xy 77.095541 -350.840283) (xy 77.045964 -350.862925) (xy 76.993669 -350.87828)
			(xy 76.939721 -350.886036) (xy 76.885219 -350.886036) (xy 76.831271 -350.87828) (xy 76.778976 -350.862925)
			(xy 76.729399 -350.840283) (xy 76.683549 -350.810817) (xy 76.642358 -350.775126) (xy 76.606667 -350.733935)
			(xy 76.577201 -350.688085) (xy 76.554559 -350.638508) (xy 76.539204 -350.586213) (xy 76.531448 -350.532265)
			(xy 76.530962 -350.505014) (xy 75.89774 -350.505014) (xy 75.89774 -351.700592) (xy 103.994964 -351.700592)
			(xy 103.999035 -351.64497) (xy 104.011161 -351.590533) (xy 104.031084 -351.538442) (xy 104.05838 -351.489807)
			(xy 104.092466 -351.445664) (xy 104.132615 -351.406955) (xy 104.177973 -351.374504) (xy 104.227573 -351.349003)
			(xy 104.280357 -351.330996) (xy 104.3352 -351.320866) (xy 104.390934 -351.318829) (xy 104.446371 -351.324929)
			(xy 104.500328 -351.339035) (xy 104.551657 -351.360847) (xy 104.599263 -351.389901) (xy 104.642131 -351.425576)
			(xy 104.679348 -351.467113) (xy 104.710121 -351.513626) (xy 104.733793 -351.564123) (xy 104.749861 -351.61753)
			(xy 104.757981 -351.672706) (xy 104.75849 -351.700592) (xy 104.757981 -351.728478) (xy 104.749861 -351.783654)
			(xy 104.733793 -351.837061) (xy 104.710121 -351.887558) (xy 104.679348 -351.934071) (xy 104.642131 -351.975608)
			(xy 104.599263 -352.011283) (xy 104.551657 -352.040337) (xy 104.500328 -352.062149) (xy 104.446371 -352.076255)
			(xy 104.390934 -352.082355) (xy 104.3352 -352.080318) (xy 104.280357 -352.070188) (xy 104.227573 -352.052181)
			(xy 104.177973 -352.02668) (xy 104.132615 -351.994229) (xy 104.092466 -351.95552) (xy 104.05838 -351.911377)
			(xy 104.031084 -351.862742) (xy 104.011161 -351.810651) (xy 103.999035 -351.756214) (xy 103.994964 -351.700592)
			(xy 75.89774 -351.700592) (xy 75.89774 -352.022918) (xy 76.07427 -352.476308) (xy 76.594208 -353.812856)
			(xy 77.82941 -355.048058) (xy 99.42652 -355.048058) (xy 99.430591 -354.992436) (xy 99.442717 -354.937999)
			(xy 99.46264 -354.885908) (xy 99.489936 -354.837273) (xy 99.524022 -354.79313) (xy 99.564171 -354.754421)
			(xy 99.609529 -354.72197) (xy 99.659129 -354.696469) (xy 99.711913 -354.678462) (xy 99.766756 -354.668332)
			(xy 99.82249 -354.666295) (xy 99.877927 -354.672395) (xy 99.931884 -354.686501) (xy 99.983213 -354.708313)
			(xy 100.030819 -354.737367) (xy 100.073687 -354.773042) (xy 100.110904 -354.814579) (xy 100.141677 -354.861092)
			(xy 100.165349 -354.911589) (xy 100.181417 -354.964996) (xy 100.189537 -355.020172) (xy 100.190046 -355.048058)
			(xy 100.189537 -355.075944) (xy 100.181417 -355.13112) (xy 100.165349 -355.184527) (xy 100.141677 -355.235024)
			(xy 100.110904 -355.281537) (xy 100.073687 -355.323074) (xy 100.030819 -355.358749) (xy 99.983213 -355.387803)
			(xy 99.931884 -355.409615) (xy 99.877927 -355.423721) (xy 99.82249 -355.429821) (xy 99.766756 -355.427784)
			(xy 99.711913 -355.417654) (xy 99.659129 -355.399647) (xy 99.609529 -355.374146) (xy 99.564171 -355.341695)
			(xy 99.524022 -355.302986) (xy 99.489936 -355.258843) (xy 99.46264 -355.210208) (xy 99.442717 -355.158117)
			(xy 99.430591 -355.10368) (xy 99.42652 -355.048058) (xy 77.82941 -355.048058) (xy 82.775806 -359.994454)
			(xy 87.567516 -359.994454) (xy 87.568039 -359.964944) (xy 87.577109 -359.906626) (xy 87.595057 -359.850402)
			(xy 87.621454 -359.797615) (xy 87.655669 -359.749525) (xy 87.696885 -359.707282) (xy 87.72017 -359.689146)
			(xy 87.731669 -359.679895) (xy 87.749252 -359.65621) (xy 87.759335 -359.628487) (xy 87.761075 -359.59904)
			(xy 87.754328 -359.570324) (xy 87.739657 -359.544732) (xy 87.729314 -359.534206) (xy 87.710907 -359.516162)
			(xy 87.678669 -359.475943) (xy 87.652144 -359.431746) (xy 87.631817 -359.384378) (xy 87.618058 -359.334703)
			(xy 87.611119 -359.283627) (xy 87.610696 -359.257854) (xy 87.611135 -359.230601) (xy 87.618898 -359.176652)
			(xy 87.634259 -359.124356) (xy 87.656906 -359.074778) (xy 87.686377 -359.028928) (xy 87.722074 -358.987738)
			(xy 87.763268 -358.952047) (xy 87.809122 -358.922582) (xy 87.858703 -358.899942) (xy 87.911001 -358.884587)
			(xy 87.964951 -358.876831) (xy 87.992204 -358.876346) (xy 88.020942 -358.876882) (xy 88.077768 -358.885504)
			(xy 88.132658 -358.902552) (xy 88.18437 -358.92764) (xy 88.231734 -358.960201) (xy 88.253062 -358.97947)
			(xy 88.264929 -358.989692) (xy 88.293199 -359.003124) (xy 88.324209 -359.007369) (xy 88.35505 -359.002028)
			(xy 88.382827 -358.987604) (xy 88.394286 -358.97693) (xy 88.403382 -358.96806) (xy 88.422574 -358.951408)
			(xy 88.43264 -358.943656) (xy 88.444447 -358.933923) (xy 88.462142 -358.908978) (xy 88.471662 -358.879914)
			(xy 88.472154 -358.849335) (xy 88.463574 -358.81998) (xy 88.44669 -358.794479) (xy 88.43518 -358.784398)
			(xy 88.413773 -358.766185) (xy 88.376036 -358.724534) (xy 88.344817 -358.677798) (xy 88.320791 -358.626987)
			(xy 88.30448 -358.573202) (xy 88.296234 -358.517606) (xy 88.295734 -358.489504) (xy 88.296173 -358.463163)
			(xy 88.303428 -358.410981) (xy 88.317788 -358.360293) (xy 88.338978 -358.31206) (xy 88.366598 -358.267197)
			(xy 88.400123 -358.226557) (xy 88.438915 -358.190911) (xy 88.460326 -358.17556) (xy 88.472459 -358.166357)
			(xy 88.491238 -358.142411) (xy 88.502137 -358.113999) (xy 88.504189 -358.083637) (xy 88.497214 -358.054017)
			(xy 88.481828 -358.027762) (xy 88.470994 -358.017064) (xy 88.451748 -357.998917) (xy 88.417965 -357.958213)
			(xy 88.390127 -357.913234) (xy 88.368767 -357.864841) (xy 88.354294 -357.813962) (xy 88.346986 -357.761573)
			(xy 88.346534 -357.735124) (xy 88.347047 -357.707644) (xy 88.354936 -357.653254) (xy 88.370553 -357.600559)
			(xy 88.393575 -357.550654) (xy 88.423525 -357.504572) (xy 88.459782 -357.463268) (xy 88.501594 -357.427598)
			(xy 88.524588 -357.412544) (xy 88.536216 -357.404727) (xy 88.554933 -357.383886) (xy 88.567286 -357.358745)
			(xy 88.572344 -357.331193) (xy 88.569727 -357.303304) (xy 88.559632 -357.277174) (xy 88.542819 -357.254769)
			(xy 88.531954 -357.24592) (xy 88.509103 -357.227703) (xy 88.468635 -357.185548) (xy 88.435063 -357.137719)
			(xy 88.409171 -357.085333) (xy 88.391564 -357.029614) (xy 88.382653 -356.971862) (xy 88.382094 -356.942644)
			(xy 88.382629 -356.913474) (xy 88.391536 -356.855819) (xy 88.409119 -356.800192) (xy 88.434968 -356.747892)
			(xy 88.468479 -356.700137) (xy 88.508871 -356.658042) (xy 88.5317 -356.639876) (xy 88.54349 -356.630122)
			(xy 88.561192 -356.605185) (xy 88.570719 -356.576125) (xy 88.571214 -356.545548) (xy 88.562635 -356.516195)
			(xy 88.54575 -356.490697) (xy 88.53424 -356.480618) (xy 88.512834 -356.462404) (xy 88.475099 -356.420752)
			(xy 88.443881 -356.374015) (xy 88.419855 -356.323205) (xy 88.403543 -356.269421) (xy 88.395295 -356.213826)
			(xy 88.394794 -356.185724) (xy 88.395234 -356.15908) (xy 88.40264 -356.106308) (xy 88.417325 -356.055083)
			(xy 88.439004 -356.006404) (xy 88.467252 -355.961219) (xy 88.50152 -355.920409) (xy 88.521032 -355.90226)
			(xy 88.530713 -355.892925) (xy 88.545327 -355.870366) (xy 88.553537 -355.844771) (xy 88.554773 -355.81792)
			(xy 88.548948 -355.791679) (xy 88.536467 -355.767873) (xy 88.527636 -355.757734) (xy 88.508665 -355.736462)
			(xy 88.476607 -355.689336) (xy 88.451906 -355.637971) (xy 88.435109 -355.583507) (xy 88.42659 -355.527151)
			(xy 88.426036 -355.498654) (xy 88.426435 -355.4714) (xy 88.434199 -355.417446) (xy 88.449562 -355.365147)
			(xy 88.472212 -355.315567) (xy 88.501687 -355.269715) (xy 88.537388 -355.228524) (xy 88.578587 -355.192833)
			(xy 88.624446 -355.163369) (xy 88.674032 -355.140731) (xy 88.726335 -355.12538) (xy 88.78029 -355.117629)
			(xy 88.807544 -355.117146) (xy 88.834954 -355.117634) (xy 88.889209 -355.125473) (xy 88.941784 -355.140999)
			(xy 88.991595 -355.163892) (xy 89.037615 -355.193679) (xy 89.078897 -355.229748) (xy 89.097104 -355.250242)
			(xy 89.106461 -355.260357) (xy 89.12933 -355.275699) (xy 89.155469 -355.284364) (xy 89.182974 -355.285721)
			(xy 89.20984 -355.279669) (xy 89.234107 -355.266652) (xy 89.254008 -355.247617) (xy 89.261442 -355.236018)
			(xy 89.276312 -355.212088) (xy 89.31195 -355.168457) (xy 89.353619 -355.130542) (xy 89.400412 -355.099171)
			(xy 89.451312 -355.075025) (xy 89.50521 -355.058629) (xy 89.560934 -355.050342) (xy 89.589102 -355.049836)
			(xy 89.61802 -355.050339) (xy 89.675192 -355.05907) (xy 89.730392 -355.07633) (xy 89.782354 -355.101724)
			(xy 89.829887 -355.134671) (xy 89.871903 -355.174415) (xy 89.890092 -355.196902) (xy 89.899989 -355.208707)
			(xy 89.925313 -355.226226) (xy 89.954706 -355.235402) (xy 89.985498 -355.235402) (xy 90.014891 -355.226226)
			(xy 90.040215 -355.208707) (xy 90.050112 -355.196902) (xy 90.066865 -355.176119) (xy 90.105219 -355.138989)
			(xy 90.148373 -355.107567) (xy 90.195487 -355.082468) (xy 90.245639 -355.064182) (xy 90.29785 -355.053065)
			(xy 90.351102 -355.049335) (xy 90.404354 -355.053065) (xy 90.456565 -355.064182) (xy 90.506717 -355.082468)
			(xy 90.553831 -355.107567) (xy 90.596985 -355.138989) (xy 90.635339 -355.176119) (xy 90.652092 -355.196902)
			(xy 90.661989 -355.208707) (xy 90.687313 -355.226226) (xy 90.716706 -355.235402) (xy 90.747498 -355.235402)
			(xy 90.776891 -355.226226) (xy 90.802215 -355.208707) (xy 90.812112 -355.196902) (xy 90.830297 -355.174413)
			(xy 90.872318 -355.134678) (xy 90.919854 -355.10174) (xy 90.971816 -355.076352) (xy 91.027015 -355.059097)
			(xy 91.084186 -355.05037) (xy 91.113102 -355.049836) (xy 91.142411 -355.05037) (xy 91.200337 -355.059342)
			(xy 91.256208 -355.077074) (xy 91.308707 -355.103148) (xy 91.356596 -355.13695) (xy 91.398748 -355.177684)
			(xy 91.416886 -355.200712) (xy 91.426627 -355.212609) (xy 91.451624 -355.230485) (xy 91.48081 -355.240107)
			(xy 91.511537 -355.240603) (xy 91.541018 -355.231927) (xy 91.566578 -355.214866) (xy 91.576652 -355.203252)
			(xy 91.594896 -355.181695) (xy 91.636601 -355.143621) (xy 91.683463 -355.112111) (xy 91.734459 -355.087854)
			(xy 91.788474 -355.07138) (xy 91.844327 -355.063049) (xy 91.872562 -355.062536) (xy 91.901479 -355.063068)
			(xy 91.95865 -355.071792) (xy 92.013849 -355.089047) (xy 92.065811 -355.114436) (xy 92.113345 -355.147377)
			(xy 92.155362 -355.187117) (xy 92.173552 -355.209602) (xy 92.183449 -355.221407) (xy 92.208773 -355.238926)
			(xy 92.238166 -355.248102) (xy 92.268958 -355.248102) (xy 92.298351 -355.238926) (xy 92.323675 -355.221407)
			(xy 92.333572 -355.209602) (xy 92.350325 -355.188819) (xy 92.388679 -355.151689) (xy 92.431833 -355.120267)
			(xy 92.478947 -355.095168) (xy 92.529099 -355.076882) (xy 92.58131 -355.065765) (xy 92.634562 -355.062035)
			(xy 92.687814 -355.065765) (xy 92.740025 -355.076882) (xy 92.790177 -355.095168) (xy 92.837291 -355.120267)
			(xy 92.880445 -355.151689) (xy 92.918799 -355.188819) (xy 92.935552 -355.209602) (xy 92.945449 -355.221407)
			(xy 92.970773 -355.238926) (xy 93.000166 -355.248102) (xy 93.030958 -355.248102) (xy 93.060351 -355.238926)
			(xy 93.085675 -355.221407) (xy 93.095572 -355.209602) (xy 93.112325 -355.188819) (xy 93.150679 -355.151689)
			(xy 93.193833 -355.120267) (xy 93.240947 -355.095168) (xy 93.291099 -355.076882) (xy 93.34331 -355.065765)
			(xy 93.396562 -355.062035) (xy 93.449814 -355.065765) (xy 93.502025 -355.076882) (xy 93.552177 -355.095168)
			(xy 93.599291 -355.120267) (xy 93.642445 -355.151689) (xy 93.680799 -355.188819) (xy 93.697552 -355.209602)
			(xy 93.707449 -355.221407) (xy 93.732773 -355.238926) (xy 93.762166 -355.248102) (xy 93.792958 -355.248102)
			(xy 93.822351 -355.238926) (xy 93.847675 -355.221407) (xy 93.857572 -355.209602) (xy 93.874325 -355.188819)
			(xy 93.912679 -355.151689) (xy 93.955833 -355.120267) (xy 94.002947 -355.095168) (xy 94.053099 -355.076882)
			(xy 94.10531 -355.065765) (xy 94.158562 -355.062035) (xy 94.211814 -355.065765) (xy 94.264025 -355.076882)
			(xy 94.314177 -355.095168) (xy 94.361291 -355.120267) (xy 94.404445 -355.151689) (xy 94.442799 -355.188819)
			(xy 94.459552 -355.209602) (xy 94.469449 -355.221407) (xy 94.494773 -355.238926) (xy 94.524166 -355.248102)
			(xy 94.554958 -355.248102) (xy 94.584351 -355.238926) (xy 94.609675 -355.221407) (xy 94.619572 -355.209602)
			(xy 94.637779 -355.187132) (xy 94.679796 -355.147396) (xy 94.727327 -355.114456) (xy 94.779285 -355.089065)
			(xy 94.83448 -355.071805) (xy 94.891647 -355.063073) (xy 94.920562 -355.062536) (xy 94.946814 -355.062978)
			(xy 94.998823 -355.070162) (xy 95.049354 -355.084412) (xy 95.097454 -355.10546) (xy 95.142211 -355.132907)
			(xy 95.182779 -355.166235) (xy 95.218392 -355.204813) (xy 95.233744 -355.226112) (xy 95.242108 -355.237325)
			(xy 95.263733 -355.255051) (xy 95.289357 -355.266248) (xy 95.317056 -355.270076) (xy 95.344755 -355.266248)
			(xy 95.370379 -355.255051) (xy 95.392004 -355.237325) (xy 95.400368 -355.226112) (xy 95.415735 -355.204826)
			(xy 95.451355 -355.166259) (xy 95.491925 -355.132939) (xy 95.536679 -355.105493) (xy 95.584773 -355.084441)
			(xy 95.635297 -355.070179) (xy 95.6873 -355.062976) (xy 95.71355 -355.062536) (xy 95.742466 -355.063076)
			(xy 95.799637 -355.071799) (xy 95.854836 -355.089052) (xy 95.906798 -355.114439) (xy 95.954333 -355.147379)
			(xy 95.99635 -355.187118) (xy 96.01454 -355.209602) (xy 96.024437 -355.221407) (xy 96.049761 -355.238926)
			(xy 96.079154 -355.248102) (xy 96.109946 -355.248102) (xy 96.139339 -355.238926) (xy 96.164663 -355.221407)
			(xy 96.17456 -355.209602) (xy 96.192774 -355.187138) (xy 96.234789 -355.147402) (xy 96.282319 -355.11446)
			(xy 96.334276 -355.089068) (xy 96.389469 -355.071808) (xy 96.446635 -355.063074) (xy 96.47555 -355.062536)
			(xy 96.502804 -355.063002) (xy 96.556757 -355.070753) (xy 96.609057 -355.086105) (xy 96.65864 -355.108745)
			(xy 96.704496 -355.138212) (xy 96.74569 -355.173906) (xy 96.781384 -355.2151) (xy 96.810852 -355.260955)
			(xy 96.833493 -355.310537) (xy 96.848845 -355.362837) (xy 96.856598 -355.41679) (xy 96.857058 -355.444044)
			(xy 96.856516 -355.47296) (xy 96.847794 -355.530131) (xy 96.830542 -355.58533) (xy 96.805155 -355.637292)
			(xy 96.772215 -355.684827) (xy 96.732476 -355.726844) (xy 96.709992 -355.745034) (xy 96.698145 -355.754885)
			(xy 96.680632 -355.780222) (xy 96.671463 -355.809627) (xy 96.671471 -355.840427) (xy 96.680655 -355.869827)
			(xy 96.698182 -355.895155) (xy 96.709992 -355.905054) (xy 96.730821 -355.921754) (xy 96.767956 -355.960111)
			(xy 96.799382 -356.003272) (xy 96.824483 -356.050391) (xy 96.84277 -356.10055) (xy 96.853885 -356.152769)
			(xy 96.857612 -356.206027) (xy 96.853878 -356.259285) (xy 96.842755 -356.311502) (xy 96.824461 -356.361658)
			(xy 96.799353 -356.408774) (xy 96.767921 -356.45193) (xy 96.73078 -356.490282) (xy 96.709992 -356.507034)
			(xy 96.698145 -356.516885) (xy 96.680632 -356.542222) (xy 96.671463 -356.571627) (xy 96.671471 -356.602427)
			(xy 96.680655 -356.631827) (xy 96.684643 -356.63759) (xy 98.915218 -356.63759) (xy 98.919289 -356.581968)
			(xy 98.931415 -356.527531) (xy 98.951338 -356.47544) (xy 98.978634 -356.426805) (xy 99.01272 -356.382662)
			(xy 99.052869 -356.343953) (xy 99.098227 -356.311502) (xy 99.147827 -356.286001) (xy 99.200611 -356.267994)
			(xy 99.255454 -356.257864) (xy 99.311188 -356.255827) (xy 99.366625 -356.261927) (xy 99.420582 -356.276033)
			(xy 99.471911 -356.297845) (xy 99.519517 -356.326899) (xy 99.562385 -356.362574) (xy 99.599602 -356.404111)
			(xy 99.630375 -356.450624) (xy 99.654047 -356.501121) (xy 99.670115 -356.554528) (xy 99.678235 -356.609704)
			(xy 99.678744 -356.63759) (xy 99.678235 -356.665476) (xy 99.670115 -356.720652) (xy 99.654047 -356.774059)
			(xy 99.630375 -356.824556) (xy 99.599602 -356.871069) (xy 99.562385 -356.912606) (xy 99.519517 -356.948281)
			(xy 99.471911 -356.977335) (xy 99.420582 -356.999147) (xy 99.366625 -357.013253) (xy 99.311188 -357.019353)
			(xy 99.255454 -357.017316) (xy 99.200611 -357.007186) (xy 99.147827 -356.989179) (xy 99.098227 -356.963678)
			(xy 99.052869 -356.931227) (xy 99.01272 -356.892518) (xy 98.978634 -356.848375) (xy 98.951338 -356.79974)
			(xy 98.931415 -356.747649) (xy 98.919289 -356.693212) (xy 98.915218 -356.63759) (xy 96.684643 -356.63759)
			(xy 96.698182 -356.657155) (xy 96.709992 -356.667054) (xy 96.730821 -356.683754) (xy 96.767956 -356.722111)
			(xy 96.799382 -356.765272) (xy 96.824483 -356.812391) (xy 96.84277 -356.86255) (xy 96.853885 -356.914769)
			(xy 96.857612 -356.968027) (xy 96.853878 -357.021285) (xy 96.842755 -357.073502) (xy 96.824461 -357.123658)
			(xy 96.799353 -357.170774) (xy 96.767921 -357.21393) (xy 96.73078 -357.252282) (xy 96.709992 -357.269034)
			(xy 96.698145 -357.278885) (xy 96.680632 -357.304222) (xy 96.671463 -357.333627) (xy 96.671471 -357.364427)
			(xy 96.680655 -357.393827) (xy 96.698182 -357.419155) (xy 96.709992 -357.429054) (xy 96.730821 -357.445754)
			(xy 96.767956 -357.484111) (xy 96.799382 -357.527272) (xy 96.801725 -357.53167) (xy 98.915218 -357.53167)
			(xy 98.919289 -357.476048) (xy 98.931415 -357.421611) (xy 98.951338 -357.36952) (xy 98.978634 -357.320885)
			(xy 99.01272 -357.276742) (xy 99.052869 -357.238033) (xy 99.098227 -357.205582) (xy 99.147827 -357.180081)
			(xy 99.200611 -357.162074) (xy 99.255454 -357.151944) (xy 99.311188 -357.149907) (xy 99.366625 -357.156007)
			(xy 99.420582 -357.170113) (xy 99.471911 -357.191925) (xy 99.519517 -357.220979) (xy 99.562385 -357.256654)
			(xy 99.599602 -357.298191) (xy 99.630375 -357.344704) (xy 99.654047 -357.395201) (xy 99.670115 -357.448608)
			(xy 99.678235 -357.503784) (xy 99.678744 -357.53167) (xy 99.678235 -357.559556) (xy 99.670115 -357.614732)
			(xy 99.654047 -357.668139) (xy 99.630375 -357.718636) (xy 99.599602 -357.765149) (xy 99.562385 -357.806686)
			(xy 99.519517 -357.842361) (xy 99.471911 -357.871415) (xy 99.420582 -357.893227) (xy 99.366625 -357.907333)
			(xy 99.311188 -357.913433) (xy 99.255454 -357.911396) (xy 99.200611 -357.901266) (xy 99.147827 -357.883259)
			(xy 99.098227 -357.857758) (xy 99.052869 -357.825307) (xy 99.01272 -357.786598) (xy 98.978634 -357.742455)
			(xy 98.951338 -357.69382) (xy 98.931415 -357.641729) (xy 98.919289 -357.587292) (xy 98.915218 -357.53167)
			(xy 96.801725 -357.53167) (xy 96.824483 -357.574391) (xy 96.84277 -357.62455) (xy 96.853885 -357.676769)
			(xy 96.857612 -357.730027) (xy 96.853878 -357.783285) (xy 96.842755 -357.835502) (xy 96.824461 -357.885658)
			(xy 96.799353 -357.932774) (xy 96.767921 -357.97593) (xy 96.73078 -358.014282) (xy 96.709992 -358.031034)
			(xy 96.698145 -358.040885) (xy 96.680632 -358.066222) (xy 96.671463 -358.095627) (xy 96.671471 -358.126427)
			(xy 96.680655 -358.155827) (xy 96.698182 -358.181155) (xy 96.709992 -358.191054) (xy 96.730821 -358.207754)
			(xy 96.767956 -358.246111) (xy 96.799382 -358.289272) (xy 96.824483 -358.336391) (xy 96.84277 -358.38655)
			(xy 96.853885 -358.438769) (xy 96.857612 -358.492027) (xy 96.853878 -358.545285) (xy 96.842755 -358.597502)
			(xy 96.824461 -358.647658) (xy 96.799353 -358.694774) (xy 96.767921 -358.73793) (xy 96.73078 -358.776282)
			(xy 96.709992 -358.793034) (xy 96.698145 -358.802885) (xy 96.680632 -358.828222) (xy 96.671463 -358.857627)
			(xy 96.671471 -358.888427) (xy 96.680655 -358.917827) (xy 96.698182 -358.943155) (xy 96.709992 -358.953054)
			(xy 96.732452 -358.971273) (xy 96.772189 -359.013287) (xy 96.805131 -359.060816) (xy 96.830523 -359.112772)
			(xy 96.847785 -359.167964) (xy 96.85652 -359.22513) (xy 96.857058 -359.254044) (xy 96.856686 -359.2813)
			(xy 96.848922 -359.335257) (xy 96.833557 -359.38756) (xy 96.810906 -359.437143) (xy 96.781429 -359.482999)
			(xy 96.745726 -359.524192) (xy 96.704523 -359.559885) (xy 96.658661 -359.589351) (xy 96.609072 -359.61199)
			(xy 96.556765 -359.627342) (xy 96.502806 -359.635093) (xy 96.47555 -359.635552) (xy 96.446634 -359.635016)
			(xy 96.389462 -359.626293) (xy 96.334263 -359.60904) (xy 96.282301 -359.583652) (xy 96.234767 -359.55071)
			(xy 96.19275 -359.510971) (xy 96.17456 -359.488486) (xy 96.164663 -359.476681) (xy 96.139339 -359.459162)
			(xy 96.109946 -359.449986) (xy 96.079154 -359.449986) (xy 96.049761 -359.459162) (xy 96.024437 -359.476681)
			(xy 96.01454 -359.488486) (xy 95.999762 -359.506885) (xy 95.966391 -359.540256) (xy 95.947992 -359.555034)
			(xy 95.936145 -359.564885) (xy 95.918632 -359.590222) (xy 95.909463 -359.619627) (xy 95.909471 -359.650427)
			(xy 95.918655 -359.679827) (xy 95.936182 -359.705155) (xy 95.947992 -359.715054) (xy 95.970452 -359.733273)
			(xy 96.010189 -359.775287) (xy 96.043131 -359.822816) (xy 96.068523 -359.874772) (xy 96.085785 -359.929964)
			(xy 96.09452 -359.98713) (xy 96.095058 -360.016044) (xy 96.094686 -360.0433) (xy 96.086922 -360.097257)
			(xy 96.071557 -360.14956) (xy 96.048906 -360.199143) (xy 96.019429 -360.244999) (xy 95.983726 -360.286192)
			(xy 95.942523 -360.321885) (xy 95.896661 -360.351351) (xy 95.847072 -360.37399) (xy 95.794765 -360.389342)
			(xy 95.740806 -360.397093) (xy 95.71355 -360.397552) (xy 95.687299 -360.397106) (xy 95.635289 -360.389924)
			(xy 95.584757 -360.375674) (xy 95.536658 -360.354627) (xy 95.491901 -360.32718) (xy 95.451332 -360.293853)
			(xy 95.415719 -360.255275) (xy 95.400368 -360.233976) (xy 95.392004 -360.222763) (xy 95.370379 -360.205037)
			(xy 95.344755 -360.19384) (xy 95.317056 -360.190012) (xy 95.289357 -360.19384) (xy 95.263733 -360.205037)
			(xy 95.242108 -360.222763) (xy 95.233744 -360.233976) (xy 95.218366 -360.255254) (xy 95.182748 -360.293821)
			(xy 95.14218 -360.327143) (xy 95.097428 -360.35459) (xy 95.049336 -360.375643) (xy 94.998813 -360.389907)
			(xy 94.946811 -360.397111) (xy 94.920562 -360.397552) (xy 94.892056 -360.397013) (xy 94.835678 -360.388524)
			(xy 94.781192 -360.37174) (xy 94.729809 -360.347035) (xy 94.682675 -360.31496) (xy 94.640838 -360.276228)
			(xy 94.62262 -360.254296) (xy 94.61269 -360.242603) (xy 94.587311 -360.225391) (xy 94.557967 -360.216484)
			(xy 94.527302 -360.216686) (xy 94.498078 -360.225979) (xy 94.472927 -360.243524) (xy 94.463108 -360.255312)
			(xy 94.444916 -360.277794) (xy 94.402896 -360.317529) (xy 94.355361 -360.350468) (xy 94.3034 -360.375856)
			(xy 94.248203 -360.393113) (xy 94.191034 -360.401843) (xy 94.162118 -360.402378) (xy 94.132824 -360.401817)
			(xy 94.074926 -360.392855) (xy 94.019076 -360.375156) (xy 93.966585 -360.349134) (xy 93.918685 -360.315399)
			(xy 93.876499 -360.274744) (xy 93.858334 -360.251756) (xy 93.849905 -360.241474) (xy 93.828885 -360.225217)
			(xy 93.804384 -360.214928) (xy 93.778059 -360.211303) (xy 93.751689 -360.214588) (xy 93.727058 -360.22456)
			(xy 93.70583 -360.240545) (xy 93.697298 -360.25074) (xy 93.679113 -360.27319) (xy 93.637118 -360.312862)
			(xy 93.589619 -360.345747) (xy 93.537703 -360.371091) (xy 93.482559 -360.388314) (xy 93.425448 -360.397022)
			(xy 93.396562 -360.397552) (xy 93.367646 -360.397008) (xy 93.310475 -360.388287) (xy 93.255276 -360.371035)
			(xy 93.203314 -360.345648) (xy 93.155779 -360.312709) (xy 93.113762 -360.27297) (xy 93.095572 -360.250486)
			(xy 93.085675 -360.238681) (xy 93.060351 -360.221162) (xy 93.030958 -360.211986) (xy 93.000166 -360.211986)
			(xy 92.970773 -360.221162) (xy 92.945449 -360.238681) (xy 92.935552 -360.250486) (xy 92.918799 -360.271269)
			(xy 92.880445 -360.308399) (xy 92.837291 -360.339821) (xy 92.790177 -360.36492) (xy 92.740025 -360.383206)
			(xy 92.687814 -360.394323) (xy 92.634562 -360.398053) (xy 92.58131 -360.394323) (xy 92.529099 -360.383206)
			(xy 92.478947 -360.36492) (xy 92.431833 -360.339821) (xy 92.388679 -360.308399) (xy 92.350325 -360.271269)
			(xy 92.333572 -360.250486) (xy 92.323675 -360.238681) (xy 92.298351 -360.221162) (xy 92.268958 -360.211986)
			(xy 92.238166 -360.211986) (xy 92.208773 -360.221162) (xy 92.183449 -360.238681) (xy 92.173552 -360.250486)
			(xy 92.156799 -360.271269) (xy 92.118445 -360.308399) (xy 92.075291 -360.339821) (xy 92.028177 -360.36492)
			(xy 91.978025 -360.383206) (xy 91.925814 -360.394323) (xy 91.872562 -360.398053) (xy 91.81931 -360.394323)
			(xy 91.767099 -360.383206) (xy 91.716947 -360.36492) (xy 91.669833 -360.339821) (xy 91.626679 -360.308399)
			(xy 91.588325 -360.271269) (xy 91.571572 -360.250486) (xy 91.561675 -360.238681) (xy 91.536351 -360.221162)
			(xy 91.506958 -360.211986) (xy 91.476166 -360.211986) (xy 91.446773 -360.221162) (xy 91.421449 -360.238681)
			(xy 91.411552 -360.250486) (xy 91.393328 -360.272942) (xy 91.351316 -360.312679) (xy 91.303788 -360.345622)
			(xy 91.251833 -360.371015) (xy 91.196641 -360.388277) (xy 91.139476 -360.397013) (xy 91.110562 -360.397552)
			(xy 91.084492 -360.397123) (xy 91.03284 -360.39001) (xy 90.982635 -360.375936) (xy 90.934812 -360.355161)
			(xy 90.890261 -360.328073) (xy 90.84981 -360.295175) (xy 90.81421 -360.25708) (xy 90.784126 -360.214495)
			(xy 90.771726 -360.191558) (xy 90.764913 -360.179441) (xy 90.745946 -360.159136) (xy 90.722205 -360.1447)
			(xy 90.695449 -360.137204) (xy 90.667663 -360.137204) (xy 90.640907 -360.1447) (xy 90.617166 -360.159136)
			(xy 90.598199 -360.179441) (xy 90.591386 -360.191558) (xy 90.578996 -360.214503) (xy 90.548924 -360.257102)
			(xy 90.51333 -360.295209) (xy 90.472879 -360.328114) (xy 90.428324 -360.355203) (xy 90.380494 -360.375973)
			(xy 90.330282 -360.390036) (xy 90.278622 -360.397131) (xy 90.25255 -360.397552) (xy 90.22617 -360.397098)
			(xy 90.173911 -360.389833) (xy 90.123153 -360.375435) (xy 90.074863 -360.354179) (xy 90.029964 -360.326471)
			(xy 89.989312 -360.292839) (xy 89.953683 -360.253925) (xy 89.938352 -360.232452) (xy 89.930165 -360.221296)
			(xy 89.908954 -360.203541) (xy 89.883751 -360.192138) (xy 89.856412 -360.187927) (xy 89.828946 -360.191218)
			(xy 89.803376 -360.201768) (xy 89.78158 -360.218802) (xy 89.772998 -360.229658) (xy 89.754877 -360.253141)
			(xy 89.712594 -360.294738) (xy 89.664381 -360.329286) (xy 89.6114 -360.355953) (xy 89.55493 -360.374095)
			(xy 89.496331 -360.383274) (xy 89.466674 -360.383836) (xy 89.440711 -360.38336) (xy 89.389265 -360.376319)
			(xy 89.339247 -360.36237) (xy 89.291582 -360.341771) (xy 89.247148 -360.314902) (xy 89.206765 -360.282259)
			(xy 89.17118 -360.244444) (xy 89.141048 -360.202155) (xy 89.1286 -360.179366) (xy 89.121978 -360.16751)
			(xy 89.103535 -360.147587) (xy 89.080488 -360.133238) (xy 89.054472 -360.12548) (xy 89.02733 -360.124862)
			(xy 89.000988 -360.131428) (xy 88.977312 -360.144712) (xy 88.95798 -360.163774) (xy 88.9508 -360.175302)
			(xy 88.936041 -360.199594) (xy 88.900425 -360.243892) (xy 88.858631 -360.282415) (xy 88.811584 -360.314311)
			(xy 88.760326 -360.338875) (xy 88.705991 -360.355562) (xy 88.649782 -360.364004) (xy 88.621362 -360.364532)
			(xy 88.592623 -360.364023) (xy 88.535795 -360.355395) (xy 88.480904 -360.338341) (xy 88.429193 -360.313247)
			(xy 88.381831 -360.28068) (xy 88.360504 -360.261408) (xy 88.348663 -360.251155) (xy 88.320383 -360.237729)
			(xy 88.289366 -360.233492) (xy 88.258521 -360.23884) (xy 88.23074 -360.253271) (xy 88.21928 -360.263948)
			(xy 88.197682 -360.284801) (xy 88.149147 -360.320133) (xy 88.095675 -360.347424) (xy 88.038588 -360.366001)
			(xy 87.979295 -360.375403) (xy 87.949278 -360.375962) (xy 87.949024 -360.375962) (xy 87.92177 -360.375522)
			(xy 87.867815 -360.367767) (xy 87.815514 -360.352412) (xy 87.765931 -360.329769) (xy 87.720076 -360.300299)
			(xy 87.678882 -360.264603) (xy 87.643188 -360.223407) (xy 87.613721 -360.177549) (xy 87.59108 -360.127965)
			(xy 87.575728 -360.075663) (xy 87.567976 -360.021708) (xy 87.567516 -359.994454) (xy 82.775806 -359.994454)
			(xy 85.68182 -362.900468) (xy 85.68182 -367.233708) (xy 88.82634 -370.378228) (xy 95.673672 -370.378228)
		)
		(stroke
			(width 0)
			(type solid)
		)
		(fill yes)
		(layer "In4.Cu")
		(net "GND")
	)
	(gr_poly
		(pts
			(xy 386.742178 -374.23217) (xy 390.555734 -357.891588) (xy 390.654794 -353.210622) (xy 390.779 -347.34373)
			(xy 390.779 -347.152468) (xy 390.742678 -347.141546) (xy 390.717073 -347.133413) (xy 390.668471 -347.110525)
			(xy 390.623858 -347.080598) (xy 390.584245 -347.044309) (xy 390.550532 -347.002482) (xy 390.523483 -346.956067)
			(xy 390.503713 -346.906115) (xy 390.491669 -346.853761) (xy 390.487624 -346.800191) (xy 390.491671 -346.746622)
			(xy 390.503718 -346.694269) (xy 390.523491 -346.644318) (xy 390.550542 -346.597904) (xy 390.584257 -346.556079)
			(xy 390.623871 -346.519792) (xy 390.668486 -346.489866) (xy 390.717089 -346.466981) (xy 390.742678 -346.458794)
			(xy 390.779 -346.447872) (xy 390.779 -346.009468) (xy 390.742678 -345.998546) (xy 390.717073 -345.990413)
			(xy 390.668471 -345.967525) (xy 390.623858 -345.937598) (xy 390.584245 -345.901309) (xy 390.550532 -345.859482)
			(xy 390.523483 -345.813067) (xy 390.503713 -345.763115) (xy 390.491669 -345.710761) (xy 390.487624 -345.657191)
			(xy 390.491671 -345.603622) (xy 390.503718 -345.551269) (xy 390.523491 -345.501318) (xy 390.550542 -345.454904)
			(xy 390.584257 -345.413079) (xy 390.623871 -345.376792) (xy 390.668486 -345.346866) (xy 390.717089 -345.323981)
			(xy 390.742678 -345.315794) (xy 390.779 -345.304872) (xy 390.779 -344.866468) (xy 390.742678 -344.855546)
			(xy 390.717073 -344.847413) (xy 390.668471 -344.824525) (xy 390.623858 -344.794598) (xy 390.584245 -344.758309)
			(xy 390.550532 -344.716482) (xy 390.523483 -344.670067) (xy 390.503713 -344.620115) (xy 390.491669 -344.567761)
			(xy 390.487624 -344.514191) (xy 390.491671 -344.460622) (xy 390.503718 -344.408269) (xy 390.523491 -344.358318)
			(xy 390.550542 -344.311904) (xy 390.584257 -344.270079) (xy 390.623871 -344.233792) (xy 390.668486 -344.203866)
			(xy 390.717089 -344.180981) (xy 390.742678 -344.172794) (xy 390.779 -344.161872) (xy 390.779 -342.34247)
			(xy 390.734804 -342.336628) (xy 390.708113 -342.332594) (xy 390.656281 -342.317521) (xy 390.607318 -342.294797)
			(xy 390.562346 -342.264943) (xy 390.522394 -342.228645) (xy 390.488378 -342.186732) (xy 390.461078 -342.140165)
			(xy 390.441119 -342.090012) (xy 390.428958 -342.03742) (xy 390.424873 -341.983596) (xy 390.428959 -341.929772)
			(xy 390.441121 -341.87718) (xy 390.461082 -341.827027) (xy 390.488383 -341.780461) (xy 390.5224 -341.738549)
			(xy 390.562352 -341.702251) (xy 390.607325 -341.672399) (xy 390.656289 -341.649676) (xy 390.708121 -341.634604)
			(xy 390.734804 -341.630508) (xy 390.779 -341.624666) (xy 390.779 -334.4545) (xy 389.138668 -332.814168)
			(xy 382.524254 -332.814168) (xy 379.615192 -329.905106) (xy 374.559322 -329.905106) (xy 371.442234 -326.788018)
			(xy 342.526366 -326.788018) (xy 335.877662 -333.436722) (xy 321.900804 -333.436722) (xy 318.454532 -336.882994)
			(xy 318.454532 -338.645246) (xy 318.48425 -338.652358) (xy 318.510554 -338.658405) (xy 318.561086 -338.677366)
			(xy 318.608177 -338.703735) (xy 318.650749 -338.73691) (xy 318.687827 -338.776129) (xy 318.718561 -338.820495)
			(xy 318.742248 -338.868991) (xy 318.758345 -338.920506) (xy 318.766484 -338.97386) (xy 318.766952 -339.000846)
			(xy 318.766473 -339.027297) (xy 318.758656 -339.079618) (xy 318.743185 -339.130207) (xy 318.720401 -339.177951)
			(xy 318.690806 -339.2218) (xy 318.65505 -339.260789) (xy 318.61392 -339.29406) (xy 318.568321 -339.32088)
			(xy 318.519257 -339.340661) (xy 318.493648 -339.347302) (xy 318.454532 -339.356446) (xy 318.454532 -341.535512)
			(xy 319.134744 -342.78189) (xy 319.143178 -342.794873) (xy 319.166322 -342.815415) (xy 319.194554 -342.828087)
			(xy 319.225284 -342.831726) (xy 319.255695 -342.826001) (xy 319.269618 -342.819228) (xy 319.297356 -342.805177)
			(xy 319.356256 -342.785267) (xy 319.417601 -342.775145) (xy 319.448688 -342.774524) (xy 319.475941 -342.774987)
			(xy 319.529891 -342.782742) (xy 319.582189 -342.798098) (xy 319.631768 -342.82074) (xy 319.67762 -342.850208)
			(xy 319.718812 -342.885902) (xy 319.754504 -342.927096) (xy 319.78397 -342.972949) (xy 319.806609 -343.02253)
			(xy 319.821962 -343.074828) (xy 319.829715 -343.128779) (xy 319.830196 -343.156032) (xy 319.829647 -343.185215)
			(xy 319.820769 -343.242901) (xy 319.803211 -343.298562) (xy 319.777381 -343.3509) (xy 319.743883 -343.398695)
			(xy 319.703497 -343.440831) (xy 319.657166 -343.476326) (xy 319.631822 -343.490804) (xy 319.618899 -343.499372)
			(xy 319.598543 -343.522741) (xy 319.586115 -343.551131) (xy 319.582756 -343.58194) (xy 319.588774 -343.612342)
			(xy 319.595754 -343.626186) (xy 319.971928 -344.315288) (xy 320.319419 -344.952066) (xy 322.703442 -344.952066)
			(xy 322.707513 -344.896444) (xy 322.719639 -344.842007) (xy 322.739562 -344.789916) (xy 322.766858 -344.741281)
			(xy 322.800944 -344.697138) (xy 322.841093 -344.658429) (xy 322.886451 -344.625978) (xy 322.936051 -344.600477)
			(xy 322.988835 -344.58247) (xy 323.043678 -344.57234) (xy 323.099412 -344.570303) (xy 323.154849 -344.576403)
			(xy 323.208806 -344.590509) (xy 323.260135 -344.612321) (xy 323.307741 -344.641375) (xy 323.350609 -344.67705)
			(xy 323.387826 -344.718587) (xy 323.418599 -344.7651) (xy 323.442271 -344.815597) (xy 323.458339 -344.869004)
			(xy 323.466459 -344.92418) (xy 323.466968 -344.952066) (xy 323.46688 -344.956892) (xy 323.685406 -344.956892)
			(xy 323.689477 -344.90127) (xy 323.701603 -344.846833) (xy 323.721526 -344.794742) (xy 323.748822 -344.746107)
			(xy 323.782908 -344.701964) (xy 323.823057 -344.663255) (xy 323.868415 -344.630804) (xy 323.918015 -344.605303)
			(xy 323.970799 -344.587296) (xy 324.025642 -344.577166) (xy 324.081376 -344.575129) (xy 324.136813 -344.581229)
			(xy 324.19077 -344.595335) (xy 324.242099 -344.617147) (xy 324.289705 -344.646201) (xy 324.332573 -344.681876)
			(xy 324.36979 -344.723413) (xy 324.400563 -344.769926) (xy 324.424235 -344.820423) (xy 324.440303 -344.87383)
			(xy 324.448423 -344.929006) (xy 324.448932 -344.956892) (xy 324.448423 -344.984778) (xy 324.440303 -345.039954)
			(xy 324.424235 -345.093361) (xy 324.400563 -345.143858) (xy 324.36979 -345.190371) (xy 324.332573 -345.231908)
			(xy 324.289705 -345.267583) (xy 324.242099 -345.296637) (xy 324.19077 -345.318449) (xy 324.136813 -345.332555)
			(xy 324.081376 -345.338655) (xy 324.025642 -345.336618) (xy 323.970799 -345.326488) (xy 323.918015 -345.308481)
			(xy 323.868415 -345.28298) (xy 323.823057 -345.250529) (xy 323.782908 -345.21182) (xy 323.748822 -345.167677)
			(xy 323.721526 -345.119042) (xy 323.701603 -345.066951) (xy 323.689477 -345.012514) (xy 323.685406 -344.956892)
			(xy 323.46688 -344.956892) (xy 323.466459 -344.979952) (xy 323.458339 -345.035128) (xy 323.442271 -345.088535)
			(xy 323.418599 -345.139032) (xy 323.387826 -345.185545) (xy 323.350609 -345.227082) (xy 323.307741 -345.262757)
			(xy 323.260135 -345.291811) (xy 323.208806 -345.313623) (xy 323.154849 -345.327729) (xy 323.099412 -345.333829)
			(xy 323.043678 -345.331792) (xy 322.988835 -345.321662) (xy 322.936051 -345.303655) (xy 322.886451 -345.278154)
			(xy 322.841093 -345.245703) (xy 322.800944 -345.206994) (xy 322.766858 -345.162851) (xy 322.739562 -345.114216)
			(xy 322.719639 -345.062125) (xy 322.707513 -345.007688) (xy 322.703442 -344.952066) (xy 320.319419 -344.952066)
			(xy 320.986401 -346.174314) (xy 323.948296 -346.174314) (xy 323.952367 -346.118692) (xy 323.964493 -346.064255)
			(xy 323.984416 -346.012164) (xy 324.011712 -345.963529) (xy 324.045798 -345.919386) (xy 324.085947 -345.880677)
			(xy 324.131305 -345.848226) (xy 324.180905 -345.822725) (xy 324.233689 -345.804718) (xy 324.288532 -345.794588)
			(xy 324.344266 -345.792551) (xy 324.399703 -345.798651) (xy 324.45366 -345.812757) (xy 324.504989 -345.834569)
			(xy 324.552595 -345.863623) (xy 324.595463 -345.899298) (xy 324.601093 -345.905582) (xy 325.481694 -345.905582)
			(xy 325.485765 -345.84996) (xy 325.497891 -345.795523) (xy 325.517814 -345.743432) (xy 325.54511 -345.694797)
			(xy 325.579196 -345.650654) (xy 325.619345 -345.611945) (xy 325.664703 -345.579494) (xy 325.714303 -345.553993)
			(xy 325.767087 -345.535986) (xy 325.82193 -345.525856) (xy 325.877664 -345.523819) (xy 325.933101 -345.529919)
			(xy 325.987058 -345.544025) (xy 326.038387 -345.565837) (xy 326.085993 -345.594891) (xy 326.128861 -345.630566)
			(xy 326.166078 -345.672103) (xy 326.196851 -345.718616) (xy 326.220523 -345.769113) (xy 326.236591 -345.82252)
			(xy 326.244711 -345.877696) (xy 326.24522 -345.905582) (xy 326.244711 -345.933468) (xy 326.236591 -345.988644)
			(xy 326.220523 -346.042051) (xy 326.196851 -346.092548) (xy 326.166078 -346.139061) (xy 326.128861 -346.180598)
			(xy 326.085993 -346.216273) (xy 326.038387 -346.245327) (xy 325.987058 -346.267139) (xy 325.933101 -346.281245)
			(xy 325.877664 -346.287345) (xy 325.82193 -346.285308) (xy 325.767087 -346.275178) (xy 325.714303 -346.257171)
			(xy 325.664703 -346.23167) (xy 325.619345 -346.199219) (xy 325.579196 -346.16051) (xy 325.54511 -346.116367)
			(xy 325.517814 -346.067732) (xy 325.497891 -346.015641) (xy 325.485765 -345.961204) (xy 325.481694 -345.905582)
			(xy 324.601093 -345.905582) (xy 324.63268 -345.940835) (xy 324.663453 -345.987348) (xy 324.687125 -346.037845)
			(xy 324.703193 -346.091252) (xy 324.711313 -346.146428) (xy 324.711822 -346.174314) (xy 324.711313 -346.2022)
			(xy 324.703193 -346.257376) (xy 324.687125 -346.310783) (xy 324.663453 -346.36128) (xy 324.63268 -346.407793)
			(xy 324.595463 -346.44933) (xy 324.552595 -346.485005) (xy 324.504989 -346.514059) (xy 324.45366 -346.535871)
			(xy 324.399703 -346.549977) (xy 324.344266 -346.556077) (xy 324.288532 -346.55404) (xy 324.233689 -346.54391)
			(xy 324.180905 -346.525903) (xy 324.131305 -346.500402) (xy 324.085947 -346.467951) (xy 324.045798 -346.429242)
			(xy 324.011712 -346.385099) (xy 323.984416 -346.336464) (xy 323.964493 -346.284373) (xy 323.952367 -346.229936)
			(xy 323.948296 -346.174314) (xy 320.986401 -346.174314) (xy 321.197224 -346.560648) (xy 321.52844 -347.120464)
			(xy 321.764914 -347.52026) (xy 321.772224 -347.531732) (xy 321.791782 -347.550623) (xy 321.815633 -347.563682)
			(xy 321.842085 -347.569981) (xy 321.869262 -347.569074) (xy 321.895236 -347.561026) (xy 321.918163 -347.546407)
			(xy 321.936419 -347.526254) (xy 321.948707 -347.501997) (xy 321.951858 -347.488764) (xy 321.95642 -347.462064)
			(xy 321.972097 -347.410216) (xy 321.994952 -347.361107) (xy 322.024525 -347.315726) (xy 322.060221 -347.274986)
			(xy 322.101321 -347.239705) (xy 322.146999 -347.210593) (xy 322.196336 -347.188236) (xy 322.24834 -347.173085)
			(xy 322.301965 -347.165442) (xy 322.329048 -347.164914) (xy 322.357643 -347.16542) (xy 322.414194 -347.17395)
			(xy 322.468838 -347.190825) (xy 322.520351 -347.215668) (xy 322.567578 -347.247923) (xy 322.609461 -347.286865)
			(xy 322.645061 -347.331624) (xy 322.673582 -347.381195) (xy 322.694383 -347.434469) (xy 322.706999 -347.49025)
			(xy 322.707795 -347.499178) (xy 326.2884 -347.499178) (xy 326.288939 -347.469489) (xy 326.298141 -347.410829)
			(xy 326.31632 -347.354303) (xy 326.343036 -347.301276) (xy 326.377645 -347.253028) (xy 326.41931 -347.210723)
			(xy 326.442832 -347.1926) (xy 326.453471 -347.184212) (xy 326.470174 -347.162889) (xy 326.480687 -347.137927)
			(xy 326.484272 -347.11108) (xy 326.480677 -347.084233) (xy 326.470153 -347.059275) (xy 326.453442 -347.03796)
			(xy 326.442832 -347.029532) (xy 326.419344 -347.011369) (xy 326.37768 -346.969072) (xy 326.343072 -346.920831)
			(xy 326.316356 -346.867811) (xy 326.298175 -346.811292) (xy 326.288969 -346.752639) (xy 326.2884 -346.722954)
			(xy 326.288886 -346.695703) (xy 326.296642 -346.641755) (xy 326.311997 -346.58946) (xy 326.334639 -346.539883)
			(xy 326.364105 -346.494033) (xy 326.399796 -346.452842) (xy 326.440987 -346.417151) (xy 326.486837 -346.387685)
			(xy 326.536414 -346.365043) (xy 326.588709 -346.349688) (xy 326.642657 -346.341932) (xy 326.697159 -346.341932)
			(xy 326.751107 -346.349688) (xy 326.803402 -346.365043) (xy 326.852979 -346.387685) (xy 326.898829 -346.417151)
			(xy 326.94002 -346.452842) (xy 326.975711 -346.494033) (xy 327.005177 -346.539883) (xy 327.027819 -346.58946)
			(xy 327.043174 -346.641755) (xy 327.05093 -346.695703) (xy 327.051416 -346.722954) (xy 327.050821 -346.75264)
			(xy 327.04163 -346.811297) (xy 327.023462 -346.867822) (xy 326.996756 -346.92085) (xy 326.962158 -346.9691)
			(xy 326.920501 -347.011407) (xy 326.896984 -347.029532) (xy 326.886411 -347.037998) (xy 326.869706 -347.059302)
			(xy 326.859187 -347.084247) (xy 326.855592 -347.11108) (xy 326.859176 -347.137914) (xy 326.869685 -347.162863)
			(xy 326.886382 -347.184173) (xy 326.896984 -347.1926) (xy 326.920491 -347.21074) (xy 326.962153 -347.253043)
			(xy 326.996758 -347.301289) (xy 327.023471 -347.354313) (xy 327.041648 -347.410835) (xy 327.050849 -347.469491)
			(xy 327.051416 -347.499178) (xy 327.05093 -347.526429) (xy 327.043174 -347.580377) (xy 327.027819 -347.632672)
			(xy 327.005177 -347.682249) (xy 326.975711 -347.728099) (xy 326.94002 -347.76929) (xy 326.898829 -347.804981)
			(xy 326.852979 -347.834447) (xy 326.803402 -347.857089) (xy 326.751107 -347.872444) (xy 326.697159 -347.8802)
			(xy 326.642657 -347.8802) (xy 326.588709 -347.872444) (xy 326.536414 -347.857089) (xy 326.486837 -347.834447)
			(xy 326.440987 -347.804981) (xy 326.399796 -347.76929) (xy 326.364105 -347.728099) (xy 326.334639 -347.682249)
			(xy 326.311997 -347.632672) (xy 326.296642 -347.580377) (xy 326.288886 -347.526429) (xy 326.2884 -347.499178)
			(xy 322.707795 -347.499178) (xy 322.70954 -347.518736) (xy 322.713096 -347.56598) (xy 324.276974 -347.56598)
			(xy 324.301969 -347.566619) (xy 324.350989 -347.576424) (xy 324.397155 -347.595603) (xy 324.438693 -347.623419)
			(xy 324.456806 -347.640656) (xy 326.53605 -349.7199) (xy 333.18069 -349.7199) (xy 336.380074 -346.520516)
			(xy 336.39817 -346.503261) (xy 336.439716 -346.475453) (xy 336.485887 -346.456279) (xy 336.53491 -346.446475)
			(xy 336.559906 -346.44584) (xy 359.887774 -346.44584) (xy 359.912769 -346.446479) (xy 359.961791 -346.456283)
			(xy 360.007958 -346.475459) (xy 360.049499 -346.503272) (xy 360.067606 -346.520516) (xy 360.084134 -346.537044)
			(xy 382.033826 -346.537044) (xy 382.033826 -346.482551) (xy 382.041582 -346.428612) (xy 382.056934 -346.376326)
			(xy 382.079571 -346.326756) (xy 382.109032 -346.280913) (xy 382.144717 -346.239729) (xy 382.185899 -346.204042)
			(xy 382.231741 -346.174579) (xy 382.281309 -346.15194) (xy 382.333595 -346.136585) (xy 382.387533 -346.128828)
			(xy 382.41478 -346.12834) (xy 382.43435 -346.128544) (xy 382.473291 -346.132488) (xy 382.492504 -346.136214)
			(xy 382.506172 -346.138647) (xy 382.533865 -346.136801) (xy 382.560034 -346.127559) (xy 382.582744 -346.111605)
			(xy 382.600312 -346.090118) (xy 382.611437 -346.064692) (xy 382.615296 -346.037208) (xy 382.611603 -346.009701)
			(xy 382.60655 -345.996768) (xy 382.596661 -345.972815) (xy 382.582754 -345.922894) (xy 382.57574 -345.871549)
			(xy 382.575308 -345.845638) (xy 382.575714 -345.818382) (xy 382.583467 -345.764424) (xy 382.59882 -345.712119)
			(xy 382.62146 -345.662531) (xy 382.650927 -345.61667) (xy 382.686621 -345.57547) (xy 382.727815 -345.539768)
			(xy 382.773671 -345.510293) (xy 382.823255 -345.487644) (xy 382.875557 -345.472281) (xy 382.929513 -345.464519)
			(xy 382.984025 -345.464515) (xy 383.037983 -345.472268) (xy 383.090288 -345.487622) (xy 383.139875 -345.510263)
			(xy 383.185736 -345.539731) (xy 383.226936 -345.575426) (xy 383.262636 -345.616621) (xy 383.292111 -345.662477)
			(xy 383.314759 -345.712061) (xy 383.33012 -345.764364) (xy 383.337881 -345.818321) (xy 383.337885 -345.872833)
			(xy 383.33013 -345.92679) (xy 383.314775 -345.979095) (xy 383.292133 -346.028682) (xy 383.262664 -346.074542)
			(xy 383.226969 -346.115741) (xy 383.185773 -346.151441) (xy 383.139916 -346.180914) (xy 383.090332 -346.203562)
			(xy 383.038029 -346.218922) (xy 382.984072 -346.226682) (xy 382.956816 -346.227146) (xy 382.937246 -346.226943)
			(xy 382.898305 -346.222999) (xy 382.879092 -346.219272) (xy 382.865405 -346.216953) (xy 382.837722 -346.218776)
			(xy 382.811557 -346.227999) (xy 382.78885 -346.243937) (xy 382.771282 -346.265408) (xy 382.760157 -346.290823)
			(xy 382.756298 -346.318296) (xy 382.759992 -346.345791) (xy 382.765046 -346.358718) (xy 382.774931 -346.382673)
			(xy 382.78884 -346.432593) (xy 382.795855 -346.483937) (xy 382.796288 -346.509848) (xy 382.79577 -346.537095)
			(xy 382.788009 -346.591033) (xy 382.77265 -346.643317) (xy 382.750007 -346.692884) (xy 382.720541 -346.738723)
			(xy 382.684851 -346.779903) (xy 382.643665 -346.815585) (xy 382.597819 -346.845042) (xy 382.548248 -346.867676)
			(xy 382.495961 -346.883024) (xy 382.442021 -346.890776) (xy 382.387528 -346.890772) (xy 382.33359 -346.883014)
			(xy 382.281304 -346.867658) (xy 382.231736 -346.845018) (xy 382.185895 -346.815555) (xy 382.144713 -346.779867)
			(xy 382.109029 -346.738683) (xy 382.079568 -346.692839) (xy 382.056932 -346.643269) (xy 382.04158 -346.590983)
			(xy 382.033826 -346.537044) (xy 360.084134 -346.537044) (xy 360.986324 -347.439234) (xy 383.381504 -347.439234)
			(xy 383.382082 -347.409547) (xy 383.391276 -347.350889) (xy 383.409446 -347.294363) (xy 383.436155 -347.241336)
			(xy 383.470757 -347.193086) (xy 383.512417 -347.15078) (xy 383.535936 -347.132656) (xy 383.546519 -347.124203)
			(xy 383.563221 -347.102895) (xy 383.573738 -347.077948) (xy 383.57733 -347.051113) (xy 383.573745 -347.024278)
			(xy 383.563235 -346.999328) (xy 383.546538 -346.978015) (xy 383.535936 -346.969588) (xy 383.512428 -346.95145)
			(xy 383.470765 -346.909147) (xy 383.436159 -346.860901) (xy 383.409446 -346.807877) (xy 383.39127 -346.751353)
			(xy 383.38207 -346.692697) (xy 383.381504 -346.66301) (xy 383.38199 -346.635759) (xy 383.389746 -346.581811)
			(xy 383.405101 -346.529516) (xy 383.427743 -346.479939) (xy 383.457209 -346.434089) (xy 383.4929 -346.392898)
			(xy 383.534091 -346.357207) (xy 383.579941 -346.327741) (xy 383.629518 -346.305099) (xy 383.681813 -346.289744)
			(xy 383.735761 -346.281988) (xy 383.790263 -346.281988) (xy 383.844211 -346.289744) (xy 383.896506 -346.305099)
			(xy 383.946083 -346.327741) (xy 383.991933 -346.357207) (xy 384.033124 -346.392898) (xy 384.068815 -346.434089)
			(xy 384.098281 -346.479939) (xy 384.120923 -346.529516) (xy 384.136278 -346.581811) (xy 384.144034 -346.635759)
			(xy 384.14452 -346.66301) (xy 384.143964 -346.692698) (xy 384.134764 -346.751357) (xy 384.116589 -346.807882)
			(xy 384.089876 -346.860909) (xy 384.05527 -346.909158) (xy 384.013608 -346.951464) (xy 383.990088 -346.969588)
			(xy 383.979459 -346.977989) (xy 383.962753 -346.999307) (xy 383.952237 -347.024267) (xy 383.948649 -347.051113)
			(xy 383.952243 -347.077958) (xy 383.962766 -347.102915) (xy 383.979478 -347.12423) (xy 383.990088 -347.132656)
			(xy 384.013622 -347.150762) (xy 384.055282 -347.193072) (xy 384.089884 -347.241325) (xy 384.116593 -347.294356)
			(xy 384.134764 -347.350884) (xy 384.143958 -347.409545) (xy 384.14452 -347.439234) (xy 384.144034 -347.466485)
			(xy 384.136278 -347.520433) (xy 384.120923 -347.572728) (xy 384.098281 -347.622305) (xy 384.068815 -347.668155)
			(xy 384.033124 -347.709346) (xy 383.991933 -347.745037) (xy 383.946083 -347.774503) (xy 383.896506 -347.797145)
			(xy 383.844211 -347.8125) (xy 383.790263 -347.820256) (xy 383.735761 -347.820256) (xy 383.681813 -347.8125)
			(xy 383.629518 -347.797145) (xy 383.579941 -347.774503) (xy 383.534091 -347.745037) (xy 383.4929 -347.709346)
			(xy 383.457209 -347.668155) (xy 383.427743 -347.622305) (xy 383.405101 -347.572728) (xy 383.389746 -347.520433)
			(xy 383.38199 -347.466485) (xy 383.381504 -347.439234) (xy 360.986324 -347.439234) (xy 362.891832 -349.344742)
			(xy 362.909093 -349.362836) (xy 362.936912 -349.404379) (xy 362.956095 -349.45055) (xy 362.965908 -349.499576)
			(xy 362.966508 -349.524574) (xy 362.966508 -350.400296) (xy 363.397796 -350.400296) (xy 363.397796 -350.3156)
			(xy 363.405847 -350.231286) (xy 363.421876 -350.14812) (xy 363.445737 -350.066853) (xy 363.477216 -349.988223)
			(xy 363.516027 -349.912942) (xy 363.561817 -349.84169) (xy 363.614173 -349.775114) (xy 363.672621 -349.713816)
			(xy 363.736631 -349.658351) (xy 363.805623 -349.609222) (xy 363.878973 -349.566873) (xy 363.956016 -349.531689)
			(xy 364.036055 -349.503987) (xy 364.118364 -349.484019) (xy 364.202199 -349.471966) (xy 364.2868 -349.467936)
			(xy 364.371401 -349.471966) (xy 364.455236 -349.484019) (xy 364.537545 -349.503987) (xy 364.617584 -349.531689)
			(xy 364.694627 -349.566873) (xy 364.767977 -349.609222) (xy 364.836969 -349.658351) (xy 364.900979 -349.713816)
			(xy 364.959427 -349.775114) (xy 365.011783 -349.84169) (xy 365.057573 -349.912942) (xy 365.096384 -349.988223)
			(xy 365.127863 -350.066853) (xy 365.151724 -350.14812) (xy 365.167753 -350.231286) (xy 365.175804 -350.3156)
			(xy 365.176308 -350.357948) (xy 365.922309 -350.357948) (xy 365.926345 -350.274501) (xy 365.938417 -350.191833)
			(xy 365.95841 -350.110716) (xy 365.986139 -350.031907) (xy 366.021345 -349.956142) (xy 366.063699 -349.884129)
			(xy 366.112805 -349.81654) (xy 366.168206 -349.754006) (xy 366.229383 -349.697111) (xy 366.295766 -349.646385)
			(xy 366.366734 -349.602304) (xy 366.441626 -349.565278) (xy 366.519742 -349.535652) (xy 366.600352 -349.513704)
			(xy 366.682704 -349.499639) (xy 366.76603 -349.493587) (xy 366.84955 -349.495606) (xy 366.932486 -349.505676)
			(xy 367.014062 -349.523704) (xy 367.093518 -349.549521) (xy 367.170111 -349.582886) (xy 367.243127 -349.623487)
			(xy 367.311883 -349.670946) (xy 367.375737 -349.724819) (xy 367.434094 -349.784604) (xy 367.486409 -349.849741)
			(xy 367.532192 -349.919624) (xy 367.571017 -349.993599) (xy 367.602522 -350.070976) (xy 367.626411 -350.151033)
			(xy 367.642462 -350.233021) (xy 367.650525 -350.316176) (xy 367.65103 -350.357948) (xy 367.650525 -350.39972)
			(xy 367.642462 -350.482875) (xy 367.626411 -350.564863) (xy 367.602522 -350.64492) (xy 367.571017 -350.722297)
			(xy 367.532192 -350.796272) (xy 367.486409 -350.866155) (xy 367.434094 -350.931292) (xy 367.375737 -350.991077)
			(xy 367.311883 -351.04495) (xy 367.243127 -351.092409) (xy 367.170111 -351.13301) (xy 367.093518 -351.166375)
			(xy 367.014062 -351.192192) (xy 366.932486 -351.21022) (xy 366.84955 -351.22029) (xy 366.76603 -351.222309)
			(xy 366.682704 -351.216257) (xy 366.600352 -351.202192) (xy 366.519742 -351.180244) (xy 366.441626 -351.150618)
			(xy 366.366734 -351.113592) (xy 366.295766 -351.069511) (xy 366.229383 -351.018785) (xy 366.168206 -350.96189)
			(xy 366.112805 -350.899356) (xy 366.063699 -350.831767) (xy 366.021345 -350.759754) (xy 365.986139 -350.683989)
			(xy 365.95841 -350.60518) (xy 365.938417 -350.524063) (xy 365.926345 -350.441395) (xy 365.922309 -350.357948)
			(xy 365.176308 -350.357948) (xy 365.175804 -350.400296) (xy 365.167753 -350.48461) (xy 365.151724 -350.567776)
			(xy 365.127863 -350.649043) (xy 365.096384 -350.727673) (xy 365.057573 -350.802954) (xy 365.011783 -350.874206)
			(xy 364.959427 -350.940782) (xy 364.900979 -351.00208) (xy 364.836969 -351.057545) (xy 364.767977 -351.106674)
			(xy 364.694627 -351.149023) (xy 364.617584 -351.184207) (xy 364.537545 -351.211909) (xy 364.455236 -351.231877)
			(xy 364.371401 -351.24393) (xy 364.2868 -351.247961) (xy 364.202199 -351.24393) (xy 364.118364 -351.231877)
			(xy 364.036055 -351.211909) (xy 363.956016 -351.184207) (xy 363.878973 -351.149023) (xy 363.805623 -351.106674)
			(xy 363.736631 -351.057545) (xy 363.672621 -351.00208) (xy 363.614173 -350.940782) (xy 363.561817 -350.874206)
			(xy 363.516027 -350.802954) (xy 363.477216 -350.727673) (xy 363.445737 -350.649043) (xy 363.421876 -350.567776)
			(xy 363.405847 -350.48461) (xy 363.397796 -350.400296) (xy 362.966508 -350.400296) (xy 362.966508 -351.014538)
			(xy 363.57941 -351.62744) (xy 365.069374 -351.62744) (xy 365.094369 -351.628079) (xy 365.143391 -351.637883)
			(xy 365.189558 -351.657059) (xy 365.231099 -351.684872) (xy 365.249206 -351.702116) (xy 366.247172 -352.700082)
			(xy 366.264428 -352.718178) (xy 366.292235 -352.759724) (xy 366.311409 -352.805895) (xy 366.321212 -352.854918)
			(xy 366.321848 -352.879914) (xy 366.321848 -353.79279) (xy 366.64722 -353.79279) (xy 366.651291 -353.737168)
			(xy 366.663417 -353.682731) (xy 366.68334 -353.63064) (xy 366.710636 -353.582005) (xy 366.744722 -353.537862)
			(xy 366.784871 -353.499153) (xy 366.830229 -353.466702) (xy 366.879829 -353.441201) (xy 366.932613 -353.423194)
			(xy 366.987456 -353.413064) (xy 367.04319 -353.411027) (xy 367.098627 -353.417127) (xy 367.152584 -353.431233)
			(xy 367.203913 -353.453045) (xy 367.251519 -353.482099) (xy 367.294387 -353.517774) (xy 367.331604 -353.559311)
			(xy 367.362377 -353.605824) (xy 367.386049 -353.656321) (xy 367.402117 -353.709728) (xy 367.410237 -353.764904)
			(xy 367.410746 -353.79279) (xy 367.410237 -353.820676) (xy 367.402117 -353.875852) (xy 367.386049 -353.929259)
			(xy 367.362377 -353.979756) (xy 367.331604 -354.026269) (xy 367.294387 -354.067806) (xy 367.251519 -354.103481)
			(xy 367.203913 -354.132535) (xy 367.152584 -354.154347) (xy 367.098627 -354.168453) (xy 367.04319 -354.174553)
			(xy 366.987456 -354.172516) (xy 366.932613 -354.162386) (xy 366.879829 -354.144379) (xy 366.830229 -354.118878)
			(xy 366.784871 -354.086427) (xy 366.744722 -354.047718) (xy 366.710636 -354.003575) (xy 366.68334 -353.95494)
			(xy 366.663417 -353.902849) (xy 366.651291 -353.848412) (xy 366.64722 -353.79279) (xy 366.321848 -353.79279)
			(xy 366.321848 -353.815142) (xy 366.321212 -353.840138) (xy 366.311413 -353.889163) (xy 366.29224 -353.935334)
			(xy 366.264429 -353.976879) (xy 366.247172 -353.994974) (xy 365.571786 -354.67036) (xy 365.55369 -354.687614)
			(xy 365.512143 -354.715418) (xy 365.465972 -354.734587) (xy 365.416949 -354.744384) (xy 365.391954 -354.745036)
			(xy 364.986824 -354.745036) (xy 364.976918 -354.783136) (xy 364.969449 -354.81009) (xy 364.947706 -354.861621)
			(xy 364.91868 -354.909429) (xy 364.882989 -354.952492) (xy 364.841399 -354.989889) (xy 364.794799 -355.020818)
			(xy 364.744186 -355.044619) (xy 364.690642 -355.060783) (xy 364.635313 -355.068963) (xy 364.607348 -355.069394)
			(xy 364.580093 -355.068934) (xy 364.526138 -355.061182) (xy 364.473835 -355.04583) (xy 364.42425 -355.02319)
			(xy 364.378392 -354.993724) (xy 364.337194 -354.95803) (xy 364.301497 -354.916836) (xy 364.272026 -354.87098)
			(xy 364.249381 -354.821397) (xy 364.234025 -354.769095) (xy 364.226269 -354.715141) (xy 364.22584 -354.687886)
			(xy 364.226286 -354.661507) (xy 364.233551 -354.609251) (xy 364.24794 -354.558494) (xy 364.26918 -354.5102)
			(xy 364.296866 -354.46529) (xy 364.33047 -354.424619) (xy 364.369354 -354.388961) (xy 364.412776 -354.358996)
			(xy 364.436152 -354.346764) (xy 364.448283 -354.34016) (xy 364.468735 -354.321615) (xy 364.483465 -354.298265)
			(xy 364.491397 -354.27182) (xy 364.491948 -354.244218) (xy 364.485079 -354.217478) (xy 364.471293 -354.193558)
			(xy 364.451598 -354.17421) (xy 364.439708 -354.167186) (xy 364.415958 -354.155105) (xy 364.371789 -354.125301)
			(xy 364.332199 -354.089637) (xy 364.29796 -354.048809) (xy 364.269739 -354.003612) (xy 364.248086 -353.954925)
			(xy 364.233422 -353.903698) (xy 364.226033 -353.850929) (xy 364.225586 -353.824286) (xy 364.22605 -353.797017)
			(xy 364.233814 -353.743034) (xy 364.249182 -353.690706) (xy 364.271841 -353.641097) (xy 364.30133 -353.595219)
			(xy 364.337048 -353.554005) (xy 364.378269 -353.518293) (xy 364.424152 -353.488812) (xy 364.473764 -353.466161)
			(xy 364.526095 -353.450801) (xy 364.580079 -353.443046) (xy 364.607348 -353.442524) (xy 364.633795 -353.442971)
			(xy 364.686182 -353.450269) (xy 364.737058 -353.464733) (xy 364.78545 -353.486085) (xy 364.830429 -353.513916)
			(xy 364.871133 -353.547693) (xy 364.906781 -353.586767) (xy 364.936692 -353.630391) (xy 364.96029 -353.677728)
			(xy 364.977124 -353.727871) (xy 364.986872 -353.779858) (xy 364.988602 -353.806252) (xy 364.990634 -353.8474)
			(xy 364.998 -353.854766) (xy 365.128302 -353.854766) (xy 365.431578 -353.55149) (xy 365.431578 -353.143566)
			(xy 364.805722 -352.51771) (xy 363.772704 -352.51771) (xy 363.758228 -352.519178) (xy 363.730954 -352.529283)
			(xy 363.707635 -352.546667) (xy 363.690164 -352.569921) (xy 363.679959 -352.597157) (xy 363.677847 -352.626166)
			(xy 363.684 -352.654594) (xy 363.697919 -352.680133) (xy 363.707934 -352.690684) (xy 363.733588 -352.716338)
			(xy 363.733588 -356.42296) (xy 363.734141 -356.437925) (xy 363.742868 -356.466557) (xy 363.759523 -356.491427)
			(xy 363.782676 -356.510397) (xy 363.810336 -356.521836) (xy 363.840124 -356.524762) (xy 363.869481 -356.518922)
			(xy 363.895882 -356.504819) (xy 363.906816 -356.494588) (xy 364.47222 -355.929184) (xy 364.489247 -355.912901)
			(xy 364.528133 -355.886307) (xy 364.571245 -355.867316) (xy 364.617114 -355.856576) (xy 364.640622 -355.855016)
			(xy 365.942372 -355.855016) (xy 372.379494 -349.41764) (xy 372.396522 -349.401357) (xy 372.435408 -349.374764)
			(xy 372.47852 -349.355772) (xy 372.524388 -349.345029) (xy 372.547896 -349.343472) (xy 382.630172 -349.343472)
			(xy 383.436876 -349.009208) (xy 384.524504 -347.921326) (xy 384.524504 -347.134688) (xy 384.504884 -347.116521)
			(xy 384.470415 -347.075642) (xy 384.441994 -347.03035) (xy 384.420177 -346.981532) (xy 384.405392 -346.930145)
			(xy 384.397929 -346.877198) (xy 384.397504 -346.850462) (xy 384.398078 -346.821335) (xy 384.406975 -346.763762)
			(xy 384.424509 -346.708208) (xy 384.450276 -346.655961) (xy 384.483677 -346.608231) (xy 384.503422 -346.58681)
			(xy 384.509889 -346.579337) (xy 384.51711 -346.56096) (xy 384.516911 -346.541216) (xy 384.50932 -346.522988)
			(xy 384.50266 -346.51569) (xy 383.288286 -345.301316) (xy 378.202952 -345.301316) (xy 378.17889 -345.300104)
			(xy 378.131841 -345.289766) (xy 378.087578 -345.270757) (xy 378.047685 -345.243757) (xy 378.030232 -345.227148)
			(xy 376.438668 -343.635584) (xy 376.421413 -343.617488) (xy 376.393606 -343.575942) (xy 376.374436 -343.529771)
			(xy 376.364638 -343.480748) (xy 376.363992 -343.455752) (xy 376.363992 -343.2683) (xy 376.363433 -343.253341)
			(xy 376.354701 -343.224725) (xy 376.338046 -343.19987) (xy 376.314899 -343.180912) (xy 376.28725 -343.169481)
			(xy 376.257474 -343.166559) (xy 376.22813 -343.172396) (xy 376.201739 -343.186491) (xy 376.190764 -343.196672)
			(xy 375.677176 -343.71026) (xy 375.659065 -343.72748) (xy 375.617504 -343.755218) (xy 375.571335 -343.774325)
			(xy 375.522327 -343.78407) (xy 375.497344 -343.784682) (xy 373.728234 -343.784682) (xy 373.703249 -343.784074)
			(xy 373.654236 -343.774339) (xy 373.608062 -343.755237) (xy 373.566497 -343.727499) (xy 373.548402 -343.71026)
			(xy 370.973858 -341.135716) (xy 370.150898 -341.135716) (xy 370.125896 -341.135124) (xy 370.076861 -341.125329)
			(xy 370.030678 -341.106156) (xy 369.989123 -341.078342) (xy 369.971066 -341.06104) (xy 368.399314 -339.489034)
			(xy 368.389275 -339.479677) (xy 368.365375 -339.466209) (xy 368.338751 -339.459596) (xy 368.311328 -339.460318)
			(xy 368.285089 -339.468322) (xy 368.261931 -339.48303) (xy 368.243531 -339.503377) (xy 368.237008 -339.51545)
			(xy 368.227529 -339.533281) (xy 368.203793 -339.565949) (xy 368.189764 -339.580474) (xy 367.710974 -340.059264)
			(xy 367.44656 -340.323932) (xy 367.428466 -340.341193) (xy 367.386923 -340.369012) (xy 367.340752 -340.388196)
			(xy 367.291726 -340.398009) (xy 367.266728 -340.398608) (xy 361.253278 -340.398608) (xy 361.228277 -340.398014)
			(xy 361.179244 -340.388216) (xy 361.133064 -340.36904) (xy 361.091513 -340.341223) (xy 361.073446 -340.323932)
			(xy 360.750104 -340.000336) (xy 360.16438 -339.414612) (xy 360.088688 -339.420454) (xy 360.075226 -339.435948)
			(xy 360.066336 -339.4456) (xy 360.061764 -339.450172) (xy 359.74147 -339.77072) (xy 359.201466 -340.310724)
			(xy 359.183356 -340.327946) (xy 359.141796 -340.355685) (xy 359.095626 -340.374794) (xy 359.046618 -340.384538)
			(xy 359.021634 -340.385146) (xy 353.079558 -340.385146) (xy 353.054572 -340.38454) (xy 353.005558 -340.374808)
			(xy 352.959382 -340.355707) (xy 352.917816 -340.327968) (xy 352.899726 -340.310724) (xy 352.395282 -339.80628)
			(xy 352.095816 -339.50656) (xy 352.085235 -339.496809) (xy 352.059947 -339.483107) (xy 352.031842 -339.476996)
			(xy 352.003148 -339.478959) (xy 351.976138 -339.488841) (xy 351.952952 -339.505859) (xy 351.935427 -339.528664)
			(xy 351.9297 -339.541866) (xy 351.919577 -339.565911) (xy 351.891032 -339.609571) (xy 351.873058 -339.62848)
			(xy 351.872296 -339.629242) (xy 351.191576 -340.310216) (xy 351.173478 -340.327466) (xy 351.131929 -340.355262)
			(xy 351.085759 -340.374425) (xy 351.036738 -340.384218) (xy 351.011744 -340.384892) (xy 344.918538 -340.384892)
			(xy 344.893542 -340.384254) (xy 344.844518 -340.374454) (xy 344.798348 -340.35528) (xy 344.756803 -340.327471)
			(xy 344.738706 -340.310216) (xy 343.972134 -339.543644) (xy 343.961167 -339.53343) (xy 343.934751 -339.519305)
			(xy 343.905374 -339.513448) (xy 343.875561 -339.516362) (xy 343.847875 -339.527796) (xy 343.824694 -339.546768)
			(xy 343.808011 -339.571648) (xy 343.799259 -339.600296) (xy 343.798652 -339.615272) (xy 343.798652 -340.146894)
			(xy 343.798906 -340.571328) (xy 343.798293 -340.596311) (xy 343.788548 -340.645318) (xy 343.769439 -340.691485)
			(xy 343.741697 -340.733043) (xy 343.724484 -340.75116) (xy 341.054944 -343.4207) (xy 341.036848 -343.437956)
			(xy 340.995302 -343.465765) (xy 340.949131 -343.484941) (xy 340.900108 -343.494748) (xy 340.875112 -343.495376)
			(xy 336.57286 -343.495376) (xy 336.547863 -343.49474) (xy 336.498838 -343.484943) (xy 336.452665 -343.465771)
			(xy 336.411118 -343.437962) (xy 336.393028 -343.4207) (xy 336.159602 -343.18702) (xy 335.736692 -342.76411)
			(xy 335.647792 -342.795352) (xy 335.647792 -342.849962) (xy 335.648046 -342.89365) (xy 335.64744 -342.918635)
			(xy 335.637706 -342.967649) (xy 335.618604 -343.013824) (xy 335.590864 -343.055388) (xy 335.573624 -343.073482)
			(xy 334.702474 -343.944632) (xy 344.389706 -343.944632) (xy 344.389706 -343.859936) (xy 344.397757 -343.775622)
			(xy 344.413786 -343.692456) (xy 344.437647 -343.611189) (xy 344.469126 -343.532559) (xy 344.507937 -343.457278)
			(xy 344.553727 -343.386026) (xy 344.606083 -343.31945) (xy 344.664531 -343.258152) (xy 344.728541 -343.202687)
			(xy 344.797533 -343.153558) (xy 344.870883 -343.111209) (xy 344.947926 -343.076025) (xy 345.027965 -343.048323)
			(xy 345.110274 -343.028355) (xy 345.194109 -343.016302) (xy 345.27871 -343.012272) (xy 345.363311 -343.016302)
			(xy 345.447146 -343.028355) (xy 345.529455 -343.048323) (xy 345.609494 -343.076025) (xy 345.686537 -343.111209)
			(xy 345.759887 -343.153558) (xy 345.828879 -343.202687) (xy 345.892889 -343.258152) (xy 345.951337 -343.31945)
			(xy 346.003693 -343.386026) (xy 346.049483 -343.457278) (xy 346.088294 -343.532559) (xy 346.119773 -343.611189)
			(xy 346.143634 -343.692456) (xy 346.159663 -343.775622) (xy 346.167714 -343.859936) (xy 346.168218 -343.902284)
			(xy 346.914219 -343.902284) (xy 346.918255 -343.818837) (xy 346.930327 -343.736169) (xy 346.95032 -343.655052)
			(xy 346.978049 -343.576243) (xy 347.013255 -343.500478) (xy 347.055609 -343.428465) (xy 347.104715 -343.360876)
			(xy 347.160116 -343.298342) (xy 347.221293 -343.241447) (xy 347.287676 -343.190721) (xy 347.358644 -343.14664)
			(xy 347.433536 -343.109614) (xy 347.511652 -343.079988) (xy 347.592262 -343.05804) (xy 347.674614 -343.043975)
			(xy 347.75794 -343.037923) (xy 347.84146 -343.039942) (xy 347.924396 -343.050012) (xy 348.005972 -343.06804)
			(xy 348.085428 -343.093857) (xy 348.162021 -343.127222) (xy 348.235037 -343.167823) (xy 348.303793 -343.215282)
			(xy 348.367647 -343.269155) (xy 348.426004 -343.32894) (xy 348.478319 -343.394077) (xy 348.524102 -343.46396)
			(xy 348.562927 -343.537935) (xy 348.594432 -343.615312) (xy 348.618321 -343.695369) (xy 348.634372 -343.777357)
			(xy 348.642435 -343.860512) (xy 348.64294 -343.902284) (xy 348.642435 -343.944056) (xy 348.642379 -343.944632)
			(xy 351.95027 -343.944632) (xy 351.95027 -343.859936) (xy 351.958321 -343.775622) (xy 351.97435 -343.692456)
			(xy 351.998211 -343.611189) (xy 352.02969 -343.532559) (xy 352.068501 -343.457278) (xy 352.114291 -343.386026)
			(xy 352.166647 -343.31945) (xy 352.225095 -343.258152) (xy 352.289105 -343.202687) (xy 352.358097 -343.153558)
			(xy 352.431447 -343.111209) (xy 352.50849 -343.076025) (xy 352.588529 -343.048323) (xy 352.670838 -343.028355)
			(xy 352.754673 -343.016302) (xy 352.839274 -343.012272) (xy 352.923875 -343.016302) (xy 353.00771 -343.028355)
			(xy 353.090019 -343.048323) (xy 353.170058 -343.076025) (xy 353.247101 -343.111209) (xy 353.320451 -343.153558)
			(xy 353.389443 -343.202687) (xy 353.453453 -343.258152) (xy 353.511901 -343.31945) (xy 353.564257 -343.386026)
			(xy 353.610047 -343.457278) (xy 353.648858 -343.532559) (xy 353.680337 -343.611189) (xy 353.704198 -343.692456)
			(xy 353.720227 -343.775622) (xy 353.728278 -343.859936) (xy 353.728782 -343.902284) (xy 354.474783 -343.902284)
			(xy 354.478819 -343.818837) (xy 354.490891 -343.736169) (xy 354.510884 -343.655052) (xy 354.538613 -343.576243)
			(xy 354.573819 -343.500478) (xy 354.616173 -343.428465) (xy 354.665279 -343.360876) (xy 354.72068 -343.298342)
			(xy 354.781857 -343.241447) (xy 354.84824 -343.190721) (xy 354.919208 -343.14664) (xy 354.9941 -343.109614)
			(xy 355.072216 -343.079988) (xy 355.152826 -343.05804) (xy 355.235178 -343.043975) (xy 355.318504 -343.037923)
			(xy 355.402024 -343.039942) (xy 355.48496 -343.050012) (xy 355.566536 -343.06804) (xy 355.645992 -343.093857)
			(xy 355.722585 -343.127222) (xy 355.795601 -343.167823) (xy 355.864357 -343.215282) (xy 355.928211 -343.269155)
			(xy 355.986568 -343.32894) (xy 356.038883 -343.394077) (xy 356.084666 -343.46396) (xy 356.123491 -343.537935)
			(xy 356.154996 -343.615312) (xy 356.178885 -343.695369) (xy 356.194936 -343.777357) (xy 356.202999 -343.860512)
			(xy 356.203504 -343.902284) (xy 356.202999 -343.944056) (xy 356.202943 -343.944632) (xy 359.655614 -343.944632)
			(xy 359.655614 -343.859936) (xy 359.663665 -343.775622) (xy 359.679694 -343.692456) (xy 359.703555 -343.611189)
			(xy 359.735034 -343.532559) (xy 359.773845 -343.457278) (xy 359.819635 -343.386026) (xy 359.871991 -343.31945)
			(xy 359.930439 -343.258152) (xy 359.994449 -343.202687) (xy 360.063441 -343.153558) (xy 360.136791 -343.111209)
			(xy 360.213834 -343.076025) (xy 360.293873 -343.048323) (xy 360.376182 -343.028355) (xy 360.460017 -343.016302)
			(xy 360.544618 -343.012272) (xy 360.629219 -343.016302) (xy 360.713054 -343.028355) (xy 360.795363 -343.048323)
			(xy 360.875402 -343.076025) (xy 360.952445 -343.111209) (xy 361.025795 -343.153558) (xy 361.094787 -343.202687)
			(xy 361.158797 -343.258152) (xy 361.217245 -343.31945) (xy 361.269601 -343.386026) (xy 361.315391 -343.457278)
			(xy 361.354202 -343.532559) (xy 361.385681 -343.611189) (xy 361.409542 -343.692456) (xy 361.425571 -343.775622)
			(xy 361.433622 -343.859936) (xy 361.434126 -343.902284) (xy 362.180127 -343.902284) (xy 362.184163 -343.818837)
			(xy 362.196235 -343.736169) (xy 362.216228 -343.655052) (xy 362.243957 -343.576243) (xy 362.279163 -343.500478)
			(xy 362.321517 -343.428465) (xy 362.370623 -343.360876) (xy 362.426024 -343.298342) (xy 362.487201 -343.241447)
			(xy 362.553584 -343.190721) (xy 362.624552 -343.14664) (xy 362.699444 -343.109614) (xy 362.77756 -343.079988)
			(xy 362.85817 -343.05804) (xy 362.940522 -343.043975) (xy 363.023848 -343.037923) (xy 363.107368 -343.039942)
			(xy 363.190304 -343.050012) (xy 363.27188 -343.06804) (xy 363.351336 -343.093857) (xy 363.427929 -343.127222)
			(xy 363.500945 -343.167823) (xy 363.569701 -343.215282) (xy 363.633555 -343.269155) (xy 363.691912 -343.32894)
			(xy 363.744227 -343.394077) (xy 363.79001 -343.46396) (xy 363.828835 -343.537935) (xy 363.86034 -343.615312)
			(xy 363.884229 -343.695369) (xy 363.90028 -343.777357) (xy 363.908343 -343.860512) (xy 363.908848 -343.902284)
			(xy 363.908343 -343.944056) (xy 363.908287 -343.944632) (xy 367.216178 -343.944632) (xy 367.216178 -343.859936)
			(xy 367.224229 -343.775622) (xy 367.240258 -343.692456) (xy 367.264119 -343.611189) (xy 367.295598 -343.532559)
			(xy 367.334409 -343.457278) (xy 367.380199 -343.386026) (xy 367.432555 -343.31945) (xy 367.491003 -343.258152)
			(xy 367.555013 -343.202687) (xy 367.624005 -343.153558) (xy 367.697355 -343.111209) (xy 367.774398 -343.076025)
			(xy 367.854437 -343.048323) (xy 367.936746 -343.028355) (xy 368.020581 -343.016302) (xy 368.105182 -343.012272)
			(xy 368.189783 -343.016302) (xy 368.273618 -343.028355) (xy 368.355927 -343.048323) (xy 368.435966 -343.076025)
			(xy 368.513009 -343.111209) (xy 368.586359 -343.153558) (xy 368.655351 -343.202687) (xy 368.719361 -343.258152)
			(xy 368.777809 -343.31945) (xy 368.830165 -343.386026) (xy 368.875955 -343.457278) (xy 368.914766 -343.532559)
			(xy 368.946245 -343.611189) (xy 368.970106 -343.692456) (xy 368.986135 -343.775622) (xy 368.994186 -343.859936)
			(xy 368.99469 -343.902284) (xy 369.740691 -343.902284) (xy 369.744727 -343.818837) (xy 369.756799 -343.736169)
			(xy 369.776792 -343.655052) (xy 369.804521 -343.576243) (xy 369.839727 -343.500478) (xy 369.882081 -343.428465)
			(xy 369.931187 -343.360876) (xy 369.986588 -343.298342) (xy 370.047765 -343.241447) (xy 370.114148 -343.190721)
			(xy 370.185116 -343.14664) (xy 370.260008 -343.109614) (xy 370.338124 -343.079988) (xy 370.418734 -343.05804)
			(xy 370.501086 -343.043975) (xy 370.584412 -343.037923) (xy 370.667932 -343.039942) (xy 370.750868 -343.050012)
			(xy 370.832444 -343.06804) (xy 370.9119 -343.093857) (xy 370.988493 -343.127222) (xy 371.061509 -343.167823)
			(xy 371.130265 -343.215282) (xy 371.194119 -343.269155) (xy 371.252476 -343.32894) (xy 371.304791 -343.394077)
			(xy 371.350574 -343.46396) (xy 371.389399 -343.537935) (xy 371.420904 -343.615312) (xy 371.444793 -343.695369)
			(xy 371.460844 -343.777357) (xy 371.468907 -343.860512) (xy 371.469412 -343.902284) (xy 371.468907 -343.944056)
			(xy 371.460844 -344.027211) (xy 371.444793 -344.109199) (xy 371.420904 -344.189256) (xy 371.389399 -344.266633)
			(xy 371.350574 -344.340608) (xy 371.304791 -344.410491) (xy 371.252476 -344.475628) (xy 371.194119 -344.535413)
			(xy 371.130265 -344.589286) (xy 371.061509 -344.636745) (xy 370.988493 -344.677346) (xy 370.9119 -344.710711)
			(xy 370.832444 -344.736528) (xy 370.750868 -344.754556) (xy 370.667932 -344.764626) (xy 370.584412 -344.766645)
			(xy 370.501086 -344.760593) (xy 370.418734 -344.746528) (xy 370.338124 -344.72458) (xy 370.260008 -344.694954)
			(xy 370.185116 -344.657928) (xy 370.114148 -344.613847) (xy 370.047765 -344.563121) (xy 369.986588 -344.506226)
			(xy 369.931187 -344.443692) (xy 369.882081 -344.376103) (xy 369.839727 -344.30409) (xy 369.804521 -344.228325)
			(xy 369.776792 -344.149516) (xy 369.756799 -344.068399) (xy 369.744727 -343.985731) (xy 369.740691 -343.902284)
			(xy 368.99469 -343.902284) (xy 368.994186 -343.944632) (xy 368.986135 -344.028946) (xy 368.970106 -344.112112)
			(xy 368.946245 -344.193379) (xy 368.914766 -344.272009) (xy 368.875955 -344.34729) (xy 368.830165 -344.418542)
			(xy 368.777809 -344.485118) (xy 368.719361 -344.546416) (xy 368.655351 -344.601881) (xy 368.586359 -344.65101)
			(xy 368.513009 -344.693359) (xy 368.435966 -344.728543) (xy 368.355927 -344.756245) (xy 368.273618 -344.776213)
			(xy 368.189783 -344.788266) (xy 368.105182 -344.792297) (xy 368.020581 -344.788266) (xy 367.936746 -344.776213)
			(xy 367.854437 -344.756245) (xy 367.774398 -344.728543) (xy 367.697355 -344.693359) (xy 367.624005 -344.65101)
			(xy 367.555013 -344.601881) (xy 367.491003 -344.546416) (xy 367.432555 -344.485118) (xy 367.380199 -344.418542)
			(xy 367.334409 -344.34729) (xy 367.295598 -344.272009) (xy 367.264119 -344.193379) (xy 367.240258 -344.112112)
			(xy 367.224229 -344.028946) (xy 367.216178 -343.944632) (xy 363.908287 -343.944632) (xy 363.90028 -344.027211)
			(xy 363.884229 -344.109199) (xy 363.86034 -344.189256) (xy 363.828835 -344.266633) (xy 363.79001 -344.340608)
			(xy 363.744227 -344.410491) (xy 363.691912 -344.475628) (xy 363.633555 -344.535413) (xy 363.569701 -344.589286)
			(xy 363.500945 -344.636745) (xy 363.427929 -344.677346) (xy 363.351336 -344.710711) (xy 363.27188 -344.736528)
			(xy 363.190304 -344.754556) (xy 363.107368 -344.764626) (xy 363.023848 -344.766645) (xy 362.940522 -344.760593)
			(xy 362.85817 -344.746528) (xy 362.77756 -344.72458) (xy 362.699444 -344.694954) (xy 362.624552 -344.657928)
			(xy 362.553584 -344.613847) (xy 362.487201 -344.563121) (xy 362.426024 -344.506226) (xy 362.370623 -344.443692)
			(xy 362.321517 -344.376103) (xy 362.279163 -344.30409) (xy 362.243957 -344.228325) (xy 362.216228 -344.149516)
			(xy 362.196235 -344.068399) (xy 362.184163 -343.985731) (xy 362.180127 -343.902284) (xy 361.434126 -343.902284)
			(xy 361.433622 -343.944632) (xy 361.425571 -344.028946) (xy 361.409542 -344.112112) (xy 361.385681 -344.193379)
			(xy 361.354202 -344.272009) (xy 361.315391 -344.34729) (xy 361.269601 -344.418542) (xy 361.217245 -344.485118)
			(xy 361.158797 -344.546416) (xy 361.094787 -344.601881) (xy 361.025795 -344.65101) (xy 360.952445 -344.693359)
			(xy 360.875402 -344.728543) (xy 360.795363 -344.756245) (xy 360.713054 -344.776213) (xy 360.629219 -344.788266)
			(xy 360.544618 -344.792297) (xy 360.460017 -344.788266) (xy 360.376182 -344.776213) (xy 360.293873 -344.756245)
			(xy 360.213834 -344.728543) (xy 360.136791 -344.693359) (xy 360.063441 -344.65101) (xy 359.994449 -344.601881)
			(xy 359.930439 -344.546416) (xy 359.871991 -344.485118) (xy 359.819635 -344.418542) (xy 359.773845 -344.34729)
			(xy 359.735034 -344.272009) (xy 359.703555 -344.193379) (xy 359.679694 -344.112112) (xy 359.663665 -344.028946)
			(xy 359.655614 -343.944632) (xy 356.202943 -343.944632) (xy 356.194936 -344.027211) (xy 356.178885 -344.109199)
			(xy 356.154996 -344.189256) (xy 356.123491 -344.266633) (xy 356.084666 -344.340608) (xy 356.038883 -344.410491)
			(xy 355.986568 -344.475628) (xy 355.928211 -344.535413) (xy 355.864357 -344.589286) (xy 355.795601 -344.636745)
			(xy 355.722585 -344.677346) (xy 355.645992 -344.710711) (xy 355.566536 -344.736528) (xy 355.48496 -344.754556)
			(xy 355.402024 -344.764626) (xy 355.318504 -344.766645) (xy 355.235178 -344.760593) (xy 355.152826 -344.746528)
			(xy 355.072216 -344.72458) (xy 354.9941 -344.694954) (xy 354.919208 -344.657928) (xy 354.84824 -344.613847)
			(xy 354.781857 -344.563121) (xy 354.72068 -344.506226) (xy 354.665279 -344.443692) (xy 354.616173 -344.376103)
			(xy 354.573819 -344.30409) (xy 354.538613 -344.228325) (xy 354.510884 -344.149516) (xy 354.490891 -344.068399)
			(xy 354.478819 -343.985731) (xy 354.474783 -343.902284) (xy 353.728782 -343.902284) (xy 353.728278 -343.944632)
			(xy 353.720227 -344.028946) (xy 353.704198 -344.112112) (xy 353.680337 -344.193379) (xy 353.648858 -344.272009)
			(xy 353.610047 -344.34729) (xy 353.564257 -344.418542) (xy 353.511901 -344.485118) (xy 353.453453 -344.546416)
			(xy 353.389443 -344.601881) (xy 353.320451 -344.65101) (xy 353.247101 -344.693359) (xy 353.170058 -344.728543)
			(xy 353.090019 -344.756245) (xy 353.00771 -344.776213) (xy 352.923875 -344.788266) (xy 352.839274 -344.792297)
			(xy 352.754673 -344.788266) (xy 352.670838 -344.776213) (xy 352.588529 -344.756245) (xy 352.50849 -344.728543)
			(xy 352.431447 -344.693359) (xy 352.358097 -344.65101) (xy 352.289105 -344.601881) (xy 352.225095 -344.546416)
			(xy 352.166647 -344.485118) (xy 352.114291 -344.418542) (xy 352.068501 -344.34729) (xy 352.02969 -344.272009)
			(xy 351.998211 -344.193379) (xy 351.97435 -344.112112) (xy 351.958321 -344.028946) (xy 351.95027 -343.944632)
			(xy 348.642379 -343.944632) (xy 348.634372 -344.027211) (xy 348.618321 -344.109199) (xy 348.594432 -344.189256)
			(xy 348.562927 -344.266633) (xy 348.524102 -344.340608) (xy 348.478319 -344.410491) (xy 348.426004 -344.475628)
			(xy 348.367647 -344.535413) (xy 348.303793 -344.589286) (xy 348.235037 -344.636745) (xy 348.162021 -344.677346)
			(xy 348.085428 -344.710711) (xy 348.005972 -344.736528) (xy 347.924396 -344.754556) (xy 347.84146 -344.764626)
			(xy 347.75794 -344.766645) (xy 347.674614 -344.760593) (xy 347.592262 -344.746528) (xy 347.511652 -344.72458)
			(xy 347.433536 -344.694954) (xy 347.358644 -344.657928) (xy 347.287676 -344.613847) (xy 347.221293 -344.563121)
			(xy 347.160116 -344.506226) (xy 347.104715 -344.443692) (xy 347.055609 -344.376103) (xy 347.013255 -344.30409)
			(xy 346.978049 -344.228325) (xy 346.95032 -344.149516) (xy 346.930327 -344.068399) (xy 346.918255 -343.985731)
			(xy 346.914219 -343.902284) (xy 346.168218 -343.902284) (xy 346.167714 -343.944632) (xy 346.159663 -344.028946)
			(xy 346.143634 -344.112112) (xy 346.119773 -344.193379) (xy 346.088294 -344.272009) (xy 346.049483 -344.34729)
			(xy 346.003693 -344.418542) (xy 345.951337 -344.485118) (xy 345.892889 -344.546416) (xy 345.828879 -344.601881)
			(xy 345.759887 -344.65101) (xy 345.686537 -344.693359) (xy 345.609494 -344.728543) (xy 345.529455 -344.756245)
			(xy 345.447146 -344.776213) (xy 345.363311 -344.788266) (xy 345.27871 -344.792297) (xy 345.194109 -344.788266)
			(xy 345.110274 -344.776213) (xy 345.027965 -344.756245) (xy 344.947926 -344.728543) (xy 344.870883 -344.693359)
			(xy 344.797533 -344.65101) (xy 344.728541 -344.601881) (xy 344.664531 -344.546416) (xy 344.606083 -344.485118)
			(xy 344.553727 -344.418542) (xy 344.507937 -344.34729) (xy 344.469126 -344.272009) (xy 344.437647 -344.193379)
			(xy 344.413786 -344.112112) (xy 344.397757 -344.028946) (xy 344.389706 -343.944632) (xy 334.702474 -343.944632)
			(xy 334.647032 -344.000074) (xy 334.647032 -347.357446) (xy 334.646395 -347.382442) (xy 334.636596 -347.431466)
			(xy 334.617421 -347.477636) (xy 334.589608 -347.519179) (xy 334.572356 -347.537278) (xy 332.740254 -349.36938)
			(xy 332.722159 -349.386638) (xy 332.680614 -349.414451) (xy 332.634443 -349.43363) (xy 332.585419 -349.443439)
			(xy 332.560422 -349.444056) (xy 328.198226 -349.444056) (xy 328.173231 -349.443417) (xy 328.124209 -349.433613)
			(xy 328.078042 -349.414436) (xy 328.036502 -349.386623) (xy 328.018394 -349.36938) (xy 327.506076 -348.857062)
			(xy 327.488814 -348.838969) (xy 327.460994 -348.797425) (xy 327.441809 -348.751254) (xy 327.431996 -348.702228)
			(xy 327.4314 -348.67723) (xy 327.4314 -347.195394) (xy 327.41997 -347.183964) (xy 327.402025 -347.16594)
			(xy 327.370583 -347.125962) (xy 327.344732 -347.08216) (xy 327.324932 -347.035311) (xy 327.311533 -346.986247)
			(xy 327.304773 -346.935837) (xy 327.3044 -346.910406) (xy 327.304863 -346.883153) (xy 327.312619 -346.829202)
			(xy 327.327975 -346.776904) (xy 327.350617 -346.727323) (xy 327.380085 -346.68147) (xy 327.415779 -346.640277)
			(xy 327.456972 -346.604584) (xy 327.502825 -346.575116) (xy 327.552406 -346.552474) (xy 327.604704 -346.537119)
			(xy 327.658655 -346.529363) (xy 327.685908 -346.528898) (xy 327.686162 -346.528898) (xy 327.71074 -346.529279)
			(xy 327.759488 -346.535591) (xy 327.807021 -346.548115) (xy 327.85255 -346.566644) (xy 327.874122 -346.578428)
			(xy 327.877678 -346.58046) (xy 327.890311 -346.587424) (xy 327.918208 -346.594704) (xy 327.947029 -346.593901)
			(xy 327.974478 -346.585077) (xy 327.998369 -346.568935) (xy 328.016798 -346.546762) (xy 328.022966 -346.533724)
			(xy 328.033468 -346.506553) (xy 328.061525 -346.455507) (xy 328.097017 -346.409319) (xy 328.139118 -346.369064)
			(xy 328.18685 -346.335679) (xy 328.239103 -346.309938) (xy 328.294662 -346.292441) (xy 328.352235 -346.283594)
			(xy 328.38136 -346.283026) (xy 328.408488 -346.2835) (xy 328.462197 -346.29118) (xy 328.514278 -346.30639)
			(xy 328.563678 -346.328824) (xy 328.609403 -346.358029) (xy 328.650529 -346.393417) (xy 328.686229 -346.434273)
			(xy 328.715781 -346.479775) (xy 328.73859 -346.529003) (xy 328.754195 -346.580966) (xy 328.762283 -346.634616)
			(xy 328.762868 -346.66174) (xy 328.762868 -346.664788) (xy 328.762267 -346.694624) (xy 328.752949 -346.753566)
			(xy 328.744326 -346.782136) (xy 328.74038 -346.796042) (xy 328.739576 -346.824923) (xy 328.74688 -346.852876)
			(xy 328.76171 -346.877672) (xy 328.782881 -346.897332) (xy 328.808706 -346.910288) (xy 328.822812 -346.913454)
			(xy 328.848885 -346.918615) (xy 328.899382 -346.935201) (xy 328.947087 -346.958635) (xy 328.991079 -346.988462)
			(xy 329.030506 -347.024106) (xy 329.064604 -347.064877) (xy 329.092715 -347.109986) (xy 329.114292 -347.158559)
			(xy 329.12892 -347.209657) (xy 329.136315 -347.262291) (xy 329.136756 -347.288866) (xy 329.136273 -347.31612)
			(xy 329.12852 -347.370074) (xy 329.113169 -347.422376) (xy 329.09053 -347.47196) (xy 329.061065 -347.517818)
			(xy 329.025375 -347.559017) (xy 328.984184 -347.594716) (xy 328.938332 -347.624191) (xy 328.888753 -347.64684)
			(xy 328.836454 -347.662203) (xy 328.782502 -347.669967) (xy 328.755248 -347.670374) (xy 328.728124 -347.669894)
			(xy 328.674425 -347.662203) (xy 328.622355 -347.646985) (xy 328.572966 -347.624546) (xy 328.527253 -347.595338)
			(xy 328.486138 -347.559951) (xy 328.450448 -347.519096) (xy 328.420905 -347.473599) (xy 328.398103 -347.424377)
			(xy 328.382502 -347.372421) (xy 328.374417 -347.318779) (xy 328.37374 -347.29166) (xy 328.37374 -347.288612)
			(xy 328.374341 -347.258775) (xy 328.383656 -347.199833) (xy 328.392282 -347.171264) (xy 328.396228 -347.157358)
			(xy 328.397032 -347.128477) (xy 328.389728 -347.100522) (xy 328.374899 -347.075725) (xy 328.353728 -347.056064)
			(xy 328.327903 -347.043107) (xy 328.313796 -347.039946) (xy 328.280958 -347.033356) (xy 328.218104 -347.010239)
			(xy 328.188828 -346.993972) (xy 328.176201 -346.987151) (xy 328.148389 -346.980119) (xy 328.119718 -346.981097)
			(xy 328.092449 -346.990006) (xy 328.068733 -347.006146) (xy 328.050439 -347.028243) (xy 328.044302 -347.041216)
			(xy 328.033016 -347.070321) (xy 328.002354 -347.124692) (xy 327.963251 -347.173347) (xy 327.940416 -347.194632)
			(xy 327.940416 -348.571566) (xy 328.30389 -348.93504) (xy 332.454758 -348.93504) (xy 334.138016 -347.251782)
			(xy 334.138016 -343.89441) (xy 334.138657 -343.869415) (xy 334.148462 -343.820395) (xy 334.167639 -343.774228)
			(xy 334.195452 -343.732688) (xy 334.212692 -343.714578) (xy 334.542384 -343.384886) (xy 335.139284 -342.78824)
			(xy 335.139284 -342.069166) (xy 335.138844 -342.055124) (xy 335.131204 -342.028101) (xy 335.116484 -342.004185)
			(xy 335.095801 -341.985189) (xy 335.070722 -341.972553) (xy 335.043147 -341.967234) (xy 335.015168 -341.969636)
			(xy 335.00187 -341.97417) (xy 334.990948 -341.978996) (xy 334.982312 -341.983822) (xy 334.954155 -341.998411)
			(xy 334.894196 -342.019053) (xy 334.831647 -342.029479) (xy 334.79994 -342.03005) (xy 334.790542 -342.03005)
			(xy 334.763731 -342.028935) (xy 334.7108 -342.020114) (xy 334.659628 -342.003962) (xy 334.611224 -341.980797)
			(xy 334.566545 -341.951078) (xy 334.526471 -341.915391) (xy 334.491795 -341.874439) (xy 334.463199 -341.829032)
			(xy 334.44125 -341.780066) (xy 334.426379 -341.728507) (xy 334.418881 -341.675373) (xy 334.418432 -341.648542)
			(xy 334.41901 -341.61875) (xy 334.42828 -341.559893) (xy 334.446587 -341.503191) (xy 334.473484 -341.450025)
			(xy 334.508319 -341.401685) (xy 334.550244 -341.359348) (xy 334.57388 -341.341202) (xy 334.584325 -341.33271)
			(xy 334.600708 -341.311362) (xy 334.610946 -341.286476) (xy 334.614329 -341.25978) (xy 334.610622 -341.233127)
			(xy 334.600083 -341.208367) (xy 334.583442 -341.187219) (xy 334.572864 -341.178896) (xy 334.549341 -341.160774)
			(xy 334.507672 -341.118471) (xy 334.473061 -341.070223) (xy 334.446343 -341.017195) (xy 334.428163 -340.960668)
			(xy 334.418961 -340.902007) (xy 334.418432 -340.872318) (xy 334.418918 -340.845067) (xy 334.426674 -340.791119)
			(xy 334.442029 -340.738824) (xy 334.464671 -340.689247) (xy 334.494137 -340.643397) (xy 334.529828 -340.602206)
			(xy 334.571019 -340.566515) (xy 334.616869 -340.537049) (xy 334.666446 -340.514407) (xy 334.718741 -340.499052)
			(xy 334.772689 -340.491296) (xy 334.827191 -340.491296) (xy 334.881139 -340.499052) (xy 334.933434 -340.514407)
			(xy 334.983011 -340.537049) (xy 335.028861 -340.566515) (xy 335.070052 -340.602206) (xy 335.105743 -340.643397)
			(xy 335.135209 -340.689247) (xy 335.157851 -340.738824) (xy 335.173206 -340.791119) (xy 335.180962 -340.845067)
			(xy 335.181448 -340.872318) (xy 335.180873 -340.902111) (xy 335.171608 -340.960972) (xy 335.153305 -341.017677)
			(xy 335.12641 -341.070847) (xy 335.091576 -341.11919) (xy 335.04965 -341.16153) (xy 335.026 -341.179658)
			(xy 335.015565 -341.188151) (xy 334.999201 -341.209495) (xy 334.988978 -341.234372) (xy 334.985607 -341.261056)
			(xy 334.989321 -341.287694) (xy 334.999862 -341.312438) (xy 335.016499 -341.33357) (xy 335.027016 -341.341964)
			(xy 335.028794 -341.343234) (xy 335.054448 -341.364316) (xy 335.068926 -341.37727) (xy 335.139284 -341.377016)
			(xy 335.13903 -341.31377) (xy 335.139644 -341.288787) (xy 335.14939 -341.239782) (xy 335.168501 -341.193616)
			(xy 335.196245 -341.152062) (xy 335.213452 -341.133938) (xy 335.372964 -340.974426) (xy 335.467706 -340.879938)
			(xy 335.473445 -340.874281) (xy 335.48552 -340.863607) (xy 335.491836 -340.858602) (xy 335.506853 -340.835346)
			(xy 335.542538 -340.793026) (xy 335.583962 -340.756305) (xy 335.630256 -340.725954) (xy 335.68045 -340.702609)
			(xy 335.733489 -340.68676) (xy 335.788262 -340.67874) (xy 335.81594 -340.678262) (xy 335.82102 -340.678262)
			(xy 335.84617 -340.679015) (xy 335.895951 -340.686323) (xy 335.944341 -340.70011) (xy 335.967578 -340.709758)
			(xy 335.976929 -340.713833) (xy 335.995226 -340.722858) (xy 336.004154 -340.727792) (xy 336.00771 -340.729824)
			(xy 336.02034 -340.736785) (xy 336.048232 -340.744059) (xy 336.077046 -340.74325) (xy 336.104485 -340.734421)
			(xy 336.128364 -340.718276) (xy 336.14678 -340.696101) (xy 336.152998 -340.683088) (xy 336.163501 -340.655917)
			(xy 336.191559 -340.604868) (xy 336.227051 -340.558679) (xy 336.269151 -340.518421) (xy 336.316882 -340.48503)
			(xy 336.369134 -340.459283) (xy 336.424693 -340.441779) (xy 336.482267 -340.432923) (xy 336.511392 -340.43239)
			(xy 336.538517 -340.432866) (xy 336.59222 -340.44055) (xy 336.644292 -340.455764) (xy 336.693685 -340.4782)
			(xy 336.739401 -340.507407) (xy 336.780519 -340.542796) (xy 336.816209 -340.583653) (xy 336.845751 -340.629153)
			(xy 336.86855 -340.678379) (xy 336.884146 -340.730339) (xy 336.892224 -340.783983) (xy 336.8929 -340.811104)
			(xy 336.8929 -340.814152) (xy 336.892302 -340.843989) (xy 336.88299 -340.902933) (xy 336.874358 -340.9315)
			(xy 336.870408 -340.945411) (xy 336.869597 -340.974303) (xy 336.876895 -341.00227) (xy 336.89172 -341.027082)
			(xy 336.91289 -341.046761) (xy 336.938716 -341.059738) (xy 336.952844 -341.062818) (xy 336.978917 -341.067981)
			(xy 337.029412 -341.084569) (xy 337.077117 -341.108004) (xy 337.121108 -341.137832) (xy 337.160534 -341.173476)
			(xy 337.194633 -341.214246) (xy 337.222744 -341.259354) (xy 337.244324 -341.307926) (xy 337.258955 -341.359023)
			(xy 337.266354 -341.411655) (xy 337.266788 -341.43823) (xy 337.2663 -341.465479) (xy 337.25854 -341.519423)
			(xy 337.243182 -341.571713) (xy 337.220539 -341.621285) (xy 337.191071 -341.66713) (xy 337.155379 -341.708315)
			(xy 337.11419 -341.744001) (xy 337.068341 -341.773463) (xy 337.018766 -341.796099) (xy 336.966474 -341.81145)
			(xy 336.912529 -341.819203) (xy 336.88528 -341.819738) (xy 336.858156 -341.81926) (xy 336.804455 -341.811573)
			(xy 336.752384 -341.796357) (xy 336.702993 -341.773919) (xy 336.657278 -341.744712) (xy 336.616162 -341.709324)
			(xy 336.580472 -341.668468) (xy 336.550929 -341.62297) (xy 336.528129 -341.573745) (xy 336.512531 -341.521787)
			(xy 336.50445 -341.468144) (xy 336.503772 -341.441024) (xy 336.503772 -341.437976) (xy 336.504368 -341.408139)
			(xy 336.513675 -341.349193) (xy 336.522314 -341.320628) (xy 336.526269 -341.306716) (xy 336.527087 -341.27782)
			(xy 336.519793 -341.249847) (xy 336.504967 -341.22503) (xy 336.483793 -341.205349) (xy 336.457961 -341.192373)
			(xy 336.443828 -341.18931) (xy 336.411062 -341.181944) (xy 336.387203 -341.17504) (xy 336.34137 -341.1559)
			(xy 336.298403 -341.130982) (xy 336.278474 -341.116158) (xy 336.272378 -341.111332) (xy 336.210148 -341.089488)
			(xy 336.189828 -341.147654) (xy 336.19059 -341.158322) (xy 336.19059 -341.159846) (xy 336.191352 -341.179404)
			(xy 336.191352 -342.499442) (xy 336.678524 -342.98636) (xy 340.769448 -342.98636) (xy 343.290144 -340.465918)
			(xy 343.290144 -338.664296) (xy 343.28971 -338.65067) (xy 343.282508 -338.624387) (xy 343.268619 -338.600941)
			(xy 343.249028 -338.581998) (xy 343.225128 -338.568904) (xy 343.198618 -338.562589) (xy 343.184988 -338.562696)
			(xy 343.173956 -338.563366) (xy 343.152558 -338.568884) (xy 343.14257 -338.573618) (xy 343.114446 -338.588175)
			(xy 343.05457 -338.608784) (xy 342.992114 -338.619228) (xy 342.960452 -338.619846) (xy 342.933202 -338.619357)
			(xy 342.879257 -338.611595) (xy 342.826966 -338.596236) (xy 342.777393 -338.573593) (xy 342.731546 -338.544126)
			(xy 342.690358 -338.508435) (xy 342.654668 -338.467246) (xy 342.625202 -338.421399) (xy 342.60256 -338.371824)
			(xy 342.587203 -338.319533) (xy 342.579442 -338.265588) (xy 342.578944 -338.238338) (xy 342.579522 -338.208547)
			(xy 342.588793 -338.14969) (xy 342.6071 -338.092989) (xy 342.633999 -338.039823) (xy 342.668835 -337.991485)
			(xy 342.710761 -337.949149) (xy 342.734392 -337.930998) (xy 342.744835 -337.922506) (xy 342.761215 -337.901158)
			(xy 342.771452 -337.876272) (xy 342.774833 -337.849578) (xy 342.771126 -337.822926) (xy 342.760588 -337.798167)
			(xy 342.743949 -337.77702) (xy 342.733376 -337.768692) (xy 342.709852 -337.75057) (xy 342.668183 -337.708267)
			(xy 342.633571 -337.66002) (xy 342.606853 -337.606992) (xy 342.588673 -337.550465) (xy 342.579471 -337.491803)
			(xy 342.578944 -337.462114) (xy 342.57943 -337.434863) (xy 342.587186 -337.380915) (xy 342.602541 -337.32862)
			(xy 342.625183 -337.279043) (xy 342.654649 -337.233193) (xy 342.69034 -337.192002) (xy 342.731531 -337.156311)
			(xy 342.777381 -337.126845) (xy 342.826958 -337.104203) (xy 342.879253 -337.088848) (xy 342.933201 -337.081092)
			(xy 342.987703 -337.081092) (xy 343.041651 -337.088848) (xy 343.093946 -337.104203) (xy 343.143523 -337.126845)
			(xy 343.189373 -337.156311) (xy 343.230564 -337.192002) (xy 343.266255 -337.233193) (xy 343.295721 -337.279043)
			(xy 343.318363 -337.32862) (xy 343.333718 -337.380915) (xy 343.341474 -337.434863) (xy 343.34196 -337.462114)
			(xy 343.34196 -337.462368) (xy 343.341466 -337.490138) (xy 343.333413 -337.545092) (xy 343.31746 -337.598292)
			(xy 343.306146 -337.623658) (xy 343.387934 -337.681062) (xy 343.459816 -337.609434) (xy 343.477868 -337.592212)
			(xy 343.519314 -337.564451) (xy 343.542112 -337.554316) (xy 343.615518 -337.523836) (xy 343.623646 -337.504278)
			(xy 343.634831 -337.478433) (xy 343.663692 -337.430076) (xy 343.699348 -337.386487) (xy 343.741026 -337.348614)
			(xy 343.787818 -337.31728) (xy 343.838708 -337.293166) (xy 343.892591 -337.276795) (xy 343.948295 -337.268523)
			(xy 343.976452 -337.268058) (xy 343.982802 -337.268058) (xy 344.00775 -337.268843) (xy 344.057127 -337.276144)
			(xy 344.105126 -337.289833) (xy 344.150926 -337.309676) (xy 344.17254 -337.32216) (xy 344.186558 -337.328994)
			(xy 344.217203 -337.334695) (xy 344.232738 -337.333336) (xy 344.245805 -337.3313) (xy 344.27033 -337.321432)
			(xy 344.291497 -337.305595) (xy 344.307885 -337.284852) (xy 344.31351 -337.272884) (xy 344.324013 -337.245713)
			(xy 344.352072 -337.194667) (xy 344.387564 -337.148478) (xy 344.429665 -337.108222) (xy 344.477396 -337.074833)
			(xy 344.529648 -337.049089) (xy 344.585206 -337.031586) (xy 344.642779 -337.022732) (xy 344.671904 -337.022186)
			(xy 344.699028 -337.022663) (xy 344.75273 -337.030348) (xy 344.804802 -337.045563) (xy 344.854193 -337.068)
			(xy 344.899908 -337.097208) (xy 344.941024 -337.132596) (xy 344.976713 -337.173452) (xy 345.006255 -337.218952)
			(xy 345.016529 -337.241134) (xy 347.15958 -337.241134) (xy 347.160076 -337.213561) (xy 347.168023 -337.158989)
			(xy 347.183743 -337.10613) (xy 347.206907 -337.056085) (xy 347.237034 -337.009894) (xy 347.273496 -336.968521)
			(xy 347.2942 -336.950304) (xy 347.305063 -336.940371) (xy 347.321136 -336.91573) (xy 347.329523 -336.887532)
			(xy 347.32953 -336.858112) (xy 347.321155 -336.82991) (xy 347.305092 -336.805263) (xy 347.2942 -336.795364)
			(xy 347.273468 -336.777175) (xy 347.237 -336.735802) (xy 347.20687 -336.689607) (xy 347.183708 -336.639555)
			(xy 347.167996 -336.586688) (xy 347.160062 -336.53211) (xy 347.15958 -336.504534) (xy 347.160087 -336.477283)
			(xy 347.167839 -336.423334) (xy 347.18319 -336.371037) (xy 347.205828 -336.321458) (xy 347.235291 -336.275606)
			(xy 347.27098 -336.234413) (xy 347.312169 -336.198719) (xy 347.358018 -336.16925) (xy 347.407594 -336.146606)
			(xy 347.459889 -336.131249) (xy 347.513837 -336.12349) (xy 347.541088 -336.123026) (xy 347.541596 -336.123026)
			(xy 347.575378 -336.12455) (xy 347.588737 -336.125329) (xy 347.615099 -336.120819) (xy 347.639377 -336.109598)
			(xy 347.659895 -336.092442) (xy 347.675237 -336.070533) (xy 347.684343 -336.045386) (xy 347.685868 -336.032094)
			(xy 347.688871 -336.003927) (xy 347.702039 -335.948837) (xy 347.723211 -335.896301) (xy 347.751922 -335.847475)
			(xy 347.78754 -335.803434) (xy 347.829282 -335.765146) (xy 347.876228 -335.733455) (xy 347.927346 -335.709058)
			(xy 347.981511 -335.692491) (xy 348.037531 -335.684119) (xy 348.065852 -335.683606) (xy 348.083871 -335.683823)
			(xy 348.119746 -335.68726) (xy 348.13748 -335.690464) (xy 348.152691 -335.692778) (xy 348.183241 -335.689255)
			(xy 348.211358 -335.6768) (xy 348.234494 -335.65654) (xy 348.250551 -335.630313) (xy 348.254828 -335.615534)
			(xy 348.262201 -335.588483) (xy 348.283834 -335.536756) (xy 348.312802 -335.48875) (xy 348.348481 -335.445499)
			(xy 348.390103 -335.407933) (xy 348.436774 -335.37686) (xy 348.487488 -335.352948) (xy 348.541154 -335.336713)
			(xy 348.596618 -335.328504) (xy 348.624652 -335.328006) (xy 348.651904 -335.3285) (xy 348.705855 -335.336251)
			(xy 348.758153 -335.351601) (xy 348.807734 -335.374239) (xy 348.853588 -335.403704) (xy 348.894782 -335.439394)
			(xy 348.930476 -335.480585) (xy 348.959944 -335.526436) (xy 348.982587 -335.576015) (xy 348.983463 -335.579)
			(xy 353.390417 -335.579) (xy 353.394585 -335.523382) (xy 353.406996 -335.469006) (xy 353.427372 -335.417087)
			(xy 353.455258 -335.368785) (xy 353.490031 -335.325178) (xy 353.530916 -335.287241) (xy 353.576997 -335.255821)
			(xy 353.627247 -335.23162) (xy 353.680542 -335.215178) (xy 353.735693 -335.206862) (xy 353.76358 -335.20634)
			(xy 353.790913 -335.206792) (xy 353.844993 -335.214765) (xy 353.897328 -335.230556) (xy 353.946793 -335.253827)
			(xy 353.992325 -335.284078) (xy 354.032946 -335.320659) (xy 354.067785 -335.362784) (xy 354.08235 -335.385918)
			(xy 354.090244 -335.398163) (xy 354.111724 -335.417832) (xy 354.137885 -335.430633) (xy 354.166597 -335.435523)
			(xy 354.195521 -335.432104) (xy 354.209096 -335.426812) (xy 354.23231 -335.417332) (xy 354.280641 -335.403977)
			(xy 354.330329 -335.397245) (xy 354.3554 -335.39684) (xy 354.380469 -335.397275) (xy 354.430152 -335.40402)
			(xy 354.478486 -335.417348) (xy 354.501704 -335.426812) (xy 354.515304 -335.431992) (xy 354.544193 -335.435371)
			(xy 354.572863 -335.430475) (xy 354.598994 -335.417702) (xy 354.620468 -335.398086) (xy 354.62845 -335.385918)
			(xy 354.643019 -335.362787) (xy 354.677862 -335.320666) (xy 354.718485 -335.284087) (xy 354.764016 -335.253836)
			(xy 354.813478 -335.23056) (xy 354.865809 -335.21476) (xy 354.919888 -335.206774) (xy 354.974552 -335.206774)
			(xy 355.028631 -335.21476) (xy 355.080962 -335.23056) (xy 355.130424 -335.253836) (xy 355.175955 -335.284087)
			(xy 355.216578 -335.320666) (xy 355.251421 -335.362787) (xy 355.26599 -335.385918) (xy 355.273941 -335.398122)
			(xy 355.295405 -335.417791) (xy 355.321551 -335.430597) (xy 355.350249 -335.435498) (xy 355.379163 -335.432094)
			(xy 355.392736 -335.426812) (xy 355.415945 -335.41732) (xy 355.464278 -335.403969) (xy 355.513968 -335.397243)
			(xy 355.53904 -335.39684) (xy 355.56588 -335.397387) (xy 355.619004 -335.405082) (xy 355.670475 -335.420321)
			(xy 355.719225 -335.442789) (xy 355.764247 -335.472021) (xy 355.804608 -335.507411) (xy 355.839472 -335.548227)
			(xy 355.868118 -335.593623) (xy 355.889952 -335.642661) (xy 355.897688 -335.668366) (xy 355.902375 -335.682854)
			(xy 355.91889 -335.708414) (xy 355.9422 -335.727978) (xy 355.970239 -335.739808) (xy 356.000517 -335.742857)
			(xy 356.030351 -335.736853) (xy 356.043992 -335.730088) (xy 356.072132 -335.715442) (xy 356.132086 -335.694719)
			(xy 356.194647 -335.684226) (xy 356.226364 -335.683606) (xy 356.244384 -335.683822) (xy 356.280258 -335.687259)
			(xy 356.297992 -335.690464) (xy 356.313202 -335.69279) (xy 356.343753 -335.689265) (xy 356.371871 -335.676806)
			(xy 356.395007 -335.656544) (xy 356.411064 -335.630314) (xy 356.41534 -335.615534) (xy 356.422702 -335.588479)
			(xy 356.444336 -335.536752) (xy 356.473305 -335.488746) (xy 356.508985 -335.445495) (xy 356.550609 -335.407928)
			(xy 356.597281 -335.376856) (xy 356.647996 -335.352945) (xy 356.701664 -335.336711) (xy 356.757129 -335.328503)
			(xy 356.785164 -335.328006) (xy 356.812417 -335.328489) (xy 356.866368 -335.336241) (xy 356.918666 -335.351593)
			(xy 356.968247 -335.374233) (xy 357.014101 -335.403698) (xy 357.055294 -335.43939) (xy 357.090988 -335.480582)
			(xy 357.120457 -335.526434) (xy 357.143099 -335.576013) (xy 357.143976 -335.579) (xy 361.550917 -335.579)
			(xy 361.555086 -335.523381) (xy 361.567497 -335.469004) (xy 361.587873 -335.417084) (xy 361.61576 -335.368781)
			(xy 361.650535 -335.325174) (xy 361.691421 -335.287237) (xy 361.737504 -335.255817) (xy 361.787755 -335.231616)
			(xy 361.841052 -335.215175) (xy 361.896204 -335.206862) (xy 361.924092 -335.20634) (xy 361.951425 -335.206783)
			(xy 362.005506 -335.214757) (xy 362.057841 -335.23055) (xy 362.107306 -335.253822) (xy 362.152838 -335.284075)
			(xy 362.193459 -335.320657) (xy 362.228297 -335.362784) (xy 362.242862 -335.385918) (xy 362.250744 -335.398171)
			(xy 362.272228 -335.417841) (xy 362.298392 -335.43064) (xy 362.327106 -335.435528) (xy 362.356032 -335.432105)
			(xy 362.369608 -335.426812) (xy 362.39282 -335.417328) (xy 362.441152 -335.403975) (xy 362.490841 -335.397244)
			(xy 362.515912 -335.39684) (xy 362.540981 -335.397271) (xy 362.590664 -335.404017) (xy 362.638998 -335.417347)
			(xy 362.662216 -335.426812) (xy 362.675812 -335.432005) (xy 362.704703 -335.435381) (xy 362.733375 -335.430482)
			(xy 362.759506 -335.417706) (xy 362.78098 -335.398087) (xy 362.788962 -335.385918) (xy 362.803531 -335.362787)
			(xy 362.838374 -335.320666) (xy 362.878997 -335.284087) (xy 362.924528 -335.253836) (xy 362.97399 -335.23056)
			(xy 363.026321 -335.21476) (xy 363.0804 -335.206774) (xy 363.135064 -335.206774) (xy 363.189143 -335.21476)
			(xy 363.241474 -335.23056) (xy 363.290936 -335.253836) (xy 363.336467 -335.284087) (xy 363.37709 -335.320666)
			(xy 363.411933 -335.362787) (xy 363.426502 -335.385918) (xy 363.434441 -335.39813) (xy 363.455909 -335.417799)
			(xy 363.482058 -335.430604) (xy 363.510759 -335.435503) (xy 363.539675 -335.432096) (xy 363.553248 -335.426812)
			(xy 363.576455 -335.417316) (xy 363.624789 -335.403967) (xy 363.67448 -335.397242) (xy 363.699552 -335.39684)
			(xy 363.726392 -335.397376) (xy 363.779517 -335.405073) (xy 363.830988 -335.420314) (xy 363.879739 -335.442783)
			(xy 363.92476 -335.472016) (xy 363.965121 -335.507407) (xy 363.999985 -335.548224) (xy 364.02863 -335.593622)
			(xy 364.050464 -335.642661) (xy 364.0582 -335.668366) (xy 364.062871 -335.68286) (xy 364.079389 -335.708422)
			(xy 364.102703 -335.727986) (xy 364.130744 -335.739816) (xy 364.161026 -335.742862) (xy 364.190862 -335.736855)
			(xy 364.204504 -335.730088) (xy 364.232659 -335.715474) (xy 364.292606 -335.69474) (xy 364.35516 -335.684233)
			(xy 364.386876 -335.683606) (xy 364.404896 -335.68382) (xy 364.44077 -335.687259) (xy 364.458504 -335.690464)
			(xy 364.473713 -335.692802) (xy 364.504265 -335.689273) (xy 364.532384 -335.676812) (xy 364.555519 -335.656547)
			(xy 364.571576 -335.630315) (xy 364.575852 -335.615534) (xy 364.583203 -335.588476) (xy 364.604838 -335.536748)
			(xy 364.633808 -335.488742) (xy 364.66949 -335.44549) (xy 364.711115 -335.407924) (xy 364.757788 -335.376851)
			(xy 364.808505 -335.352942) (xy 364.862174 -335.336709) (xy 364.917641 -335.328502) (xy 364.945676 -335.328006)
			(xy 364.972929 -335.328478) (xy 365.02688 -335.336232) (xy 365.079179 -335.351585) (xy 365.12876 -335.374226)
			(xy 365.174614 -335.403693) (xy 365.215807 -335.439386) (xy 365.251501 -335.480578) (xy 365.280969 -335.526431)
			(xy 365.303611 -335.576012) (xy 365.318966 -335.62831) (xy 365.326722 -335.682261) (xy 365.327184 -335.709514)
			(xy 365.326665 -335.737087) (xy 365.318724 -335.791657) (xy 365.30301 -335.844517) (xy 365.27985 -335.894563)
			(xy 365.249727 -335.940754) (xy 365.213267 -335.982127) (xy 365.192564 -336.000344) (xy 365.181647 -336.010225)
			(xy 365.165566 -336.034878) (xy 365.157178 -336.063092) (xy 365.157181 -336.092526) (xy 365.165573 -336.120739)
			(xy 365.181659 -336.145388) (xy 365.192564 -336.155284) (xy 365.213285 -336.173484) (xy 365.249752 -336.214856)
			(xy 365.279881 -336.261047) (xy 365.303045 -336.311096) (xy 365.318761 -336.363959) (xy 365.326701 -336.418534)
			(xy 365.326699 -336.473684) (xy 365.318757 -336.528258) (xy 365.303039 -336.581121) (xy 365.279872 -336.631168)
			(xy 365.249741 -336.677359) (xy 365.213272 -336.718729) (xy 365.192564 -336.736944) (xy 365.181647 -336.746825)
			(xy 365.165566 -336.771478) (xy 365.157178 -336.799692) (xy 365.157181 -336.829126) (xy 365.165573 -336.857339)
			(xy 365.181659 -336.881988) (xy 365.192564 -336.891884) (xy 365.213263 -336.910108) (xy 365.249736 -336.951473)
			(xy 365.279871 -336.99766) (xy 365.303039 -337.047706) (xy 365.318757 -337.100566) (xy 365.326698 -337.15514)
			(xy 365.327184 -337.182714) (xy 365.326758 -337.209968) (xy 365.318999 -337.263922) (xy 365.312332 -337.286625)
			(xy 365.717275 -337.286625) (xy 365.717279 -337.232123) (xy 365.725039 -337.178175) (xy 365.740398 -337.125881)
			(xy 365.763043 -337.076305) (xy 365.792513 -337.030457) (xy 365.828207 -336.989269) (xy 365.8694 -336.95358)
			(xy 365.915253 -336.924117) (xy 365.964832 -336.901479) (xy 366.017128 -336.886128) (xy 366.071077 -336.878375)
			(xy 366.098328 -336.877914) (xy 366.113057 -336.878063) (xy 366.142427 -336.880351) (xy 366.157002 -336.882486)
			(xy 366.171557 -336.88423) (xy 366.200601 -336.880377) (xy 366.227353 -336.86843) (xy 366.249607 -336.849374)
			(xy 366.265529 -336.82478) (xy 366.273806 -336.796675) (xy 366.273755 -336.767376) (xy 366.270032 -336.7532)
			(xy 366.262676 -336.726691) (xy 366.254769 -336.672249) (xy 366.254284 -336.644742) (xy 366.25471 -336.617485)
			(xy 366.262462 -336.563526) (xy 366.277815 -336.511219) (xy 366.300456 -336.46163) (xy 366.329924 -336.415768)
			(xy 366.365619 -336.374566) (xy 366.406814 -336.338864) (xy 366.452671 -336.309388) (xy 366.502256 -336.286739)
			(xy 366.55456 -336.271377) (xy 366.608518 -336.263615) (xy 366.663031 -336.263611) (xy 366.71699 -336.271366)
			(xy 366.769296 -336.286721) (xy 366.818885 -336.309364) (xy 366.864745 -336.338834) (xy 366.905946 -336.37453)
			(xy 366.941646 -336.415727) (xy 366.97112 -336.461586) (xy 366.993767 -336.511172) (xy 367.009127 -336.563476)
			(xy 367.016886 -336.617435) (xy 367.016888 -336.671948) (xy 367.009131 -336.725907) (xy 366.993773 -336.778212)
			(xy 366.971128 -336.827799) (xy 366.941656 -336.873659) (xy 366.905958 -336.914857) (xy 366.864759 -336.950556)
			(xy 366.8189 -336.980028) (xy 366.769313 -337.002673) (xy 366.717007 -337.01803) (xy 366.663049 -337.025788)
			(xy 366.635792 -337.02625) (xy 366.621063 -337.026099) (xy 366.591693 -337.023813) (xy 366.577118 -337.021678)
			(xy 366.562577 -337.019774) (xy 366.533512 -337.023648) (xy 366.506747 -337.03562) (xy 366.484486 -337.054704)
			(xy 366.468564 -337.079326) (xy 366.460293 -337.107457) (xy 366.460356 -337.136778) (xy 366.464088 -337.150964)
			(xy 366.471458 -337.17747) (xy 366.479357 -337.231915) (xy 366.479836 -337.259422) (xy 366.479321 -337.286673)
			(xy 366.471561 -337.340621) (xy 366.456203 -337.392915) (xy 366.433559 -337.442491) (xy 366.40409 -337.48834)
			(xy 366.368396 -337.529528) (xy 366.327203 -337.565217) (xy 366.281351 -337.594681) (xy 366.231772 -337.617319)
			(xy 366.179476 -337.632671) (xy 366.125527 -337.640424) (xy 366.071025 -337.640421) (xy 366.017077 -337.632661)
			(xy 365.964783 -337.617302) (xy 365.915207 -337.594658) (xy 365.869358 -337.565189) (xy 365.82817 -337.529494)
			(xy 365.792481 -337.488301) (xy 365.763018 -337.442449) (xy 365.74038 -337.39287) (xy 365.725028 -337.340574)
			(xy 365.717275 -337.286625) (xy 365.312332 -337.286625) (xy 365.30364 -337.316222) (xy 365.280994 -337.365804)
			(xy 365.251522 -337.411658) (xy 365.215824 -337.452851) (xy 365.174628 -337.488545) (xy 365.12877 -337.518012)
			(xy 365.079186 -337.540653) (xy 365.026885 -337.556007) (xy 364.97293 -337.563761) (xy 364.945676 -337.564222)
			(xy 364.917821 -337.563704) (xy 364.862706 -337.555578) (xy 364.809356 -337.53953) (xy 364.758904 -337.515902)
			(xy 364.71242 -337.485194) (xy 364.670891 -337.448059) (xy 364.635198 -337.405284) (xy 364.606098 -337.357777)
			(xy 364.584209 -337.306547) (xy 364.576614 -337.279742) (xy 364.572272 -337.26565) (xy 364.556899 -337.240508)
			(xy 364.534998 -337.22079) (xy 364.508385 -337.208132) (xy 364.479268 -337.203584) (xy 364.4646 -337.205066)
			(xy 364.451583 -337.206734) (xy 364.425399 -337.208514) (xy 364.412276 -337.208622) (xy 364.398127 -337.208531)
			(xy 364.369904 -337.206495) (xy 364.355888 -337.204558) (xy 364.342533 -337.203057) (xy 364.315853 -337.206144)
			(xy 364.290907 -337.216099) (xy 364.26943 -337.232227) (xy 364.252916 -337.253409) (xy 364.242512 -337.278171)
			(xy 364.240318 -337.291426) (xy 364.236214 -337.318577) (xy 364.221244 -337.371407) (xy 364.198855 -337.421545)
			(xy 364.169509 -337.467956) (xy 364.133814 -337.509681) (xy 364.092506 -337.545858) (xy 364.046438 -337.57574)
			(xy 363.996563 -337.598709) (xy 363.94391 -337.614291) (xy 363.889567 -337.622164) (xy 363.862112 -337.622642)
			(xy 363.834863 -337.622111) (xy 363.780918 -337.614357) (xy 363.728627 -337.599005) (xy 363.679052 -337.576368)
			(xy 363.633203 -337.546906) (xy 363.592014 -337.511219) (xy 363.556322 -337.470034) (xy 363.526855 -337.424189)
			(xy 363.504211 -337.374617) (xy 363.488853 -337.322327) (xy 363.481093 -337.268383) (xy 363.480604 -337.241134)
			(xy 363.481092 -337.21356) (xy 363.48904 -337.158988) (xy 363.50476 -337.106129) (xy 363.527926 -337.056083)
			(xy 363.558055 -337.009893) (xy 363.594519 -336.96852) (xy 363.615224 -336.950304) (xy 363.626084 -336.940369)
			(xy 363.642154 -336.915728) (xy 363.650539 -336.887531) (xy 363.650546 -336.858113) (xy 363.642173 -336.829912)
			(xy 363.626114 -336.805264) (xy 363.615224 -336.795364) (xy 363.594497 -336.77717) (xy 363.558027 -336.735798)
			(xy 363.527896 -336.689605) (xy 363.504733 -336.639553) (xy 363.48902 -336.586688) (xy 363.481086 -336.53211)
			(xy 363.480604 -336.504534) (xy 363.481038 -336.478032) (xy 363.488387 -336.42554) (xy 363.502936 -336.374572)
			(xy 363.524404 -336.32611) (xy 363.552377 -336.281088) (xy 363.568996 -336.26044) (xy 363.578467 -336.248313)
			(xy 363.590263 -336.219907) (xy 363.593087 -336.189278) (xy 363.586685 -336.159193) (xy 363.571635 -336.132369)
			(xy 363.549295 -336.111226) (xy 363.535722 -336.103976) (xy 363.512025 -336.091888) (xy 363.468045 -336.061961)
			(xy 363.428765 -336.026086) (xy 363.394984 -335.984992) (xy 363.380782 -335.962498) (xy 363.372854 -335.950277)
			(xy 363.351384 -335.930606) (xy 363.325232 -335.917801) (xy 363.296528 -335.912905) (xy 363.26761 -335.916317)
			(xy 363.254036 -335.921604) (xy 363.230819 -335.931075) (xy 363.18249 -335.944433) (xy 363.132803 -335.951169)
			(xy 363.107732 -335.951576) (xy 363.082662 -335.951162) (xy 363.032979 -335.944408) (xy 362.984645 -335.931072)
			(xy 362.961428 -335.921604) (xy 362.947855 -335.916345) (xy 362.918952 -335.912981) (xy 362.890271 -335.917894)
			(xy 362.864136 -335.930686) (xy 362.842662 -335.950321) (xy 362.834682 -335.962498) (xy 362.820113 -335.985629)
			(xy 362.78527 -336.02775) (xy 362.744647 -336.064329) (xy 362.699116 -336.09458) (xy 362.649654 -336.117856)
			(xy 362.597323 -336.133656) (xy 362.543244 -336.141642) (xy 362.48858 -336.141642) (xy 362.434501 -336.133656)
			(xy 362.38217 -336.117856) (xy 362.332708 -336.09458) (xy 362.287177 -336.064329) (xy 362.246554 -336.02775)
			(xy 362.211711 -335.985629) (xy 362.197142 -335.962498) (xy 362.189252 -335.95025) (xy 362.167772 -335.930579)
			(xy 362.141609 -335.917777) (xy 362.112896 -335.912888) (xy 362.083971 -335.916311) (xy 362.070396 -335.921604)
			(xy 362.047184 -335.931087) (xy 361.998852 -335.944441) (xy 361.949163 -335.951171) (xy 361.924092 -335.951576)
			(xy 361.896204 -335.951138) (xy 361.841052 -335.942825) (xy 361.787755 -335.926384) (xy 361.737504 -335.902183)
			(xy 361.691421 -335.870763) (xy 361.650535 -335.832826) (xy 361.61576 -335.789219) (xy 361.587873 -335.740916)
			(xy 361.567497 -335.688996) (xy 361.555086 -335.634619) (xy 361.550917 -335.579) (xy 357.143976 -335.579)
			(xy 357.158454 -335.628311) (xy 357.16621 -335.682261) (xy 357.166672 -335.709514) (xy 357.166157 -335.737087)
			(xy 357.158216 -335.791658) (xy 357.142501 -335.844517) (xy 357.119341 -335.894564) (xy 357.089216 -335.940755)
			(xy 357.052756 -335.982127) (xy 357.032052 -336.000344) (xy 357.021136 -336.010226) (xy 357.005057 -336.034879)
			(xy 356.99667 -336.063092) (xy 356.996673 -336.092526) (xy 357.005064 -336.120738) (xy 357.021148 -336.145388)
			(xy 357.032052 -336.155284) (xy 357.052774 -336.173483) (xy 357.089241 -336.214855) (xy 357.119372 -336.261047)
			(xy 357.142536 -336.311096) (xy 357.158253 -336.363959) (xy 357.166193 -336.418534) (xy 357.166192 -336.473684)
			(xy 357.158249 -336.528259) (xy 357.14253 -336.581121) (xy 357.119363 -336.631169) (xy 357.08923 -336.67736)
			(xy 357.052761 -336.718729) (xy 357.032052 -336.736944) (xy 357.021136 -336.746826) (xy 357.005057 -336.771479)
			(xy 356.99667 -336.799692) (xy 356.996673 -336.829126) (xy 357.005064 -336.857338) (xy 357.021148 -336.881988)
			(xy 357.032052 -336.891884) (xy 357.052749 -336.910111) (xy 357.089222 -336.951475) (xy 357.119358 -336.997661)
			(xy 357.142526 -337.047706) (xy 357.158245 -337.100567) (xy 357.166186 -337.15514) (xy 357.166672 -337.182714)
			(xy 357.166258 -337.209969) (xy 357.160641 -337.249022) (xy 357.497106 -337.249022) (xy 357.49711 -337.194524)
			(xy 357.50487 -337.140581) (xy 357.520227 -337.088292) (xy 357.54287 -337.03872) (xy 357.572337 -336.992875)
			(xy 357.608029 -336.951691) (xy 357.649218 -336.916005) (xy 357.695067 -336.886545) (xy 357.744642 -336.863909)
			(xy 357.796933 -336.848559) (xy 357.850877 -336.840806) (xy 357.878126 -336.840322) (xy 357.903517 -336.840764)
			(xy 357.953848 -336.847513) (xy 357.978456 -336.853784) (xy 357.993101 -336.857224) (xy 358.023156 -336.856294)
			(xy 358.051639 -336.846659) (xy 358.076088 -336.829153) (xy 358.094384 -336.805291) (xy 358.104946 -336.777137)
			(xy 358.106859 -336.747129) (xy 358.103932 -336.732372) (xy 358.099173 -336.710842) (xy 358.094083 -336.667043)
			(xy 358.093772 -336.644996) (xy 358.093772 -336.644742) (xy 358.09421 -336.617485) (xy 358.101962 -336.563526)
			(xy 358.117315 -336.511219) (xy 358.139957 -336.461629) (xy 358.169425 -336.415767) (xy 358.20512 -336.374565)
			(xy 358.246316 -336.338863) (xy 358.292173 -336.309387) (xy 358.341759 -336.286738) (xy 358.394064 -336.271376)
			(xy 358.448022 -336.263615) (xy 358.502536 -336.263611) (xy 358.556495 -336.271367) (xy 358.608801 -336.286723)
			(xy 358.658389 -336.309366) (xy 358.70425 -336.338837) (xy 358.74545 -336.374535) (xy 358.78115 -336.415732)
			(xy 358.810623 -336.461592) (xy 358.83327 -336.511179) (xy 358.848628 -336.563484) (xy 358.856387 -336.617443)
			(xy 358.856387 -336.671956) (xy 358.848629 -336.725915) (xy 358.83327 -336.77822) (xy 358.810624 -336.827807)
			(xy 358.781151 -336.873667) (xy 358.745451 -336.914864) (xy 358.704251 -336.950562) (xy 358.65839 -336.980033)
			(xy 358.608802 -337.002677) (xy 358.556496 -337.018033) (xy 358.502537 -337.025788) (xy 358.47528 -337.02625)
			(xy 358.449889 -337.025807) (xy 358.399558 -337.019059) (xy 358.37495 -337.012788) (xy 358.360298 -337.009388)
			(xy 358.330251 -337.010317) (xy 358.301774 -337.019948) (xy 358.27733 -337.037447) (xy 358.259034 -337.061301)
			(xy 358.24847 -337.089446) (xy 358.246551 -337.119446) (xy 358.249474 -337.1342) (xy 358.254228 -337.155731)
			(xy 358.259321 -337.199529) (xy 358.259634 -337.221576) (xy 358.259634 -337.22183) (xy 358.25909 -337.249079)
			(xy 358.25133 -337.303022) (xy 358.235972 -337.355311) (xy 358.213328 -337.404882) (xy 358.183861 -337.450727)
			(xy 358.148169 -337.491911) (xy 358.10698 -337.527596) (xy 358.061131 -337.557057) (xy 358.011556 -337.579692)
			(xy 357.959264 -337.595042) (xy 357.90532 -337.602794) (xy 357.850822 -337.60279) (xy 357.79688 -337.59503)
			(xy 357.74459 -337.579672) (xy 357.695019 -337.557029) (xy 357.649174 -337.527562) (xy 357.60799 -337.49187)
			(xy 357.572305 -337.450681) (xy 357.542844 -337.404832) (xy 357.520208 -337.355257) (xy 357.504858 -337.302966)
			(xy 357.497106 -337.249022) (xy 357.160641 -337.249022) (xy 357.158498 -337.263923) (xy 357.143139 -337.316225)
			(xy 357.120492 -337.365807) (xy 357.091019 -337.411662) (xy 357.05532 -337.452855) (xy 357.014122 -337.488549)
			(xy 356.968263 -337.518016) (xy 356.918678 -337.540656) (xy 356.866375 -337.556009) (xy 356.812419 -337.563762)
			(xy 356.785164 -337.564222) (xy 356.757309 -337.563715) (xy 356.702193 -337.555587) (xy 356.648843 -337.539538)
			(xy 356.598391 -337.515908) (xy 356.551907 -337.485199) (xy 356.510378 -337.448062) (xy 356.474685 -337.405286)
			(xy 356.445586 -337.357779) (xy 356.423697 -337.306547) (xy 356.416102 -337.279742) (xy 356.411772 -337.265645)
			(xy 356.396397 -337.240502) (xy 356.374492 -337.220784) (xy 356.347876 -337.208128) (xy 356.318757 -337.203582)
			(xy 356.304088 -337.205066) (xy 356.291071 -337.206735) (xy 356.264887 -337.208515) (xy 356.251764 -337.208622)
			(xy 356.237615 -337.208532) (xy 356.209392 -337.206495) (xy 356.195376 -337.204558) (xy 356.182023 -337.203045)
			(xy 356.155341 -337.206135) (xy 356.130394 -337.216092) (xy 356.108917 -337.232223) (xy 356.092403 -337.253406)
			(xy 356.082 -337.27817) (xy 356.079806 -337.291426) (xy 356.075714 -337.318579) (xy 356.060743 -337.37141)
			(xy 356.038353 -337.421549) (xy 356.009006 -337.46796) (xy 355.973309 -337.509686) (xy 355.932 -337.545862)
			(xy 355.885931 -337.575744) (xy 355.836054 -337.598712) (xy 355.7834 -337.614293) (xy 355.729056 -337.622165)
			(xy 355.7016 -337.622642) (xy 355.67435 -337.622122) (xy 355.620406 -337.614367) (xy 355.568114 -337.599013)
			(xy 355.518539 -337.576375) (xy 355.47269 -337.546911) (xy 355.4315 -337.511224) (xy 355.395809 -337.470037)
			(xy 355.366342 -337.424191) (xy 355.343699 -337.374618) (xy 355.328341 -337.322328) (xy 355.32058 -337.268384)
			(xy 355.320092 -337.241134) (xy 355.320584 -337.21356) (xy 355.328531 -337.158989) (xy 355.344252 -337.10613)
			(xy 355.367417 -337.056084) (xy 355.397544 -337.009893) (xy 355.434007 -336.968521) (xy 355.454712 -336.950304)
			(xy 355.465574 -336.94037) (xy 355.481645 -336.915729) (xy 355.490031 -336.887531) (xy 355.490038 -336.858113)
			(xy 355.481664 -336.829911) (xy 355.465603 -336.805263) (xy 355.454712 -336.795364) (xy 355.433983 -336.777173)
			(xy 355.397513 -336.7358) (xy 355.367383 -336.689606) (xy 355.34422 -336.639554) (xy 355.328508 -336.586688)
			(xy 355.320574 -336.53211) (xy 355.320092 -336.504534) (xy 355.320528 -336.478032) (xy 355.327878 -336.425541)
			(xy 355.342426 -336.374573) (xy 355.363893 -336.326111) (xy 355.391865 -336.281089) (xy 355.408484 -336.26044)
			(xy 355.417925 -336.248295) (xy 355.429707 -336.219894) (xy 355.432526 -336.189276) (xy 355.42613 -336.159201)
			(xy 355.411094 -336.13238) (xy 355.388774 -336.111232) (xy 355.37521 -336.103976) (xy 355.351511 -336.091892)
			(xy 355.307531 -336.061963) (xy 355.268253 -336.026087) (xy 355.234472 -335.984992) (xy 355.22027 -335.962498)
			(xy 355.212354 -335.950269) (xy 355.19088 -335.930598) (xy 355.164725 -335.917794) (xy 355.136018 -335.9129)
			(xy 355.107098 -335.916315) (xy 355.093524 -335.921604) (xy 355.070308 -335.931079) (xy 355.021978 -335.944435)
			(xy 354.972291 -335.951169) (xy 354.94722 -335.951576) (xy 354.922151 -335.951133) (xy 354.872469 -335.944392)
			(xy 354.824134 -335.931066) (xy 354.800916 -335.921604) (xy 354.787324 -335.916389) (xy 354.758423 -335.913003)
			(xy 354.729739 -335.917897) (xy 354.703596 -335.930674) (xy 354.682112 -335.950299) (xy 354.67417 -335.962498)
			(xy 354.659601 -335.985629) (xy 354.624758 -336.02775) (xy 354.584135 -336.064329) (xy 354.538604 -336.09458)
			(xy 354.489142 -336.117856) (xy 354.436811 -336.133656) (xy 354.382732 -336.141642) (xy 354.328068 -336.141642)
			(xy 354.273989 -336.133656) (xy 354.221658 -336.117856) (xy 354.172196 -336.09458) (xy 354.126665 -336.064329)
			(xy 354.086042 -336.02775) (xy 354.051199 -335.985629) (xy 354.03663 -335.962498) (xy 354.028751 -335.950242)
			(xy 354.007268 -335.93057) (xy 353.981103 -335.91777) (xy 353.952387 -335.912884) (xy 353.92346 -335.916309)
			(xy 353.909884 -335.921604) (xy 353.886673 -335.931091) (xy 353.838341 -335.944443) (xy 353.788652 -335.951172)
			(xy 353.76358 -335.951576) (xy 353.735693 -335.951138) (xy 353.680542 -335.942822) (xy 353.627247 -335.92638)
			(xy 353.576997 -335.902179) (xy 353.530916 -335.870759) (xy 353.490031 -335.832822) (xy 353.455258 -335.789215)
			(xy 353.427372 -335.740913) (xy 353.406996 -335.688994) (xy 353.394585 -335.634618) (xy 353.390417 -335.579)
			(xy 348.983463 -335.579) (xy 348.997942 -335.628312) (xy 349.005698 -335.682262) (xy 349.00616 -335.709514)
			(xy 349.005649 -335.737087) (xy 348.997708 -335.791659) (xy 348.981993 -335.844518) (xy 348.958831 -335.894565)
			(xy 348.928706 -335.940755) (xy 348.892245 -335.982128) (xy 348.87154 -336.000344) (xy 348.860626 -336.010227)
			(xy 348.844548 -336.03488) (xy 348.836162 -336.063093) (xy 348.836165 -336.092525) (xy 348.844555 -336.120737)
			(xy 348.860638 -336.145387) (xy 348.87154 -336.155284) (xy 348.892262 -336.173483) (xy 348.928731 -336.214854)
			(xy 348.958862 -336.261046) (xy 348.982028 -336.311095) (xy 348.997745 -336.363958) (xy 349.005685 -336.418534)
			(xy 349.005684 -336.473684) (xy 348.997741 -336.52826) (xy 348.982021 -336.581122) (xy 348.958854 -336.63117)
			(xy 348.92872 -336.67736) (xy 348.892249 -336.71873) (xy 348.87154 -336.736944) (xy 348.860626 -336.746827)
			(xy 348.844548 -336.77148) (xy 348.836162 -336.799693) (xy 348.836165 -336.829125) (xy 348.844555 -336.857337)
			(xy 348.860638 -336.881987) (xy 348.87154 -336.891884) (xy 348.892255 -336.910091) (xy 348.928723 -336.951462)
			(xy 348.958854 -336.997653) (xy 348.982018 -337.047701) (xy 348.997735 -337.100564) (xy 349.005674 -337.155139)
			(xy 349.00616 -337.182714) (xy 349.005954 -337.196688) (xy 349.431337 -337.196688) (xy 349.439088 -337.142734)
			(xy 349.454439 -337.090433) (xy 349.477077 -337.040848) (xy 349.506541 -336.99499) (xy 349.542231 -336.953792)
			(xy 349.583421 -336.918092) (xy 349.629273 -336.888618) (xy 349.678852 -336.865969) (xy 349.73115 -336.850606)
			(xy 349.785102 -336.842843) (xy 349.812356 -336.842354) (xy 349.83547 -336.843116) (xy 349.848795 -336.843542)
			(xy 349.874897 -336.838144) (xy 349.898719 -336.826187) (xy 349.918644 -336.808483) (xy 349.933321 -336.786233)
			(xy 349.941752 -336.760947) (xy 349.943367 -336.734342) (xy 349.941134 -336.721196) (xy 349.937481 -336.702293)
			(xy 349.933539 -336.663993) (xy 349.93326 -336.644742) (xy 349.93371 -336.617485) (xy 349.941463 -336.563525)
			(xy 349.956816 -336.511218) (xy 349.979457 -336.461628) (xy 350.008926 -336.415765) (xy 350.044621 -336.374563)
			(xy 350.085818 -336.338861) (xy 350.131676 -336.309386) (xy 350.181262 -336.286737) (xy 350.233567 -336.271375)
			(xy 350.287526 -336.263614) (xy 350.34204 -336.263612) (xy 350.395999 -336.271368) (xy 350.448305 -336.286724)
			(xy 350.497894 -336.309369) (xy 350.543755 -336.33884) (xy 350.584954 -336.374539) (xy 350.620654 -336.415737)
			(xy 350.650126 -336.461597) (xy 350.672772 -336.511185) (xy 350.68813 -336.563491) (xy 350.695887 -336.61745)
			(xy 350.695886 -336.671964) (xy 350.688127 -336.725923) (xy 350.672767 -336.778229) (xy 350.650119 -336.827815)
			(xy 350.620645 -336.873674) (xy 350.584944 -336.914871) (xy 350.543743 -336.950568) (xy 350.497881 -336.980038)
			(xy 350.448292 -337.002681) (xy 350.395985 -337.018035) (xy 350.342025 -337.025789) (xy 350.314768 -337.02625)
			(xy 350.291654 -337.025488) (xy 350.278329 -337.025079) (xy 350.252227 -337.030472) (xy 350.228404 -337.042425)
			(xy 350.208478 -337.060126) (xy 350.193801 -337.082374) (xy 350.18537 -337.107659) (xy 350.183757 -337.134263)
			(xy 350.18599 -337.147408) (xy 350.189644 -337.166311) (xy 350.193585 -337.204611) (xy 350.193864 -337.223862)
			(xy 350.193463 -337.251116) (xy 350.185711 -337.30507) (xy 350.17036 -337.357371) (xy 350.147721 -337.406955)
			(xy 350.118257 -337.452813) (xy 350.082566 -337.494011) (xy 350.041376 -337.52971) (xy 349.995524 -337.559184)
			(xy 349.945944 -337.581832) (xy 349.893646 -337.597194) (xy 349.839694 -337.604957) (xy 349.785186 -337.604963)
			(xy 349.731232 -337.597211) (xy 349.678931 -337.58186) (xy 349.629347 -337.559222) (xy 349.583489 -337.529758)
			(xy 349.542291 -337.494068) (xy 349.506591 -337.452877) (xy 349.477117 -337.407026) (xy 349.454468 -337.357446)
			(xy 349.439106 -337.305148) (xy 349.431343 -337.251196) (xy 349.431337 -337.196688) (xy 349.005954 -337.196688)
			(xy 349.005758 -337.209969) (xy 348.997998 -337.263925) (xy 348.982638 -337.316227) (xy 348.95999 -337.365811)
			(xy 348.930516 -337.411666) (xy 348.894816 -337.45286) (xy 348.853616 -337.488553) (xy 348.807756 -337.51802)
			(xy 348.758169 -337.540659) (xy 348.705864 -337.556011) (xy 348.651907 -337.563762) (xy 348.624652 -337.564222)
			(xy 348.596796 -337.563726) (xy 348.54168 -337.555596) (xy 348.48833 -337.539545) (xy 348.437878 -337.515914)
			(xy 348.391394 -337.485204) (xy 348.349865 -337.448066) (xy 348.314173 -337.405289) (xy 348.285073 -337.35778)
			(xy 348.263185 -337.306548) (xy 348.25559 -337.279742) (xy 348.251272 -337.265641) (xy 348.235894 -337.240497)
			(xy 348.213987 -337.220779) (xy 348.187368 -337.208124) (xy 348.158246 -337.203581) (xy 348.143576 -337.205066)
			(xy 348.13056 -337.206736) (xy 348.104375 -337.208515) (xy 348.091252 -337.208622) (xy 348.077103 -337.208522)
			(xy 348.04888 -337.206492) (xy 348.034864 -337.204558) (xy 348.021512 -337.203033) (xy 347.994829 -337.206126)
			(xy 347.969882 -337.216085) (xy 347.948405 -337.232218) (xy 347.931891 -337.253404) (xy 347.921488 -337.278169)
			(xy 347.919294 -337.291426) (xy 347.915213 -337.318581) (xy 347.900242 -337.371413) (xy 347.877851 -337.421553)
			(xy 347.848503 -337.467965) (xy 347.812805 -337.50969) (xy 347.771494 -337.545867) (xy 347.725423 -337.575748)
			(xy 347.675545 -337.598715) (xy 347.622889 -337.614295) (xy 347.568544 -337.622166) (xy 347.541088 -337.622642)
			(xy 347.513838 -337.622133) (xy 347.459893 -337.614376) (xy 347.407601 -337.599021) (xy 347.358026 -337.576381)
			(xy 347.312177 -337.546917) (xy 347.270988 -337.511228) (xy 347.235296 -337.470041) (xy 347.205829 -337.424194)
			(xy 347.183186 -337.37462) (xy 347.167828 -337.322329) (xy 347.160068 -337.268384) (xy 347.15958 -337.241134)
			(xy 345.016529 -337.241134) (xy 345.029054 -337.268177) (xy 345.04465 -337.320136) (xy 345.052728 -337.37378)
			(xy 345.053412 -337.4009) (xy 345.053412 -337.403948) (xy 345.052814 -337.433785) (xy 345.043503 -337.492729)
			(xy 345.03487 -337.521296) (xy 345.030919 -337.535206) (xy 345.030107 -337.564099) (xy 345.037405 -337.592066)
			(xy 345.05223 -337.616879) (xy 345.073401 -337.636557) (xy 345.099229 -337.649532) (xy 345.113356 -337.652614)
			(xy 345.139428 -337.657777) (xy 345.189922 -337.674367) (xy 345.237626 -337.697802) (xy 345.281616 -337.727631)
			(xy 345.321041 -337.763275) (xy 345.355139 -337.804045) (xy 345.38325 -337.849152) (xy 345.404829 -337.897724)
			(xy 345.41946 -337.94882) (xy 345.42686 -338.001451) (xy 345.4273 -338.028026) (xy 345.426812 -338.055276)
			(xy 345.419053 -338.10922) (xy 345.403695 -338.161512) (xy 345.381053 -338.211085) (xy 345.351586 -338.256932)
			(xy 345.315894 -338.298118) (xy 345.274704 -338.333806) (xy 345.228855 -338.363269) (xy 345.17928 -338.385907)
			(xy 345.126987 -338.40126) (xy 345.073042 -338.409015) (xy 345.045792 -338.409534) (xy 345.018667 -338.409057)
			(xy 344.964965 -338.401371) (xy 344.912893 -338.386157) (xy 344.863501 -338.363719) (xy 344.817785 -338.334512)
			(xy 344.776667 -338.299124) (xy 344.740977 -338.258268) (xy 344.711433 -338.212769) (xy 344.688633 -338.163543)
			(xy 344.673035 -338.111585) (xy 344.664954 -338.057941) (xy 344.664284 -338.03082) (xy 344.664284 -338.027772)
			(xy 344.66488 -337.997935) (xy 344.674188 -337.93899) (xy 344.682826 -337.910424) (xy 344.68678 -337.896512)
			(xy 344.687597 -337.867616) (xy 344.680302 -337.839644) (xy 344.665477 -337.814826) (xy 344.644305 -337.795144)
			(xy 344.618473 -337.782167) (xy 344.60434 -337.779106) (xy 344.571504 -337.772513) (xy 344.508653 -337.749391)
			(xy 344.479372 -337.733132) (xy 344.466749 -337.726317) (xy 344.438947 -337.719296) (xy 344.41029 -337.720283)
			(xy 344.383038 -337.729202) (xy 344.359341 -337.745348) (xy 344.34107 -337.767447) (xy 344.334846 -337.780376)
			(xy 344.323564 -337.809484) (xy 344.292908 -337.863861) (xy 344.253811 -337.912523) (xy 344.23096 -337.933792)
			(xy 344.23096 -339.082634) (xy 345.024202 -339.875876) (xy 350.90608 -339.875876) (xy 351.438464 -339.343746)
			(xy 351.438464 -338.670646) (xy 351.437954 -338.655851) (xy 351.429465 -338.627505) (xy 351.413214 -338.602777)
			(xy 351.390561 -338.583738) (xy 351.363406 -338.571985) (xy 351.334021 -338.5685) (xy 351.30487 -338.573576)
			(xy 351.291398 -338.579714) (xy 351.264834 -338.59237) (xy 351.208778 -338.610251) (xy 351.150638 -338.619293)
			(xy 351.121218 -338.619846) (xy 351.117408 -338.619846) (xy 351.090326 -338.619116) (xy 351.03677 -338.610947)
			(xy 350.984909 -338.595282) (xy 350.935785 -338.572438) (xy 350.890388 -338.542873) (xy 350.84963 -338.507183)
			(xy 350.814332 -338.466085) (xy 350.785203 -338.420407) (xy 350.762831 -338.371067) (xy 350.747664 -338.319058)
			(xy 350.740007 -338.265426) (xy 350.739456 -338.238338) (xy 350.740034 -338.208547) (xy 350.749305 -338.14969)
			(xy 350.767613 -338.09299) (xy 350.794512 -338.039825) (xy 350.829349 -337.991487) (xy 350.871275 -337.949153)
			(xy 350.894904 -337.930998) (xy 350.905346 -337.922505) (xy 350.921724 -337.901156) (xy 350.931959 -337.876272)
			(xy 350.935341 -337.849578) (xy 350.931634 -337.822927) (xy 350.921097 -337.798169) (xy 350.90446 -337.777021)
			(xy 350.893888 -337.768692) (xy 350.870364 -337.75057) (xy 350.828693 -337.708268) (xy 350.79408 -337.660021)
			(xy 350.767361 -337.606993) (xy 350.749181 -337.550465) (xy 350.739978 -337.491804) (xy 350.739456 -337.462114)
			(xy 350.739942 -337.434863) (xy 350.747698 -337.380915) (xy 350.763053 -337.32862) (xy 350.785695 -337.279043)
			(xy 350.815161 -337.233193) (xy 350.850852 -337.192002) (xy 350.892043 -337.156311) (xy 350.937893 -337.126845)
			(xy 350.98747 -337.104203) (xy 351.039765 -337.088848) (xy 351.093713 -337.081092) (xy 351.148215 -337.081092)
			(xy 351.202163 -337.088848) (xy 351.254458 -337.104203) (xy 351.304035 -337.126845) (xy 351.349885 -337.156311)
			(xy 351.391076 -337.192002) (xy 351.426767 -337.233193) (xy 351.456233 -337.279043) (xy 351.478875 -337.32862)
			(xy 351.49423 -337.380915) (xy 351.501986 -337.434863) (xy 351.502472 -337.462114) (xy 351.502017 -337.488696)
			(xy 351.494645 -337.541345) (xy 351.480032 -337.592461) (xy 351.458461 -337.641051) (xy 351.43035 -337.686174)
			(xy 351.396244 -337.726956) (xy 351.356805 -337.762605) (xy 351.312796 -337.792431) (xy 351.289112 -337.804506)
			(xy 351.280753 -337.809032) (xy 351.267898 -337.823016) (xy 351.261001 -337.840714) (xy 351.261005 -337.859709)
			(xy 351.26791 -337.877404) (xy 351.280772 -337.891382) (xy 351.289112 -337.895946) (xy 351.309686 -337.906868)
			(xy 351.321564 -337.913154) (xy 351.347569 -337.919895) (xy 351.374433 -337.91963) (xy 351.4003 -337.912377)
			(xy 351.412048 -337.905852) (xy 351.425936 -337.89675) (xy 351.447453 -337.871488) (xy 351.454212 -337.856322)
			(xy 351.464453 -337.830958) (xy 351.494054 -337.784975) (xy 351.512886 -337.765136) (xy 351.703132 -337.57489)
			(xy 351.719445 -337.559278) (xy 351.756498 -337.533482) (xy 351.776792 -337.523582) (xy 351.785842 -337.499018)
			(xy 351.80972 -337.452433) (xy 351.839746 -337.409552) (xy 351.875354 -337.37118) (xy 351.915875 -337.338038)
			(xy 351.960548 -337.31075) (xy 352.008534 -337.289828) (xy 352.05893 -337.275665) (xy 352.11079 -337.268528)
			(xy 352.136964 -337.268058) (xy 352.137218 -337.268058) (xy 352.162934 -337.268481) (xy 352.213901 -337.275394)
			(xy 352.263475 -337.289094) (xy 352.31076 -337.309331) (xy 352.333052 -337.32216) (xy 352.34707 -337.328992)
			(xy 352.377715 -337.33469) (xy 352.39325 -337.333336) (xy 352.406316 -337.331298) (xy 352.430839 -337.321429)
			(xy 352.452003 -337.305591) (xy 352.468389 -337.284848) (xy 352.474022 -337.272884) (xy 352.484525 -337.245714)
			(xy 352.512584 -337.194668) (xy 352.548077 -337.148481) (xy 352.590178 -337.108226) (xy 352.637909 -337.074839)
			(xy 352.690161 -337.049095) (xy 352.745719 -337.031594) (xy 352.803291 -337.022742) (xy 352.832416 -337.022186)
			(xy 352.85954 -337.022664) (xy 352.91324 -337.03035) (xy 352.96531 -337.045566) (xy 353.0147 -337.068004)
			(xy 353.060413 -337.097212) (xy 353.101529 -337.1326) (xy 353.137216 -337.173456) (xy 353.166757 -337.218955)
			(xy 353.189555 -337.26818) (xy 353.20515 -337.320138) (xy 353.213228 -337.373781) (xy 353.213924 -337.4009)
			(xy 353.213924 -337.403948) (xy 353.213326 -337.433785) (xy 353.204016 -337.492729) (xy 353.195382 -337.521296)
			(xy 353.191431 -337.535206) (xy 353.190618 -337.564098) (xy 353.197916 -337.592065) (xy 353.212742 -337.616876)
			(xy 353.233914 -337.636552) (xy 353.259742 -337.649524) (xy 353.273868 -337.652614) (xy 353.29994 -337.657778)
			(xy 353.350433 -337.674369) (xy 353.398135 -337.697805) (xy 353.442123 -337.727634) (xy 353.481547 -337.763278)
			(xy 353.515644 -337.804048) (xy 353.543754 -337.849155) (xy 353.565333 -337.897726) (xy 353.579963 -337.948821)
			(xy 353.587362 -338.001452) (xy 353.587812 -338.028026) (xy 353.587324 -338.055276) (xy 353.579565 -338.109221)
			(xy 353.564208 -338.161513) (xy 353.541565 -338.211087) (xy 353.512098 -338.256935) (xy 353.476407 -338.298122)
			(xy 353.435217 -338.333811) (xy 353.389368 -338.363276) (xy 353.339792 -338.385915) (xy 353.2875 -338.40127)
			(xy 353.233554 -338.409026) (xy 353.206304 -338.409534) (xy 353.179179 -338.409058) (xy 353.125475 -338.401374)
			(xy 353.073402 -338.38616) (xy 353.024008 -338.363723) (xy 352.978291 -338.334516) (xy 352.937172 -338.299128)
			(xy 352.90148 -338.258272) (xy 352.871935 -338.212772) (xy 352.849134 -338.163546) (xy 352.833535 -338.111586)
			(xy 352.825454 -338.057941) (xy 352.824796 -338.03082) (xy 352.824796 -338.027772) (xy 352.825392 -337.997935)
			(xy 352.8347 -337.93899) (xy 352.843338 -337.910424) (xy 352.847292 -337.896512) (xy 352.848108 -337.867615)
			(xy 352.840814 -337.839642) (xy 352.825989 -337.814823) (xy 352.804818 -337.795139) (xy 352.778987 -337.782159)
			(xy 352.764852 -337.779106) (xy 352.732015 -337.772514) (xy 352.669163 -337.749393) (xy 352.639884 -337.733132)
			(xy 352.62726 -337.726315) (xy 352.599457 -337.719291) (xy 352.570797 -337.720276) (xy 352.543541 -337.729194)
			(xy 352.519841 -337.745339) (xy 352.501567 -337.76744) (xy 352.495358 -337.780376) (xy 352.484076 -337.809484)
			(xy 352.453421 -337.863862) (xy 352.414325 -337.912525) (xy 352.391472 -337.933792) (xy 352.391472 -339.082634)
			(xy 352.919284 -339.610446) (xy 353.184968 -339.876384) (xy 358.916224 -339.876384) (xy 359.627424 -339.16493)
			(xy 359.627424 -338.654898) (xy 359.626908 -338.639937) (xy 359.618253 -338.611295) (xy 359.60166 -338.586397)
			(xy 359.578555 -338.567385) (xy 359.550927 -338.555896) (xy 359.521155 -338.552918) (xy 359.491799 -338.558708)
			(xy 359.478326 -338.565236) (xy 359.455968 -338.578174) (xy 359.408511 -338.598574) (xy 359.358738 -338.612394)
			(xy 359.307558 -338.619384) (xy 359.28173 -338.619846) (xy 359.281476 -338.619846) (xy 359.254225 -338.619359)
			(xy 359.200278 -338.6116) (xy 359.147984 -338.596243) (xy 359.098407 -338.573601) (xy 359.052557 -338.544134)
			(xy 359.011366 -338.508443) (xy 358.975674 -338.467254) (xy 358.946206 -338.421405) (xy 358.923562 -338.371829)
			(xy 358.908203 -338.319536) (xy 358.900442 -338.265589) (xy 358.899968 -338.238338) (xy 358.900546 -338.208546)
			(xy 358.909816 -338.149687) (xy 358.92812 -338.092984) (xy 358.955015 -338.039815) (xy 358.989847 -337.991471)
			(xy 359.031769 -337.949129) (xy 359.055416 -337.930998) (xy 359.065857 -337.922504) (xy 359.082233 -337.901155)
			(xy 359.092467 -337.876271) (xy 359.095848 -337.849578) (xy 359.092142 -337.822928) (xy 359.081606 -337.79817)
			(xy 359.064971 -337.777022) (xy 359.0544 -337.768692) (xy 359.030875 -337.750571) (xy 358.989203 -337.708269)
			(xy 358.954589 -337.660022) (xy 358.927869 -337.606994) (xy 358.909688 -337.550466) (xy 358.900486 -337.491804)
			(xy 358.899968 -337.462114) (xy 358.900454 -337.434863) (xy 358.90821 -337.380915) (xy 358.923565 -337.32862)
			(xy 358.946207 -337.279043) (xy 358.975673 -337.233193) (xy 359.011364 -337.192002) (xy 359.052555 -337.156311)
			(xy 359.098405 -337.126845) (xy 359.147982 -337.104203) (xy 359.200277 -337.088848) (xy 359.254225 -337.081092)
			(xy 359.308727 -337.081092) (xy 359.362675 -337.088848) (xy 359.41497 -337.104203) (xy 359.464547 -337.126845)
			(xy 359.510397 -337.156311) (xy 359.551588 -337.192002) (xy 359.587279 -337.233193) (xy 359.616745 -337.279043)
			(xy 359.639387 -337.32862) (xy 359.654742 -337.380915) (xy 359.662498 -337.434863) (xy 359.662984 -337.462114)
			(xy 359.66241 -337.491907) (xy 359.653145 -337.550769) (xy 359.634844 -337.607476) (xy 359.607951 -337.660649)
			(xy 359.573119 -337.708994) (xy 359.531196 -337.751339) (xy 359.507536 -337.769454) (xy 359.497106 -337.77795)
			(xy 359.480751 -337.799297) (xy 359.470534 -337.824173) (xy 359.467164 -337.850854) (xy 359.470875 -337.877489)
			(xy 359.481409 -337.902232) (xy 359.498036 -337.923368) (xy 359.508552 -337.93176) (xy 359.510076 -337.932776)
			(xy 359.520915 -337.941075) (xy 359.54151 -337.958998) (xy 359.551224 -337.96859) (xy 359.55605 -337.973162)
			(xy 359.627424 -337.973162) (xy 359.627424 -337.916012) (xy 359.628064 -337.891017) (xy 359.63787 -337.841997)
			(xy 359.657047 -337.79583) (xy 359.68486 -337.75429) (xy 359.7021 -337.73618) (xy 359.790238 -337.648042)
			(xy 359.863644 -337.57489) (xy 359.879954 -337.559273) (xy 359.917001 -337.533465) (xy 359.937304 -337.523582)
			(xy 359.946354 -337.499019) (xy 359.970233 -337.452435) (xy 360.000258 -337.409554) (xy 360.035867 -337.371183)
			(xy 360.076388 -337.338043) (xy 360.121061 -337.310756) (xy 360.169047 -337.289835) (xy 360.219443 -337.275674)
			(xy 360.271302 -337.268538) (xy 360.297476 -337.268058) (xy 360.29773 -337.268058) (xy 360.323446 -337.268481)
			(xy 360.374412 -337.275397) (xy 360.423986 -337.289098) (xy 360.471269 -337.309336) (xy 360.493564 -337.32216)
			(xy 360.507583 -337.328991) (xy 360.538227 -337.334685) (xy 360.553762 -337.333336) (xy 360.566827 -337.331297)
			(xy 360.591347 -337.321426) (xy 360.61251 -337.305587) (xy 360.628893 -337.284844) (xy 360.634534 -337.272884)
			(xy 360.645038 -337.245714) (xy 360.673097 -337.19467) (xy 360.70859 -337.148484) (xy 360.750691 -337.10823)
			(xy 360.798422 -337.074844) (xy 360.850674 -337.049102) (xy 360.906232 -337.031603) (xy 360.963804 -337.022752)
			(xy 360.992928 -337.022186) (xy 361.020051 -337.022665) (xy 361.07375 -337.030352) (xy 361.125819 -337.045569)
			(xy 361.175207 -337.068008) (xy 361.220919 -337.097216) (xy 361.262033 -337.132605) (xy 361.297719 -337.17346)
			(xy 361.327259 -337.218959) (xy 361.350056 -337.268183) (xy 361.36565 -337.320139) (xy 361.373728 -337.373781)
			(xy 361.374436 -337.4009) (xy 361.374436 -337.403948) (xy 361.373838 -337.433785) (xy 361.364528 -337.492729)
			(xy 361.355894 -337.521296) (xy 361.351943 -337.535206) (xy 361.35113 -337.564097) (xy 361.358428 -337.592063)
			(xy 361.373254 -337.616873) (xy 361.394427 -337.636547) (xy 361.420256 -337.649517) (xy 361.43438 -337.652614)
			(xy 361.460451 -337.657779) (xy 361.510943 -337.67437) (xy 361.558643 -337.697808) (xy 361.602631 -337.727637)
			(xy 361.642053 -337.763281) (xy 361.676149 -337.804051) (xy 361.704258 -337.849158) (xy 361.725836 -337.897728)
			(xy 361.740465 -337.948822) (xy 361.747864 -338.001452) (xy 361.748324 -338.028026) (xy 361.747836 -338.055276)
			(xy 361.740077 -338.109222) (xy 361.72472 -338.161515) (xy 361.702077 -338.21109) (xy 361.672611 -338.256938)
			(xy 361.636919 -338.298126) (xy 361.59573 -338.333817) (xy 361.549881 -338.363282) (xy 361.500305 -338.385923)
			(xy 361.448012 -338.401279) (xy 361.394066 -338.409037) (xy 361.366816 -338.409534) (xy 361.33969 -338.409058)
			(xy 361.285985 -338.401376) (xy 361.23391 -338.386163) (xy 361.184515 -338.363727) (xy 361.138796 -338.334521)
			(xy 361.097676 -338.299132) (xy 361.061983 -338.258276) (xy 361.032437 -338.212775) (xy 361.009635 -338.163549)
			(xy 360.994035 -338.111588) (xy 360.985954 -338.057942) (xy 360.985308 -338.03082) (xy 360.985308 -338.027772)
			(xy 360.985904 -337.997935) (xy 360.995213 -337.93899) (xy 361.00385 -337.910424) (xy 361.007806 -337.896515)
			(xy 361.008625 -337.867623) (xy 361.001328 -337.839655) (xy 360.986499 -337.814846) (xy 360.965322 -337.795175)
			(xy 360.939487 -337.782214) (xy 360.925364 -337.779106) (xy 360.892527 -337.772515) (xy 360.829674 -337.749396)
			(xy 360.800396 -337.733132) (xy 360.787772 -337.726313) (xy 360.759966 -337.719285) (xy 360.731303 -337.720269)
			(xy 360.704045 -337.729185) (xy 360.680342 -337.745331) (xy 360.662065 -337.767432) (xy 360.65587 -337.780376)
			(xy 360.644585 -337.809482) (xy 360.613926 -337.863855) (xy 360.574823 -337.912511) (xy 360.551984 -337.933792)
			(xy 360.551984 -339.082634) (xy 361.358942 -339.889592) (xy 367.161064 -339.889592) (xy 367.755424 -339.295232)
			(xy 367.755424 -338.672424) (xy 367.754927 -338.657928) (xy 367.746801 -338.630099) (xy 367.731169 -338.605683)
			(xy 367.709297 -338.586655) (xy 367.682953 -338.574552) (xy 367.654267 -338.570355) (xy 367.62556 -338.574402)
			(xy 367.612168 -338.579968) (xy 367.607342 -338.582254) (xy 367.581447 -338.5941) (xy 367.527022 -338.610845)
			(xy 367.470713 -338.619322) (xy 367.442242 -338.619846) (xy 367.435384 -338.619846) (xy 367.408438 -338.618921)
			(xy 367.355197 -338.610419) (xy 367.303683 -338.594506) (xy 367.254923 -338.571499) (xy 367.209888 -338.541857)
			(xy 367.169474 -338.506168) (xy 367.134488 -338.465146) (xy 367.105626 -338.419606) (xy 367.083463 -338.370456)
			(xy 367.068441 -338.318676) (xy 367.060859 -338.265296) (xy 367.06048 -338.238338) (xy 367.061058 -338.208546)
			(xy 367.070328 -338.149687) (xy 367.088633 -338.092985) (xy 367.115529 -338.039816) (xy 367.150361 -337.991473)
			(xy 367.192283 -337.949132) (xy 367.215928 -337.930998) (xy 367.226368 -337.922504) (xy 367.242742 -337.901154)
			(xy 367.252975 -337.87627) (xy 367.256355 -337.849578) (xy 367.25265 -337.822928) (xy 367.242115 -337.798171)
			(xy 367.225482 -337.777022) (xy 367.214912 -337.768692) (xy 367.191392 -337.750568) (xy 367.149729 -337.708262)
			(xy 367.115123 -337.660014) (xy 367.08841 -337.606986) (xy 367.070233 -337.550461) (xy 367.061033 -337.491802)
			(xy 367.06048 -337.462114) (xy 367.060966 -337.434863) (xy 367.068722 -337.380915) (xy 367.084077 -337.32862)
			(xy 367.106719 -337.279043) (xy 367.136185 -337.233193) (xy 367.171876 -337.192002) (xy 367.213067 -337.156311)
			(xy 367.258917 -337.126845) (xy 367.308494 -337.104203) (xy 367.360789 -337.088848) (xy 367.414737 -337.081092)
			(xy 367.469239 -337.081092) (xy 367.523187 -337.088848) (xy 367.575482 -337.104203) (xy 367.625059 -337.126845)
			(xy 367.670909 -337.156311) (xy 367.7121 -337.192002) (xy 367.747791 -337.233193) (xy 367.777257 -337.279043)
			(xy 367.799899 -337.32862) (xy 367.815254 -337.380915) (xy 367.82301 -337.434863) (xy 367.823496 -337.462114)
			(xy 367.823041 -337.488695) (xy 367.815668 -337.541342) (xy 367.801053 -337.592455) (xy 367.779479 -337.641042)
			(xy 367.751366 -337.686161) (xy 367.717257 -337.726937) (xy 367.677814 -337.76258) (xy 367.633803 -337.792397)
			(xy 367.610136 -337.804506) (xy 367.601774 -337.80903) (xy 367.588913 -337.823012) (xy 367.582012 -337.840712)
			(xy 367.582016 -337.85971) (xy 367.588925 -337.877408) (xy 367.601793 -337.891384) (xy 367.610136 -337.895946)
			(xy 367.619788 -337.900772) (xy 367.629186 -337.905852) (xy 367.642044 -337.912497) (xy 367.670225 -337.919034)
			(xy 367.699109 -337.917414) (xy 367.726382 -337.907766) (xy 367.749859 -337.890863) (xy 367.76766 -337.868059)
			(xy 367.773458 -337.854798) (xy 367.783638 -337.830955) (xy 367.812187 -337.787688) (xy 367.8301 -337.768946)
			(xy 367.830354 -337.768692) (xy 368.024156 -337.57489) (xy 368.040466 -337.559274) (xy 368.077515 -337.533468)
			(xy 368.097816 -337.523582) (xy 368.106866 -337.499019) (xy 368.130745 -337.452436) (xy 368.160771 -337.409556)
			(xy 368.19638 -337.371186) (xy 368.236901 -337.338047) (xy 368.281575 -337.310762) (xy 368.32956 -337.289842)
			(xy 368.379956 -337.275683) (xy 368.431814 -337.268549) (xy 368.457988 -337.268058) (xy 368.458242 -337.268058)
			(xy 368.48396 -337.268476) (xy 368.53493 -337.27538) (xy 368.58451 -337.289071) (xy 368.6318 -337.309301)
			(xy 368.654076 -337.32216) (xy 368.668095 -337.328989) (xy 368.698738 -337.334679) (xy 368.714274 -337.333336)
			(xy 368.727338 -337.331296) (xy 368.751856 -337.321422) (xy 368.773016 -337.305583) (xy 368.789398 -337.28484)
			(xy 368.795046 -337.272884) (xy 368.80555 -337.245715) (xy 368.833609 -337.194671) (xy 368.869103 -337.148486)
			(xy 368.911204 -337.108234) (xy 368.958935 -337.074849) (xy 369.011187 -337.049109) (xy 369.066744 -337.031611)
			(xy 369.124316 -337.022763) (xy 369.15344 -337.022186) (xy 369.180563 -337.022665) (xy 369.23426 -337.030355)
			(xy 369.286328 -337.045572) (xy 369.335714 -337.068012) (xy 369.381425 -337.09722) (xy 369.422537 -337.132609)
			(xy 369.458222 -337.173464) (xy 369.487761 -337.218962) (xy 369.510557 -337.268185) (xy 369.526151 -337.320141)
			(xy 369.534228 -337.373782) (xy 369.534948 -337.4009) (xy 369.534948 -337.403948) (xy 369.534351 -337.433785)
			(xy 369.52504 -337.492729) (xy 369.516406 -337.521296) (xy 369.512454 -337.535205) (xy 369.511641 -337.564096)
			(xy 369.518939 -337.592061) (xy 369.533767 -337.61687) (xy 369.55494 -337.636542) (xy 369.58077 -337.649509)
			(xy 369.594892 -337.652614) (xy 369.620967 -337.657773) (xy 369.671468 -337.674357) (xy 369.719179 -337.697789)
			(xy 369.763177 -337.727615) (xy 369.802609 -337.763258) (xy 369.836713 -337.804029) (xy 369.86483 -337.849138)
			(xy 369.886413 -337.897713) (xy 369.901047 -337.948813) (xy 369.908448 -338.001449) (xy 369.908836 -338.028026)
			(xy 369.908348 -338.055277) (xy 369.900589 -338.109223) (xy 369.885232 -338.161516) (xy 369.86259 -338.211092)
			(xy 369.833123 -338.256941) (xy 369.797432 -338.298131) (xy 369.756243 -338.333822) (xy 369.710394 -338.363289)
			(xy 369.660818 -338.385931) (xy 369.608525 -338.401289) (xy 369.554579 -338.409048) (xy 369.527328 -338.409534)
			(xy 369.500202 -338.409059) (xy 369.446495 -338.401378) (xy 369.394419 -338.386166) (xy 369.345023 -338.363731)
			(xy 369.299302 -338.334525) (xy 369.25818 -338.299136) (xy 369.222486 -338.25828) (xy 369.192939 -338.212779)
			(xy 369.170136 -338.163551) (xy 369.154536 -338.11159) (xy 369.146454 -338.057942) (xy 369.14582 -338.03082)
			(xy 369.14582 -338.027772) (xy 369.146416 -337.997935) (xy 369.155725 -337.93899) (xy 369.164362 -337.910424)
			(xy 369.168318 -337.896515) (xy 369.169136 -337.867622) (xy 369.16184 -337.839653) (xy 369.147012 -337.814842)
			(xy 369.125835 -337.79517) (xy 369.100001 -337.782207) (xy 369.085876 -337.779106) (xy 369.053038 -337.772516)
			(xy 368.990184 -337.749399) (xy 368.960908 -337.733132) (xy 368.948283 -337.726311) (xy 368.920476 -337.71928)
			(xy 368.89181 -337.720261) (xy 368.864548 -337.729176) (xy 368.840842 -337.745322) (xy 368.822562 -337.767424)
			(xy 368.816382 -337.780376) (xy 368.805098 -337.809482) (xy 368.774439 -337.863856) (xy 368.735337 -337.912513)
			(xy 368.712496 -337.933792) (xy 368.712496 -339.082634) (xy 370.256562 -340.6267) (xy 371.079522 -340.6267)
			(xy 371.10452 -340.627334) (xy 371.124233 -340.631272) (xy 374.003316 -340.631272) (xy 374.003769 -340.603734)
			(xy 374.011666 -340.549227) (xy 374.027321 -340.496423) (xy 374.050409 -340.44642) (xy 374.080448 -340.400257)
			(xy 374.116816 -340.358896) (xy 374.158754 -340.323195) (xy 374.205391 -340.293897) (xy 374.255757 -340.271613)
			(xy 374.308805 -340.256804) (xy 374.336056 -340.252812) (xy 374.349853 -340.250659) (xy 374.375538 -340.239719)
			(xy 374.397306 -340.222238) (xy 374.413534 -340.199522) (xy 374.423013 -340.173262) (xy 374.425036 -340.145418)
			(xy 374.42267 -340.131654) (xy 374.419017 -340.112687) (xy 374.415068 -340.07426) (xy 374.414796 -340.054946)
			(xy 374.415282 -340.027695) (xy 374.423038 -339.973747) (xy 374.438393 -339.921452) (xy 374.461035 -339.871875)
			(xy 374.490501 -339.826025) (xy 374.526192 -339.784834) (xy 374.567383 -339.749143) (xy 374.613233 -339.719677)
			(xy 374.66281 -339.697035) (xy 374.715105 -339.68168) (xy 374.769053 -339.673924) (xy 374.823555 -339.673924)
			(xy 374.877503 -339.68168) (xy 374.929798 -339.697035) (xy 374.979375 -339.719677) (xy 375.025225 -339.749143)
			(xy 375.066416 -339.784834) (xy 375.102107 -339.826025) (xy 375.131573 -339.871875) (xy 375.154215 -339.921452)
			(xy 375.16957 -339.973747) (xy 375.177326 -340.027695) (xy 375.177812 -340.054946) (xy 375.177351 -340.082484)
			(xy 375.169452 -340.136989) (xy 375.153796 -340.189791) (xy 375.130709 -340.239793) (xy 375.10067 -340.285954)
			(xy 375.064304 -340.327316) (xy 375.022367 -340.363016) (xy 374.975732 -340.392315) (xy 374.925368 -340.414601)
			(xy 374.872322 -340.429412) (xy 374.845072 -340.433406) (xy 374.831299 -340.435672) (xy 374.805626 -340.446595)
			(xy 374.783863 -340.464053) (xy 374.767632 -340.486746) (xy 374.758143 -340.512982) (xy 374.756103 -340.540807)
			(xy 374.758458 -340.554564) (xy 374.762114 -340.573531) (xy 374.766061 -340.611958) (xy 374.766332 -340.631272)
			(xy 374.765846 -340.658523) (xy 374.75809 -340.712471) (xy 374.742735 -340.764766) (xy 374.720093 -340.814343)
			(xy 374.690627 -340.860193) (xy 374.654936 -340.901384) (xy 374.613745 -340.937075) (xy 374.567895 -340.966541)
			(xy 374.518318 -340.989183) (xy 374.466023 -341.004538) (xy 374.412075 -341.012294) (xy 374.357573 -341.012294)
			(xy 374.303625 -341.004538) (xy 374.25133 -340.989183) (xy 374.201753 -340.966541) (xy 374.155903 -340.937075)
			(xy 374.114712 -340.901384) (xy 374.079021 -340.860193) (xy 374.049555 -340.814343) (xy 374.026913 -340.764766)
			(xy 374.011558 -340.712471) (xy 374.003802 -340.658523) (xy 374.003316 -340.631272) (xy 371.124233 -340.631272)
			(xy 371.153548 -340.637128) (xy 371.199724 -340.656296) (xy 371.241275 -340.684101) (xy 371.259354 -340.701376)
			(xy 373.833644 -343.27592) (xy 375.391934 -343.27592) (xy 375.865644 -342.801956) (xy 375.865644 -342.10371)
			(xy 375.865174 -342.08983) (xy 375.857694 -342.063097) (xy 375.843284 -342.039371) (xy 375.823012 -342.020407)
			(xy 375.798378 -342.007609) (xy 375.771206 -342.001926) (xy 375.743508 -342.003778) (xy 375.730262 -342.007952)
			(xy 375.699334 -342.018267) (xy 375.635096 -342.029381) (xy 375.6025 -342.03005) (xy 375.575248 -342.029564)
			(xy 375.521298 -342.021808) (xy 375.469001 -342.006453) (xy 375.419421 -341.983813) (xy 375.373567 -341.954347)
			(xy 375.332374 -341.918656) (xy 375.296678 -341.877466) (xy 375.267207 -341.831616) (xy 375.244561 -341.782039)
			(xy 375.229201 -341.729743) (xy 375.221439 -341.675794) (xy 375.220992 -341.648542) (xy 375.221569 -341.61875)
			(xy 375.230839 -341.559891) (xy 375.249144 -341.503189) (xy 375.27604 -341.45002) (xy 375.310873 -341.401678)
			(xy 375.352796 -341.359337) (xy 375.37644 -341.341202) (xy 375.38688 -341.332707) (xy 375.403253 -341.311357)
			(xy 375.413485 -341.286473) (xy 375.416866 -341.25978) (xy 375.413161 -341.23313) (xy 375.402628 -341.208372)
			(xy 375.385997 -341.187222) (xy 375.375424 -341.178896) (xy 375.351903 -341.160772) (xy 375.310239 -341.118468)
			(xy 375.275631 -341.070219) (xy 375.248916 -341.017192) (xy 375.230738 -340.960666) (xy 375.221537 -340.902006)
			(xy 375.220992 -340.872318) (xy 375.221478 -340.845067) (xy 375.229234 -340.791119) (xy 375.244589 -340.738824)
			(xy 375.267231 -340.689247) (xy 375.296697 -340.643397) (xy 375.332388 -340.602206) (xy 375.373579 -340.566515)
			(xy 375.419429 -340.537049) (xy 375.469006 -340.514407) (xy 375.521301 -340.499052) (xy 375.575249 -340.491296)
			(xy 375.629751 -340.491296) (xy 375.683699 -340.499052) (xy 375.735994 -340.514407) (xy 375.785571 -340.537049)
			(xy 375.831421 -340.566515) (xy 375.872612 -340.602206) (xy 375.908303 -340.643397) (xy 375.937769 -340.689247)
			(xy 375.960411 -340.738824) (xy 375.975766 -340.791119) (xy 375.983522 -340.845067) (xy 375.984008 -340.872318)
			(xy 375.983553 -340.898899) (xy 375.976179 -340.951546) (xy 375.961564 -341.002659) (xy 375.939991 -341.051246)
			(xy 375.911877 -341.096365) (xy 375.877769 -341.137142) (xy 375.838327 -341.172785) (xy 375.794316 -341.202604)
			(xy 375.770648 -341.21471) (xy 375.762286 -341.219233) (xy 375.749422 -341.233214) (xy 375.742521 -341.250914)
			(xy 375.742526 -341.269912) (xy 375.749437 -341.287609) (xy 375.762307 -341.301583) (xy 375.770648 -341.30615)
			(xy 375.774458 -341.307928) (xy 375.787705 -341.314104) (xy 375.816438 -341.319395) (xy 375.845495 -341.316345)
			(xy 375.872504 -341.305203) (xy 375.895261 -341.28688) (xy 375.903998 -341.275162) (xy 375.911913 -341.262852)
			(xy 375.93012 -341.239937) (xy 375.94032 -341.229442) (xy 376.184668 -340.985094) (xy 376.200978 -340.969479)
			(xy 376.238027 -340.943673) (xy 376.258328 -340.933786) (xy 376.267377 -340.90922) (xy 376.291254 -340.86263)
			(xy 376.321277 -340.819742) (xy 376.356884 -340.781364) (xy 376.397405 -340.748216) (xy 376.442078 -340.72092)
			(xy 376.490064 -340.69999) (xy 376.540462 -340.685819) (xy 376.592324 -340.678673) (xy 376.6185 -340.678262)
			(xy 376.618754 -340.678262) (xy 376.644472 -340.67868) (xy 376.695441 -340.685586) (xy 376.74502 -340.699279)
			(xy 376.79231 -340.71951) (xy 376.814588 -340.732364) (xy 376.828607 -340.739191) (xy 376.85925 -340.744878)
			(xy 376.874786 -340.74354) (xy 376.887857 -340.74151) (xy 376.912392 -340.73165) (xy 376.93357 -340.715818)
			(xy 376.949969 -340.695075) (xy 376.955558 -340.683088) (xy 376.964448 -340.660736) (xy 376.969326 -340.647397)
			(xy 376.972295 -340.619161) (xy 376.967378 -340.591199) (xy 376.954956 -340.56567) (xy 376.935986 -340.544546)
			(xy 376.911936 -340.529458) (xy 376.884662 -340.521573) (xy 376.870468 -340.521036) (xy 376.326146 -340.521036)
			(xy 376.300164 -340.52054) (xy 376.248845 -340.51238) (xy 376.199437 -340.496286) (xy 376.153157 -340.472656)
			(xy 376.111148 -340.44207) (xy 376.092466 -340.424008) (xy 375.045986 -339.377528) (xy 375.021856 -339.380068)
			(xy 375.011789 -339.381048) (xy 374.991585 -339.382065) (xy 374.98147 -339.3821) (xy 374.980708 -339.3821)
			(xy 374.954517 -339.381646) (xy 374.902634 -339.374436) (xy 374.852225 -339.360191) (xy 374.828054 -339.350096)
			(xy 374.801892 -339.337396) (xy 374.790716 -339.3313) (xy 374.661176 -339.3313) (xy 374.568466 -339.42401)
			(xy 374.560338 -339.432392) (xy 374.541617 -339.450407) (xy 374.499603 -339.480966) (xy 374.453331 -339.504586)
			(xy 374.403936 -339.520687) (xy 374.352633 -339.528874) (xy 374.326658 -339.52942) (xy 372.121176 -339.52942)
			(xy 372.095197 -339.528918) (xy 372.043884 -339.520749) (xy 371.994483 -339.504647) (xy 371.948211 -339.481009)
			(xy 371.906212 -339.450418) (xy 371.887496 -339.432392) (xy 369.352322 -336.896964) (xy 368.34064 -336.896964)
			(xy 368.310618 -336.895453) (xy 368.25183 -336.882932) (xy 368.2238 -336.872072) (xy 367.816384 -336.703162)
			(xy 367.50244 -336.573114) (xy 367.482589 -336.564509) (xy 367.445118 -336.542877) (xy 367.410791 -336.51654)
			(xy 367.395252 -336.501486) (xy 366.908842 -336.015076) (xy 366.89082 -335.996371) (xy 366.860291 -335.95435)
			(xy 366.836716 -335.908069) (xy 366.820674 -335.858668) (xy 366.812562 -335.807366) (xy 366.812068 -335.781396)
			(xy 366.812068 -335.222596) (xy 366.461294 -334.872076) (xy 366.282732 -334.872076) (xy 366.268235 -334.872572)
			(xy 366.240404 -334.880697) (xy 366.215986 -334.896328) (xy 366.196956 -334.918201) (xy 366.184852 -334.944546)
			(xy 366.180655 -334.973234) (xy 366.184702 -335.001942) (xy 366.190276 -335.015332) (xy 366.201493 -335.040637)
			(xy 366.217331 -335.093673) (xy 366.225346 -335.148439) (xy 366.225836 -335.176114) (xy 366.225836 -335.176368)
			(xy 366.22535 -335.203619) (xy 366.217594 -335.257567) (xy 366.202239 -335.309862) (xy 366.179597 -335.359439)
			(xy 366.150131 -335.405289) (xy 366.11444 -335.44648) (xy 366.073249 -335.482171) (xy 366.027399 -335.511637)
			(xy 365.977822 -335.534279) (xy 365.925527 -335.549634) (xy 365.871579 -335.55739) (xy 365.817077 -335.55739)
			(xy 365.763129 -335.549634) (xy 365.710834 -335.534279) (xy 365.661257 -335.511637) (xy 365.615407 -335.482171)
			(xy 365.574216 -335.44648) (xy 365.538525 -335.405289) (xy 365.509059 -335.359439) (xy 365.486417 -335.309862)
			(xy 365.471062 -335.257567) (xy 365.463306 -335.203619) (xy 365.46282 -335.176368) (xy 365.46333 -335.14841)
			(xy 365.471522 -335.093098) (xy 365.487682 -335.039568) (xy 365.499142 -335.014062) (xy 365.504972 -335.000616)
			(xy 365.509475 -334.971669) (xy 365.505579 -334.942634) (xy 365.493605 -334.915898) (xy 365.474537 -334.893658)
			(xy 365.449942 -334.877742) (xy 365.421842 -334.869459) (xy 365.407194 -334.869028) (xy 361.911138 -334.869028)
			(xy 361.475274 -335.305146) (xy 361.453698 -335.32588) (xy 361.40528 -335.36104) (xy 361.351961 -335.388197)
			(xy 361.295052 -335.406683) (xy 361.235952 -335.416044) (xy 361.206034 -335.416652) (xy 358.761538 -335.416652)
			(xy 358.731624 -335.416041) (xy 358.672536 -335.406646) (xy 358.615638 -335.388144) (xy 358.562326 -335.360988)
			(xy 358.513906 -335.325843) (xy 358.492298 -335.305146) (xy 358.110028 -334.922876) (xy 358.014778 -334.922876)
			(xy 358.014778 -334.986376) (xy 358.020874 -334.997552) (xy 358.034868 -335.025214) (xy 358.054679 -335.08395)
			(xy 358.064716 -335.14512) (xy 358.065324 -335.176114) (xy 358.065324 -335.176368) (xy 358.064863 -335.203623)
			(xy 358.05711 -335.257578) (xy 358.041757 -335.309881) (xy 358.019117 -335.359466) (xy 357.98965 -335.405324)
			(xy 357.953956 -335.446522) (xy 357.912763 -335.482221) (xy 357.866908 -335.511694) (xy 357.817326 -335.53434)
			(xy 357.765025 -335.5497) (xy 357.711071 -335.55746) (xy 357.683816 -335.557876) (xy 357.656827 -335.55741)
			(xy 357.603389 -335.549806) (xy 357.551555 -335.534746) (xy 357.502361 -335.512533) (xy 357.456788 -335.483608)
			(xy 357.415747 -335.44855) (xy 357.380055 -335.408057) (xy 357.350426 -335.362939) (xy 357.327451 -335.314096)
			(xy 357.311588 -335.262503) (xy 357.303155 -335.209189) (xy 357.302308 -335.18221) (xy 357.302308 -335.176114)
			(xy 357.302839 -335.146612) (xy 357.311899 -335.088309) (xy 357.320342 -335.060036) (xy 357.320596 -335.059274)
			(xy 357.321612 -335.056226) (xy 357.325468 -335.043063) (xy 357.326788 -335.015678) (xy 357.320772 -334.988929)
			(xy 357.307852 -334.964747) (xy 357.288962 -334.944876) (xy 357.265464 -334.93075) (xy 357.239053 -334.923388)
			(xy 357.225346 -334.922876) (xy 353.709986 -334.922876) (xy 353.401122 -335.23174) (xy 353.379506 -335.252516)
			(xy 353.330999 -335.287749) (xy 353.27758 -335.314963) (xy 353.220563 -335.333491) (xy 353.16135 -335.342876)
			(xy 353.131374 -335.3435) (xy 350.57334 -335.3435) (xy 350.543359 -335.342945) (xy 350.484135 -335.333566)
			(xy 350.427109 -335.315033) (xy 350.373687 -335.287803) (xy 350.325184 -335.252547) (xy 350.303592 -335.23174)
			(xy 349.994728 -334.922876) (xy 349.854266 -334.922876) (xy 349.854266 -334.986376) (xy 349.860362 -334.997552)
			(xy 349.874356 -335.025214) (xy 349.894168 -335.08395) (xy 349.904206 -335.14512) (xy 349.904812 -335.176114)
			(xy 349.904812 -335.176368) (xy 349.904326 -335.203619) (xy 349.89657 -335.257567) (xy 349.881215 -335.309862)
			(xy 349.858573 -335.359439) (xy 349.829107 -335.405289) (xy 349.793416 -335.44648) (xy 349.752225 -335.482171)
			(xy 349.706375 -335.511637) (xy 349.656798 -335.534279) (xy 349.604503 -335.549634) (xy 349.550555 -335.55739)
			(xy 349.496053 -335.55739) (xy 349.442105 -335.549634) (xy 349.38981 -335.534279) (xy 349.340233 -335.511637)
			(xy 349.294383 -335.482171) (xy 349.253192 -335.44648) (xy 349.217501 -335.405289) (xy 349.188035 -335.359439)
			(xy 349.165393 -335.309862) (xy 349.150038 -335.257567) (xy 349.142282 -335.203619) (xy 349.141796 -335.176368)
			(xy 349.142347 -335.146892) (xy 349.15142 -335.088643) (xy 349.169346 -335.032482) (xy 349.195697 -334.979747)
			(xy 349.229847 -334.931694) (xy 349.25 -334.910176) (xy 349.264478 -334.89519) (xy 349.264478 -334.822038)
			(xy 349.154242 -334.711548) (xy 345.803474 -334.711548) (xy 345.464384 -335.050892) (xy 345.46413 -335.051146)
			(xy 345.446179 -335.068484) (xy 345.406562 -335.098835) (xy 345.36333 -335.12377) (xy 345.340432 -335.133696)
			(xy 345.20886 -335.188052) (xy 344.727022 -335.387696) (xy 344.70386 -335.396845) (xy 344.655755 -335.40973)
			(xy 344.60638 -335.416233) (xy 344.58148 -335.416652) (xy 342.80729 -335.416652) (xy 342.468635 -335.7555)
			(xy 345.217421 -335.7555) (xy 345.22159 -335.699879) (xy 345.234002 -335.6455) (xy 345.254381 -335.593578)
			(xy 345.28227 -335.545274) (xy 345.317048 -335.501666) (xy 345.357937 -335.463729) (xy 345.404023 -335.432311)
			(xy 345.454278 -335.408112) (xy 345.507578 -335.391674) (xy 345.562733 -335.383363) (xy 345.590622 -335.38287)
			(xy 345.590876 -335.38287) (xy 345.618412 -335.383381) (xy 345.672883 -335.391499) (xy 345.725561 -335.40756)
			(xy 345.750642 -335.418938) (xy 345.763019 -335.424383) (xy 345.789613 -335.429217) (xy 345.816543 -335.426897)
			(xy 345.841919 -335.417588) (xy 345.86396 -335.401941) (xy 345.881119 -335.381056) (xy 345.88704 -335.3689)
			(xy 345.898378 -335.344653) (xy 345.927062 -335.299459) (xy 345.96192 -335.258838) (xy 346.002233 -335.223624)
			(xy 346.047173 -335.194544) (xy 346.095812 -335.172197) (xy 346.14715 -335.157042) (xy 346.200128 -335.149393)
			(xy 346.226892 -335.148936) (xy 346.253364 -335.149401) (xy 346.305773 -335.156901) (xy 346.356596 -335.171737)
			(xy 346.404809 -335.193611) (xy 346.449445 -335.222083) (xy 346.489606 -335.256582) (xy 346.524485 -335.296413)
			(xy 346.55338 -335.340776) (xy 346.564966 -335.364582) (xy 346.571667 -335.377804) (xy 346.5913 -335.399992)
			(xy 346.616473 -335.415614) (xy 346.64507 -335.423359) (xy 346.674687 -335.422574) (xy 346.688918 -335.41843)
			(xy 346.717263 -335.409661) (xy 346.775839 -335.400225) (xy 346.805504 -335.399634) (xy 346.833361 -335.40015)
			(xy 346.888456 -335.40844) (xy 346.915232 -335.416144) (xy 346.929563 -335.419986) (xy 346.959217 -335.420195)
			(xy 346.987682 -335.411879) (xy 347.01256 -335.395739) (xy 347.031755 -335.373135) (xy 347.038168 -335.359756)
			(xy 347.049483 -335.335288) (xy 347.078037 -335.289568) (xy 347.112884 -335.248442) (xy 347.153294 -335.212767)
			(xy 347.198425 -335.18329) (xy 347.247333 -335.160625) (xy 347.298997 -335.145247) (xy 347.352338 -335.137476)
			(xy 347.37929 -335.136998) (xy 347.407178 -335.13746) (xy 347.462333 -335.145772) (xy 347.515632 -335.162211)
			(xy 347.565885 -335.186411) (xy 347.611971 -335.217831) (xy 347.652859 -335.255768) (xy 347.687636 -335.299376)
			(xy 347.715525 -335.34768) (xy 347.735902 -335.399601) (xy 347.748314 -335.453979) (xy 347.752483 -335.5096)
			(xy 347.748314 -335.565221) (xy 347.735902 -335.619599) (xy 347.715525 -335.67152) (xy 347.687636 -335.719824)
			(xy 347.652859 -335.763432) (xy 347.611971 -335.801369) (xy 347.565885 -335.832789) (xy 347.515632 -335.856989)
			(xy 347.462333 -335.873428) (xy 347.407178 -335.88174) (xy 347.37929 -335.882234) (xy 347.351433 -335.88172)
			(xy 347.296338 -335.873428) (xy 347.269562 -335.865724) (xy 347.255229 -335.861894) (xy 347.225578 -335.861687)
			(xy 347.197116 -335.870002) (xy 347.172239 -335.886138) (xy 347.153041 -335.908736) (xy 347.146626 -335.922112)
			(xy 347.135349 -335.946598) (xy 347.106786 -335.992315) (xy 347.071933 -336.033439) (xy 347.031516 -336.069111)
			(xy 346.986381 -336.098585) (xy 346.937469 -336.121247) (xy 346.885801 -336.136624) (xy 346.832457 -336.144393)
			(xy 346.805504 -336.14487) (xy 346.779032 -336.144405) (xy 346.726623 -336.136904) (xy 346.675801 -336.122068)
			(xy 346.627587 -336.100194) (xy 346.582951 -336.071722) (xy 346.54279 -336.037224) (xy 346.507912 -335.997393)
			(xy 346.479016 -335.95303) (xy 346.46743 -335.929224) (xy 346.46073 -335.916001) (xy 346.441097 -335.893812)
			(xy 346.415924 -335.878189) (xy 346.387326 -335.870445) (xy 346.357709 -335.871231) (xy 346.343478 -335.875376)
			(xy 346.315133 -335.884146) (xy 346.256557 -335.893581) (xy 346.226892 -335.894172) (xy 346.226638 -335.894172)
			(xy 346.199102 -335.893661) (xy 346.144631 -335.885544) (xy 346.091952 -335.869482) (xy 346.066872 -335.858104)
			(xy 346.054496 -335.852654) (xy 346.027901 -335.847814) (xy 346.000968 -335.850131) (xy 345.97559 -335.859442)
			(xy 345.953548 -335.875092) (xy 345.936392 -335.895983) (xy 345.930474 -335.908142) (xy 345.919098 -335.93237)
			(xy 345.890422 -335.977566) (xy 345.855571 -336.01819) (xy 345.815263 -336.053406) (xy 345.770329 -336.082489)
			(xy 345.721693 -336.104839) (xy 345.67036 -336.119996) (xy 345.617385 -336.127648) (xy 345.590622 -336.128106)
			(xy 345.562733 -336.127637) (xy 345.507578 -336.119326) (xy 345.454278 -336.102888) (xy 345.404023 -336.078689)
			(xy 345.357937 -336.047271) (xy 345.317048 -336.009334) (xy 345.28227 -335.965726) (xy 345.254381 -335.917422)
			(xy 345.234002 -335.8655) (xy 345.22159 -335.811121) (xy 345.217421 -335.7555) (xy 342.468635 -335.7555)
			(xy 342.362536 -335.86166) (xy 342.362282 -335.861914) (xy 342.344331 -335.879252) (xy 342.304713 -335.909603)
			(xy 342.261483 -335.934539) (xy 342.238584 -335.944464) (xy 341.573358 -336.220054) (xy 341.162132 -336.63128)
			(xy 341.85682 -336.63128) (xy 341.860891 -336.575658) (xy 341.873017 -336.521221) (xy 341.89294 -336.46913)
			(xy 341.920236 -336.420495) (xy 341.954322 -336.376352) (xy 341.994471 -336.337643) (xy 342.039829 -336.305192)
			(xy 342.089429 -336.279691) (xy 342.142213 -336.261684) (xy 342.197056 -336.251554) (xy 342.25279 -336.249517)
			(xy 342.308227 -336.255617) (xy 342.362184 -336.269723) (xy 342.413513 -336.291535) (xy 342.461119 -336.320589)
			(xy 342.503987 -336.356264) (xy 342.541204 -336.397801) (xy 342.571977 -336.444314) (xy 342.595649 -336.494811)
			(xy 342.611717 -336.548218) (xy 342.619837 -336.603394) (xy 342.620346 -336.63128) (xy 342.619837 -336.659166)
			(xy 342.611717 -336.714342) (xy 342.595649 -336.767749) (xy 342.571977 -336.818246) (xy 342.541204 -336.864759)
			(xy 342.503987 -336.906296) (xy 342.461119 -336.941971) (xy 342.413513 -336.971025) (xy 342.362184 -336.992837)
			(xy 342.308227 -337.006943) (xy 342.25279 -337.013043) (xy 342.197056 -337.011006) (xy 342.142213 -337.000876)
			(xy 342.089429 -336.982869) (xy 342.039829 -336.957368) (xy 341.994471 -336.924917) (xy 341.954322 -336.886208)
			(xy 341.920236 -336.842065) (xy 341.89294 -336.79343) (xy 341.873017 -336.741339) (xy 341.860891 -336.686902)
			(xy 341.85682 -336.63128) (xy 341.162132 -336.63128) (xy 340.440518 -337.352894) (xy 341.12911 -337.352894)
			(xy 341.133181 -337.297272) (xy 341.145307 -337.242835) (xy 341.16523 -337.190744) (xy 341.192526 -337.142109)
			(xy 341.226612 -337.097966) (xy 341.266761 -337.059257) (xy 341.312119 -337.026806) (xy 341.361719 -337.001305)
			(xy 341.414503 -336.983298) (xy 341.469346 -336.973168) (xy 341.52508 -336.971131) (xy 341.580517 -336.977231)
			(xy 341.634474 -336.991337) (xy 341.685803 -337.013149) (xy 341.733409 -337.042203) (xy 341.776277 -337.077878)
			(xy 341.813494 -337.119415) (xy 341.844267 -337.165928) (xy 341.867939 -337.216425) (xy 341.884007 -337.269832)
			(xy 341.892127 -337.325008) (xy 341.892636 -337.352894) (xy 341.892127 -337.38078) (xy 341.884007 -337.435956)
			(xy 341.867939 -337.489363) (xy 341.844267 -337.53986) (xy 341.813494 -337.586373) (xy 341.776277 -337.62791)
			(xy 341.733409 -337.663585) (xy 341.685803 -337.692639) (xy 341.634474 -337.714451) (xy 341.580517 -337.728557)
			(xy 341.52508 -337.734657) (xy 341.469346 -337.73262) (xy 341.414503 -337.72249) (xy 341.361719 -337.704483)
			(xy 341.312119 -337.678982) (xy 341.266761 -337.646531) (xy 341.226612 -337.607822) (xy 341.192526 -337.563679)
			(xy 341.16523 -337.515044) (xy 341.145307 -337.462953) (xy 341.133181 -337.408516) (xy 341.12911 -337.352894)
			(xy 340.440518 -337.352894) (xy 339.83168 -337.961732) (xy 339.810065 -337.982512) (xy 339.76156 -338.017753)
			(xy 339.708142 -338.044976) (xy 339.651124 -338.063513) (xy 339.591909 -338.072907) (xy 339.561932 -338.073492)
			(xy 337.631786 -338.073492) (xy 336.952082 -338.753196) (xy 336.930468 -338.773978) (xy 336.881964 -338.809222)
			(xy 336.828546 -338.836448) (xy 336.771528 -338.854987) (xy 336.712312 -338.864383) (xy 336.682334 -338.864956)
			(xy 334.608932 -338.864956) (xy 334.484688 -338.9892) (xy 337.069421 -338.9892) (xy 337.073589 -338.933585)
			(xy 337.085998 -338.879212) (xy 337.106372 -338.827295) (xy 337.134256 -338.778995) (xy 337.169027 -338.73539)
			(xy 337.209907 -338.697453) (xy 337.255985 -338.666033) (xy 337.306231 -338.64183) (xy 337.359523 -338.625386)
			(xy 337.41467 -338.617068) (xy 337.442556 -338.616544) (xy 337.469888 -338.617013) (xy 337.523968 -338.624982)
			(xy 337.576303 -338.64077) (xy 337.625767 -338.664039) (xy 337.6713 -338.694287) (xy 337.711922 -338.730866)
			(xy 337.746761 -338.772989) (xy 337.761326 -338.796122) (xy 337.769241 -338.808351) (xy 337.790716 -338.82802)
			(xy 337.816871 -338.840823) (xy 337.845578 -338.845717) (xy 337.874498 -338.842304) (xy 337.888072 -338.837016)
			(xy 337.911288 -338.827544) (xy 337.959618 -338.814186) (xy 338.009305 -338.807451) (xy 338.034376 -338.807044)
			(xy 338.059446 -338.807454) (xy 338.109129 -338.814209) (xy 338.157463 -338.827547) (xy 338.18068 -338.837016)
			(xy 338.194253 -338.842275) (xy 338.223156 -338.845636) (xy 338.251835 -338.840723) (xy 338.27797 -338.827931)
			(xy 338.299445 -338.808297) (xy 338.307426 -338.796122) (xy 338.321995 -338.772991) (xy 338.356838 -338.73087)
			(xy 338.397461 -338.694291) (xy 338.442992 -338.66404) (xy 338.492454 -338.640764) (xy 338.544785 -338.624964)
			(xy 338.598864 -338.616978) (xy 338.653528 -338.616978) (xy 338.707607 -338.624964) (xy 338.759938 -338.640764)
			(xy 338.8094 -338.66404) (xy 338.854931 -338.694291) (xy 338.895554 -338.73087) (xy 338.930397 -338.772991)
			(xy 338.944966 -338.796122) (xy 338.952843 -338.808379) (xy 338.974328 -338.828047) (xy 339.000494 -338.840846)
			(xy 339.029209 -338.845733) (xy 339.058136 -338.84231) (xy 339.071712 -338.837016) (xy 339.094924 -338.827531)
			(xy 339.143256 -338.814178) (xy 339.192945 -338.807448) (xy 339.218016 -338.807044) (xy 339.245655 -338.807541)
			(xy 339.300322 -338.815736) (xy 339.35318 -338.831914) (xy 339.40307 -338.85572) (xy 339.448896 -338.886633)
			(xy 339.489656 -338.923974) (xy 339.524454 -338.966925) (xy 339.552528 -339.014544) (xy 339.573262 -339.065786)
			(xy 339.58022 -339.09254) (xy 339.583825 -339.105648) (xy 339.596965 -339.129436) (xy 339.615914 -339.148918)
			(xy 339.639329 -339.162712) (xy 339.665554 -339.169842) (xy 339.69273 -339.169804) (xy 339.718934 -339.1626)
			(xy 339.730842 -339.15604) (xy 339.752985 -339.143402) (xy 339.799938 -339.123527) (xy 339.849122 -339.110092)
			(xy 339.899659 -339.103338) (xy 339.925152 -339.102954) (xy 339.93201 -339.102954) (xy 339.947094 -339.102679)
			(xy 339.976082 -339.094373) (xy 340.001392 -339.07798) (xy 340.020827 -339.054924) (xy 340.032701 -339.027205)
			(xy 340.03488 -339.012276) (xy 340.038284 -338.984522) (xy 340.052283 -338.930385) (xy 340.07403 -338.878869)
			(xy 340.103059 -338.831077) (xy 340.13875 -338.788031) (xy 340.180338 -338.750652) (xy 340.226935 -338.71974)
			(xy 340.277543 -338.695956) (xy 340.331079 -338.67981) (xy 340.386397 -338.671646) (xy 340.414356 -338.671154)
			(xy 340.441606 -338.671696) (xy 340.495552 -338.679446) (xy 340.547846 -338.694795) (xy 340.597424 -338.717429)
			(xy 340.643275 -338.746889) (xy 340.684467 -338.782575) (xy 340.720162 -338.823759) (xy 340.749631 -338.869604)
			(xy 340.772277 -338.919177) (xy 340.787636 -338.971468) (xy 340.795398 -339.025412) (xy 340.795864 -339.052662)
			(xy 340.795316 -339.082032) (xy 340.786317 -339.14008) (xy 340.768526 -339.196061) (xy 340.742363 -339.248654)
			(xy 340.708447 -339.296614) (xy 340.66758 -339.338808) (xy 340.64448 -339.356954) (xy 340.633399 -339.366027)
			(xy 340.616251 -339.388944) (xy 340.606145 -339.415722) (xy 340.603874 -339.444253) (xy 340.609619 -339.472293)
			(xy 340.622926 -339.497633) (xy 340.642749 -339.518279) (xy 340.654894 -339.525864) (xy 340.679326 -339.540649)
			(xy 340.723967 -339.576255) (xy 340.762805 -339.618116) (xy 340.794972 -339.665295) (xy 340.819752 -339.716741)
			(xy 340.836589 -339.771304) (xy 340.845109 -339.827767) (xy 340.845648 -339.856318) (xy 340.845255 -339.882212)
			(xy 340.838252 -339.933526) (xy 340.824365 -339.983418) (xy 340.803849 -340.03097) (xy 340.777082 -340.075305)
			(xy 340.744557 -340.115607) (xy 340.726014 -340.133686) (xy 340.715911 -340.143825) (xy 340.701296 -340.168419)
			(xy 340.694088 -340.196105) (xy 340.694855 -340.224704) (xy 340.703535 -340.251965) (xy 340.719447 -340.275741)
			(xy 340.730078 -340.285324) (xy 340.750901 -340.30352) (xy 340.787573 -340.344907) (xy 340.817878 -340.39116)
			(xy 340.841179 -340.441307) (xy 340.856987 -340.494296) (xy 340.864971 -340.549014) (xy 340.86546 -340.576662)
			(xy 340.865009 -340.603916) (xy 340.857256 -340.65787) (xy 340.841903 -340.710171) (xy 340.819261 -340.759754)
			(xy 340.789792 -340.80561) (xy 340.754097 -340.846804) (xy 340.712902 -340.882498) (xy 340.667045 -340.911966)
			(xy 340.617462 -340.934606) (xy 340.56516 -340.949958) (xy 340.511206 -340.95771) (xy 340.483952 -340.95817)
			(xy 340.454875 -340.957639) (xy 340.397395 -340.948821) (xy 340.341918 -340.93138) (xy 340.289732 -340.905722)
			(xy 340.242044 -340.872441) (xy 340.19996 -340.832307) (xy 340.164454 -340.786251) (xy 340.136351 -340.735339)
			(xy 340.125812 -340.708234) (xy 340.120356 -340.694656) (xy 340.102875 -340.671198) (xy 340.07946 -340.653661)
			(xy 340.052032 -340.643485) (xy 340.022844 -340.641505) (xy 340.008464 -340.644226) (xy 339.988029 -340.648495)
			(xy 339.946534 -340.653076) (xy 339.92566 -340.65337) (xy 339.925152 -340.65337) (xy 339.910936 -340.653208)
			(xy 339.882586 -340.65105) (xy 339.86851 -340.649052) (xy 339.853186 -340.647282) (xy 339.822729 -340.652112)
			(xy 339.795094 -340.665797) (xy 339.772792 -340.687094) (xy 339.757848 -340.714069) (xy 339.75421 -340.729062)
			(xy 339.747713 -340.757293) (xy 339.727473 -340.811567) (xy 339.699262 -340.862158) (xy 339.663727 -340.907903)
			(xy 339.621687 -340.947751) (xy 339.574106 -340.980787) (xy 339.522078 -341.006251) (xy 339.466799 -341.023558)
			(xy 339.409539 -341.03231) (xy 339.380576 -341.032846) (xy 339.353326 -341.032345) (xy 339.299381 -341.024586)
			(xy 339.247089 -341.00923) (xy 339.197514 -340.986588) (xy 339.151665 -340.957123) (xy 339.110476 -340.921434)
			(xy 339.074785 -340.880246) (xy 339.045318 -340.834399) (xy 339.022675 -340.784825) (xy 339.007317 -340.732533)
			(xy 338.999556 -340.678588) (xy 338.999068 -340.651338) (xy 338.999571 -340.623765) (xy 339.007517 -340.569194)
			(xy 339.023236 -340.516336) (xy 339.046399 -340.46629) (xy 339.076524 -340.420099) (xy 339.112984 -340.378726)
			(xy 339.133688 -340.360508) (xy 339.144548 -340.350571) (xy 339.160623 -340.325932) (xy 339.169012 -340.297734)
			(xy 339.169019 -340.268315) (xy 339.160644 -340.240113) (xy 339.14458 -340.215466) (xy 339.133688 -340.205568)
			(xy 339.112956 -340.18738) (xy 339.076488 -340.146006) (xy 339.046358 -340.099811) (xy 339.023196 -340.049759)
			(xy 339.007484 -339.996892) (xy 338.99955 -339.942314) (xy 338.999068 -339.914738) (xy 338.999512 -339.888237)
			(xy 339.006861 -339.835745) (xy 339.021408 -339.784778) (xy 339.042873 -339.736316) (xy 339.070842 -339.691293)
			(xy 339.08746 -339.670644) (xy 339.096904 -339.6585) (xy 339.10869 -339.630099) (xy 339.111512 -339.599479)
			(xy 339.105115 -339.569402) (xy 339.090076 -339.542581) (xy 339.067752 -339.521435) (xy 339.054186 -339.51418)
			(xy 339.0305 -339.502071) (xy 338.986517 -339.472151) (xy 338.947235 -339.436283) (xy 338.91345 -339.395194)
			(xy 338.899246 -339.372702) (xy 338.891351 -339.360457) (xy 338.869873 -339.340786) (xy 338.843711 -339.327983)
			(xy 338.814999 -339.323094) (xy 338.786075 -339.326515) (xy 338.7725 -339.331808) (xy 338.749287 -339.34129)
			(xy 338.700956 -339.354644) (xy 338.651267 -339.361375) (xy 338.626196 -339.36178) (xy 338.601127 -339.361345)
			(xy 338.551444 -339.3546) (xy 338.50311 -339.341272) (xy 338.479892 -339.331808) (xy 338.466296 -339.326615)
			(xy 338.437405 -339.323236) (xy 338.408732 -339.328134) (xy 338.3826 -339.340911) (xy 338.361126 -339.360532)
			(xy 338.353146 -339.372702) (xy 338.338577 -339.395833) (xy 338.303734 -339.437954) (xy 338.263111 -339.474533)
			(xy 338.21758 -339.504784) (xy 338.168118 -339.52806) (xy 338.115787 -339.54386) (xy 338.061708 -339.551846)
			(xy 338.007044 -339.551846) (xy 337.952965 -339.54386) (xy 337.900634 -339.52806) (xy 337.851172 -339.504784)
			(xy 337.805641 -339.474533) (xy 337.765018 -339.437954) (xy 337.730175 -339.395833) (xy 337.715606 -339.372702)
			(xy 337.707654 -339.360498) (xy 337.686191 -339.340827) (xy 337.660045 -339.328019) (xy 337.631347 -339.323119)
			(xy 337.602432 -339.326524) (xy 337.58886 -339.331808) (xy 337.565652 -339.341303) (xy 337.517318 -339.354652)
			(xy 337.467628 -339.361378) (xy 337.442556 -339.36178) (xy 337.41467 -339.361332) (xy 337.359523 -339.353014)
			(xy 337.306231 -339.33657) (xy 337.255985 -339.312367) (xy 337.209907 -339.280947) (xy 337.169027 -339.24301)
			(xy 337.134256 -339.199405) (xy 337.106372 -339.151105) (xy 337.085998 -339.099188) (xy 337.073589 -339.044815)
			(xy 337.069421 -338.9892) (xy 334.484688 -338.9892) (xy 334.242156 -339.231732) (xy 334.224206 -339.249072)
			(xy 334.18459 -339.279426) (xy 334.14136 -339.304365) (xy 334.118458 -339.314282) (xy 333.609442 -339.525102)
			(xy 333.215234 -339.919056) (xy 333.124437 -340.054946) (xy 333.611726 -340.054946) (xy 333.615797 -339.999324)
			(xy 333.627923 -339.944887) (xy 333.647846 -339.892796) (xy 333.675142 -339.844161) (xy 333.709228 -339.800018)
			(xy 333.749377 -339.761309) (xy 333.794735 -339.728858) (xy 333.844335 -339.703357) (xy 333.897119 -339.68535)
			(xy 333.951962 -339.67522) (xy 334.007696 -339.673183) (xy 334.063133 -339.679283) (xy 334.11709 -339.693389)
			(xy 334.168419 -339.715201) (xy 334.216025 -339.744255) (xy 334.258893 -339.77993) (xy 334.29611 -339.821467)
			(xy 334.326883 -339.86798) (xy 334.350555 -339.918477) (xy 334.366623 -339.971884) (xy 334.374743 -340.02706)
			(xy 334.375252 -340.054946) (xy 334.374743 -340.082832) (xy 334.366623 -340.138008) (xy 334.350555 -340.191415)
			(xy 334.326883 -340.241912) (xy 334.29611 -340.288425) (xy 334.258893 -340.329962) (xy 334.216025 -340.365637)
			(xy 334.168419 -340.394691) (xy 334.11709 -340.416503) (xy 334.063133 -340.430609) (xy 334.007696 -340.436709)
			(xy 333.951962 -340.434672) (xy 333.897119 -340.424542) (xy 333.844335 -340.406535) (xy 333.794735 -340.381034)
			(xy 333.749377 -340.348583) (xy 333.709228 -340.309874) (xy 333.675142 -340.265731) (xy 333.647846 -340.217096)
			(xy 333.627923 -340.165005) (xy 333.615797 -340.110568) (xy 333.611726 -340.054946) (xy 333.124437 -340.054946)
			(xy 333.064358 -340.144862) (xy 332.760828 -340.599014) (xy 332.760828 -341.013288) (xy 333.031082 -341.013288)
			(xy 333.035153 -340.957666) (xy 333.047279 -340.903229) (xy 333.067202 -340.851138) (xy 333.094498 -340.802503)
			(xy 333.128584 -340.75836) (xy 333.168733 -340.719651) (xy 333.214091 -340.6872) (xy 333.263691 -340.661699)
			(xy 333.316475 -340.643692) (xy 333.371318 -340.633562) (xy 333.427052 -340.631525) (xy 333.482489 -340.637625)
			(xy 333.536446 -340.651731) (xy 333.587775 -340.673543) (xy 333.635381 -340.702597) (xy 333.678249 -340.738272)
			(xy 333.715466 -340.779809) (xy 333.746239 -340.826322) (xy 333.769911 -340.876819) (xy 333.785979 -340.930226)
			(xy 333.794099 -340.985402) (xy 333.794608 -341.013288) (xy 333.794099 -341.041174) (xy 333.785979 -341.09635)
			(xy 333.769911 -341.149757) (xy 333.746239 -341.200254) (xy 333.715466 -341.246767) (xy 333.678249 -341.288304)
			(xy 333.635381 -341.323979) (xy 333.587775 -341.353033) (xy 333.536446 -341.374845) (xy 333.482489 -341.388951)
			(xy 333.427052 -341.395051) (xy 333.371318 -341.393014) (xy 333.316475 -341.382884) (xy 333.263691 -341.364877)
			(xy 333.214091 -341.339376) (xy 333.168733 -341.306925) (xy 333.128584 -341.268216) (xy 333.094498 -341.224073)
			(xy 333.067202 -341.175438) (xy 333.047279 -341.123347) (xy 333.035153 -341.06891) (xy 333.031082 -341.013288)
			(xy 332.760828 -341.013288) (xy 332.760828 -342.971374) (xy 332.760272 -343.001355) (xy 332.750892 -343.060578)
			(xy 332.732359 -343.117604) (xy 332.705129 -343.171026) (xy 332.669874 -343.219528) (xy 332.649068 -343.241122)
			(xy 332.080108 -343.810082) (xy 332.058531 -343.830817) (xy 332.010114 -343.865977) (xy 331.956795 -343.893136)
			(xy 331.899886 -343.911626) (xy 331.840787 -343.920991) (xy 331.810868 -343.921588) (xy 329.748896 -343.921588)
			(xy 329.361292 -344.309446) (xy 329.350961 -344.320647) (xy 329.33681 -344.347614) (xy 329.331232 -344.377554)
			(xy 329.334721 -344.407808) (xy 329.346967 -344.435692) (xy 329.366884 -344.458731) (xy 329.392704 -344.47488)
			(xy 329.407266 -344.479372) (xy 329.434872 -344.487176) (xy 329.487461 -344.510092) (xy 329.535917 -344.540796)
			(xy 329.579097 -344.578563) (xy 329.615979 -344.6225) (xy 329.631294 -344.646758) (xy 329.639277 -344.658928)
			(xy 329.660754 -344.678549) (xy 329.686886 -344.691331) (xy 329.71556 -344.696238) (xy 329.744455 -344.692874)
			(xy 329.75804 -344.687652) (xy 329.781257 -344.678186) (xy 329.829592 -344.664853) (xy 329.879275 -344.658101)
			(xy 329.904344 -344.65768) (xy 329.929416 -344.658081) (xy 329.979107 -344.664805) (xy 330.027442 -344.678152)
			(xy 330.050648 -344.687652) (xy 330.06422 -344.692939) (xy 330.093135 -344.696349) (xy 330.121836 -344.69145)
			(xy 330.147982 -344.67864) (xy 330.169444 -344.658964) (xy 330.177394 -344.646758) (xy 330.191963 -344.623627)
			(xy 330.226806 -344.581506) (xy 330.267429 -344.544927) (xy 330.31296 -344.514676) (xy 330.362422 -344.4914)
			(xy 330.414753 -344.4756) (xy 330.468832 -344.467614) (xy 330.523496 -344.467614) (xy 330.577575 -344.4756)
			(xy 330.629906 -344.4914) (xy 330.679368 -344.514676) (xy 330.724899 -344.544927) (xy 330.765522 -344.581506)
			(xy 330.800365 -344.623627) (xy 330.814934 -344.646758) (xy 330.822918 -344.658923) (xy 330.844394 -344.678536)
			(xy 330.870524 -344.691307) (xy 330.899193 -344.696205) (xy 330.928081 -344.692832) (xy 330.94168 -344.687652)
			(xy 330.967751 -344.677101) (xy 331.022215 -344.663075) (xy 331.050138 -344.659712) (xy 331.055472 -344.65895)
			(xy 331.087984 -344.657426) (xy 331.116484 -344.657967) (xy 331.172818 -344.666646) (xy 331.227173 -344.683805)
			(xy 331.27828 -344.709043) (xy 331.324947 -344.74177) (xy 331.366084 -344.781224) (xy 331.400732 -344.826484)
			(xy 331.414882 -344.851228) (xy 331.428598 -344.878914) (xy 331.434644 -344.891366) (xy 331.45227 -344.912694)
			(xy 331.474983 -344.928496) (xy 331.501109 -344.937608) (xy 331.528722 -344.939357) (xy 331.555789 -344.933615)
			(xy 331.568298 -344.927682) (xy 331.595677 -344.914102) (xy 331.653686 -344.89487) (xy 331.714017 -344.885128)
			(xy 331.744574 -344.884502) (xy 331.744828 -344.884502) (xy 331.767071 -344.884859) (xy 331.811252 -344.89008)
			(xy 331.832966 -344.894916) (xy 331.845763 -344.898023) (xy 331.870932 -344.905775) (xy 331.883258 -344.91041)
			(xy 331.88402 -344.910664) (xy 331.897521 -344.914739) (xy 331.925678 -344.916105) (xy 331.953136 -344.90972)
			(xy 331.977801 -344.896072) (xy 331.997796 -344.876199) (xy 332.011595 -344.851617) (xy 332.015338 -344.83802)
			(xy 332.021895 -344.809932) (xy 332.042328 -344.755996) (xy 332.070648 -344.705751) (xy 332.106211 -344.660343)
			(xy 332.148205 -344.620807) (xy 332.195673 -344.588044) (xy 332.247533 -344.562802) (xy 332.302602 -344.545656)
			(xy 332.359625 -344.536996) (xy 332.388464 -344.536522) (xy 332.415718 -344.536983) (xy 332.469671 -344.544736)
			(xy 332.521971 -344.560089) (xy 332.571554 -344.58273) (xy 332.61741 -344.612197) (xy 332.658604 -344.647892)
			(xy 332.694299 -344.689086) (xy 332.723767 -344.734941) (xy 332.746409 -344.784523) (xy 332.761763 -344.836823)
			(xy 332.769517 -344.890776) (xy 332.769972 -344.91803) (xy 332.769485 -344.945598) (xy 332.761547 -345.000161)
			(xy 332.74584 -345.053014) (xy 332.722692 -345.103056) (xy 332.692583 -345.149247) (xy 332.674722 -345.170252)
			(xy 332.665969 -345.181443) (xy 332.654441 -345.207398) (xy 332.650502 -345.235523) (xy 332.654454 -345.263647)
			(xy 332.665993 -345.289596) (xy 332.674722 -345.300808) (xy 332.692587 -345.321812) (xy 332.722711 -345.367997)
			(xy 332.745869 -345.418039) (xy 332.76158 -345.470893) (xy 332.769517 -345.52546) (xy 332.769972 -345.55303)
			(xy 332.769483 -345.580603) (xy 332.761536 -345.635172) (xy 332.745813 -345.688029) (xy 332.722641 -345.738069)
			(xy 332.692503 -345.784251) (xy 332.656028 -345.82561) (xy 332.635352 -345.84386) (xy 332.624455 -345.853756)
			(xy 332.608383 -345.878403) (xy 332.600002 -345.906607) (xy 332.600008 -345.936031) (xy 332.6084 -345.964233)
			(xy 332.624481 -345.988873) (xy 332.635352 -345.9988) (xy 332.656059 -346.017016) (xy 332.692525 -346.058387)
			(xy 332.722656 -346.104577) (xy 332.745824 -346.154623) (xy 332.761547 -346.207483) (xy 332.769495 -346.262056)
			(xy 332.769972 -346.28963) (xy 332.769507 -346.316881) (xy 332.761746 -346.370826) (xy 332.746387 -346.423118)
			(xy 332.723742 -346.472693) (xy 332.694273 -346.518539) (xy 332.658579 -346.559725) (xy 332.617386 -346.595412)
			(xy 332.571535 -346.624874) (xy 332.521957 -346.64751) (xy 332.469662 -346.66286) (xy 332.415715 -346.670611)
			(xy 332.388464 -346.671138) (xy 332.360516 -346.670647) (xy 332.305218 -346.662488) (xy 332.251701 -346.64635)
			(xy 332.201111 -346.622579) (xy 332.15453 -346.591682) (xy 332.112953 -346.554321) (xy 332.077271 -346.511295)
			(xy 332.048247 -346.463524) (xy 332.036928 -346.437966) (xy 332.030168 -346.423989) (xy 332.009709 -346.400654)
			(xy 331.983189 -346.384537) (xy 331.953054 -346.377125) (xy 331.922084 -346.379101) (xy 331.907388 -346.384118)
			(xy 331.885471 -346.392166) (xy 331.84017 -346.403471) (xy 331.793827 -346.40916) (xy 331.770482 -346.409518)
			(xy 331.770228 -346.409518) (xy 331.75608 -346.409415) (xy 331.727856 -346.407384) (xy 331.71384 -346.405454)
			(xy 331.700494 -346.403884) (xy 331.673813 -346.407004) (xy 331.648871 -346.416979) (xy 331.627397 -346.433119)
			(xy 331.61088 -346.454303) (xy 331.600464 -346.479065) (xy 331.59827 -346.492322) (xy 331.594181 -346.519479)
			(xy 331.57922 -346.572319) (xy 331.556837 -346.622467) (xy 331.527494 -346.668888) (xy 331.491799 -346.710622)
			(xy 331.450488 -346.746806) (xy 331.404415 -346.776692) (xy 331.354533 -346.799664) (xy 331.301873 -346.815245)
			(xy 331.247523 -346.823115) (xy 331.220064 -346.823538) (xy 331.192814 -346.82305) (xy 331.138868 -346.815289)
			(xy 331.086576 -346.799931) (xy 331.037001 -346.777289) (xy 330.991153 -346.747822) (xy 330.949965 -346.712131)
			(xy 330.914275 -346.670942) (xy 330.884809 -346.625093) (xy 330.862167 -346.575518) (xy 330.846809 -346.523226)
			(xy 330.83905 -346.46928) (xy 330.838556 -346.44203) (xy 330.839041 -346.414455) (xy 330.846979 -346.359879)
			(xy 330.862693 -346.307015) (xy 330.885858 -346.256965) (xy 330.915988 -346.210774) (xy 330.952457 -346.169402)
			(xy 330.973176 -346.1512) (xy 330.984079 -346.141302) (xy 331.000163 -346.11665) (xy 331.008556 -346.088437)
			(xy 331.008562 -346.059002) (xy 331.00018 -346.030785) (xy 330.984105 -346.006127) (xy 330.973176 -345.99626)
			(xy 330.952546 -345.978119) (xy 330.916198 -345.936926) (xy 330.886134 -345.890946) (xy 330.862975 -345.84113)
			(xy 330.847201 -345.788507) (xy 330.839136 -345.734166) (xy 330.838556 -345.7067) (xy 330.838556 -345.702128)
			(xy 330.839064 -345.684094) (xy 330.84101 -345.657636) (xy 330.851291 -345.60559) (xy 330.86867 -345.555466)
			(xy 330.892814 -345.508226) (xy 330.907644 -345.486228) (xy 330.90866 -345.484704) (xy 330.908914 -345.48445)
			(xy 330.916413 -345.473192) (xy 330.925758 -345.447816) (xy 330.928099 -345.420876) (xy 330.923273 -345.394269)
			(xy 330.911619 -345.369868) (xy 330.893958 -345.349391) (xy 330.883006 -345.341448) (xy 330.882244 -345.34094)
			(xy 330.859655 -345.325389) (xy 330.818862 -345.288739) (xy 330.783857 -345.246525) (xy 330.769214 -345.223338)
			(xy 330.76642 -345.21902) (xy 330.766166 -345.218766) (xy 330.758414 -345.208147) (xy 330.738548 -345.19094)
			(xy 330.714957 -345.179357) (xy 330.702158 -345.176348) (xy 330.687091 -345.17383) (xy 330.656713 -345.176927)
			(xy 330.642468 -345.182444) (xy 330.619251 -345.191911) (xy 330.570917 -345.205245) (xy 330.521233 -345.211998)
			(xy 330.496164 -345.212416) (xy 330.471092 -345.212015) (xy 330.4214 -345.205292) (xy 330.373065 -345.191947)
			(xy 330.34986 -345.182444) (xy 330.336288 -345.177156) (xy 330.307371 -345.173743) (xy 330.278668 -345.178641)
			(xy 330.252519 -345.19145) (xy 330.231056 -345.211126) (xy 330.223114 -345.223338) (xy 330.208545 -345.246469)
			(xy 330.173702 -345.28859) (xy 330.133079 -345.325169) (xy 330.087548 -345.35542) (xy 330.038086 -345.378696)
			(xy 329.985755 -345.394496) (xy 329.931676 -345.402482) (xy 329.877012 -345.402482) (xy 329.822933 -345.394496)
			(xy 329.770602 -345.378696) (xy 329.72114 -345.35542) (xy 329.675609 -345.325169) (xy 329.634986 -345.28859)
			(xy 329.600143 -345.246469) (xy 329.585574 -345.223338) (xy 329.57759 -345.211172) (xy 329.556113 -345.191559)
			(xy 329.529983 -345.178786) (xy 329.501314 -345.173886) (xy 329.472425 -345.177257) (xy 329.458828 -345.182444)
			(xy 329.43561 -345.191908) (xy 329.387276 -345.205238) (xy 329.337593 -345.211985) (xy 329.312524 -345.212416)
			(xy 329.285905 -345.211965) (xy 329.233209 -345.204392) (xy 329.182127 -345.189396) (xy 329.133699 -345.167282)
			(xy 329.088912 -345.138502) (xy 329.048676 -345.10364) (xy 329.013812 -345.063406) (xy 328.985028 -345.01862)
			(xy 328.962912 -344.970194) (xy 328.947913 -344.919113) (xy 328.940336 -344.866417) (xy 328.939906 -344.839798)
			(xy 328.940338 -344.814642) (xy 328.947138 -344.764791) (xy 328.960574 -344.716306) (xy 328.980403 -344.670065)
			(xy 328.992992 -344.648282) (xy 328.998167 -344.638669) (xy 329.000651 -344.616999) (xy 328.993944 -344.596245)
			(xy 328.979249 -344.580127) (xy 328.959201 -344.571537) (xy 328.948288 -344.57132) (xy 326.27189 -344.57132)
			(xy 326.241974 -344.570713) (xy 326.182883 -344.561325) (xy 326.125981 -344.542827) (xy 326.072665 -344.515674)
			(xy 326.024241 -344.480531) (xy 326.00265 -344.459814) (xy 325.726552 -344.183716) (xy 325.406258 -344.183716)
			(xy 325.392459 -344.184171) (xy 325.365869 -344.191564) (xy 325.34224 -344.205824) (xy 325.323307 -344.225903)
			(xy 325.310458 -344.250328) (xy 325.304638 -344.277306) (xy 325.306274 -344.304856) (xy 325.310246 -344.318082)
			(xy 325.310754 -344.320114) (xy 325.320501 -344.34973) (xy 325.331346 -344.411125) (xy 325.332344 -344.442288)
			(xy 325.332344 -344.45067) (xy 325.331582 -344.47773) (xy 325.323358 -344.531234) (xy 325.307653 -344.583038)
			(xy 325.284781 -344.632102) (xy 325.255204 -344.67744) (xy 325.219514 -344.718141) (xy 325.178429 -344.753388)
			(xy 325.132773 -344.782472) (xy 325.083464 -344.80481) (xy 325.031493 -344.819953) (xy 324.977902 -344.827597)
			(xy 324.950836 -344.828114) (xy 324.923581 -344.827653) (xy 324.869626 -344.8199) (xy 324.817324 -344.804547)
			(xy 324.767739 -344.781907) (xy 324.721881 -344.75244) (xy 324.680683 -344.716747) (xy 324.644985 -344.675553)
			(xy 324.615513 -344.629698) (xy 324.592867 -344.580116) (xy 324.577509 -344.527815) (xy 324.56975 -344.473861)
			(xy 324.569328 -344.446606) (xy 324.569909 -344.416705) (xy 324.579235 -344.357636) (xy 324.597659 -344.300743)
			(xy 324.624731 -344.24742) (xy 324.659787 -344.198972) (xy 324.701971 -344.156585) (xy 324.725792 -344.138504)
			(xy 324.736855 -344.129135) (xy 324.753665 -344.105535) (xy 324.763182 -344.078166) (xy 324.764641 -344.049227)
			(xy 324.757924 -344.021041) (xy 324.751192 -344.008202) (xy 324.737578 -343.986147) (xy 324.715791 -343.939119)
			(xy 324.707758 -343.914476) (xy 324.69981 -343.887092) (xy 324.691263 -343.830717) (xy 324.69074 -343.802208)
			(xy 324.691203 -343.774956) (xy 324.698959 -343.721007) (xy 324.714315 -343.668711) (xy 324.736958 -343.619133)
			(xy 324.766426 -343.573282) (xy 324.802121 -343.532092) (xy 324.843314 -343.496402) (xy 324.889168 -343.466938)
			(xy 324.938748 -343.444301) (xy 324.991046 -343.428951) (xy 325.044996 -343.4212) (xy 325.072248 -343.4207)
			(xy 325.88454 -343.4207) (xy 325.914522 -343.421254) (xy 325.973747 -343.43063) (xy 326.030775 -343.44916)
			(xy 326.0842 -343.476389) (xy 326.132704 -343.511643) (xy 326.154288 -343.53246) (xy 326.24014 -343.618312)
			(xy 326.430386 -343.808812) (xy 328.783188 -343.808812) (xy 329.32116 -343.270586) (xy 329.342737 -343.249851)
			(xy 329.391154 -343.214689) (xy 329.444472 -343.187528) (xy 329.501381 -343.169035) (xy 329.560481 -343.159666)
			(xy 329.5904 -343.15908) (xy 331.652372 -343.15908) (xy 331.997812 -342.813386) (xy 331.997812 -340.482936)
			(xy 331.998332 -340.454806) (xy 332.006625 -340.39916) (xy 332.022992 -340.345333) (xy 332.04708 -340.29449)
			(xy 332.062328 -340.270846) (xy 332.602078 -339.463888) (xy 332.612635 -339.448489) (xy 332.636301 -339.41961)
			(xy 332.649322 -339.40623) (xy 332.999588 -339.055964) (xy 333.009636 -339.045252) (xy 333.02366 -339.019461)
			(xy 333.029764 -338.990745) (xy 333.027442 -338.961479) (xy 333.016888 -338.934085) (xy 332.998973 -338.910827)
			(xy 332.987396 -338.901786) (xy 332.965746 -338.886478) (xy 332.92649 -338.850836) (xy 332.892547 -338.810102)
			(xy 332.864571 -338.765061) (xy 332.843101 -338.71658) (xy 332.82855 -338.665593) (xy 332.821199 -338.613083)
			(xy 332.820772 -338.586572) (xy 332.821259 -338.559004) (xy 332.829198 -338.504442) (xy 332.844906 -338.45159)
			(xy 332.868056 -338.401549) (xy 332.898167 -338.35536) (xy 332.916022 -338.33435) (xy 332.924892 -338.322994)
			(xy 332.936495 -338.296634) (xy 332.940274 -338.268082) (xy 332.935927 -338.239611) (xy 332.9238 -338.213487)
			(xy 332.914752 -338.20227) (xy 332.89711 -338.181339) (xy 332.867383 -338.135373) (xy 332.844541 -338.085626)
			(xy 332.829052 -338.033122) (xy 332.821237 -337.978942) (xy 332.820772 -337.951572) (xy 332.82126 -337.924322)
			(xy 332.829019 -337.870376) (xy 332.844377 -337.818083) (xy 332.867019 -337.768508) (xy 332.896486 -337.72266)
			(xy 332.932177 -337.681471) (xy 332.973366 -337.645781) (xy 333.019215 -337.616315) (xy 333.068791 -337.593674)
			(xy 333.121084 -337.578318) (xy 333.17503 -337.570559) (xy 333.20228 -337.570064) (xy 333.99476 -337.570064)
			(xy 334.024741 -337.570619) (xy 334.083966 -337.579997) (xy 334.140993 -337.598528) (xy 334.194417 -337.625756)
			(xy 334.242922 -337.66101) (xy 334.264508 -337.681824) (xy 334.684624 -338.10194) (xy 336.524346 -338.10194)
			(xy 337.20405 -337.422236) (xy 337.225663 -337.401454) (xy 337.274168 -337.366212) (xy 337.327586 -337.338987)
			(xy 337.384605 -337.320451) (xy 337.44382 -337.31106) (xy 337.473798 -337.310476) (xy 339.403944 -337.310476)
			(xy 341.087456 -335.626964) (xy 341.101426 -335.613756) (xy 341.10676 -335.60893) (xy 341.116586 -335.599327)
			(xy 341.131162 -335.576051) (xy 341.138993 -335.549727) (xy 341.139509 -335.522268) (xy 341.132673 -335.495668)
			(xy 341.118982 -335.471861) (xy 341.109554 -335.461864) (xy 341.089753 -335.44367) (xy 341.054951 -335.402678)
			(xy 341.026249 -335.357207) (xy 341.004214 -335.308156) (xy 340.989283 -335.256497) (xy 340.981753 -335.203255)
			(xy 340.981284 -335.176368) (xy 340.981772 -335.1488) (xy 340.989711 -335.094238) (xy 341.00542 -335.041387)
			(xy 341.028571 -334.991347) (xy 341.058682 -334.945159) (xy 341.076534 -334.924146) (xy 341.085424 -334.912793)
			(xy 341.097064 -334.886425) (xy 341.100869 -334.857855) (xy 341.096536 -334.82936) (xy 341.084409 -334.803212)
			(xy 341.075264 -334.792066) (xy 341.070946 -334.78724) (xy 341.068914 -334.7847) (xy 341.052435 -334.764076)
			(xy 341.024713 -334.71915) (xy 341.003443 -334.670834) (xy 340.98903 -334.620049) (xy 340.98175 -334.567763)
			(xy 340.981284 -334.541368) (xy 340.981363 -334.52863) (xy 340.983019 -334.503209) (xy 340.984586 -334.490568)
			(xy 340.988707 -334.463441) (xy 341.003723 -334.410668) (xy 341.026145 -334.360591) (xy 341.055512 -334.314244)
			(xy 341.091216 -334.272583) (xy 341.132523 -334.236469) (xy 341.178577 -334.206646) (xy 341.22843 -334.18373)
			(xy 341.281053 -334.168195) (xy 341.335358 -334.16036) (xy 341.362792 -334.15986) (xy 342.155272 -334.15986)
			(xy 342.185253 -334.160416) (xy 342.244477 -334.169795) (xy 342.301503 -334.188328) (xy 342.354926 -334.215557)
			(xy 342.403429 -334.250811) (xy 342.42502 -334.27162) (xy 342.543892 -334.390492) (xy 342.80729 -334.654144)
			(xy 344.505026 -334.654144) (xy 344.978482 -334.457802) (xy 345.375738 -334.060546) (xy 345.397313 -334.039807)
			(xy 345.445728 -334.004637) (xy 345.499046 -333.977468) (xy 345.555956 -333.958969) (xy 345.615058 -333.949595)
			(xy 345.644978 -333.94904) (xy 349.312738 -333.94904) (xy 349.342653 -333.949649) (xy 349.401743 -333.95904)
			(xy 349.458643 -333.97754) (xy 349.511958 -334.004693) (xy 349.560382 -334.039836) (xy 349.581978 -334.060546)
			(xy 349.681292 -334.15986) (xy 350.152716 -334.15986) (xy 350.182696 -334.160419) (xy 350.241916 -334.169805)
			(xy 350.298938 -334.188343) (xy 350.352356 -334.215575) (xy 350.400854 -334.250832) (xy 350.422464 -334.27162)
			(xy 350.731328 -334.580484) (xy 352.973386 -334.580484) (xy 353.28225 -334.27162) (xy 353.303864 -334.250839)
			(xy 353.352368 -334.215598) (xy 353.405787 -334.188375) (xy 353.462805 -334.16984) (xy 353.522021 -334.160449)
			(xy 353.551998 -334.15986) (xy 358.268016 -334.15986) (xy 358.297996 -334.160419) (xy 358.357216 -334.169805)
			(xy 358.414238 -334.188343) (xy 358.467656 -334.215575) (xy 358.516154 -334.250832) (xy 358.537764 -334.27162)
			(xy 358.656636 -334.390492) (xy 358.920034 -334.654144) (xy 361.047538 -334.654144) (xy 361.483402 -334.218026)
			(xy 361.504979 -334.197292) (xy 361.553396 -334.162132) (xy 361.606715 -334.134973) (xy 361.663624 -334.116485)
			(xy 361.722724 -334.107121) (xy 361.752642 -334.10652) (xy 365.791242 -334.10652) (xy 365.819199 -334.107028)
			(xy 365.874508 -334.115227) (xy 365.928028 -334.131414) (xy 365.978611 -334.155243) (xy 366.025172 -334.186201)
			(xy 366.046258 -334.204564) (xy 366.05337 -334.21066) (xy 366.598454 -334.21066) (xy 366.624436 -334.211156)
			(xy 366.675755 -334.219316) (xy 366.725163 -334.235409) (xy 366.771443 -334.25904) (xy 366.813452 -334.289625)
			(xy 366.832134 -334.307688) (xy 366.90554 -334.381348) (xy 367.376202 -334.85201) (xy 367.394223 -334.870715)
			(xy 367.424749 -334.912737) (xy 367.448323 -334.959019) (xy 367.464365 -335.008419) (xy 367.472479 -335.05972)
			(xy 367.472976 -335.08569) (xy 367.472976 -335.579) (xy 369.711391 -335.579) (xy 369.71556 -335.523376)
			(xy 369.727972 -335.468994) (xy 369.748351 -335.41707) (xy 369.776242 -335.368763) (xy 369.81102 -335.325152)
			(xy 369.85191 -335.287212) (xy 369.897998 -335.255791) (xy 369.948254 -335.231589) (xy 370.001557 -335.215148)
			(xy 370.056714 -335.206835) (xy 370.084604 -335.20634) (xy 370.111937 -335.206773) (xy 370.166019 -335.214749)
			(xy 370.218354 -335.230543) (xy 370.267819 -335.253818) (xy 370.313351 -335.284071) (xy 370.353972 -335.320655)
			(xy 370.38881 -335.362783) (xy 370.403374 -335.385918) (xy 370.41134 -335.398111) (xy 370.4328 -335.41778)
			(xy 370.458942 -335.430588) (xy 370.487637 -335.435491) (xy 370.516548 -335.432092) (xy 370.53012 -335.426812)
			(xy 370.553331 -335.417325) (xy 370.601663 -335.403973) (xy 370.651352 -335.397244) (xy 370.676424 -335.39684)
			(xy 370.701493 -335.397267) (xy 370.751176 -335.404015) (xy 370.799511 -335.417346) (xy 370.822728 -335.426812)
			(xy 370.836319 -335.432017) (xy 370.865212 -335.435391) (xy 370.893886 -335.430489) (xy 370.920018 -335.41771)
			(xy 370.941493 -335.398088) (xy 370.949474 -335.385918) (xy 370.964043 -335.362787) (xy 370.998886 -335.320666)
			(xy 371.039509 -335.284087) (xy 371.08504 -335.253836) (xy 371.134502 -335.23056) (xy 371.186833 -335.21476)
			(xy 371.240912 -335.206774) (xy 371.295576 -335.206774) (xy 371.349655 -335.21476) (xy 371.401986 -335.23056)
			(xy 371.451448 -335.253836) (xy 371.496979 -335.284087) (xy 371.537602 -335.320666) (xy 371.572445 -335.362787)
			(xy 371.587014 -335.385918) (xy 371.594942 -335.398139) (xy 371.616413 -335.417808) (xy 371.642565 -335.430612)
			(xy 371.671268 -335.435508) (xy 371.700186 -335.432098) (xy 371.71376 -335.426812) (xy 371.736966 -335.417312)
			(xy 371.785301 -335.403965) (xy 371.834992 -335.397241) (xy 371.860064 -335.39684) (xy 371.887949 -335.397417)
			(xy 371.943098 -335.405724) (xy 371.996392 -335.422159) (xy 372.046641 -335.446353) (xy 372.092723 -335.477767)
			(xy 372.133608 -335.515699) (xy 372.168382 -335.5593) (xy 372.196269 -335.607598) (xy 372.216645 -335.659513)
			(xy 372.229056 -335.713885) (xy 372.233224 -335.7695) (xy 372.229056 -335.825115) (xy 372.216645 -335.879487)
			(xy 372.196269 -335.931402) (xy 372.168382 -335.9797) (xy 372.133608 -336.023301) (xy 372.092723 -336.061233)
			(xy 372.046641 -336.092647) (xy 371.996392 -336.116841) (xy 371.943098 -336.133276) (xy 371.887949 -336.141583)
			(xy 371.860064 -336.142076) (xy 371.832733 -336.141582) (xy 371.778654 -336.133616) (xy 371.726321 -336.117831)
			(xy 371.676857 -336.094567) (xy 371.631324 -336.064323) (xy 371.590701 -336.027748) (xy 371.55586 -335.985629)
			(xy 371.541294 -335.962498) (xy 371.533355 -335.950285) (xy 371.511888 -335.930614) (xy 371.485739 -335.917808)
			(xy 371.457037 -335.91291) (xy 371.428121 -335.916318) (xy 371.414548 -335.921604) (xy 371.391341 -335.931102)
			(xy 371.343007 -335.94445) (xy 371.293316 -335.951174) (xy 371.268244 -335.951576) (xy 371.243174 -335.951158)
			(xy 371.193491 -335.944406) (xy 371.145157 -335.931071) (xy 371.12194 -335.921604) (xy 371.108362 -335.916358)
			(xy 371.079462 -335.912991) (xy 371.050783 -335.917901) (xy 371.024648 -335.93069) (xy 371.003174 -335.950323)
			(xy 370.995194 -335.962498) (xy 370.980625 -335.985629) (xy 370.945782 -336.02775) (xy 370.905159 -336.064329)
			(xy 370.859628 -336.09458) (xy 370.810166 -336.117856) (xy 370.757835 -336.133656) (xy 370.703756 -336.141642)
			(xy 370.649092 -336.141642) (xy 370.595013 -336.133656) (xy 370.542682 -336.117856) (xy 370.49322 -336.09458)
			(xy 370.447689 -336.064329) (xy 370.407066 -336.02775) (xy 370.372223 -335.985629) (xy 370.357654 -335.962498)
			(xy 370.349753 -335.950258) (xy 370.328276 -335.930587) (xy 370.302116 -335.917784) (xy 370.273406 -335.912893)
			(xy 370.244483 -335.916312) (xy 370.230908 -335.921604) (xy 370.207694 -335.931084) (xy 370.159363 -335.944438)
			(xy 370.109675 -335.95117) (xy 370.084604 -335.951576) (xy 370.056714 -335.951165) (xy 370.001557 -335.942852)
			(xy 369.948254 -335.926411) (xy 369.897998 -335.902209) (xy 369.85191 -335.870788) (xy 369.81102 -335.832848)
			(xy 369.776242 -335.789237) (xy 369.748351 -335.74093) (xy 369.727972 -335.689006) (xy 369.71556 -335.634624)
			(xy 369.711391 -335.579) (xy 367.472976 -335.579) (xy 367.472976 -335.64449) (xy 367.81613 -335.987644)
			(xy 368.416078 -336.236056) (xy 369.489228 -336.236056) (xy 369.515195 -336.236567) (xy 369.56649 -336.244694)
			(xy 369.615882 -336.260742) (xy 369.662157 -336.284318) (xy 369.704175 -336.31484) (xy 369.722908 -336.33283)
			(xy 370.872881 -337.482688) (xy 371.647212 -337.482688) (xy 371.647734 -337.455115) (xy 371.655675 -337.400545)
			(xy 371.671388 -337.347686) (xy 371.694547 -337.29764) (xy 371.72467 -337.251449) (xy 371.761129 -337.210075)
			(xy 371.781832 -337.191858) (xy 371.792738 -337.18197) (xy 371.808804 -337.157315) (xy 371.817183 -337.129106)
			(xy 371.817181 -337.099679) (xy 371.808798 -337.071471) (xy 371.792728 -337.046819) (xy 371.781832 -337.036918)
			(xy 371.761133 -337.018694) (xy 371.72466 -336.977329) (xy 371.694526 -336.931142) (xy 371.671358 -336.881096)
			(xy 371.655639 -336.828235) (xy 371.647698 -336.773662) (xy 371.647212 -336.746088) (xy 371.647644 -336.718834)
			(xy 371.655403 -336.664881) (xy 371.670761 -336.612581) (xy 371.693407 -336.562999) (xy 371.722878 -336.517145)
			(xy 371.758575 -336.475952) (xy 371.799771 -336.440259) (xy 371.845628 -336.410791) (xy 371.895211 -336.38815)
			(xy 371.947512 -336.372796) (xy 372.001466 -336.365041) (xy 372.02872 -336.36458) (xy 372.029482 -336.36458)
			(xy 372.041453 -336.364696) (xy 372.065346 -336.366219) (xy 372.077234 -336.367628) (xy 372.090996 -336.368863)
			(xy 372.118323 -336.364892) (xy 372.143589 -336.353747) (xy 372.164947 -336.336242) (xy 372.180837 -336.313657)
			(xy 372.190098 -336.287642) (xy 372.191534 -336.273902) (xy 372.194089 -336.24537) (xy 372.206571 -336.189465)
			(xy 372.227274 -336.136055) (xy 372.255732 -336.086344) (xy 372.291306 -336.041447) (xy 372.333195 -336.002377)
			(xy 372.380457 -335.970012) (xy 372.432028 -335.945079) (xy 372.486747 -335.92814) (xy 372.543385 -335.919577)
			(xy 372.572026 -335.919064) (xy 372.590045 -335.919286) (xy 372.62592 -335.922719) (xy 372.643654 -335.925922)
			(xy 372.658866 -335.928241) (xy 372.689419 -335.924725) (xy 372.71754 -335.91227) (xy 372.740676 -335.892007)
			(xy 372.756729 -335.865774) (xy 372.761002 -335.850992) (xy 372.768437 -335.823959) (xy 372.790061 -335.772233)
			(xy 372.819019 -335.724227) (xy 372.854689 -335.680974) (xy 372.896304 -335.643406) (xy 372.942967 -335.61233)
			(xy 372.993675 -335.588415) (xy 373.047335 -335.572177) (xy 373.102794 -335.563964) (xy 373.130826 -335.563464)
			(xy 373.158077 -335.563954) (xy 373.212023 -335.571713) (xy 373.264316 -335.58707) (xy 373.313891 -335.609712)
			(xy 373.35974 -335.639178) (xy 373.400929 -335.674869) (xy 373.43662 -335.716058) (xy 373.466087 -335.761907)
			(xy 373.488729 -335.811482) (xy 373.504087 -335.863775) (xy 373.511846 -335.917721) (xy 373.512334 -335.944972)
			(xy 373.511872 -335.972547) (xy 373.503922 -336.027121) (xy 373.488198 -336.079982) (xy 373.465027 -336.130028)
			(xy 373.434893 -336.176218) (xy 373.398423 -336.217587) (xy 373.377714 -336.235802) (xy 373.366844 -336.245729)
			(xy 373.350769 -336.27037) (xy 373.342381 -336.298571) (xy 373.342376 -336.327993) (xy 373.350753 -336.356197)
			(xy 373.36682 -336.380844) (xy 373.377714 -336.390742) (xy 373.398391 -336.408989) (xy 373.434853 -336.450357)
			(xy 373.464979 -336.496543) (xy 373.488141 -336.546586) (xy 373.503857 -336.599442) (xy 373.511799 -336.65401)
			(xy 373.511802 -336.709154) (xy 373.503865 -336.763723) (xy 373.488154 -336.81658) (xy 373.464997 -336.866625)
			(xy 373.434875 -336.912815) (xy 373.398417 -336.954186) (xy 373.377714 -336.972402) (xy 373.366844 -336.982329)
			(xy 373.350769 -337.00697) (xy 373.342381 -337.035171) (xy 373.342376 -337.064593) (xy 373.350753 -337.092797)
			(xy 373.36682 -337.117444) (xy 373.377714 -337.127342) (xy 373.398403 -337.145577) (xy 373.434875 -337.186941)
			(xy 373.465009 -337.233126) (xy 373.488179 -337.283169) (xy 373.5039 -337.336028) (xy 373.511845 -337.390599)
			(xy 373.512334 -337.418172) (xy 373.511819 -337.445423) (xy 373.504066 -337.499371) (xy 373.488715 -337.551666)
			(xy 373.466078 -337.601244) (xy 373.436615 -337.647096) (xy 373.400927 -337.688289) (xy 373.35974 -337.723983)
			(xy 373.313892 -337.753452) (xy 373.264317 -337.776096) (xy 373.212024 -337.791455) (xy 373.158077 -337.799215)
			(xy 373.130826 -337.79968) (xy 373.102971 -337.799148) (xy 373.047855 -337.791028) (xy 372.994504 -337.774985)
			(xy 372.944051 -337.75136) (xy 372.897566 -337.720654) (xy 372.856036 -337.683519) (xy 372.820343 -337.640744)
			(xy 372.791244 -337.593237) (xy 372.769358 -337.542005) (xy 372.761764 -337.5152) (xy 372.757496 -337.501082)
			(xy 372.742104 -337.475937) (xy 372.720184 -337.456222) (xy 372.693554 -337.443572) (xy 372.664424 -337.439035)
			(xy 372.64975 -337.440524) (xy 372.636923 -337.442176) (xy 372.61112 -337.443953) (xy 372.598188 -337.44408)
			(xy 372.597426 -337.44408) (xy 372.579795 -337.443842) (xy 372.544687 -337.440537) (xy 372.527322 -337.437476)
			(xy 372.513546 -337.435268) (xy 372.485761 -337.437711) (xy 372.459678 -337.447592) (xy 372.437249 -337.464172)
			(xy 372.420152 -337.48621) (xy 372.409666 -337.512056) (xy 372.407688 -337.525868) (xy 372.404033 -337.553442)
			(xy 372.389802 -337.607212) (xy 372.36791 -337.658344) (xy 372.338821 -337.705752) (xy 372.303152 -337.748431)
			(xy 372.261661 -337.785475) (xy 372.215229 -337.816097) (xy 372.16484 -337.839648) (xy 372.111563 -337.855628)
			(xy 372.056531 -337.863698) (xy 372.02872 -337.864196) (xy 372.001467 -337.863726) (xy 371.947516 -337.855971)
			(xy 371.895217 -337.840617) (xy 371.845636 -337.817976) (xy 371.799783 -337.788509) (xy 371.758589 -337.752816)
			(xy 371.722896 -337.711624) (xy 371.693428 -337.665771) (xy 371.670785 -337.61619) (xy 371.65543 -337.563892)
			(xy 371.647675 -337.509941) (xy 371.647212 -337.482688) (xy 370.872881 -337.482688) (xy 372.258336 -338.868004)
			(xy 373.55399 -338.868004) (xy 373.568071 -338.867564) (xy 373.595164 -338.859887) (xy 373.619123 -338.845091)
			(xy 373.638119 -338.824303) (xy 373.650702 -338.79911) (xy 373.655911 -338.771436) (xy 373.653348 -338.743393)
			(xy 373.648732 -338.730082) (xy 373.637074 -338.697711) (xy 373.624297 -338.630109) (xy 373.623332 -338.595716)
			(xy 373.623332 -338.588096) (xy 373.6242 -338.560169) (xy 373.633044 -338.505002) (xy 373.649825 -338.451711)
			(xy 373.674187 -338.401431) (xy 373.705609 -338.355234) (xy 373.72417 -338.33435) (xy 373.733173 -338.322878)
			(xy 373.744838 -338.296162) (xy 373.748494 -338.26724) (xy 373.743845 -338.238462) (xy 373.731269 -338.212163)
			(xy 373.721884 -338.201) (xy 373.711724 -338.189316) (xy 373.7102 -338.187538) (xy 373.693853 -338.166971)
			(xy 373.666364 -338.122201) (xy 373.645274 -338.074083) (xy 373.630984 -338.023528) (xy 373.623762 -337.97149)
			(xy 373.623332 -337.945222) (xy 373.623815 -337.917999) (xy 373.631557 -337.864106) (xy 373.646888 -337.811863)
			(xy 373.669494 -337.762332) (xy 373.698916 -337.716521) (xy 373.734556 -337.675361) (xy 373.775689 -337.63969)
			(xy 373.821478 -337.610233) (xy 373.870991 -337.587589) (xy 373.923223 -337.572219) (xy 373.977109 -337.564436)
			(xy 374.004332 -337.563968) (xy 374.53062 -337.563968) (xy 374.560536 -337.564576) (xy 374.619627 -337.573965)
			(xy 374.676527 -337.592463) (xy 374.729843 -337.619617) (xy 374.778267 -337.65476) (xy 374.79986 -337.675474)
			(xy 375.251218 -338.126832) (xy 375.271948 -338.14841) (xy 375.307101 -338.19683) (xy 375.334252 -338.250149)
			(xy 375.352733 -338.307057) (xy 375.362091 -338.366155) (xy 375.362724 -338.396072) (xy 375.362724 -338.759292)
			(xy 375.592685 -338.9892) (xy 377.871895 -338.9892) (xy 377.876064 -338.933575) (xy 377.888477 -338.879193)
			(xy 377.908856 -338.827269) (xy 377.936747 -338.778961) (xy 377.971527 -338.735351) (xy 378.012418 -338.697411)
			(xy 378.058507 -338.66599) (xy 378.108764 -338.641789) (xy 378.162068 -338.625349) (xy 378.217226 -338.617038)
			(xy 378.245116 -338.616544) (xy 378.27245 -338.616965) (xy 378.326532 -338.624943) (xy 378.378868 -338.64074)
			(xy 378.428332 -338.664016) (xy 378.473864 -338.694271) (xy 378.514485 -338.730857) (xy 378.549322 -338.772986)
			(xy 378.563886 -338.796122) (xy 378.571839 -338.808324) (xy 378.593304 -338.827993) (xy 378.619449 -338.840799)
			(xy 378.648146 -338.8457) (xy 378.677059 -338.842298) (xy 378.690632 -338.837016) (xy 378.713841 -338.827525)
			(xy 378.762174 -338.814174) (xy 378.811864 -338.807447) (xy 378.836936 -338.807044) (xy 378.862005 -338.807467)
			(xy 378.911688 -338.814217) (xy 378.960023 -338.82755) (xy 378.98324 -338.837016) (xy 378.996827 -338.842232)
			(xy 379.025723 -338.845603) (xy 379.054397 -338.840699) (xy 379.08053 -338.827917) (xy 379.102005 -338.808293)
			(xy 379.109986 -338.796122) (xy 379.124555 -338.772991) (xy 379.159398 -338.73087) (xy 379.200021 -338.694291)
			(xy 379.245552 -338.66404) (xy 379.295014 -338.640764) (xy 379.347345 -338.624964) (xy 379.401424 -338.616978)
			(xy 379.456088 -338.616978) (xy 379.510167 -338.624964) (xy 379.562498 -338.640764) (xy 379.61196 -338.66404)
			(xy 379.657491 -338.694291) (xy 379.698114 -338.73087) (xy 379.732957 -338.772991) (xy 379.747526 -338.796122)
			(xy 379.755441 -338.808351) (xy 379.776916 -338.82802) (xy 379.803071 -338.840823) (xy 379.831778 -338.845717)
			(xy 379.860698 -338.842304) (xy 379.874272 -338.837016) (xy 379.897488 -338.827544) (xy 379.945818 -338.814186)
			(xy 379.995505 -338.807451) (xy 380.020576 -338.807044) (xy 380.045517 -338.807416) (xy 380.094955 -338.814065)
			(xy 380.143064 -338.827247) (xy 380.188986 -338.846727) (xy 380.231899 -338.872158) (xy 380.251716 -338.887308)
			(xy 380.26328 -338.895793) (xy 380.289788 -338.906699) (xy 380.318285 -338.909788) (xy 380.346513 -338.904813)
			(xy 380.372238 -338.89217) (xy 380.393421 -338.872859) (xy 380.401322 -338.860892) (xy 380.416313 -338.837415)
			(xy 380.451977 -338.794632) (xy 380.493486 -338.757491) (xy 380.539956 -338.726784) (xy 380.590398 -338.703162)
			(xy 380.64374 -338.68713) (xy 380.698846 -338.679027) (xy 380.726696 -338.67852) (xy 380.754851 -338.678952)
			(xy 380.810552 -338.687216) (xy 380.864433 -338.703578) (xy 380.915323 -338.727684) (xy 380.962116 -338.75901)
			(xy 381.003795 -338.796875) (xy 381.039454 -338.840456) (xy 381.068319 -338.888806) (xy 381.089761 -338.940874)
			(xy 381.097028 -338.96808) (xy 381.101361 -338.983027) (xy 381.117615 -339.009543) (xy 381.141093 -339.029942)
			(xy 381.169619 -339.042335) (xy 381.200552 -339.045572) (xy 381.2159 -339.04301) (xy 381.234621 -339.039456)
			(xy 381.272538 -339.035641) (xy 381.291592 -339.03539) (xy 381.291846 -339.03539) (xy 381.319095 -339.035883)
			(xy 381.373037 -339.043645) (xy 381.425326 -339.059004) (xy 381.474898 -339.081647) (xy 381.520742 -339.111115)
			(xy 381.561926 -339.146806) (xy 381.597613 -339.187995) (xy 381.627075 -339.233843) (xy 381.649712 -339.283417)
			(xy 381.665065 -339.335708) (xy 381.67282 -339.389651) (xy 381.67282 -339.444149) (xy 381.665065 -339.498092)
			(xy 381.649712 -339.550383) (xy 381.627075 -339.599957) (xy 381.597613 -339.645805) (xy 381.561926 -339.686994)
			(xy 381.520742 -339.722685) (xy 381.474898 -339.752153) (xy 381.425326 -339.774796) (xy 381.373037 -339.790155)
			(xy 381.319095 -339.797917) (xy 381.291846 -339.798406) (xy 381.263693 -339.797916) (xy 381.207995 -339.789659)
			(xy 381.154117 -339.773304) (xy 381.103229 -339.749205) (xy 381.056436 -339.717886) (xy 381.014757 -339.680028)
			(xy 380.979096 -339.636454) (xy 380.950229 -339.588111) (xy 380.928783 -339.536049) (xy 380.921514 -339.508846)
			(xy 380.917228 -339.493882) (xy 380.900967 -339.467358) (xy 380.877478 -339.446956) (xy 380.848939 -339.434569)
			(xy 380.817994 -339.431344) (xy 380.802642 -339.433916) (xy 380.783858 -339.437482) (xy 380.745814 -339.4413)
			(xy 380.726696 -339.441536) (xy 380.726442 -339.441536) (xy 380.700302 -339.441074) (xy 380.648512 -339.433943)
			(xy 380.598183 -339.419797) (xy 380.550262 -339.3989) (xy 380.505649 -339.371646) (xy 380.485142 -339.35543)
			(xy 380.473724 -339.346722) (xy 380.44736 -339.335384) (xy 380.41888 -339.33185) (xy 380.390544 -339.3364)
			(xy 380.364601 -339.348673) (xy 380.343112 -339.367694) (xy 380.335028 -339.37956) (xy 380.3293 -339.388435)
			(xy 380.316971 -339.405588) (xy 380.31039 -339.41385) (xy 380.301159 -339.426158) (xy 380.289769 -339.454718)
			(xy 380.287381 -339.485373) (xy 380.29421 -339.515353) (xy 380.30964 -339.541948) (xy 380.332277 -339.562757)
			(xy 380.34595 -339.569806) (xy 380.369084 -339.581162) (xy 380.412323 -339.609201) (xy 380.451386 -339.642814)
			(xy 380.485561 -339.681387) (xy 380.514222 -339.724216) (xy 380.536847 -339.770519) (xy 380.54534 -339.79485)
			(xy 380.550438 -339.808602) (xy 380.567205 -339.832649) (xy 380.590102 -339.850956) (xy 380.61725 -339.862021)
			(xy 380.64642 -339.864934) (xy 380.66091 -339.862668) (xy 380.678646 -339.859483) (xy 380.71452 -339.856046)
			(xy 380.732538 -339.85581) (xy 380.7333 -339.85581) (xy 380.760554 -339.856255) (xy 380.814506 -339.864013)
			(xy 380.866805 -339.87937) (xy 380.916387 -339.902014) (xy 380.962241 -339.931483) (xy 381.003434 -339.967179)
			(xy 381.039128 -340.008374) (xy 381.068595 -340.054229) (xy 381.091237 -340.103811) (xy 381.106591 -340.156111)
			(xy 381.114346 -340.210064) (xy 381.114808 -340.237318) (xy 381.114554 -340.247732) (xy 381.114676 -340.262099)
			(xy 381.12194 -340.289884) (xy 381.136646 -340.31455) (xy 381.157635 -340.334151) (xy 381.183249 -340.347138)
			(xy 381.211465 -340.352486) (xy 381.225806 -340.351618) (xy 381.262382 -340.34984) (xy 381.289639 -340.350206)
			(xy 381.343599 -340.357962) (xy 381.395906 -340.373318) (xy 381.445494 -340.395962) (xy 381.491355 -340.425434)
			(xy 381.532555 -340.461132) (xy 381.568256 -340.50233) (xy 381.597729 -340.54819) (xy 381.620376 -340.597778)
			(xy 381.635735 -340.650084) (xy 381.643493 -340.704043) (xy 381.643493 -340.758557) (xy 381.635735 -340.812516)
			(xy 381.620376 -340.864822) (xy 381.597729 -340.91441) (xy 381.568256 -340.96027) (xy 381.532555 -341.001468)
			(xy 381.491355 -341.037166) (xy 381.445494 -341.066638) (xy 381.395906 -341.089282) (xy 381.343599 -341.104638)
			(xy 381.289639 -341.112394) (xy 381.262382 -341.112856) (xy 381.251371 -341.112781) (xy 381.229386 -341.111508)
			(xy 381.21844 -341.110316) (xy 381.203582 -341.109091) (xy 381.174247 -341.11434) (xy 381.14768 -341.12784)
			(xy 381.126144 -341.148439) (xy 381.111478 -341.17438) (xy 381.107696 -341.188802) (xy 381.100847 -341.216546)
			(xy 381.07999 -341.269747) (xy 381.051435 -341.319245) (xy 381.015821 -341.363933) (xy 380.973944 -341.402814)
			(xy 380.926739 -341.435018) (xy 380.875262 -341.459826) (xy 380.820661 -341.476683) (xy 380.764158 -341.485214)
			(xy 380.735586 -341.485728) (xy 380.706599 -341.485189) (xy 380.649292 -341.476416) (xy 380.593972 -341.459074)
			(xy 380.541912 -341.433561) (xy 380.494312 -341.400467) (xy 380.452267 -341.360551) (xy 380.416744 -341.314734)
			(xy 380.388562 -341.26407) (xy 380.36837 -341.209726) (xy 380.356632 -341.152952) (xy 380.354586 -341.124032)
			(xy 380.353411 -341.109958) (xy 380.34432 -341.083231) (xy 380.328247 -341.060024) (xy 380.306424 -341.042115)
			(xy 380.280526 -341.030879) (xy 380.252539 -341.027179) (xy 380.238508 -341.028782) (xy 380.224743 -341.030678)
			(xy 380.19703 -341.032711) (xy 380.183136 -341.032846) (xy 380.155887 -341.032288) (xy 380.101944 -341.024538)
			(xy 380.049653 -341.009189) (xy 380.000079 -340.986555) (xy 379.95423 -340.957096) (xy 379.91304 -340.921412)
			(xy 379.877348 -340.880229) (xy 379.847881 -340.834386) (xy 379.825237 -340.784816) (xy 379.809878 -340.732528)
			(xy 379.802117 -340.678587) (xy 379.801628 -340.651338) (xy 379.80211 -340.623764) (xy 379.810058 -340.569191)
			(xy 379.825779 -340.516331) (xy 379.848946 -340.466285) (xy 379.879076 -340.420095) (xy 379.915542 -340.378724)
			(xy 379.936248 -340.360508) (xy 379.947111 -340.350573) (xy 379.963193 -340.325935) (xy 379.971585 -340.297735)
			(xy 379.971592 -340.268314) (xy 379.963214 -340.24011) (xy 379.947144 -340.215464) (xy 379.936248 -340.205568)
			(xy 379.915528 -340.187366) (xy 379.879056 -340.145997) (xy 379.848924 -340.099805) (xy 379.825759 -340.049755)
			(xy 379.810046 -339.99689) (xy 379.80211 -339.942313) (xy 379.801628 -339.914738) (xy 379.802058 -339.888236)
			(xy 379.809408 -339.835744) (xy 379.823958 -339.784775) (xy 379.845426 -339.736313) (xy 379.8734 -339.691292)
			(xy 379.89002 -339.670644) (xy 379.899478 -339.658509) (xy 379.911271 -339.630105) (xy 379.914094 -339.59948)
			(xy 379.907695 -339.569399) (xy 379.892649 -339.542576) (xy 379.870316 -339.521432) (xy 379.856746 -339.51418)
			(xy 379.833054 -339.502083) (xy 379.789072 -339.472159) (xy 379.749792 -339.436287) (xy 379.716009 -339.395195)
			(xy 379.701806 -339.372702) (xy 379.693854 -339.360498) (xy 379.672391 -339.340827) (xy 379.646245 -339.328019)
			(xy 379.617547 -339.323119) (xy 379.588632 -339.326524) (xy 379.57506 -339.331808) (xy 379.551852 -339.341303)
			(xy 379.503518 -339.354652) (xy 379.453828 -339.361378) (xy 379.428756 -339.36178) (xy 379.403687 -339.361358)
			(xy 379.354004 -339.354608) (xy 379.305669 -339.341274) (xy 379.282452 -339.331808) (xy 379.26887 -339.326573)
			(xy 379.239972 -339.323203) (xy 379.211294 -339.32811) (xy 379.18516 -339.340897) (xy 379.163686 -339.360528)
			(xy 379.155706 -339.372702) (xy 379.141137 -339.395833) (xy 379.106294 -339.437954) (xy 379.065671 -339.474533)
			(xy 379.02014 -339.504784) (xy 378.970678 -339.52806) (xy 378.918347 -339.54386) (xy 378.864268 -339.551846)
			(xy 378.809604 -339.551846) (xy 378.755525 -339.54386) (xy 378.703194 -339.52806) (xy 378.653732 -339.504784)
			(xy 378.608201 -339.474533) (xy 378.567578 -339.437954) (xy 378.532735 -339.395833) (xy 378.518166 -339.372702)
			(xy 378.510252 -339.360471) (xy 378.488779 -339.340799) (xy 378.462623 -339.327995) (xy 378.433915 -339.323102)
			(xy 378.404994 -339.326518) (xy 378.39142 -339.331808) (xy 378.368205 -339.341284) (xy 378.319875 -339.35464)
			(xy 378.270187 -339.361374) (xy 378.245116 -339.36178) (xy 378.217226 -339.361362) (xy 378.162068 -339.353051)
			(xy 378.108764 -339.336611) (xy 378.058507 -339.31241) (xy 378.012418 -339.280989) (xy 377.971527 -339.243049)
			(xy 377.936747 -339.199439) (xy 377.908856 -339.151131) (xy 377.888477 -339.099207) (xy 377.876064 -339.044825)
			(xy 377.871895 -338.9892) (xy 375.592685 -338.9892) (xy 376.463306 -339.85962) (xy 377.866656 -339.85962)
			(xy 377.892638 -339.860116) (xy 377.943958 -339.868275) (xy 377.993367 -339.884368) (xy 378.039648 -339.907996)
			(xy 378.08166 -339.938579) (xy 378.100336 -339.956648) (xy 381.555244 -343.411556) (xy 381.974852 -343.411556)
			(xy 381.996612 -343.399499) (xy 382.04259 -343.380507) (xy 382.090649 -343.367656) (xy 382.139971 -343.361165)
			(xy 382.164844 -343.360756) (xy 382.17221 -343.360756) (xy 382.199142 -343.361701) (xy 382.252352 -343.370236)
			(xy 382.30383 -343.386173) (xy 382.352554 -343.409196) (xy 382.397553 -343.438847) (xy 382.437932 -343.474535)
			(xy 382.472887 -343.51555) (xy 382.501722 -343.561076) (xy 382.523863 -343.610207) (xy 382.538871 -343.661965)
			(xy 382.546445 -343.715319) (xy 382.54686 -343.742264) (xy 382.54637 -343.769831) (xy 382.538428 -343.824392)
			(xy 382.522717 -343.877241) (xy 382.499565 -343.92728) (xy 382.469454 -343.973466) (xy 382.45161 -343.994486)
			(xy 382.442849 -344.005678) (xy 382.431305 -344.031638) (xy 382.42735 -344.059772) (xy 382.43129 -344.087909)
			(xy 382.442819 -344.113875) (xy 382.45161 -344.125042) (xy 382.469474 -344.146047) (xy 382.499594 -344.192232)
			(xy 382.522749 -344.242274) (xy 382.538456 -344.295129) (xy 382.546387 -344.349694) (xy 382.54686 -344.377264)
			(xy 382.546396 -344.404258) (xy 382.538795 -344.457708) (xy 382.523739 -344.509554) (xy 382.50153 -344.558762)
			(xy 382.472609 -344.604349) (xy 382.45542 -344.625168) (xy 382.446388 -344.636513) (xy 382.434494 -344.662944)
			(xy 382.430506 -344.691653) (xy 382.434748 -344.720325) (xy 382.446876 -344.74665) (xy 382.465913 -344.768505)
			(xy 382.483715 -344.7799) (xy 386.032387 -344.7799) (xy 386.036556 -344.724273) (xy 386.04897 -344.669889)
			(xy 386.069351 -344.617962) (xy 386.097243 -344.569653) (xy 386.132025 -344.526041) (xy 386.172918 -344.488101)
			(xy 386.21901 -344.456679) (xy 386.26927 -344.432478) (xy 386.322576 -344.416039) (xy 386.377736 -344.407729)
			(xy 386.405628 -344.407236) (xy 386.432959 -344.407731) (xy 386.487038 -344.415696) (xy 386.539372 -344.43148)
			(xy 386.588836 -344.454744) (xy 386.634369 -344.484988) (xy 386.674992 -344.521563) (xy 386.709832 -344.563683)
			(xy 386.724398 -344.586814) (xy 386.732342 -344.599023) (xy 386.753808 -344.618693) (xy 386.779956 -344.631498)
			(xy 386.808656 -344.636398) (xy 386.837571 -344.632992) (xy 386.851144 -344.627708) (xy 386.874352 -344.618213)
			(xy 386.922686 -344.604864) (xy 386.972376 -344.598138) (xy 386.997448 -344.597736) (xy 387.022517 -344.598156)
			(xy 387.072201 -344.604907) (xy 387.120535 -344.618241) (xy 387.143752 -344.627708) (xy 387.157334 -344.63294)
			(xy 387.186232 -344.636309) (xy 387.214909 -344.631401) (xy 387.241043 -344.618616) (xy 387.262517 -344.598987)
			(xy 387.270498 -344.586814) (xy 387.285067 -344.563683) (xy 387.31991 -344.521562) (xy 387.360533 -344.484983)
			(xy 387.406064 -344.454732) (xy 387.455526 -344.431456) (xy 387.507857 -344.415656) (xy 387.561936 -344.40767)
			(xy 387.6166 -344.40767) (xy 387.670679 -344.415656) (xy 387.72301 -344.431456) (xy 387.772472 -344.454732)
			(xy 387.818003 -344.484983) (xy 387.858626 -344.521562) (xy 387.893469 -344.563683) (xy 387.908038 -344.586814)
			(xy 387.915944 -344.59905) (xy 387.937421 -344.61872) (xy 387.963579 -344.631522) (xy 387.992288 -344.636414)
			(xy 388.021209 -344.632998) (xy 388.034784 -344.627708) (xy 388.057999 -344.618232) (xy 388.106329 -344.604875)
			(xy 388.156017 -344.598142) (xy 388.181088 -344.597736) (xy 388.207932 -344.598171) (xy 388.261065 -344.605875)
			(xy 388.312542 -344.621125) (xy 388.361297 -344.643606) (xy 388.406321 -344.672851) (xy 388.446681 -344.708256)
			(xy 388.481541 -344.749087) (xy 388.510181 -344.794499) (xy 388.532006 -344.843551) (xy 388.539736 -344.869262)
			(xy 388.544362 -344.883773) (xy 388.560887 -344.909341) (xy 388.584211 -344.928907) (xy 388.612263 -344.940734)
			(xy 388.642554 -344.943775) (xy 388.672397 -344.937757) (xy 388.68604 -344.930984) (xy 388.714189 -344.916356)
			(xy 388.774138 -344.895627) (xy 388.836696 -344.885126) (xy 388.868412 -344.884502) (xy 388.886431 -344.884725)
			(xy 388.922306 -344.888158) (xy 388.94004 -344.89136) (xy 388.955244 -344.893737) (xy 388.985802 -344.890199)
			(xy 389.013922 -344.877728) (xy 389.037058 -344.857454) (xy 389.053113 -344.831214) (xy 389.057388 -344.81643)
			(xy 389.064795 -344.789389) (xy 389.086426 -344.737665) (xy 389.11539 -344.689661) (xy 389.151065 -344.64641)
			(xy 389.192683 -344.608844) (xy 389.239348 -344.577769) (xy 389.290058 -344.553856) (xy 389.343719 -344.537617)
			(xy 389.39918 -344.529403) (xy 389.427212 -344.528902) (xy 389.454464 -344.529367) (xy 389.508413 -344.537125)
			(xy 389.560709 -344.552482) (xy 389.610287 -344.575125) (xy 389.656138 -344.604594) (xy 389.697328 -344.640288)
			(xy 389.733019 -344.68148) (xy 389.762485 -344.727333) (xy 389.785125 -344.776912) (xy 389.80048 -344.829209)
			(xy 389.808235 -344.883158) (xy 389.80872 -344.91041) (xy 389.808185 -344.937982) (xy 389.800246 -344.992551)
			(xy 389.784534 -345.04541) (xy 389.761377 -345.095456) (xy 389.731257 -345.141647) (xy 389.694801 -345.183022)
			(xy 389.6741 -345.20124) (xy 389.663193 -345.211129) (xy 389.647122 -345.235782) (xy 389.638739 -345.263992)
			(xy 389.638741 -345.293421) (xy 389.647127 -345.32163) (xy 389.663202 -345.346281) (xy 389.6741 -345.35618)
			(xy 389.694815 -345.374385) (xy 389.731279 -345.415758) (xy 389.761405 -345.461949) (xy 389.784567 -345.511998)
			(xy 389.800281 -345.564859) (xy 389.808221 -345.619433) (xy 389.80822 -345.67458) (xy 389.800279 -345.729153)
			(xy 389.784563 -345.782015) (xy 389.761399 -345.832062) (xy 389.731271 -345.878253) (xy 389.694806 -345.919624)
			(xy 389.6741 -345.93784) (xy 389.663193 -345.947729) (xy 389.647122 -345.972382) (xy 389.638739 -346.000592)
			(xy 389.638741 -346.030021) (xy 389.647127 -346.05823) (xy 389.663202 -346.082881) (xy 389.6741 -346.09278)
			(xy 389.694805 -346.110998) (xy 389.731275 -346.152365) (xy 389.761408 -346.198554) (xy 389.784575 -346.2486)
			(xy 389.800293 -346.301462) (xy 389.808234 -346.356036) (xy 389.80872 -346.38361) (xy 389.808232 -346.410861)
			(xy 389.800474 -346.464808) (xy 389.785118 -346.517102) (xy 389.762477 -346.566678) (xy 389.733011 -346.612528)
			(xy 389.697319 -346.653718) (xy 389.65613 -346.689409) (xy 389.61028 -346.718876) (xy 389.560704 -346.741517)
			(xy 389.50841 -346.756874) (xy 389.454463 -346.764631) (xy 389.427212 -346.765118) (xy 389.399358 -346.764571)
			(xy 389.344244 -346.756449) (xy 389.290895 -346.740406) (xy 389.240443 -346.716782) (xy 389.193959 -346.686078)
			(xy 389.152429 -346.648946) (xy 389.116736 -346.606174) (xy 389.087635 -346.55867) (xy 389.065746 -346.507442)
			(xy 389.05815 -346.480638) (xy 389.053874 -346.466522) (xy 389.038487 -346.441374) (xy 389.01657 -346.421656)
			(xy 388.98994 -346.409005) (xy 388.96081 -346.404471) (xy 388.946136 -346.405962) (xy 388.93312 -346.407636)
			(xy 388.906935 -346.409413) (xy 388.893812 -346.409518) (xy 388.879663 -346.409423) (xy 388.85144 -346.40739)
			(xy 388.837424 -346.405454) (xy 388.82408 -346.403805) (xy 388.797379 -346.40691) (xy 388.772419 -346.416889)
			(xy 388.750936 -346.433048) (xy 388.734426 -346.454261) (xy 388.724036 -346.479053) (xy 388.721854 -346.492322)
			(xy 388.717712 -346.519466) (xy 388.702744 -346.572294) (xy 388.680358 -346.62243) (xy 388.651017 -346.668839)
			(xy 388.615326 -346.710563) (xy 388.574022 -346.74674) (xy 388.527959 -346.776623) (xy 388.478089 -346.799595)
			(xy 388.42544 -346.81518) (xy 388.371101 -346.823057) (xy 388.343648 -346.823538) (xy 388.316398 -346.823)
			(xy 388.262451 -346.81525) (xy 388.210156 -346.799902) (xy 388.160578 -346.777267) (xy 388.114726 -346.747807)
			(xy 388.073534 -346.712121) (xy 388.03784 -346.670936) (xy 388.00837 -346.62509) (xy 387.985725 -346.575517)
			(xy 387.970366 -346.523225) (xy 387.962605 -346.46928) (xy 387.96214 -346.44203) (xy 387.962612 -346.414456)
			(xy 387.970562 -346.359882) (xy 387.986284 -346.307022) (xy 388.009453 -346.256976) (xy 388.039585 -346.210786)
			(xy 388.076053 -346.169415) (xy 388.09676 -346.1512) (xy 388.10763 -346.141273) (xy 388.12371 -346.116632)
			(xy 388.1321 -346.088431) (xy 388.132106 -346.059008) (xy 388.123726 -346.030803) (xy 388.107656 -346.006157)
			(xy 388.09676 -345.99626) (xy 388.076067 -345.97803) (xy 388.039597 -345.936664) (xy 388.009463 -345.890478)
			(xy 387.986295 -345.840434) (xy 387.970574 -345.787575) (xy 387.962629 -345.733003) (xy 387.96214 -345.70543)
			(xy 387.962563 -345.678928) (xy 387.969914 -345.626435) (xy 387.984465 -345.575466) (xy 388.005935 -345.527005)
			(xy 388.033911 -345.481984) (xy 388.050532 -345.461336) (xy 388.059995 -345.449205) (xy 388.071785 -345.4208)
			(xy 388.074606 -345.390175) (xy 388.068206 -345.360093) (xy 388.05316 -345.33327) (xy 388.030828 -345.312125)
			(xy 388.017258 -345.304872) (xy 387.993566 -345.292774) (xy 387.949585 -345.262851) (xy 387.910304 -345.226979)
			(xy 387.876521 -345.185887) (xy 387.862318 -345.163394) (xy 387.854357 -345.151197) (xy 387.832896 -345.131527)
			(xy 387.806753 -345.118719) (xy 387.778056 -345.113816) (xy 387.749144 -345.117218) (xy 387.735572 -345.1225)
			(xy 387.712363 -345.13199) (xy 387.664029 -345.145341) (xy 387.61434 -345.152069) (xy 387.589268 -345.152472)
			(xy 387.564199 -345.152047) (xy 387.514516 -345.145298) (xy 387.466181 -345.131966) (xy 387.442964 -345.1225)
			(xy 387.429377 -345.117281) (xy 387.400481 -345.113909) (xy 387.371806 -345.118813) (xy 387.345673 -345.131595)
			(xy 387.324198 -345.151222) (xy 387.316218 -345.163394) (xy 387.301649 -345.186525) (xy 387.266806 -345.228646)
			(xy 387.226183 -345.265225) (xy 387.180652 -345.295476) (xy 387.13119 -345.318752) (xy 387.078859 -345.334552)
			(xy 387.02478 -345.342538) (xy 386.970116 -345.342538) (xy 386.916037 -345.334552) (xy 386.863706 -345.318752)
			(xy 386.814244 -345.295476) (xy 386.768713 -345.265225) (xy 386.72809 -345.228646) (xy 386.693247 -345.186525)
			(xy 386.678678 -345.163394) (xy 386.670755 -345.15117) (xy 386.649283 -345.131499) (xy 386.62313 -345.118695)
			(xy 386.594425 -345.1138) (xy 386.565506 -345.117212) (xy 386.551932 -345.1225) (xy 386.528715 -345.131972)
			(xy 386.480386 -345.14533) (xy 386.430699 -345.152065) (xy 386.405628 -345.152472) (xy 386.377736 -345.152071)
			(xy 386.322576 -345.143761) (xy 386.26927 -345.127322) (xy 386.21901 -345.103121) (xy 386.172918 -345.071699)
			(xy 386.132025 -345.033759) (xy 386.097243 -344.990147) (xy 386.069351 -344.941838) (xy 386.04897 -344.889911)
			(xy 386.036556 -344.835527) (xy 386.032387 -344.7799) (xy 382.483715 -344.7799) (xy 382.490325 -344.784131)
			(xy 382.518144 -344.792266) (xy 382.532636 -344.792808) (xy 383.400808 -344.792808) (xy 383.424871 -344.794016)
			(xy 383.471924 -344.804349) (xy 383.516191 -344.823354) (xy 383.556088 -344.850353) (xy 383.573528 -344.866976)
			(xy 384.44297 -345.736672) (xy 384.958844 -346.252546) (xy 384.975529 -346.27004) (xy 385.002631 -346.310065)
			(xy 385.012692 -346.332048) (xy 385.018983 -346.345447) (xy 385.037943 -346.368161) (xy 385.062615 -346.384493)
			(xy 385.090931 -346.393073) (xy 385.120518 -346.393183) (xy 385.148897 -346.384813) (xy 385.173689 -346.368666)
			(xy 385.183634 -346.357702) (xy 385.201852 -346.336999) (xy 385.243225 -346.300541) (xy 385.289416 -346.270417)
			(xy 385.339462 -346.247257) (xy 385.392321 -346.231541) (xy 385.446891 -346.223598) (xy 385.474464 -346.223082)
			(xy 385.50159 -346.223556) (xy 385.555297 -346.231237) (xy 385.607373 -346.246448) (xy 385.65677 -346.268883)
			(xy 385.70249 -346.298089) (xy 385.743611 -346.333478) (xy 385.779305 -346.374335) (xy 385.808851 -346.419836)
			(xy 385.831653 -346.469064) (xy 385.847251 -346.521026) (xy 385.855331 -346.574674) (xy 385.855972 -346.601796)
			(xy 385.855972 -346.604844) (xy 385.855375 -346.634681) (xy 385.846063 -346.693625) (xy 385.83743 -346.722192)
			(xy 385.833477 -346.736101) (xy 385.832662 -346.764991) (xy 385.83996 -346.792955) (xy 385.854789 -346.817763)
			(xy 385.875964 -346.837433) (xy 385.901796 -346.850395) (xy 385.915916 -346.85351) (xy 385.94199 -346.858671)
			(xy 385.992489 -346.875257) (xy 386.040197 -346.89869) (xy 386.084192 -346.928516) (xy 386.123623 -346.96416)
			(xy 386.157725 -347.004931) (xy 386.185839 -347.050039) (xy 386.207422 -347.098612) (xy 386.222055 -347.149711)
			(xy 386.229456 -347.202346) (xy 386.22986 -347.228922) (xy 386.229395 -347.256173) (xy 386.221635 -347.310119)
			(xy 386.206277 -347.362411) (xy 386.183633 -347.411985) (xy 386.154163 -347.457832) (xy 386.118469 -347.499018)
			(xy 386.077276 -347.534705) (xy 386.031424 -347.564166) (xy 385.981845 -347.586801) (xy 385.92955 -347.60215)
			(xy 385.875603 -347.6099) (xy 385.848352 -347.61043) (xy 385.821229 -347.60995) (xy 385.767531 -347.60226)
			(xy 385.715464 -347.587042) (xy 385.666078 -347.564602) (xy 385.620367 -347.535394) (xy 385.579254 -347.500005)
			(xy 385.543569 -347.45915) (xy 385.514029 -347.413653) (xy 385.491232 -347.36443) (xy 385.475637 -347.312475)
			(xy 385.467557 -347.258834) (xy 385.466844 -347.231716) (xy 385.466844 -347.228668) (xy 385.46744 -347.198831)
			(xy 385.476748 -347.139886) (xy 385.485386 -347.11132) (xy 385.48934 -347.09741) (xy 385.490158 -347.068517)
			(xy 385.482861 -347.040548) (xy 385.468034 -347.015736) (xy 385.446859 -346.99606) (xy 385.421026 -346.983092)
			(xy 385.4069 -346.980002) (xy 385.374062 -346.973413) (xy 385.311206 -346.9503) (xy 385.281932 -346.934028)
			(xy 385.269306 -346.927203) (xy 385.241495 -346.920166) (xy 385.212824 -346.921143) (xy 385.185556 -346.930055)
			(xy 385.161842 -346.9462) (xy 385.143556 -346.968304) (xy 385.137406 -346.981272) (xy 385.128609 -347.004192)
			(xy 385.105958 -347.04775) (xy 385.077913 -347.088046) (xy 385.061714 -347.106494) (xy 385.045712 -347.123258)
			(xy 385.03352 -347.13545) (xy 385.03352 -348.02699) (xy 385.032879 -348.051984) (xy 385.023072 -348.101003)
			(xy 385.003891 -348.147167) (xy 384.976073 -348.188702) (xy 384.958844 -348.206822) (xy 383.760726 -349.404686)
			(xy 383.742642 -349.421956) (xy 383.701055 -349.449712) (xy 383.678176 -349.459804) (xy 382.778 -349.832676)
			(xy 382.754764 -349.84169) (xy 382.705889 -349.851416) (xy 382.680972 -349.85198) (xy 372.664736 -349.85198)
			(xy 367.164329 -355.352604) (xy 368.216686 -355.352604) (xy 368.220757 -355.296982) (xy 368.232883 -355.242545)
			(xy 368.252806 -355.190454) (xy 368.280102 -355.141819) (xy 368.314188 -355.097676) (xy 368.354337 -355.058967)
			(xy 368.399695 -355.026516) (xy 368.449295 -355.001015) (xy 368.502079 -354.983008) (xy 368.556922 -354.972878)
			(xy 368.612656 -354.970841) (xy 368.668093 -354.976941) (xy 368.72205 -354.991047) (xy 368.773379 -355.012859)
			(xy 368.820985 -355.041913) (xy 368.863853 -355.077588) (xy 368.90107 -355.119125) (xy 368.931843 -355.165638)
			(xy 368.955515 -355.216135) (xy 368.971583 -355.269542) (xy 368.979703 -355.324718) (xy 368.980212 -355.352604)
			(xy 368.979703 -355.38049) (xy 368.971583 -355.435666) (xy 368.955515 -355.489073) (xy 368.931843 -355.53957)
			(xy 368.90107 -355.586083) (xy 368.863853 -355.62762) (xy 368.820985 -355.663295) (xy 368.773379 -355.692349)
			(xy 368.72205 -355.714161) (xy 368.668093 -355.728267) (xy 368.612656 -355.734367) (xy 368.556922 -355.73233)
			(xy 368.502079 -355.7222) (xy 368.449295 -355.704193) (xy 368.399695 -355.678692) (xy 368.354337 -355.646241)
			(xy 368.314188 -355.607532) (xy 368.280102 -355.563389) (xy 368.252806 -355.514754) (xy 368.232883 -355.462663)
			(xy 368.220757 -355.408226) (xy 368.216686 -355.352604) (xy 367.164329 -355.352604) (xy 366.227614 -356.289356)
			(xy 366.210586 -356.30564) (xy 366.171701 -356.332234) (xy 366.128589 -356.351228) (xy 366.082721 -356.361973)
			(xy 366.059212 -356.363524) (xy 364.757462 -356.363524) (xy 364.747051 -356.373938) (xy 368.222274 -356.373938)
			(xy 368.226345 -356.318316) (xy 368.238471 -356.263879) (xy 368.258394 -356.211788) (xy 368.28569 -356.163153)
			(xy 368.319776 -356.11901) (xy 368.359925 -356.080301) (xy 368.405283 -356.04785) (xy 368.454883 -356.022349)
			(xy 368.507667 -356.004342) (xy 368.56251 -355.994212) (xy 368.618244 -355.992175) (xy 368.673681 -355.998275)
			(xy 368.727638 -356.012381) (xy 368.778967 -356.034193) (xy 368.826573 -356.063247) (xy 368.869441 -356.098922)
			(xy 368.906658 -356.140459) (xy 368.937431 -356.186972) (xy 368.961103 -356.237469) (xy 368.977171 -356.290876)
			(xy 368.985291 -356.346052) (xy 368.9858 -356.373938) (xy 368.985291 -356.401824) (xy 368.977171 -356.457)
			(xy 368.961103 -356.510407) (xy 368.937431 -356.560904) (xy 368.906658 -356.607417) (xy 368.869441 -356.648954)
			(xy 368.826573 -356.684629) (xy 368.778967 -356.713683) (xy 368.727638 -356.735495) (xy 368.673681 -356.749601)
			(xy 368.618244 -356.755701) (xy 368.56251 -356.753664) (xy 368.507667 -356.743534) (xy 368.454883 -356.725527)
			(xy 368.405283 -356.700026) (xy 368.359925 -356.667575) (xy 368.319776 -356.628866) (xy 368.28569 -356.584723)
			(xy 368.258394 -356.536088) (xy 368.238471 -356.483997) (xy 368.226345 -356.42956) (xy 368.222274 -356.373938)
			(xy 364.747051 -356.373938) (xy 363.923787 -357.197406) (xy 364.728504 -357.197406) (xy 364.732575 -357.141784)
			(xy 364.744701 -357.087347) (xy 364.764624 -357.035256) (xy 364.79192 -356.986621) (xy 364.826006 -356.942478)
			(xy 364.866155 -356.903769) (xy 364.911513 -356.871318) (xy 364.961113 -356.845817) (xy 365.013897 -356.82781)
			(xy 365.06874 -356.81768) (xy 365.124474 -356.815643) (xy 365.179911 -356.821743) (xy 365.233868 -356.835849)
			(xy 365.285197 -356.857661) (xy 365.332803 -356.886715) (xy 365.375671 -356.92239) (xy 365.412888 -356.963927)
			(xy 365.443661 -357.01044) (xy 365.467333 -357.060937) (xy 365.483401 -357.114344) (xy 365.491521 -357.16952)
			(xy 365.49203 -357.197406) (xy 365.491521 -357.225292) (xy 365.483401 -357.280468) (xy 365.467333 -357.333875)
			(xy 365.443661 -357.384372) (xy 365.412888 -357.430885) (xy 365.375671 -357.472422) (xy 365.332803 -357.508097)
			(xy 365.285197 -357.537151) (xy 365.233868 -357.558963) (xy 365.179911 -357.573069) (xy 365.124474 -357.579169)
			(xy 365.06874 -357.577132) (xy 365.013897 -357.567002) (xy 364.961113 -357.548995) (xy 364.911513 -357.523494)
			(xy 364.866155 -357.491043) (xy 364.826006 -357.452334) (xy 364.79192 -357.408191) (xy 364.764624 -357.359556)
			(xy 364.744701 -357.307465) (xy 364.732575 -357.253028) (xy 364.728504 -357.197406) (xy 363.923787 -357.197406)
			(xy 363.733588 -357.387652) (xy 363.733588 -357.397558) (xy 362.965492 -358.1654) (xy 362.955586 -358.1654)
			(xy 362.735368 -358.385618) (xy 362.364528 -358.756712) (xy 362.347499 -358.772992) (xy 362.308612 -358.799578)
			(xy 362.2655 -358.818561) (xy 362.264957 -358.818688) (xy 366.653062 -358.818688) (xy 366.657133 -358.763066)
			(xy 366.669259 -358.708629) (xy 366.689182 -358.656538) (xy 366.716478 -358.607903) (xy 366.750564 -358.56376)
			(xy 366.790713 -358.525051) (xy 366.836071 -358.4926) (xy 366.885671 -358.467099) (xy 366.938455 -358.449092)
			(xy 366.993298 -358.438962) (xy 367.049032 -358.436925) (xy 367.104469 -358.443025) (xy 367.158426 -358.457131)
			(xy 367.209755 -358.478943) (xy 367.257361 -358.507997) (xy 367.300229 -358.543672) (xy 367.337446 -358.585209)
			(xy 367.368219 -358.631722) (xy 367.391891 -358.682219) (xy 367.407959 -358.735626) (xy 367.416079 -358.790802)
			(xy 367.416588 -358.818688) (xy 367.416079 -358.846574) (xy 367.407959 -358.90175) (xy 367.391891 -358.955157)
			(xy 367.368219 -359.005654) (xy 367.337446 -359.052167) (xy 367.300229 -359.093704) (xy 367.257361 -359.129379)
			(xy 367.209755 -359.158433) (xy 367.158426 -359.180245) (xy 367.104469 -359.194351) (xy 367.049032 -359.200451)
			(xy 366.993298 -359.198414) (xy 366.938455 -359.188284) (xy 366.885671 -359.170277) (xy 366.836071 -359.144776)
			(xy 366.790713 -359.112325) (xy 366.750564 -359.073616) (xy 366.716478 -359.029473) (xy 366.689182 -358.980838)
			(xy 366.669259 -358.928747) (xy 366.657133 -358.87431) (xy 366.653062 -358.818688) (xy 362.264957 -358.818688)
			(xy 362.219632 -358.829292) (xy 362.196126 -358.83088) (xy 361.31246 -358.83088) (xy 361.294304 -358.850523)
			(xy 361.253441 -358.885038) (xy 361.208155 -358.913503) (xy 361.159335 -358.935361) (xy 361.10794 -358.950182)
			(xy 361.054978 -358.957676) (xy 361.028234 -358.958134) (xy 361.000979 -358.957673) (xy 360.947023 -358.949921)
			(xy 360.894719 -358.934568) (xy 360.845133 -358.911928) (xy 360.799274 -358.882461) (xy 360.758075 -358.846767)
			(xy 360.722375 -358.805574) (xy 360.692901 -358.75972) (xy 360.670253 -358.710137) (xy 360.654892 -358.657836)
			(xy 360.647131 -358.603881) (xy 360.646726 -358.576626) (xy 360.647383 -358.54453) (xy 360.658118 -358.481241)
			(xy 360.679289 -358.420639) (xy 360.694224 -358.392222) (xy 360.70102 -358.378752) (xy 360.707224 -358.349242)
			(xy 360.704546 -358.319206) (xy 360.69322 -358.291259) (xy 360.674231 -358.267833) (xy 360.649233 -358.250969)
			(xy 360.620401 -358.242134) (xy 360.605324 -358.2416) (xy 359.00995 -358.2416) (xy 358.355392 -357.587042)
			(xy 358.355392 -357.127302) (xy 358.48544 -357.054404) (xy 358.499915 -357.045689) (xy 358.524023 -357.022032)
			(xy 358.541095 -356.992888) (xy 358.54994 -356.960291) (xy 358.549941 -356.926515) (xy 358.541097 -356.893917)
			(xy 358.524026 -356.864772) (xy 358.49992 -356.841114) (xy 358.48544 -356.832408) (xy 358.355392 -356.75951)
			(xy 358.355392 -356.410768) (xy 358.135936 -356.410768) (xy 358.049068 -356.49789) (xy 357.876348 -356.67061)
			(xy 357.876348 -360.61142) (xy 360.771438 -360.61142) (xy 360.775509 -360.555798) (xy 360.787635 -360.501361)
			(xy 360.807558 -360.44927) (xy 360.834854 -360.400635) (xy 360.86894 -360.356492) (xy 360.909089 -360.317783)
			(xy 360.954447 -360.285332) (xy 361.004047 -360.259831) (xy 361.056831 -360.241824) (xy 361.111674 -360.231694)
			(xy 361.167408 -360.229657) (xy 361.222845 -360.235757) (xy 361.276802 -360.249863) (xy 361.328131 -360.271675)
			(xy 361.375737 -360.300729) (xy 361.418605 -360.336404) (xy 361.455822 -360.377941) (xy 361.486595 -360.424454)
			(xy 361.510267 -360.474951) (xy 361.526335 -360.528358) (xy 361.534455 -360.583534) (xy 361.534964 -360.61142)
			(xy 361.534455 -360.639306) (xy 361.526335 -360.694482) (xy 361.510267 -360.747889) (xy 361.486595 -360.798386)
			(xy 361.455822 -360.844899) (xy 361.418605 -360.886436) (xy 361.375737 -360.922111) (xy 361.328131 -360.951165)
			(xy 361.276802 -360.972977) (xy 361.222845 -360.987083) (xy 361.167408 -360.993183) (xy 361.111674 -360.991146)
			(xy 361.056831 -360.981016) (xy 361.004047 -360.963009) (xy 360.954447 -360.937508) (xy 360.909089 -360.905057)
			(xy 360.86894 -360.866348) (xy 360.834854 -360.822205) (xy 360.807558 -360.77357) (xy 360.787635 -360.721479)
			(xy 360.775509 -360.667042) (xy 360.771438 -360.61142) (xy 357.876348 -360.61142) (xy 357.876348 -361.544616)
			(xy 360.295696 -361.544616) (xy 360.299767 -361.488994) (xy 360.311893 -361.434557) (xy 360.331816 -361.382466)
			(xy 360.359112 -361.333831) (xy 360.393198 -361.289688) (xy 360.433347 -361.250979) (xy 360.478705 -361.218528)
			(xy 360.528305 -361.193027) (xy 360.581089 -361.17502) (xy 360.635932 -361.16489) (xy 360.691666 -361.162853)
			(xy 360.747103 -361.168953) (xy 360.80106 -361.183059) (xy 360.852389 -361.204871) (xy 360.899995 -361.233925)
			(xy 360.942863 -361.2696) (xy 360.98008 -361.311137) (xy 361.010853 -361.35765) (xy 361.034525 -361.408147)
			(xy 361.050593 -361.461554) (xy 361.058713 -361.51673) (xy 361.059222 -361.544616) (xy 361.058713 -361.572502)
			(xy 361.050593 -361.627678) (xy 361.034525 -361.681085) (xy 361.010853 -361.731582) (xy 360.98008 -361.778095)
			(xy 360.942863 -361.819632) (xy 360.899995 -361.855307) (xy 360.852389 -361.884361) (xy 360.80106 -361.906173)
			(xy 360.747103 -361.920279) (xy 360.691666 -361.926379) (xy 360.635932 -361.924342) (xy 360.581089 -361.914212)
			(xy 360.528305 -361.896205) (xy 360.478705 -361.870704) (xy 360.433347 -361.838253) (xy 360.393198 -361.799544)
			(xy 360.359112 -361.755401) (xy 360.331816 -361.706766) (xy 360.311893 -361.654675) (xy 360.299767 -361.600238)
			(xy 360.295696 -361.544616) (xy 357.876348 -361.544616) (xy 357.876348 -362.171234) (xy 357.875713 -362.196231)
			(xy 357.865915 -362.245256) (xy 357.846743 -362.291429) (xy 357.818932 -362.332974) (xy 357.801672 -362.351066)
			(xy 357.722678 -362.43006) (xy 358.973626 -362.43006) (xy 358.977697 -362.374438) (xy 358.989823 -362.320001)
			(xy 359.009746 -362.26791) (xy 359.037042 -362.219275) (xy 359.071128 -362.175132) (xy 359.111277 -362.136423)
			(xy 359.156635 -362.103972) (xy 359.206235 -362.078471) (xy 359.259019 -362.060464) (xy 359.313862 -362.050334)
			(xy 359.369596 -362.048297) (xy 359.425033 -362.054397) (xy 359.47899 -362.068503) (xy 359.530319 -362.090315)
			(xy 359.577925 -362.119369) (xy 359.620793 -362.155044) (xy 359.65801 -362.196581) (xy 359.688783 -362.243094)
			(xy 359.712455 -362.293591) (xy 359.728523 -362.346998) (xy 359.736643 -362.402174) (xy 359.737152 -362.43006)
			(xy 359.736643 -362.457946) (xy 359.728523 -362.513122) (xy 359.712455 -362.566529) (xy 359.688783 -362.617026)
			(xy 359.65801 -362.663539) (xy 359.620793 -362.705076) (xy 359.577925 -362.740751) (xy 359.530319 -362.769805)
			(xy 359.47899 -362.791617) (xy 359.425033 -362.805723) (xy 359.369596 -362.811823) (xy 359.313862 -362.809786)
			(xy 359.259019 -362.799656) (xy 359.206235 -362.781649) (xy 359.156635 -362.756148) (xy 359.111277 -362.723697)
			(xy 359.071128 -362.684988) (xy 359.037042 -362.640845) (xy 359.009746 -362.59221) (xy 358.989823 -362.540119)
			(xy 358.977697 -362.485682) (xy 358.973626 -362.43006) (xy 357.722678 -362.43006) (xy 357.406448 -362.74629)
			(xy 357.406448 -363.375702) (xy 357.676702 -363.375702) (xy 357.680773 -363.32008) (xy 357.692899 -363.265643)
			(xy 357.712822 -363.213552) (xy 357.740118 -363.164917) (xy 357.774204 -363.120774) (xy 357.814353 -363.082065)
			(xy 357.859711 -363.049614) (xy 357.909311 -363.024113) (xy 357.962095 -363.006106) (xy 358.016938 -362.995976)
			(xy 358.072672 -362.993939) (xy 358.128109 -363.000039) (xy 358.182066 -363.014145) (xy 358.233395 -363.035957)
			(xy 358.281001 -363.065011) (xy 358.323869 -363.100686) (xy 358.361086 -363.142223) (xy 358.391859 -363.188736)
			(xy 358.415531 -363.239233) (xy 358.431599 -363.29264) (xy 358.436422 -363.32541) (xy 360.662472 -363.32541)
			(xy 360.666543 -363.269788) (xy 360.678669 -363.215351) (xy 360.698592 -363.16326) (xy 360.725888 -363.114625)
			(xy 360.759974 -363.070482) (xy 360.800123 -363.031773) (xy 360.845481 -362.999322) (xy 360.895081 -362.973821)
			(xy 360.947865 -362.955814) (xy 361.002708 -362.945684) (xy 361.058442 -362.943647) (xy 361.113879 -362.949747)
			(xy 361.167836 -362.963853) (xy 361.219165 -362.985665) (xy 361.266771 -363.014719) (xy 361.309639 -363.050394)
			(xy 361.346856 -363.091931) (xy 361.377629 -363.138444) (xy 361.401301 -363.188941) (xy 361.417369 -363.242348)
			(xy 361.425489 -363.297524) (xy 361.425998 -363.32541) (xy 361.425489 -363.353296) (xy 361.417369 -363.408472)
			(xy 361.401301 -363.461879) (xy 361.377629 -363.512376) (xy 361.346856 -363.558889) (xy 361.309639 -363.600426)
			(xy 361.266771 -363.636101) (xy 361.219165 -363.665155) (xy 361.167836 -363.686967) (xy 361.113879 -363.701073)
			(xy 361.058442 -363.707173) (xy 361.002708 -363.705136) (xy 360.947865 -363.695006) (xy 360.895081 -363.676999)
			(xy 360.845481 -363.651498) (xy 360.800123 -363.619047) (xy 360.759974 -363.580338) (xy 360.725888 -363.536195)
			(xy 360.698592 -363.48756) (xy 360.678669 -363.435469) (xy 360.666543 -363.381032) (xy 360.662472 -363.32541)
			(xy 358.436422 -363.32541) (xy 358.439719 -363.347816) (xy 358.440228 -363.375702) (xy 358.439719 -363.403588)
			(xy 358.431599 -363.458764) (xy 358.415531 -363.512171) (xy 358.391859 -363.562668) (xy 358.361086 -363.609181)
			(xy 358.323869 -363.650718) (xy 358.281001 -363.686393) (xy 358.233395 -363.715447) (xy 358.182066 -363.737259)
			(xy 358.128109 -363.751365) (xy 358.072672 -363.757465) (xy 358.016938 -363.755428) (xy 357.962095 -363.745298)
			(xy 357.909311 -363.727291) (xy 357.859711 -363.70179) (xy 357.814353 -363.669339) (xy 357.774204 -363.63063)
			(xy 357.740118 -363.586487) (xy 357.712822 -363.537852) (xy 357.692899 -363.485761) (xy 357.680773 -363.431324)
			(xy 357.676702 -363.375702) (xy 357.406448 -363.375702) (xy 357.406448 -364.40618) (xy 357.767634 -364.40618)
			(xy 357.771705 -364.350558) (xy 357.783831 -364.296121) (xy 357.803754 -364.24403) (xy 357.83105 -364.195395)
			(xy 357.865136 -364.151252) (xy 357.905285 -364.112543) (xy 357.950643 -364.080092) (xy 358.000243 -364.054591)
			(xy 358.053027 -364.036584) (xy 358.10787 -364.026454) (xy 358.163604 -364.024417) (xy 358.219041 -364.030517)
			(xy 358.272998 -364.044623) (xy 358.324327 -364.066435) (xy 358.371933 -364.095489) (xy 358.414801 -364.131164)
			(xy 358.452018 -364.172701) (xy 358.482791 -364.219214) (xy 358.484587 -364.223046) (xy 359.35107 -364.223046)
			(xy 359.355141 -364.167424) (xy 359.367267 -364.112987) (xy 359.38719 -364.060896) (xy 359.414486 -364.012261)
			(xy 359.448572 -363.968118) (xy 359.488721 -363.929409) (xy 359.534079 -363.896958) (xy 359.583679 -363.871457)
			(xy 359.636463 -363.85345) (xy 359.691306 -363.84332) (xy 359.74704 -363.841283) (xy 359.802477 -363.847383)
			(xy 359.856434 -363.861489) (xy 359.907763 -363.883301) (xy 359.955369 -363.912355) (xy 359.998237 -363.94803)
			(xy 360.035454 -363.989567) (xy 360.066227 -364.03608) (xy 360.089899 -364.086577) (xy 360.105967 -364.139984)
			(xy 360.114087 -364.19516) (xy 360.114137 -364.1979) (xy 361.550202 -364.1979) (xy 361.554273 -364.142278)
			(xy 361.566399 -364.087841) (xy 361.586322 -364.03575) (xy 361.613618 -363.987115) (xy 361.647704 -363.942972)
			(xy 361.687853 -363.904263) (xy 361.733211 -363.871812) (xy 361.782811 -363.846311) (xy 361.835595 -363.828304)
			(xy 361.890438 -363.818174) (xy 361.946172 -363.816137) (xy 362.001609 -363.822237) (xy 362.055566 -363.836343)
			(xy 362.106895 -363.858155) (xy 362.154501 -363.887209) (xy 362.197369 -363.922884) (xy 362.234586 -363.964421)
			(xy 362.265359 -364.010934) (xy 362.289031 -364.061431) (xy 362.305099 -364.114838) (xy 362.313219 -364.170014)
			(xy 362.313728 -364.1979) (xy 362.313219 -364.225786) (xy 362.305099 -364.280962) (xy 362.289031 -364.334369)
			(xy 362.265359 -364.384866) (xy 362.234586 -364.431379) (xy 362.197369 -364.472916) (xy 362.154501 -364.508591)
			(xy 362.106895 -364.537645) (xy 362.055566 -364.559457) (xy 362.001609 -364.573563) (xy 361.946172 -364.579663)
			(xy 361.890438 -364.577626) (xy 361.835595 -364.567496) (xy 361.782811 -364.549489) (xy 361.733211 -364.523988)
			(xy 361.687853 -364.491537) (xy 361.647704 -364.452828) (xy 361.613618 -364.408685) (xy 361.586322 -364.36005)
			(xy 361.566399 -364.307959) (xy 361.554273 -364.253522) (xy 361.550202 -364.1979) (xy 360.114137 -364.1979)
			(xy 360.114596 -364.223046) (xy 360.114087 -364.250932) (xy 360.105967 -364.306108) (xy 360.089899 -364.359515)
			(xy 360.066227 -364.410012) (xy 360.035454 -364.456525) (xy 359.998237 -364.498062) (xy 359.955369 -364.533737)
			(xy 359.907763 -364.562791) (xy 359.856434 -364.584603) (xy 359.802477 -364.598709) (xy 359.74704 -364.604809)
			(xy 359.691306 -364.602772) (xy 359.636463 -364.592642) (xy 359.583679 -364.574635) (xy 359.534079 -364.549134)
			(xy 359.488721 -364.516683) (xy 359.448572 -364.477974) (xy 359.414486 -364.433831) (xy 359.38719 -364.385196)
			(xy 359.367267 -364.333105) (xy 359.355141 -364.278668) (xy 359.35107 -364.223046) (xy 358.484587 -364.223046)
			(xy 358.506463 -364.269711) (xy 358.522531 -364.323118) (xy 358.530651 -364.378294) (xy 358.53116 -364.40618)
			(xy 358.530651 -364.434066) (xy 358.522531 -364.489242) (xy 358.506463 -364.542649) (xy 358.482791 -364.593146)
			(xy 358.452018 -364.639659) (xy 358.414801 -364.681196) (xy 358.371933 -364.716871) (xy 358.324327 -364.745925)
			(xy 358.272998 -364.767737) (xy 358.219041 -364.781843) (xy 358.163604 -364.787943) (xy 358.10787 -364.785906)
			(xy 358.053027 -364.775776) (xy 358.000243 -364.757769) (xy 357.950643 -364.732268) (xy 357.905285 -364.699817)
			(xy 357.865136 -364.661108) (xy 357.83105 -364.616965) (xy 357.803754 -364.56833) (xy 357.783831 -364.516239)
			(xy 357.771705 -364.461802) (xy 357.767634 -364.40618) (xy 357.406448 -364.40618) (xy 357.406448 -364.940596)
			(xy 358.631742 -364.940596) (xy 358.635813 -364.884974) (xy 358.647939 -364.830537) (xy 358.667862 -364.778446)
			(xy 358.695158 -364.729811) (xy 358.729244 -364.685668) (xy 358.769393 -364.646959) (xy 358.814751 -364.614508)
			(xy 358.864351 -364.589007) (xy 358.917135 -364.571) (xy 358.971978 -364.56087) (xy 359.027712 -364.558833)
			(xy 359.083149 -364.564933) (xy 359.137106 -364.579039) (xy 359.188435 -364.600851) (xy 359.236041 -364.629905)
			(xy 359.278909 -364.66558) (xy 359.316126 -364.707117) (xy 359.329101 -364.726728) (xy 360.233466 -364.726728)
			(xy 360.237537 -364.671106) (xy 360.249663 -364.616669) (xy 360.269586 -364.564578) (xy 360.296882 -364.515943)
			(xy 360.330968 -364.4718) (xy 360.371117 -364.433091) (xy 360.416475 -364.40064) (xy 360.466075 -364.375139)
			(xy 360.518859 -364.357132) (xy 360.573702 -364.347002) (xy 360.629436 -364.344965) (xy 360.684873 -364.351065)
			(xy 360.73883 -364.365171) (xy 360.790159 -364.386983) (xy 360.837765 -364.416037) (xy 360.880633 -364.451712)
			(xy 360.91785 -364.493249) (xy 360.948623 -364.539762) (xy 360.972295 -364.590259) (xy 360.988363 -364.643666)
			(xy 360.996483 -364.698842) (xy 360.996992 -364.726728) (xy 360.996483 -364.754614) (xy 360.988363 -364.80979)
			(xy 360.972295 -364.863197) (xy 360.948623 -364.913694) (xy 360.91785 -364.960207) (xy 360.880633 -365.001744)
			(xy 360.837765 -365.037419) (xy 360.790159 -365.066473) (xy 360.73883 -365.088285) (xy 360.684873 -365.102391)
			(xy 360.629436 -365.108491) (xy 360.573702 -365.106454) (xy 360.518859 -365.096324) (xy 360.466075 -365.078317)
			(xy 360.416475 -365.052816) (xy 360.371117 -365.020365) (xy 360.330968 -364.981656) (xy 360.296882 -364.937513)
			(xy 360.269586 -364.888878) (xy 360.249663 -364.836787) (xy 360.237537 -364.78235) (xy 360.233466 -364.726728)
			(xy 359.329101 -364.726728) (xy 359.346899 -364.75363) (xy 359.370571 -364.804127) (xy 359.386639 -364.857534)
			(xy 359.394759 -364.91271) (xy 359.395268 -364.940596) (xy 359.394759 -364.968482) (xy 359.386639 -365.023658)
			(xy 359.370571 -365.077065) (xy 359.346899 -365.127562) (xy 359.316126 -365.174075) (xy 359.278909 -365.215612)
			(xy 359.236041 -365.251287) (xy 359.188435 -365.280341) (xy 359.137106 -365.302153) (xy 359.083149 -365.316259)
			(xy 359.027712 -365.322359) (xy 358.971978 -365.320322) (xy 358.917135 -365.310192) (xy 358.864351 -365.292185)
			(xy 358.814751 -365.266684) (xy 358.769393 -365.234233) (xy 358.729244 -365.195524) (xy 358.695158 -365.151381)
			(xy 358.667862 -365.102746) (xy 358.647939 -365.050655) (xy 358.635813 -364.996218) (xy 358.631742 -364.940596)
			(xy 357.406448 -364.940596) (xy 357.406448 -365.043466) (xy 357.40581 -365.068462) (xy 357.396007 -365.117483)
			(xy 357.376831 -365.163652) (xy 357.349017 -365.205193) (xy 357.331772 -365.223298) (xy 356.765352 -365.789718)
			(xy 357.87914 -365.789718) (xy 357.883211 -365.734096) (xy 357.895337 -365.679659) (xy 357.91526 -365.627568)
			(xy 357.942556 -365.578933) (xy 357.976642 -365.53479) (xy 358.016791 -365.496081) (xy 358.062149 -365.46363)
			(xy 358.111749 -365.438129) (xy 358.164533 -365.420122) (xy 358.219376 -365.409992) (xy 358.27511 -365.407955)
			(xy 358.330547 -365.414055) (xy 358.384504 -365.428161) (xy 358.435833 -365.449973) (xy 358.483439 -365.479027)
			(xy 358.526307 -365.514702) (xy 358.563524 -365.556239) (xy 358.594297 -365.602752) (xy 358.617969 -365.653249)
			(xy 358.634037 -365.706656) (xy 358.642157 -365.761832) (xy 358.642666 -365.789718) (xy 358.642157 -365.817604)
			(xy 358.634037 -365.87278) (xy 358.617969 -365.926187) (xy 358.594297 -365.976684) (xy 358.563524 -366.023197)
			(xy 358.526307 -366.064734) (xy 358.483439 -366.100409) (xy 358.435833 -366.129463) (xy 358.384504 -366.151275)
			(xy 358.330547 -366.165381) (xy 358.27511 -366.171481) (xy 358.219376 -366.169444) (xy 358.164533 -366.159314)
			(xy 358.111749 -366.141307) (xy 358.062149 -366.115806) (xy 358.016791 -366.083355) (xy 357.976642 -366.044646)
			(xy 357.942556 -366.000503) (xy 357.91526 -365.951868) (xy 357.895337 -365.899777) (xy 357.883211 -365.84534)
			(xy 357.87914 -365.789718) (xy 356.765352 -365.789718) (xy 356.537768 -366.017302) (xy 356.537768 -366.572546)
			(xy 356.582472 -366.57788) (xy 356.609882 -366.581704) (xy 356.663281 -366.596242) (xy 356.714019 -366.618342)
			(xy 356.761031 -366.647541) (xy 356.803331 -366.683227) (xy 356.840031 -366.724651) (xy 356.87036 -366.770942)
			(xy 356.893683 -366.82113) (xy 356.909509 -366.874161) (xy 356.917506 -366.928923) (xy 356.918006 -366.956594)
			(xy 356.917543 -366.983847) (xy 356.909787 -367.037799) (xy 356.894431 -367.090097) (xy 356.871789 -367.139678)
			(xy 356.842321 -367.185531) (xy 356.806628 -367.226725) (xy 356.765435 -367.262419) (xy 356.719581 -367.291887)
			(xy 356.670001 -367.31453) (xy 356.617702 -367.329886) (xy 356.563751 -367.337643) (xy 356.536498 -367.338102)
			(xy 356.510119 -367.337657) (xy 356.457864 -367.330393) (xy 356.407107 -367.316003) (xy 356.358815 -367.294762)
			(xy 356.313907 -367.267075) (xy 356.273238 -367.233468) (xy 356.237584 -367.194582) (xy 356.207624 -367.151157)
			(xy 356.195376 -367.12779) (xy 356.188674 -367.115431) (xy 356.169699 -367.094703) (xy 356.145785 -367.079941)
			(xy 356.118749 -367.072269) (xy 356.090647 -367.072269) (xy 356.063611 -367.079941) (xy 356.039697 -367.094703)
			(xy 356.020722 -367.115431) (xy 356.01402 -367.12779) (xy 356.001776 -367.151159) (xy 355.971819 -367.194585)
			(xy 355.936166 -367.233472) (xy 355.895497 -367.267077) (xy 355.850587 -367.294761) (xy 355.802292 -367.315995)
			(xy 355.751533 -367.330376) (xy 355.699277 -367.337628) (xy 355.672898 -367.338102) (xy 355.645645 -367.337639)
			(xy 355.591695 -367.329881) (xy 355.539398 -367.314525) (xy 355.489818 -367.291882) (xy 355.443966 -367.262414)
			(xy 355.402774 -367.22672) (xy 355.367081 -367.185528) (xy 355.337614 -367.139675) (xy 355.314972 -367.090095)
			(xy 355.299617 -367.037797) (xy 355.291861 -366.983847) (xy 355.29139 -366.956594) (xy 355.291859 -366.929989)
			(xy 355.299263 -366.877297) (xy 355.313915 -366.826145) (xy 355.335529 -366.777523) (xy 355.363687 -366.732374)
			(xy 355.397843 -366.691574) (xy 355.437334 -366.655913) (xy 355.481395 -366.626083) (xy 355.529173 -366.602661)
			(xy 355.579741 -366.586102) (xy 355.605842 -366.580928) (xy 355.647752 -366.573562) (xy 355.647752 -365.75365)
			(xy 355.648389 -365.728654) (xy 355.658189 -365.67963) (xy 355.677363 -365.63346) (xy 355.705175 -365.591917)
			(xy 355.722428 -365.573818) (xy 356.516432 -364.779814) (xy 356.516432 -362.482638) (xy 356.51707 -362.457642)
			(xy 356.526871 -362.408619) (xy 356.546046 -362.36245) (xy 356.573857 -362.320907) (xy 356.591108 -362.302806)
			(xy 356.986332 -361.907582) (xy 356.986332 -356.406958) (xy 356.986968 -356.381961) (xy 356.996766 -356.332936)
			(xy 357.015938 -356.286764) (xy 357.043748 -356.245218) (xy 357.061008 -356.227126) (xy 357.698294 -355.58984)
			(xy 357.715322 -355.573557) (xy 357.754208 -355.546964) (xy 357.79732 -355.527972) (xy 357.843188 -355.517229)
			(xy 357.866696 -355.515672) (xy 358.355392 -355.515672) (xy 358.355392 -355.356922) (xy 357.875078 -354.876608)
			(xy 357.85628 -354.857064) (xy 357.82423 -354.813326) (xy 357.799191 -354.765229) (xy 357.781745 -354.713888)
			(xy 357.772294 -354.660493) (xy 357.771059 -354.606283) (xy 357.778068 -354.552514) (xy 357.785162 -354.526342)
			(xy 357.788491 -354.513299) (xy 357.788929 -354.486392) (xy 357.782322 -354.460305) (xy 357.76913 -354.43685)
			(xy 357.750268 -354.417656) (xy 357.727048 -354.404055) (xy 357.701081 -354.396993) (xy 357.687626 -354.396548)
			(xy 356.968298 -354.396548) (xy 356.9433 -354.395916) (xy 356.894271 -354.386124) (xy 356.848095 -354.366955)
			(xy 356.806544 -354.339148) (xy 356.788466 -354.321872) (xy 355.668834 -353.20224) (xy 350.277938 -353.20224)
			(xy 349.905828 -353.57435) (xy 349.896275 -353.58449) (xy 349.882613 -353.608758) (xy 349.876022 -353.635816)
			(xy 349.876996 -353.663648) (xy 349.88546 -353.69018) (xy 349.900785 -353.713434) (xy 349.921828 -353.731676)
			(xy 349.934276 -353.737926) (xy 349.958481 -353.749839) (xy 350.003564 -353.779468) (xy 350.044022 -353.815154)
			(xy 350.079048 -353.856185) (xy 350.107943 -353.901742) (xy 350.13013 -353.950916) (xy 350.145166 -354.002726)
			(xy 350.152752 -354.056138) (xy 350.153224 -354.083112) (xy 350.152737 -354.110363) (xy 350.14498 -354.16431)
			(xy 350.129624 -354.216605) (xy 350.106982 -354.266181) (xy 350.077516 -354.312031) (xy 350.041824 -354.353222)
			(xy 350.000635 -354.388913) (xy 349.954785 -354.41838) (xy 349.905208 -354.441022) (xy 349.892316 -354.444808)
			(xy 352.808284 -354.444808) (xy 352.812355 -354.389186) (xy 352.824481 -354.334749) (xy 352.844404 -354.282658)
			(xy 352.8717 -354.234023) (xy 352.905786 -354.18988) (xy 352.945935 -354.151171) (xy 352.991293 -354.11872)
			(xy 353.040893 -354.093219) (xy 353.093677 -354.075212) (xy 353.14852 -354.065082) (xy 353.204254 -354.063045)
			(xy 353.259691 -354.069145) (xy 353.313648 -354.083251) (xy 353.364977 -354.105063) (xy 353.412583 -354.134117)
			(xy 353.455451 -354.169792) (xy 353.492668 -354.211329) (xy 353.523441 -354.257842) (xy 353.547113 -354.308339)
			(xy 353.563181 -354.361746) (xy 353.571301 -354.416922) (xy 353.57181 -354.444808) (xy 353.571301 -354.472694)
			(xy 353.563181 -354.52787) (xy 353.547113 -354.581277) (xy 353.523441 -354.631774) (xy 353.492668 -354.678287)
			(xy 353.455451 -354.719824) (xy 353.412583 -354.755499) (xy 353.364977 -354.784553) (xy 353.313648 -354.806365)
			(xy 353.259691 -354.820471) (xy 353.204254 -354.826571) (xy 353.14852 -354.824534) (xy 353.093677 -354.814404)
			(xy 353.040893 -354.796397) (xy 352.991293 -354.770896) (xy 352.945935 -354.738445) (xy 352.905786 -354.699736)
			(xy 352.8717 -354.655593) (xy 352.844404 -354.606958) (xy 352.824481 -354.554867) (xy 352.812355 -354.50043)
			(xy 352.808284 -354.444808) (xy 349.892316 -354.444808) (xy 349.852914 -354.456379) (xy 349.798967 -354.464137)
			(xy 349.771716 -354.46462) (xy 349.771716 -354.464874) (xy 349.742161 -354.464321) (xy 349.683758 -354.455208)
			(xy 349.627458 -354.437198) (xy 349.57461 -354.410721) (xy 349.550228 -354.394008) (xy 349.53879 -354.385459)
			(xy 349.512445 -354.374474) (xy 349.484089 -354.371209) (xy 349.455936 -354.375919) (xy 349.430187 -354.388237)
			(xy 349.408853 -354.407199) (xy 349.3936 -354.431326) (xy 349.38562 -354.458732) (xy 349.385128 -354.473002)
			(xy 349.385128 -356.040436) (xy 351.932746 -356.040436) (xy 351.936817 -355.984814) (xy 351.948943 -355.930377)
			(xy 351.968866 -355.878286) (xy 351.996162 -355.829651) (xy 352.030248 -355.785508) (xy 352.070397 -355.746799)
			(xy 352.115755 -355.714348) (xy 352.165355 -355.688847) (xy 352.218139 -355.67084) (xy 352.272982 -355.66071)
			(xy 352.328716 -355.658673) (xy 352.384153 -355.664773) (xy 352.43811 -355.678879) (xy 352.489439 -355.700691)
			(xy 352.537045 -355.729745) (xy 352.579913 -355.76542) (xy 352.61713 -355.806957) (xy 352.647903 -355.85347)
			(xy 352.671575 -355.903967) (xy 352.687643 -355.957374) (xy 352.695763 -356.01255) (xy 352.696272 -356.040436)
			(xy 352.695763 -356.068322) (xy 352.687643 -356.123498) (xy 352.671575 -356.176905) (xy 352.647903 -356.227402)
			(xy 352.61713 -356.273915) (xy 352.579913 -356.315452) (xy 352.537045 -356.351127) (xy 352.489439 -356.380181)
			(xy 352.43811 -356.401993) (xy 352.384153 -356.416099) (xy 352.328716 -356.422199) (xy 352.272982 -356.420162)
			(xy 352.218139 -356.410032) (xy 352.165355 -356.392025) (xy 352.115755 -356.366524) (xy 352.070397 -356.334073)
			(xy 352.030248 -356.295364) (xy 351.996162 -356.251221) (xy 351.968866 -356.202586) (xy 351.948943 -356.150495)
			(xy 351.936817 -356.096058) (xy 351.932746 -356.040436) (xy 349.385128 -356.040436) (xy 349.385128 -358.221267)
			(xy 351.436611 -358.221267) (xy 351.444366 -358.167309) (xy 351.459721 -358.115003) (xy 351.482364 -358.065416)
			(xy 351.511833 -358.019555) (xy 351.547529 -357.978356) (xy 351.588725 -357.942656) (xy 351.634583 -357.913182)
			(xy 351.684168 -357.890534) (xy 351.736472 -357.875174) (xy 351.79043 -357.867414) (xy 351.817686 -357.86695)
			(xy 351.833829 -357.867091) (xy 351.866003 -357.869764) (xy 351.881948 -357.872284) (xy 351.89597 -357.874265)
			(xy 351.924113 -357.871202) (xy 351.950334 -357.86053) (xy 351.972617 -357.843069) (xy 351.989249 -357.82016)
			(xy 351.998953 -357.793566) (xy 352.000981 -357.765329) (xy 351.998534 -357.75138) (xy 351.994727 -357.732111)
			(xy 351.990659 -357.693042) (xy 351.990406 -357.673402) (xy 351.990876 -357.646151) (xy 351.998632 -357.592203)
			(xy 352.013987 -357.539908) (xy 352.036627 -357.490331) (xy 352.066093 -357.44448) (xy 352.101784 -357.40329)
			(xy 352.142974 -357.367598) (xy 352.188824 -357.338131) (xy 352.238401 -357.315489) (xy 352.290695 -357.300134)
			(xy 352.344643 -357.292376) (xy 352.399145 -357.292375) (xy 352.453093 -357.300131) (xy 352.505388 -357.315485)
			(xy 352.554966 -357.338125) (xy 352.600816 -357.367591) (xy 352.642007 -357.403281) (xy 352.6777 -357.444471)
			(xy 352.707167 -357.49032) (xy 352.729809 -357.539897) (xy 352.745166 -357.592191) (xy 352.752924 -357.646139)
			(xy 352.752925 -357.700641) (xy 352.74517 -357.754589) (xy 352.729816 -357.806884) (xy 352.707177 -357.856462)
			(xy 352.677712 -357.902313) (xy 352.642022 -357.943505) (xy 352.600832 -357.979197) (xy 352.554983 -358.008665)
			(xy 352.505407 -358.031308) (xy 352.453113 -358.046665) (xy 352.399165 -358.054423) (xy 352.371914 -358.05491)
			(xy 352.355771 -358.05477) (xy 352.323597 -358.052097) (xy 352.307652 -358.049576) (xy 352.293627 -358.047643)
			(xy 352.265492 -358.050705) (xy 352.239279 -358.061372) (xy 352.217001 -358.078825) (xy 352.200369 -358.101723)
			(xy 352.190662 -358.128307) (xy 352.188624 -358.156534) (xy 352.191066 -358.17048) (xy 352.194867 -358.18975)
			(xy 352.198939 -358.228818) (xy 352.199194 -358.248458) (xy 352.19879 -358.275714) (xy 352.191038 -358.329673)
			(xy 352.175685 -358.381979) (xy 352.153045 -358.431568) (xy 352.123578 -358.47743) (xy 352.087884 -358.518631)
			(xy 352.04669 -358.554333) (xy 352.000833 -358.583809) (xy 351.951249 -358.606459) (xy 351.898946 -358.621822)
			(xy 351.844989 -358.629585) (xy 351.790476 -358.629589) (xy 351.736518 -358.621836) (xy 351.684212 -358.606482)
			(xy 351.634624 -358.583841) (xy 351.588763 -358.554372) (xy 351.547562 -358.518677) (xy 351.511861 -358.477482)
			(xy 351.482386 -358.431625) (xy 351.459737 -358.38204) (xy 351.444376 -358.329737) (xy 351.436615 -358.27578)
			(xy 351.436611 -358.221267) (xy 349.385128 -358.221267) (xy 349.385128 -359.484168) (xy 349.7359 -359.484168)
			(xy 349.739971 -359.428546) (xy 349.752097 -359.374109) (xy 349.77202 -359.322018) (xy 349.799316 -359.273383)
			(xy 349.833402 -359.22924) (xy 349.873551 -359.190531) (xy 349.918909 -359.15808) (xy 349.968509 -359.132579)
			(xy 350.021293 -359.114572) (xy 350.076136 -359.104442) (xy 350.13187 -359.102405) (xy 350.187307 -359.108505)
			(xy 350.241264 -359.122611) (xy 350.292593 -359.144423) (xy 350.307817 -359.153714) (xy 351.933254 -359.153714)
			(xy 351.937325 -359.098092) (xy 351.949451 -359.043655) (xy 351.969374 -358.991564) (xy 351.99667 -358.942929)
			(xy 352.030756 -358.898786) (xy 352.070905 -358.860077) (xy 352.116263 -358.827626) (xy 352.165863 -358.802125)
			(xy 352.218647 -358.784118) (xy 352.27349 -358.773988) (xy 352.329224 -358.771951) (xy 352.384661 -358.778051)
			(xy 352.438618 -358.792157) (xy 352.489947 -358.813969) (xy 352.537553 -358.843023) (xy 352.580421 -358.878698)
			(xy 352.617638 -358.920235) (xy 352.648411 -358.966748) (xy 352.672083 -359.017245) (xy 352.688151 -359.070652)
			(xy 352.696271 -359.125828) (xy 352.69678 -359.153714) (xy 352.696271 -359.1816) (xy 352.688151 -359.236776)
			(xy 352.672083 -359.290183) (xy 352.648411 -359.34068) (xy 352.617638 -359.387193) (xy 352.580421 -359.42873)
			(xy 352.537553 -359.464405) (xy 352.489947 -359.493459) (xy 352.438618 -359.515271) (xy 352.384661 -359.529377)
			(xy 352.329224 -359.535477) (xy 352.27349 -359.53344) (xy 352.218647 -359.52331) (xy 352.165863 -359.505303)
			(xy 352.116263 -359.479802) (xy 352.070905 -359.447351) (xy 352.030756 -359.408642) (xy 351.99667 -359.364499)
			(xy 351.969374 -359.315864) (xy 351.949451 -359.263773) (xy 351.937325 -359.209336) (xy 351.933254 -359.153714)
			(xy 350.307817 -359.153714) (xy 350.340199 -359.173477) (xy 350.383067 -359.209152) (xy 350.420284 -359.250689)
			(xy 350.451057 -359.297202) (xy 350.474729 -359.347699) (xy 350.490797 -359.401106) (xy 350.498917 -359.456282)
			(xy 350.499426 -359.484168) (xy 350.498917 -359.512054) (xy 350.490797 -359.56723) (xy 350.474729 -359.620637)
			(xy 350.451057 -359.671134) (xy 350.420284 -359.717647) (xy 350.383067 -359.759184) (xy 350.340199 -359.794859)
			(xy 350.292593 -359.823913) (xy 350.241264 -359.845725) (xy 350.187307 -359.859831) (xy 350.13187 -359.865931)
			(xy 350.076136 -359.863894) (xy 350.021293 -359.853764) (xy 349.968509 -359.835757) (xy 349.918909 -359.810256)
			(xy 349.873551 -359.777805) (xy 349.833402 -359.739096) (xy 349.799316 -359.694953) (xy 349.77202 -359.646318)
			(xy 349.752097 -359.594227) (xy 349.739971 -359.53979) (xy 349.7359 -359.484168) (xy 349.385128 -359.484168)
			(xy 349.385128 -360.248708) (xy 352.035362 -360.248708) (xy 352.039433 -360.193086) (xy 352.051559 -360.138649)
			(xy 352.071482 -360.086558) (xy 352.098778 -360.037923) (xy 352.132864 -359.99378) (xy 352.173013 -359.955071)
			(xy 352.218371 -359.92262) (xy 352.267971 -359.897119) (xy 352.320755 -359.879112) (xy 352.375598 -359.868982)
			(xy 352.431332 -359.866945) (xy 352.486769 -359.873045) (xy 352.540726 -359.887151) (xy 352.592055 -359.908963)
			(xy 352.639661 -359.938017) (xy 352.682529 -359.973692) (xy 352.719746 -360.015229) (xy 352.750519 -360.061742)
			(xy 352.774191 -360.112239) (xy 352.790259 -360.165646) (xy 352.798379 -360.220822) (xy 352.798888 -360.248708)
			(xy 352.798379 -360.276594) (xy 352.790259 -360.33177) (xy 352.774191 -360.385177) (xy 352.750519 -360.435674)
			(xy 352.719746 -360.482187) (xy 352.682529 -360.523724) (xy 352.639661 -360.559399) (xy 352.592055 -360.588453)
			(xy 352.540726 -360.610265) (xy 352.486769 -360.624371) (xy 352.431332 -360.630471) (xy 352.375598 -360.628434)
			(xy 352.320755 -360.618304) (xy 352.267971 -360.600297) (xy 352.218371 -360.574796) (xy 352.173013 -360.542345)
			(xy 352.132864 -360.503636) (xy 352.098778 -360.459493) (xy 352.071482 -360.410858) (xy 352.051559 -360.358767)
			(xy 352.039433 -360.30433) (xy 352.035362 -360.248708) (xy 349.385128 -360.248708) (xy 349.385128 -361.56773)
			(xy 349.385589 -361.581622) (xy 349.393148 -361.608359) (xy 349.407643 -361.632064) (xy 349.427997 -361.650977)
			(xy 349.452701 -361.663695) (xy 349.47992 -361.669275) (xy 349.507635 -361.667301) (xy 349.533789 -361.657921)
			(xy 349.545402 -361.65028) (xy 349.570499 -361.631906) (xy 349.62541 -361.602697) (xy 349.684329 -361.582773)
			(xy 349.745698 -361.572661) (xy 349.776796 -361.572048) (xy 349.77705 -361.572048) (xy 349.804308 -361.572508)
			(xy 349.858271 -361.58026) (xy 349.910581 -361.595613) (xy 349.960173 -361.618255) (xy 350.006038 -361.647725)
			(xy 350.047241 -361.683423) (xy 350.082945 -361.724622) (xy 350.112421 -361.770483) (xy 350.135069 -361.820072)
			(xy 350.15043 -361.87238) (xy 350.158189 -361.926342) (xy 350.158189 -361.952032) (xy 350.408746 -361.952032)
			(xy 350.412817 -361.89641) (xy 350.424943 -361.841973) (xy 350.444866 -361.789882) (xy 350.472162 -361.741247)
			(xy 350.506248 -361.697104) (xy 350.546397 -361.658395) (xy 350.591755 -361.625944) (xy 350.641355 -361.600443)
			(xy 350.694139 -361.582436) (xy 350.748982 -361.572306) (xy 350.804716 -361.570269) (xy 350.860153 -361.576369)
			(xy 350.91411 -361.590475) (xy 350.965439 -361.612287) (xy 351.013045 -361.641341) (xy 351.055913 -361.677016)
			(xy 351.059723 -361.681268) (xy 352.721162 -361.681268) (xy 352.725233 -361.625646) (xy 352.737359 -361.571209)
			(xy 352.757282 -361.519118) (xy 352.784578 -361.470483) (xy 352.818664 -361.42634) (xy 352.858813 -361.387631)
			(xy 352.904171 -361.35518) (xy 352.953771 -361.329679) (xy 353.006555 -361.311672) (xy 353.061398 -361.301542)
			(xy 353.117132 -361.299505) (xy 353.172569 -361.305605) (xy 353.226526 -361.319711) (xy 353.277855 -361.341523)
			(xy 353.325461 -361.370577) (xy 353.368329 -361.406252) (xy 353.405546 -361.447789) (xy 353.436319 -361.494302)
			(xy 353.459991 -361.544799) (xy 353.476059 -361.598206) (xy 353.484179 -361.653382) (xy 353.484688 -361.681268)
			(xy 353.484179 -361.709154) (xy 353.476059 -361.76433) (xy 353.459991 -361.817737) (xy 353.436319 -361.868234)
			(xy 353.405546 -361.914747) (xy 353.368329 -361.956284) (xy 353.325461 -361.991959) (xy 353.277855 -362.021013)
			(xy 353.226526 -362.042825) (xy 353.172569 -362.056931) (xy 353.117132 -362.063031) (xy 353.061398 -362.060994)
			(xy 353.006555 -362.050864) (xy 352.953771 -362.032857) (xy 352.904171 -362.007356) (xy 352.858813 -361.974905)
			(xy 352.818664 -361.936196) (xy 352.784578 -361.892053) (xy 352.757282 -361.843418) (xy 352.737359 -361.791327)
			(xy 352.725233 -361.73689) (xy 352.721162 -361.681268) (xy 351.059723 -361.681268) (xy 351.09313 -361.718553)
			(xy 351.123903 -361.765066) (xy 351.147575 -361.815563) (xy 351.163643 -361.86897) (xy 351.171763 -361.924146)
			(xy 351.172272 -361.952032) (xy 351.171763 -361.979918) (xy 351.163643 -362.035094) (xy 351.147575 -362.088501)
			(xy 351.123903 -362.138998) (xy 351.09313 -362.185511) (xy 351.055913 -362.227048) (xy 351.013045 -362.262723)
			(xy 350.965439 -362.291777) (xy 350.91411 -362.313589) (xy 350.860153 -362.327695) (xy 350.804716 -362.333795)
			(xy 350.748982 -362.331758) (xy 350.694139 -362.321628) (xy 350.641355 -362.303621) (xy 350.591755 -362.27812)
			(xy 350.546397 -362.245669) (xy 350.506248 -362.20696) (xy 350.472162 -362.162817) (xy 350.444866 -362.114182)
			(xy 350.424943 -362.062091) (xy 350.412817 -362.007654) (xy 350.408746 -361.952032) (xy 350.158189 -361.952032)
			(xy 350.158189 -361.980858) (xy 350.15043 -362.03482) (xy 350.135069 -362.087128) (xy 350.112421 -362.136717)
			(xy 350.082945 -362.182578) (xy 350.047241 -362.223777) (xy 350.006038 -362.259475) (xy 349.960173 -362.288945)
			(xy 349.910581 -362.311587) (xy 349.858271 -362.32694) (xy 349.804308 -362.334692) (xy 349.77705 -362.335064)
			(xy 349.776796 -362.335064) (xy 349.751921 -362.334668) (xy 349.702594 -362.328208) (xy 349.654525 -362.315385)
			(xy 349.608534 -362.296417) (xy 349.565401 -362.271628) (xy 349.545402 -362.256832) (xy 349.533795 -362.249196)
			(xy 349.507642 -362.239858) (xy 349.47994 -362.237911) (xy 349.452737 -362.243501) (xy 349.428047 -362.256213)
			(xy 349.407695 -362.275107) (xy 349.393186 -362.298786) (xy 349.385594 -362.325499) (xy 349.385128 -362.339382)
			(xy 349.385128 -362.463334) (xy 349.545402 -362.623608) (xy 351.008948 -362.623608) (xy 351.013019 -362.567986)
			(xy 351.025145 -362.513549) (xy 351.045068 -362.461458) (xy 351.072364 -362.412823) (xy 351.10645 -362.36868)
			(xy 351.146599 -362.329971) (xy 351.191957 -362.29752) (xy 351.241557 -362.272019) (xy 351.294341 -362.254012)
			(xy 351.349184 -362.243882) (xy 351.404918 -362.241845) (xy 351.460355 -362.247945) (xy 351.514312 -362.262051)
			(xy 351.565641 -362.283863) (xy 351.613247 -362.312917) (xy 351.653899 -362.346748) (xy 353.600002 -362.346748)
			(xy 353.604073 -362.291126) (xy 353.616199 -362.236689) (xy 353.636122 -362.184598) (xy 353.663418 -362.135963)
			(xy 353.697504 -362.09182) (xy 353.737653 -362.053111) (xy 353.783011 -362.02066) (xy 353.832611 -361.995159)
			(xy 353.885395 -361.977152) (xy 353.940238 -361.967022) (xy 353.995972 -361.964985) (xy 354.051409 -361.971085)
			(xy 354.105366 -361.985191) (xy 354.156695 -362.007003) (xy 354.204301 -362.036057) (xy 354.247169 -362.071732)
			(xy 354.284386 -362.113269) (xy 354.315159 -362.159782) (xy 354.338831 -362.210279) (xy 354.354899 -362.263686)
			(xy 354.363019 -362.318862) (xy 354.363528 -362.346748) (xy 354.363019 -362.374634) (xy 354.354899 -362.42981)
			(xy 354.338831 -362.483217) (xy 354.315159 -362.533714) (xy 354.284386 -362.580227) (xy 354.247169 -362.621764)
			(xy 354.204301 -362.657439) (xy 354.156695 -362.686493) (xy 354.105366 -362.708305) (xy 354.051409 -362.722411)
			(xy 353.995972 -362.728511) (xy 353.940238 -362.726474) (xy 353.885395 -362.716344) (xy 353.832611 -362.698337)
			(xy 353.783011 -362.672836) (xy 353.737653 -362.640385) (xy 353.697504 -362.601676) (xy 353.663418 -362.557533)
			(xy 353.636122 -362.508898) (xy 353.616199 -362.456807) (xy 353.604073 -362.40237) (xy 353.600002 -362.346748)
			(xy 351.653899 -362.346748) (xy 351.656115 -362.348592) (xy 351.693332 -362.390129) (xy 351.724105 -362.436642)
			(xy 351.747777 -362.487139) (xy 351.763845 -362.540546) (xy 351.771965 -362.595722) (xy 351.772474 -362.623608)
			(xy 351.771965 -362.651494) (xy 351.763845 -362.70667) (xy 351.747777 -362.760077) (xy 351.724105 -362.810574)
			(xy 351.693332 -362.857087) (xy 351.656115 -362.898624) (xy 351.613247 -362.934299) (xy 351.565641 -362.963353)
			(xy 351.514312 -362.985165) (xy 351.460355 -362.999271) (xy 351.404918 -363.005371) (xy 351.349184 -363.003334)
			(xy 351.294341 -362.993204) (xy 351.241557 -362.975197) (xy 351.191957 -362.949696) (xy 351.146599 -362.917245)
			(xy 351.10645 -362.878536) (xy 351.072364 -362.834393) (xy 351.045068 -362.785758) (xy 351.025145 -362.733667)
			(xy 351.013019 -362.67923) (xy 351.008948 -362.623608) (xy 349.545402 -362.623608) (xy 350.559624 -363.63783)
			(xy 352.31146 -363.63783) (xy 352.315531 -363.582208) (xy 352.327657 -363.527771) (xy 352.34758 -363.47568)
			(xy 352.374876 -363.427045) (xy 352.408962 -363.382902) (xy 352.449111 -363.344193) (xy 352.494469 -363.311742)
			(xy 352.544069 -363.286241) (xy 352.596853 -363.268234) (xy 352.651696 -363.258104) (xy 352.70743 -363.256067)
			(xy 352.762867 -363.262167) (xy 352.816824 -363.276273) (xy 352.820083 -363.277658) (xy 354.17836 -363.277658)
			(xy 354.182431 -363.222036) (xy 354.194557 -363.167599) (xy 354.21448 -363.115508) (xy 354.241776 -363.066873)
			(xy 354.275862 -363.02273) (xy 354.316011 -362.984021) (xy 354.361369 -362.95157) (xy 354.410969 -362.926069)
			(xy 354.463753 -362.908062) (xy 354.518596 -362.897932) (xy 354.57433 -362.895895) (xy 354.629767 -362.901995)
			(xy 354.683724 -362.916101) (xy 354.735053 -362.937913) (xy 354.782659 -362.966967) (xy 354.825527 -363.002642)
			(xy 354.862744 -363.044179) (xy 354.893517 -363.090692) (xy 354.917189 -363.141189) (xy 354.933257 -363.194596)
			(xy 354.941377 -363.249772) (xy 354.941886 -363.277658) (xy 354.941377 -363.305544) (xy 354.933257 -363.36072)
			(xy 354.917189 -363.414127) (xy 354.893517 -363.464624) (xy 354.862744 -363.511137) (xy 354.825527 -363.552674)
			(xy 354.782659 -363.588349) (xy 354.735053 -363.617403) (xy 354.683724 -363.639215) (xy 354.629767 -363.653321)
			(xy 354.57433 -363.659421) (xy 354.518596 -363.657384) (xy 354.463753 -363.647254) (xy 354.410969 -363.629247)
			(xy 354.361369 -363.603746) (xy 354.316011 -363.571295) (xy 354.275862 -363.532586) (xy 354.241776 -363.488443)
			(xy 354.21448 -363.439808) (xy 354.194557 -363.387717) (xy 354.182431 -363.33328) (xy 354.17836 -363.277658)
			(xy 352.820083 -363.277658) (xy 352.868153 -363.298085) (xy 352.915759 -363.327139) (xy 352.958627 -363.362814)
			(xy 352.995844 -363.404351) (xy 353.026617 -363.450864) (xy 353.050289 -363.501361) (xy 353.066357 -363.554768)
			(xy 353.074477 -363.609944) (xy 353.074986 -363.63783) (xy 353.074477 -363.665716) (xy 353.066357 -363.720892)
			(xy 353.050289 -363.774299) (xy 353.026617 -363.824796) (xy 352.995844 -363.871309) (xy 352.958627 -363.912846)
			(xy 352.915759 -363.948521) (xy 352.868153 -363.977575) (xy 352.816824 -363.999387) (xy 352.762867 -364.013493)
			(xy 352.70743 -364.019593) (xy 352.651696 -364.017556) (xy 352.596853 -364.007426) (xy 352.544069 -363.989419)
			(xy 352.494469 -363.963918) (xy 352.449111 -363.931467) (xy 352.408962 -363.892758) (xy 352.374876 -363.848615)
			(xy 352.34758 -363.79998) (xy 352.327657 -363.747889) (xy 352.315531 -363.693452) (xy 352.31146 -363.63783)
			(xy 350.559624 -363.63783) (xy 351.260918 -364.339124) (xy 352.982022 -364.339124) (xy 353.00702 -364.339758)
			(xy 353.056047 -364.349553) (xy 353.102222 -364.368722) (xy 353.143772 -364.396529) (xy 353.161854 -364.4138)
			(xy 354.060504 -364.4138) (xy 354.064575 -364.358178) (xy 354.076701 -364.303741) (xy 354.096624 -364.25165)
			(xy 354.12392 -364.203015) (xy 354.158006 -364.158872) (xy 354.198155 -364.120163) (xy 354.243513 -364.087712)
			(xy 354.293113 -364.062211) (xy 354.345897 -364.044204) (xy 354.40074 -364.034074) (xy 354.456474 -364.032037)
			(xy 354.511911 -364.038137) (xy 354.565868 -364.052243) (xy 354.617197 -364.074055) (xy 354.664803 -364.103109)
			(xy 354.707671 -364.138784) (xy 354.744888 -364.180321) (xy 354.775661 -364.226834) (xy 354.799333 -364.277331)
			(xy 354.815401 -364.330738) (xy 354.823521 -364.385914) (xy 354.823529 -364.386368) (xy 355.566216 -364.386368)
			(xy 355.570287 -364.330746) (xy 355.582413 -364.276309) (xy 355.602336 -364.224218) (xy 355.629632 -364.175583)
			(xy 355.663718 -364.13144) (xy 355.703867 -364.092731) (xy 355.749225 -364.06028) (xy 355.798825 -364.034779)
			(xy 355.851609 -364.016772) (xy 355.906452 -364.006642) (xy 355.962186 -364.004605) (xy 356.017623 -364.010705)
			(xy 356.07158 -364.024811) (xy 356.122909 -364.046623) (xy 356.170515 -364.075677) (xy 356.213383 -364.111352)
			(xy 356.2506 -364.152889) (xy 356.281373 -364.199402) (xy 356.305045 -364.249899) (xy 356.321113 -364.303306)
			(xy 356.329233 -364.358482) (xy 356.329742 -364.386368) (xy 356.329233 -364.414254) (xy 356.321113 -364.46943)
			(xy 356.305045 -364.522837) (xy 356.281373 -364.573334) (xy 356.2506 -364.619847) (xy 356.213383 -364.661384)
			(xy 356.170515 -364.697059) (xy 356.122909 -364.726113) (xy 356.07158 -364.747925) (xy 356.017623 -364.762031)
			(xy 355.962186 -364.768131) (xy 355.906452 -364.766094) (xy 355.851609 -364.755964) (xy 355.798825 -364.737957)
			(xy 355.749225 -364.712456) (xy 355.703867 -364.680005) (xy 355.663718 -364.641296) (xy 355.629632 -364.597153)
			(xy 355.602336 -364.548518) (xy 355.582413 -364.496427) (xy 355.570287 -364.44199) (xy 355.566216 -364.386368)
			(xy 354.823529 -364.386368) (xy 354.82403 -364.4138) (xy 354.823521 -364.441686) (xy 354.815401 -364.496862)
			(xy 354.799333 -364.550269) (xy 354.775661 -364.600766) (xy 354.744888 -364.647279) (xy 354.707671 -364.688816)
			(xy 354.664803 -364.724491) (xy 354.617197 -364.753545) (xy 354.565868 -364.775357) (xy 354.511911 -364.789463)
			(xy 354.456474 -364.795563) (xy 354.40074 -364.793526) (xy 354.345897 -364.783396) (xy 354.293113 -364.765389)
			(xy 354.243513 -364.739888) (xy 354.198155 -364.707437) (xy 354.158006 -364.668728) (xy 354.12392 -364.624585)
			(xy 354.096624 -364.57595) (xy 354.076701 -364.523859) (xy 354.064575 -364.469422) (xy 354.060504 -364.4138)
			(xy 353.161854 -364.4138) (xy 353.648772 -364.900718) (xy 353.666025 -364.918815) (xy 353.693827 -364.960362)
			(xy 353.712994 -365.006533) (xy 353.72279 -365.055555) (xy 353.723448 -365.08055) (xy 353.723448 -365.21644)
			(xy 354.854508 -365.21644) (xy 354.858579 -365.160818) (xy 354.870705 -365.106381) (xy 354.890628 -365.05429)
			(xy 354.917924 -365.005655) (xy 354.95201 -364.961512) (xy 354.992159 -364.922803) (xy 355.037517 -364.890352)
			(xy 355.087117 -364.864851) (xy 355.139901 -364.846844) (xy 355.194744 -364.836714) (xy 355.250478 -364.834677)
			(xy 355.305915 -364.840777) (xy 355.359872 -364.854883) (xy 355.411201 -364.876695) (xy 355.458807 -364.905749)
			(xy 355.501675 -364.941424) (xy 355.538892 -364.982961) (xy 355.569665 -365.029474) (xy 355.593337 -365.079971)
			(xy 355.609405 -365.133378) (xy 355.617525 -365.188554) (xy 355.618034 -365.21644) (xy 355.617525 -365.244326)
			(xy 355.609405 -365.299502) (xy 355.593337 -365.352909) (xy 355.569665 -365.403406) (xy 355.538892 -365.449919)
			(xy 355.501675 -365.491456) (xy 355.458807 -365.527131) (xy 355.411201 -365.556185) (xy 355.359872 -365.577997)
			(xy 355.305915 -365.592103) (xy 355.250478 -365.598203) (xy 355.194744 -365.596166) (xy 355.139901 -365.586036)
			(xy 355.087117 -365.568029) (xy 355.037517 -365.542528) (xy 354.992159 -365.510077) (xy 354.95201 -365.471368)
			(xy 354.917924 -365.427225) (xy 354.890628 -365.37859) (xy 354.870705 -365.326499) (xy 354.858579 -365.272062)
			(xy 354.854508 -365.21644) (xy 353.723448 -365.21644) (xy 353.723448 -367.07953) (xy 353.763834 -367.084356)
			(xy 353.76866 -367.084864) (xy 353.796231 -367.088516) (xy 353.849986 -367.102775) (xy 353.901102 -367.124685)
			(xy 353.948496 -367.153784) (xy 353.991163 -367.189455) (xy 354.028201 -367.230941) (xy 354.058825 -367.277364)
			(xy 354.082386 -367.327741) (xy 354.098384 -367.381004) (xy 354.106481 -367.436025) (xy 354.106988 -367.463832)
			(xy 354.1065 -367.491081) (xy 354.098739 -367.545024) (xy 354.083381 -367.597314) (xy 354.060738 -367.646886)
			(xy 354.03127 -367.692731) (xy 353.995579 -367.733916) (xy 353.954389 -367.769602) (xy 353.90854 -367.799063)
			(xy 353.858965 -367.821699) (xy 353.806673 -367.83705) (xy 353.752729 -367.844803) (xy 353.72548 -367.84534)
			(xy 353.699101 -367.844893) (xy 353.646847 -367.837628) (xy 353.59609 -367.823237) (xy 353.547798 -367.801997)
			(xy 353.50289 -367.77431) (xy 353.462221 -367.740704) (xy 353.426566 -367.701819) (xy 353.396603 -367.658396)
			(xy 353.384358 -367.635028) (xy 353.377813 -367.62298) (xy 353.359441 -367.602643) (xy 353.336313 -367.587938)
			(xy 353.310103 -367.579929) (xy 353.282706 -367.579195) (xy 353.256104 -367.585789) (xy 353.232222 -367.599235)
			(xy 353.212787 -367.618559) (xy 353.205542 -367.630202) (xy 353.203002 -367.635028) (xy 353.191388 -367.657267)
			(xy 353.163193 -367.698767) (xy 353.129807 -367.736217) (xy 353.111054 -367.752884) (xy 353.088433 -367.771669)
			(xy 353.03854 -367.802778) (xy 352.984469 -367.825873) (xy 352.956114 -367.833656) (xy 352.943106 -367.838396)
			(xy 352.92007 -367.853733) (xy 352.901983 -367.874678) (xy 352.895662 -367.886996) (xy 352.889551 -367.901344)
			(xy 352.885421 -367.93224) (xy 352.890779 -367.962947) (xy 352.905126 -367.99062) (xy 352.915728 -368.002058)
			(xy 354.38715 -369.47348) (xy 360.57205 -369.47348) (xy 363.519212 -366.526318) (xy 363.519212 -364.00867)
			(xy 362.939076 -363.42828) (xy 362.827824 -363.42828) (xy 362.827824 -360.924856) (xy 361.752896 -359.849928)
			(xy 361.340146 -359.849928) (xy 361.321989 -359.869568) (xy 361.281123 -359.904077) (xy 361.235836 -359.932538)
			(xy 361.187017 -359.954391) (xy 361.135623 -359.969208) (xy 361.082663 -359.976699) (xy 361.05592 -359.977182)
			(xy 361.028668 -359.97672) (xy 360.974719 -359.968966) (xy 360.922422 -359.953613) (xy 360.872843 -359.930973)
			(xy 360.82699 -359.901507) (xy 360.785798 -359.865816) (xy 360.750105 -359.824626) (xy 360.720637 -359.778775)
			(xy 360.697994 -359.729197) (xy 360.682638 -359.676901) (xy 360.674881 -359.622952) (xy 360.674881 -359.568448)
			(xy 360.682638 -359.514499) (xy 360.697994 -359.462203) (xy 360.720637 -359.412625) (xy 360.750105 -359.366774)
			(xy 360.785798 -359.325584) (xy 360.82699 -359.289893) (xy 360.872843 -359.260427) (xy 360.922422 -359.237787)
			(xy 360.974719 -359.222434) (xy 361.028668 -359.21468) (xy 361.05592 -359.214166) (xy 361.082662 -359.214638)
			(xy 361.135617 -359.222148) (xy 361.187006 -359.236977) (xy 361.235821 -359.258834) (xy 361.281108 -359.287291)
			(xy 361.321978 -359.321791) (xy 361.340146 -359.34142) (xy 361.963716 -359.34142) (xy 362.034074 -359.411778)
			(xy 362.038138 -359.415842) (xy 362.082334 -359.460038) (xy 363.93323 -359.460038) (xy 363.937301 -359.404416)
			(xy 363.949427 -359.349979) (xy 363.96935 -359.297888) (xy 363.996646 -359.249253) (xy 364.030732 -359.20511)
			(xy 364.070881 -359.166401) (xy 364.116239 -359.13395) (xy 364.165839 -359.108449) (xy 364.218623 -359.090442)
			(xy 364.273466 -359.080312) (xy 364.3292 -359.078275) (xy 364.384637 -359.084375) (xy 364.438594 -359.098481)
			(xy 364.489923 -359.120293) (xy 364.537529 -359.149347) (xy 364.580397 -359.185022) (xy 364.617614 -359.226559)
			(xy 364.648387 -359.273072) (xy 364.672059 -359.323569) (xy 364.688127 -359.376976) (xy 364.696247 -359.432152)
			(xy 364.696756 -359.460038) (xy 364.696247 -359.487924) (xy 364.688127 -359.5431) (xy 364.672059 -359.596507)
			(xy 364.648387 -359.647004) (xy 364.617614 -359.693517) (xy 364.580397 -359.735054) (xy 364.537529 -359.770729)
			(xy 364.489923 -359.799783) (xy 364.438594 -359.821595) (xy 364.384637 -359.835701) (xy 364.3292 -359.841801)
			(xy 364.273466 -359.839764) (xy 364.218623 -359.829634) (xy 364.165839 -359.811627) (xy 364.116239 -359.786126)
			(xy 364.070881 -359.753675) (xy 364.030732 -359.714966) (xy 363.996646 -359.670823) (xy 363.96935 -359.622188)
			(xy 363.949427 -359.570097) (xy 363.937301 -359.51566) (xy 363.93323 -359.460038) (xy 362.082334 -359.460038)
			(xy 363.26191 -360.639614) (xy 363.265974 -360.643678) (xy 363.336332 -360.714036) (xy 363.336332 -363.018832)
			(xy 363.790482 -363.018832) (xy 363.794553 -362.96321) (xy 363.806679 -362.908773) (xy 363.826602 -362.856682)
			(xy 363.853898 -362.808047) (xy 363.887984 -362.763904) (xy 363.928133 -362.725195) (xy 363.973491 -362.692744)
			(xy 364.023091 -362.667243) (xy 364.075875 -362.649236) (xy 364.130718 -362.639106) (xy 364.186452 -362.637069)
			(xy 364.241889 -362.643169) (xy 364.295846 -362.657275) (xy 364.347175 -362.679087) (xy 364.394781 -362.708141)
			(xy 364.437649 -362.743816) (xy 364.474866 -362.785353) (xy 364.505639 -362.831866) (xy 364.529311 -362.882363)
			(xy 364.545379 -362.93577) (xy 364.553499 -362.990946) (xy 364.554008 -363.018832) (xy 364.553499 -363.046718)
			(xy 364.545379 -363.101894) (xy 364.529311 -363.155301) (xy 364.505639 -363.205798) (xy 364.474866 -363.252311)
			(xy 364.437649 -363.293848) (xy 364.394781 -363.329523) (xy 364.347175 -363.358577) (xy 364.295846 -363.380389)
			(xy 364.241889 -363.394495) (xy 364.186452 -363.400595) (xy 364.130718 -363.398558) (xy 364.075875 -363.388428)
			(xy 364.023091 -363.370421) (xy 363.973491 -363.34492) (xy 363.928133 -363.312469) (xy 363.887984 -363.27376)
			(xy 363.853898 -363.229617) (xy 363.826602 -363.180982) (xy 363.806679 -363.128891) (xy 363.794553 -363.074454)
			(xy 363.790482 -363.018832) (xy 363.336332 -363.018832) (xy 363.336332 -363.106208) (xy 363.953552 -363.723428)
			(xy 363.957108 -363.726984) (xy 364.027974 -363.79785) (xy 364.027974 -363.895894) (xy 364.028228 -363.90326)
			(xy 364.028228 -364.978696) (xy 365.31245 -364.978696) (xy 365.316521 -364.923074) (xy 365.328647 -364.868637)
			(xy 365.34857 -364.816546) (xy 365.375866 -364.767911) (xy 365.409952 -364.723768) (xy 365.450101 -364.685059)
			(xy 365.495459 -364.652608) (xy 365.545059 -364.627107) (xy 365.597843 -364.6091) (xy 365.652686 -364.59897)
			(xy 365.70842 -364.596933) (xy 365.763857 -364.603033) (xy 365.817814 -364.617139) (xy 365.869143 -364.638951)
			(xy 365.916749 -364.668005) (xy 365.959617 -364.70368) (xy 365.996834 -364.745217) (xy 366.027607 -364.79173)
			(xy 366.051279 -364.842227) (xy 366.067347 -364.895634) (xy 366.075467 -364.95081) (xy 366.075976 -364.978696)
			(xy 366.075467 -365.006582) (xy 366.067347 -365.061758) (xy 366.051279 -365.115165) (xy 366.027607 -365.165662)
			(xy 365.996834 -365.212175) (xy 365.959617 -365.253712) (xy 365.916749 -365.289387) (xy 365.869143 -365.318441)
			(xy 365.817814 -365.340253) (xy 365.763857 -365.354359) (xy 365.70842 -365.360459) (xy 365.652686 -365.358422)
			(xy 365.597843 -365.348292) (xy 365.545059 -365.330285) (xy 365.495459 -365.304784) (xy 365.450101 -365.272333)
			(xy 365.409952 -365.233624) (xy 365.375866 -365.189481) (xy 365.34857 -365.140846) (xy 365.328647 -365.088755)
			(xy 365.316521 -365.034318) (xy 365.31245 -364.978696) (xy 364.028228 -364.978696) (xy 364.028228 -366.631728)
			(xy 364.027974 -366.639856) (xy 364.027974 -366.737138) (xy 363.957108 -366.808004) (xy 363.953552 -366.81156)
			(xy 360.857292 -369.90782) (xy 360.853736 -369.911376) (xy 360.78287 -369.982242) (xy 360.685588 -369.982242)
			(xy 360.67746 -369.982496) (xy 354.28174 -369.982496) (xy 354.273612 -369.982242) (xy 354.17633 -369.982242)
			(xy 354.105464 -369.911376) (xy 354.101908 -369.90782) (xy 350.749616 -366.555528) (xy 346.955364 -366.555528)
			(xy 346.433648 -367.077244) (xy 346.433648 -367.09858) (xy 346.433221 -367.125858) (xy 346.425524 -367.179868)
			(xy 346.410214 -367.23223) (xy 346.387601 -367.281878) (xy 346.358148 -367.3278) (xy 346.322455 -367.369058)
			(xy 346.281249 -367.404812) (xy 346.235371 -367.434332) (xy 346.185756 -367.457018) (xy 346.133416 -367.472405)
			(xy 346.079418 -367.480181) (xy 346.05214 -367.480596) (xy 346.024875 -367.480135) (xy 345.970899 -367.472376)
			(xy 345.918577 -367.457011) (xy 345.868977 -367.434353) (xy 345.823108 -367.404863) (xy 345.781905 -367.369143)
			(xy 345.746208 -367.32792) (xy 345.716744 -367.282035) (xy 345.694114 -367.232422) (xy 345.678779 -367.180092)
			(xy 345.67105 -367.126112) (xy 345.671086 -367.071581) (xy 345.678887 -367.017611) (xy 345.694292 -366.965302)
			(xy 345.716988 -366.915719) (xy 345.746513 -366.869872) (xy 345.782265 -366.828697) (xy 345.823515 -366.793032)
			(xy 345.869424 -366.763604) (xy 345.919054 -366.741011) (xy 345.971396 -366.725716) (xy 346.025382 -366.718029)
			(xy 346.052648 -366.71758) (xy 346.073984 -366.71758) (xy 346.670122 -366.121442) (xy 346.674186 -366.117378)
			(xy 346.744544 -366.04702) (xy 350.960436 -366.04702) (xy 351.030794 -366.117378) (xy 351.032826 -366.11941)
			(xy 351.034858 -366.121442) (xy 352.323654 -367.409984) (xy 352.334746 -367.420289) (xy 352.361474 -367.434476)
			(xy 352.391184 -367.440215) (xy 352.421273 -367.437003) (xy 352.449103 -367.425122) (xy 352.472234 -367.405613)
			(xy 352.488639 -367.380186) (xy 352.493326 -367.365788) (xy 352.49358 -367.364518) (xy 352.494342 -367.36147)
			(xy 352.502891 -367.332913) (xy 352.527625 -367.278679) (xy 352.5605 -367.228957) (xy 352.600715 -367.184959)
			(xy 352.623628 -367.16589) (xy 352.648371 -367.14686) (xy 352.702789 -367.116291) (xy 352.761465 -367.09501)
			(xy 352.79203 -367.088674) (xy 352.833432 -367.081054) (xy 352.833432 -365.344202) (xy 352.71837 -365.22914)
			(xy 350.997012 -365.22914) (xy 350.972017 -365.228499) (xy 350.922998 -365.218693) (xy 350.876833 -365.199514)
			(xy 350.835296 -365.171698) (xy 350.81718 -365.154464) (xy 348.569788 -362.907072) (xy 348.552538 -362.888974)
			(xy 348.524742 -362.847425) (xy 348.50558 -362.801254) (xy 348.495788 -362.752234) (xy 348.495112 -362.72724)
			(xy 348.495112 -361.564936) (xy 348.494668 -361.551222) (xy 348.487368 -361.524783) (xy 348.473286 -361.501246)
			(xy 348.453441 -361.482312) (xy 348.429268 -361.469352) (xy 348.402516 -361.463301) (xy 348.375119 -361.464599)
			(xy 348.349058 -361.473152) (xy 348.337378 -361.480354) (xy 348.313822 -361.495374) (xy 348.26325 -361.51911)
			(xy 348.209759 -361.535224) (xy 348.154491 -361.543372) (xy 348.126558 -361.543854) (xy 348.099305 -361.543365)
			(xy 348.045356 -361.535603) (xy 347.99306 -361.520242) (xy 347.943482 -361.497596) (xy 347.897631 -361.468125)
			(xy 347.856441 -361.432429) (xy 347.82075 -361.391235) (xy 347.791284 -361.345381) (xy 347.768643 -361.295801)
			(xy 347.753288 -361.243503) (xy 347.745532 -361.189553) (xy 347.745532 -361.135047) (xy 347.753288 -361.081097)
			(xy 347.768643 -361.028799) (xy 347.791284 -360.979219) (xy 347.82075 -360.933365) (xy 347.856441 -360.892171)
			(xy 347.897631 -360.856475) (xy 347.943482 -360.827004) (xy 347.99306 -360.804358) (xy 348.045356 -360.788997)
			(xy 348.099305 -360.781235) (xy 348.126558 -360.780838) (xy 348.126558 -360.780584) (xy 348.153845 -360.781053)
			(xy 348.207862 -360.788836) (xy 348.26022 -360.804234) (xy 348.309849 -360.826933) (xy 348.33306 -360.84129)
			(xy 348.344612 -360.849281) (xy 348.37088 -360.859204) (xy 348.398856 -360.8616) (xy 348.426429 -360.856287)
			(xy 348.451512 -360.843667) (xy 348.472211 -360.824694) (xy 348.486962 -360.800801) (xy 348.494649 -360.773795)
			(xy 348.495112 -360.759756) (xy 348.495112 -358.662986) (xy 348.494674 -358.649024) (xy 348.487107 -358.622143)
			(xy 348.472542 -358.598317) (xy 348.452068 -358.579327) (xy 348.427217 -358.566591) (xy 348.399844 -358.561063)
			(xy 348.371998 -358.563155) (xy 348.358714 -358.567482) (xy 348.334578 -358.577531) (xy 348.284247 -358.591674)
			(xy 348.232455 -358.598806) (xy 348.206314 -358.599232) (xy 348.179059 -358.59877) (xy 348.125103 -358.591014)
			(xy 348.0728 -358.575658) (xy 348.023215 -358.553015) (xy 347.977357 -358.523546) (xy 347.93616 -358.48785)
			(xy 347.900463 -358.446654) (xy 347.870991 -358.400797) (xy 347.848346 -358.351213) (xy 347.832989 -358.298911)
			(xy 347.825231 -358.244955) (xy 347.825231 -358.190445) (xy 347.832989 -358.136489) (xy 347.848346 -358.084187)
			(xy 347.870991 -358.034603) (xy 347.900463 -357.988746) (xy 347.93616 -357.94755) (xy 347.977357 -357.911854)
			(xy 348.023215 -357.882385) (xy 348.0728 -357.859742) (xy 348.125103 -357.844386) (xy 348.179059 -357.83663)
			(xy 348.206314 -357.836216) (xy 348.232454 -357.836646) (xy 348.284243 -357.843787) (xy 348.334572 -357.857933)
			(xy 348.358714 -357.867966) (xy 348.371986 -357.872337) (xy 348.399841 -357.874432) (xy 348.427221 -357.868901)
			(xy 348.452079 -357.856159) (xy 348.472555 -357.837158) (xy 348.487116 -357.81332) (xy 348.494674 -357.786429)
			(xy 348.495112 -357.772462) (xy 348.495112 -353.831144) (xy 348.495749 -353.806148) (xy 348.505549 -353.757124)
			(xy 348.524722 -353.710952) (xy 348.552531 -353.669407) (xy 348.569788 -353.651312) (xy 349.8342 -352.3869)
			(xy 349.852297 -352.369647) (xy 349.893845 -352.341846) (xy 349.940015 -352.322678) (xy 349.989037 -352.312879)
			(xy 350.014032 -352.312224) (xy 354.24364 -352.312224) (xy 354.258832 -352.31167) (xy 354.287874 -352.302746)
			(xy 354.313005 -352.285671) (xy 354.331998 -352.261957) (xy 354.343172 -352.233704) (xy 354.345537 -352.203414)
			(xy 354.338884 -352.173768) (xy 354.331778 -352.160332) (xy 354.33 -352.157284) (xy 354.32873 -352.154998)
			(xy 354.313856 -352.126608) (xy 354.292775 -352.066086) (xy 354.282106 -352.002892) (xy 354.281486 -351.970848)
			(xy 354.281486 -351.96272) (xy 354.282591 -351.934567) (xy 354.29206 -351.879029) (xy 354.309592 -351.825486)
			(xy 354.334807 -351.775103) (xy 354.367155 -351.728975) (xy 354.405935 -351.688105) (xy 354.450302 -351.653381)
			(xy 354.499293 -351.625558) (xy 354.551842 -351.605241) (xy 354.606807 -351.592872) (xy 354.662994 -351.588718)
			(xy 354.719181 -351.592872) (xy 354.774146 -351.605241) (xy 354.826695 -351.625558) (xy 354.875686 -351.653381)
			(xy 354.920053 -351.688105) (xy 354.93865 -351.707704) (xy 355.638352 -351.707704) (xy 355.642423 -351.652082)
			(xy 355.654549 -351.597645) (xy 355.674472 -351.545554) (xy 355.701768 -351.496919) (xy 355.735854 -351.452776)
			(xy 355.776003 -351.414067) (xy 355.821361 -351.381616) (xy 355.870961 -351.356115) (xy 355.923745 -351.338108)
			(xy 355.978588 -351.327978) (xy 356.034322 -351.325941) (xy 356.089759 -351.332041) (xy 356.143716 -351.346147)
			(xy 356.195045 -351.367959) (xy 356.242651 -351.397013) (xy 356.285519 -351.432688) (xy 356.322736 -351.474225)
			(xy 356.340416 -351.500948) (xy 356.859076 -351.500948) (xy 356.863147 -351.445326) (xy 356.875273 -351.390889)
			(xy 356.895196 -351.338798) (xy 356.922492 -351.290163) (xy 356.956578 -351.24602) (xy 356.996727 -351.207311)
			(xy 357.042085 -351.17486) (xy 357.091685 -351.149359) (xy 357.144469 -351.131352) (xy 357.199312 -351.121222)
			(xy 357.255046 -351.119185) (xy 357.310483 -351.125285) (xy 357.36444 -351.139391) (xy 357.415769 -351.161203)
			(xy 357.463375 -351.190257) (xy 357.506243 -351.225932) (xy 357.54346 -351.267469) (xy 357.574233 -351.313982)
			(xy 357.597905 -351.364479) (xy 357.613973 -351.417886) (xy 357.619842 -351.457768) (xy 359.071416 -351.457768)
			(xy 359.075487 -351.402146) (xy 359.087613 -351.347709) (xy 359.107536 -351.295618) (xy 359.134832 -351.246983)
			(xy 359.168918 -351.20284) (xy 359.209067 -351.164131) (xy 359.254425 -351.13168) (xy 359.304025 -351.106179)
			(xy 359.356809 -351.088172) (xy 359.411652 -351.078042) (xy 359.467386 -351.076005) (xy 359.522823 -351.082105)
			(xy 359.57678 -351.096211) (xy 359.628109 -351.118023) (xy 359.675715 -351.147077) (xy 359.718583 -351.182752)
			(xy 359.7558 -351.224289) (xy 359.786573 -351.270802) (xy 359.810245 -351.321299) (xy 359.826313 -351.374706)
			(xy 359.834433 -351.429882) (xy 359.834942 -351.457768) (xy 359.834433 -351.485654) (xy 359.826313 -351.54083)
			(xy 359.810245 -351.594237) (xy 359.786573 -351.644734) (xy 359.7558 -351.691247) (xy 359.718583 -351.732784)
			(xy 359.675715 -351.768459) (xy 359.628109 -351.797513) (xy 359.57678 -351.819325) (xy 359.522823 -351.833431)
			(xy 359.467386 -351.839531) (xy 359.411652 -351.837494) (xy 359.356809 -351.827364) (xy 359.304025 -351.809357)
			(xy 359.254425 -351.783856) (xy 359.209067 -351.751405) (xy 359.168918 -351.712696) (xy 359.134832 -351.668553)
			(xy 359.107536 -351.619918) (xy 359.087613 -351.567827) (xy 359.075487 -351.51339) (xy 359.071416 -351.457768)
			(xy 357.619842 -351.457768) (xy 357.622093 -351.473062) (xy 357.622602 -351.500948) (xy 357.622093 -351.528834)
			(xy 357.613973 -351.58401) (xy 357.597905 -351.637417) (xy 357.574233 -351.687914) (xy 357.54346 -351.734427)
			(xy 357.506243 -351.775964) (xy 357.463375 -351.811639) (xy 357.415769 -351.840693) (xy 357.36444 -351.862505)
			(xy 357.310483 -351.876611) (xy 357.255046 -351.882711) (xy 357.199312 -351.880674) (xy 357.144469 -351.870544)
			(xy 357.091685 -351.852537) (xy 357.042085 -351.827036) (xy 356.996727 -351.794585) (xy 356.956578 -351.755876)
			(xy 356.922492 -351.711733) (xy 356.895196 -351.663098) (xy 356.875273 -351.611007) (xy 356.863147 -351.55657)
			(xy 356.859076 -351.500948) (xy 356.340416 -351.500948) (xy 356.353509 -351.520738) (xy 356.377181 -351.571235)
			(xy 356.393249 -351.624642) (xy 356.401369 -351.679818) (xy 356.401878 -351.707704) (xy 356.401369 -351.73559)
			(xy 356.393249 -351.790766) (xy 356.377181 -351.844173) (xy 356.353509 -351.89467) (xy 356.322736 -351.941183)
			(xy 356.285519 -351.98272) (xy 356.242651 -352.018395) (xy 356.195045 -352.047449) (xy 356.143716 -352.069261)
			(xy 356.089759 -352.083367) (xy 356.034322 -352.089467) (xy 355.978588 -352.08743) (xy 355.923745 -352.0773)
			(xy 355.870961 -352.059293) (xy 355.821361 -352.033792) (xy 355.776003 -352.001341) (xy 355.735854 -351.962632)
			(xy 355.701768 -351.918489) (xy 355.674472 -351.869854) (xy 355.654549 -351.817763) (xy 355.642423 -351.763326)
			(xy 355.638352 -351.707704) (xy 354.93865 -351.707704) (xy 354.958833 -351.728975) (xy 354.991181 -351.775103)
			(xy 355.016396 -351.825486) (xy 355.033928 -351.879029) (xy 355.043397 -351.934567) (xy 355.044502 -351.96272)
			(xy 355.044502 -351.970848) (xy 355.043868 -352.002892) (xy 355.033204 -352.066085) (xy 355.012134 -352.126609)
			(xy 354.997258 -352.154998) (xy 354.995988 -352.157284) (xy 354.99421 -352.160332) (xy 354.987188 -352.173795)
			(xy 354.980582 -352.203414) (xy 354.982967 -352.233667) (xy 354.994133 -352.261886) (xy 355.013095 -352.285579)
			(xy 355.03818 -352.302658) (xy 355.067175 -352.311615) (xy 355.082348 -352.312224) (xy 355.932486 -352.312224)
			(xy 355.957481 -352.312864) (xy 356.006502 -352.322669) (xy 356.052668 -352.341846) (xy 356.094209 -352.369659)
			(xy 356.112318 -352.3869) (xy 357.221282 -353.495864) (xy 357.357172 -353.495864) (xy 357.357172 -352.768662)
			(xy 357.539036 -352.586798) (xy 357.558436 -352.56813) (xy 357.601831 -352.536267) (xy 357.649531 -352.511302)
			(xy 357.700445 -352.493806) (xy 357.753414 -352.484177) (xy 357.807229 -352.482636) (xy 357.860663 -352.489216)
			(xy 357.912496 -352.503769) (xy 357.961546 -352.525962) (xy 358.006694 -352.555289) (xy 358.046911 -352.591081)
			(xy 358.081278 -352.632521) (xy 358.109013 -352.678665) (xy 358.11968 -352.703384) (xy 358.125766 -352.717195)
			(xy 358.143387 -352.741689) (xy 358.166263 -352.761364) (xy 358.193117 -352.775121) (xy 358.222449 -352.782193)
			(xy 358.237536 -352.782632) (xy 358.253648 -352.782168) (xy 358.284849 -352.774116) (xy 358.31304 -352.75851)
			(xy 358.336427 -352.736343) (xy 358.353519 -352.709026) (xy 358.363228 -352.678301) (xy 358.364536 -352.662236)
			(xy 358.366405 -352.635917) (xy 358.376936 -352.584218) (xy 358.394985 -352.53464) (xy 358.420156 -352.48827)
			(xy 358.451898 -352.446125) (xy 358.489515 -352.409129) (xy 358.510586 -352.39325) (xy 358.511279 -352.366141)
			(xy 358.519386 -352.312523) (xy 358.535003 -352.260593) (xy 358.557817 -352.211397) (xy 358.587366 -352.165928)
			(xy 358.623055 -352.1251) (xy 358.664166 -352.089737) (xy 358.70987 -352.060552) (xy 358.759246 -352.038132)
			(xy 358.811299 -352.022929) (xy 358.86498 -352.01525) (xy 358.892094 -352.01479) (xy 358.919335 -352.015274)
			(xy 358.973264 -352.023022) (xy 359.025543 -352.038362) (xy 359.075109 -352.060981) (xy 359.120954 -352.090419)
			(xy 359.162146 -352.126078) (xy 359.197847 -352.167234) (xy 359.227332 -352.213049) (xy 359.250002 -352.262591)
			(xy 359.258108 -352.288602) (xy 359.268776 -352.324924) (xy 360.050334 -352.324924) (xy 360.062018 -352.29038)
			(xy 360.071445 -352.26407) (xy 360.096904 -352.214317) (xy 360.129347 -352.16881) (xy 360.16808 -352.128521)
			(xy 360.212276 -352.094313) (xy 360.260988 -352.066917) (xy 360.313176 -352.046918) (xy 360.367722 -352.034745)
			(xy 360.42346 -352.030659) (xy 360.479198 -352.034745) (xy 360.533744 -352.046918) (xy 360.585932 -352.066917)
			(xy 360.634644 -352.094313) (xy 360.67884 -352.128521) (xy 360.717573 -352.16881) (xy 360.750016 -352.214317)
			(xy 360.775475 -352.26407) (xy 360.784902 -352.29038) (xy 360.796586 -352.324924) (xy 362.773214 -352.324924)
			(xy 362.78772 -352.324392) (xy 362.81555 -352.316187) (xy 362.839942 -352.300474) (xy 362.858919 -352.278527)
			(xy 362.870945 -352.252123) (xy 362.875046 -352.2234) (xy 362.870888 -352.194685) (xy 362.858811 -352.168304)
			(xy 362.849668 -352.15703) (xy 362.076238 -351.383346) (xy 362.076238 -349.788226) (xy 359.624122 -347.33611)
			(xy 336.823558 -347.33611) (xy 333.549498 -350.61017) (xy 326.167242 -350.61017) (xy 324.013322 -348.45625)
			(xy 322.710048 -348.45625) (xy 322.700904 -348.49562) (xy 322.693799 -348.524103) (xy 322.672033 -348.578621)
			(xy 322.642173 -348.629161) (xy 322.604924 -348.67453) (xy 322.561165 -348.713659) (xy 322.53682 -348.730062)
			(xy 322.495926 -348.756478) (xy 323.760741 -350.895412) (xy 336.039206 -350.895412) (xy 336.039731 -350.866495)
			(xy 336.048458 -350.809324) (xy 336.065715 -350.754126) (xy 336.091105 -350.702164) (xy 336.124048 -350.65463)
			(xy 336.163787 -350.612612) (xy 336.186272 -350.594422) (xy 336.198067 -350.584512) (xy 336.215587 -350.559193)
			(xy 336.224765 -350.529802) (xy 336.224768 -350.499012) (xy 336.215593 -350.469621) (xy 336.198077 -350.444299)
			(xy 336.186272 -350.434402) (xy 336.163784 -350.416217) (xy 336.12405 -350.374195) (xy 336.091112 -350.326659)
			(xy 336.065725 -350.274696) (xy 336.04847 -350.219498) (xy 336.039741 -350.162328) (xy 336.039206 -350.133412)
			(xy 336.039743 -350.1044) (xy 336.048511 -350.047042) (xy 336.065861 -349.991673) (xy 336.091395 -349.939569)
			(xy 336.124522 -349.891931) (xy 336.144108 -349.870522) (xy 336.154365 -349.858964) (xy 336.167938 -349.831216)
			(xy 336.1726 -349.80068) (xy 336.167925 -349.770145) (xy 336.154342 -349.742403) (xy 336.144108 -349.730822)
			(xy 336.124536 -349.709401) (xy 336.091417 -349.661761) (xy 336.065886 -349.609659) (xy 336.04853 -349.554295)
			(xy 336.039748 -349.496942) (xy 336.039206 -349.467932) (xy 336.039729 -349.440676) (xy 336.04749 -349.386719)
			(xy 336.062846 -349.334415) (xy 336.085484 -349.284826) (xy 336.114944 -349.23896) (xy 336.150627 -349.19775)
			(xy 336.191808 -349.162033) (xy 336.214466 -349.146876) (xy 336.226362 -349.138554) (xy 336.245364 -349.116627)
			(xy 336.25742 -349.090236) (xy 336.261553 -349.061517) (xy 336.25743 -349.032797) (xy 336.245383 -349.006402)
			(xy 336.226389 -348.984469) (xy 336.214466 -348.976188) (xy 336.19178 -348.961065) (xy 336.150579 -348.925356)
			(xy 336.11488 -348.884147) (xy 336.085409 -348.838276) (xy 336.062767 -348.788677) (xy 336.047415 -348.736361)
			(xy 336.039664 -348.682393) (xy 336.039206 -348.655132) (xy 336.039685 -348.627879) (xy 336.047438 -348.573928)
			(xy 336.062791 -348.52163) (xy 336.085431 -348.472049) (xy 336.114897 -348.426195) (xy 336.150589 -348.385001)
			(xy 336.19178 -348.349307) (xy 336.237633 -348.319839) (xy 336.287213 -348.297197) (xy 336.339511 -348.281842)
			(xy 336.393461 -348.274086) (xy 336.420714 -348.273624) (xy 336.446635 -348.274074) (xy 336.497997 -348.281107)
			(xy 336.547935 -348.295027) (xy 336.595529 -348.315578) (xy 336.639903 -348.342383) (xy 336.680241 -348.374947)
			(xy 336.698336 -348.393512) (xy 336.707692 -348.402998) (xy 336.730329 -348.417038) (xy 336.755831 -348.424737)
			(xy 336.782456 -348.425569) (xy 336.808389 -348.419477) (xy 336.831858 -348.406876) (xy 336.851264 -348.388627)
			(xy 336.85861 -348.37751) (xy 336.873637 -348.354274) (xy 336.909342 -348.312) (xy 336.950778 -348.275326)
			(xy 336.997075 -348.245019) (xy 337.047264 -348.221716) (xy 337.100292 -348.205904) (xy 337.155047 -348.197915)
			(xy 337.182714 -348.197424) (xy 337.209967 -348.197847) (xy 337.263918 -348.205606) (xy 337.316215 -348.220963)
			(xy 337.365795 -348.243607) (xy 337.411647 -348.273076) (xy 337.452839 -348.308771) (xy 337.488532 -348.349964)
			(xy 337.518 -348.395818) (xy 337.540642 -348.445398) (xy 337.555997 -348.497696) (xy 337.563754 -348.551647)
			(xy 337.563754 -348.606153) (xy 337.560749 -348.627052) (xy 337.766138 -348.627052) (xy 337.766138 -348.572548)
			(xy 337.773894 -348.518599) (xy 337.789248 -348.466303) (xy 337.811888 -348.416723) (xy 337.841353 -348.37087)
			(xy 337.877043 -348.329677) (xy 337.918232 -348.293982) (xy 337.964081 -348.264511) (xy 338.013657 -348.241865)
			(xy 338.065952 -348.226504) (xy 338.1199 -348.218741) (xy 338.147152 -348.218252) (xy 338.176069 -348.218785)
			(xy 338.23324 -348.227508) (xy 338.288439 -348.244762) (xy 338.340402 -348.270151) (xy 338.387936 -348.303093)
			(xy 338.429952 -348.342833) (xy 338.448142 -348.365318) (xy 338.458039 -348.377123) (xy 338.483363 -348.394642)
			(xy 338.512756 -348.403818) (xy 338.543548 -348.403818) (xy 338.572941 -348.394642) (xy 338.598265 -348.377123)
			(xy 338.608162 -348.365318) (xy 338.624915 -348.344535) (xy 338.663269 -348.307405) (xy 338.706423 -348.275983)
			(xy 338.753537 -348.250884) (xy 338.803689 -348.232598) (xy 338.8559 -348.221481) (xy 338.909152 -348.217751)
			(xy 338.962404 -348.221481) (xy 339.014615 -348.232598) (xy 339.064767 -348.250884) (xy 339.111881 -348.275983)
			(xy 339.155035 -348.307405) (xy 339.193389 -348.344535) (xy 339.210142 -348.365318) (xy 339.220039 -348.377123)
			(xy 339.245363 -348.394642) (xy 339.274756 -348.403818) (xy 339.305548 -348.403818) (xy 339.334941 -348.394642)
			(xy 339.360265 -348.377123) (xy 339.370162 -348.365318) (xy 339.386915 -348.344535) (xy 339.425269 -348.307405)
			(xy 339.468423 -348.275983) (xy 339.515537 -348.250884) (xy 339.565689 -348.232598) (xy 339.6179 -348.221481)
			(xy 339.671152 -348.217751) (xy 339.724404 -348.221481) (xy 339.776615 -348.232598) (xy 339.826767 -348.250884)
			(xy 339.873881 -348.275983) (xy 339.917035 -348.307405) (xy 339.955389 -348.344535) (xy 339.972142 -348.365318)
			(xy 339.982039 -348.377123) (xy 340.007363 -348.394642) (xy 340.036756 -348.403818) (xy 340.067548 -348.403818)
			(xy 340.096941 -348.394642) (xy 340.122265 -348.377123) (xy 340.132162 -348.365318) (xy 340.150379 -348.342856)
			(xy 340.192393 -348.303119) (xy 340.239922 -348.270177) (xy 340.291878 -348.244785) (xy 340.347072 -348.227524)
			(xy 340.404237 -348.21879) (xy 340.433152 -348.218252) (xy 340.461719 -348.218782) (xy 340.518214 -348.227316)
			(xy 340.572807 -348.244169) (xy 340.624281 -348.268966) (xy 340.671487 -348.301155) (xy 340.713371 -348.340015)
			(xy 340.731602 -348.362016) (xy 340.741172 -348.373259) (xy 340.765411 -348.390096) (xy 340.793451 -348.399307)
			(xy 340.822953 -348.400124) (xy 340.851459 -348.392478) (xy 340.876593 -348.377006) (xy 340.886796 -348.366334)
			(xy 340.904952 -348.346705) (xy 340.945838 -348.312247) (xy 340.991134 -348.283834) (xy 341.039954 -348.262024)
			(xy 341.09134 -348.247243) (xy 341.144287 -348.239782) (xy 341.171022 -348.239334) (xy 341.199937 -348.239896)
			(xy 341.257107 -348.248614) (xy 341.312306 -348.265862) (xy 341.364268 -348.291246) (xy 341.411803 -348.324183)
			(xy 341.453821 -348.363917) (xy 341.472012 -348.3864) (xy 341.481909 -348.398205) (xy 341.507233 -348.415724)
			(xy 341.536626 -348.4249) (xy 341.567418 -348.4249) (xy 341.596811 -348.415724) (xy 341.622135 -348.398205)
			(xy 341.632032 -348.3864) (xy 341.650205 -348.363901) (xy 341.692228 -348.324167) (xy 341.739767 -348.29123)
			(xy 341.791732 -348.265844) (xy 341.846933 -348.248591) (xy 341.904105 -348.239867) (xy 341.933022 -348.239334)
			(xy 341.960275 -348.239737) (xy 342.014227 -348.247497) (xy 342.066524 -348.262856) (xy 342.116104 -348.285501)
			(xy 342.161957 -348.314971) (xy 342.203149 -348.350666) (xy 342.238842 -348.391861) (xy 342.26831 -348.437715)
			(xy 342.290952 -348.487296) (xy 342.306307 -348.539595) (xy 342.314064 -348.593547) (xy 342.314064 -348.648053)
			(xy 342.306307 -348.702005) (xy 342.290952 -348.754304) (xy 342.26831 -348.803885) (xy 342.238842 -348.849739)
			(xy 342.203149 -348.890934) (xy 342.161957 -348.926629) (xy 342.116104 -348.956099) (xy 342.066524 -348.978744)
			(xy 342.014227 -348.994103) (xy 341.960275 -349.001863) (xy 341.933022 -349.00235) (xy 341.904105 -349.001835)
			(xy 341.846933 -348.993108) (xy 341.791733 -348.975851) (xy 341.739771 -348.950458) (xy 341.692237 -348.917513)
			(xy 341.650221 -348.877771) (xy 341.632032 -348.855284) (xy 341.622135 -348.843479) (xy 341.596811 -348.82596)
			(xy 341.567418 -348.816784) (xy 341.536626 -348.816784) (xy 341.507233 -348.82596) (xy 341.481909 -348.843479)
			(xy 341.472012 -348.855284) (xy 341.45381 -348.877758) (xy 341.411793 -348.917495) (xy 341.364261 -348.950435)
			(xy 341.312301 -348.975826) (xy 341.257106 -348.993084) (xy 341.199937 -349.001814) (xy 341.171022 -349.00235)
			(xy 341.142456 -349.001766) (xy 341.085964 -348.993244) (xy 341.031372 -348.976401) (xy 340.979898 -348.951614)
			(xy 340.932691 -348.919435) (xy 340.890804 -348.880583) (xy 340.872572 -348.858586) (xy 340.86303 -348.847318)
			(xy 340.838783 -348.83048) (xy 340.810736 -348.821272) (xy 340.781228 -348.82046) (xy 340.752717 -348.828113)
			(xy 340.727582 -348.843592) (xy 340.717378 -348.854268) (xy 340.699186 -348.873862) (xy 340.658307 -348.908323)
			(xy 340.613018 -348.93674) (xy 340.564206 -348.958556) (xy 340.512826 -348.973344) (xy 340.459885 -348.980815)
			(xy 340.433152 -348.981268) (xy 340.404236 -348.980725) (xy 340.347065 -348.972002) (xy 340.291866 -348.95475)
			(xy 340.239904 -348.929363) (xy 340.19237 -348.896424) (xy 340.150352 -348.856686) (xy 340.132162 -348.834202)
			(xy 340.122265 -348.822397) (xy 340.096941 -348.804878) (xy 340.067548 -348.795702) (xy 340.036756 -348.795702)
			(xy 340.007363 -348.804878) (xy 339.982039 -348.822397) (xy 339.972142 -348.834202) (xy 339.955389 -348.854985)
			(xy 339.917035 -348.892115) (xy 339.873881 -348.923537) (xy 339.826767 -348.948636) (xy 339.776615 -348.966922)
			(xy 339.724404 -348.978039) (xy 339.671152 -348.981769) (xy 339.6179 -348.978039) (xy 339.565689 -348.966922)
			(xy 339.515537 -348.948636) (xy 339.468423 -348.923537) (xy 339.425269 -348.892115) (xy 339.386915 -348.854985)
			(xy 339.370162 -348.834202) (xy 339.360265 -348.822397) (xy 339.334941 -348.804878) (xy 339.305548 -348.795702)
			(xy 339.274756 -348.795702) (xy 339.245363 -348.804878) (xy 339.220039 -348.822397) (xy 339.210142 -348.834202)
			(xy 339.193389 -348.854985) (xy 339.155035 -348.892115) (xy 339.111881 -348.923537) (xy 339.064767 -348.948636)
			(xy 339.014615 -348.966922) (xy 338.962404 -348.978039) (xy 338.909152 -348.981769) (xy 338.8559 -348.978039)
			(xy 338.803689 -348.966922) (xy 338.753537 -348.948636) (xy 338.706423 -348.923537) (xy 338.663269 -348.892115)
			(xy 338.624915 -348.854985) (xy 338.608162 -348.834202) (xy 338.598265 -348.822397) (xy 338.572941 -348.804878)
			(xy 338.543548 -348.795702) (xy 338.512756 -348.795702) (xy 338.483363 -348.804878) (xy 338.458039 -348.822397)
			(xy 338.448142 -348.834202) (xy 338.429928 -348.856666) (xy 338.387913 -348.896402) (xy 338.340383 -348.929343)
			(xy 338.288426 -348.954735) (xy 338.233233 -348.971996) (xy 338.176067 -348.98073) (xy 338.147152 -348.981268)
			(xy 338.1199 -348.980859) (xy 338.065952 -348.973096) (xy 338.013657 -348.957735) (xy 337.964081 -348.935089)
			(xy 337.918232 -348.905618) (xy 337.877043 -348.869923) (xy 337.841353 -348.82873) (xy 337.811888 -348.782877)
			(xy 337.789248 -348.733297) (xy 337.773894 -348.681001) (xy 337.766138 -348.627052) (xy 337.560749 -348.627052)
			(xy 337.555997 -348.660104) (xy 337.540642 -348.712402) (xy 337.518 -348.761982) (xy 337.488532 -348.807836)
			(xy 337.452839 -348.849029) (xy 337.411647 -348.884724) (xy 337.365795 -348.914193) (xy 337.316215 -348.936837)
			(xy 337.263918 -348.952194) (xy 337.209967 -348.959953) (xy 337.182714 -348.96044) (xy 337.156793 -348.960017)
			(xy 337.10543 -348.952976) (xy 337.055492 -348.939049) (xy 337.007899 -348.918493) (xy 336.963525 -348.891684)
			(xy 336.923187 -348.859117) (xy 336.905092 -348.840552) (xy 336.895703 -348.831104) (xy 336.873072 -348.817068)
			(xy 336.84758 -348.809369) (xy 336.820963 -348.808534) (xy 336.795038 -348.814618) (xy 336.771572 -348.827208)
			(xy 336.752166 -348.845443) (xy 336.744818 -348.856554) (xy 336.729487 -348.880269) (xy 336.692936 -348.923312)
			(xy 336.650442 -348.960499) (xy 336.626962 -348.976188) (xy 336.614968 -348.984388) (xy 336.595949 -349.006342)
			(xy 336.583886 -349.032766) (xy 336.579756 -349.061517) (xy 336.583895 -349.090268) (xy 336.595967 -349.116687)
			(xy 336.614994 -349.138635) (xy 336.626962 -349.146876) (xy 336.653745 -349.164882) (xy 336.701371 -349.208427)
			(xy 336.721704 -349.23349) (xy 336.731601 -349.245295) (xy 336.756925 -349.262814) (xy 336.786318 -349.27199)
			(xy 336.81711 -349.27199) (xy 336.846503 -349.262814) (xy 336.871827 -349.245295) (xy 336.881724 -349.23349)
			(xy 336.899899 -349.210993) (xy 336.941922 -349.171259) (xy 336.989461 -349.138322) (xy 337.041425 -349.112936)
			(xy 337.096625 -349.095683) (xy 337.153797 -349.086957) (xy 337.182714 -349.086424) (xy 337.209969 -349.086842)
			(xy 337.263923 -349.094602) (xy 337.316224 -349.109961) (xy 337.365806 -349.132608) (xy 337.411661 -349.16208)
			(xy 337.452854 -349.197779) (xy 337.488548 -349.238976) (xy 337.518015 -349.284834) (xy 337.540655 -349.33442)
			(xy 337.556008 -349.386722) (xy 337.563761 -349.440677) (xy 337.564222 -349.467932) (xy 337.563704 -349.496945)
			(xy 337.554931 -349.554303) (xy 337.537575 -349.609672) (xy 337.512038 -349.661775) (xy 337.478908 -349.709413)
			(xy 337.45932 -349.730822) (xy 337.449116 -349.742424) (xy 337.435534 -349.770156) (xy 337.43086 -349.80068)
			(xy 337.435521 -349.831205) (xy 337.449093 -349.858943) (xy 337.45932 -349.870522) (xy 337.478917 -349.891921)
			(xy 337.512032 -349.939567) (xy 337.537558 -349.991675) (xy 337.554908 -350.047044) (xy 337.563683 -350.1044)
			(xy 337.564222 -350.133412) (xy 337.563824 -350.15424) (xy 337.765644 -350.15424) (xy 337.766188 -350.125228)
			(xy 337.774952 -350.06787) (xy 337.792301 -350.012501) (xy 337.817833 -349.960397) (xy 337.85096 -349.912759)
			(xy 337.870546 -349.89135) (xy 337.880781 -349.879772) (xy 337.894365 -349.852032) (xy 337.899035 -349.8215)
			(xy 337.894365 -349.790968) (xy 337.880781 -349.763228) (xy 337.870546 -349.75165) (xy 337.850977 -349.730227)
			(xy 337.81786 -349.682586) (xy 337.79233 -349.630485) (xy 337.774972 -349.575122) (xy 337.766188 -349.51777)
			(xy 337.765644 -349.48876) (xy 337.76614 -349.46151) (xy 337.773901 -349.407565) (xy 337.789259 -349.355274)
			(xy 337.811901 -349.305699) (xy 337.841367 -349.259851) (xy 337.877057 -349.218663) (xy 337.918245 -349.182972)
			(xy 337.964092 -349.153505) (xy 338.013666 -349.130862) (xy 338.065957 -349.115503) (xy 338.119902 -349.107741)
			(xy 338.147152 -349.107252) (xy 338.176069 -349.107785) (xy 338.23324 -349.116508) (xy 338.288439 -349.133762)
			(xy 338.340402 -349.159151) (xy 338.387936 -349.192093) (xy 338.429952 -349.231833) (xy 338.448142 -349.254318)
			(xy 338.458039 -349.266123) (xy 338.483363 -349.283642) (xy 338.512756 -349.292818) (xy 338.543548 -349.292818)
			(xy 338.572941 -349.283642) (xy 338.598265 -349.266123) (xy 338.608162 -349.254318) (xy 338.624915 -349.233535)
			(xy 338.663269 -349.196405) (xy 338.706423 -349.164983) (xy 338.753537 -349.139884) (xy 338.803689 -349.121598)
			(xy 338.8559 -349.110481) (xy 338.909152 -349.106751) (xy 338.962404 -349.110481) (xy 339.014615 -349.121598)
			(xy 339.064767 -349.139884) (xy 339.111881 -349.164983) (xy 339.155035 -349.196405) (xy 339.193389 -349.233535)
			(xy 339.210142 -349.254318) (xy 339.220039 -349.266123) (xy 339.245363 -349.283642) (xy 339.274756 -349.292818)
			(xy 339.305548 -349.292818) (xy 339.334941 -349.283642) (xy 339.360265 -349.266123) (xy 339.370162 -349.254318)
			(xy 339.386915 -349.233535) (xy 339.425269 -349.196405) (xy 339.468423 -349.164983) (xy 339.515537 -349.139884)
			(xy 339.565689 -349.121598) (xy 339.6179 -349.110481) (xy 339.671152 -349.106751) (xy 339.724404 -349.110481)
			(xy 339.776615 -349.121598) (xy 339.826767 -349.139884) (xy 339.873881 -349.164983) (xy 339.917035 -349.196405)
			(xy 339.955389 -349.233535) (xy 339.972142 -349.254318) (xy 339.982039 -349.266123) (xy 340.007363 -349.283642)
			(xy 340.036756 -349.292818) (xy 340.067548 -349.292818) (xy 340.096941 -349.283642) (xy 340.122265 -349.266123)
			(xy 340.132162 -349.254318) (xy 340.150379 -349.231856) (xy 340.192393 -349.192119) (xy 340.239922 -349.159177)
			(xy 340.291878 -349.133785) (xy 340.347072 -349.116524) (xy 340.404237 -349.10779) (xy 340.433152 -349.107252)
			(xy 340.461719 -349.107782) (xy 340.518214 -349.116316) (xy 340.572807 -349.133169) (xy 340.624281 -349.157966)
			(xy 340.671487 -349.190155) (xy 340.713371 -349.229015) (xy 340.731602 -349.251016) (xy 340.741172 -349.262259)
			(xy 340.765411 -349.279096) (xy 340.793451 -349.288307) (xy 340.822953 -349.289124) (xy 340.851459 -349.281478)
			(xy 340.876593 -349.266006) (xy 340.886796 -349.255334) (xy 340.904952 -349.235705) (xy 340.945838 -349.201247)
			(xy 340.991134 -349.172834) (xy 341.039954 -349.151024) (xy 341.09134 -349.136243) (xy 341.144287 -349.128782)
			(xy 341.171022 -349.128334) (xy 341.199937 -349.128896) (xy 341.257107 -349.137614) (xy 341.312306 -349.154862)
			(xy 341.364268 -349.180246) (xy 341.411803 -349.213183) (xy 341.453821 -349.252917) (xy 341.472012 -349.2754)
			(xy 341.481909 -349.287205) (xy 341.507233 -349.304724) (xy 341.536626 -349.3139) (xy 341.567418 -349.3139)
			(xy 341.596811 -349.304724) (xy 341.622135 -349.287205) (xy 341.632032 -349.2754) (xy 341.650205 -349.252901)
			(xy 341.692228 -349.213167) (xy 341.739767 -349.18023) (xy 341.791732 -349.154844) (xy 341.846933 -349.137591)
			(xy 341.904105 -349.128867) (xy 341.933022 -349.128334) (xy 341.960275 -349.128737) (xy 342.014227 -349.136497)
			(xy 342.066524 -349.151856) (xy 342.116104 -349.174501) (xy 342.161957 -349.203971) (xy 342.203149 -349.239666)
			(xy 342.238842 -349.280861) (xy 342.26831 -349.326715) (xy 342.290952 -349.376296) (xy 342.306307 -349.428595)
			(xy 342.314064 -349.482547) (xy 342.314064 -349.537053) (xy 342.306307 -349.591005) (xy 342.290952 -349.643304)
			(xy 342.26831 -349.692885) (xy 342.238842 -349.738739) (xy 342.203149 -349.779934) (xy 342.161957 -349.815629)
			(xy 342.116104 -349.845099) (xy 342.066524 -349.867744) (xy 342.014227 -349.883103) (xy 341.960275 -349.890863)
			(xy 341.933022 -349.89135) (xy 341.904105 -349.890835) (xy 341.846933 -349.882108) (xy 341.791733 -349.864851)
			(xy 341.739771 -349.839458) (xy 341.692237 -349.806513) (xy 341.650221 -349.766771) (xy 341.632032 -349.744284)
			(xy 341.622135 -349.732479) (xy 341.596811 -349.71496) (xy 341.567418 -349.705784) (xy 341.536626 -349.705784)
			(xy 341.507233 -349.71496) (xy 341.481909 -349.732479) (xy 341.472012 -349.744284) (xy 341.45381 -349.766758)
			(xy 341.411793 -349.806495) (xy 341.364261 -349.839435) (xy 341.312301 -349.864826) (xy 341.257106 -349.882084)
			(xy 341.199937 -349.890814) (xy 341.171022 -349.89135) (xy 341.142456 -349.890766) (xy 341.085964 -349.882244)
			(xy 341.031372 -349.865401) (xy 340.979898 -349.840614) (xy 340.932691 -349.808435) (xy 340.890804 -349.769583)
			(xy 340.872572 -349.747586) (xy 340.86303 -349.736318) (xy 340.838783 -349.71948) (xy 340.810736 -349.710272)
			(xy 340.781228 -349.70946) (xy 340.752717 -349.717113) (xy 340.727582 -349.732592) (xy 340.717378 -349.743268)
			(xy 340.699186 -349.762862) (xy 340.658307 -349.797323) (xy 340.613018 -349.82574) (xy 340.564206 -349.847556)
			(xy 340.512826 -349.862344) (xy 340.459885 -349.869815) (xy 340.433152 -349.870268) (xy 340.404236 -349.869725)
			(xy 340.347065 -349.861002) (xy 340.291866 -349.84375) (xy 340.239904 -349.818363) (xy 340.19237 -349.785424)
			(xy 340.150352 -349.745686) (xy 340.132162 -349.723202) (xy 340.122265 -349.711397) (xy 340.096941 -349.693878)
			(xy 340.067548 -349.684702) (xy 340.036756 -349.684702) (xy 340.007363 -349.693878) (xy 339.982039 -349.711397)
			(xy 339.972142 -349.723202) (xy 339.955389 -349.743985) (xy 339.917035 -349.781115) (xy 339.873881 -349.812537)
			(xy 339.826767 -349.837636) (xy 339.776615 -349.855922) (xy 339.724404 -349.867039) (xy 339.671152 -349.870769)
			(xy 339.6179 -349.867039) (xy 339.565689 -349.855922) (xy 339.515537 -349.837636) (xy 339.468423 -349.812537)
			(xy 339.425269 -349.781115) (xy 339.386915 -349.743985) (xy 339.370162 -349.723202) (xy 339.360265 -349.711397)
			(xy 339.334941 -349.693878) (xy 339.305548 -349.684702) (xy 339.274756 -349.684702) (xy 339.245363 -349.693878)
			(xy 339.220039 -349.711397) (xy 339.210142 -349.723202) (xy 339.193389 -349.743985) (xy 339.155035 -349.781115)
			(xy 339.111881 -349.812537) (xy 339.064767 -349.837636) (xy 339.014615 -349.855922) (xy 338.962404 -349.867039)
			(xy 338.909152 -349.870769) (xy 338.8559 -349.867039) (xy 338.803689 -349.855922) (xy 338.753537 -349.837636)
			(xy 338.706423 -349.812537) (xy 338.663269 -349.781115) (xy 338.624915 -349.743985) (xy 338.608162 -349.723202)
			(xy 338.598265 -349.711397) (xy 338.572941 -349.693878) (xy 338.543548 -349.684702) (xy 338.512756 -349.684702)
			(xy 338.483363 -349.693878) (xy 338.458039 -349.711397) (xy 338.448142 -349.723202) (xy 338.423758 -349.75165)
			(xy 338.413523 -349.763228) (xy 338.399939 -349.790968) (xy 338.395268 -349.8215) (xy 338.399939 -349.852032)
			(xy 338.413523 -349.879772) (xy 338.423758 -349.89135) (xy 338.443327 -349.912773) (xy 338.476444 -349.960414)
			(xy 338.501975 -350.012515) (xy 338.519332 -350.067878) (xy 338.528116 -350.12523) (xy 338.52866 -350.15424)
			(xy 338.528174 -350.181491) (xy 338.520418 -350.235439) (xy 338.505063 -350.287734) (xy 338.482421 -350.337311)
			(xy 338.452955 -350.383161) (xy 338.417264 -350.424352) (xy 338.376073 -350.460043) (xy 338.330223 -350.489509)
			(xy 338.280646 -350.512151) (xy 338.228351 -350.527506) (xy 338.174403 -350.535262) (xy 338.119901 -350.535262)
			(xy 338.065953 -350.527506) (xy 338.013658 -350.512151) (xy 337.964081 -350.489509) (xy 337.918231 -350.460043)
			(xy 337.87704 -350.424352) (xy 337.841349 -350.383161) (xy 337.811883 -350.337311) (xy 337.789241 -350.287734)
			(xy 337.773886 -350.235439) (xy 337.76613 -350.181491) (xy 337.765644 -350.15424) (xy 337.563824 -350.15424)
			(xy 337.56367 -350.162328) (xy 337.554952 -350.219499) (xy 337.537703 -350.274698) (xy 337.512318 -350.326661)
			(xy 337.479378 -350.374195) (xy 337.43964 -350.416212) (xy 337.417156 -350.434402) (xy 337.405335 -350.444284)
			(xy 337.38781 -350.46961) (xy 337.378631 -350.499008) (xy 337.378634 -350.529806) (xy 337.387816 -350.559204)
			(xy 337.405345 -350.584527) (xy 337.417156 -350.594422) (xy 337.439641 -350.612612) (xy 337.479378 -350.65463)
			(xy 337.512318 -350.702165) (xy 337.537707 -350.754127) (xy 337.554962 -350.809325) (xy 337.563689 -350.866496)
			(xy 337.564222 -350.895412) (xy 337.563848 -350.91624) (xy 342.433656 -350.91624) (xy 342.434182 -350.887323)
			(xy 342.442906 -350.830151) (xy 342.460161 -350.774952) (xy 342.485551 -350.722989) (xy 342.518495 -350.675455)
			(xy 342.558236 -350.633439) (xy 342.580722 -350.61525) (xy 342.592484 -350.605307) (xy 342.609996 -350.579994)
			(xy 342.619172 -350.550614) (xy 342.61918 -350.519835) (xy 342.610018 -350.49045) (xy 342.592518 -350.465129)
			(xy 342.580722 -350.45523) (xy 342.558257 -350.437016) (xy 342.51852 -350.395002) (xy 342.485578 -350.347472)
			(xy 342.460186 -350.295515) (xy 342.442926 -350.240321) (xy 342.434193 -350.183155) (xy 342.433656 -350.15424)
			(xy 342.434224 -350.125229) (xy 342.442986 -350.067874) (xy 342.46033 -350.012505) (xy 342.485856 -349.960401)
			(xy 342.518976 -349.912761) (xy 342.538558 -349.89135) (xy 342.548791 -349.879771) (xy 342.562374 -349.852032)
			(xy 342.567044 -349.8215) (xy 342.562374 -349.790968) (xy 342.548791 -349.763229) (xy 342.538558 -349.75165)
			(xy 342.518991 -349.730225) (xy 342.485874 -349.682585) (xy 342.460342 -349.630484) (xy 342.442985 -349.575121)
			(xy 342.4342 -349.51777) (xy 342.433656 -349.48876) (xy 342.43414 -349.461509) (xy 342.441902 -349.407564)
			(xy 342.45726 -349.355271) (xy 342.479903 -349.305696) (xy 342.50937 -349.259848) (xy 342.545062 -349.218659)
			(xy 342.586251 -349.182968) (xy 342.632099 -349.153501) (xy 342.681675 -349.130858) (xy 342.733967 -349.115501)
			(xy 342.787913 -349.10774) (xy 342.815164 -349.107252) (xy 342.844081 -349.107776) (xy 342.901253 -349.116501)
			(xy 342.956452 -349.133757) (xy 343.008415 -349.159147) (xy 343.055948 -349.192091) (xy 343.097965 -349.231832)
			(xy 343.116154 -349.254318) (xy 343.126051 -349.266123) (xy 343.151375 -349.283642) (xy 343.180768 -349.292818)
			(xy 343.21156 -349.292818) (xy 343.240953 -349.283642) (xy 343.266277 -349.266123) (xy 343.276174 -349.254318)
			(xy 343.294384 -349.231851) (xy 343.336399 -349.192114) (xy 343.38393 -349.159172) (xy 343.435888 -349.133781)
			(xy 343.491082 -349.116521) (xy 343.548249 -349.107789) (xy 343.577164 -349.107252) (xy 343.604413 -349.107812)
			(xy 343.658355 -349.115562) (xy 343.710646 -349.130911) (xy 343.760221 -349.153545) (xy 343.806069 -349.183003)
			(xy 343.847259 -349.218687) (xy 343.882951 -349.25987) (xy 343.912419 -349.305713) (xy 343.935063 -349.355282)
			(xy 343.950422 -349.40757) (xy 343.958183 -349.461512) (xy 343.958672 -349.48876) (xy 343.958124 -349.517772)
			(xy 343.94936 -349.575129) (xy 343.932012 -349.630498) (xy 343.906481 -349.682603) (xy 343.873356 -349.730241)
			(xy 343.85377 -349.75165) (xy 343.843534 -349.763227) (xy 343.829948 -349.790967) (xy 343.825277 -349.8215)
			(xy 343.829948 -349.852033) (xy 343.843534 -349.879773) (xy 343.85377 -349.89135) (xy 343.873341 -349.912771)
			(xy 343.906457 -349.960413) (xy 343.931987 -350.012514) (xy 343.949344 -350.067878) (xy 343.958128 -350.12523)
			(xy 343.958672 -350.15424) (xy 343.958121 -350.183156) (xy 343.949401 -350.240326) (xy 343.93215 -350.295525)
			(xy 343.906764 -350.347487) (xy 343.873826 -350.395021) (xy 343.834089 -350.437039) (xy 343.811606 -350.45523)
			(xy 343.799761 -350.465084) (xy 343.782246 -350.49042) (xy 343.773075 -350.519824) (xy 343.773082 -350.550625)
			(xy 343.782267 -350.580025) (xy 343.799795 -350.605352) (xy 343.811606 -350.61525) (xy 343.834067 -350.633468)
			(xy 343.873803 -350.675482) (xy 343.906745 -350.723012) (xy 343.932137 -350.774968) (xy 343.949398 -350.83016)
			(xy 343.958133 -350.887326) (xy 343.958672 -350.91624) (xy 343.958259 -350.943494) (xy 343.950496 -350.997446)
			(xy 343.935134 -351.049744) (xy 343.912486 -351.099324) (xy 343.883012 -351.145176) (xy 343.847313 -351.186367)
			(xy 343.806115 -351.222058) (xy 343.760257 -351.251522) (xy 343.710673 -351.274161) (xy 343.658372 -351.289513)
			(xy 343.604418 -351.297265) (xy 343.577164 -351.297748) (xy 343.548248 -351.297203) (xy 343.491077 -351.288482)
			(xy 343.435878 -351.271231) (xy 343.383916 -351.245844) (xy 343.336381 -351.212904) (xy 343.294364 -351.173166)
			(xy 343.276174 -351.150682) (xy 343.266277 -351.138877) (xy 343.240953 -351.121358) (xy 343.21156 -351.112182)
			(xy 343.180768 -351.112182) (xy 343.151375 -351.121358) (xy 343.126051 -351.138877) (xy 343.116154 -351.150682)
			(xy 343.097928 -351.173136) (xy 343.055916 -351.212874) (xy 343.008389 -351.245817) (xy 342.956434 -351.27121)
			(xy 342.901243 -351.288473) (xy 342.844078 -351.297209) (xy 342.815164 -351.297748) (xy 342.787914 -351.297256)
			(xy 342.733968 -351.289495) (xy 342.681676 -351.274138) (xy 342.632101 -351.251495) (xy 342.586253 -351.222029)
			(xy 342.545064 -351.186338) (xy 342.509373 -351.14515) (xy 342.479907 -351.099302) (xy 342.457264 -351.049728)
			(xy 342.441905 -350.997436) (xy 342.434144 -350.94349) (xy 342.433656 -350.91624) (xy 337.563848 -350.91624)
			(xy 337.563733 -350.922663) (xy 337.555976 -350.97661) (xy 337.54062 -351.028904) (xy 337.517978 -351.07848)
			(xy 337.488512 -351.12433) (xy 337.452821 -351.165519) (xy 337.411631 -351.201211) (xy 337.365782 -351.230677)
			(xy 337.316206 -351.253319) (xy 337.263912 -351.268675) (xy 337.209965 -351.276433) (xy 337.182714 -351.27692)
			(xy 337.153796 -351.276422) (xy 337.096622 -351.267693) (xy 337.041422 -351.250433) (xy 336.98946 -351.225038)
			(xy 336.941926 -351.192089) (xy 336.899912 -351.152342) (xy 336.881724 -351.129854) (xy 336.871827 -351.118049)
			(xy 336.846503 -351.10053) (xy 336.81711 -351.091354) (xy 336.786318 -351.091354) (xy 336.756925 -351.10053)
			(xy 336.731601 -351.118049) (xy 336.721704 -351.129854) (xy 336.703524 -351.152347) (xy 336.661501 -351.192079)
			(xy 336.613963 -351.225015) (xy 336.562 -351.250402) (xy 336.506801 -351.267656) (xy 336.44963 -351.276385)
			(xy 336.420714 -351.27692) (xy 336.393462 -351.276432) (xy 336.339513 -351.268677) (xy 336.287216 -351.253323)
			(xy 336.237637 -351.230683) (xy 336.191784 -351.201218) (xy 336.150592 -351.165527) (xy 336.114898 -351.124337)
			(xy 336.085429 -351.078486) (xy 336.062786 -351.028908) (xy 336.047429 -350.976613) (xy 336.03967 -350.922664)
			(xy 336.039206 -350.895412) (xy 323.760741 -350.895412) (xy 326.400466 -355.359462) (xy 346.853256 -355.359462)
			(xy 346.853256 -352.941636) (xy 346.85375 -352.912511) (xy 346.86141 -352.854765) (xy 346.876539 -352.798512)
			(xy 346.898877 -352.744714) (xy 346.928043 -352.694289) (xy 346.963539 -352.648102) (xy 346.983812 -352.627184)
			(xy 350.693482 -348.917514) (xy 350.7144 -348.897252) (xy 350.760596 -348.86179) (xy 350.811026 -348.832662)
			(xy 350.864826 -348.810365) (xy 350.921077 -348.795283) (xy 350.978815 -348.787672) (xy 351.007934 -348.787212)
			(xy 359.212388 -348.787212) (xy 359.241508 -348.787685) (xy 359.29925 -348.795278) (xy 359.355505 -348.81035)
			(xy 359.40931 -348.832641) (xy 359.459741 -348.86177) (xy 359.505935 -348.897238) (xy 359.52684 -348.917514)
			(xy 361.653328 -351.044002) (xy 361.673642 -351.064885) (xy 361.709158 -351.111067) (xy 361.738334 -351.161494)
			(xy 361.760671 -351.215302) (xy 361.775785 -351.271567) (xy 361.783417 -351.329324) (xy 361.783884 -351.358454)
			(xy 361.783336 -351.387561) (xy 361.775746 -351.445277) (xy 361.76069 -351.501509) (xy 361.738425 -351.555297)
			(xy 361.709333 -351.605719) (xy 361.67391 -351.651914) (xy 361.632763 -351.693092) (xy 361.586594 -351.72855)
			(xy 361.536193 -351.757679) (xy 361.482422 -351.779984) (xy 361.426201 -351.795081) (xy 361.36849 -351.802714)
			(xy 361.339384 -351.803208) (xy 361.338876 -351.803208) (xy 361.309756 -351.802752) (xy 361.252013 -351.795155)
			(xy 361.195758 -351.780079) (xy 361.141954 -351.757785) (xy 361.091523 -351.728653) (xy 361.045329 -351.693183)
			(xy 361.024424 -351.672906) (xy 359.028238 -349.67672) (xy 351.192084 -349.67672) (xy 350.201049 -350.667828)
			(xy 354.882702 -350.667828) (xy 354.886773 -350.612206) (xy 354.898899 -350.557769) (xy 354.918822 -350.505678)
			(xy 354.946118 -350.457043) (xy 354.980204 -350.4129) (xy 355.020353 -350.374191) (xy 355.065711 -350.34174)
			(xy 355.115311 -350.316239) (xy 355.168095 -350.298232) (xy 355.222938 -350.288102) (xy 355.278672 -350.286065)
			(xy 355.334109 -350.292165) (xy 355.388066 -350.306271) (xy 355.439395 -350.328083) (xy 355.487001 -350.357137)
			(xy 355.529869 -350.392812) (xy 355.567086 -350.434349) (xy 355.597859 -350.480862) (xy 355.621531 -350.531359)
			(xy 355.637599 -350.584766) (xy 355.645719 -350.639942) (xy 355.646228 -350.667828) (xy 355.645719 -350.695714)
			(xy 355.637599 -350.75089) (xy 355.621531 -350.804297) (xy 355.597859 -350.854794) (xy 355.567086 -350.901307)
			(xy 355.529869 -350.942844) (xy 355.487001 -350.978519) (xy 355.439395 -351.007573) (xy 355.388066 -351.029385)
			(xy 355.334109 -351.043491) (xy 355.278672 -351.049591) (xy 355.222938 -351.047554) (xy 355.168095 -351.037424)
			(xy 355.115311 -351.019417) (xy 355.065711 -350.993916) (xy 355.020353 -350.961465) (xy 354.980204 -350.922756)
			(xy 354.946118 -350.878613) (xy 354.918822 -350.829978) (xy 354.898899 -350.777887) (xy 354.886773 -350.72345)
			(xy 354.882702 -350.667828) (xy 350.201049 -350.667828) (xy 349.263858 -351.605088) (xy 351.934778 -351.605088)
			(xy 351.938849 -351.549466) (xy 351.950975 -351.495029) (xy 351.970898 -351.442938) (xy 351.998194 -351.394303)
			(xy 352.03228 -351.35016) (xy 352.072429 -351.311451) (xy 352.117787 -351.279) (xy 352.167387 -351.253499)
			(xy 352.220171 -351.235492) (xy 352.275014 -351.225362) (xy 352.330748 -351.223325) (xy 352.386185 -351.229425)
			(xy 352.440142 -351.243531) (xy 352.491471 -351.265343) (xy 352.539077 -351.294397) (xy 352.581945 -351.330072)
			(xy 352.619162 -351.371609) (xy 352.649935 -351.418122) (xy 352.673607 -351.468619) (xy 352.689675 -351.522026)
			(xy 352.697795 -351.577202) (xy 352.698304 -351.605088) (xy 352.697795 -351.632974) (xy 352.689675 -351.68815)
			(xy 352.673607 -351.741557) (xy 352.649935 -351.792054) (xy 352.627431 -351.826068) (xy 352.798378 -351.826068)
			(xy 352.802449 -351.770446) (xy 352.814575 -351.716009) (xy 352.834498 -351.663918) (xy 352.861794 -351.615283)
			(xy 352.89588 -351.57114) (xy 352.936029 -351.532431) (xy 352.981387 -351.49998) (xy 353.030987 -351.474479)
			(xy 353.083771 -351.456472) (xy 353.138614 -351.446342) (xy 353.194348 -351.444305) (xy 353.249785 -351.450405)
			(xy 353.303742 -351.464511) (xy 353.355071 -351.486323) (xy 353.402677 -351.515377) (xy 353.445545 -351.551052)
			(xy 353.482762 -351.592589) (xy 353.513535 -351.639102) (xy 353.537207 -351.689599) (xy 353.553275 -351.743006)
			(xy 353.561395 -351.798182) (xy 353.561904 -351.826068) (xy 353.561395 -351.853954) (xy 353.553275 -351.90913)
			(xy 353.537207 -351.962537) (xy 353.513535 -352.013034) (xy 353.482762 -352.059547) (xy 353.445545 -352.101084)
			(xy 353.402677 -352.136759) (xy 353.355071 -352.165813) (xy 353.303742 -352.187625) (xy 353.249785 -352.201731)
			(xy 353.194348 -352.207831) (xy 353.138614 -352.205794) (xy 353.083771 -352.195664) (xy 353.030987 -352.177657)
			(xy 352.981387 -352.152156) (xy 352.936029 -352.119705) (xy 352.89588 -352.080996) (xy 352.861794 -352.036853)
			(xy 352.834498 -351.988218) (xy 352.814575 -351.936127) (xy 352.802449 -351.88169) (xy 352.798378 -351.826068)
			(xy 352.627431 -351.826068) (xy 352.619162 -351.838567) (xy 352.581945 -351.880104) (xy 352.539077 -351.915779)
			(xy 352.491471 -351.944833) (xy 352.440142 -351.966645) (xy 352.386185 -351.980751) (xy 352.330748 -351.986851)
			(xy 352.275014 -351.984814) (xy 352.220171 -351.974684) (xy 352.167387 -351.956677) (xy 352.117787 -351.931176)
			(xy 352.072429 -351.898725) (xy 352.03228 -351.860016) (xy 351.998194 -351.815873) (xy 351.970898 -351.767238)
			(xy 351.950975 -351.715147) (xy 351.938849 -351.66071) (xy 351.934778 -351.605088) (xy 349.263858 -351.605088)
			(xy 347.743272 -353.125786) (xy 347.743272 -355.359462) (xy 347.742753 -355.389866) (xy 347.734473 -355.450107)
			(xy 347.718068 -355.50866) (xy 347.693842 -355.564434) (xy 347.662247 -355.616389) (xy 347.623872 -355.663559)
			(xy 347.579431 -355.705063) (xy 347.529753 -355.74013) (xy 347.475763 -355.768105) (xy 347.418466 -355.788469)
			(xy 347.35893 -355.80084) (xy 347.298264 -355.80499) (xy 347.237598 -355.80084) (xy 347.178062 -355.788469)
			(xy 347.120765 -355.768105) (xy 347.066775 -355.74013) (xy 347.017097 -355.705063) (xy 346.972656 -355.663559)
			(xy 346.934281 -355.616389) (xy 346.902686 -355.564434) (xy 346.87846 -355.50866) (xy 346.862055 -355.450107)
			(xy 346.853775 -355.389866) (xy 346.853256 -355.359462) (xy 326.400466 -355.359462) (xy 327.307677 -356.89365)
			(xy 336.912199 -356.89365) (xy 336.912199 -356.83915) (xy 336.919955 -356.785205) (xy 336.93531 -356.732913)
			(xy 336.95795 -356.683338) (xy 336.987415 -356.63749) (xy 337.023105 -356.596302) (xy 337.064293 -356.560613)
			(xy 337.110142 -356.531148) (xy 337.159717 -356.508508) (xy 337.212009 -356.493155) (xy 337.265954 -356.485399)
			(xy 337.293204 -356.484936) (xy 337.319273 -356.485399) (xy 337.370924 -356.492507) (xy 337.421127 -356.506577)
			(xy 337.468949 -356.527347) (xy 337.5135 -356.55443) (xy 337.553953 -356.587323) (xy 337.589553 -356.625414)
			(xy 337.619639 -356.667995) (xy 337.63204 -356.69093) (xy 337.638853 -356.703047) (xy 337.65782 -356.723352)
			(xy 337.681561 -356.737788) (xy 337.708317 -356.745284) (xy 337.736103 -356.745284) (xy 337.762859 -356.737788)
			(xy 337.7866 -356.723352) (xy 337.805567 -356.703047) (xy 337.81238 -356.69093) (xy 337.825437 -356.666805)
			(xy 337.857419 -356.622237) (xy 337.895431 -356.582687) (xy 337.916774 -356.565454) (xy 337.928536 -356.555509)
			(xy 337.946057 -356.530199) (xy 337.955239 -356.500818) (xy 337.955247 -356.470036) (xy 337.946081 -356.44065)
			(xy 337.928574 -356.41533) (xy 337.916774 -356.405434) (xy 337.894301 -356.38723) (xy 337.854567 -356.345212)
			(xy 337.821627 -356.29768) (xy 337.796237 -356.245721) (xy 337.778978 -356.190526) (xy 337.770245 -356.133359)
			(xy 337.769708 -356.104444) (xy 337.770196 -356.077192) (xy 337.777948 -356.023241) (xy 337.793299 -355.970942)
			(xy 337.815937 -355.921361) (xy 337.845402 -355.875507) (xy 337.881094 -355.834314) (xy 337.922285 -355.798619)
			(xy 337.968137 -355.769151) (xy 338.017716 -355.746509) (xy 338.070013 -355.731154) (xy 338.123964 -355.723398)
			(xy 338.151216 -355.722936) (xy 338.180131 -355.723501) (xy 338.237301 -355.732219) (xy 338.292499 -355.749466)
			(xy 338.344462 -355.774849) (xy 338.391997 -355.807785) (xy 338.434015 -355.84752) (xy 338.452206 -355.870002)
			(xy 338.462103 -355.881807) (xy 338.487427 -355.899326) (xy 338.51682 -355.908502) (xy 338.547612 -355.908502)
			(xy 338.577005 -355.899326) (xy 338.602329 -355.881807) (xy 338.612226 -355.870002) (xy 338.628979 -355.849219)
			(xy 338.667333 -355.812089) (xy 338.710487 -355.780667) (xy 338.757601 -355.755568) (xy 338.807753 -355.737282)
			(xy 338.859964 -355.726165) (xy 338.913216 -355.722435) (xy 338.966468 -355.726165) (xy 339.018679 -355.737282)
			(xy 339.068831 -355.755568) (xy 339.115945 -355.780667) (xy 339.159099 -355.812089) (xy 339.197453 -355.849219)
			(xy 339.214206 -355.870002) (xy 339.224103 -355.881807) (xy 339.249427 -355.899326) (xy 339.27882 -355.908502)
			(xy 339.309612 -355.908502) (xy 339.339005 -355.899326) (xy 339.364329 -355.881807) (xy 339.374226 -355.870002)
			(xy 339.390979 -355.849219) (xy 339.429333 -355.812089) (xy 339.472487 -355.780667) (xy 339.519601 -355.755568)
			(xy 339.569753 -355.737282) (xy 339.621964 -355.726165) (xy 339.675216 -355.722435) (xy 339.728468 -355.726165)
			(xy 339.780679 -355.737282) (xy 339.830831 -355.755568) (xy 339.877945 -355.780667) (xy 339.921099 -355.812089)
			(xy 339.959453 -355.849219) (xy 339.976206 -355.870002) (xy 339.986103 -355.881807) (xy 340.011427 -355.899326)
			(xy 340.04082 -355.908502) (xy 340.071612 -355.908502) (xy 340.101005 -355.899326) (xy 340.126329 -355.881807)
			(xy 340.136226 -355.870002) (xy 340.152979 -355.849219) (xy 340.191333 -355.812089) (xy 340.234487 -355.780667)
			(xy 340.281601 -355.755568) (xy 340.331753 -355.737282) (xy 340.383964 -355.726165) (xy 340.437216 -355.722435)
			(xy 340.490468 -355.726165) (xy 340.542679 -355.737282) (xy 340.592831 -355.755568) (xy 340.639945 -355.780667)
			(xy 340.683099 -355.812089) (xy 340.721453 -355.849219) (xy 340.738206 -355.870002) (xy 340.748103 -355.881807)
			(xy 340.773427 -355.899326) (xy 340.80282 -355.908502) (xy 340.833612 -355.908502) (xy 340.863005 -355.899326)
			(xy 340.888329 -355.881807) (xy 340.898226 -355.870002) (xy 340.914979 -355.849219) (xy 340.953333 -355.812089)
			(xy 340.996487 -355.780667) (xy 341.043601 -355.755568) (xy 341.093753 -355.737282) (xy 341.145964 -355.726165)
			(xy 341.199216 -355.722435) (xy 341.252468 -355.726165) (xy 341.304679 -355.737282) (xy 341.354831 -355.755568)
			(xy 341.401945 -355.780667) (xy 341.445099 -355.812089) (xy 341.483453 -355.849219) (xy 341.500206 -355.870002)
			(xy 341.510103 -355.881807) (xy 341.535427 -355.899326) (xy 341.56482 -355.908502) (xy 341.595612 -355.908502)
			(xy 341.625005 -355.899326) (xy 341.650329 -355.881807) (xy 341.660226 -355.870002) (xy 341.678403 -355.847506)
			(xy 341.720425 -355.807772) (xy 341.767963 -355.774834) (xy 341.819927 -355.749448) (xy 341.875127 -355.732194)
			(xy 341.932299 -355.723469) (xy 341.961216 -355.722936) (xy 341.987469 -355.723337) (xy 342.03948 -355.730528)
			(xy 342.090012 -355.744786) (xy 342.138112 -355.76584) (xy 342.182868 -355.793294) (xy 342.223436 -355.826627)
			(xy 342.259047 -355.86521) (xy 342.274398 -355.886512) (xy 342.282762 -355.897725) (xy 342.304387 -355.915451)
			(xy 342.330011 -355.926648) (xy 342.35771 -355.930476) (xy 342.385409 -355.926648) (xy 342.411033 -355.915451)
			(xy 342.432658 -355.897725) (xy 342.441022 -355.886512) (xy 342.456356 -355.865201) (xy 342.491981 -355.826635)
			(xy 342.532557 -355.793316) (xy 342.577317 -355.765873) (xy 342.625416 -355.744825) (xy 342.675946 -355.730568)
			(xy 342.727953 -355.723372) (xy 342.754204 -355.722936) (xy 342.784327 -355.723508) (xy 342.843823 -355.73299)
			(xy 342.901091 -355.7517) (xy 342.954708 -355.779176) (xy 343.003343 -355.814733) (xy 343.024968 -355.835712)
			(xy 343.03469 -355.84493) (xy 343.057852 -355.858375) (xy 343.083713 -355.865337) (xy 343.110495 -355.865337)
			(xy 343.136356 -355.858375) (xy 343.159518 -355.84493) (xy 343.16924 -355.835712) (xy 343.19087 -355.814737)
			(xy 343.239497 -355.779168) (xy 343.293112 -355.751687) (xy 343.350382 -355.732977) (xy 343.40988 -355.723505)
			(xy 343.440004 -355.722936) (xy 343.467259 -355.723352) (xy 343.521214 -355.73111) (xy 343.573515 -355.746469)
			(xy 343.623098 -355.769115) (xy 343.668954 -355.798588) (xy 343.710147 -355.834287) (xy 343.745841 -355.875485)
			(xy 343.775308 -355.921344) (xy 343.797948 -355.97093) (xy 343.8133 -356.023233) (xy 343.821052 -356.077189)
			(xy 343.821512 -356.104444) (xy 343.820987 -356.133361) (xy 343.812264 -356.190533) (xy 343.795009 -356.245734)
			(xy 343.769619 -356.297696) (xy 343.736675 -356.34523) (xy 343.696932 -356.387245) (xy 343.674446 -356.405434)
			(xy 343.662593 -356.415281) (xy 343.645071 -356.440617) (xy 343.635897 -356.470024) (xy 343.635899 -356.478332)
			(xy 346.916246 -356.478332) (xy 346.920317 -356.42271) (xy 346.932443 -356.368273) (xy 346.952366 -356.316182)
			(xy 346.979662 -356.267547) (xy 347.013748 -356.223404) (xy 347.053897 -356.184695) (xy 347.099255 -356.152244)
			(xy 347.148855 -356.126743) (xy 347.201639 -356.108736) (xy 347.256482 -356.098606) (xy 347.312216 -356.096569)
			(xy 347.367653 -356.102669) (xy 347.42161 -356.116775) (xy 347.472939 -356.138587) (xy 347.520545 -356.167641)
			(xy 347.563413 -356.203316) (xy 347.60063 -356.244853) (xy 347.631403 -356.291366) (xy 347.655075 -356.341863)
			(xy 347.671143 -356.39527) (xy 347.679263 -356.450446) (xy 347.679772 -356.478332) (xy 347.679263 -356.506218)
			(xy 347.671143 -356.561394) (xy 347.655075 -356.614801) (xy 347.631403 -356.665298) (xy 347.60063 -356.711811)
			(xy 347.563413 -356.753348) (xy 347.520545 -356.789023) (xy 347.472939 -356.818077) (xy 347.42161 -356.839889)
			(xy 347.367653 -356.853995) (xy 347.312216 -356.860095) (xy 347.256482 -356.858058) (xy 347.201639 -356.847928)
			(xy 347.148855 -356.829921) (xy 347.099255 -356.80442) (xy 347.053897 -356.771969) (xy 347.013748 -356.73326)
			(xy 346.979662 -356.689117) (xy 346.952366 -356.640482) (xy 346.932443 -356.588391) (xy 346.920317 -356.533954)
			(xy 346.916246 -356.478332) (xy 343.635899 -356.478332) (xy 343.635905 -356.500829) (xy 343.645095 -356.530232)
			(xy 343.662631 -356.555558) (xy 343.674446 -356.565454) (xy 343.696917 -356.583659) (xy 343.736651 -356.625678)
			(xy 343.76959 -356.67321) (xy 343.79498 -356.725168) (xy 343.81224 -356.780362) (xy 343.820974 -356.837529)
			(xy 343.821512 -356.866444) (xy 343.821063 -356.893696) (xy 343.813301 -356.947645) (xy 343.79794 -356.99994)
			(xy 343.775294 -357.049517) (xy 343.745824 -357.095367) (xy 343.710129 -357.136557) (xy 343.668935 -357.172248)
			(xy 343.623082 -357.201713) (xy 343.573503 -357.224354) (xy 343.521206 -357.239709) (xy 343.467256 -357.247466)
			(xy 343.440004 -357.247952) (xy 343.409881 -357.247378) (xy 343.350384 -357.237898) (xy 343.293117 -357.219188)
			(xy 343.2395 -357.191712) (xy 343.190865 -357.156155) (xy 343.16924 -357.135176) (xy 343.159518 -357.125958)
			(xy 343.136356 -357.112513) (xy 343.110495 -357.105551) (xy 343.083713 -357.105551) (xy 343.057852 -357.112513)
			(xy 343.03469 -357.125958) (xy 343.024968 -357.135176) (xy 343.003332 -357.156145) (xy 342.954707 -357.191715)
			(xy 342.901093 -357.219198) (xy 342.843825 -357.237909) (xy 342.784328 -357.247383) (xy 342.754204 -357.247952)
			(xy 342.727951 -357.247541) (xy 342.675941 -357.240352) (xy 342.625408 -357.226097) (xy 342.577309 -357.205044)
			(xy 342.532552 -357.177592) (xy 342.491984 -357.14426) (xy 342.456373 -357.105677) (xy 342.441022 -357.084376)
			(xy 342.432658 -357.073163) (xy 342.411033 -357.055437) (xy 342.385409 -357.04424) (xy 342.35771 -357.040412)
			(xy 342.330011 -357.04424) (xy 342.304387 -357.055437) (xy 342.282762 -357.073163) (xy 342.274398 -357.084376)
			(xy 342.259048 -357.105675) (xy 342.223426 -357.144242) (xy 342.182853 -357.177562) (xy 342.138096 -357.205006)
			(xy 342.09 -357.226057) (xy 342.039472 -357.240316) (xy 341.987467 -357.247514) (xy 341.961216 -357.247952)
			(xy 341.932299 -357.24744) (xy 341.875126 -357.238713) (xy 341.819927 -357.221454) (xy 341.767964 -357.196062)
			(xy 341.720431 -357.163116) (xy 341.678415 -357.123373) (xy 341.660226 -357.100886) (xy 341.650329 -357.089081)
			(xy 341.625005 -357.071562) (xy 341.595612 -357.062386) (xy 341.56482 -357.062386) (xy 341.535427 -357.071562)
			(xy 341.510103 -357.089081) (xy 341.500206 -357.100886) (xy 341.483453 -357.121669) (xy 341.445099 -357.158799)
			(xy 341.401945 -357.190221) (xy 341.354831 -357.21532) (xy 341.304679 -357.233606) (xy 341.252468 -357.244723)
			(xy 341.199216 -357.248453) (xy 341.145964 -357.244723) (xy 341.093753 -357.233606) (xy 341.043601 -357.21532)
			(xy 340.996487 -357.190221) (xy 340.953333 -357.158799) (xy 340.914979 -357.121669) (xy 340.898226 -357.100886)
			(xy 340.888329 -357.089081) (xy 340.863005 -357.071562) (xy 340.833612 -357.062386) (xy 340.80282 -357.062386)
			(xy 340.773427 -357.071562) (xy 340.748103 -357.089081) (xy 340.738206 -357.100886) (xy 340.721453 -357.121669)
			(xy 340.683099 -357.158799) (xy 340.639945 -357.190221) (xy 340.592831 -357.21532) (xy 340.542679 -357.233606)
			(xy 340.490468 -357.244723) (xy 340.437216 -357.248453) (xy 340.383964 -357.244723) (xy 340.331753 -357.233606)
			(xy 340.281601 -357.21532) (xy 340.234487 -357.190221) (xy 340.191333 -357.158799) (xy 340.152979 -357.121669)
			(xy 340.136226 -357.100886) (xy 340.126329 -357.089081) (xy 340.101005 -357.071562) (xy 340.071612 -357.062386)
			(xy 340.04082 -357.062386) (xy 340.011427 -357.071562) (xy 339.986103 -357.089081) (xy 339.976206 -357.100886)
			(xy 339.959453 -357.121669) (xy 339.921099 -357.158799) (xy 339.877945 -357.190221) (xy 339.830831 -357.21532)
			(xy 339.780679 -357.233606) (xy 339.728468 -357.244723) (xy 339.675216 -357.248453) (xy 339.621964 -357.244723)
			(xy 339.569753 -357.233606) (xy 339.519601 -357.21532) (xy 339.472487 -357.190221) (xy 339.429333 -357.158799)
			(xy 339.390979 -357.121669) (xy 339.374226 -357.100886) (xy 339.364329 -357.089081) (xy 339.339005 -357.071562)
			(xy 339.309612 -357.062386) (xy 339.27882 -357.062386) (xy 339.249427 -357.071562) (xy 339.224103 -357.089081)
			(xy 339.214206 -357.100886) (xy 339.197453 -357.121669) (xy 339.159099 -357.158799) (xy 339.115945 -357.190221)
			(xy 339.068831 -357.21532) (xy 339.018679 -357.233606) (xy 338.966468 -357.244723) (xy 338.913216 -357.248453)
			(xy 338.859964 -357.244723) (xy 338.807753 -357.233606) (xy 338.757601 -357.21532) (xy 338.710487 -357.190221)
			(xy 338.667333 -357.158799) (xy 338.628979 -357.121669) (xy 338.612226 -357.100886) (xy 338.602329 -357.089081)
			(xy 338.577005 -357.071562) (xy 338.547612 -357.062386) (xy 338.51682 -357.062386) (xy 338.487427 -357.071562)
			(xy 338.462103 -357.089081) (xy 338.452206 -357.100886) (xy 338.434008 -357.123364) (xy 338.39199 -357.1631)
			(xy 338.344457 -357.19604) (xy 338.292497 -357.221429) (xy 338.2373 -357.238687) (xy 338.180132 -357.247417)
			(xy 338.151216 -357.247952) (xy 338.125148 -357.247479) (xy 338.073497 -357.240373) (xy 338.023293 -357.226305)
			(xy 337.975471 -357.205538) (xy 337.93092 -357.178456) (xy 337.890467 -357.145564) (xy 337.854867 -357.107473)
			(xy 337.82478 -357.064893) (xy 337.81238 -357.041958) (xy 337.805567 -357.029841) (xy 337.7866 -357.009536)
			(xy 337.762859 -356.9951) (xy 337.736103 -356.987604) (xy 337.708317 -356.987604) (xy 337.681561 -356.9951)
			(xy 337.65782 -357.009536) (xy 337.638853 -357.029841) (xy 337.63204 -357.041958) (xy 337.619684 -357.064922)
			(xy 337.589607 -357.107522) (xy 337.554009 -357.145628) (xy 337.513553 -357.178532) (xy 337.468992 -357.20562)
			(xy 337.421158 -357.226386) (xy 337.370941 -357.240445) (xy 337.319278 -357.247534) (xy 337.293204 -357.247952)
			(xy 337.265954 -357.247401) (xy 337.212009 -357.239645) (xy 337.159717 -357.224292) (xy 337.110142 -357.201652)
			(xy 337.064293 -357.172187) (xy 337.023105 -357.136498) (xy 336.987415 -357.09531) (xy 336.95795 -357.049462)
			(xy 336.93531 -356.999887) (xy 336.919955 -356.947595) (xy 336.912199 -356.89365) (xy 327.307677 -356.89365)
			(xy 328.694435 -359.238802) (xy 335.453223 -359.238802) (xy 335.456952 -359.18555) (xy 335.46807 -359.133337)
			(xy 335.486358 -359.083185) (xy 335.511459 -359.036072) (xy 335.542884 -358.992918) (xy 335.580018 -358.954566)
			(xy 335.600802 -358.937814) (xy 335.612602 -358.927911) (xy 335.630117 -358.902589) (xy 335.639292 -358.873197)
			(xy 335.639292 -358.842407) (xy 335.630119 -358.813016) (xy 335.612605 -358.787692) (xy 335.600802 -358.777794)
			(xy 335.578316 -358.759606) (xy 335.538581 -358.717586) (xy 335.505642 -358.67005) (xy 335.480254 -358.618088)
			(xy 335.462999 -358.56289) (xy 335.45427 -358.50572) (xy 335.453736 -358.476804) (xy 335.454159 -358.449549)
			(xy 335.461917 -358.395595) (xy 335.477275 -358.343293) (xy 335.49992 -358.29371) (xy 335.529391 -358.247855)
			(xy 335.565089 -358.206661) (xy 335.606287 -358.170967) (xy 335.652145 -358.141501) (xy 335.701731 -358.118861)
			(xy 335.754034 -358.103508) (xy 335.807989 -358.095756) (xy 335.835244 -358.095296) (xy 335.864296 -358.095875)
			(xy 335.92173 -358.104666) (xy 335.977166 -358.122067) (xy 336.029321 -358.147676) (xy 336.076988 -358.1809)
			(xy 336.119063 -358.220971) (xy 336.13725 -358.243632) (xy 336.146504 -358.254707) (xy 336.169828 -358.271677)
			(xy 336.196969 -358.281442) (xy 336.225758 -358.283222) (xy 336.253895 -358.276877) (xy 336.279133 -358.262911)
			(xy 336.28965 -358.25303) (xy 336.298332 -358.244396) (xy 336.316634 -358.228128) (xy 336.326226 -358.220518)
			(xy 336.33802 -358.21061) (xy 336.355531 -358.185287) (xy 336.364703 -358.155898) (xy 336.364705 -358.125111)
			(xy 336.355535 -358.095721) (xy 336.338026 -358.070397) (xy 336.326226 -358.060498) (xy 336.303747 -358.042302)
			(xy 336.26401 -358.000284) (xy 336.23107 -357.95275) (xy 336.205681 -357.90079) (xy 336.188424 -357.845593)
			(xy 336.179695 -357.788424) (xy 336.17916 -357.759508) (xy 336.179685 -357.732258) (xy 336.18744 -357.678314)
			(xy 336.202792 -357.626022) (xy 336.22543 -357.576447) (xy 336.254893 -357.530598) (xy 336.29058 -357.489408)
			(xy 336.331766 -357.453717) (xy 336.377611 -357.424249) (xy 336.427184 -357.401606) (xy 336.479475 -357.386248)
			(xy 336.533418 -357.378488) (xy 336.560668 -357.378) (xy 336.588047 -357.378477) (xy 336.64224 -357.386314)
			(xy 336.694757 -357.401816) (xy 336.744519 -357.424665) (xy 336.790505 -357.454393) (xy 336.831769 -357.490388)
			(xy 336.849974 -357.510842) (xy 336.860022 -357.521832) (xy 336.885087 -357.537887) (xy 336.913716 -357.54604)
			(xy 336.943479 -357.545599) (xy 336.971854 -357.536602) (xy 336.996433 -357.519812) (xy 337.006184 -357.508556)
			(xy 337.024421 -357.486776) (xy 337.066213 -357.448305) (xy 337.113247 -357.416454) (xy 337.164482 -357.391927)
			(xy 337.218787 -357.375267) (xy 337.274962 -357.366841) (xy 337.303364 -357.366316) (xy 337.331062 -357.366795)
			(xy 337.385876 -357.374797) (xy 337.438957 -357.390639) (xy 337.489191 -357.413988) (xy 337.535522 -357.444352)
			(xy 337.576978 -357.481096) (xy 337.59521 -357.501952) (xy 337.604729 -357.512643) (xy 337.628495 -357.528585)
			(xy 337.655753 -357.537301) (xy 337.684359 -357.538106) (xy 337.712064 -357.530938) (xy 337.736689 -357.516359)
			(xy 337.746848 -357.50627) (xy 337.764952 -357.487755) (xy 337.805259 -357.455249) (xy 337.849593 -357.428494)
			(xy 337.897138 -357.407982) (xy 337.947021 -357.394091) (xy 337.998325 -357.387075) (xy 338.024216 -357.386636)
			(xy 338.051471 -357.38704) (xy 338.105427 -357.3948) (xy 338.157728 -357.410161) (xy 338.207312 -357.432808)
			(xy 338.253167 -357.462282) (xy 338.29436 -357.497982) (xy 338.330054 -357.539181) (xy 338.35952 -357.585041)
			(xy 338.38216 -357.634628) (xy 338.397512 -357.686932) (xy 338.405264 -357.740889) (xy 338.405724 -357.768144)
			(xy 338.405194 -357.797061) (xy 338.396471 -357.854233) (xy 338.379218 -357.909433) (xy 338.353828 -357.961395)
			(xy 338.320885 -358.008929) (xy 338.281144 -358.050945) (xy 338.258658 -358.069134) (xy 338.246804 -358.078981)
			(xy 338.22928 -358.104316) (xy 338.220104 -358.133724) (xy 338.220112 -358.16453) (xy 338.229303 -358.193933)
			(xy 338.246842 -358.219259) (xy 338.258658 -358.229154) (xy 338.281111 -358.247382) (xy 338.32085 -358.289392)
			(xy 338.353794 -358.336919) (xy 338.379188 -358.388874) (xy 338.39645 -358.444065) (xy 338.405186 -358.50123)
			(xy 338.405724 -358.530144) (xy 338.405225 -358.557347) (xy 338.397493 -358.611202) (xy 338.382179 -358.663409)
			(xy 338.359595 -358.712906) (xy 338.330198 -358.758688) (xy 338.31276 -358.779572) (xy 338.303282 -358.791464)
			(xy 338.291054 -358.819286) (xy 338.287557 -358.849474) (xy 338.293099 -358.879354) (xy 338.307191 -358.906279)
			(xy 338.328583 -358.927865) (xy 338.341716 -358.935528) (xy 338.364879 -358.948451) (xy 338.407693 -358.979759)
			(xy 338.445736 -359.016719) (xy 338.462366 -359.037382) (xy 338.472263 -359.049187) (xy 338.497587 -359.066706)
			(xy 338.52698 -359.075882) (xy 338.557772 -359.075882) (xy 338.587165 -359.066706) (xy 338.612489 -359.049187)
			(xy 338.622386 -359.037382) (xy 338.639139 -359.016599) (xy 338.677493 -358.979469) (xy 338.720647 -358.948047)
			(xy 338.767761 -358.922948) (xy 338.817913 -358.904662) (xy 338.870124 -358.893545) (xy 338.923376 -358.889815)
			(xy 338.976628 -358.893545) (xy 339.028839 -358.904662) (xy 339.078991 -358.922948) (xy 339.126105 -358.948047)
			(xy 339.169259 -358.979469) (xy 339.207613 -359.016599) (xy 339.224366 -359.037382) (xy 339.234263 -359.049187)
			(xy 339.259587 -359.066706) (xy 339.28898 -359.075882) (xy 339.319772 -359.075882) (xy 339.349165 -359.066706)
			(xy 339.374489 -359.049187) (xy 339.384386 -359.037382) (xy 339.401139 -359.016599) (xy 339.439493 -358.979469)
			(xy 339.482647 -358.948047) (xy 339.529761 -358.922948) (xy 339.579913 -358.904662) (xy 339.632124 -358.893545)
			(xy 339.685376 -358.889815) (xy 339.738628 -358.893545) (xy 339.790839 -358.904662) (xy 339.840991 -358.922948)
			(xy 339.888105 -358.948047) (xy 339.931259 -358.979469) (xy 339.969613 -359.016599) (xy 339.986366 -359.037382)
			(xy 339.996263 -359.049187) (xy 340.021587 -359.066706) (xy 340.05098 -359.075882) (xy 340.081772 -359.075882)
			(xy 340.111165 -359.066706) (xy 340.136489 -359.049187) (xy 340.146386 -359.037382) (xy 340.163139 -359.016599)
			(xy 340.201493 -358.979469) (xy 340.244647 -358.948047) (xy 340.291761 -358.922948) (xy 340.341913 -358.904662)
			(xy 340.394124 -358.893545) (xy 340.447376 -358.889815) (xy 340.500628 -358.893545) (xy 340.552839 -358.904662)
			(xy 340.602991 -358.922948) (xy 340.650105 -358.948047) (xy 340.693259 -358.979469) (xy 340.731613 -359.016599)
			(xy 340.748366 -359.037382) (xy 340.758263 -359.049187) (xy 340.783587 -359.066706) (xy 340.81298 -359.075882)
			(xy 340.843772 -359.075882) (xy 340.873165 -359.066706) (xy 340.898489 -359.049187) (xy 340.908386 -359.037382)
			(xy 340.925139 -359.016599) (xy 340.963493 -358.979469) (xy 341.006647 -358.948047) (xy 341.053761 -358.922948)
			(xy 341.103913 -358.904662) (xy 341.156124 -358.893545) (xy 341.209376 -358.889815) (xy 341.262628 -358.893545)
			(xy 341.314839 -358.904662) (xy 341.364991 -358.922948) (xy 341.412105 -358.948047) (xy 341.455259 -358.979469)
			(xy 341.493613 -359.016599) (xy 341.510366 -359.037382) (xy 341.520263 -359.049187) (xy 341.545587 -359.066706)
			(xy 341.57498 -359.075882) (xy 341.605772 -359.075882) (xy 341.635165 -359.066706) (xy 341.660489 -359.049187)
			(xy 341.670386 -359.037382) (xy 341.688207 -359.015359) (xy 341.729273 -358.976336) (xy 341.752174 -358.959658)
			(xy 341.764272 -358.950505) (xy 341.782866 -358.926555) (xy 341.793608 -358.8982) (xy 341.795551 -358.867941)
			(xy 341.788523 -358.838446) (xy 341.773144 -358.812314) (xy 341.762334 -358.80167) (xy 341.743114 -358.783539)
			(xy 341.709397 -358.742857) (xy 341.681616 -358.697912) (xy 341.660303 -358.649563) (xy 341.645864 -358.598736)
			(xy 341.638575 -358.546403) (xy 341.638128 -358.519984) (xy 341.638696 -358.491069) (xy 341.647413 -358.4339)
			(xy 341.664661 -358.378701) (xy 341.690043 -358.326739) (xy 341.722978 -358.279204) (xy 341.762712 -358.237186)
			(xy 341.785194 -358.218994) (xy 341.797015 -358.209114) (xy 341.814531 -358.183785) (xy 341.823704 -358.154388)
			(xy 341.823701 -358.123593) (xy 341.814522 -358.094197) (xy 341.797001 -358.068872) (xy 341.785194 -358.058974)
			(xy 341.762697 -358.040799) (xy 341.722963 -357.998776) (xy 341.690026 -357.951238) (xy 341.66464 -357.899273)
			(xy 341.647386 -357.844073) (xy 341.638661 -357.786901) (xy 341.638128 -357.757984) (xy 341.63854 -357.730729)
			(xy 341.6463 -357.676774) (xy 341.66166 -357.624473) (xy 341.684307 -357.574891) (xy 341.71378 -357.529036)
			(xy 341.749479 -357.487842) (xy 341.790678 -357.452149) (xy 341.836536 -357.422682) (xy 341.886122 -357.400042)
			(xy 341.938425 -357.384689) (xy 341.992381 -357.376936) (xy 342.019636 -357.376476) (xy 342.01989 -357.376476)
			(xy 342.047433 -357.37695) (xy 342.101943 -357.384895) (xy 342.154745 -357.400592) (xy 342.204743 -357.423715)
			(xy 342.250898 -357.453785) (xy 342.292251 -357.490176) (xy 342.310466 -357.510842) (xy 342.320577 -357.521809)
			(xy 342.345631 -357.537962) (xy 342.374281 -357.5462) (xy 342.404088 -357.545822) (xy 342.432519 -357.536859)
			(xy 342.457154 -357.520074) (xy 342.46693 -357.50881) (xy 342.485142 -357.486967) (xy 342.526959 -357.448426)
			(xy 342.574034 -357.416519) (xy 342.625322 -357.39195) (xy 342.679689 -357.375266) (xy 342.735929 -357.366836)
			(xy 342.764364 -357.366316) (xy 342.794486 -357.366919) (xy 342.85398 -357.376394) (xy 342.911248 -357.395098)
			(xy 342.964865 -357.422566) (xy 343.013502 -357.458117) (xy 343.035128 -357.479092) (xy 343.04485 -357.48831)
			(xy 343.068012 -357.501755) (xy 343.093873 -357.508717) (xy 343.120655 -357.508717) (xy 343.146516 -357.501755)
			(xy 343.169678 -357.48831) (xy 343.1794 -357.479092) (xy 343.201 -357.458085) (xy 343.249636 -357.422521)
			(xy 343.303259 -357.395046) (xy 343.360534 -357.376344) (xy 343.420038 -357.36688) (xy 343.450164 -357.366316)
			(xy 343.477417 -357.366789) (xy 343.531369 -357.374542) (xy 343.583668 -357.389894) (xy 343.63325 -357.412534)
			(xy 343.679104 -357.442001) (xy 343.720298 -357.477694) (xy 343.734715 -357.494332) (xy 346.916246 -357.494332)
			(xy 346.920317 -357.43871) (xy 346.932443 -357.384273) (xy 346.952366 -357.332182) (xy 346.979662 -357.283547)
			(xy 347.013748 -357.239404) (xy 347.053897 -357.200695) (xy 347.099255 -357.168244) (xy 347.148855 -357.142743)
			(xy 347.201639 -357.124736) (xy 347.256482 -357.114606) (xy 347.312216 -357.112569) (xy 347.367653 -357.118669)
			(xy 347.42161 -357.132775) (xy 347.472939 -357.154587) (xy 347.520545 -357.183641) (xy 347.563413 -357.219316)
			(xy 347.60063 -357.260853) (xy 347.631403 -357.307366) (xy 347.655075 -357.357863) (xy 347.671143 -357.41127)
			(xy 347.679263 -357.466446) (xy 347.679772 -357.494332) (xy 347.679263 -357.522218) (xy 347.671143 -357.577394)
			(xy 347.655075 -357.630801) (xy 347.631403 -357.681298) (xy 347.60063 -357.727811) (xy 347.563413 -357.769348)
			(xy 347.520545 -357.805023) (xy 347.472939 -357.834077) (xy 347.42161 -357.855889) (xy 347.367653 -357.869995)
			(xy 347.312216 -357.876095) (xy 347.256482 -357.874058) (xy 347.201639 -357.863928) (xy 347.148855 -357.845921)
			(xy 347.099255 -357.82042) (xy 347.053897 -357.787969) (xy 347.013748 -357.74926) (xy 346.979662 -357.705117)
			(xy 346.952366 -357.656482) (xy 346.932443 -357.604391) (xy 346.920317 -357.549954) (xy 346.916246 -357.494332)
			(xy 343.734715 -357.494332) (xy 343.755992 -357.518886) (xy 343.78546 -357.56474) (xy 343.808102 -357.614321)
			(xy 343.823456 -357.666619) (xy 343.83121 -357.720571) (xy 343.831672 -357.747824) (xy 343.83111 -357.776739)
			(xy 343.822392 -357.833909) (xy 343.805143 -357.889108) (xy 343.77976 -357.94107) (xy 343.746823 -357.988605)
			(xy 343.707089 -358.030623) (xy 343.684606 -358.048814) (xy 343.672777 -358.058686) (xy 343.655261 -358.084017)
			(xy 343.646089 -358.113416) (xy 343.646093 -358.144213) (xy 343.655274 -358.17361) (xy 343.672798 -358.198936)
			(xy 343.684606 -358.208834) (xy 343.705414 -358.225558) (xy 343.742548 -358.263913) (xy 343.773972 -358.307071)
			(xy 343.799073 -358.354188) (xy 343.81736 -358.404344) (xy 343.828477 -358.456559) (xy 343.832205 -358.509815)
			(xy 343.828473 -358.56307) (xy 343.817352 -358.615285) (xy 343.799061 -358.665439) (xy 343.773957 -358.712554)
			(xy 343.742529 -358.755709) (xy 343.705392 -358.794062) (xy 343.684606 -358.810814) (xy 343.672777 -358.820686)
			(xy 343.655261 -358.846017) (xy 343.646089 -358.875416) (xy 343.646093 -358.906213) (xy 343.655274 -358.93561)
			(xy 343.672798 -358.960936) (xy 343.684606 -358.970834) (xy 343.705414 -358.987558) (xy 343.742548 -359.025913)
			(xy 343.773972 -359.069071) (xy 343.799073 -359.116188) (xy 343.81736 -359.166344) (xy 343.828477 -359.218559)
			(xy 343.832205 -359.271815) (xy 343.828473 -359.32507) (xy 343.822394 -359.353612) (xy 346.946726 -359.353612)
			(xy 346.950797 -359.29799) (xy 346.962923 -359.243553) (xy 346.982846 -359.191462) (xy 347.010142 -359.142827)
			(xy 347.044228 -359.098684) (xy 347.084377 -359.059975) (xy 347.129735 -359.027524) (xy 347.179335 -359.002023)
			(xy 347.232119 -358.984016) (xy 347.286962 -358.973886) (xy 347.342696 -358.971849) (xy 347.398133 -358.977949)
			(xy 347.45209 -358.992055) (xy 347.503419 -359.013867) (xy 347.551025 -359.042921) (xy 347.593893 -359.078596)
			(xy 347.63111 -359.120133) (xy 347.661883 -359.166646) (xy 347.685555 -359.217143) (xy 347.701623 -359.27055)
			(xy 347.709743 -359.325726) (xy 347.710252 -359.353612) (xy 347.709743 -359.381498) (xy 347.701623 -359.436674)
			(xy 347.685555 -359.490081) (xy 347.661883 -359.540578) (xy 347.63111 -359.587091) (xy 347.593893 -359.628628)
			(xy 347.551025 -359.664303) (xy 347.503419 -359.693357) (xy 347.45209 -359.715169) (xy 347.398133 -359.729275)
			(xy 347.342696 -359.735375) (xy 347.286962 -359.733338) (xy 347.232119 -359.723208) (xy 347.179335 -359.705201)
			(xy 347.129735 -359.6797) (xy 347.084377 -359.647249) (xy 347.044228 -359.60854) (xy 347.010142 -359.564397)
			(xy 346.982846 -359.515762) (xy 346.962923 -359.463671) (xy 346.950797 -359.409234) (xy 346.946726 -359.353612)
			(xy 343.822394 -359.353612) (xy 343.817352 -359.377285) (xy 343.799061 -359.427439) (xy 343.773957 -359.474554)
			(xy 343.742529 -359.517709) (xy 343.705392 -359.556062) (xy 343.684606 -359.572814) (xy 343.672777 -359.582686)
			(xy 343.655261 -359.608017) (xy 343.646089 -359.637416) (xy 343.646093 -359.668213) (xy 343.655274 -359.69761)
			(xy 343.672798 -359.722936) (xy 343.684606 -359.732834) (xy 343.705414 -359.749558) (xy 343.742548 -359.787913)
			(xy 343.773972 -359.831071) (xy 343.799073 -359.878188) (xy 343.81736 -359.928344) (xy 343.828477 -359.980559)
			(xy 343.832205 -360.033815) (xy 343.828473 -360.08707) (xy 343.817352 -360.139285) (xy 343.799061 -360.189439)
			(xy 343.773957 -360.236554) (xy 343.742529 -360.279709) (xy 343.705392 -360.318062) (xy 343.684606 -360.334814)
			(xy 343.672777 -360.344686) (xy 343.655261 -360.370017) (xy 343.646089 -360.399416) (xy 343.646093 -360.430213)
			(xy 343.655274 -360.45961) (xy 343.672798 -360.484936) (xy 343.673697 -360.48569) (xy 347.061788 -360.48569)
			(xy 347.065859 -360.430068) (xy 347.077985 -360.375631) (xy 347.097908 -360.32354) (xy 347.125204 -360.274905)
			(xy 347.15929 -360.230762) (xy 347.199439 -360.192053) (xy 347.244797 -360.159602) (xy 347.294397 -360.134101)
			(xy 347.347181 -360.116094) (xy 347.402024 -360.105964) (xy 347.457758 -360.103927) (xy 347.513195 -360.110027)
			(xy 347.567152 -360.124133) (xy 347.618481 -360.145945) (xy 347.666087 -360.174999) (xy 347.708955 -360.210674)
			(xy 347.746172 -360.252211) (xy 347.776945 -360.298724) (xy 347.800617 -360.349221) (xy 347.816685 -360.402628)
			(xy 347.824805 -360.457804) (xy 347.825314 -360.48569) (xy 347.824805 -360.513576) (xy 347.816685 -360.568752)
			(xy 347.800617 -360.622159) (xy 347.776945 -360.672656) (xy 347.746172 -360.719169) (xy 347.708955 -360.760706)
			(xy 347.666087 -360.796381) (xy 347.618481 -360.825435) (xy 347.567152 -360.847247) (xy 347.513195 -360.861353)
			(xy 347.457758 -360.867453) (xy 347.402024 -360.865416) (xy 347.347181 -360.855286) (xy 347.294397 -360.837279)
			(xy 347.244797 -360.811778) (xy 347.199439 -360.779327) (xy 347.15929 -360.740618) (xy 347.125204 -360.696475)
			(xy 347.097908 -360.64784) (xy 347.077985 -360.595749) (xy 347.065859 -360.541312) (xy 347.061788 -360.48569)
			(xy 343.673697 -360.48569) (xy 343.684606 -360.494834) (xy 343.707107 -360.513004) (xy 343.746841 -360.555029)
			(xy 343.779778 -360.602568) (xy 343.805163 -360.654533) (xy 343.822415 -360.709734) (xy 343.83114 -360.766907)
			(xy 343.831672 -360.795824) (xy 343.831267 -360.823079) (xy 343.823506 -360.877034) (xy 343.808145 -360.929335)
			(xy 343.785497 -360.978918) (xy 343.756023 -361.024773) (xy 343.720324 -361.065966) (xy 343.679125 -361.101659)
			(xy 343.633265 -361.131126) (xy 343.583679 -361.153766) (xy 343.531375 -361.169119) (xy 343.477419 -361.176872)
			(xy 343.450164 -361.177332) (xy 343.420835 -361.17678) (xy 343.362867 -361.167803) (xy 343.306955 -361.150067)
			(xy 343.254413 -361.123987) (xy 343.206477 -361.090179) (xy 343.164276 -361.049438) (xy 343.128803 -361.002721)
			(xy 343.114376 -360.97718) (xy 343.109557 -360.969235) (xy 343.095458 -360.957159) (xy 343.077983 -360.950894)
			(xy 343.059423 -360.951261) (xy 343.04221 -360.958212) (xy 343.035128 -360.964226) (xy 343.02319 -360.974894)
			(xy 343.013502 -360.983802) (xy 342.998565 -361.005455) (xy 342.98967 -361.030211) (xy 342.987408 -361.056418)
			(xy 342.991932 -361.082332) (xy 343.002939 -361.106223) (xy 343.010998 -361.116626) (xy 343.027386 -361.137204)
			(xy 343.054961 -361.182004) (xy 343.076115 -361.23017) (xy 343.090444 -361.280787) (xy 343.097678 -361.332893)
			(xy 343.09812 -361.359196) (xy 343.097619 -361.386447) (xy 343.089863 -361.440393) (xy 343.074509 -361.492687)
			(xy 343.051869 -361.542263) (xy 343.022404 -361.588113) (xy 342.986714 -361.629303) (xy 342.945526 -361.664995)
			(xy 342.899677 -361.694461) (xy 342.850102 -361.717103) (xy 342.797809 -361.732459) (xy 342.743863 -361.740217)
			(xy 342.716612 -361.740704) (xy 342.687694 -361.740214) (xy 342.630519 -361.731484) (xy 342.575318 -361.714223)
			(xy 342.523356 -361.688826) (xy 342.475823 -361.655876) (xy 342.43381 -361.616127) (xy 342.415622 -361.593638)
			(xy 342.405725 -361.581833) (xy 342.380401 -361.564314) (xy 342.351008 -361.555138) (xy 342.320216 -361.555138)
			(xy 342.290823 -361.564314) (xy 342.265499 -361.581833) (xy 342.255602 -361.593638) (xy 342.248333 -361.602813)
			(xy 342.232828 -361.620351) (xy 342.224614 -361.62869) (xy 342.214238 -361.639813) (xy 342.200039 -361.666701)
			(xy 342.19437 -361.696575) (xy 342.197731 -361.726795) (xy 342.209827 -361.754692) (xy 342.21928 -361.766612)
			(xy 342.236469 -361.78743) (xy 342.265387 -361.833019) (xy 342.287596 -361.882227) (xy 342.302652 -361.934073)
			(xy 342.310254 -361.987522) (xy 342.31072 -362.014516) (xy 342.310237 -362.041767) (xy 342.302479 -362.095714)
			(xy 342.287122 -362.148008) (xy 342.26448 -362.197585) (xy 342.235013 -362.243435) (xy 342.199322 -362.284624)
			(xy 342.158131 -362.320316) (xy 342.112281 -362.349782) (xy 342.062705 -362.372424) (xy 342.01041 -362.38778)
			(xy 341.956463 -362.395537) (xy 341.929212 -362.396024) (xy 341.901243 -362.395556) (xy 341.845902 -362.3874)
			(xy 341.792347 -362.371247) (xy 341.741726 -362.347444) (xy 341.695126 -362.3165) (xy 341.653546 -362.279081)
			(xy 341.635334 -362.257848) (xy 341.625758 -362.247132) (xy 341.601994 -362.231) (xy 341.574677 -362.222124)
			(xy 341.545969 -362.221208) (xy 341.518142 -362.228325) (xy 341.493398 -362.24291) (xy 341.483188 -362.253022)
			(xy 341.465075 -362.271613) (xy 341.424725 -362.30426) (xy 341.38032 -362.331132) (xy 341.33268 -362.351734)
			(xy 341.282687 -362.365685) (xy 341.231264 -362.372726) (xy 341.205312 -362.373164) (xy 341.176395 -362.372651)
			(xy 341.119223 -362.363923) (xy 341.064023 -362.346664) (xy 341.012061 -362.321272) (xy 340.964528 -362.288327)
			(xy 340.922511 -362.248584) (xy 340.904322 -362.226098) (xy 340.894425 -362.214293) (xy 340.869101 -362.196774)
			(xy 340.839708 -362.187598) (xy 340.808916 -362.187598) (xy 340.779523 -362.196774) (xy 340.754199 -362.214293)
			(xy 340.744302 -362.226098) (xy 340.727549 -362.246881) (xy 340.689195 -362.284011) (xy 340.646041 -362.315433)
			(xy 340.598927 -362.340532) (xy 340.548775 -362.358818) (xy 340.496564 -362.369935) (xy 340.443312 -362.373665)
			(xy 340.39006 -362.369935) (xy 340.337849 -362.358818) (xy 340.287697 -362.340532) (xy 340.240583 -362.315433)
			(xy 340.197429 -362.284011) (xy 340.159075 -362.246881) (xy 340.142322 -362.226098) (xy 340.132425 -362.214293)
			(xy 340.107101 -362.196774) (xy 340.077708 -362.187598) (xy 340.046916 -362.187598) (xy 340.017523 -362.196774)
			(xy 339.992199 -362.214293) (xy 339.982302 -362.226098) (xy 339.964109 -362.24858) (xy 339.92209 -362.288315)
			(xy 339.874555 -362.321255) (xy 339.822594 -362.346643) (xy 339.767397 -362.3639) (xy 339.710228 -362.372629)
			(xy 339.681312 -362.373164) (xy 339.654097 -362.372702) (xy 339.600221 -362.364968) (xy 339.54799 -362.349654)
			(xy 339.498466 -362.327072) (xy 339.452655 -362.297681) (xy 339.411486 -362.262076) (xy 339.393276 -362.241846)
			(xy 339.383459 -362.231266) (xy 339.359238 -362.215595) (xy 339.331598 -362.207332) (xy 339.302751 -362.207139)
			(xy 339.275003 -362.215032) (xy 339.250575 -362.230378) (xy 339.240622 -362.24083) (xy 339.222462 -362.260636)
			(xy 339.18151 -362.295429) (xy 339.13608 -362.324127) (xy 339.08707 -362.346163) (xy 339.035452 -362.3611)
			(xy 338.982248 -362.368642) (xy 338.95538 -362.3691) (xy 338.926465 -362.368524) (xy 338.869297 -362.359807)
			(xy 338.814099 -362.342561) (xy 338.762137 -362.31718) (xy 338.714602 -362.284246) (xy 338.672582 -362.244515)
			(xy 338.65439 -362.222034) (xy 338.644493 -362.210229) (xy 338.619169 -362.19271) (xy 338.589776 -362.183534)
			(xy 338.558984 -362.183534) (xy 338.529591 -362.19271) (xy 338.504267 -362.210229) (xy 338.49437 -362.222034)
			(xy 338.476205 -362.244539) (xy 338.434178 -362.284271) (xy 338.386638 -362.317207) (xy 338.334672 -362.342591)
			(xy 338.27947 -362.359843) (xy 338.222297 -362.368567) (xy 338.19338 -362.3691) (xy 338.167312 -362.36863)
			(xy 338.115662 -362.361521) (xy 338.06546 -362.347451) (xy 338.017638 -362.326681) (xy 337.973087 -362.299599)
			(xy 337.932635 -362.266708) (xy 337.897034 -362.228618) (xy 337.866946 -362.18604) (xy 337.854544 -362.163106)
			(xy 337.847731 -362.150989) (xy 337.828764 -362.130684) (xy 337.805023 -362.116248) (xy 337.778267 -362.108752)
			(xy 337.750481 -362.108752) (xy 337.723725 -362.116248) (xy 337.699984 -362.130684) (xy 337.681017 -362.150989)
			(xy 337.674204 -362.163106) (xy 337.661804 -362.186044) (xy 337.63173 -362.228638) (xy 337.596136 -362.266741)
			(xy 337.555686 -362.299643) (xy 337.511132 -362.326731) (xy 337.463305 -362.347499) (xy 337.413096 -362.361562)
			(xy 337.361439 -362.368658) (xy 337.335368 -362.3691) (xy 337.30799 -362.368598) (xy 337.253798 -362.360767)
			(xy 337.201281 -362.345269) (xy 337.151519 -362.322425) (xy 337.105533 -362.292702) (xy 337.064268 -362.256711)
			(xy 337.046062 -362.236258) (xy 337.035978 -362.225304) (xy 337.010922 -362.209248) (xy 336.982304 -362.201091)
			(xy 336.952548 -362.201525) (xy 336.924179 -362.210513) (xy 336.899603 -362.227293) (xy 336.889852 -362.238544)
			(xy 336.871595 -362.260307) (xy 336.829807 -362.298779) (xy 336.782778 -362.330632) (xy 336.731546 -362.355162)
			(xy 336.677245 -362.371826) (xy 336.621073 -362.380257) (xy 336.592672 -362.380784) (xy 336.563618 -362.380272)
			(xy 336.50618 -362.371469) (xy 336.450742 -362.354055) (xy 336.398587 -362.328433) (xy 336.350922 -362.295197)
			(xy 336.30885 -362.255115) (xy 336.290666 -362.232448) (xy 336.281394 -362.221386) (xy 336.258079 -362.204404)
			(xy 336.230941 -362.19463) (xy 336.202152 -362.192845) (xy 336.174014 -362.199193) (xy 336.14878 -362.213165)
			(xy 336.138266 -362.22305) (xy 336.116651 -362.244093) (xy 336.067986 -362.279738) (xy 336.014317 -362.307277)
			(xy 335.956981 -362.326024) (xy 335.897409 -362.335512) (xy 335.867248 -362.33608) (xy 335.839995 -362.3356)
			(xy 335.786043 -362.327849) (xy 335.733744 -362.312497) (xy 335.684162 -362.289858) (xy 335.638307 -362.260393)
			(xy 335.597114 -362.224701) (xy 335.561419 -362.183509) (xy 335.531951 -362.137655) (xy 335.50931 -362.088075)
			(xy 335.493955 -362.035776) (xy 335.486201 -361.981825) (xy 335.48574 -361.954572) (xy 335.486232 -361.926969)
			(xy 335.494193 -361.872338) (xy 335.509943 -361.819426) (xy 335.533154 -361.769336) (xy 335.563343 -361.723113)
			(xy 335.581244 -361.702096) (xy 335.590775 -361.690438) (xy 335.603212 -361.663031) (xy 335.607139 -361.633191)
			(xy 335.602218 -361.6035) (xy 335.588874 -361.576523) (xy 335.578958 -361.56519) (xy 335.559564 -361.54383)
			(xy 335.526755 -361.496377) (xy 335.501471 -361.444522) (xy 335.484288 -361.389449) (xy 335.4756 -361.332416)
			(xy 335.475072 -361.30357) (xy 335.475072 -361.303316) (xy 335.475523 -361.275711) (xy 335.483492 -361.221079)
			(xy 335.499252 -361.168165) (xy 335.522473 -361.118076) (xy 335.55267 -361.071856) (xy 335.570576 -361.05084)
			(xy 335.580061 -361.039148) (xy 335.592499 -361.011753) (xy 335.596433 -360.981925) (xy 335.591524 -360.952241)
			(xy 335.578196 -360.925268) (xy 335.56829 -360.913934) (xy 335.548875 -360.892593) (xy 335.516067 -360.845135)
			(xy 335.490786 -360.793275) (xy 335.473609 -360.738198) (xy 335.464928 -360.681161) (xy 335.464404 -360.652314)
			(xy 335.464404 -360.65206) (xy 335.464898 -360.624457) (xy 335.472859 -360.569827) (xy 335.48861 -360.516915)
			(xy 335.511821 -360.466825) (xy 335.542007 -360.420602) (xy 335.559908 -360.399584) (xy 335.569445 -360.387932)
			(xy 335.581872 -360.360522) (xy 335.585794 -360.330682) (xy 335.580873 -360.300991) (xy 335.567534 -360.274013)
			(xy 335.557622 -360.262678) (xy 335.538216 -360.241329) (xy 335.50541 -360.193872) (xy 335.480129 -360.142014)
			(xy 335.462949 -360.086939) (xy 335.454263 -360.029904) (xy 335.453736 -360.001058) (xy 335.453736 -360.000804)
			(xy 335.454244 -359.971887) (xy 335.462973 -359.914714) (xy 335.480232 -359.859515) (xy 335.505626 -359.807553)
			(xy 335.538572 -359.760019) (xy 335.578315 -359.718003) (xy 335.600802 -359.699814) (xy 335.612602 -359.689911)
			(xy 335.630117 -359.664589) (xy 335.639292 -359.635197) (xy 335.639292 -359.604407) (xy 335.630119 -359.575016)
			(xy 335.612605 -359.549692) (xy 335.600802 -359.539794) (xy 335.580021 -359.523037) (xy 335.542887 -359.484686)
			(xy 335.511462 -359.441533) (xy 335.48636 -359.39442) (xy 335.468071 -359.344267) (xy 335.456953 -359.292055)
			(xy 335.453223 -359.238802) (xy 328.694435 -359.238802) (xy 330.843916 -362.873798) (xy 346.387672 -362.873798)
			(xy 346.391743 -362.818176) (xy 346.403869 -362.763739) (xy 346.423792 -362.711648) (xy 346.451088 -362.663013)
			(xy 346.485174 -362.61887) (xy 346.525323 -362.580161) (xy 346.570681 -362.54771) (xy 346.620281 -362.522209)
			(xy 346.673065 -362.504202) (xy 346.727908 -362.494072) (xy 346.783642 -362.492035) (xy 346.839079 -362.498135)
			(xy 346.893036 -362.512241) (xy 346.944365 -362.534053) (xy 346.991971 -362.563107) (xy 347.034839 -362.598782)
			(xy 347.072056 -362.640319) (xy 347.102829 -362.686832) (xy 347.126501 -362.737329) (xy 347.142569 -362.790736)
			(xy 347.150689 -362.845912) (xy 347.151198 -362.873798) (xy 347.150689 -362.901684) (xy 347.142569 -362.95686)
			(xy 347.126501 -363.010267) (xy 347.102829 -363.060764) (xy 347.072056 -363.107277) (xy 347.034839 -363.148814)
			(xy 346.991971 -363.184489) (xy 346.944365 -363.213543) (xy 346.893036 -363.235355) (xy 346.839079 -363.249461)
			(xy 346.783642 -363.255561) (xy 346.727908 -363.253524) (xy 346.673065 -363.243394) (xy 346.620281 -363.225387)
			(xy 346.570681 -363.199886) (xy 346.525323 -363.167435) (xy 346.485174 -363.128726) (xy 346.451088 -363.084583)
			(xy 346.423792 -363.035948) (xy 346.403869 -362.983857) (xy 346.391743 -362.92942) (xy 346.387672 -362.873798)
			(xy 330.843916 -362.873798) (xy 331.269727 -363.593888) (xy 346.993462 -363.593888) (xy 346.997533 -363.538266)
			(xy 347.009659 -363.483829) (xy 347.029582 -363.431738) (xy 347.056878 -363.383103) (xy 347.090964 -363.33896)
			(xy 347.131113 -363.300251) (xy 347.176471 -363.2678) (xy 347.226071 -363.242299) (xy 347.278855 -363.224292)
			(xy 347.333698 -363.214162) (xy 347.389432 -363.212125) (xy 347.444869 -363.218225) (xy 347.498826 -363.232331)
			(xy 347.550155 -363.254143) (xy 347.597761 -363.283197) (xy 347.640629 -363.318872) (xy 347.677846 -363.360409)
			(xy 347.708619 -363.406922) (xy 347.732291 -363.457419) (xy 347.748359 -363.510826) (xy 347.756479 -363.566002)
			(xy 347.756988 -363.593888) (xy 347.756479 -363.621774) (xy 347.748359 -363.67695) (xy 347.732291 -363.730357)
			(xy 347.708619 -363.780854) (xy 347.677846 -363.827367) (xy 347.640629 -363.868904) (xy 347.597761 -363.904579)
			(xy 347.550155 -363.933633) (xy 347.498826 -363.955445) (xy 347.444869 -363.969551) (xy 347.389432 -363.975651)
			(xy 347.333698 -363.973614) (xy 347.278855 -363.963484) (xy 347.226071 -363.945477) (xy 347.176471 -363.919976)
			(xy 347.131113 -363.887525) (xy 347.090964 -363.848816) (xy 347.056878 -363.804673) (xy 347.029582 -363.756038)
			(xy 347.009659 -363.703947) (xy 346.997533 -363.64951) (xy 346.993462 -363.593888) (xy 331.269727 -363.593888)
			(xy 331.60662 -364.16361) (xy 347.661482 -364.16361) (xy 347.665553 -364.107988) (xy 347.677679 -364.053551)
			(xy 347.697602 -364.00146) (xy 347.724898 -363.952825) (xy 347.758984 -363.908682) (xy 347.799133 -363.869973)
			(xy 347.844491 -363.837522) (xy 347.894091 -363.812021) (xy 347.946875 -363.794014) (xy 348.001718 -363.783884)
			(xy 348.057452 -363.781847) (xy 348.112889 -363.787947) (xy 348.166846 -363.802053) (xy 348.218175 -363.823865)
			(xy 348.265781 -363.852919) (xy 348.308649 -363.888594) (xy 348.345866 -363.930131) (xy 348.376639 -363.976644)
			(xy 348.400311 -364.027141) (xy 348.416379 -364.080548) (xy 348.424499 -364.135724) (xy 348.425008 -364.16361)
			(xy 348.424499 -364.191496) (xy 348.416379 -364.246672) (xy 348.400311 -364.300079) (xy 348.376639 -364.350576)
			(xy 348.345866 -364.397089) (xy 348.308649 -364.438626) (xy 348.265781 -364.474301) (xy 348.218175 -364.503355)
			(xy 348.166846 -364.525167) (xy 348.112889 -364.539273) (xy 348.057452 -364.545373) (xy 348.001718 -364.543336)
			(xy 347.946875 -364.533206) (xy 347.894091 -364.515199) (xy 347.844491 -364.489698) (xy 347.799133 -364.457247)
			(xy 347.758984 -364.418538) (xy 347.724898 -364.374395) (xy 347.697602 -364.32576) (xy 347.677679 -364.273669)
			(xy 347.665553 -364.219232) (xy 347.661482 -364.16361) (xy 331.60662 -364.16361) (xy 333.937088 -368.104674)
			(xy 346.277182 -368.104674) (xy 346.281253 -368.049052) (xy 346.293379 -367.994615) (xy 346.313302 -367.942524)
			(xy 346.340598 -367.893889) (xy 346.374684 -367.849746) (xy 346.414833 -367.811037) (xy 346.460191 -367.778586)
			(xy 346.509791 -367.753085) (xy 346.562575 -367.735078) (xy 346.617418 -367.724948) (xy 346.673152 -367.722911)
			(xy 346.728589 -367.729011) (xy 346.782546 -367.743117) (xy 346.833875 -367.764929) (xy 346.881481 -367.793983)
			(xy 346.924349 -367.829658) (xy 346.961566 -367.871195) (xy 346.992339 -367.917708) (xy 347.016011 -367.968205)
			(xy 347.032079 -368.021612) (xy 347.040199 -368.076788) (xy 347.040708 -368.104674) (xy 347.040569 -368.112294)
			(xy 347.30385 -368.112294) (xy 347.307921 -368.056672) (xy 347.320047 -368.002235) (xy 347.33997 -367.950144)
			(xy 347.367266 -367.901509) (xy 347.401352 -367.857366) (xy 347.441501 -367.818657) (xy 347.486859 -367.786206)
			(xy 347.536459 -367.760705) (xy 347.589243 -367.742698) (xy 347.644086 -367.732568) (xy 347.69982 -367.730531)
			(xy 347.755257 -367.736631) (xy 347.809214 -367.750737) (xy 347.860543 -367.772549) (xy 347.908149 -367.801603)
			(xy 347.951017 -367.837278) (xy 347.988234 -367.878815) (xy 348.019007 -367.925328) (xy 348.042679 -367.975825)
			(xy 348.058747 -368.029232) (xy 348.066867 -368.084408) (xy 348.067376 -368.112294) (xy 348.066867 -368.14018)
			(xy 348.058747 -368.195356) (xy 348.042679 -368.248763) (xy 348.019007 -368.29926) (xy 347.988234 -368.345773)
			(xy 347.951017 -368.38731) (xy 347.908149 -368.422985) (xy 347.860543 -368.452039) (xy 347.809214 -368.473851)
			(xy 347.755257 -368.487957) (xy 347.69982 -368.494057) (xy 347.644086 -368.49202) (xy 347.589243 -368.48189)
			(xy 347.536459 -368.463883) (xy 347.486859 -368.438382) (xy 347.441501 -368.405931) (xy 347.401352 -368.367222)
			(xy 347.367266 -368.323079) (xy 347.33997 -368.274444) (xy 347.320047 -368.222353) (xy 347.307921 -368.167916)
			(xy 347.30385 -368.112294) (xy 347.040569 -368.112294) (xy 347.040199 -368.13256) (xy 347.032079 -368.187736)
			(xy 347.016011 -368.241143) (xy 346.992339 -368.29164) (xy 346.961566 -368.338153) (xy 346.924349 -368.37969)
			(xy 346.881481 -368.415365) (xy 346.833875 -368.444419) (xy 346.782546 -368.466231) (xy 346.728589 -368.480337)
			(xy 346.673152 -368.486437) (xy 346.617418 -368.4844) (xy 346.562575 -368.47427) (xy 346.509791 -368.456263)
			(xy 346.460191 -368.430762) (xy 346.414833 -368.398311) (xy 346.374684 -368.359602) (xy 346.340598 -368.315459)
			(xy 346.313302 -368.266824) (xy 346.293379 -368.214733) (xy 346.281253 -368.160296) (xy 346.277182 -368.104674)
			(xy 333.937088 -368.104674) (xy 334.845537 -369.640956) (xy 346.293343 -369.640956) (xy 346.293343 -369.586444)
			(xy 346.301101 -369.532488) (xy 346.31646 -369.480185) (xy 346.339106 -369.430601) (xy 346.368579 -369.384745)
			(xy 346.404278 -369.343549) (xy 346.445477 -369.307855) (xy 346.491336 -369.278387) (xy 346.540923 -369.255746)
			(xy 346.593227 -369.240393) (xy 346.647184 -369.23264) (xy 346.67444 -369.23218) (xy 346.697732 -369.232556)
			(xy 346.743963 -369.238287) (xy 346.766642 -369.24361) (xy 346.772738 -369.24488) (xy 346.780104 -369.24488)
			(xy 346.794227 -369.244434) (xy 346.8214 -369.236728) (xy 346.845427 -369.22188) (xy 346.864472 -369.201022)
			(xy 346.87708 -369.175747) (xy 346.882289 -369.147987) (xy 346.88145 -369.133882) (xy 346.879672 -369.098068)
			(xy 346.880148 -369.070817) (xy 346.887908 -369.01687) (xy 346.903267 -368.964576) (xy 346.92591 -368.915)
			(xy 346.955378 -368.869151) (xy 346.99107 -368.827962) (xy 347.03226 -368.79227) (xy 347.078111 -368.762804)
			(xy 347.127687 -368.740162) (xy 347.179982 -368.724806) (xy 347.233929 -368.717047) (xy 347.26118 -368.71656)
			(xy 347.261688 -368.71656) (xy 347.28959 -368.71705) (xy 347.344797 -368.7252) (xy 347.398224 -368.741313)
			(xy 347.448732 -368.765044) (xy 347.472254 -368.78006) (xy 351.54616 -368.78006) (xy 351.571148 -368.780511)
			(xy 351.620505 -368.788354) (xy 351.668027 -368.803822) (xy 351.712544 -368.826533) (xy 351.752961 -368.855928)
			(xy 351.77095 -368.873278) (xy 353.019614 -370.122196) (xy 362.486194 -370.122196) (xy 366.375696 -366.23244)
			(xy 366.375696 -364.09757) (xy 366.360711 -364.074032) (xy 366.336999 -364.023522) (xy 366.32089 -363.9701)
			(xy 366.312726 -363.914903) (xy 366.312196 -363.887004) (xy 366.312196 -363.886496) (xy 366.312682 -363.859245)
			(xy 366.320438 -363.805297) (xy 366.335793 -363.753002) (xy 366.358435 -363.703425) (xy 366.387901 -363.657575)
			(xy 366.423592 -363.616384) (xy 366.464783 -363.580693) (xy 366.510633 -363.551227) (xy 366.56021 -363.528585)
			(xy 366.612505 -363.51323) (xy 366.666453 -363.505474) (xy 366.720955 -363.505474) (xy 366.774903 -363.51323)
			(xy 366.827198 -363.528585) (xy 366.876775 -363.551227) (xy 366.922625 -363.580693) (xy 366.963816 -363.616384)
			(xy 366.999507 -363.657575) (xy 367.028973 -363.703425) (xy 367.051615 -363.753002) (xy 367.06697 -363.805297)
			(xy 367.074726 -363.859245) (xy 367.075212 -363.886496) (xy 367.075212 -363.887004) (xy 367.074734 -363.914907)
			(xy 367.066581 -363.970114) (xy 367.050465 -364.023542) (xy 367.02673 -364.074048) (xy 367.011712 -364.09757)
			(xy 367.011712 -366.364012) (xy 367.011239 -366.388999) (xy 367.003403 -366.438355) (xy 366.987941 -366.485878)
			(xy 366.965234 -366.530396) (xy 366.935842 -366.570813) (xy 366.918494 -366.588802) (xy 364.501684 -369.005358)
			(xy 364.491595 -369.016157) (xy 364.477565 -369.042152) (xy 364.471553 -369.071074) (xy 364.474062 -369.100507)
			(xy 364.484881 -369.127995) (xy 364.503108 -369.151241) (xy 364.527221 -369.168305) (xy 364.541054 -369.173506)
			(xy 364.565908 -369.182403) (xy 364.613107 -369.206047) (xy 364.656596 -369.235971) (xy 364.695545 -369.271604)
			(xy 364.72921 -369.312265) (xy 364.756949 -369.357179) (xy 364.778233 -369.405488) (xy 364.792654 -369.456269)
			(xy 364.799938 -369.508553) (xy 364.800388 -369.534948) (xy 364.799967 -369.562201) (xy 364.792203 -369.616152)
			(xy 364.776841 -369.66845) (xy 364.754193 -369.718028) (xy 364.72472 -369.763879) (xy 364.689021 -369.80507)
			(xy 364.647825 -369.84076) (xy 364.601969 -369.870225) (xy 364.552386 -369.892865) (xy 364.500086 -369.908218)
			(xy 364.446133 -369.915972) (xy 364.41888 -369.916456) (xy 364.392484 -369.915997) (xy 364.340194 -369.908728)
			(xy 364.289406 -369.894317) (xy 364.241091 -369.87304) (xy 364.196172 -369.845304) (xy 364.155507 -369.811637)
			(xy 364.119873 -369.772685) (xy 364.089951 -369.729191) (xy 364.066313 -369.681986) (xy 364.057438 -369.657122)
			(xy 364.052316 -369.643252) (xy 364.035246 -369.619121) (xy 364.011986 -369.600882) (xy 363.98448 -369.59006)
			(xy 363.955027 -369.58756) (xy 363.926091 -369.593592) (xy 363.90009 -369.60765) (xy 363.88929 -369.617752)
			(xy 363.168184 -370.339112) (xy 363.157928 -370.350043) (xy 363.143827 -370.37648) (xy 363.138005 -370.405873)
			(xy 363.140966 -370.435689) (xy 363.152454 -370.463363) (xy 363.17148 -370.486511) (xy 363.196405 -370.50314)
			(xy 363.225084 -370.511818) (xy 363.240066 -370.51234) (xy 365.252762 -370.51234) (xy 365.721646 -370.043456)
			(xy 365.73093 -370.033442) (xy 365.744412 -370.009712) (xy 365.751124 -369.983258) (xy 365.750589 -369.95597)
			(xy 365.742843 -369.9298) (xy 365.72844 -369.906617) (xy 365.708411 -369.888078) (xy 365.6965 -369.881404)
			(xy 365.673514 -369.869067) (xy 365.630873 -369.839012) (xy 365.592725 -369.803427) (xy 365.559782 -369.762975)
			(xy 365.53266 -369.718411) (xy 365.511863 -369.670567) (xy 365.497781 -369.620335) (xy 365.490676 -369.568652)
			(xy 365.490252 -369.542568) (xy 365.490748 -369.515318) (xy 365.498508 -369.461373) (xy 365.513865 -369.40908)
			(xy 365.536507 -369.359506) (xy 365.565973 -369.313657) (xy 365.601663 -369.272469) (xy 365.642851 -369.236778)
			(xy 365.688699 -369.207311) (xy 365.738273 -369.184668) (xy 365.790565 -369.169309) (xy 365.84451 -369.161548)
			(xy 365.87176 -369.16106) (xy 365.897843 -369.161483) (xy 365.949521 -369.168598) (xy 365.999748 -369.182687)
			(xy 366.047588 -369.203488) (xy 366.092147 -369.230612) (xy 366.132596 -369.263554) (xy 366.16818 -369.301699)
			(xy 366.198235 -369.344336) (xy 366.210596 -369.367308) (xy 366.21725 -369.379244) (xy 366.235779 -369.399315)
			(xy 366.25897 -369.41375) (xy 366.28516 -369.421513) (xy 366.312471 -369.42205) (xy 366.338945 -369.41532)
			(xy 366.362685 -369.401807) (xy 366.372648 -369.392454) (xy 367.341404 -368.423952) (xy 367.341404 -362.253784)
			(xy 367.055654 -361.968034) (xy 367.035576 -361.947153) (xy 367.001522 -361.900297) (xy 366.975218 -361.848689)
			(xy 366.957312 -361.793602) (xy 366.948245 -361.736392) (xy 366.947704 -361.70743) (xy 366.947704 -360.535982)
			(xy 366.947203 -360.521799) (xy 366.939393 -360.494528) (xy 366.924381 -360.470459) (xy 366.903326 -360.451449)
			(xy 366.877852 -360.438967) (xy 366.849928 -360.433976) (xy 366.821708 -360.436861) (xy 366.795371 -360.447399)
			(xy 366.783874 -360.455718) (xy 366.763761 -360.470789) (xy 366.720316 -360.496057) (xy 366.673928 -360.5154)
			(xy 366.625402 -360.528482) (xy 366.575578 -360.535077) (xy 366.550448 -360.535474) (xy 366.52319 -360.535082)
			(xy 366.469229 -360.52733) (xy 366.416921 -360.511977) (xy 366.36733 -360.489335) (xy 366.321467 -360.459866)
			(xy 366.280265 -360.424169) (xy 366.244563 -360.382971) (xy 366.215088 -360.337112) (xy 366.19244 -360.287524)
			(xy 366.17708 -360.235218) (xy 366.169321 -360.181257) (xy 366.169321 -360.126743) (xy 366.17708 -360.072782)
			(xy 366.19244 -360.020476) (xy 366.215088 -359.970888) (xy 366.244563 -359.925029) (xy 366.280265 -359.883831)
			(xy 366.321467 -359.848134) (xy 366.36733 -359.818665) (xy 366.416921 -359.796023) (xy 366.469229 -359.78067)
			(xy 366.52319 -359.772918) (xy 366.550448 -359.772458) (xy 366.579995 -359.773049) (xy 366.638381 -359.782179)
			(xy 366.694662 -359.800198) (xy 366.747494 -359.826675) (xy 366.795614 -359.860978) (xy 366.837873 -359.902287)
			(xy 366.85601 -359.92562) (xy 366.87125 -359.94594) (xy 366.947704 -359.94594) (xy 366.947704 -359.817924)
			(xy 366.948303 -359.788964) (xy 366.95736 -359.731758) (xy 366.975253 -359.676672) (xy 367.001542 -359.625063)
			(xy 367.035581 -359.578201) (xy 367.055654 -359.55732) (xy 370.501672 -356.111048) (xy 370.504974 -356.105714)
			(xy 370.51985 -356.081911) (xy 370.5555 -356.038558) (xy 370.59712 -356.0009) (xy 370.643811 -355.96975)
			(xy 370.694565 -355.945782) (xy 370.748284 -355.929513) (xy 370.803808 -355.921295) (xy 370.831872 -355.920802)
			(xy 370.859125 -355.921281) (xy 370.913075 -355.929035) (xy 370.965374 -355.944388) (xy 371.014954 -355.967028)
			(xy 371.060808 -355.996494) (xy 371.102001 -356.032186) (xy 371.137695 -356.073377) (xy 371.167164 -356.11923)
			(xy 371.189806 -356.168809) (xy 371.205161 -356.221107) (xy 371.212917 -356.275057) (xy 371.21338 -356.30231)
			(xy 371.212836 -356.330808) (xy 371.20435 -356.38717) (xy 371.187568 -356.44164) (xy 371.162863 -356.493005)
			(xy 371.130788 -356.54012) (xy 371.092056 -356.581935) (xy 371.047531 -356.617518) (xy 371.023134 -356.632256)
			(xy 369.554001 -358.101389) (xy 369.986045 -358.101389) (xy 369.993796 -358.047437) (xy 370.009146 -357.995136)
			(xy 370.031783 -357.945553) (xy 370.061246 -357.899696) (xy 370.096935 -357.858499) (xy 370.138124 -357.8228)
			(xy 370.183974 -357.793326) (xy 370.233552 -357.770678) (xy 370.285848 -357.755315) (xy 370.339799 -357.747551)
			(xy 370.367052 -357.747062) (xy 370.380048 -357.747169) (xy 370.405979 -357.748949) (xy 370.418868 -357.750618)
			(xy 370.433246 -357.752024) (xy 370.461801 -357.747758) (xy 370.488017 -357.735664) (xy 370.509796 -357.71671)
			(xy 370.525393 -357.692414) (xy 370.533559 -357.664721) (xy 370.53364 -357.635849) (xy 370.53012 -357.62184)
			(xy 370.523261 -357.596222) (xy 370.515862 -357.543708) (xy 370.515388 -357.517192) (xy 370.515388 -357.51643)
			(xy 370.515823 -357.489174) (xy 370.523576 -357.435218) (xy 370.53893 -357.382913) (xy 370.561571 -357.333327)
			(xy 370.591039 -357.287467) (xy 370.626734 -357.246268) (xy 370.667928 -357.210568) (xy 370.713784 -357.181095)
			(xy 370.763368 -357.158447) (xy 370.81567 -357.143087) (xy 370.869626 -357.135326) (xy 370.924137 -357.135324)
			(xy 370.978093 -357.143079) (xy 371.030397 -357.158434) (xy 371.079983 -357.181077) (xy 371.125842 -357.210546)
			(xy 371.16704 -357.246242) (xy 371.202738 -357.287437) (xy 371.232211 -357.333294) (xy 371.254857 -357.382878)
			(xy 371.270216 -357.435181) (xy 371.277975 -357.489137) (xy 371.277976 -357.543648) (xy 371.270219 -357.597605)
			(xy 371.254862 -357.649908) (xy 371.232218 -357.699493) (xy 371.202747 -357.745351) (xy 371.16705 -357.786548)
			(xy 371.125854 -357.822245) (xy 371.079996 -357.851716) (xy 371.030411 -357.874361) (xy 370.978108 -357.889718)
			(xy 370.924152 -357.897475) (xy 370.896896 -357.897938) (xy 370.8839 -357.897826) (xy 370.857969 -357.896049)
			(xy 370.84508 -357.894382) (xy 370.830698 -357.893022) (xy 370.802146 -357.897276) (xy 370.77593 -357.909361)
			(xy 370.754151 -357.928308) (xy 370.738553 -357.952598) (xy 370.730387 -357.980286) (xy 370.730307 -358.009153)
			(xy 370.733828 -358.02316) (xy 370.740688 -358.048778) (xy 370.748086 -358.101292) (xy 370.74856 -358.127808)
			(xy 370.74856 -358.12857) (xy 370.748154 -358.155823) (xy 370.740402 -358.209775) (xy 370.72505 -358.262075)
			(xy 370.702411 -358.311657) (xy 370.672947 -358.357513) (xy 370.637256 -358.398709) (xy 370.596066 -358.434407)
			(xy 370.550215 -358.463879) (xy 370.500637 -358.486527) (xy 370.44834 -358.501888) (xy 370.394389 -358.50965)
			(xy 370.339883 -358.509655) (xy 370.285931 -358.501903) (xy 370.233631 -358.486552) (xy 370.184048 -358.463914)
			(xy 370.138191 -358.43445) (xy 370.096995 -358.39876) (xy 370.061297 -358.357571) (xy 370.031823 -358.311721)
			(xy 370.009176 -358.262142) (xy 369.993814 -358.209846) (xy 369.986051 -358.155895) (xy 369.986045 -358.101389)
			(xy 369.554001 -358.101389) (xy 368.690906 -358.964484) (xy 370.72773 -358.964484) (xy 370.731801 -358.908862)
			(xy 370.743927 -358.854425) (xy 370.76385 -358.802334) (xy 370.791146 -358.753699) (xy 370.825232 -358.709556)
			(xy 370.865381 -358.670847) (xy 370.910739 -358.638396) (xy 370.960339 -358.612895) (xy 371.013123 -358.594888)
			(xy 371.067966 -358.584758) (xy 371.1237 -358.582721) (xy 371.179137 -358.588821) (xy 371.233094 -358.602927)
			(xy 371.284423 -358.624739) (xy 371.332029 -358.653793) (xy 371.374897 -358.689468) (xy 371.412114 -358.731005)
			(xy 371.442887 -358.777518) (xy 371.466559 -358.828015) (xy 371.482627 -358.881422) (xy 371.490747 -358.936598)
			(xy 371.491256 -358.964484) (xy 371.490747 -358.99237) (xy 371.482627 -359.047546) (xy 371.466559 -359.100953)
			(xy 371.442887 -359.15145) (xy 371.412114 -359.197963) (xy 371.374897 -359.2395) (xy 371.332029 -359.275175)
			(xy 371.284423 -359.304229) (xy 371.233094 -359.326041) (xy 371.179137 -359.340147) (xy 371.1237 -359.346247)
			(xy 371.067966 -359.34421) (xy 371.013123 -359.33408) (xy 370.960339 -359.316073) (xy 370.910739 -359.290572)
			(xy 370.865381 -359.258121) (xy 370.825232 -359.219412) (xy 370.791146 -359.175269) (xy 370.76385 -359.126634)
			(xy 370.743927 -359.074543) (xy 370.731801 -359.020106) (xy 370.72773 -358.964484) (xy 368.690906 -358.964484)
			(xy 367.684812 -359.970578) (xy 367.684812 -360.680508) (xy 376.90628 -360.680508) (xy 376.910351 -360.624886)
			(xy 376.922477 -360.570449) (xy 376.9424 -360.518358) (xy 376.969696 -360.469723) (xy 377.003782 -360.42558)
			(xy 377.043931 -360.386871) (xy 377.089289 -360.35442) (xy 377.138889 -360.328919) (xy 377.191673 -360.310912)
			(xy 377.246516 -360.300782) (xy 377.30225 -360.298745) (xy 377.357687 -360.304845) (xy 377.411644 -360.318951)
			(xy 377.462973 -360.340763) (xy 377.510579 -360.369817) (xy 377.553447 -360.405492) (xy 377.590664 -360.447029)
			(xy 377.621437 -360.493542) (xy 377.645109 -360.544039) (xy 377.661177 -360.597446) (xy 377.669297 -360.652622)
			(xy 377.669806 -360.680508) (xy 377.669297 -360.708394) (xy 377.661177 -360.76357) (xy 377.645109 -360.816977)
			(xy 377.621437 -360.867474) (xy 377.590664 -360.913987) (xy 377.553447 -360.955524) (xy 377.510579 -360.991199)
			(xy 377.462973 -361.020253) (xy 377.411644 -361.042065) (xy 377.357687 -361.056171) (xy 377.30225 -361.062271)
			(xy 377.246516 -361.060234) (xy 377.191673 -361.050104) (xy 377.138889 -361.032097) (xy 377.089289 -361.006596)
			(xy 377.043931 -360.974145) (xy 377.003782 -360.935436) (xy 376.969696 -360.891293) (xy 376.9424 -360.842658)
			(xy 376.922477 -360.790567) (xy 376.910351 -360.73613) (xy 376.90628 -360.680508) (xy 367.684812 -360.680508)
			(xy 367.684812 -361.133136) (xy 369.3861 -361.133136) (xy 369.390189 -361.077254) (xy 369.402372 -361.022564)
			(xy 369.422388 -360.97023) (xy 369.449811 -360.921368) (xy 369.484056 -360.87702) (xy 369.524392 -360.83813)
			(xy 369.569962 -360.805528) (xy 369.619793 -360.779909) (xy 369.672823 -360.761817) (xy 369.727921 -360.75164)
			(xy 369.783915 -360.749594) (xy 369.83961 -360.755722) (xy 369.893819 -360.769894) (xy 369.945387 -360.791808)
			(xy 369.993215 -360.820997) (xy 370.036283 -360.856838) (xy 370.073673 -360.898568) (xy 370.104589 -360.945298)
			(xy 370.128372 -360.996031) (xy 370.144514 -361.049687) (xy 370.152673 -361.105121) (xy 370.153184 -361.133136)
			(xy 370.152673 -361.161151) (xy 370.144514 -361.216585) (xy 370.128372 -361.270241) (xy 370.104589 -361.320974)
			(xy 370.073673 -361.367704) (xy 370.036283 -361.409434) (xy 369.993215 -361.445275) (xy 369.945387 -361.474464)
			(xy 369.893819 -361.496378) (xy 369.83961 -361.51055) (xy 369.783915 -361.516678) (xy 369.727921 -361.514632)
			(xy 369.672823 -361.504455) (xy 369.619793 -361.486363) (xy 369.569962 -361.460744) (xy 369.524392 -361.428142)
			(xy 369.484056 -361.389252) (xy 369.449811 -361.344904) (xy 369.422388 -361.296042) (xy 369.402372 -361.243708)
			(xy 369.390189 -361.189018) (xy 369.3861 -361.133136) (xy 367.684812 -361.133136) (xy 367.684812 -361.554776)
			(xy 367.970562 -361.840526) (xy 367.990672 -361.861378) (xy 368.024721 -361.908242) (xy 368.051019 -361.959857)
			(xy 368.068917 -362.014951) (xy 368.077976 -362.072166) (xy 368.078437 -362.097066) (xy 376.025154 -362.097066)
			(xy 376.029225 -362.041444) (xy 376.041351 -361.987007) (xy 376.061274 -361.934916) (xy 376.08857 -361.886281)
			(xy 376.122656 -361.842138) (xy 376.162805 -361.803429) (xy 376.208163 -361.770978) (xy 376.257763 -361.745477)
			(xy 376.310547 -361.72747) (xy 376.36539 -361.71734) (xy 376.421124 -361.715303) (xy 376.476561 -361.721403)
			(xy 376.52724 -361.734652) (xy 382.553685 -361.734652) (xy 382.553685 -361.680148) (xy 382.561442 -361.6262)
			(xy 382.576798 -361.573905) (xy 382.59944 -361.524328) (xy 382.628907 -361.478477) (xy 382.6646 -361.437287)
			(xy 382.705792 -361.401596) (xy 382.751643 -361.372131) (xy 382.801222 -361.349492) (xy 382.853518 -361.334138)
			(xy 382.907466 -361.326384) (xy 382.934718 -361.325922) (xy 382.96148 -361.326343) (xy 383.014474 -361.333852)
			(xy 383.0659 -361.348693) (xy 383.114747 -361.370573) (xy 383.160058 -361.399065) (xy 383.200943 -361.433608)
			(xy 383.2366 -361.473525) (xy 383.26633 -361.518033) (xy 383.289549 -361.566259) (xy 383.305801 -361.617256)
			(xy 383.314768 -361.670023) (xy 383.315972 -361.696762) (xy 383.316841 -361.712162) (xy 383.3268 -361.741345)
			(xy 383.345005 -361.766232) (xy 383.369801 -361.784562) (xy 383.398933 -361.794667) (xy 383.429753 -361.79563)
			(xy 383.44475 -361.792012) (xy 383.469775 -361.785504) (xy 383.521005 -361.778492) (xy 383.546858 -361.778042)
			(xy 383.574112 -361.778495) (xy 383.628066 -361.786247) (xy 383.680367 -361.8016) (xy 383.72995 -361.824242)
			(xy 383.775806 -361.85371) (xy 383.817001 -361.889405) (xy 383.852695 -361.9306) (xy 383.882162 -361.976457)
			(xy 383.904802 -362.02604) (xy 383.920155 -362.078342) (xy 383.927906 -362.132296) (xy 383.928366 -362.15955)
			(xy 383.928112 -362.176568) (xy 383.927909 -362.191398) (xy 383.935129 -362.220154) (xy 383.950314 -362.245619)
			(xy 383.97218 -362.265641) (xy 383.998881 -362.278529) (xy 384.02816 -362.283195) (xy 384.04292 -362.281724)
			(xy 384.055371 -362.280175) (xy 384.080411 -362.278523) (xy 384.092958 -362.278422) (xy 384.120211 -362.278894)
			(xy 384.174163 -362.286646) (xy 384.226463 -362.301999) (xy 384.276045 -362.324639) (xy 384.3219 -362.354105)
			(xy 384.363094 -362.389798) (xy 384.398788 -362.430991) (xy 384.428256 -362.476845) (xy 384.450897 -362.526426)
			(xy 384.466251 -362.578725) (xy 384.474005 -362.632677) (xy 384.474466 -362.65993) (xy 384.474274 -362.676528)
			(xy 384.471345 -362.709595) (xy 384.468624 -362.72597) (xy 384.466495 -362.741477) (xy 384.470727 -362.772475)
			(xy 384.484126 -362.800745) (xy 384.505442 -362.823645) (xy 384.532681 -362.839034) (xy 384.547872 -362.84281)
			(xy 384.576032 -362.849306) (xy 384.630114 -362.869669) (xy 384.680507 -362.897954) (xy 384.726059 -362.933515)
			(xy 384.765729 -362.975538) (xy 384.798607 -363.023062) (xy 384.823944 -363.075) (xy 384.84116 -363.130165)
			(xy 384.84986 -363.187295) (xy 384.850386 -363.21619) (xy 384.850207 -363.233753) (xy 384.84703 -363.268734)
			(xy 384.844036 -363.28604) (xy 384.841779 -363.301008) (xy 384.845177 -363.331074) (xy 384.857239 -363.358822)
			(xy 384.876904 -363.381817) (xy 384.902446 -363.398037) (xy 384.93162 -363.406059) (xy 384.961864 -363.405177)
			(xy 384.97637 -363.400848) (xy 385.005916 -363.391507) (xy 385.067055 -363.381427) (xy 385.098036 -363.380782)
			(xy 385.098798 -363.380782) (xy 385.126051 -363.381253) (xy 385.180003 -363.38901) (xy 385.232301 -363.404366)
			(xy 385.281882 -363.427009) (xy 385.327736 -363.456477) (xy 385.368929 -363.492171) (xy 385.404623 -363.533364)
			(xy 385.434091 -363.579218) (xy 385.456734 -363.628799) (xy 385.47209 -363.681097) (xy 385.479847 -363.735049)
			(xy 385.479847 -363.789555) (xy 385.472089 -363.843507) (xy 385.456733 -363.895805) (xy 385.434089 -363.945386)
			(xy 385.404621 -363.991239) (xy 385.368926 -364.032432) (xy 385.327733 -364.068125) (xy 385.281879 -364.097593)
			(xy 385.232298 -364.120235) (xy 385.179999 -364.135591) (xy 385.126047 -364.143347) (xy 385.071541 -364.143346)
			(xy 385.017589 -364.135588) (xy 384.965291 -364.120231) (xy 384.915711 -364.097587) (xy 384.869858 -364.068118)
			(xy 384.828665 -364.032423) (xy 384.792972 -363.991229) (xy 384.763505 -363.945375) (xy 384.740863 -363.895794)
			(xy 384.725508 -363.843495) (xy 384.717753 -363.789543) (xy 384.71729 -363.76229) (xy 384.717465 -363.744727)
			(xy 384.720645 -363.709746) (xy 384.72364 -363.69244) (xy 384.725817 -363.677466) (xy 384.722415 -363.647418)
			(xy 384.71036 -363.619686) (xy 384.690709 -363.596702) (xy 384.665187 -363.580483) (xy 384.636034 -363.572453)
			(xy 384.605807 -363.573315) (xy 384.591306 -363.577632) (xy 384.561761 -363.586978) (xy 384.500621 -363.597055)
			(xy 384.46964 -363.597698) (xy 384.468878 -363.597698) (xy 384.441626 -363.597243) (xy 384.387676 -363.589483)
			(xy 384.33538 -363.574124) (xy 384.285803 -363.55148) (xy 384.239952 -363.522011) (xy 384.198762 -363.486316)
			(xy 384.16307 -363.445123) (xy 384.133605 -363.399269) (xy 384.110964 -363.349689) (xy 384.09561 -363.297392)
			(xy 384.087855 -363.243442) (xy 384.08737 -363.21619) (xy 384.087564 -363.199592) (xy 384.090491 -363.166525)
			(xy 384.093212 -363.15015) (xy 384.095292 -363.134639) (xy 384.091067 -363.103649) (xy 384.077678 -363.075384)
			(xy 384.056375 -363.052484) (xy 384.029149 -363.037091) (xy 384.013964 -363.03331) (xy 383.985798 -363.026841)
			(xy 383.931718 -363.00647) (xy 383.881327 -362.978179) (xy 383.835777 -362.942614) (xy 383.79611 -362.900588)
			(xy 383.763232 -362.853061) (xy 383.737895 -362.801122) (xy 383.720679 -362.745956) (xy 383.711977 -362.688825)
			(xy 383.71145 -362.65993) (xy 383.711704 -362.642912) (xy 383.711907 -362.628082) (xy 383.704683 -362.599329)
			(xy 383.689497 -362.573866) (xy 383.667631 -362.553845) (xy 383.640933 -362.540956) (xy 383.611655 -362.536288)
			(xy 383.596896 -362.537756) (xy 383.584444 -362.539304) (xy 383.559405 -362.540956) (xy 383.546858 -362.541058)
			(xy 383.520097 -362.540586) (xy 383.467103 -362.533086) (xy 383.415678 -362.518254) (xy 383.36683 -362.496381)
			(xy 383.321518 -362.467896) (xy 383.280631 -362.433357) (xy 383.244973 -362.393444) (xy 383.215243 -362.348939)
			(xy 383.192024 -362.300716) (xy 383.175772 -362.249721) (xy 383.166806 -362.196956) (xy 383.165604 -362.170218)
			(xy 383.164656 -362.154828) (xy 383.154702 -362.125661) (xy 383.13651 -362.100785) (xy 383.111733 -362.082457)
			(xy 383.08262 -362.072344) (xy 383.051817 -362.071363) (xy 383.036826 -362.074968) (xy 383.011802 -362.08148)
			(xy 382.960572 -362.08849) (xy 382.934718 -362.088938) (xy 382.907466 -362.088416) (xy 382.853518 -362.080662)
			(xy 382.801222 -362.065308) (xy 382.751643 -362.042669) (xy 382.705792 -362.013204) (xy 382.6646 -361.977513)
			(xy 382.628907 -361.936323) (xy 382.59944 -361.890472) (xy 382.576798 -361.840895) (xy 382.561442 -361.7886)
			(xy 382.553685 -361.734652) (xy 376.52724 -361.734652) (xy 376.530518 -361.735509) (xy 376.581847 -361.757321)
			(xy 376.629453 -361.786375) (xy 376.672321 -361.82205) (xy 376.709538 -361.863587) (xy 376.740311 -361.9101)
			(xy 376.763983 -361.960597) (xy 376.780051 -362.014004) (xy 376.788171 -362.06918) (xy 376.78868 -362.097066)
			(xy 376.788171 -362.124952) (xy 376.780051 -362.180128) (xy 376.763983 -362.233535) (xy 376.740311 -362.284032)
			(xy 376.709538 -362.330545) (xy 376.672321 -362.372082) (xy 376.629453 -362.407757) (xy 376.581847 -362.436811)
			(xy 376.530518 -362.458623) (xy 376.476561 -362.472729) (xy 376.421124 -362.478829) (xy 376.36539 -362.476792)
			(xy 376.310547 -362.466662) (xy 376.257763 -362.448655) (xy 376.208163 -362.423154) (xy 376.162805 -362.390703)
			(xy 376.122656 -362.351994) (xy 376.08857 -362.307851) (xy 376.061274 -362.259216) (xy 376.041351 -362.207125)
			(xy 376.029225 -362.152688) (xy 376.025154 -362.097066) (xy 368.078437 -362.097066) (xy 368.078512 -362.10113)
			(xy 368.078512 -365.64062) (xy 380.886211 -365.64062) (xy 380.890247 -365.557173) (xy 380.902319 -365.474505)
			(xy 380.922312 -365.393388) (xy 380.950041 -365.314579) (xy 380.985247 -365.238814) (xy 381.027601 -365.166801)
			(xy 381.076707 -365.099212) (xy 381.132108 -365.036678) (xy 381.193285 -364.979783) (xy 381.259668 -364.929057)
			(xy 381.330636 -364.884976) (xy 381.405528 -364.84795) (xy 381.483644 -364.818324) (xy 381.564254 -364.796376)
			(xy 381.646606 -364.782311) (xy 381.729932 -364.776259) (xy 381.813452 -364.778278) (xy 381.896388 -364.788348)
			(xy 381.977964 -364.806376) (xy 382.05742 -364.832193) (xy 382.134013 -364.865558) (xy 382.207029 -364.906159)
			(xy 382.275785 -364.953618) (xy 382.339639 -365.007491) (xy 382.397996 -365.067276) (xy 382.450311 -365.132413)
			(xy 382.496094 -365.202296) (xy 382.534919 -365.276271) (xy 382.566424 -365.353648) (xy 382.590313 -365.433705)
			(xy 382.606364 -365.515693) (xy 382.614427 -365.598848) (xy 382.614932 -365.64062) (xy 382.614427 -365.682392)
			(xy 382.606364 -365.765547) (xy 382.590313 -365.847535) (xy 382.566424 -365.927592) (xy 382.534919 -366.004969)
			(xy 382.496094 -366.078944) (xy 382.450311 -366.148827) (xy 382.397996 -366.213964) (xy 382.339639 -366.273749)
			(xy 382.275785 -366.327622) (xy 382.207029 -366.375081) (xy 382.134013 -366.415682) (xy 382.05742 -366.449047)
			(xy 381.977964 -366.474864) (xy 381.896388 -366.492892) (xy 381.813452 -366.502962) (xy 381.729932 -366.504981)
			(xy 381.646606 -366.498929) (xy 381.564254 -366.484864) (xy 381.483644 -366.462916) (xy 381.405528 -366.43329)
			(xy 381.330636 -366.396264) (xy 381.259668 -366.352183) (xy 381.193285 -366.301457) (xy 381.132108 -366.244562)
			(xy 381.076707 -366.182028) (xy 381.027601 -366.114439) (xy 380.985247 -366.042426) (xy 380.950041 -365.966661)
			(xy 380.922312 -365.887852) (xy 380.902319 -365.806735) (xy 380.890247 -365.724067) (xy 380.886211 -365.64062)
			(xy 368.078512 -365.64062) (xy 368.078512 -367.776252) (xy 369.189506 -367.776252) (xy 369.193577 -367.72063)
			(xy 369.205703 -367.666193) (xy 369.225626 -367.614102) (xy 369.252922 -367.565467) (xy 369.287008 -367.521324)
			(xy 369.327157 -367.482615) (xy 369.372515 -367.450164) (xy 369.422115 -367.424663) (xy 369.474899 -367.406656)
			(xy 369.529742 -367.396526) (xy 369.585476 -367.394489) (xy 369.640913 -367.400589) (xy 369.69487 -367.414695)
			(xy 369.746199 -367.436507) (xy 369.793805 -367.465561) (xy 369.836673 -367.501236) (xy 369.87389 -367.542773)
			(xy 369.904663 -367.589286) (xy 369.928335 -367.639783) (xy 369.944403 -367.69319) (xy 369.952523 -367.748366)
			(xy 369.953032 -367.776252) (xy 369.952523 -367.804138) (xy 369.944403 -367.859314) (xy 369.928335 -367.912721)
			(xy 369.905269 -367.961926) (xy 370.232686 -367.961926) (xy 370.23319 -367.933008) (xy 370.241918 -367.875835)
			(xy 370.259176 -367.820634) (xy 370.28457 -367.768672) (xy 370.317518 -367.721139) (xy 370.357264 -367.679124)
			(xy 370.379752 -367.660936) (xy 370.391535 -367.651012) (xy 370.409059 -367.625697) (xy 370.418241 -367.59631)
			(xy 370.418245 -367.565522) (xy 370.409073 -367.536131) (xy 370.391557 -367.510811) (xy 370.379752 -367.500916)
			(xy 370.357266 -367.482728) (xy 370.317533 -367.440706) (xy 370.284596 -367.39317) (xy 370.259208 -367.341209)
			(xy 370.241952 -367.286011) (xy 370.233222 -367.228842) (xy 370.232686 -367.199926) (xy 370.233172 -367.172675)
			(xy 370.240928 -367.118727) (xy 370.256283 -367.066432) (xy 370.278925 -367.016855) (xy 370.308391 -366.971005)
			(xy 370.344082 -366.929814) (xy 370.385273 -366.894123) (xy 370.431123 -366.864657) (xy 370.4807 -366.842015)
			(xy 370.532995 -366.82666) (xy 370.586943 -366.818904) (xy 370.641445 -366.818904) (xy 370.695393 -366.82666)
			(xy 370.747688 -366.842015) (xy 370.797265 -366.864657) (xy 370.843115 -366.894123) (xy 370.884306 -366.929814)
			(xy 370.919997 -366.971005) (xy 370.949463 -367.016855) (xy 370.972105 -367.066432) (xy 370.98746 -367.118727)
			(xy 370.995216 -367.172675) (xy 370.995702 -367.199926) (xy 370.99513 -367.228841) (xy 370.986412 -367.28601)
			(xy 370.969165 -367.341207) (xy 370.943783 -367.393169) (xy 370.910849 -367.440705) (xy 370.871117 -367.482724)
			(xy 370.848636 -367.500916) (xy 370.836802 -367.510784) (xy 370.819281 -367.536114) (xy 370.810106 -367.565516)
			(xy 370.810111 -367.596316) (xy 370.819295 -367.625715) (xy 370.836825 -367.65104) (xy 370.848636 -367.660936)
			(xy 370.871144 -367.679098) (xy 370.910876 -367.721125) (xy 370.943811 -367.768666) (xy 370.969195 -367.820633)
			(xy 370.986446 -367.875835) (xy 370.99517 -367.933008) (xy 370.995702 -367.961926) (xy 372.38051 -367.961926)
			(xy 372.381043 -367.93301) (xy 372.389769 -367.875839) (xy 372.407023 -367.82064) (xy 372.432412 -367.768678)
			(xy 372.465353 -367.721144) (xy 372.505092 -367.679127) (xy 372.527576 -367.660936) (xy 372.539356 -367.651011)
			(xy 372.556876 -367.625695) (xy 372.566056 -367.596309) (xy 372.56606 -367.565523) (xy 372.55689 -367.536134)
			(xy 372.539378 -367.510813) (xy 372.527576 -367.500916) (xy 372.505095 -367.482722) (xy 372.465361 -367.440702)
			(xy 372.432422 -367.393168) (xy 372.407034 -367.341207) (xy 372.389777 -367.28601) (xy 372.381046 -367.228842)
			(xy 372.38051 -367.199926) (xy 372.380996 -367.172675) (xy 372.388752 -367.118727) (xy 372.404107 -367.066432)
			(xy 372.426749 -367.016855) (xy 372.456215 -366.971005) (xy 372.491906 -366.929814) (xy 372.533097 -366.894123)
			(xy 372.578947 -366.864657) (xy 372.628524 -366.842015) (xy 372.680819 -366.82666) (xy 372.734767 -366.818904)
			(xy 372.789269 -366.818904) (xy 372.843217 -366.82666) (xy 372.895512 -366.842015) (xy 372.945089 -366.864657)
			(xy 372.990939 -366.894123) (xy 373.03213 -366.929814) (xy 373.067821 -366.971005) (xy 373.097287 -367.016855)
			(xy 373.119929 -367.066432) (xy 373.135284 -367.118727) (xy 373.14304 -367.172675) (xy 373.143526 -367.199926)
			(xy 373.142982 -367.228842) (xy 373.134263 -367.286014) (xy 373.117011 -367.341213) (xy 373.091625 -367.393176)
			(xy 373.058684 -367.44071) (xy 373.018945 -367.482726) (xy 372.99646 -367.500916) (xy 372.984624 -367.510783)
			(xy 372.967099 -367.536112) (xy 372.957922 -367.565515) (xy 372.957926 -367.596317) (xy 372.967113 -367.625716)
			(xy 372.984647 -367.651041) (xy 372.99646 -367.660936) (xy 373.018952 -367.679117) (xy 373.058689 -367.721137)
			(xy 373.091628 -367.768674) (xy 373.117015 -367.820638) (xy 373.134269 -367.875838) (xy 373.142994 -367.933009)
			(xy 373.143526 -367.961926) (xy 374.51411 -367.961926) (xy 374.514643 -367.93301) (xy 374.523369 -367.875839)
			(xy 374.540623 -367.82064) (xy 374.566012 -367.768678) (xy 374.598953 -367.721144) (xy 374.638692 -367.679127)
			(xy 374.661176 -367.660936) (xy 374.672956 -367.651011) (xy 374.690476 -367.625695) (xy 374.699656 -367.596309)
			(xy 374.69966 -367.565523) (xy 374.69049 -367.536134) (xy 374.672978 -367.510813) (xy 374.661176 -367.500916)
			(xy 374.638695 -367.482722) (xy 374.598961 -367.440702) (xy 374.566022 -367.393168) (xy 374.540634 -367.341207)
			(xy 374.523377 -367.28601) (xy 374.514646 -367.228842) (xy 374.51411 -367.199926) (xy 374.514596 -367.172675)
			(xy 374.522352 -367.118727) (xy 374.537707 -367.066432) (xy 374.560349 -367.016855) (xy 374.589815 -366.971005)
			(xy 374.625506 -366.929814) (xy 374.666697 -366.894123) (xy 374.712547 -366.864657) (xy 374.762124 -366.842015)
			(xy 374.814419 -366.82666) (xy 374.868367 -366.818904) (xy 374.922869 -366.818904) (xy 374.976817 -366.82666)
			(xy 375.029112 -366.842015) (xy 375.078689 -366.864657) (xy 375.124539 -366.894123) (xy 375.16573 -366.929814)
			(xy 375.201421 -366.971005) (xy 375.230887 -367.016855) (xy 375.253529 -367.066432) (xy 375.268884 -367.118727)
			(xy 375.27664 -367.172675) (xy 375.277126 -367.199926) (xy 375.276582 -367.228842) (xy 375.267863 -367.286014)
			(xy 375.250611 -367.341213) (xy 375.225225 -367.393176) (xy 375.192284 -367.44071) (xy 375.152545 -367.482726)
			(xy 375.13006 -367.500916) (xy 375.118224 -367.510783) (xy 375.100699 -367.536112) (xy 375.091522 -367.565515)
			(xy 375.091526 -367.596317) (xy 375.100713 -367.625716) (xy 375.118247 -367.651041) (xy 375.13006 -367.660936)
			(xy 375.152552 -367.679117) (xy 375.192289 -367.721137) (xy 375.225228 -367.768674) (xy 375.250615 -367.820638)
			(xy 375.267869 -367.875838) (xy 375.276594 -367.933009) (xy 375.276603 -367.933478) (xy 376.66676 -367.933478)
			(xy 376.667312 -367.904562) (xy 376.676031 -367.847391) (xy 376.693281 -367.792192) (xy 376.718666 -367.74023)
			(xy 376.751605 -367.692695) (xy 376.791342 -367.650678) (xy 376.813826 -367.632488) (xy 376.825649 -367.622612)
			(xy 376.84316 -367.597281) (xy 376.852329 -367.567884) (xy 376.852325 -367.537089) (xy 376.843148 -367.507694)
			(xy 376.825631 -367.482368) (xy 376.813826 -367.472468) (xy 376.791333 -367.454288) (xy 376.751597 -367.412267)
			(xy 376.718658 -367.36473) (xy 376.693271 -367.312766) (xy 376.676018 -367.257566) (xy 376.667293 -367.200395)
			(xy 376.66676 -367.171478) (xy 376.667246 -367.144227) (xy 376.675002 -367.090279) (xy 376.690357 -367.037984)
			(xy 376.712999 -366.988407) (xy 376.742465 -366.942557) (xy 376.778156 -366.901366) (xy 376.819347 -366.865675)
			(xy 376.865197 -366.836209) (xy 376.914774 -366.813567) (xy 376.967069 -366.798212) (xy 377.021017 -366.790456)
			(xy 377.075519 -366.790456) (xy 377.129467 -366.798212) (xy 377.181762 -366.813567) (xy 377.231339 -366.836209)
			(xy 377.277189 -366.865675) (xy 377.31838 -366.901366) (xy 377.354071 -366.942557) (xy 377.383537 -366.988407)
			(xy 377.406179 -367.037984) (xy 377.421534 -367.090279) (xy 377.42929 -367.144227) (xy 377.429776 -367.171478)
			(xy 377.429251 -367.200395) (xy 377.420525 -367.257566) (xy 377.403269 -367.312765) (xy 377.377878 -367.364727)
			(xy 377.344935 -367.412261) (xy 377.305195 -367.454278) (xy 377.28271 -367.472468) (xy 377.270927 -367.48239)
			(xy 377.25341 -367.507707) (xy 377.244232 -367.537093) (xy 377.244228 -367.56788) (xy 377.253398 -367.597269)
			(xy 377.270909 -367.62259) (xy 377.28271 -367.632488) (xy 377.30519 -367.650683) (xy 377.344925 -367.692702)
			(xy 377.377864 -367.740237) (xy 377.403253 -367.792197) (xy 377.42051 -367.847394) (xy 377.42924 -367.904562)
			(xy 377.429776 -367.933478) (xy 377.42929 -367.960729) (xy 377.421534 -368.014677) (xy 377.406179 -368.066972)
			(xy 377.383537 -368.116549) (xy 377.354071 -368.162399) (xy 377.336143 -368.18309) (xy 380.86182 -368.18309)
			(xy 380.86182 -368.098394) (xy 380.869871 -368.01408) (xy 380.8859 -367.930914) (xy 380.909761 -367.849647)
			(xy 380.94124 -367.771017) (xy 380.980051 -367.695736) (xy 381.025841 -367.624484) (xy 381.078197 -367.557908)
			(xy 381.136645 -367.49661) (xy 381.200655 -367.441145) (xy 381.269647 -367.392016) (xy 381.342997 -367.349667)
			(xy 381.42004 -367.314483) (xy 381.500079 -367.286781) (xy 381.582388 -367.266813) (xy 381.666223 -367.25476)
			(xy 381.750824 -367.25073) (xy 381.835425 -367.25476) (xy 381.91926 -367.266813) (xy 382.001569 -367.286781)
			(xy 382.081608 -367.314483) (xy 382.158651 -367.349667) (xy 382.232001 -367.392016) (xy 382.300993 -367.441145)
			(xy 382.365003 -367.49661) (xy 382.423451 -367.557908) (xy 382.475807 -367.624484) (xy 382.521597 -367.695736)
			(xy 382.560408 -367.771017) (xy 382.591887 -367.849647) (xy 382.615748 -367.930914) (xy 382.631777 -368.01408)
			(xy 382.639828 -368.098394) (xy 382.640332 -368.140742) (xy 382.639828 -368.18309) (xy 382.631777 -368.267404)
			(xy 382.615748 -368.35057) (xy 382.591887 -368.431837) (xy 382.560408 -368.510467) (xy 382.521597 -368.585748)
			(xy 382.475807 -368.657) (xy 382.423451 -368.723576) (xy 382.365003 -368.784874) (xy 382.300993 -368.840339)
			(xy 382.232001 -368.889468) (xy 382.158651 -368.931817) (xy 382.081608 -368.967001) (xy 382.001569 -368.994703)
			(xy 381.91926 -369.014671) (xy 381.835425 -369.026724) (xy 381.750824 -369.030755) (xy 381.666223 -369.026724)
			(xy 381.582388 -369.014671) (xy 381.500079 -368.994703) (xy 381.42004 -368.967001) (xy 381.342997 -368.931817)
			(xy 381.269647 -368.889468) (xy 381.200655 -368.840339) (xy 381.136645 -368.784874) (xy 381.078197 -368.723576)
			(xy 381.025841 -368.657) (xy 380.980051 -368.585748) (xy 380.94124 -368.510467) (xy 380.909761 -368.431837)
			(xy 380.8859 -368.35057) (xy 380.869871 -368.267404) (xy 380.86182 -368.18309) (xy 377.336143 -368.18309)
			(xy 377.31838 -368.20359) (xy 377.277189 -368.239281) (xy 377.231339 -368.268747) (xy 377.181762 -368.291389)
			(xy 377.129467 -368.306744) (xy 377.075519 -368.3145) (xy 377.021017 -368.3145) (xy 376.967069 -368.306744)
			(xy 376.914774 -368.291389) (xy 376.865197 -368.268747) (xy 376.819347 -368.239281) (xy 376.778156 -368.20359)
			(xy 376.742465 -368.162399) (xy 376.712999 -368.116549) (xy 376.690357 -368.066972) (xy 376.675002 -368.014677)
			(xy 376.667246 -367.960729) (xy 376.66676 -367.933478) (xy 375.276603 -367.933478) (xy 375.277126 -367.961926)
			(xy 375.27664 -367.989177) (xy 375.268884 -368.043125) (xy 375.253529 -368.09542) (xy 375.230887 -368.144997)
			(xy 375.201421 -368.190847) (xy 375.16573 -368.232038) (xy 375.124539 -368.267729) (xy 375.078689 -368.297195)
			(xy 375.029112 -368.319837) (xy 374.976817 -368.335192) (xy 374.922869 -368.342948) (xy 374.868367 -368.342948)
			(xy 374.814419 -368.335192) (xy 374.762124 -368.319837) (xy 374.712547 -368.297195) (xy 374.666697 -368.267729)
			(xy 374.625506 -368.232038) (xy 374.589815 -368.190847) (xy 374.560349 -368.144997) (xy 374.537707 -368.09542)
			(xy 374.522352 -368.043125) (xy 374.514596 -367.989177) (xy 374.51411 -367.961926) (xy 373.143526 -367.961926)
			(xy 373.14304 -367.989177) (xy 373.135284 -368.043125) (xy 373.119929 -368.09542) (xy 373.097287 -368.144997)
			(xy 373.067821 -368.190847) (xy 373.03213 -368.232038) (xy 372.990939 -368.267729) (xy 372.945089 -368.297195)
			(xy 372.895512 -368.319837) (xy 372.843217 -368.335192) (xy 372.789269 -368.342948) (xy 372.734767 -368.342948)
			(xy 372.680819 -368.335192) (xy 372.628524 -368.319837) (xy 372.578947 -368.297195) (xy 372.533097 -368.267729)
			(xy 372.491906 -368.232038) (xy 372.456215 -368.190847) (xy 372.426749 -368.144997) (xy 372.404107 -368.09542)
			(xy 372.388752 -368.043125) (xy 372.380996 -367.989177) (xy 372.38051 -367.961926) (xy 370.995702 -367.961926)
			(xy 370.995216 -367.989177) (xy 370.98746 -368.043125) (xy 370.972105 -368.09542) (xy 370.949463 -368.144997)
			(xy 370.919997 -368.190847) (xy 370.884306 -368.232038) (xy 370.843115 -368.267729) (xy 370.797265 -368.297195)
			(xy 370.747688 -368.319837) (xy 370.695393 -368.335192) (xy 370.641445 -368.342948) (xy 370.586943 -368.342948)
			(xy 370.532995 -368.335192) (xy 370.4807 -368.319837) (xy 370.431123 -368.297195) (xy 370.385273 -368.267729)
			(xy 370.344082 -368.232038) (xy 370.308391 -368.190847) (xy 370.278925 -368.144997) (xy 370.256283 -368.09542)
			(xy 370.240928 -368.043125) (xy 370.233172 -367.989177) (xy 370.232686 -367.961926) (xy 369.905269 -367.961926)
			(xy 369.904663 -367.963218) (xy 369.87389 -368.009731) (xy 369.836673 -368.051268) (xy 369.793805 -368.086943)
			(xy 369.746199 -368.115997) (xy 369.69487 -368.137809) (xy 369.640913 -368.151915) (xy 369.585476 -368.158015)
			(xy 369.529742 -368.155978) (xy 369.474899 -368.145848) (xy 369.422115 -368.127841) (xy 369.372515 -368.10234)
			(xy 369.327157 -368.069889) (xy 369.287008 -368.03118) (xy 369.252922 -367.987037) (xy 369.225626 -367.938402)
			(xy 369.205703 -367.886311) (xy 369.193577 -367.831874) (xy 369.189506 -367.776252) (xy 368.078512 -367.776252)
			(xy 368.078512 -368.576606) (xy 368.077927 -368.605566) (xy 368.068867 -368.662773) (xy 368.05097 -368.717859)
			(xy 368.024677 -368.769468) (xy 367.990636 -368.816329) (xy 367.970562 -368.83721) (xy 365.66602 -371.141752)
			(xy 365.645191 -371.1619) (xy 365.598336 -371.196002) (xy 365.546723 -371.22235) (xy 365.491622 -371.240297)
			(xy 365.434391 -371.2494) (xy 365.405416 -371.249956) (xy 352.63582 -371.249956) (xy 352.606846 -371.249408)
			(xy 352.549618 -371.240297) (xy 352.494522 -371.222342) (xy 352.442913 -371.195987) (xy 352.396065 -371.16188)
			(xy 352.375216 -371.141752) (xy 351.215706 -369.982496) (xy 348.203266 -369.982496) (xy 348.189536 -369.982979)
			(xy 348.163083 -369.990353) (xy 348.13955 -370.004506) (xy 348.120635 -370.024416) (xy 348.107706 -370.048644)
			(xy 348.101696 -370.07544) (xy 348.10192 -370.089176) (xy 348.102428 -370.108734) (xy 348.102428 -370.108988)
			(xy 348.101942 -370.136239) (xy 348.094186 -370.190187) (xy 348.078831 -370.242482) (xy 348.056189 -370.292059)
			(xy 348.026723 -370.337909) (xy 347.991032 -370.3791) (xy 347.949841 -370.414791) (xy 347.903991 -370.444257)
			(xy 347.854414 -370.466899) (xy 347.802119 -370.482254) (xy 347.748171 -370.49001) (xy 347.693669 -370.49001)
			(xy 347.639721 -370.482254) (xy 347.587426 -370.466899) (xy 347.537849 -370.444257) (xy 347.491999 -370.414791)
			(xy 347.450808 -370.3791) (xy 347.415117 -370.337909) (xy 347.385651 -370.292059) (xy 347.363009 -370.242482)
			(xy 347.347654 -370.190187) (xy 347.339898 -370.136239) (xy 347.339412 -370.108988) (xy 347.339412 -370.108734)
			(xy 347.33992 -370.089176) (xy 347.340228 -370.075427) (xy 347.334265 -370.048587) (xy 347.321343 -370.02432)
			(xy 347.302402 -370.004391) (xy 347.278823 -369.990253) (xy 347.252321 -369.982934) (xy 347.238574 -369.982496)
			(xy 346.772738 -369.982496) (xy 346.766642 -369.983766) (xy 346.743962 -369.989084) (xy 346.697732 -369.994816)
			(xy 346.67444 -369.995196) (xy 346.647184 -369.99476) (xy 346.593227 -369.987007) (xy 346.540923 -369.971654)
			(xy 346.491336 -369.949013) (xy 346.445477 -369.919545) (xy 346.404278 -369.883851) (xy 346.368579 -369.842655)
			(xy 346.339106 -369.796799) (xy 346.31646 -369.747215) (xy 346.301101 -369.694912) (xy 346.293343 -369.640956)
			(xy 334.845537 -369.640956) (xy 335.610741 -370.934996) (xy 347.608396 -370.934996) (xy 347.612467 -370.879374)
			(xy 347.624593 -370.824937) (xy 347.644516 -370.772846) (xy 347.671812 -370.724211) (xy 347.705898 -370.680068)
			(xy 347.746047 -370.641359) (xy 347.791405 -370.608908) (xy 347.841005 -370.583407) (xy 347.893789 -370.5654)
			(xy 347.948632 -370.55527) (xy 348.004366 -370.553233) (xy 348.059803 -370.559333) (xy 348.11376 -370.573439)
			(xy 348.165089 -370.595251) (xy 348.212695 -370.624305) (xy 348.255563 -370.65998) (xy 348.29278 -370.701517)
			(xy 348.323553 -370.74803) (xy 348.347225 -370.798527) (xy 348.363293 -370.851934) (xy 348.371413 -370.90711)
			(xy 348.371922 -370.934996) (xy 348.371413 -370.962882) (xy 348.363293 -371.018058) (xy 348.347225 -371.071465)
			(xy 348.323553 -371.121962) (xy 348.29278 -371.168475) (xy 348.255563 -371.210012) (xy 348.212695 -371.245687)
			(xy 348.165089 -371.274741) (xy 348.11376 -371.296553) (xy 348.059803 -371.310659) (xy 348.004366 -371.316759)
			(xy 347.948632 -371.314722) (xy 347.893789 -371.304592) (xy 347.841005 -371.286585) (xy 347.791405 -371.261084)
			(xy 347.746047 -371.228633) (xy 347.705898 -371.189924) (xy 347.671812 -371.145781) (xy 347.644516 -371.097146)
			(xy 347.624593 -371.045055) (xy 347.612467 -370.990618) (xy 347.608396 -370.934996) (xy 335.610741 -370.934996)
			(xy 337.885786 -374.782334) (xy 342.0364 -378.932948) (xy 382.0414 -378.932948)
		)
		(stroke
			(width 0)
			(type solid)
		)
		(fill yes)
		(layer "In4.Cu")
		(net "GND")
	)
	(gr_poly
		(pts
			(xy 307.617368 -78.203298) (xy 317.608458 -78.203298) (xy 317.622009 -78.202878) (xy 317.648158 -78.195757)
			(xy 317.671511 -78.182005) (xy 317.690423 -78.162593) (xy 317.70356 -78.138889) (xy 317.709996 -78.112563)
			(xy 317.709277 -78.085471) (xy 317.701454 -78.059523) (xy 317.694564 -78.04785) (xy 317.680833 -78.025046)
			(xy 317.65918 -77.976418) (xy 317.64451 -77.925249) (xy 317.637108 -77.872535) (xy 317.636652 -77.84592)
			(xy 317.637138 -77.818669) (xy 317.644894 -77.764721) (xy 317.660249 -77.712426) (xy 317.682891 -77.662849)
			(xy 317.712357 -77.616999) (xy 317.748048 -77.575808) (xy 317.789239 -77.540117) (xy 317.835089 -77.510651)
			(xy 317.884666 -77.488009) (xy 317.936961 -77.472654) (xy 317.990909 -77.464898) (xy 318.045411 -77.464898)
			(xy 318.099359 -77.472654) (xy 318.151654 -77.488009) (xy 318.201231 -77.510651) (xy 318.247081 -77.540117)
			(xy 318.288272 -77.575808) (xy 318.323963 -77.616999) (xy 318.353429 -77.662849) (xy 318.376071 -77.712426)
			(xy 318.391426 -77.764721) (xy 318.399182 -77.818669) (xy 318.399668 -77.84592) (xy 318.399186 -77.872532)
			(xy 318.391758 -77.925237) (xy 318.37709 -77.976401) (xy 318.355466 -78.025036) (xy 318.341756 -78.04785)
			(xy 318.334938 -78.059558) (xy 318.327127 -78.085492) (xy 318.326412 -78.112566) (xy 318.332843 -78.138876)
			(xy 318.345967 -78.162568) (xy 318.36486 -78.181974) (xy 318.388192 -78.195727) (xy 318.41432 -78.20286)
			(xy 318.427862 -78.203298) (xy 321.555618 -78.203298) (xy 321.569583 -78.202859) (xy 321.596468 -78.195287)
			(xy 321.620295 -78.180714) (xy 321.639283 -78.16023) (xy 321.652011 -78.135368) (xy 321.657527 -78.107988)
			(xy 321.655418 -78.080137) (xy 321.645843 -78.0539) (xy 321.629516 -78.031238) (xy 321.618864 -78.022196)
			(xy 321.596763 -78.004011) (xy 321.557746 -77.962142) (xy 321.525428 -77.914909) (xy 321.500536 -77.863375)
			(xy 321.483629 -77.808698) (xy 321.475087 -77.752108) (xy 321.474592 -77.723492) (xy 321.475078 -77.696241)
			(xy 321.482834 -77.642293) (xy 321.498189 -77.589998) (xy 321.520831 -77.540421) (xy 321.550297 -77.494571)
			(xy 321.585988 -77.45338) (xy 321.627179 -77.417689) (xy 321.673029 -77.388223) (xy 321.722606 -77.365581)
			(xy 321.774901 -77.350226) (xy 321.828849 -77.34247) (xy 321.883351 -77.34247) (xy 321.937299 -77.350226)
			(xy 321.989594 -77.365581) (xy 322.039171 -77.388223) (xy 322.085021 -77.417689) (xy 322.126212 -77.45338)
			(xy 322.161903 -77.494571) (xy 322.191369 -77.540421) (xy 322.214011 -77.589998) (xy 322.229366 -77.642293)
			(xy 322.237122 -77.696241) (xy 322.237608 -77.723492) (xy 322.237089 -77.752103) (xy 322.228527 -77.808682)
			(xy 322.211609 -77.863347) (xy 322.186714 -77.914871) (xy 322.154401 -77.962097) (xy 322.115396 -78.003967)
			(xy 322.093336 -78.022196) (xy 322.08268 -78.031234) (xy 322.066353 -78.053897) (xy 322.056777 -78.080136)
			(xy 322.054668 -78.107988) (xy 322.060184 -78.13537) (xy 322.072913 -78.160233) (xy 322.091902 -78.180718)
			(xy 322.11573 -78.195291) (xy 322.142616 -78.202864) (xy 322.156582 -78.203298) (xy 322.756784 -78.203298)
			(xy 326.97293 -73.987152) (xy 326.97293 -72.889618) (xy 328.533252 -71.329296) (xy 328.533252 -70.368414)
			(xy 325.8439 -67.679062) (xy 323.215508 -67.679062) (xy 323.215508 -68.494148) (xy 323.215001 -68.525979)
			(xy 323.207016 -68.589137) (xy 323.19119 -68.6508) (xy 323.179948 -68.680584) (xy 323.17538 -68.693268)
			(xy 323.172383 -68.720052) (xy 323.176508 -68.746685) (xy 323.187469 -68.771306) (xy 323.204499 -68.792194)
			(xy 323.226408 -68.80789) (xy 323.251664 -68.817295) (xy 323.265038 -68.819014) (xy 323.290827 -68.821848)
			(xy 323.341358 -68.833608) (xy 323.389826 -68.852115) (xy 323.435335 -68.877025) (xy 323.477045 -68.907878)
			(xy 323.514184 -68.944105) (xy 323.530468 -68.964302) (xy 323.540365 -68.976107) (xy 323.565689 -68.993626)
			(xy 323.595082 -69.002802) (xy 323.625874 -69.002802) (xy 323.655267 -68.993626) (xy 323.680591 -68.976107)
			(xy 323.690488 -68.964302) (xy 323.704186 -68.947241) (xy 323.734865 -68.916045) (xy 323.751702 -68.902072)
			(xy 323.763116 -68.892125) (xy 323.780039 -68.867039) (xy 323.788882 -68.8381) (xy 323.788873 -68.807839)
			(xy 323.780012 -68.778905) (xy 323.763074 -68.753829) (xy 323.751702 -68.74383) (xy 323.729976 -68.725623)
			(xy 323.691633 -68.683876) (xy 323.659895 -68.636911) (xy 323.635464 -68.585763) (xy 323.618878 -68.531561)
			(xy 323.610503 -68.4755) (xy 323.60997 -68.447158) (xy 323.610459 -68.419908) (xy 323.61822 -68.365964)
			(xy 323.633578 -68.313673) (xy 323.656222 -68.264099) (xy 323.685689 -68.218253) (xy 323.72138 -68.177066)
			(xy 323.762569 -68.141377) (xy 323.808417 -68.111912) (xy 323.857992 -68.089271) (xy 323.910283 -68.073916)
			(xy 323.964228 -68.066157) (xy 323.991478 -68.06565) (xy 324.020395 -68.066183) (xy 324.077567 -68.074907)
			(xy 324.132767 -68.092161) (xy 324.184731 -68.117547) (xy 324.232269 -68.150485) (xy 324.274291 -68.190221)
			(xy 324.292468 -68.212716) (xy 324.302365 -68.224521) (xy 324.327689 -68.24204) (xy 324.357082 -68.251216)
			(xy 324.387874 -68.251216) (xy 324.417267 -68.24204) (xy 324.442591 -68.224521) (xy 324.452488 -68.212716)
			(xy 324.470679 -68.190233) (xy 324.512696 -68.150496) (xy 324.560231 -68.117558) (xy 324.612193 -68.092174)
			(xy 324.667392 -68.074924) (xy 324.724562 -68.066206) (xy 324.753478 -68.06565) (xy 324.780731 -68.066134)
			(xy 324.834684 -68.073888) (xy 324.886984 -68.089241) (xy 324.936566 -68.11188) (xy 324.982422 -68.141345)
			(xy 325.023619 -68.177036) (xy 325.059316 -68.218226) (xy 325.088789 -68.264078) (xy 325.111437 -68.313656)
			(xy 325.126798 -68.365954) (xy 325.134561 -68.419905) (xy 325.134863 -68.439284) (xy 325.411844 -68.439284)
			(xy 325.415915 -68.383662) (xy 325.428041 -68.329225) (xy 325.447964 -68.277134) (xy 325.47526 -68.228499)
			(xy 325.509346 -68.184356) (xy 325.549495 -68.145647) (xy 325.594853 -68.113196) (xy 325.644453 -68.087695)
			(xy 325.697237 -68.069688) (xy 325.75208 -68.059558) (xy 325.807814 -68.057521) (xy 325.863251 -68.063621)
			(xy 325.917208 -68.077727) (xy 325.968537 -68.099539) (xy 326.016143 -68.128593) (xy 326.059011 -68.164268)
			(xy 326.096228 -68.205805) (xy 326.127001 -68.252318) (xy 326.150673 -68.302815) (xy 326.166741 -68.356222)
			(xy 326.174861 -68.411398) (xy 326.17537 -68.439284) (xy 326.174861 -68.46717) (xy 326.166741 -68.522346)
			(xy 326.150673 -68.575753) (xy 326.127001 -68.62625) (xy 326.096228 -68.672763) (xy 326.059011 -68.7143)
			(xy 326.016143 -68.749975) (xy 325.968537 -68.779029) (xy 325.917208 -68.800841) (xy 325.863251 -68.814947)
			(xy 325.807814 -68.821047) (xy 325.75208 -68.81901) (xy 325.697237 -68.80888) (xy 325.644453 -68.790873)
			(xy 325.594853 -68.765372) (xy 325.549495 -68.732921) (xy 325.509346 -68.694212) (xy 325.47526 -68.650069)
			(xy 325.447964 -68.601434) (xy 325.428041 -68.549343) (xy 325.415915 -68.494906) (xy 325.411844 -68.439284)
			(xy 325.134863 -68.439284) (xy 325.134986 -68.447158) (xy 325.134464 -68.475499) (xy 325.126069 -68.531555)
			(xy 325.109472 -68.585752) (xy 325.085038 -68.636896) (xy 325.053306 -68.683863) (xy 325.014974 -68.725617)
			(xy 324.993254 -68.74383) (xy 324.981773 -68.753748) (xy 324.964729 -68.778827) (xy 324.955809 -68.807808)
			(xy 324.955799 -68.838131) (xy 324.964702 -68.867117) (xy 324.981731 -68.892207) (xy 324.993254 -68.902072)
			(xy 325.014982 -68.920278) (xy 325.05333 -68.962023) (xy 325.08507 -69.008987) (xy 325.109504 -69.060136)
			(xy 325.126092 -69.114339) (xy 325.134468 -69.170401) (xy 325.134986 -69.198744) (xy 325.134497 -69.225993)
			(xy 325.126735 -69.279934) (xy 325.111376 -69.332222) (xy 325.088732 -69.381793) (xy 325.059264 -69.427636)
			(xy 325.023572 -69.468819) (xy 324.982383 -69.504504) (xy 324.936535 -69.533964) (xy 324.886961 -69.556599)
			(xy 324.83467 -69.571949) (xy 324.780727 -69.579701) (xy 324.753478 -69.580252) (xy 324.724563 -69.579716)
			(xy 324.667394 -69.570986) (xy 324.612198 -69.553728) (xy 324.560239 -69.528338) (xy 324.512707 -69.495397)
			(xy 324.470689 -69.455661) (xy 324.452488 -69.433186) (xy 324.442591 -69.421381) (xy 324.417267 -69.403862)
			(xy 324.387874 -69.394686) (xy 324.357082 -69.394686) (xy 324.327689 -69.403862) (xy 324.302365 -69.421381)
			(xy 324.292468 -69.433186) (xy 324.275715 -69.453969) (xy 324.237361 -69.491099) (xy 324.194207 -69.522521)
			(xy 324.147093 -69.54762) (xy 324.096941 -69.565906) (xy 324.04473 -69.577023) (xy 323.991478 -69.580753)
			(xy 323.938226 -69.577023) (xy 323.886015 -69.565906) (xy 323.835863 -69.54762) (xy 323.788749 -69.522521)
			(xy 323.745595 -69.491099) (xy 323.707241 -69.453969) (xy 323.690488 -69.433186) (xy 323.680591 -69.421381)
			(xy 323.655267 -69.403862) (xy 323.625874 -69.394686) (xy 323.595082 -69.394686) (xy 323.565689 -69.403862)
			(xy 323.540365 -69.421381) (xy 323.530468 -69.433186) (xy 323.512279 -69.455672) (xy 323.470263 -69.495415)
			(xy 323.422729 -69.52836) (xy 323.370767 -69.553752) (xy 323.315567 -69.571009) (xy 323.258395 -69.579736)
			(xy 323.229478 -69.580252) (xy 323.200268 -69.579236) (xy 323.1769 -69.577458) (xy 323.124576 -69.629782)
			(xy 323.233034 -69.73824) (xy 324.3072 -69.73824) (xy 324.339158 -69.738742) (xy 324.40257 -69.746753)
			(xy 324.464478 -69.762648) (xy 324.523906 -69.786177) (xy 324.579916 -69.816969) (xy 324.631625 -69.854538)
			(xy 324.678218 -69.898291) (xy 324.718959 -69.947539) (xy 324.753207 -70.001505) (xy 324.780421 -70.059338)
			(xy 324.800173 -70.120126) (xy 324.812149 -70.18291) (xy 324.816163 -70.2467) (xy 324.812149 -70.31049)
			(xy 324.800173 -70.373274) (xy 324.780421 -70.434062) (xy 324.753207 -70.491895) (xy 324.718959 -70.545861)
			(xy 324.678218 -70.595109) (xy 324.631625 -70.638862) (xy 324.579916 -70.676431) (xy 324.523906 -70.707223)
			(xy 324.464478 -70.730752) (xy 324.40257 -70.746647) (xy 324.339158 -70.754658) (xy 324.3072 -70.755256)
			(xy 323.022468 -70.755256) (xy 322.98918 -70.75472) (xy 322.923178 -70.745997) (xy 322.85888 -70.728732)
			(xy 322.797386 -70.70322) (xy 322.73975 -70.669897) (xy 322.686958 -70.629335) (xy 322.663058 -70.606158)
			(xy 321.98818 -69.93128) (xy 321.965014 -69.907381) (xy 321.924494 -69.854576) (xy 321.891215 -69.796933)
			(xy 321.865749 -69.735437) (xy 321.848531 -69.671142) (xy 321.839857 -69.60515) (xy 321.839336 -69.57187)
			(xy 321.839336 -68.853558) (xy 321.839882 -68.820281) (xy 321.848571 -68.754295) (xy 321.865796 -68.690008)
			(xy 321.89126 -68.628517) (xy 321.92453 -68.570875) (xy 321.965037 -68.518066) (xy 321.98818 -68.494148)
			(xy 322.198492 -68.283582) (xy 322.198492 -63.388748) (xy 322.199024 -63.355459) (xy 322.207737 -63.289452)
			(xy 322.224996 -63.225149) (xy 322.250503 -63.16365) (xy 322.283822 -63.106008) (xy 322.324383 -63.05321)
			(xy 322.34759 -63.029338) (xy 323.99859 -61.378338) (xy 324.022505 -61.355181) (xy 324.075305 -61.314641)
			(xy 324.132943 -61.281333) (xy 324.194432 -61.255828) (xy 324.258722 -61.23856) (xy 324.324716 -61.229826)
			(xy 324.358 -61.22924) (xy 324.576186 -61.22924) (xy 324.576186 -61.144912) (xy 324.545198 -61.131704)
			(xy 324.519622 -61.120396) (xy 324.471811 -61.091395) (xy 324.428744 -61.055727) (xy 324.391342 -61.014157)
			(xy 324.360407 -60.967574) (xy 324.3366 -60.916975) (xy 324.320432 -60.863445) (xy 324.312248 -60.808127)
			(xy 324.311772 -60.780168) (xy 324.312258 -60.752917) (xy 324.320014 -60.698969) (xy 324.335369 -60.646674)
			(xy 324.358011 -60.597097) (xy 324.387477 -60.551247) (xy 324.423168 -60.510056) (xy 324.464359 -60.474365)
			(xy 324.510209 -60.444899) (xy 324.559786 -60.422257) (xy 324.612081 -60.406902) (xy 324.666029 -60.399146)
			(xy 324.720531 -60.399146) (xy 324.774479 -60.406902) (xy 324.826774 -60.422257) (xy 324.876351 -60.444899)
			(xy 324.922201 -60.474365) (xy 324.963392 -60.510056) (xy 324.999083 -60.551247) (xy 325.028549 -60.597097)
			(xy 325.051191 -60.646674) (xy 325.066546 -60.698969) (xy 325.074302 -60.752917) (xy 325.074788 -60.780168)
			(xy 325.074374 -60.805717) (xy 325.067548 -60.856356) (xy 325.054027 -60.905632) (xy 325.034052 -60.952663)
			(xy 325.007981 -60.996609) (xy 324.97628 -61.036684) (xy 324.958202 -61.054742) (xy 324.947749 -61.065632)
			(xy 324.933159 -61.092039) (xy 324.926918 -61.121557) (xy 324.92957 -61.15161) (xy 324.940885 -61.179578)
			(xy 324.959874 -61.203022) (xy 324.984882 -61.219898) (xy 325.013729 -61.228734) (xy 325.028814 -61.22924)
			(xy 326.833738 -61.22924) (xy 326.847989 -61.228768) (xy 326.87538 -61.220888) (xy 326.899516 -61.205727)
			(xy 326.918506 -61.184473) (xy 326.930864 -61.15879) (xy 326.935623 -61.130688) (xy 326.934576 -61.116464)
			(xy 326.933485 -61.10583) (xy 326.932344 -61.084482) (xy 326.93229 -61.073792) (xy 326.932776 -61.046541)
			(xy 326.940532 -60.992593) (xy 326.955887 -60.940298) (xy 326.978529 -60.890721) (xy 327.007995 -60.844871)
			(xy 327.043686 -60.80368) (xy 327.084877 -60.767989) (xy 327.130727 -60.738523) (xy 327.180304 -60.715881)
			(xy 327.232599 -60.700526) (xy 327.286547 -60.69277) (xy 327.341049 -60.69277) (xy 327.394997 -60.700526)
			(xy 327.447292 -60.715881) (xy 327.496869 -60.738523) (xy 327.542719 -60.767989) (xy 327.58391 -60.80368)
			(xy 327.619601 -60.844871) (xy 327.649067 -60.890721) (xy 327.671709 -60.940298) (xy 327.687064 -60.992593)
			(xy 327.69482 -61.046541) (xy 327.695306 -61.073792) (xy 327.695263 -61.084482) (xy 327.694122 -61.105831)
			(xy 327.69302 -61.116464) (xy 327.691932 -61.130678) (xy 327.696752 -61.158763) (xy 327.709137 -61.184426)
			(xy 327.728126 -61.205672) (xy 327.752242 -61.220851) (xy 327.779611 -61.228783) (xy 327.793858 -61.22924)
			(xy 327.847452 -61.22924) (xy 327.861645 -61.228765) (xy 327.88893 -61.22094) (xy 327.91301 -61.20591)
			(xy 327.932025 -61.184834) (xy 327.944507 -61.15934) (xy 327.949492 -61.131396) (xy 327.948544 -61.117226)
			(xy 327.947578 -61.107285) (xy 327.946563 -61.087336) (xy 327.946512 -61.077348) (xy 327.946995 -61.049879)
			(xy 327.954885 -60.995511) (xy 327.970494 -60.942837) (xy 327.9935 -60.892948) (xy 328.023425 -60.846876)
			(xy 328.059652 -60.805575) (xy 328.101429 -60.769899) (xy 328.147893 -60.740586) (xy 328.198083 -60.718243)
			(xy 328.224388 -60.710318) (xy 328.237778 -60.706066) (xy 328.261694 -60.691346) (xy 328.280687 -60.67066)
			(xy 328.293317 -60.645577) (xy 328.298625 -60.618) (xy 328.296209 -60.590021) (xy 328.291698 -60.576714)
			(xy 328.280348 -60.544287) (xy 328.268076 -60.476696) (xy 328.267314 -60.442348) (xy 328.2678 -60.415097)
			(xy 328.275556 -60.361149) (xy 328.290911 -60.308854) (xy 328.313553 -60.259277) (xy 328.343019 -60.213427)
			(xy 328.37871 -60.172236) (xy 328.419901 -60.136545) (xy 328.465751 -60.107079) (xy 328.515328 -60.084437)
			(xy 328.567623 -60.069082) (xy 328.621571 -60.061326) (xy 328.676073 -60.061326) (xy 328.730021 -60.069082)
			(xy 328.782316 -60.084437) (xy 328.831893 -60.107079) (xy 328.877743 -60.136545) (xy 328.918934 -60.172236)
			(xy 328.954625 -60.213427) (xy 328.984091 -60.259277) (xy 329.006733 -60.308854) (xy 329.022088 -60.361149)
			(xy 329.029844 -60.415097) (xy 329.03033 -60.442348) (xy 329.029847 -60.469818) (xy 329.021958 -60.524188)
			(xy 329.00635 -60.576864) (xy 328.983346 -60.626756) (xy 328.953422 -60.672831) (xy 328.917197 -60.714136)
			(xy 328.875421 -60.749817) (xy 328.828958 -60.779134) (xy 328.778769 -60.801483) (xy 328.752454 -60.809378)
			(xy 328.739059 -60.813626) (xy 328.715133 -60.828342) (xy 328.69613 -60.849028) (xy 328.683494 -60.874115)
			(xy 328.678183 -60.901699) (xy 328.6806 -60.929684) (xy 328.685144 -60.942982) (xy 328.696493 -60.97541)
			(xy 328.708764 -61.043) (xy 328.709528 -61.077348) (xy 328.709475 -61.087336) (xy 328.708457 -61.107285)
			(xy 328.707496 -61.117226) (xy 328.706499 -61.131399) (xy 328.711468 -61.159363) (xy 328.723949 -61.184875)
			(xy 328.742977 -61.205959) (xy 328.767078 -61.220985) (xy 328.794387 -61.228787) (xy 328.808588 -61.22924)
			(xy 328.973688 -61.22924) (xy 330.055982 -60.1472) (xy 330.026264 -60.11164) (xy 330.010742 -60.092343)
			(xy 329.984619 -60.050269) (xy 329.964575 -60.004983) (xy 329.950996 -59.957357) (xy 329.944144 -59.90831)
			(xy 329.943714 -59.883548) (xy 329.944231 -59.855561) (xy 329.952981 -59.800275) (xy 329.970273 -59.747038)
			(xy 329.995681 -59.697163) (xy 330.028579 -59.651877) (xy 330.068157 -59.612296) (xy 330.113441 -59.579394)
			(xy 330.163314 -59.553983) (xy 330.216549 -59.536687) (xy 330.271835 -59.527933) (xy 330.299822 -59.52744)
			(xy 330.324584 -59.527867) (xy 330.37363 -59.534725) (xy 330.421254 -59.548307) (xy 330.46654 -59.56835)
			(xy 330.508616 -59.594469) (xy 330.527914 -59.60999) (xy 330.563474 -59.639708) (xy 332.791308 -57.411874)
			(xy 332.800654 -57.40193) (xy 332.814169 -57.378233) (xy 332.82092 -57.351802) (xy 332.820425 -57.324527)
			(xy 332.812719 -57.298358) (xy 332.798352 -57.275168) (xy 332.778353 -57.256614) (xy 332.754152 -57.244025)
			(xy 332.72748 -57.238299) (xy 332.713838 -57.238646) (xy 332.696312 -57.239154) (xy 332.670318 -57.238672)
			(xy 332.61897 -57.230541) (xy 332.569527 -57.214477) (xy 332.523205 -57.190876) (xy 332.481146 -57.160319)
			(xy 332.444384 -57.123558) (xy 332.413827 -57.081499) (xy 332.390225 -57.035178) (xy 332.374161 -56.985734)
			(xy 332.366029 -56.934387) (xy 332.36603 -56.882399) (xy 332.374164 -56.831051) (xy 332.390231 -56.781609)
			(xy 332.413835 -56.735288) (xy 332.444394 -56.693231) (xy 332.481157 -56.656472) (xy 332.523217 -56.625917)
			(xy 332.56954 -56.602318) (xy 332.618985 -56.586256) (xy 332.670333 -56.578127) (xy 332.72232 -56.578131)
			(xy 332.773667 -56.586269) (xy 332.823109 -56.602338) (xy 332.869428 -56.625945) (xy 332.911484 -56.656507)
			(xy 332.948241 -56.693271) (xy 332.978793 -56.735334) (xy 333.00239 -56.781658) (xy 333.018448 -56.831103)
			(xy 333.026574 -56.882452) (xy 333.02702 -56.908446) (xy 333.026512 -56.925972) (xy 333.026206 -56.939602)
			(xy 333.031974 -56.966239) (xy 333.044583 -56.990401) (xy 333.063133 -57.010367) (xy 333.086304 -57.024716)
			(xy 333.112445 -57.032425) (xy 333.139694 -57.032945) (xy 333.16611 -57.026239) (xy 333.189811 -57.012784)
			(xy 333.19974 -57.003442) (xy 333.3369 -56.866282) (xy 333.347054 -56.85541) (xy 333.36114 -56.829223)
			(xy 333.367077 -56.800087) (xy 333.364362 -56.770477) (xy 333.353224 -56.742906) (xy 333.33461 -56.719718)
			(xy 333.322676 -56.710834) (xy 333.301002 -56.695278) (xy 333.262506 -56.658344) (xy 333.23044 -56.615709)
			(xy 333.205635 -56.568478) (xy 333.188735 -56.517878) (xy 333.180178 -56.46522) (xy 333.179674 -56.438546)
			(xy 333.180154 -56.412554) (xy 333.188279 -56.361209) (xy 333.204337 -56.311767) (xy 333.227932 -56.265446)
			(xy 333.258483 -56.223387) (xy 333.295238 -56.186625) (xy 333.337291 -56.156066) (xy 333.383608 -56.132462)
			(xy 333.433046 -56.116394) (xy 333.48439 -56.108259) (xy 333.510382 -56.107838) (xy 333.523082 -56.108092)
			(xy 333.536734 -56.108166) (xy 333.563301 -56.101928) (xy 333.587265 -56.088871) (xy 333.606911 -56.06993)
			(xy 333.620834 -56.046459) (xy 333.628039 -56.020137) (xy 333.628492 -56.006492) (xy 333.628492 -55.565548)
			(xy 333.629024 -55.532259) (xy 333.637737 -55.466252) (xy 333.654996 -55.401949) (xy 333.680503 -55.34045)
			(xy 333.713822 -55.282808) (xy 333.754383 -55.23001) (xy 333.77759 -55.206138) (xy 333.907892 -55.075582)
			(xy 333.907892 -54.873652) (xy 333.907394 -54.858855) (xy 333.898919 -54.830502) (xy 333.882666 -54.805771)
			(xy 333.860002 -54.786743) (xy 333.832831 -54.775017) (xy 333.803438 -54.771578) (xy 333.774295 -54.776716)
			(xy 333.74785 -54.789999) (xy 333.736696 -54.799738) (xy 333.718198 -54.816528) (xy 333.677091 -54.844912)
			(xy 333.632181 -54.866786) (xy 333.58449 -54.881653) (xy 333.535105 -54.889174) (xy 333.510128 -54.889654)
			(xy 333.484134 -54.889173) (xy 333.432785 -54.881044) (xy 333.383339 -54.864982) (xy 333.337016 -54.841382)
			(xy 333.294955 -54.810826) (xy 333.258192 -54.774067) (xy 333.227632 -54.732008) (xy 333.204029 -54.685686)
			(xy 333.187963 -54.636243) (xy 333.179829 -54.584894) (xy 333.179829 -54.532906) (xy 333.187963 -54.481557)
			(xy 333.204029 -54.432114) (xy 333.227632 -54.385792) (xy 333.258192 -54.343733) (xy 333.294955 -54.306974)
			(xy 333.337016 -54.276418) (xy 333.383339 -54.252818) (xy 333.432785 -54.236756) (xy 333.484134 -54.228627)
			(xy 333.510128 -54.228238) (xy 333.537151 -54.228777) (xy 333.590477 -54.237565) (xy 333.641665 -54.254903)
			(xy 333.689356 -54.28033) (xy 333.732279 -54.31317) (xy 333.769295 -54.35255) (xy 333.799419 -54.397421)
			(xy 333.811118 -54.421786) (xy 333.82458 -54.451504) (xy 333.907892 -54.451504) (xy 333.907892 -54.320948)
			(xy 333.908424 -54.287659) (xy 333.917137 -54.221652) (xy 333.934396 -54.157349) (xy 333.959903 -54.09585)
			(xy 333.993222 -54.038208) (xy 334.033783 -53.98541) (xy 334.05699 -53.961538) (xy 334.366108 -53.652166)
			(xy 334.375975 -53.641525) (xy 334.38983 -53.616044) (xy 334.395962 -53.587695) (xy 334.393876 -53.558766)
			(xy 334.38374 -53.53159) (xy 334.366373 -53.50836) (xy 334.343175 -53.49095) (xy 334.316018 -53.480764)
			(xy 334.301592 -53.479192) (xy 334.27689 -53.476964) (xy 334.228509 -53.466044) (xy 334.182302 -53.448021)
			(xy 334.139306 -53.423299) (xy 334.100484 -53.392432) (xy 334.066708 -53.356112) (xy 334.038736 -53.315156)
			(xy 334.017194 -53.270481) (xy 334.002567 -53.223089) (xy 333.995182 -53.174045) (xy 333.99476 -53.149246)
			(xy 333.99527 -53.123259) (xy 334.0034 -53.071924) (xy 334.019461 -53.022494) (xy 334.043057 -52.976184)
			(xy 334.073607 -52.934136) (xy 334.110358 -52.897385) (xy 334.152406 -52.866835) (xy 334.198716 -52.843239)
			(xy 334.248146 -52.827178) (xy 334.299481 -52.819048) (xy 334.351455 -52.819048) (xy 334.40279 -52.827178)
			(xy 334.45222 -52.843239) (xy 334.49853 -52.866835) (xy 334.540578 -52.897385) (xy 334.577329 -52.934136)
			(xy 334.607879 -52.976184) (xy 334.631475 -53.022494) (xy 334.647536 -53.071924) (xy 334.655666 -53.123259)
			(xy 334.656176 -53.149246) (xy 334.655826 -53.172349) (xy 334.649447 -53.218111) (xy 334.643476 -53.240432)
			(xy 334.635094 -53.269134) (xy 334.692244 -53.326284) (xy 334.758792 -53.259736) (xy 334.785386 -53.234075)
			(xy 334.844663 -53.189945) (xy 334.909716 -53.154884) (xy 334.944212 -53.141626) (xy 334.957427 -53.136306)
			(xy 334.980454 -53.119551) (xy 334.997963 -53.097094) (xy 335.008595 -53.070677) (xy 335.011526 -53.042352)
			(xy 335.006527 -53.014317) (xy 334.993986 -52.988751) (xy 334.974878 -52.967637) (xy 334.963008 -52.959762)
			(xy 334.942953 -52.946722) (xy 334.906472 -52.915782) (xy 334.874828 -52.879909) (xy 334.848681 -52.839852)
			(xy 334.828576 -52.796447) (xy 334.814933 -52.750599) (xy 334.808037 -52.703264) (xy 334.80756 -52.679346)
			(xy 334.808148 -52.650222) (xy 334.818309 -52.592869) (xy 334.838379 -52.53819) (xy 334.852518 -52.512722)
			(xy 334.859677 -52.499396) (xy 334.866642 -52.469975) (xy 334.864695 -52.439803) (xy 334.854005 -52.411521)
			(xy 334.835508 -52.387605) (xy 334.810824 -52.370147) (xy 334.796638 -52.364894) (xy 334.772135 -52.356364)
			(xy 334.725935 -52.332755) (xy 334.683996 -52.302213) (xy 334.647347 -52.26549) (xy 334.616892 -52.223488)
			(xy 334.593378 -52.177241) (xy 334.577384 -52.127886) (xy 334.569303 -52.076637) (xy 334.5688 -52.050696)
			(xy 334.56931 -52.024709) (xy 334.57744 -51.973374) (xy 334.593501 -51.923944) (xy 334.617097 -51.877634)
			(xy 334.647647 -51.835586) (xy 334.684398 -51.798835) (xy 334.726446 -51.768285) (xy 334.772756 -51.744689)
			(xy 334.822186 -51.728628) (xy 334.873521 -51.720498) (xy 334.925495 -51.720498) (xy 334.97683 -51.728628)
			(xy 335.02626 -51.744689) (xy 335.07257 -51.768285) (xy 335.114618 -51.798835) (xy 335.151369 -51.835586)
			(xy 335.181919 -51.877634) (xy 335.205515 -51.923944) (xy 335.221576 -51.973374) (xy 335.229706 -52.024709)
			(xy 335.230216 -52.050696) (xy 335.229696 -52.076683) (xy 336.16951 -52.076683) (xy 336.16951 -52.024709)
			(xy 336.17764 -51.973374) (xy 336.193701 -51.923944) (xy 336.217297 -51.877634) (xy 336.247847 -51.835586)
			(xy 336.284598 -51.798835) (xy 336.326646 -51.768285) (xy 336.372956 -51.744689) (xy 336.422386 -51.728628)
			(xy 336.473721 -51.720498) (xy 336.525695 -51.720498) (xy 336.57703 -51.728628) (xy 336.62646 -51.744689)
			(xy 336.67277 -51.768285) (xy 336.714818 -51.798835) (xy 336.751569 -51.835586) (xy 336.782119 -51.877634)
			(xy 336.805715 -51.923944) (xy 336.821776 -51.973374) (xy 336.829906 -52.024709) (xy 336.830416 -52.050696)
			(xy 336.829906 -52.076683) (xy 336.96961 -52.076683) (xy 336.96961 -52.024709) (xy 336.97774 -51.973374)
			(xy 336.993801 -51.923944) (xy 337.017397 -51.877634) (xy 337.047947 -51.835586) (xy 337.084698 -51.798835)
			(xy 337.126746 -51.768285) (xy 337.173056 -51.744689) (xy 337.222486 -51.728628) (xy 337.273821 -51.720498)
			(xy 337.325795 -51.720498) (xy 337.37713 -51.728628) (xy 337.42656 -51.744689) (xy 337.467469 -51.765533)
			(xy 344.034112 -51.765533) (xy 344.034112 -51.713559) (xy 344.042242 -51.662224) (xy 344.058303 -51.612794)
			(xy 344.081899 -51.566484) (xy 344.112449 -51.524436) (xy 344.1492 -51.487685) (xy 344.191248 -51.457135)
			(xy 344.237558 -51.433539) (xy 344.286988 -51.417478) (xy 344.338323 -51.409348) (xy 344.390297 -51.409348)
			(xy 344.441632 -51.417478) (xy 344.491062 -51.433539) (xy 344.537372 -51.457135) (xy 344.57942 -51.487685)
			(xy 344.616171 -51.524436) (xy 344.646721 -51.566484) (xy 344.670317 -51.612794) (xy 344.67216 -51.618467)
			(xy 344.821512 -51.618467) (xy 344.821512 -51.566493) (xy 344.829642 -51.515158) (xy 344.845703 -51.465728)
			(xy 344.869299 -51.419418) (xy 344.899849 -51.37737) (xy 344.9366 -51.340619) (xy 344.978648 -51.310069)
			(xy 345.024958 -51.286473) (xy 345.074388 -51.270412) (xy 345.125723 -51.262282) (xy 345.177697 -51.262282)
			(xy 345.229032 -51.270412) (xy 345.278462 -51.286473) (xy 345.324772 -51.310069) (xy 345.36682 -51.340619)
			(xy 345.403571 -51.37737) (xy 345.434121 -51.419418) (xy 345.457717 -51.465728) (xy 345.473778 -51.515158)
			(xy 345.481908 -51.566493) (xy 345.482418 -51.59248) (xy 345.481908 -51.618467) (xy 345.473778 -51.669802)
			(xy 345.457717 -51.719232) (xy 345.434121 -51.765542) (xy 345.403571 -51.80759) (xy 345.36682 -51.844341)
			(xy 345.324772 -51.874891) (xy 345.278462 -51.898487) (xy 345.229032 -51.914548) (xy 345.177697 -51.922678)
			(xy 345.125723 -51.922678) (xy 345.074388 -51.914548) (xy 345.024958 -51.898487) (xy 344.978648 -51.874891)
			(xy 344.9366 -51.844341) (xy 344.899849 -51.80759) (xy 344.869299 -51.765542) (xy 344.845703 -51.719232)
			(xy 344.829642 -51.669802) (xy 344.821512 -51.618467) (xy 344.67216 -51.618467) (xy 344.686378 -51.662224)
			(xy 344.694508 -51.713559) (xy 344.695018 -51.739546) (xy 344.694508 -51.765533) (xy 344.686378 -51.816868)
			(xy 344.670317 -51.866298) (xy 344.646721 -51.912608) (xy 344.616171 -51.954656) (xy 344.57942 -51.991407)
			(xy 344.537372 -52.021957) (xy 344.491062 -52.045553) (xy 344.441632 -52.061614) (xy 344.390297 -52.069744)
			(xy 344.338323 -52.069744) (xy 344.286988 -52.061614) (xy 344.237558 -52.045553) (xy 344.191248 -52.021957)
			(xy 344.1492 -51.991407) (xy 344.112449 -51.954656) (xy 344.081899 -51.912608) (xy 344.058303 -51.866298)
			(xy 344.042242 -51.816868) (xy 344.034112 -51.765533) (xy 337.467469 -51.765533) (xy 337.47287 -51.768285)
			(xy 337.514918 -51.798835) (xy 337.551669 -51.835586) (xy 337.582219 -51.877634) (xy 337.605815 -51.923944)
			(xy 337.621876 -51.973374) (xy 337.630006 -52.024709) (xy 337.630516 -52.050696) (xy 337.630006 -52.076683)
			(xy 337.621876 -52.128018) (xy 337.605815 -52.177448) (xy 337.582219 -52.223758) (xy 337.551669 -52.265806)
			(xy 337.514918 -52.302557) (xy 337.47287 -52.333107) (xy 337.42656 -52.356703) (xy 337.37713 -52.372764)
			(xy 337.325795 -52.380894) (xy 337.273821 -52.380894) (xy 337.222486 -52.372764) (xy 337.173056 -52.356703)
			(xy 337.126746 -52.333107) (xy 337.084698 -52.302557) (xy 337.047947 -52.265806) (xy 337.017397 -52.223758)
			(xy 336.993801 -52.177448) (xy 336.97774 -52.128018) (xy 336.96961 -52.076683) (xy 336.829906 -52.076683)
			(xy 336.821776 -52.128018) (xy 336.805715 -52.177448) (xy 336.782119 -52.223758) (xy 336.751569 -52.265806)
			(xy 336.714818 -52.302557) (xy 336.67277 -52.333107) (xy 336.62646 -52.356703) (xy 336.57703 -52.372764)
			(xy 336.525695 -52.380894) (xy 336.473721 -52.380894) (xy 336.422386 -52.372764) (xy 336.372956 -52.356703)
			(xy 336.326646 -52.333107) (xy 336.284598 -52.302557) (xy 336.247847 -52.265806) (xy 336.217297 -52.223758)
			(xy 336.193701 -52.177448) (xy 336.17764 -52.128018) (xy 336.16951 -52.076683) (xy 335.229696 -52.076683)
			(xy 335.229633 -52.079821) (xy 335.21948 -52.137178) (xy 335.199417 -52.191862) (xy 335.185258 -52.21732)
			(xy 335.178107 -52.230645) (xy 335.171155 -52.260059) (xy 335.173111 -52.290221) (xy 335.183803 -52.318491)
			(xy 335.202295 -52.342398) (xy 335.226972 -52.359851) (xy 335.241138 -52.365148) (xy 335.26564 -52.373681)
			(xy 335.311834 -52.397295) (xy 335.35377 -52.427839) (xy 335.390416 -52.464563) (xy 335.420871 -52.506563)
			(xy 335.444387 -52.552808) (xy 335.460385 -52.60216) (xy 335.468472 -52.653406) (xy 335.468976 -52.679346)
			(xy 335.468534 -52.703782) (xy 335.468303 -52.705333) (xy 338.06435 -52.705333) (xy 338.06435 -52.653359)
			(xy 338.07248 -52.602024) (xy 338.088541 -52.552594) (xy 338.112137 -52.506284) (xy 338.142687 -52.464236)
			(xy 338.179438 -52.427485) (xy 338.221486 -52.396935) (xy 338.267796 -52.373339) (xy 338.317226 -52.357278)
			(xy 338.368561 -52.349148) (xy 338.420535 -52.349148) (xy 338.47187 -52.357278) (xy 338.5213 -52.373339)
			(xy 338.56761 -52.396935) (xy 338.609658 -52.427485) (xy 338.646409 -52.464236) (xy 338.676959 -52.506284)
			(xy 338.684654 -52.521386) (xy 339.293725 -52.521386) (xy 339.293725 -52.469414) (xy 339.301855 -52.418083)
			(xy 339.317916 -52.368655) (xy 339.34151 -52.322348) (xy 339.372059 -52.280303) (xy 339.408809 -52.243554)
			(xy 339.450855 -52.213006) (xy 339.497162 -52.189412) (xy 339.54659 -52.173353) (xy 339.597922 -52.165224)
			(xy 339.623908 -52.164742) (xy 339.646967 -52.165139) (xy 339.69264 -52.171533) (xy 339.736981 -52.18421)
			(xy 339.779132 -52.202925) (xy 339.798914 -52.21478) (xy 339.811413 -52.221939) (xy 339.839131 -52.229722)
			(xy 339.867919 -52.229458) (xy 339.89549 -52.22117) (xy 339.919651 -52.205515) (xy 339.938483 -52.183739)
			(xy 339.950488 -52.157572) (xy 339.953092 -52.143406) (xy 339.957382 -52.117557) (xy 339.973054 -52.067561)
			(xy 339.996417 -52.020664) (xy 340.026884 -51.978038) (xy 340.063693 -51.940751) (xy 340.105923 -51.909738)
			(xy 340.152517 -51.885773) (xy 340.202306 -51.869458) (xy 340.254047 -51.8612) (xy 340.280244 -51.860704)
			(xy 340.30623 -51.861193) (xy 340.357561 -51.869329) (xy 340.406987 -51.885395) (xy 340.453292 -51.908994)
			(xy 340.495336 -51.939545) (xy 340.532083 -51.976297) (xy 340.562629 -52.018345) (xy 340.586222 -52.064653)
			(xy 340.602281 -52.114082) (xy 340.610411 -52.165414) (xy 340.610411 -52.217386) (xy 340.607553 -52.235433)
			(xy 343.220042 -52.235433) (xy 343.220042 -52.183459) (xy 343.228172 -52.132124) (xy 343.244233 -52.082694)
			(xy 343.267829 -52.036384) (xy 343.298379 -51.994336) (xy 343.33513 -51.957585) (xy 343.377178 -51.927035)
			(xy 343.423488 -51.903439) (xy 343.472918 -51.887378) (xy 343.524253 -51.879248) (xy 343.576227 -51.879248)
			(xy 343.627562 -51.887378) (xy 343.676992 -51.903439) (xy 343.723302 -51.927035) (xy 343.76535 -51.957585)
			(xy 343.802101 -51.994336) (xy 343.832651 -52.036384) (xy 343.856247 -52.082694) (xy 343.872308 -52.132124)
			(xy 343.880438 -52.183459) (xy 343.880948 -52.209446) (xy 343.880438 -52.235433) (xy 343.872308 -52.286768)
			(xy 343.856247 -52.336198) (xy 343.832651 -52.382508) (xy 343.802101 -52.424556) (xy 343.76535 -52.461307)
			(xy 343.723302 -52.491857) (xy 343.676992 -52.515453) (xy 343.627562 -52.531514) (xy 343.576227 -52.539644)
			(xy 343.524253 -52.539644) (xy 343.472918 -52.531514) (xy 343.423488 -52.515453) (xy 343.377178 -52.491857)
			(xy 343.33513 -52.461307) (xy 343.298379 -52.424556) (xy 343.267829 -52.382508) (xy 343.244233 -52.336198)
			(xy 343.228172 -52.286768) (xy 343.220042 -52.235433) (xy 340.607553 -52.235433) (xy 340.602281 -52.268718)
			(xy 340.586222 -52.318147) (xy 340.562629 -52.364455) (xy 340.532083 -52.406503) (xy 340.495336 -52.443255)
			(xy 340.453292 -52.473806) (xy 340.406987 -52.497405) (xy 340.357561 -52.513471) (xy 340.30623 -52.521607)
			(xy 340.280244 -52.52212) (xy 340.257184 -52.521736) (xy 340.211512 -52.515336) (xy 340.16717 -52.502655)
			(xy 340.12502 -52.483938) (xy 340.105238 -52.472082) (xy 340.092758 -52.46489) (xy 340.065035 -52.45712)
			(xy 340.036245 -52.457393) (xy 340.008674 -52.465688) (xy 339.984512 -52.481346) (xy 339.965678 -52.503123)
			(xy 339.953668 -52.52929) (xy 339.95106 -52.543456) (xy 339.946691 -52.56929) (xy 339.931027 -52.619281)
			(xy 339.907675 -52.666176) (xy 339.879695 -52.705333) (xy 344.034112 -52.705333) (xy 344.034112 -52.653359)
			(xy 344.042242 -52.602024) (xy 344.058303 -52.552594) (xy 344.081899 -52.506284) (xy 344.112449 -52.464236)
			(xy 344.1492 -52.427485) (xy 344.191248 -52.396935) (xy 344.237558 -52.373339) (xy 344.286988 -52.357278)
			(xy 344.338323 -52.349148) (xy 344.390297 -52.349148) (xy 344.441632 -52.357278) (xy 344.491062 -52.373339)
			(xy 344.537372 -52.396935) (xy 344.57942 -52.427485) (xy 344.616171 -52.464236) (xy 344.646721 -52.506284)
			(xy 344.670317 -52.552594) (xy 344.686378 -52.602024) (xy 344.689102 -52.619227) (xy 344.821512 -52.619227)
			(xy 344.821512 -52.567253) (xy 344.829642 -52.515918) (xy 344.845703 -52.466488) (xy 344.869299 -52.420178)
			(xy 344.899849 -52.37813) (xy 344.9366 -52.341379) (xy 344.978648 -52.310829) (xy 345.024958 -52.287233)
			(xy 345.074388 -52.271172) (xy 345.125723 -52.263042) (xy 345.177697 -52.263042) (xy 345.229032 -52.271172)
			(xy 345.278462 -52.287233) (xy 345.324772 -52.310829) (xy 345.36682 -52.341379) (xy 345.403571 -52.37813)
			(xy 345.434121 -52.420178) (xy 345.457717 -52.466488) (xy 345.473778 -52.515918) (xy 345.481908 -52.567253)
			(xy 345.482418 -52.59324) (xy 345.481908 -52.619227) (xy 345.473778 -52.670562) (xy 345.457717 -52.719992)
			(xy 345.434121 -52.766302) (xy 345.403571 -52.80835) (xy 345.36682 -52.845101) (xy 345.324772 -52.875651)
			(xy 345.278462 -52.899247) (xy 345.229032 -52.915308) (xy 345.177697 -52.923438) (xy 345.125723 -52.923438)
			(xy 345.074388 -52.915308) (xy 345.024958 -52.899247) (xy 344.978648 -52.875651) (xy 344.9366 -52.845101)
			(xy 344.899849 -52.80835) (xy 344.869299 -52.766302) (xy 344.845703 -52.719992) (xy 344.829642 -52.670562)
			(xy 344.821512 -52.619227) (xy 344.689102 -52.619227) (xy 344.694508 -52.653359) (xy 344.695018 -52.679346)
			(xy 344.694508 -52.705333) (xy 344.686378 -52.756668) (xy 344.670317 -52.806098) (xy 344.646721 -52.852408)
			(xy 344.616171 -52.894456) (xy 344.581091 -52.929536) (xy 347.47455 -52.929536) (xy 347.478526 -52.87521)
			(xy 347.490369 -52.822041) (xy 347.509828 -52.771164) (xy 347.536488 -52.723662) (xy 347.569779 -52.680548)
			(xy 347.608993 -52.642741) (xy 347.653295 -52.611046) (xy 347.701738 -52.58614) (xy 347.753292 -52.568552)
			(xy 347.806858 -52.558658) (xy 347.861293 -52.556668) (xy 347.915438 -52.562626) (xy 347.968138 -52.576404)
			(xy 348.018271 -52.597708) (xy 348.064767 -52.626084) (xy 348.106637 -52.660928) (xy 348.142986 -52.701497)
			(xy 348.173042 -52.746926) (xy 348.196163 -52.796247) (xy 348.211856 -52.848409) (xy 348.219787 -52.9023)
			(xy 348.220284 -52.929536) (xy 348.220108 -52.939188) (xy 348.944182 -52.939188) (xy 348.948253 -52.883566)
			(xy 348.960379 -52.829129) (xy 348.980302 -52.777038) (xy 349.007598 -52.728403) (xy 349.041684 -52.68426)
			(xy 349.081833 -52.645551) (xy 349.127191 -52.6131) (xy 349.176791 -52.587599) (xy 349.229575 -52.569592)
			(xy 349.284418 -52.559462) (xy 349.340152 -52.557425) (xy 349.395589 -52.563525) (xy 349.449546 -52.577631)
			(xy 349.500875 -52.599443) (xy 349.548481 -52.628497) (xy 349.591349 -52.664172) (xy 349.628566 -52.705709)
			(xy 349.659339 -52.752222) (xy 349.683011 -52.802719) (xy 349.699079 -52.856126) (xy 349.707199 -52.911302)
			(xy 349.707708 -52.939188) (xy 349.707199 -52.967074) (xy 349.699079 -53.02225) (xy 349.683011 -53.075657)
			(xy 349.659339 -53.126154) (xy 349.628566 -53.172667) (xy 349.591349 -53.214204) (xy 349.548481 -53.249879)
			(xy 349.500875 -53.278933) (xy 349.449546 -53.300745) (xy 349.395589 -53.314851) (xy 349.340152 -53.320951)
			(xy 349.284418 -53.318914) (xy 349.229575 -53.308784) (xy 349.176791 -53.290777) (xy 349.127191 -53.265276)
			(xy 349.081833 -53.232825) (xy 349.041684 -53.194116) (xy 349.007598 -53.149973) (xy 348.980302 -53.101338)
			(xy 348.960379 -53.049247) (xy 348.948253 -52.99481) (xy 348.944182 -52.939188) (xy 348.220108 -52.939188)
			(xy 348.219787 -52.956772) (xy 348.211856 -53.010663) (xy 348.196163 -53.062825) (xy 348.173042 -53.112146)
			(xy 348.142986 -53.157575) (xy 348.106637 -53.198144) (xy 348.064767 -53.232988) (xy 348.018271 -53.261364)
			(xy 347.968138 -53.282668) (xy 347.915438 -53.296446) (xy 347.861293 -53.302404) (xy 347.806858 -53.300414)
			(xy 347.753292 -53.29052) (xy 347.701738 -53.272932) (xy 347.653295 -53.248026) (xy 347.608993 -53.216331)
			(xy 347.569779 -53.178524) (xy 347.536488 -53.13541) (xy 347.509828 -53.087908) (xy 347.490369 -53.037031)
			(xy 347.478526 -52.983862) (xy 347.47455 -52.929536) (xy 344.581091 -52.929536) (xy 344.57942 -52.931207)
			(xy 344.537372 -52.961757) (xy 344.491062 -52.985353) (xy 344.441632 -53.001414) (xy 344.390297 -53.009544)
			(xy 344.338323 -53.009544) (xy 344.286988 -53.001414) (xy 344.237558 -52.985353) (xy 344.191248 -52.961757)
			(xy 344.1492 -52.931207) (xy 344.112449 -52.894456) (xy 344.081899 -52.852408) (xy 344.058303 -52.806098)
			(xy 344.042242 -52.756668) (xy 344.034112 -52.705333) (xy 339.879695 -52.705333) (xy 339.877217 -52.708801)
			(xy 339.840418 -52.746088) (xy 339.798198 -52.777104) (xy 339.751615 -52.801072) (xy 339.701834 -52.817393)
			(xy 339.650102 -52.825657) (xy 339.623908 -52.826158) (xy 339.597922 -52.825576) (xy 339.54659 -52.817447)
			(xy 339.497162 -52.801388) (xy 339.450855 -52.777794) (xy 339.408809 -52.747246) (xy 339.372059 -52.710497)
			(xy 339.34151 -52.668452) (xy 339.317916 -52.622145) (xy 339.301855 -52.572717) (xy 339.293725 -52.521386)
			(xy 338.684654 -52.521386) (xy 338.700555 -52.552594) (xy 338.716616 -52.602024) (xy 338.724746 -52.653359)
			(xy 338.725256 -52.679346) (xy 338.724746 -52.705333) (xy 338.716616 -52.756668) (xy 338.700555 -52.806098)
			(xy 338.676959 -52.852408) (xy 338.646409 -52.894456) (xy 338.609658 -52.931207) (xy 338.56761 -52.961757)
			(xy 338.5213 -52.985353) (xy 338.47187 -53.001414) (xy 338.420535 -53.009544) (xy 338.368561 -53.009544)
			(xy 338.317226 -53.001414) (xy 338.267796 -52.985353) (xy 338.221486 -52.961757) (xy 338.179438 -52.931207)
			(xy 338.142687 -52.894456) (xy 338.112137 -52.852408) (xy 338.088541 -52.806098) (xy 338.07248 -52.756668)
			(xy 338.06435 -52.705333) (xy 335.468303 -52.705333) (xy 335.461339 -52.752122) (xy 335.447111 -52.798877)
			(xy 335.42616 -52.843031) (xy 335.398942 -52.883622) (xy 335.366049 -52.919769) (xy 335.328198 -52.950684)
			(xy 335.307432 -52.963572) (xy 335.295489 -52.971261) (xy 335.276074 -52.991977) (xy 335.263111 -53.017237)
			(xy 335.2576 -53.045089) (xy 335.259967 -53.073382) (xy 335.27003 -53.099931) (xy 335.287011 -53.122685)
			(xy 335.309599 -53.139887) (xy 335.322672 -53.145436) (xy 335.350942 -53.156909) (xy 335.385233 -53.175233)
			(xy 335.62341 -53.175233) (xy 335.62341 -53.123259) (xy 335.63154 -53.071924) (xy 335.647601 -53.022494)
			(xy 335.671197 -52.976184) (xy 335.701747 -52.934136) (xy 335.738498 -52.897385) (xy 335.780546 -52.866835)
			(xy 335.826856 -52.843239) (xy 335.876286 -52.827178) (xy 335.927621 -52.819048) (xy 335.979595 -52.819048)
			(xy 336.03093 -52.827178) (xy 336.08036 -52.843239) (xy 336.12667 -52.866835) (xy 336.168718 -52.897385)
			(xy 336.205469 -52.934136) (xy 336.236019 -52.976184) (xy 336.259615 -53.022494) (xy 336.275676 -53.071924)
			(xy 336.283806 -53.123259) (xy 336.284316 -53.149246) (xy 336.283806 -53.175233) (xy 337.25155 -53.175233)
			(xy 337.25155 -53.123259) (xy 337.25968 -53.071924) (xy 337.275741 -53.022494) (xy 337.299337 -52.976184)
			(xy 337.329887 -52.934136) (xy 337.366638 -52.897385) (xy 337.408686 -52.866835) (xy 337.454996 -52.843239)
			(xy 337.504426 -52.827178) (xy 337.555761 -52.819048) (xy 337.607735 -52.819048) (xy 337.65907 -52.827178)
			(xy 337.7085 -52.843239) (xy 337.75481 -52.866835) (xy 337.796858 -52.897385) (xy 337.833609 -52.934136)
			(xy 337.864159 -52.976184) (xy 337.887755 -53.022494) (xy 337.903816 -53.071924) (xy 337.911946 -53.123259)
			(xy 337.912456 -53.149246) (xy 337.911946 -53.175233) (xy 339.96046 -53.175233) (xy 339.96046 -53.123259)
			(xy 339.96859 -53.071924) (xy 339.984651 -53.022494) (xy 340.008247 -52.976184) (xy 340.038797 -52.934136)
			(xy 340.075548 -52.897385) (xy 340.117596 -52.866835) (xy 340.163906 -52.843239) (xy 340.213336 -52.827178)
			(xy 340.264671 -52.819048) (xy 340.316645 -52.819048) (xy 340.36798 -52.827178) (xy 340.41741 -52.843239)
			(xy 340.46372 -52.866835) (xy 340.505768 -52.897385) (xy 340.542519 -52.934136) (xy 340.573069 -52.976184)
			(xy 340.596665 -53.022494) (xy 340.612726 -53.071924) (xy 340.620856 -53.123259) (xy 340.621366 -53.149246)
			(xy 340.620861 -53.174979) (xy 341.59114 -53.174979) (xy 341.59114 -53.123005) (xy 341.59927 -53.07167)
			(xy 341.615331 -53.02224) (xy 341.638927 -52.97593) (xy 341.669477 -52.933882) (xy 341.706228 -52.897131)
			(xy 341.748276 -52.866581) (xy 341.794586 -52.842985) (xy 341.844016 -52.826924) (xy 341.895351 -52.818794)
			(xy 341.947325 -52.818794) (xy 341.99866 -52.826924) (xy 342.04809 -52.842985) (xy 342.0944 -52.866581)
			(xy 342.136448 -52.897131) (xy 342.173199 -52.933882) (xy 342.203749 -52.97593) (xy 342.227345 -53.02224)
			(xy 342.243406 -53.07167) (xy 342.251536 -53.123005) (xy 342.252046 -53.148992) (xy 342.251536 -53.174979)
			(xy 342.243406 -53.226314) (xy 342.227345 -53.275744) (xy 342.203749 -53.322054) (xy 342.173199 -53.364102)
			(xy 342.136448 -53.400853) (xy 342.0944 -53.431403) (xy 342.04809 -53.454999) (xy 341.99866 -53.47106)
			(xy 341.947325 -53.47919) (xy 341.895351 -53.47919) (xy 341.844016 -53.47106) (xy 341.794586 -53.454999)
			(xy 341.748276 -53.431403) (xy 341.706228 -53.400853) (xy 341.669477 -53.364102) (xy 341.638927 -53.322054)
			(xy 341.615331 -53.275744) (xy 341.59927 -53.226314) (xy 341.59114 -53.174979) (xy 340.620861 -53.174979)
			(xy 340.620856 -53.175233) (xy 340.612726 -53.226568) (xy 340.596665 -53.275998) (xy 340.573069 -53.322308)
			(xy 340.542519 -53.364356) (xy 340.505768 -53.401107) (xy 340.46372 -53.431657) (xy 340.41741 -53.455253)
			(xy 340.36798 -53.471314) (xy 340.316645 -53.479444) (xy 340.264671 -53.479444) (xy 340.213336 -53.471314)
			(xy 340.163906 -53.455253) (xy 340.117596 -53.431657) (xy 340.075548 -53.401107) (xy 340.038797 -53.364356)
			(xy 340.008247 -53.322308) (xy 339.984651 -53.275998) (xy 339.96859 -53.226568) (xy 339.96046 -53.175233)
			(xy 337.911946 -53.175233) (xy 337.903816 -53.226568) (xy 337.887755 -53.275998) (xy 337.864159 -53.322308)
			(xy 337.833609 -53.364356) (xy 337.796858 -53.401107) (xy 337.75481 -53.431657) (xy 337.7085 -53.455253)
			(xy 337.65907 -53.471314) (xy 337.607735 -53.479444) (xy 337.555761 -53.479444) (xy 337.504426 -53.471314)
			(xy 337.454996 -53.455253) (xy 337.408686 -53.431657) (xy 337.366638 -53.401107) (xy 337.329887 -53.364356)
			(xy 337.299337 -53.322308) (xy 337.275741 -53.275998) (xy 337.25968 -53.226568) (xy 337.25155 -53.175233)
			(xy 336.283806 -53.175233) (xy 336.275676 -53.226568) (xy 336.259615 -53.275998) (xy 336.236019 -53.322308)
			(xy 336.205469 -53.364356) (xy 336.168718 -53.401107) (xy 336.12667 -53.431657) (xy 336.08036 -53.455253)
			(xy 336.03093 -53.471314) (xy 335.979595 -53.479444) (xy 335.927621 -53.479444) (xy 335.876286 -53.471314)
			(xy 335.826856 -53.455253) (xy 335.780546 -53.431657) (xy 335.738498 -53.401107) (xy 335.701747 -53.364356)
			(xy 335.671197 -53.322308) (xy 335.647601 -53.275998) (xy 335.63154 -53.226568) (xy 335.62341 -53.175233)
			(xy 335.385233 -53.175233) (xy 335.404753 -53.185664) (xy 335.454734 -53.220653) (xy 335.500169 -53.261373)
			(xy 335.540402 -53.30724) (xy 335.574855 -53.357593) (xy 335.603033 -53.411707) (xy 335.624531 -53.468806)
			(xy 335.639039 -53.528068) (xy 335.646349 -53.58864) (xy 335.646776 -53.619146) (xy 335.646379 -53.644879)
			(xy 342.404956 -53.644879) (xy 342.404956 -53.592905) (xy 342.413086 -53.54157) (xy 342.429147 -53.49214)
			(xy 342.452743 -53.44583) (xy 342.483293 -53.403782) (xy 342.520044 -53.367031) (xy 342.562092 -53.336481)
			(xy 342.608402 -53.312885) (xy 342.657832 -53.296824) (xy 342.709167 -53.288694) (xy 342.761141 -53.288694)
			(xy 342.812476 -53.296824) (xy 342.861906 -53.312885) (xy 342.908216 -53.336481) (xy 342.950264 -53.367031)
			(xy 342.987015 -53.403782) (xy 343.017565 -53.44583) (xy 343.041161 -53.49214) (xy 343.057222 -53.54157)
			(xy 343.065352 -53.592905) (xy 343.065862 -53.618892) (xy 343.065352 -53.644879) (xy 343.057222 -53.696214)
			(xy 343.041161 -53.745644) (xy 343.017565 -53.791954) (xy 342.987015 -53.834002) (xy 342.950264 -53.870753)
			(xy 342.908216 -53.901303) (xy 342.861906 -53.924899) (xy 342.812476 -53.94096) (xy 342.761141 -53.94909)
			(xy 342.709167 -53.94909) (xy 342.657832 -53.94096) (xy 342.608402 -53.924899) (xy 342.562092 -53.901303)
			(xy 342.520044 -53.870753) (xy 342.483293 -53.834002) (xy 342.452743 -53.791954) (xy 342.429147 -53.745644)
			(xy 342.413086 -53.696214) (xy 342.404956 -53.644879) (xy 335.646379 -53.644879) (xy 335.64628 -53.651283)
			(xy 335.638171 -53.715043) (xy 335.622089 -53.777272) (xy 335.598289 -53.836978) (xy 335.567152 -53.893206)
			(xy 335.529175 -53.94506) (xy 335.484963 -53.991712) (xy 335.435222 -54.032419) (xy 335.40827 -54.04993)
			(xy 335.40319 -54.052978) (xy 335.341168 -54.115033) (xy 341.59114 -54.115033) (xy 341.59114 -54.063059)
			(xy 341.59927 -54.011724) (xy 341.615331 -53.962294) (xy 341.638927 -53.915984) (xy 341.669477 -53.873936)
			(xy 341.706228 -53.837185) (xy 341.748276 -53.806635) (xy 341.794586 -53.783039) (xy 341.844016 -53.766978)
			(xy 341.895351 -53.758848) (xy 341.947325 -53.758848) (xy 341.99866 -53.766978) (xy 342.04809 -53.783039)
			(xy 342.0944 -53.806635) (xy 342.136448 -53.837185) (xy 342.173199 -53.873936) (xy 342.203749 -53.915984)
			(xy 342.227345 -53.962294) (xy 342.243406 -54.011724) (xy 342.251536 -54.063059) (xy 342.252046 -54.089046)
			(xy 342.251541 -54.114779) (xy 343.220296 -54.114779) (xy 343.220296 -54.062805) (xy 343.228426 -54.01147)
			(xy 343.244487 -53.96204) (xy 343.268083 -53.91573) (xy 343.298633 -53.873682) (xy 343.335384 -53.836931)
			(xy 343.377432 -53.806381) (xy 343.423742 -53.782785) (xy 343.473172 -53.766724) (xy 343.524507 -53.758594)
			(xy 343.576481 -53.758594) (xy 343.627816 -53.766724) (xy 343.677246 -53.782785) (xy 343.723556 -53.806381)
			(xy 343.765604 -53.836931) (xy 343.802355 -53.873682) (xy 343.832905 -53.91573) (xy 343.856501 -53.96204)
			(xy 343.872562 -54.01147) (xy 343.880692 -54.062805) (xy 343.881202 -54.088792) (xy 343.880692 -54.114779)
			(xy 343.872562 -54.166114) (xy 343.856501 -54.215544) (xy 343.832905 -54.261854) (xy 343.802355 -54.303902)
			(xy 343.765604 -54.340653) (xy 343.723556 -54.371203) (xy 343.677246 -54.394799) (xy 343.627816 -54.41086)
			(xy 343.576481 -54.41899) (xy 343.524507 -54.41899) (xy 343.473172 -54.41086) (xy 343.423742 -54.394799)
			(xy 343.377432 -54.371203) (xy 343.335384 -54.340653) (xy 343.298633 -54.303902) (xy 343.268083 -54.261854)
			(xy 343.244487 -54.215544) (xy 343.228426 -54.166114) (xy 343.220296 -54.114779) (xy 342.251541 -54.114779)
			(xy 342.251536 -54.115033) (xy 342.243406 -54.166368) (xy 342.227345 -54.215798) (xy 342.203749 -54.262108)
			(xy 342.173199 -54.304156) (xy 342.136448 -54.340907) (xy 342.0944 -54.371457) (xy 342.04809 -54.395053)
			(xy 341.99866 -54.411114) (xy 341.947325 -54.419244) (xy 341.895351 -54.419244) (xy 341.844016 -54.411114)
			(xy 341.794586 -54.395053) (xy 341.748276 -54.371457) (xy 341.706228 -54.340907) (xy 341.669477 -54.304156)
			(xy 341.638927 -54.262108) (xy 341.615331 -54.215798) (xy 341.59927 -54.166368) (xy 341.59114 -54.115033)
			(xy 335.341168 -54.115033) (xy 334.924908 -54.531514) (xy 334.924908 -55.20436) (xy 334.986884 -55.20436)
			(xy 334.997298 -55.199534) (xy 335.0006 -55.19801) (xy 335.008982 -55.1942) (xy 335.578704 -54.624478)
			(xy 335.651856 -54.624478) (xy 336.058764 -54.217316) (xy 336.058764 -54.217824) (xy 336.29854 -54.4576)
			(xy 336.308851 -54.467277) (xy 336.333546 -54.481032) (xy 336.361069 -54.487473) (xy 336.389302 -54.486104)
			(xy 336.416073 -54.477032) (xy 336.439322 -54.460953) (xy 336.457258 -54.439106) (xy 336.463386 -54.426358)
			(xy 336.474849 -54.401481) (xy 336.504762 -54.355598) (xy 336.541827 -54.315274) (xy 336.585032 -54.281609)
			(xy 336.633194 -54.255525) (xy 336.684996 -54.237735) (xy 336.739022 -54.228726) (xy 336.766408 -54.228238)
			(xy 336.792396 -54.228722) (xy 336.84373 -54.236854) (xy 336.893161 -54.252918) (xy 336.93947 -54.276517)
			(xy 336.981516 -54.30707) (xy 337.018265 -54.343825) (xy 337.048812 -54.385876) (xy 337.072403 -54.432189)
			(xy 337.088458 -54.481622) (xy 337.096582 -54.532958) (xy 337.097116 -54.558946) (xy 337.096604 -54.584933)
			(xy 338.06435 -54.584933) (xy 338.06435 -54.532959) (xy 338.07248 -54.481624) (xy 338.088541 -54.432194)
			(xy 338.112137 -54.385884) (xy 338.142687 -54.343836) (xy 338.179438 -54.307085) (xy 338.221486 -54.276535)
			(xy 338.267796 -54.252939) (xy 338.317226 -54.236878) (xy 338.368561 -54.228748) (xy 338.420535 -54.228748)
			(xy 338.47187 -54.236878) (xy 338.5213 -54.252939) (xy 338.56761 -54.276535) (xy 338.609658 -54.307085)
			(xy 338.646409 -54.343836) (xy 338.676959 -54.385884) (xy 338.700555 -54.432194) (xy 338.716616 -54.481624)
			(xy 338.724746 -54.532959) (xy 338.725256 -54.558946) (xy 338.724746 -54.584933) (xy 339.14766 -54.584933)
			(xy 339.14766 -54.532959) (xy 339.15579 -54.481624) (xy 339.171851 -54.432194) (xy 339.195447 -54.385884)
			(xy 339.225997 -54.343836) (xy 339.262748 -54.307085) (xy 339.304796 -54.276535) (xy 339.351106 -54.252939)
			(xy 339.400536 -54.236878) (xy 339.451871 -54.228748) (xy 339.503845 -54.228748) (xy 339.55518 -54.236878)
			(xy 339.60461 -54.252939) (xy 339.65092 -54.276535) (xy 339.692968 -54.307085) (xy 339.729719 -54.343836)
			(xy 339.760269 -54.385884) (xy 339.783865 -54.432194) (xy 339.799926 -54.481624) (xy 339.808056 -54.532959)
			(xy 339.808566 -54.558946) (xy 339.808056 -54.584933) (xy 340.7758 -54.584933) (xy 340.7758 -54.532959)
			(xy 340.78393 -54.481624) (xy 340.799991 -54.432194) (xy 340.823587 -54.385884) (xy 340.854137 -54.343836)
			(xy 340.890888 -54.307085) (xy 340.932936 -54.276535) (xy 340.979246 -54.252939) (xy 341.028676 -54.236878)
			(xy 341.080011 -54.228748) (xy 341.131985 -54.228748) (xy 341.18332 -54.236878) (xy 341.23275 -54.252939)
			(xy 341.27906 -54.276535) (xy 341.321108 -54.307085) (xy 341.357859 -54.343836) (xy 341.388409 -54.385884)
			(xy 341.412005 -54.432194) (xy 341.428066 -54.481624) (xy 341.436196 -54.532959) (xy 341.436706 -54.558946)
			(xy 341.436201 -54.584679) (xy 342.404956 -54.584679) (xy 342.404956 -54.532705) (xy 342.413086 -54.48137)
			(xy 342.429147 -54.43194) (xy 342.452743 -54.38563) (xy 342.483293 -54.343582) (xy 342.520044 -54.306831)
			(xy 342.562092 -54.276281) (xy 342.608402 -54.252685) (xy 342.657832 -54.236624) (xy 342.709167 -54.228494)
			(xy 342.761141 -54.228494) (xy 342.812476 -54.236624) (xy 342.861906 -54.252685) (xy 342.908216 -54.276281)
			(xy 342.950264 -54.306831) (xy 342.987015 -54.343582) (xy 343.017565 -54.38563) (xy 343.041161 -54.43194)
			(xy 343.057222 -54.48137) (xy 343.065352 -54.532705) (xy 343.065862 -54.558692) (xy 343.065352 -54.584679)
			(xy 344.034366 -54.584679) (xy 344.034366 -54.532705) (xy 344.042496 -54.48137) (xy 344.058557 -54.43194)
			(xy 344.082153 -54.38563) (xy 344.112703 -54.343582) (xy 344.149454 -54.306831) (xy 344.191502 -54.276281)
			(xy 344.237812 -54.252685) (xy 344.287242 -54.236624) (xy 344.338577 -54.228494) (xy 344.390551 -54.228494)
			(xy 344.441886 -54.236624) (xy 344.491316 -54.252685) (xy 344.537626 -54.276281) (xy 344.579674 -54.306831)
			(xy 344.616425 -54.343582) (xy 344.643221 -54.380463) (xy 344.821512 -54.380463) (xy 344.821512 -54.328489)
			(xy 344.829642 -54.277154) (xy 344.845703 -54.227724) (xy 344.869299 -54.181414) (xy 344.899849 -54.139366)
			(xy 344.9366 -54.102615) (xy 344.978648 -54.072065) (xy 345.024958 -54.048469) (xy 345.074388 -54.032408)
			(xy 345.125723 -54.024278) (xy 345.177697 -54.024278) (xy 345.229032 -54.032408) (xy 345.278462 -54.048469)
			(xy 345.324772 -54.072065) (xy 345.36682 -54.102615) (xy 345.403571 -54.139366) (xy 345.434121 -54.181414)
			(xy 345.457717 -54.227724) (xy 345.473778 -54.277154) (xy 345.481908 -54.328489) (xy 345.482418 -54.354476)
			(xy 345.481908 -54.380463) (xy 345.473778 -54.431798) (xy 345.457717 -54.481228) (xy 345.434121 -54.527538)
			(xy 345.403571 -54.569586) (xy 345.36682 -54.606337) (xy 345.324772 -54.636887) (xy 345.278462 -54.660483)
			(xy 345.229032 -54.676544) (xy 345.177697 -54.684674) (xy 345.125723 -54.684674) (xy 345.074388 -54.676544)
			(xy 345.024958 -54.660483) (xy 344.978648 -54.636887) (xy 344.9366 -54.606337) (xy 344.899849 -54.569586)
			(xy 344.869299 -54.527538) (xy 344.845703 -54.481228) (xy 344.829642 -54.431798) (xy 344.821512 -54.380463)
			(xy 344.643221 -54.380463) (xy 344.646975 -54.38563) (xy 344.670571 -54.43194) (xy 344.686632 -54.48137)
			(xy 344.694762 -54.532705) (xy 344.695272 -54.558692) (xy 344.694762 -54.584679) (xy 344.686632 -54.636014)
			(xy 344.670571 -54.685444) (xy 344.646975 -54.731754) (xy 344.616425 -54.773802) (xy 344.579674 -54.810553)
			(xy 344.537626 -54.841103) (xy 344.491316 -54.864699) (xy 344.441886 -54.88076) (xy 344.390551 -54.88889)
			(xy 344.338577 -54.88889) (xy 344.287242 -54.88076) (xy 344.237812 -54.864699) (xy 344.191502 -54.841103)
			(xy 344.149454 -54.810553) (xy 344.112703 -54.773802) (xy 344.082153 -54.731754) (xy 344.058557 -54.685444)
			(xy 344.042496 -54.636014) (xy 344.034366 -54.584679) (xy 343.065352 -54.584679) (xy 343.057222 -54.636014)
			(xy 343.041161 -54.685444) (xy 343.017565 -54.731754) (xy 342.987015 -54.773802) (xy 342.950264 -54.810553)
			(xy 342.908216 -54.841103) (xy 342.861906 -54.864699) (xy 342.812476 -54.88076) (xy 342.761141 -54.88889)
			(xy 342.709167 -54.88889) (xy 342.657832 -54.88076) (xy 342.608402 -54.864699) (xy 342.562092 -54.841103)
			(xy 342.520044 -54.810553) (xy 342.483293 -54.773802) (xy 342.452743 -54.731754) (xy 342.429147 -54.685444)
			(xy 342.413086 -54.636014) (xy 342.404956 -54.584679) (xy 341.436201 -54.584679) (xy 341.436196 -54.584933)
			(xy 341.428066 -54.636268) (xy 341.412005 -54.685698) (xy 341.388409 -54.732008) (xy 341.357859 -54.774056)
			(xy 341.321108 -54.810807) (xy 341.27906 -54.841357) (xy 341.23275 -54.864953) (xy 341.18332 -54.881014)
			(xy 341.131985 -54.889144) (xy 341.080011 -54.889144) (xy 341.028676 -54.881014) (xy 340.979246 -54.864953)
			(xy 340.932936 -54.841357) (xy 340.890888 -54.810807) (xy 340.854137 -54.774056) (xy 340.823587 -54.732008)
			(xy 340.799991 -54.685698) (xy 340.78393 -54.636268) (xy 340.7758 -54.584933) (xy 339.808056 -54.584933)
			(xy 339.799926 -54.636268) (xy 339.783865 -54.685698) (xy 339.760269 -54.732008) (xy 339.729719 -54.774056)
			(xy 339.692968 -54.810807) (xy 339.65092 -54.841357) (xy 339.60461 -54.864953) (xy 339.55518 -54.881014)
			(xy 339.503845 -54.889144) (xy 339.451871 -54.889144) (xy 339.400536 -54.881014) (xy 339.351106 -54.864953)
			(xy 339.304796 -54.841357) (xy 339.262748 -54.810807) (xy 339.225997 -54.774056) (xy 339.195447 -54.732008)
			(xy 339.171851 -54.685698) (xy 339.15579 -54.636268) (xy 339.14766 -54.584933) (xy 338.724746 -54.584933)
			(xy 338.716616 -54.636268) (xy 338.700555 -54.685698) (xy 338.676959 -54.732008) (xy 338.646409 -54.774056)
			(xy 338.609658 -54.810807) (xy 338.56761 -54.841357) (xy 338.5213 -54.864953) (xy 338.47187 -54.881014)
			(xy 338.420535 -54.889144) (xy 338.368561 -54.889144) (xy 338.317226 -54.881014) (xy 338.267796 -54.864953)
			(xy 338.221486 -54.841357) (xy 338.179438 -54.810807) (xy 338.142687 -54.774056) (xy 338.112137 -54.732008)
			(xy 338.088541 -54.685698) (xy 338.07248 -54.636268) (xy 338.06435 -54.584933) (xy 337.096604 -54.584933)
			(xy 337.096577 -54.586326) (xy 337.087552 -54.640339) (xy 337.069756 -54.692127) (xy 337.043675 -54.740278)
			(xy 337.010021 -54.783478) (xy 336.969713 -54.820545) (xy 336.923851 -54.85047) (xy 336.898996 -54.861968)
			(xy 336.886243 -54.868055) (xy 336.864461 -54.88604) (xy 336.848435 -54.909301) (xy 336.839387 -54.936061)
			(xy 336.838011 -54.964275) (xy 336.844411 -54.991788) (xy 336.858097 -55.016498) (xy 336.867754 -55.026814)
			(xy 336.895773 -55.054833) (xy 337.25155 -55.054833) (xy 337.25155 -55.002859) (xy 337.25968 -54.951524)
			(xy 337.275741 -54.902094) (xy 337.299337 -54.855784) (xy 337.329887 -54.813736) (xy 337.366638 -54.776985)
			(xy 337.408686 -54.746435) (xy 337.454996 -54.722839) (xy 337.504426 -54.706778) (xy 337.555761 -54.698648)
			(xy 337.607735 -54.698648) (xy 337.65907 -54.706778) (xy 337.7085 -54.722839) (xy 337.75481 -54.746435)
			(xy 337.796858 -54.776985) (xy 337.833609 -54.813736) (xy 337.864159 -54.855784) (xy 337.887755 -54.902094)
			(xy 337.903816 -54.951524) (xy 337.911946 -55.002859) (xy 337.912456 -55.028846) (xy 337.911946 -55.054833)
			(xy 339.96046 -55.054833) (xy 339.96046 -55.002859) (xy 339.96859 -54.951524) (xy 339.984651 -54.902094)
			(xy 340.008247 -54.855784) (xy 340.038797 -54.813736) (xy 340.075548 -54.776985) (xy 340.117596 -54.746435)
			(xy 340.163906 -54.722839) (xy 340.213336 -54.706778) (xy 340.264671 -54.698648) (xy 340.316645 -54.698648)
			(xy 340.36798 -54.706778) (xy 340.41741 -54.722839) (xy 340.46372 -54.746435) (xy 340.505768 -54.776985)
			(xy 340.542519 -54.813736) (xy 340.573069 -54.855784) (xy 340.596665 -54.902094) (xy 340.612726 -54.951524)
			(xy 340.620856 -55.002859) (xy 340.621366 -55.028846) (xy 340.620856 -55.054833) (xy 341.59114 -55.054833)
			(xy 341.59114 -55.002859) (xy 341.59927 -54.951524) (xy 341.615331 -54.902094) (xy 341.638927 -54.855784)
			(xy 341.669477 -54.813736) (xy 341.706228 -54.776985) (xy 341.748276 -54.746435) (xy 341.794586 -54.722839)
			(xy 341.844016 -54.706778) (xy 341.895351 -54.698648) (xy 341.947325 -54.698648) (xy 341.99866 -54.706778)
			(xy 342.04809 -54.722839) (xy 342.0944 -54.746435) (xy 342.136448 -54.776985) (xy 342.173199 -54.813736)
			(xy 342.203749 -54.855784) (xy 342.227345 -54.902094) (xy 342.243406 -54.951524) (xy 342.251536 -55.002859)
			(xy 342.252046 -55.028846) (xy 342.251541 -55.054579) (xy 343.220296 -55.054579) (xy 343.220296 -55.002605)
			(xy 343.228426 -54.95127) (xy 343.244487 -54.90184) (xy 343.268083 -54.85553) (xy 343.298633 -54.813482)
			(xy 343.335384 -54.776731) (xy 343.377432 -54.746181) (xy 343.423742 -54.722585) (xy 343.473172 -54.706524)
			(xy 343.524507 -54.698394) (xy 343.576481 -54.698394) (xy 343.627816 -54.706524) (xy 343.677246 -54.722585)
			(xy 343.723556 -54.746181) (xy 343.765604 -54.776731) (xy 343.802355 -54.813482) (xy 343.832905 -54.85553)
			(xy 343.856501 -54.90184) (xy 343.872562 -54.95127) (xy 343.880692 -55.002605) (xy 343.881202 -55.028592)
			(xy 343.880692 -55.054579) (xy 343.872562 -55.105914) (xy 343.856501 -55.155344) (xy 343.832905 -55.201654)
			(xy 343.802355 -55.243702) (xy 343.765604 -55.280453) (xy 343.723556 -55.311003) (xy 343.677246 -55.334599)
			(xy 343.627816 -55.35066) (xy 343.576481 -55.35879) (xy 343.524507 -55.35879) (xy 343.473172 -55.35066)
			(xy 343.423742 -55.334599) (xy 343.377432 -55.311003) (xy 343.335384 -55.280453) (xy 343.298633 -55.243702)
			(xy 343.268083 -55.201654) (xy 343.244487 -55.155344) (xy 343.228426 -55.105914) (xy 343.220296 -55.054579)
			(xy 342.251541 -55.054579) (xy 342.251536 -55.054833) (xy 342.243406 -55.106168) (xy 342.227345 -55.155598)
			(xy 342.203749 -55.201908) (xy 342.173199 -55.243956) (xy 342.136448 -55.280707) (xy 342.0944 -55.311257)
			(xy 342.04809 -55.334853) (xy 341.99866 -55.350914) (xy 341.947325 -55.359044) (xy 341.895351 -55.359044)
			(xy 341.844016 -55.350914) (xy 341.794586 -55.334853) (xy 341.748276 -55.311257) (xy 341.706228 -55.280707)
			(xy 341.669477 -55.243956) (xy 341.638927 -55.201908) (xy 341.615331 -55.155598) (xy 341.59927 -55.106168)
			(xy 341.59114 -55.054833) (xy 340.620856 -55.054833) (xy 340.612726 -55.106168) (xy 340.596665 -55.155598)
			(xy 340.573069 -55.201908) (xy 340.542519 -55.243956) (xy 340.505768 -55.280707) (xy 340.46372 -55.311257)
			(xy 340.41741 -55.334853) (xy 340.36798 -55.350914) (xy 340.316645 -55.359044) (xy 340.264671 -55.359044)
			(xy 340.213336 -55.350914) (xy 340.163906 -55.334853) (xy 340.117596 -55.311257) (xy 340.075548 -55.280707)
			(xy 340.038797 -55.243956) (xy 340.008247 -55.201908) (xy 339.984651 -55.155598) (xy 339.96859 -55.106168)
			(xy 339.96046 -55.054833) (xy 337.911946 -55.054833) (xy 337.903816 -55.106168) (xy 337.887755 -55.155598)
			(xy 337.864159 -55.201908) (xy 337.833609 -55.243956) (xy 337.796858 -55.280707) (xy 337.75481 -55.311257)
			(xy 337.7085 -55.334853) (xy 337.65907 -55.350914) (xy 337.607735 -55.359044) (xy 337.555761 -55.359044)
			(xy 337.504426 -55.350914) (xy 337.454996 -55.334853) (xy 337.408686 -55.311257) (xy 337.366638 -55.280707)
			(xy 337.329887 -55.243956) (xy 337.299337 -55.201908) (xy 337.275741 -55.155598) (xy 337.25968 -55.106168)
			(xy 337.25155 -55.054833) (xy 336.895773 -55.054833) (xy 337.365673 -55.524733) (xy 338.06435 -55.524733)
			(xy 338.06435 -55.472759) (xy 338.07248 -55.421424) (xy 338.088541 -55.371994) (xy 338.112137 -55.325684)
			(xy 338.142687 -55.283636) (xy 338.179438 -55.246885) (xy 338.221486 -55.216335) (xy 338.267796 -55.192739)
			(xy 338.317226 -55.176678) (xy 338.368561 -55.168548) (xy 338.420535 -55.168548) (xy 338.47187 -55.176678)
			(xy 338.5213 -55.192739) (xy 338.56761 -55.216335) (xy 338.609658 -55.246885) (xy 338.646409 -55.283636)
			(xy 338.676959 -55.325684) (xy 338.700555 -55.371994) (xy 338.716616 -55.421424) (xy 338.724746 -55.472759)
			(xy 338.725256 -55.498746) (xy 338.724746 -55.524733) (xy 339.14766 -55.524733) (xy 339.14766 -55.472759)
			(xy 339.15579 -55.421424) (xy 339.171851 -55.371994) (xy 339.195447 -55.325684) (xy 339.225997 -55.283636)
			(xy 339.262748 -55.246885) (xy 339.304796 -55.216335) (xy 339.351106 -55.192739) (xy 339.400536 -55.176678)
			(xy 339.451871 -55.168548) (xy 339.503845 -55.168548) (xy 339.55518 -55.176678) (xy 339.60461 -55.192739)
			(xy 339.65092 -55.216335) (xy 339.692968 -55.246885) (xy 339.729719 -55.283636) (xy 339.760269 -55.325684)
			(xy 339.783865 -55.371994) (xy 339.799926 -55.421424) (xy 339.808056 -55.472759) (xy 339.808566 -55.498746)
			(xy 339.808056 -55.524733) (xy 340.7758 -55.524733) (xy 340.7758 -55.472759) (xy 340.78393 -55.421424)
			(xy 340.799991 -55.371994) (xy 340.823587 -55.325684) (xy 340.854137 -55.283636) (xy 340.890888 -55.246885)
			(xy 340.932936 -55.216335) (xy 340.979246 -55.192739) (xy 341.028676 -55.176678) (xy 341.080011 -55.168548)
			(xy 341.131985 -55.168548) (xy 341.18332 -55.176678) (xy 341.23275 -55.192739) (xy 341.27906 -55.216335)
			(xy 341.321108 -55.246885) (xy 341.357859 -55.283636) (xy 341.388409 -55.325684) (xy 341.412005 -55.371994)
			(xy 341.428066 -55.421424) (xy 341.436196 -55.472759) (xy 341.436706 -55.498746) (xy 341.436201 -55.524479)
			(xy 342.404956 -55.524479) (xy 342.404956 -55.472505) (xy 342.413086 -55.42117) (xy 342.429147 -55.37174)
			(xy 342.452743 -55.32543) (xy 342.483293 -55.283382) (xy 342.520044 -55.246631) (xy 342.562092 -55.216081)
			(xy 342.608402 -55.192485) (xy 342.657832 -55.176424) (xy 342.709167 -55.168294) (xy 342.761141 -55.168294)
			(xy 342.812476 -55.176424) (xy 342.861906 -55.192485) (xy 342.908216 -55.216081) (xy 342.950264 -55.246631)
			(xy 342.987015 -55.283382) (xy 343.017565 -55.32543) (xy 343.041161 -55.37174) (xy 343.057222 -55.42117)
			(xy 343.065352 -55.472505) (xy 343.065862 -55.498492) (xy 343.065352 -55.524479) (xy 344.034366 -55.524479)
			(xy 344.034366 -55.472505) (xy 344.042496 -55.42117) (xy 344.058557 -55.37174) (xy 344.082153 -55.32543)
			(xy 344.112703 -55.283382) (xy 344.149454 -55.246631) (xy 344.191502 -55.216081) (xy 344.237812 -55.192485)
			(xy 344.287242 -55.176424) (xy 344.338577 -55.168294) (xy 344.390551 -55.168294) (xy 344.441886 -55.176424)
			(xy 344.491316 -55.192485) (xy 344.537626 -55.216081) (xy 344.579674 -55.246631) (xy 344.616425 -55.283382)
			(xy 344.646975 -55.32543) (xy 344.670571 -55.37174) (xy 344.673652 -55.381223) (xy 344.821512 -55.381223)
			(xy 344.821512 -55.329249) (xy 344.829642 -55.277914) (xy 344.845703 -55.228484) (xy 344.869299 -55.182174)
			(xy 344.899849 -55.140126) (xy 344.9366 -55.103375) (xy 344.978648 -55.072825) (xy 345.024958 -55.049229)
			(xy 345.074388 -55.033168) (xy 345.125723 -55.025038) (xy 345.177697 -55.025038) (xy 345.229032 -55.033168)
			(xy 345.278462 -55.049229) (xy 345.324772 -55.072825) (xy 345.36682 -55.103375) (xy 345.403571 -55.140126)
			(xy 345.434121 -55.182174) (xy 345.457717 -55.228484) (xy 345.473778 -55.277914) (xy 345.481908 -55.329249)
			(xy 345.482418 -55.355236) (xy 345.481908 -55.381223) (xy 345.473778 -55.432558) (xy 345.457717 -55.481988)
			(xy 345.434121 -55.528298) (xy 345.403571 -55.570346) (xy 345.36682 -55.607097) (xy 345.324772 -55.637647)
			(xy 345.278462 -55.661243) (xy 345.229032 -55.677304) (xy 345.177697 -55.685434) (xy 345.125723 -55.685434)
			(xy 345.074388 -55.677304) (xy 345.024958 -55.661243) (xy 344.978648 -55.637647) (xy 344.9366 -55.607097)
			(xy 344.899849 -55.570346) (xy 344.869299 -55.528298) (xy 344.845703 -55.481988) (xy 344.829642 -55.432558)
			(xy 344.821512 -55.381223) (xy 344.673652 -55.381223) (xy 344.686632 -55.42117) (xy 344.694762 -55.472505)
			(xy 344.695272 -55.498492) (xy 344.694762 -55.524479) (xy 344.686632 -55.575814) (xy 344.670571 -55.625244)
			(xy 344.646975 -55.671554) (xy 344.616425 -55.713602) (xy 344.579674 -55.750353) (xy 344.537626 -55.780903)
			(xy 344.491316 -55.804499) (xy 344.441886 -55.82056) (xy 344.390551 -55.82869) (xy 344.338577 -55.82869)
			(xy 344.287242 -55.82056) (xy 344.237812 -55.804499) (xy 344.191502 -55.780903) (xy 344.149454 -55.750353)
			(xy 344.112703 -55.713602) (xy 344.082153 -55.671554) (xy 344.058557 -55.625244) (xy 344.042496 -55.575814)
			(xy 344.034366 -55.524479) (xy 343.065352 -55.524479) (xy 343.057222 -55.575814) (xy 343.041161 -55.625244)
			(xy 343.017565 -55.671554) (xy 342.987015 -55.713602) (xy 342.950264 -55.750353) (xy 342.908216 -55.780903)
			(xy 342.861906 -55.804499) (xy 342.812476 -55.82056) (xy 342.761141 -55.82869) (xy 342.709167 -55.82869)
			(xy 342.657832 -55.82056) (xy 342.608402 -55.804499) (xy 342.562092 -55.780903) (xy 342.520044 -55.750353)
			(xy 342.483293 -55.713602) (xy 342.452743 -55.671554) (xy 342.429147 -55.625244) (xy 342.413086 -55.575814)
			(xy 342.404956 -55.524479) (xy 341.436201 -55.524479) (xy 341.436196 -55.524733) (xy 341.428066 -55.576068)
			(xy 341.412005 -55.625498) (xy 341.388409 -55.671808) (xy 341.357859 -55.713856) (xy 341.321108 -55.750607)
			(xy 341.27906 -55.781157) (xy 341.23275 -55.804753) (xy 341.18332 -55.820814) (xy 341.131985 -55.828944)
			(xy 341.080011 -55.828944) (xy 341.028676 -55.820814) (xy 340.979246 -55.804753) (xy 340.932936 -55.781157)
			(xy 340.890888 -55.750607) (xy 340.854137 -55.713856) (xy 340.823587 -55.671808) (xy 340.799991 -55.625498)
			(xy 340.78393 -55.576068) (xy 340.7758 -55.524733) (xy 339.808056 -55.524733) (xy 339.799926 -55.576068)
			(xy 339.783865 -55.625498) (xy 339.760269 -55.671808) (xy 339.729719 -55.713856) (xy 339.692968 -55.750607)
			(xy 339.65092 -55.781157) (xy 339.60461 -55.804753) (xy 339.55518 -55.820814) (xy 339.503845 -55.828944)
			(xy 339.451871 -55.828944) (xy 339.400536 -55.820814) (xy 339.351106 -55.804753) (xy 339.304796 -55.781157)
			(xy 339.262748 -55.750607) (xy 339.225997 -55.713856) (xy 339.195447 -55.671808) (xy 339.171851 -55.625498)
			(xy 339.15579 -55.576068) (xy 339.14766 -55.524733) (xy 338.724746 -55.524733) (xy 338.716616 -55.576068)
			(xy 338.700555 -55.625498) (xy 338.676959 -55.671808) (xy 338.646409 -55.713856) (xy 338.609658 -55.750607)
			(xy 338.56761 -55.781157) (xy 338.5213 -55.804753) (xy 338.47187 -55.820814) (xy 338.420535 -55.828944)
			(xy 338.368561 -55.828944) (xy 338.317226 -55.820814) (xy 338.267796 -55.804753) (xy 338.221486 -55.781157)
			(xy 338.179438 -55.750607) (xy 338.142687 -55.713856) (xy 338.112137 -55.671808) (xy 338.088541 -55.625498)
			(xy 338.07248 -55.576068) (xy 338.06435 -55.524733) (xy 337.365673 -55.524733) (xy 337.490562 -55.649622)
			(xy 337.517232 -55.644288) (xy 337.533195 -55.641316) (xy 337.565512 -55.638132) (xy 337.581748 -55.637938)
			(xy 337.607731 -55.638452) (xy 337.659057 -55.646588) (xy 337.708478 -55.662654) (xy 337.754778 -55.686253)
			(xy 337.796816 -55.716805) (xy 337.833556 -55.753556) (xy 337.864096 -55.795602) (xy 337.887682 -55.841909)
			(xy 337.903733 -55.891334) (xy 337.911856 -55.942662) (xy 337.912456 -55.968646) (xy 337.91226 -55.984883)
			(xy 337.911302 -55.994633) (xy 339.96046 -55.994633) (xy 339.96046 -55.942659) (xy 339.96859 -55.891324)
			(xy 339.984651 -55.841894) (xy 340.008247 -55.795584) (xy 340.038797 -55.753536) (xy 340.075548 -55.716785)
			(xy 340.117596 -55.686235) (xy 340.163906 -55.662639) (xy 340.213336 -55.646578) (xy 340.264671 -55.638448)
			(xy 340.316645 -55.638448) (xy 340.36798 -55.646578) (xy 340.41741 -55.662639) (xy 340.46372 -55.686235)
			(xy 340.505768 -55.716785) (xy 340.542519 -55.753536) (xy 340.573069 -55.795584) (xy 340.596665 -55.841894)
			(xy 340.612726 -55.891324) (xy 340.620856 -55.942659) (xy 340.621366 -55.968646) (xy 340.620856 -55.994633)
			(xy 341.59114 -55.994633) (xy 341.59114 -55.942659) (xy 341.59927 -55.891324) (xy 341.615331 -55.841894)
			(xy 341.638927 -55.795584) (xy 341.669477 -55.753536) (xy 341.706228 -55.716785) (xy 341.748276 -55.686235)
			(xy 341.794586 -55.662639) (xy 341.844016 -55.646578) (xy 341.895351 -55.638448) (xy 341.947325 -55.638448)
			(xy 341.99866 -55.646578) (xy 342.04809 -55.662639) (xy 342.0944 -55.686235) (xy 342.136448 -55.716785)
			(xy 342.173199 -55.753536) (xy 342.203749 -55.795584) (xy 342.227345 -55.841894) (xy 342.243406 -55.891324)
			(xy 342.251536 -55.942659) (xy 342.252046 -55.968646) (xy 342.251541 -55.994379) (xy 343.220296 -55.994379)
			(xy 343.220296 -55.942405) (xy 343.228426 -55.89107) (xy 343.244487 -55.84164) (xy 343.268083 -55.79533)
			(xy 343.298633 -55.753282) (xy 343.335384 -55.716531) (xy 343.377432 -55.685981) (xy 343.423742 -55.662385)
			(xy 343.473172 -55.646324) (xy 343.524507 -55.638194) (xy 343.576481 -55.638194) (xy 343.627816 -55.646324)
			(xy 343.677246 -55.662385) (xy 343.723556 -55.685981) (xy 343.765604 -55.716531) (xy 343.802355 -55.753282)
			(xy 343.832905 -55.79533) (xy 343.856501 -55.84164) (xy 343.872562 -55.89107) (xy 343.880692 -55.942405)
			(xy 343.881202 -55.968392) (xy 343.880692 -55.994379) (xy 343.872562 -56.045714) (xy 343.856501 -56.095144)
			(xy 343.832905 -56.141454) (xy 343.802355 -56.183502) (xy 343.765604 -56.220253) (xy 343.723556 -56.250803)
			(xy 343.677246 -56.274399) (xy 343.627816 -56.29046) (xy 343.576481 -56.29859) (xy 343.524507 -56.29859)
			(xy 343.473172 -56.29046) (xy 343.423742 -56.274399) (xy 343.377432 -56.250803) (xy 343.335384 -56.220253)
			(xy 343.298633 -56.183502) (xy 343.268083 -56.141454) (xy 343.244487 -56.095144) (xy 343.228426 -56.045714)
			(xy 343.220296 -55.994379) (xy 342.251541 -55.994379) (xy 342.251536 -55.994633) (xy 342.243406 -56.045968)
			(xy 342.227345 -56.095398) (xy 342.203749 -56.141708) (xy 342.173199 -56.183756) (xy 342.136448 -56.220507)
			(xy 342.0944 -56.251057) (xy 342.04809 -56.274653) (xy 341.99866 -56.290714) (xy 341.947325 -56.298844)
			(xy 341.895351 -56.298844) (xy 341.844016 -56.290714) (xy 341.794586 -56.274653) (xy 341.748276 -56.251057)
			(xy 341.706228 -56.220507) (xy 341.669477 -56.183756) (xy 341.638927 -56.141708) (xy 341.615331 -56.095398)
			(xy 341.59927 -56.045968) (xy 341.59114 -55.994633) (xy 340.620856 -55.994633) (xy 340.612726 -56.045968)
			(xy 340.596665 -56.095398) (xy 340.573069 -56.141708) (xy 340.542519 -56.183756) (xy 340.505768 -56.220507)
			(xy 340.46372 -56.251057) (xy 340.41741 -56.274653) (xy 340.36798 -56.290714) (xy 340.316645 -56.298844)
			(xy 340.264671 -56.298844) (xy 340.213336 -56.290714) (xy 340.163906 -56.274653) (xy 340.117596 -56.251057)
			(xy 340.075548 -56.220507) (xy 340.038797 -56.183756) (xy 340.008247 -56.141708) (xy 339.984651 -56.095398)
			(xy 339.96859 -56.045968) (xy 339.96046 -55.994633) (xy 337.911302 -55.994633) (xy 337.909084 -56.0172)
			(xy 337.906106 -56.033162) (xy 337.900772 -56.059832) (xy 338.032344 -56.191404) (xy 338.043729 -56.201945)
			(xy 338.071266 -56.216209) (xy 338.101812 -56.221564) (xy 338.132559 -56.21752) (xy 338.160681 -56.204447)
			(xy 338.172552 -56.194452) (xy 338.190949 -56.178241) (xy 338.231628 -56.150866) (xy 338.275903 -56.129798)
			(xy 338.322804 -56.115496) (xy 338.371302 -56.108275) (xy 338.395818 -56.107838) (xy 338.421805 -56.108323)
			(xy 338.473139 -56.116456) (xy 338.522568 -56.132521) (xy 338.568875 -56.15612) (xy 338.61092 -56.186673)
			(xy 338.647668 -56.223428) (xy 338.678213 -56.265479) (xy 338.701804 -56.311791) (xy 338.717859 -56.361224)
			(xy 338.725983 -56.412559) (xy 338.726526 -56.438546) (xy 338.726079 -56.46306) (xy 338.725859 -56.464533)
			(xy 339.14766 -56.464533) (xy 339.14766 -56.412559) (xy 339.15579 -56.361224) (xy 339.171851 -56.311794)
			(xy 339.195447 -56.265484) (xy 339.225997 -56.223436) (xy 339.262748 -56.186685) (xy 339.304796 -56.156135)
			(xy 339.351106 -56.132539) (xy 339.400536 -56.116478) (xy 339.451871 -56.108348) (xy 339.503845 -56.108348)
			(xy 339.55518 -56.116478) (xy 339.60461 -56.132539) (xy 339.65092 -56.156135) (xy 339.692968 -56.186685)
			(xy 339.729719 -56.223436) (xy 339.760269 -56.265484) (xy 339.783865 -56.311794) (xy 339.799926 -56.361224)
			(xy 339.808056 -56.412559) (xy 339.808566 -56.438546) (xy 339.808056 -56.464533) (xy 340.7758 -56.464533)
			(xy 340.7758 -56.412559) (xy 340.78393 -56.361224) (xy 340.799991 -56.311794) (xy 340.823587 -56.265484)
			(xy 340.854137 -56.223436) (xy 340.890888 -56.186685) (xy 340.932936 -56.156135) (xy 340.979246 -56.132539)
			(xy 341.028676 -56.116478) (xy 341.080011 -56.108348) (xy 341.131985 -56.108348) (xy 341.18332 -56.116478)
			(xy 341.23275 -56.132539) (xy 341.27906 -56.156135) (xy 341.321108 -56.186685) (xy 341.357859 -56.223436)
			(xy 341.388409 -56.265484) (xy 341.412005 -56.311794) (xy 341.428066 -56.361224) (xy 341.436196 -56.412559)
			(xy 341.436706 -56.438546) (xy 341.436201 -56.464279) (xy 342.404956 -56.464279) (xy 342.404956 -56.412305)
			(xy 342.413086 -56.36097) (xy 342.429147 -56.31154) (xy 342.452743 -56.26523) (xy 342.483293 -56.223182)
			(xy 342.520044 -56.186431) (xy 342.562092 -56.155881) (xy 342.608402 -56.132285) (xy 342.657832 -56.116224)
			(xy 342.709167 -56.108094) (xy 342.761141 -56.108094) (xy 342.812476 -56.116224) (xy 342.861906 -56.132285)
			(xy 342.908216 -56.155881) (xy 342.950264 -56.186431) (xy 342.987015 -56.223182) (xy 343.017565 -56.26523)
			(xy 343.041161 -56.31154) (xy 343.057222 -56.36097) (xy 343.065352 -56.412305) (xy 343.065862 -56.438292)
			(xy 343.065352 -56.464279) (xy 344.034366 -56.464279) (xy 344.034366 -56.412305) (xy 344.042496 -56.36097)
			(xy 344.058557 -56.31154) (xy 344.082153 -56.26523) (xy 344.112703 -56.223182) (xy 344.149454 -56.186431)
			(xy 344.191502 -56.155881) (xy 344.237812 -56.132285) (xy 344.287242 -56.116224) (xy 344.338577 -56.108094)
			(xy 344.390551 -56.108094) (xy 344.441886 -56.116224) (xy 344.491316 -56.132285) (xy 344.537626 -56.155881)
			(xy 344.579674 -56.186431) (xy 344.616425 -56.223182) (xy 344.646975 -56.26523) (xy 344.648361 -56.267951)
			(xy 350.634558 -56.267951) (xy 350.634558 -56.213449) (xy 350.642313 -56.159503) (xy 350.657667 -56.107209)
			(xy 350.680306 -56.057632) (xy 350.70977 -56.011782) (xy 350.745458 -55.970591) (xy 350.786645 -55.934897)
			(xy 350.832492 -55.905428) (xy 350.882066 -55.882783) (xy 350.934358 -55.867423) (xy 350.988303 -55.859661)
			(xy 351.015554 -55.859172) (xy 351.042924 -55.859605) (xy 351.097102 -55.867417) (xy 351.14961 -55.882887)
			(xy 351.19937 -55.905697) (xy 351.245361 -55.935381) (xy 351.286642 -55.971329) (xy 351.30486 -55.99176)
			(xy 351.315028 -56.002834) (xy 351.340383 -56.018963) (xy 351.369337 -56.02701) (xy 351.399379 -56.026279)
			(xy 351.427906 -56.016832) (xy 351.452447 -55.999489) (xy 351.462086 -55.98795) (xy 351.480252 -55.96539)
			(xy 351.522267 -55.925521) (xy 351.569829 -55.892467) (xy 351.621844 -55.866987) (xy 351.677115 -55.84967)
			(xy 351.73437 -55.840913) (xy 351.76333 -55.840376) (xy 351.790192 -55.840832) (xy 351.843385 -55.848373)
			(xy 351.894994 -55.863302) (xy 351.943998 -55.885323) (xy 351.989429 -55.914001) (xy 352.030387 -55.948769)
			(xy 352.066062 -55.988939) (xy 352.095749 -56.033716) (xy 352.118862 -56.082215) (xy 352.134941 -56.133477)
			(xy 352.139758 -56.159908) (xy 352.142669 -56.174482) (xy 352.155724 -56.201166) (xy 352.17589 -56.22298)
			(xy 352.201469 -56.238087) (xy 352.230308 -56.245215) (xy 352.245168 -56.244998) (xy 352.264472 -56.24449)
			(xy 352.291724 -56.244981) (xy 352.345674 -56.252734) (xy 352.397971 -56.268087) (xy 352.447551 -56.290726)
			(xy 352.493404 -56.320191) (xy 352.534597 -56.355882) (xy 352.570291 -56.397072) (xy 352.59976 -56.442923)
			(xy 352.622403 -56.492501) (xy 352.637759 -56.544797) (xy 352.645517 -56.598746) (xy 352.64598 -56.625998)
			(xy 352.645486 -56.654128) (xy 352.637224 -56.709778) (xy 352.620878 -56.763611) (xy 352.596802 -56.814459)
			(xy 352.56552 -56.86122) (xy 352.527709 -56.90288) (xy 352.48419 -56.938535) (xy 352.460306 -56.953404)
			(xy 352.447564 -56.961695) (xy 352.427203 -56.984243) (xy 352.414358 -57.011776) (xy 352.410161 -57.041866)
			(xy 352.414984 -57.071862) (xy 352.42119 -57.085738) (xy 352.433586 -57.11211) (xy 352.451138 -57.167671)
			(xy 352.460011 -57.22526) (xy 352.46056 -57.254394) (xy 352.460139 -57.281649) (xy 352.452382 -57.335604)
			(xy 352.437024 -57.387905) (xy 352.414379 -57.437489) (xy 352.384907 -57.483344) (xy 352.349208 -57.524538)
			(xy 352.333144 -57.538456) (xy 353.557743 -57.538456) (xy 353.557743 -57.483944) (xy 353.565501 -57.429988)
			(xy 353.58086 -57.377685) (xy 353.603506 -57.328101) (xy 353.632979 -57.282245) (xy 353.668678 -57.241049)
			(xy 353.709877 -57.205355) (xy 353.755736 -57.175887) (xy 353.805323 -57.153246) (xy 353.857627 -57.137893)
			(xy 353.911584 -57.13014) (xy 353.93884 -57.12968) (xy 353.96621 -57.130162) (xy 354.020389 -57.137973)
			(xy 354.072893 -57.153457) (xy 354.12264 -57.176296) (xy 354.168607 -57.206019) (xy 354.189538 -57.22366)
			(xy 354.200866 -57.232896) (xy 354.227423 -57.245072) (xy 354.25634 -57.249245) (xy 354.285257 -57.245072)
			(xy 354.311814 -57.232896) (xy 354.323142 -57.22366) (xy 354.34408 -57.206028) (xy 354.390052 -57.176316)
			(xy 354.439798 -57.15348) (xy 354.492297 -57.137987) (xy 354.546471 -57.130155) (xy 354.57384 -57.12968)
			(xy 354.601092 -57.130141) (xy 354.65504 -57.137902) (xy 354.707334 -57.153262) (xy 354.756911 -57.175907)
			(xy 354.80276 -57.205376) (xy 354.84395 -57.24107) (xy 354.879641 -57.282262) (xy 354.909107 -57.328114)
			(xy 354.931748 -57.377692) (xy 354.947104 -57.429988) (xy 354.954861 -57.483936) (xy 354.955348 -57.511188)
			(xy 354.954865 -57.53812) (xy 354.947259 -57.591445) (xy 354.932225 -57.643168) (xy 354.921566 -57.667906)
			(xy 354.916557 -57.680195) (xy 354.912251 -57.706367) (xy 354.914839 -57.732764) (xy 354.924144 -57.757602)
			(xy 354.939539 -57.779201) (xy 354.959982 -57.7961) (xy 354.971858 -57.802018) (xy 354.996355 -57.813846)
			(xy 355.042055 -57.843347) (xy 355.083103 -57.879039) (xy 355.118667 -57.920199) (xy 355.148026 -57.965991)
			(xy 355.170585 -58.015488) (xy 355.185887 -58.067687) (xy 355.193621 -58.12153) (xy 355.194108 -58.148728)
			(xy 355.193622 -58.175979) (xy 355.185866 -58.229927) (xy 355.170511 -58.282222) (xy 355.147869 -58.331799)
			(xy 355.118403 -58.377649) (xy 355.082712 -58.41884) (xy 355.041521 -58.454531) (xy 354.995671 -58.483997)
			(xy 354.946094 -58.506639) (xy 354.893799 -58.521994) (xy 354.839851 -58.52975) (xy 354.785349 -58.52975)
			(xy 354.731401 -58.521994) (xy 354.679106 -58.506639) (xy 354.629529 -58.483997) (xy 354.583679 -58.454531)
			(xy 354.542488 -58.41884) (xy 354.506797 -58.377649) (xy 354.477331 -58.331799) (xy 354.454689 -58.282222)
			(xy 354.439334 -58.229927) (xy 354.431578 -58.175979) (xy 354.431092 -58.148728) (xy 354.431586 -58.121797)
			(xy 354.439189 -58.068472) (xy 354.454218 -58.016748) (xy 354.464874 -57.99201) (xy 354.469896 -57.979724)
			(xy 354.474208 -57.953549) (xy 354.471623 -57.927147) (xy 354.462315 -57.902306) (xy 354.446914 -57.880707)
			(xy 354.426462 -57.863811) (xy 354.414582 -57.857898) (xy 354.389947 -57.84604) (xy 354.344047 -57.816336)
			(xy 354.323142 -57.798716) (xy 354.311814 -57.78948) (xy 354.285257 -57.777304) (xy 354.25634 -57.773131)
			(xy 354.227423 -57.777304) (xy 354.200866 -57.78948) (xy 354.189538 -57.798716) (xy 354.168604 -57.816353)
			(xy 354.122632 -57.846065) (xy 354.072885 -57.868901) (xy 354.020384 -57.884392) (xy 353.966209 -57.892221)
			(xy 353.93884 -57.892696) (xy 353.911584 -57.89226) (xy 353.857627 -57.884507) (xy 353.805323 -57.869154)
			(xy 353.755736 -57.846513) (xy 353.709877 -57.817045) (xy 353.668678 -57.781351) (xy 353.632979 -57.740155)
			(xy 353.603506 -57.694299) (xy 353.58086 -57.644715) (xy 353.565501 -57.592412) (xy 353.557743 -57.538456)
			(xy 352.333144 -57.538456) (xy 352.30801 -57.560232) (xy 352.262152 -57.589699) (xy 352.212566 -57.612339)
			(xy 352.160263 -57.62769) (xy 352.106307 -57.635442) (xy 352.079052 -57.635902) (xy 352.050822 -57.635438)
			(xy 351.994976 -57.627138) (xy 351.940964 -57.610696) (xy 351.889966 -57.586473) (xy 351.843095 -57.554996)
			(xy 351.801376 -57.516955) (xy 351.76572 -57.473179) (xy 351.736907 -57.424625) (xy 351.715565 -57.372355)
			(xy 351.702162 -57.31751) (xy 351.699068 -57.289446) (xy 351.697441 -57.275965) (xy 351.687971 -57.250525)
			(xy 351.672124 -57.228486) (xy 351.651024 -57.211408) (xy 351.626165 -57.200504) (xy 351.59931 -57.196546)
			(xy 351.585784 -57.197752) (xy 351.574462 -57.199048) (xy 351.551714 -57.200448) (xy 351.540318 -57.200546)
			(xy 351.513069 -57.200005) (xy 351.459125 -57.192252) (xy 351.406834 -57.176901) (xy 351.357259 -57.154265)
			(xy 351.311411 -57.124804) (xy 351.270221 -57.089118) (xy 351.23453 -57.047934) (xy 351.205062 -57.00209)
			(xy 351.182418 -56.952519) (xy 351.16706 -56.90023) (xy 351.159299 -56.846287) (xy 351.15881 -56.819038)
			(xy 351.159028 -56.799532) (xy 351.162975 -56.76072) (xy 351.166684 -56.741568) (xy 351.16899 -56.728085)
			(xy 351.167219 -56.700803) (xy 351.158274 -56.674967) (xy 351.142795 -56.65243) (xy 351.121893 -56.634806)
			(xy 351.097065 -56.623359) (xy 351.070089 -56.618908) (xy 351.056448 -56.619902) (xy 351.046257 -56.620953)
			(xy 351.025799 -56.622099) (xy 351.015554 -56.622188) (xy 350.988303 -56.621739) (xy 350.934358 -56.613977)
			(xy 350.882066 -56.598617) (xy 350.832492 -56.575972) (xy 350.786645 -56.546503) (xy 350.745458 -56.510809)
			(xy 350.70977 -56.469618) (xy 350.680306 -56.423768) (xy 350.657667 -56.374191) (xy 350.642313 -56.321897)
			(xy 350.634558 -56.267951) (xy 344.648361 -56.267951) (xy 344.670571 -56.31154) (xy 344.686632 -56.36097)
			(xy 344.694762 -56.412305) (xy 344.695272 -56.438292) (xy 344.694762 -56.464279) (xy 344.686632 -56.515614)
			(xy 344.670571 -56.565044) (xy 344.646975 -56.611354) (xy 344.616425 -56.653402) (xy 344.579674 -56.690153)
			(xy 344.537626 -56.720703) (xy 344.491316 -56.744299) (xy 344.441886 -56.76036) (xy 344.390551 -56.76849)
			(xy 344.338577 -56.76849) (xy 344.287242 -56.76036) (xy 344.237812 -56.744299) (xy 344.191502 -56.720703)
			(xy 344.149454 -56.690153) (xy 344.112703 -56.653402) (xy 344.082153 -56.611354) (xy 344.058557 -56.565044)
			(xy 344.042496 -56.515614) (xy 344.034366 -56.464279) (xy 343.065352 -56.464279) (xy 343.057222 -56.515614)
			(xy 343.041161 -56.565044) (xy 343.017565 -56.611354) (xy 342.987015 -56.653402) (xy 342.950264 -56.690153)
			(xy 342.908216 -56.720703) (xy 342.861906 -56.744299) (xy 342.812476 -56.76036) (xy 342.761141 -56.76849)
			(xy 342.709167 -56.76849) (xy 342.657832 -56.76036) (xy 342.608402 -56.744299) (xy 342.562092 -56.720703)
			(xy 342.520044 -56.690153) (xy 342.483293 -56.653402) (xy 342.452743 -56.611354) (xy 342.429147 -56.565044)
			(xy 342.413086 -56.515614) (xy 342.404956 -56.464279) (xy 341.436201 -56.464279) (xy 341.436196 -56.464533)
			(xy 341.428066 -56.515868) (xy 341.412005 -56.565298) (xy 341.388409 -56.611608) (xy 341.357859 -56.653656)
			(xy 341.321108 -56.690407) (xy 341.27906 -56.720957) (xy 341.23275 -56.744553) (xy 341.18332 -56.760614)
			(xy 341.131985 -56.768744) (xy 341.080011 -56.768744) (xy 341.028676 -56.760614) (xy 340.979246 -56.744553)
			(xy 340.932936 -56.720957) (xy 340.890888 -56.690407) (xy 340.854137 -56.653656) (xy 340.823587 -56.611608)
			(xy 340.799991 -56.565298) (xy 340.78393 -56.515868) (xy 340.7758 -56.464533) (xy 339.808056 -56.464533)
			(xy 339.799926 -56.515868) (xy 339.783865 -56.565298) (xy 339.760269 -56.611608) (xy 339.729719 -56.653656)
			(xy 339.692968 -56.690407) (xy 339.65092 -56.720957) (xy 339.60461 -56.744553) (xy 339.55518 -56.760614)
			(xy 339.503845 -56.768744) (xy 339.451871 -56.768744) (xy 339.400536 -56.760614) (xy 339.351106 -56.744553)
			(xy 339.304796 -56.720957) (xy 339.262748 -56.690407) (xy 339.225997 -56.653656) (xy 339.195447 -56.611608)
			(xy 339.171851 -56.565298) (xy 339.15579 -56.515868) (xy 339.14766 -56.464533) (xy 338.725859 -56.464533)
			(xy 338.718843 -56.511552) (xy 338.704535 -56.558447) (xy 338.683469 -56.602719) (xy 338.656105 -56.643402)
			(xy 338.639912 -56.661812) (xy 338.629841 -56.673631) (xy 338.61673 -56.701763) (xy 338.612683 -56.732535)
			(xy 338.618074 -56.7631) (xy 338.632404 -56.79063) (xy 338.64296 -56.80202) (xy 338.864956 -57.024016)
			(xy 347.457522 -57.024016) (xy 347.458043 -56.996131) (xy 347.466355 -56.940984) (xy 347.482793 -56.887692)
			(xy 347.506991 -56.837446) (xy 347.538407 -56.791367) (xy 347.57634 -56.750485) (xy 347.619942 -56.715713)
			(xy 347.66824 -56.687828) (xy 347.720155 -56.667453) (xy 347.774526 -56.655043) (xy 347.83014 -56.650876)
			(xy 347.885754 -56.655043) (xy 347.940125 -56.667453) (xy 347.99204 -56.687828) (xy 348.040338 -56.715713)
			(xy 348.08394 -56.750485) (xy 348.121873 -56.791367) (xy 348.153289 -56.837446) (xy 348.177487 -56.887692)
			(xy 348.193925 -56.940984) (xy 348.202237 -56.996131) (xy 348.202758 -57.024016) (xy 348.202343 -57.049164)
			(xy 348.195616 -57.099006) (xy 348.182246 -57.147491) (xy 348.162477 -57.193737) (xy 348.149926 -57.215532)
			(xy 348.143211 -57.227663) (xy 348.135862 -57.254384) (xy 348.135983 -57.282096) (xy 348.143564 -57.308752)
			(xy 348.158046 -57.332381) (xy 348.178357 -57.351235) (xy 348.202996 -57.36392) (xy 348.216474 -57.36717)
			(xy 348.241606 -57.372786) (xy 348.29015 -57.389964) (xy 348.335868 -57.413661) (xy 348.377887 -57.443428)
			(xy 348.415409 -57.478696) (xy 348.447717 -57.518793) (xy 348.46133 -57.540652) (xy 348.469329 -57.553206)
			(xy 348.491259 -57.57332) (xy 348.518061 -57.586249) (xy 348.547453 -57.590891) (xy 348.576935 -57.586853)
			(xy 348.603997 -57.574477) (xy 348.615508 -57.565036) (xy 348.636482 -57.547232) (xy 348.682594 -57.517224)
			(xy 348.732536 -57.494147) (xy 348.785274 -57.478478) (xy 348.839714 -57.470541) (xy 348.867222 -57.47004)
			(xy 348.894478 -57.470435) (xy 348.948434 -57.478196) (xy 349.000736 -57.493557) (xy 349.050319 -57.516206)
			(xy 349.096175 -57.54568) (xy 349.137368 -57.581381) (xy 349.173062 -57.622582) (xy 349.202528 -57.668442)
			(xy 349.225167 -57.71803) (xy 349.240519 -57.770335) (xy 349.24827 -57.824292) (xy 349.24873 -57.851548)
			(xy 349.248222 -57.870852) (xy 349.247971 -57.884011) (xy 349.253389 -57.909756) (xy 349.265198 -57.933266)
			(xy 349.282615 -57.952984) (xy 349.304488 -57.967605) (xy 349.329367 -57.97616) (xy 349.342456 -57.977532)
			(xy 349.370961 -57.980116) (xy 349.426803 -57.99266) (xy 349.480143 -58.013408) (xy 349.529784 -58.041894)
			(xy 349.574611 -58.077477) (xy 349.613618 -58.119359) (xy 349.645929 -58.166599) (xy 349.670818 -58.218138)
			(xy 349.687727 -58.272816) (xy 349.696275 -58.329407) (xy 349.696786 -58.358024) (xy 349.6963 -58.385275)
			(xy 349.688544 -58.439223) (xy 349.673189 -58.491518) (xy 349.650547 -58.541095) (xy 349.621081 -58.586945)
			(xy 349.58539 -58.628136) (xy 349.544199 -58.663827) (xy 349.498349 -58.693293) (xy 349.448772 -58.715935)
			(xy 349.396477 -58.73129) (xy 349.342529 -58.739046) (xy 349.288027 -58.739046) (xy 349.234079 -58.73129)
			(xy 349.181784 -58.715935) (xy 349.132207 -58.693293) (xy 349.086357 -58.663827) (xy 349.045166 -58.628136)
			(xy 349.009475 -58.586945) (xy 348.980009 -58.541095) (xy 348.957367 -58.491518) (xy 348.942012 -58.439223)
			(xy 348.934256 -58.385275) (xy 348.93377 -58.358024) (xy 348.934278 -58.33872) (xy 348.934556 -58.325561)
			(xy 348.92913 -58.299815) (xy 348.917316 -58.276304) (xy 348.899894 -58.256586) (xy 348.878017 -58.241966)
			(xy 348.853135 -58.233411) (xy 348.840044 -58.23204) (xy 348.813555 -58.22967) (xy 348.76155 -58.218545)
			(xy 348.711597 -58.200299) (xy 348.664665 -58.175286) (xy 348.621665 -58.143992) (xy 348.583433 -58.107026)
			(xy 348.550711 -58.065103) (xy 348.537022 -58.042302) (xy 348.529164 -58.029658) (xy 348.507481 -58.009275)
			(xy 348.480845 -57.996005) (xy 348.451514 -57.990976) (xy 348.421978 -57.994614) (xy 348.394744 -58.00661)
			(xy 348.383098 -58.015886) (xy 348.362766 -58.032561) (xy 348.318338 -58.060687) (xy 348.270396 -58.082287)
			(xy 348.219894 -58.096932) (xy 348.167835 -58.104331) (xy 348.141544 -58.104786) (xy 348.114926 -58.104325)
			(xy 348.062231 -58.096754) (xy 348.01115 -58.08176) (xy 347.962723 -58.059647) (xy 347.917936 -58.030868)
			(xy 347.877702 -57.996006) (xy 347.84284 -57.955773) (xy 347.814058 -57.910988) (xy 347.791945 -57.862562)
			(xy 347.776949 -57.811481) (xy 347.769376 -57.758786) (xy 347.768926 -57.732168) (xy 347.769322 -57.70702)
			(xy 347.776053 -57.657176) (xy 347.789428 -57.608691) (xy 347.809204 -57.562446) (xy 347.821758 -57.540652)
			(xy 347.828503 -57.528536) (xy 347.835851 -57.50181) (xy 347.835728 -57.474092) (xy 347.828142 -57.447432)
			(xy 347.813655 -57.423801) (xy 347.793337 -57.404946) (xy 347.768691 -57.392262) (xy 347.75521 -57.389014)
			(xy 347.727564 -57.382761) (xy 347.67441 -57.363092) (xy 347.624848 -57.3356) (xy 347.580021 -57.300918)
			(xy 347.540964 -57.259847) (xy 347.508579 -57.213334) (xy 347.483612 -57.162453) (xy 347.466639 -57.108377)
			(xy 347.458053 -57.052354) (xy 347.457522 -57.024016) (xy 338.864956 -57.024016) (xy 339.337983 -57.497043)
			(xy 345.157046 -57.497043) (xy 345.157046 -57.445069) (xy 345.165176 -57.393734) (xy 345.181237 -57.344304)
			(xy 345.204833 -57.297994) (xy 345.235383 -57.255946) (xy 345.272134 -57.219195) (xy 345.314182 -57.188645)
			(xy 345.360492 -57.165049) (xy 345.409922 -57.148988) (xy 345.461257 -57.140858) (xy 345.513231 -57.140858)
			(xy 345.564566 -57.148988) (xy 345.613996 -57.165049) (xy 345.660306 -57.188645) (xy 345.702354 -57.219195)
			(xy 345.739105 -57.255946) (xy 345.769655 -57.297994) (xy 345.793251 -57.344304) (xy 345.809312 -57.393734)
			(xy 345.817442 -57.445069) (xy 345.817952 -57.471056) (xy 345.817442 -57.497043) (xy 345.809312 -57.548378)
			(xy 345.793251 -57.597808) (xy 345.769655 -57.644118) (xy 345.739105 -57.686166) (xy 345.702354 -57.722917)
			(xy 345.660306 -57.753467) (xy 345.613996 -57.777063) (xy 345.564566 -57.793124) (xy 345.513231 -57.801254)
			(xy 345.461257 -57.801254) (xy 345.409922 -57.793124) (xy 345.360492 -57.777063) (xy 345.314182 -57.753467)
			(xy 345.272134 -57.722917) (xy 345.235383 -57.686166) (xy 345.204833 -57.644118) (xy 345.181237 -57.597808)
			(xy 345.165176 -57.548378) (xy 345.157046 -57.497043) (xy 339.337983 -57.497043) (xy 339.785452 -57.944512)
			(xy 339.785452 -60.057792) (xy 345.349078 -60.057792) (xy 345.353054 -60.003466) (xy 345.364897 -59.950297)
			(xy 345.384356 -59.89942) (xy 345.411016 -59.851918) (xy 345.444307 -59.808804) (xy 345.483521 -59.770997)
			(xy 345.527823 -59.739302) (xy 345.576266 -59.714396) (xy 345.62782 -59.696808) (xy 345.681386 -59.686914)
			(xy 345.735821 -59.684924) (xy 345.789966 -59.690882) (xy 345.842666 -59.70466) (xy 345.892799 -59.725964)
			(xy 345.939295 -59.75434) (xy 345.981165 -59.789184) (xy 346.017514 -59.829753) (xy 346.04757 -59.875182)
			(xy 346.070691 -59.924503) (xy 346.086384 -59.976665) (xy 346.094315 -60.030556) (xy 346.094443 -60.037554)
			(xy 349.026149 -60.037554) (xy 349.026149 -59.983046) (xy 349.033907 -59.929091) (xy 349.049265 -59.876791)
			(xy 349.07191 -59.827208) (xy 349.10138 -59.781353) (xy 349.137077 -59.740159) (xy 349.178274 -59.704465)
			(xy 349.224131 -59.674997) (xy 349.273715 -59.652356) (xy 349.326017 -59.637002) (xy 349.379972 -59.629248)
			(xy 349.407226 -59.628786) (xy 349.436632 -59.629333) (xy 349.494748 -59.638349) (xy 349.550792 -59.65618)
			(xy 349.603435 -59.682402) (xy 349.651428 -59.716394) (xy 349.67291 -59.736482) (xy 349.683484 -59.746129)
			(xy 349.708741 -59.75958) (xy 349.736735 -59.765505) (xy 349.765275 -59.76344) (xy 349.792125 -59.753547)
			(xy 349.815182 -59.736601) (xy 349.824294 -59.72556) (xy 349.842495 -59.702814) (xy 349.884582 -59.662542)
			(xy 349.932305 -59.629139) (xy 349.984552 -59.603382) (xy 350.040109 -59.585871) (xy 350.097682 -59.577013)
			(xy 350.126808 -59.576462) (xy 350.152507 -59.576907) (xy 350.20344 -59.583803) (xy 350.252988 -59.59747)
			(xy 350.300254 -59.617661) (xy 350.344385 -59.64401) (xy 350.384581 -59.676041) (xy 350.402652 -59.694318)
			(xy 350.412546 -59.704127) (xy 350.436494 -59.718351) (xy 350.463397 -59.725564) (xy 350.491248 -59.725226)
			(xy 350.517969 -59.717365) (xy 350.541565 -59.702565) (xy 350.551242 -59.69254) (xy 350.569422 -59.673242)
			(xy 350.610164 -59.639317) (xy 350.655209 -59.611359) (xy 350.703691 -59.589904) (xy 350.754675 -59.575367)
			(xy 350.807182 -59.568027) (xy 350.83369 -59.567572) (xy 350.860046 -59.568014) (xy 350.912258 -59.575258)
			(xy 350.962975 -59.589622) (xy 351.011231 -59.610832) (xy 351.056106 -59.638486) (xy 351.096747 -59.672056)
			(xy 351.132377 -59.710902) (xy 351.162319 -59.754284) (xy 351.174558 -59.77763) (xy 351.181698 -59.790662)
			(xy 351.202114 -59.812234) (xy 351.227862 -59.827041) (xy 351.256776 -59.833836) (xy 351.286424 -59.832048)
			(xy 351.300542 -59.827414) (xy 351.32749 -59.817856) (xy 351.383071 -59.804424) (xy 351.439846 -59.797634)
			(xy 351.468436 -59.797188) (xy 351.498501 -59.797623) (xy 351.558168 -59.805074) (xy 351.616453 -59.819857)
			(xy 351.672459 -59.841744) (xy 351.725323 -59.870398) (xy 351.774232 -59.905379) (xy 351.818432 -59.946147)
			(xy 351.857243 -59.992075) (xy 351.890067 -60.042456) (xy 351.9164 -60.096514) (xy 351.935835 -60.153417)
			(xy 351.9424 -60.18276) (xy 351.945865 -60.196843) (xy 351.959483 -60.222432) (xy 351.979737 -60.24317)
			(xy 352.004997 -60.257388) (xy 352.033233 -60.263944) (xy 352.062174 -60.26231) (xy 352.076004 -60.257944)
			(xy 352.106992 -60.247578) (xy 352.171353 -60.236332) (xy 352.20402 -60.235592) (xy 352.231285 -60.236037)
			(xy 352.285259 -60.243803) (xy 352.337577 -60.259175) (xy 352.387175 -60.281838) (xy 352.43304 -60.311332)
			(xy 352.474239 -60.347055) (xy 352.509933 -60.38828) (xy 352.539393 -60.434166) (xy 352.562021 -60.48378)
			(xy 352.571837 -60.517278) (xy 355.221032 -60.517278) (xy 355.221535 -60.487794) (xy 355.229565 -60.429375)
			(xy 355.245474 -60.372593) (xy 355.268967 -60.318507) (xy 355.299606 -60.268123) (xy 355.33682 -60.222381)
			(xy 355.379916 -60.182132) (xy 355.428092 -60.148126) (xy 355.480449 -60.120997) (xy 355.536012 -60.10125)
			(xy 355.593747 -60.089252) (xy 355.652578 -60.085228) (xy 355.711409 -60.089252) (xy 355.769144 -60.10125)
			(xy 355.824707 -60.120997) (xy 355.877064 -60.148126) (xy 355.92524 -60.182132) (xy 355.968336 -60.222381)
			(xy 356.00555 -60.268123) (xy 356.036189 -60.318507) (xy 356.059682 -60.372593) (xy 356.075591 -60.429375)
			(xy 356.083621 -60.487794) (xy 356.084124 -60.517278) (xy 356.083731 -60.544288) (xy 356.077009 -60.597889)
			(xy 356.063653 -60.650233) (xy 356.054152 -60.67552) (xy 356.049402 -60.688844) (xy 356.046664 -60.716986)
			(xy 356.051755 -60.744799) (xy 356.064284 -60.770147) (xy 356.083289 -60.791082) (xy 356.10731 -60.805998)
			(xy 356.134502 -60.813747) (xy 356.14864 -60.814204) (xy 356.473506 -60.814204) (xy 356.487204 -60.813768)
			(xy 356.513618 -60.806508) (xy 356.537151 -60.792484) (xy 356.556106 -60.772706) (xy 356.56912 -60.7486)
			(xy 356.575254 -60.721901) (xy 356.574067 -60.694533) (xy 356.57028 -60.681362) (xy 356.560387 -60.648912)
			(xy 356.549669 -60.581929) (xy 356.548944 -60.548012) (xy 356.549447 -60.51851) (xy 356.557482 -60.460057)
			(xy 356.5734 -60.403242) (xy 356.596907 -60.349124) (xy 356.627564 -60.298711) (xy 356.6648 -60.252941)
			(xy 356.707922 -60.212669) (xy 356.756126 -60.178643) (xy 356.808513 -60.151497) (xy 356.86411 -60.131739)
			(xy 356.921879 -60.119734) (xy 356.980744 -60.115708) (xy 357.039609 -60.119734) (xy 357.097378 -60.131739)
			(xy 357.152975 -60.151497) (xy 357.205362 -60.178643) (xy 357.253566 -60.212669) (xy 357.296688 -60.252941)
			(xy 357.333924 -60.298711) (xy 357.364581 -60.349124) (xy 357.388088 -60.403242) (xy 357.404006 -60.460057)
			(xy 357.412041 -60.51851) (xy 357.412544 -60.548012) (xy 357.412088 -60.576849) (xy 357.404404 -60.63401)
			(xy 357.389176 -60.689637) (xy 357.366675 -60.742741) (xy 357.3373 -60.792375) (xy 357.301577 -60.837654)
			(xy 357.260141 -60.877771) (xy 357.213732 -60.912012) (xy 357.163175 -60.939767) (xy 357.136446 -60.950602)
			(xy 357.12218 -60.956645) (xy 357.097941 -60.975921) (xy 357.080594 -61.001576) (xy 357.071733 -61.031251)
			(xy 357.072172 -61.062217) (xy 357.07288 -61.064648) (xy 378.870462 -61.064648) (xy 378.874533 -61.009026)
			(xy 378.886659 -60.954589) (xy 378.906582 -60.902498) (xy 378.933878 -60.853863) (xy 378.967964 -60.80972)
			(xy 379.008113 -60.771011) (xy 379.053471 -60.73856) (xy 379.103071 -60.713059) (xy 379.155855 -60.695052)
			(xy 379.210698 -60.684922) (xy 379.266432 -60.682885) (xy 379.321869 -60.688985) (xy 379.375826 -60.703091)
			(xy 379.427155 -60.724903) (xy 379.474761 -60.753957) (xy 379.517629 -60.789632) (xy 379.554846 -60.831169)
			(xy 379.585619 -60.877682) (xy 379.609291 -60.928179) (xy 379.625359 -60.981586) (xy 379.633479 -61.036762)
			(xy 379.633988 -61.064648) (xy 379.633479 -61.092534) (xy 379.625359 -61.14771) (xy 379.609291 -61.201117)
			(xy 379.585619 -61.251614) (xy 379.554846 -61.298127) (xy 379.517629 -61.339664) (xy 379.474761 -61.375339)
			(xy 379.427155 -61.404393) (xy 379.375826 -61.426205) (xy 379.321869 -61.440311) (xy 379.266432 -61.446411)
			(xy 379.210698 -61.444374) (xy 379.155855 -61.434244) (xy 379.103071 -61.416237) (xy 379.053471 -61.390736)
			(xy 379.008113 -61.358285) (xy 378.967964 -61.319576) (xy 378.933878 -61.275433) (xy 378.906582 -61.226798)
			(xy 378.886659 -61.174707) (xy 378.874533 -61.12027) (xy 378.870462 -61.064648) (xy 357.07288 -61.064648)
			(xy 357.076502 -61.077094) (xy 357.085372 -61.10601) (xy 357.094951 -61.165727) (xy 357.095552 -61.195966)
			(xy 357.095067 -61.223237) (xy 357.087309 -61.277223) (xy 357.071947 -61.329556) (xy 357.049292 -61.37917)
			(xy 357.019807 -61.425054) (xy 356.984092 -61.466275) (xy 356.942873 -61.501993) (xy 356.896991 -61.531481)
			(xy 356.847379 -61.554138) (xy 356.795047 -61.569504) (xy 356.741061 -61.577265) (xy 356.71379 -61.577728)
			(xy 355.85019 -61.577728) (xy 355.822917 -61.577308) (xy 355.768927 -61.569543) (xy 355.716591 -61.554174)
			(xy 355.666976 -61.531513) (xy 355.621091 -61.502021) (xy 355.57987 -61.466299) (xy 355.544153 -61.425074)
			(xy 355.514666 -61.379185) (xy 355.492011 -61.329567) (xy 355.476647 -61.27723) (xy 355.468889 -61.223239)
			(xy 355.468428 -61.195966) (xy 355.468924 -61.168385) (xy 355.476869 -61.113799) (xy 355.492591 -61.060926)
			(xy 355.503734 -61.035692) (xy 355.50975 -61.021247) (xy 355.513727 -60.990232) (xy 355.508136 -60.959466)
			(xy 355.493501 -60.931832) (xy 355.471193 -60.90992) (xy 355.457506 -60.902342) (xy 355.43122 -60.888432)
			(xy 355.38237 -60.854516) (xy 355.338639 -60.814214) (xy 355.300854 -60.768292) (xy 355.26973 -60.717617)
			(xy 355.245858 -60.663149) (xy 355.229688 -60.60592) (xy 355.221528 -60.547013) (xy 355.221032 -60.517278)
			(xy 352.571837 -60.517278) (xy 352.577355 -60.536109) (xy 352.585083 -60.590089) (xy 352.585528 -60.617354)
			(xy 352.585528 -61.480954) (xy 352.585034 -61.508212) (xy 352.577284 -61.562175) (xy 352.561935 -61.614486)
			(xy 352.539301 -61.664082) (xy 352.50984 -61.709952) (xy 352.474153 -61.751165) (xy 352.432965 -61.78688)
			(xy 352.387115 -61.816373) (xy 352.337536 -61.839042) (xy 352.285235 -61.854427) (xy 352.231278 -61.862215)
			(xy 352.20402 -61.862716) (xy 352.170886 -61.861971) (xy 352.105621 -61.850476) (xy 352.074226 -61.839856)
			(xy 352.060549 -61.835438) (xy 352.031884 -61.833557) (xy 352.003831 -61.83974) (xy 351.978612 -61.853497)
			(xy 351.958228 -61.873738) (xy 351.944294 -61.898859) (xy 351.940622 -61.912754) (xy 351.932852 -61.944465)
			(xy 351.910003 -62.005626) (xy 351.879142 -62.06316) (xy 351.840829 -62.116026) (xy 351.795759 -62.163262)
			(xy 351.74475 -62.204014) (xy 351.688726 -62.23754) (xy 351.673507 -62.244055) (xy 371.426147 -62.244055)
			(xy 371.426147 -62.189545) (xy 371.433905 -62.13559) (xy 371.449263 -62.083289) (xy 371.471909 -62.033705)
			(xy 371.50138 -61.98785) (xy 371.537078 -61.946655) (xy 371.578276 -61.910961) (xy 371.624134 -61.881493)
			(xy 371.673719 -61.858852) (xy 371.726022 -61.843499) (xy 371.779977 -61.835745) (xy 371.807232 -61.835284)
			(xy 371.833834 -61.835791) (xy 371.886524 -61.843164) (xy 371.937678 -61.857788) (xy 371.986303 -61.879381)
			(xy 372.031454 -61.907524) (xy 372.072255 -61.941669) (xy 372.107913 -61.981154) (xy 372.123208 -62.002924)
			(xy 372.131542 -62.014404) (xy 372.153286 -62.032608) (xy 372.179199 -62.044126) (xy 372.207282 -62.048066)
			(xy 372.235365 -62.044126) (xy 372.261278 -62.032608) (xy 372.283022 -62.014404) (xy 372.291356 -62.002924)
			(xy 372.306662 -61.981162) (xy 372.342327 -61.941683) (xy 372.383129 -61.90754) (xy 372.428277 -61.879394)
			(xy 372.476896 -61.85779) (xy 372.528044 -61.843147) (xy 372.580731 -61.83575) (xy 372.607332 -61.835284)
			(xy 372.634581 -61.835788) (xy 372.688524 -61.843548) (xy 372.740814 -61.858906) (xy 372.790386 -61.881548)
			(xy 372.836232 -61.911015) (xy 372.877417 -61.946705) (xy 372.913105 -61.987894) (xy 372.942567 -62.033742)
			(xy 372.965206 -62.083316) (xy 372.980559 -62.135607) (xy 372.988314 -62.189551) (xy 372.988314 -62.244049)
			(xy 372.980559 -62.297993) (xy 372.965206 -62.350284) (xy 372.942567 -62.399858) (xy 372.913105 -62.445706)
			(xy 372.877417 -62.486895) (xy 372.836232 -62.522585) (xy 372.790386 -62.552052) (xy 372.740814 -62.574694)
			(xy 372.688524 -62.590052) (xy 372.634581 -62.597812) (xy 372.607332 -62.5983) (xy 372.580729 -62.597827)
			(xy 372.528037 -62.59045) (xy 372.476882 -62.575819) (xy 372.428257 -62.554221) (xy 372.383106 -62.526073)
			(xy 372.342306 -62.491923) (xy 372.30665 -62.452432) (xy 372.291356 -62.43066) (xy 372.283022 -62.41918)
			(xy 372.261278 -62.400976) (xy 372.235365 -62.389458) (xy 372.207282 -62.385518) (xy 372.179199 -62.389458)
			(xy 372.153286 -62.400976) (xy 372.131542 -62.41918) (xy 372.123208 -62.43066) (xy 372.10792 -62.452435)
			(xy 372.072253 -62.491914) (xy 372.031448 -62.526057) (xy 371.986297 -62.554202) (xy 371.937674 -62.575804)
			(xy 371.886523 -62.590443) (xy 371.833834 -62.597837) (xy 371.807232 -62.5983) (xy 371.779977 -62.597855)
			(xy 371.726022 -62.590101) (xy 371.673719 -62.574748) (xy 371.624134 -62.552107) (xy 371.578276 -62.522639)
			(xy 371.537078 -62.486945) (xy 371.50138 -62.44575) (xy 371.471909 -62.399895) (xy 371.449263 -62.350311)
			(xy 371.433905 -62.29801) (xy 371.426147 -62.244055) (xy 351.673507 -62.244055) (xy 351.628705 -62.263234)
			(xy 351.565776 -62.280628) (xy 351.50108 -62.289407) (xy 351.468436 -62.289944) (xy 351.436717 -62.289518)
			(xy 351.373821 -62.281242) (xy 351.312544 -62.264827) (xy 351.253933 -62.240553) (xy 351.198993 -62.208837)
			(xy 351.148662 -62.170221) (xy 351.103803 -62.125365) (xy 351.065183 -62.075037) (xy 351.033463 -62.020099)
			(xy 351.009185 -61.96149) (xy 350.992765 -61.900214) (xy 350.984484 -61.837319) (xy 350.984484 -61.773881)
			(xy 350.992765 -61.710986) (xy 351.009185 -61.64971) (xy 351.033463 -61.591101) (xy 351.065183 -61.536163)
			(xy 351.103803 -61.485835) (xy 351.148662 -61.440979) (xy 351.198993 -61.402363) (xy 351.253933 -61.370647)
			(xy 351.312544 -61.346373) (xy 351.373821 -61.329958) (xy 351.436717 -61.321682) (xy 351.468436 -61.321188)
			(xy 351.504384 -61.321871) (xy 351.575487 -61.332525) (xy 351.64424 -61.353551) (xy 351.67697 -61.368432)
			(xy 351.690404 -61.374366) (xy 351.719399 -61.378977) (xy 351.748509 -61.375162) (xy 351.775336 -61.363235)
			(xy 351.797671 -61.344179) (xy 351.813672 -61.319564) (xy 351.822022 -61.291417) (xy 351.822512 -61.276738)
			(xy 351.822512 -60.810394) (xy 351.822016 -60.795712) (xy 351.81369 -60.767554) (xy 351.797699 -60.742927)
			(xy 351.775364 -60.723865) (xy 351.748529 -60.711944) (xy 351.719413 -60.708148) (xy 351.690419 -60.71279)
			(xy 351.67697 -60.7187) (xy 351.644241 -60.73359) (xy 351.575494 -60.754648) (xy 351.504386 -60.765289)
			(xy 351.468436 -60.765944) (xy 351.436485 -60.765445) (xy 351.373141 -60.75703) (xy 351.311453 -60.740356)
			(xy 351.252495 -60.715712) (xy 351.197292 -60.683526) (xy 351.146802 -60.644357) (xy 351.101904 -60.598887)
			(xy 351.063377 -60.547906) (xy 351.031891 -60.4923) (xy 351.007995 -60.433035) (xy 350.999552 -60.402216)
			(xy 350.995293 -60.387952) (xy 350.979908 -60.362487) (xy 350.957851 -60.34252) (xy 350.930985 -60.329739)
			(xy 350.901579 -60.325221) (xy 350.886776 -60.326778) (xy 350.873575 -60.328541) (xy 350.847008 -60.330446)
			(xy 350.83369 -60.330588) (xy 350.80799 -60.33016) (xy 350.757056 -60.323262) (xy 350.707507 -60.309593)
			(xy 350.66024 -60.2894) (xy 350.616111 -60.263047) (xy 350.575915 -60.231012) (xy 350.557846 -60.212732)
			(xy 350.547951 -60.202926) (xy 350.524002 -60.188709) (xy 350.4971 -60.181501) (xy 350.469252 -60.181838)
			(xy 350.442532 -60.189696) (xy 350.418935 -60.204489) (xy 350.409256 -60.21451) (xy 350.391067 -60.233799)
			(xy 350.350328 -60.267727) (xy 350.305285 -60.295688) (xy 350.256805 -60.317144) (xy 350.205821 -60.331682)
			(xy 350.153316 -60.339023) (xy 350.126808 -60.339478) (xy 350.097402 -60.33892) (xy 350.039286 -60.329908)
			(xy 349.983242 -60.312081) (xy 349.930599 -60.28586) (xy 349.882606 -60.251869) (xy 349.861124 -60.231782)
			(xy 349.850515 -60.222177) (xy 349.825269 -60.208729) (xy 349.797285 -60.202801) (xy 349.768754 -60.204859)
			(xy 349.74191 -60.21474) (xy 349.718854 -60.231671) (xy 349.70974 -60.242704) (xy 349.691593 -60.265495)
			(xy 349.649493 -60.305761) (xy 349.601759 -60.339158) (xy 349.549501 -60.364906) (xy 349.493935 -60.382408)
			(xy 349.436354 -60.391256) (xy 349.407226 -60.391802) (xy 349.379972 -60.391352) (xy 349.326017 -60.383598)
			(xy 349.273715 -60.368244) (xy 349.224131 -60.345603) (xy 349.178274 -60.316135) (xy 349.137077 -60.280441)
			(xy 349.10138 -60.239247) (xy 349.07191 -60.193392) (xy 349.049265 -60.143809) (xy 349.033907 -60.091509)
			(xy 349.026149 -60.037554) (xy 346.094443 -60.037554) (xy 346.094812 -60.057792) (xy 346.094315 -60.085028)
			(xy 346.086384 -60.138919) (xy 346.070691 -60.191081) (xy 346.04757 -60.240402) (xy 346.017514 -60.285831)
			(xy 345.981165 -60.3264) (xy 345.939295 -60.361244) (xy 345.892799 -60.38962) (xy 345.842666 -60.410924)
			(xy 345.789966 -60.424702) (xy 345.735821 -60.43066) (xy 345.681386 -60.42867) (xy 345.62782 -60.418776)
			(xy 345.576266 -60.401188) (xy 345.527823 -60.376282) (xy 345.483521 -60.344587) (xy 345.444307 -60.30678)
			(xy 345.411016 -60.263666) (xy 345.384356 -60.216164) (xy 345.364897 -60.165287) (xy 345.353054 -60.112118)
			(xy 345.349078 -60.057792) (xy 339.785452 -60.057792) (xy 339.785452 -60.357766) (xy 343.053883 -63.626197)
			(xy 349.462882 -63.626197) (xy 349.462882 -63.562803) (xy 349.471156 -63.499952) (xy 349.487563 -63.438719)
			(xy 349.511822 -63.380151) (xy 349.543517 -63.32525) (xy 349.582107 -63.274955) (xy 349.626931 -63.230128)
			(xy 349.677223 -63.191535) (xy 349.732122 -63.159836) (xy 349.790689 -63.135573) (xy 349.851921 -63.119162)
			(xy 349.914771 -63.110884) (xy 349.946468 -63.110364) (xy 349.982408 -63.111) (xy 350.053508 -63.121557)
			(xy 350.122267 -63.142506) (xy 350.155002 -63.157354) (xy 350.168477 -63.163186) (xy 350.197454 -63.167808)
			(xy 350.22655 -63.164007) (xy 350.253368 -63.152097) (xy 350.275697 -63.133059) (xy 350.291698 -63.108461)
			(xy 350.300051 -63.080332) (xy 350.300544 -63.06566) (xy 350.300544 -62.599316) (xy 350.299986 -62.584638)
			(xy 350.291669 -62.556487) (xy 350.275688 -62.531865) (xy 350.253363 -62.512805) (xy 350.22654 -62.500882)
			(xy 350.197433 -62.497081) (xy 350.168447 -62.501717) (xy 350.155002 -62.507622) (xy 350.122268 -62.522477)
			(xy 350.053511 -62.543438) (xy 349.982409 -62.553995) (xy 349.946468 -62.554612) (xy 349.914771 -62.554116)
			(xy 349.851921 -62.545838) (xy 349.790689 -62.529427) (xy 349.732122 -62.505164) (xy 349.677223 -62.473465)
			(xy 349.626931 -62.434872) (xy 349.582107 -62.390045) (xy 349.543517 -62.33975) (xy 349.511822 -62.284849)
			(xy 349.487563 -62.226281) (xy 349.471156 -62.165048) (xy 349.462882 -62.102197) (xy 349.462882 -62.038803)
			(xy 349.471156 -61.975952) (xy 349.487563 -61.914719) (xy 349.511822 -61.856151) (xy 349.543517 -61.80125)
			(xy 349.582107 -61.750955) (xy 349.626931 -61.706128) (xy 349.677223 -61.667535) (xy 349.732122 -61.635836)
			(xy 349.790689 -61.611573) (xy 349.851921 -61.595162) (xy 349.914771 -61.586884) (xy 349.946468 -61.586364)
			(xy 349.976523 -61.586828) (xy 350.03617 -61.594265) (xy 350.094438 -61.60903) (xy 350.15043 -61.630895)
			(xy 350.203284 -61.659523) (xy 350.252188 -61.694475) (xy 350.296388 -61.735211) (xy 350.335205 -61.781107)
			(xy 350.368042 -61.831455) (xy 350.394393 -61.88548) (xy 350.413853 -61.942353) (xy 350.420432 -61.971682)
			(xy 350.423845 -61.98578) (xy 350.437474 -62.011373) (xy 350.457738 -62.03211) (xy 350.483009 -62.046326)
			(xy 350.511255 -62.052877) (xy 350.540203 -62.051236) (xy 350.554036 -62.046866) (xy 350.585031 -62.036555)
			(xy 350.649394 -62.025439) (xy 350.682052 -62.024768) (xy 350.709303 -62.0253) (xy 350.76325 -62.03305)
			(xy 350.815545 -62.048398) (xy 350.865123 -62.071034) (xy 350.910975 -62.100494) (xy 350.952168 -62.136181)
			(xy 350.987862 -62.177367) (xy 351.017332 -62.223213) (xy 351.039976 -62.272788) (xy 351.055335 -62.32508)
			(xy 351.063095 -62.379026) (xy 351.06356 -62.406276) (xy 351.06356 -63.269876) (xy 351.063122 -63.29713)
			(xy 351.055367 -63.351085) (xy 351.040012 -63.403386) (xy 351.017369 -63.452969) (xy 350.987899 -63.498825)
			(xy 350.952202 -63.540019) (xy 350.911006 -63.575713) (xy 350.865148 -63.60518) (xy 350.815564 -63.62782)
			(xy 350.763261 -63.643172) (xy 350.709306 -63.650924) (xy 350.682052 -63.651384) (xy 350.648928 -63.650698)
			(xy 350.583664 -63.639327) (xy 350.552258 -63.628778) (xy 350.538608 -63.624266) (xy 350.509928 -63.622399)
			(xy 350.481864 -63.628599) (xy 350.456639 -63.642374) (xy 350.436254 -63.662634) (xy 350.422322 -63.687773)
			(xy 350.418654 -63.701676) (xy 350.410903 -63.733381) (xy 350.388016 -63.794504) (xy 350.357128 -63.852)
			(xy 350.318797 -63.904827) (xy 350.273719 -63.952027) (xy 350.22271 -63.992746) (xy 350.166695 -64.026245)
			(xy 350.106688 -64.051918) (xy 350.043777 -64.069299) (xy 349.979102 -64.078074) (xy 349.946468 -64.078612)
			(xy 349.914771 -64.078116) (xy 349.851921 -64.069838) (xy 349.790689 -64.053427) (xy 349.732122 -64.029164)
			(xy 349.677223 -63.997465) (xy 349.626931 -63.958872) (xy 349.582107 -63.914045) (xy 349.543517 -63.86375)
			(xy 349.511822 -63.808849) (xy 349.487563 -63.750281) (xy 349.471156 -63.689048) (xy 349.462882 -63.626197)
			(xy 343.053883 -63.626197) (xy 344.998548 -65.570862) (xy 349.473012 -65.570862) (xy 349.485933 -65.54244)
			(xy 349.518029 -65.488887) (xy 349.556742 -65.439903) (xy 349.601428 -65.3963) (xy 349.651346 -65.3588)
			(xy 349.705669 -65.328026) (xy 349.763497 -65.304487) (xy 349.82387 -65.288574) (xy 349.885787 -65.280551)
			(xy 349.948221 -65.280551) (xy 350.010138 -65.288574) (xy 350.070511 -65.304487) (xy 350.128339 -65.328026)
			(xy 350.182662 -65.3588) (xy 350.23258 -65.3963) (xy 350.277266 -65.439903) (xy 350.315979 -65.488887)
			(xy 350.348075 -65.54244) (xy 350.360996 -65.570862) (xy 352.280982 -65.570862) (xy 352.294545 -65.570438)
			(xy 352.320715 -65.563302) (xy 352.344085 -65.54953) (xy 352.363005 -65.530092) (xy 352.376141 -65.506359)
			(xy 352.382567 -65.480005) (xy 352.381829 -65.452889) (xy 352.378264 -65.439798) (xy 352.370647 -65.412879)
			(xy 352.36248 -65.357534) (xy 352.362008 -65.329562) (xy 352.362008 -64.465962) (xy 352.36255 -64.436951)
			(xy 352.371331 -64.379597) (xy 352.388684 -64.324231) (xy 352.414211 -64.272126) (xy 352.447325 -64.224481)
			(xy 352.46691 -64.203072) (xy 352.476396 -64.192433) (xy 352.4896 -64.167186) (xy 352.495322 -64.139276)
			(xy 352.493119 -64.11087) (xy 352.483161 -64.084175) (xy 352.466223 -64.061266) (xy 352.455226 -64.052196)
			(xy 352.430343 -64.032508) (xy 352.385444 -63.987672) (xy 352.346786 -63.937356) (xy 352.31503 -63.882422)
			(xy 352.290722 -63.823811) (xy 352.274277 -63.762527) (xy 352.265977 -63.69962) (xy 352.265488 -63.667894)
			(xy 352.265984 -63.636875) (xy 352.27391 -63.575347) (xy 352.289631 -63.515335) (xy 352.312891 -63.457823)
			(xy 352.343307 -63.403754) (xy 352.380381 -63.354013) (xy 352.423506 -63.309417) (xy 352.471975 -63.270695)
			(xy 352.524994 -63.238482) (xy 352.581693 -63.213307) (xy 352.641144 -63.195582) (xy 352.702373 -63.185596)
			(xy 352.733356 -63.184024) (xy 352.746798 -63.183142) (xy 352.772533 -63.175208) (xy 352.795304 -63.160832)
			(xy 352.813533 -63.14101) (xy 352.825955 -63.117117) (xy 352.83171 -63.09081) (xy 352.8314 -63.077344)
			(xy 352.830892 -63.058548) (xy 352.831378 -63.031297) (xy 352.839134 -62.977349) (xy 352.854489 -62.925054)
			(xy 352.877131 -62.875477) (xy 352.906597 -62.829627) (xy 352.942288 -62.788436) (xy 352.983479 -62.752745)
			(xy 353.029329 -62.723279) (xy 353.078906 -62.700637) (xy 353.131201 -62.685282) (xy 353.185149 -62.677526)
			(xy 353.239651 -62.677526) (xy 353.293599 -62.685282) (xy 353.345894 -62.700637) (xy 353.395471 -62.723279)
			(xy 353.441321 -62.752745) (xy 353.482512 -62.788436) (xy 353.518203 -62.829627) (xy 353.547669 -62.875477)
			(xy 353.570311 -62.925054) (xy 353.585666 -62.977349) (xy 353.593422 -63.031297) (xy 353.593908 -63.058548)
			(xy 353.593401 -63.087149) (xy 353.584869 -63.14371) (xy 353.567988 -63.198364) (xy 353.543137 -63.249885)
			(xy 353.510873 -63.297119) (xy 353.471918 -63.339006) (xy 353.427146 -63.374608) (xy 353.377561 -63.403127)
			(xy 353.324274 -63.423924) (xy 353.296474 -63.430658) (xy 353.283466 -63.434047) (xy 353.259732 -63.44665)
			(xy 353.240106 -63.465005) (xy 353.225944 -63.487843) (xy 353.218226 -63.513583) (xy 353.217487 -63.540445)
			(xy 353.220274 -63.553594) (xy 353.226616 -63.581741) (xy 353.233359 -63.639044) (xy 353.233736 -63.667894)
			(xy 353.233204 -63.700153) (xy 353.224641 -63.764101) (xy 353.209038 -63.82131) (xy 363.201202 -63.82131)
			(xy 363.205273 -63.765688) (xy 363.217399 -63.711251) (xy 363.237322 -63.65916) (xy 363.264618 -63.610525)
			(xy 363.298704 -63.566382) (xy 363.338853 -63.527673) (xy 363.384211 -63.495222) (xy 363.433811 -63.469721)
			(xy 363.486595 -63.451714) (xy 363.541438 -63.441584) (xy 363.597172 -63.439547) (xy 363.652609 -63.445647)
			(xy 363.706566 -63.459753) (xy 363.757895 -63.481565) (xy 363.805501 -63.510619) (xy 363.848369 -63.546294)
			(xy 363.885586 -63.587831) (xy 363.916359 -63.634344) (xy 363.940031 -63.684841) (xy 363.956099 -63.738248)
			(xy 363.964219 -63.793424) (xy 363.964728 -63.82131) (xy 363.964219 -63.849196) (xy 363.956099 -63.904372)
			(xy 363.940031 -63.957779) (xy 363.916359 -64.008276) (xy 363.885586 -64.054789) (xy 363.848369 -64.096326)
			(xy 363.805501 -64.132001) (xy 363.7639 -64.15739) (xy 372.245123 -64.15739) (xy 372.245123 -64.098386)
			(xy 372.253158 -64.039933) (xy 372.269076 -63.983118) (xy 372.292583 -63.929) (xy 372.32324 -63.878587)
			(xy 372.360476 -63.832817) (xy 372.403598 -63.792545) (xy 372.451802 -63.758519) (xy 372.504189 -63.731373)
			(xy 372.559786 -63.711615) (xy 372.617555 -63.69961) (xy 372.67642 -63.695584) (xy 372.735285 -63.69961)
			(xy 372.793054 -63.711615) (xy 372.848651 -63.731373) (xy 372.901038 -63.758519) (xy 372.949242 -63.792545)
			(xy 372.992364 -63.832817) (xy 373.0296 -63.878587) (xy 373.060257 -63.929) (xy 373.083764 -63.983118)
			(xy 373.099682 -64.039933) (xy 373.107717 -64.098386) (xy 373.10822 -64.127888) (xy 373.107717 -64.15739)
			(xy 373.099682 -64.215843) (xy 373.0878 -64.258254) (xy 373.382467 -64.258254) (xy 373.382467 -64.203746)
			(xy 373.390225 -64.149793) (xy 373.405583 -64.097494) (xy 373.428227 -64.047913) (xy 373.457698 -64.002059)
			(xy 373.493395 -63.960867) (xy 373.534591 -63.925174) (xy 373.580448 -63.895708) (xy 373.630032 -63.873069)
			(xy 373.682333 -63.857717) (xy 373.736286 -63.849965) (xy 373.76354 -63.849504) (xy 373.790143 -63.849997)
			(xy 373.842834 -63.85737) (xy 373.893989 -63.871997) (xy 373.942613 -63.893592) (xy 373.987764 -63.921737)
			(xy 374.028565 -63.955885) (xy 374.064222 -63.995373) (xy 374.079516 -64.017144) (xy 374.08785 -64.028624)
			(xy 374.109594 -64.046828) (xy 374.135507 -64.058346) (xy 374.16359 -64.062286) (xy 374.191673 -64.058346)
			(xy 374.217586 -64.046828) (xy 374.23933 -64.028624) (xy 374.247664 -64.017144) (xy 374.262971 -63.995383)
			(xy 374.298635 -63.955903) (xy 374.339437 -63.921759) (xy 374.384584 -63.893612) (xy 374.433204 -63.872009)
			(xy 374.484352 -63.857366) (xy 374.537039 -63.849969) (xy 374.56364 -63.849504) (xy 374.59089 -63.849969)
			(xy 374.644835 -63.85773) (xy 374.697127 -63.873089) (xy 374.746701 -63.895733) (xy 374.792548 -63.925201)
			(xy 374.833734 -63.960894) (xy 374.869423 -64.002085) (xy 374.898886 -64.047934) (xy 374.921525 -64.097511)
			(xy 374.936879 -64.149804) (xy 374.944634 -64.20375) (xy 374.944634 -64.25825) (xy 374.936879 -64.312196)
			(xy 374.921525 -64.364489) (xy 374.898886 -64.414066) (xy 374.869423 -64.459915) (xy 374.833734 -64.501106)
			(xy 374.792548 -64.536799) (xy 374.746701 -64.566267) (xy 374.697127 -64.588911) (xy 374.644835 -64.60427)
			(xy 374.59089 -64.612031) (xy 374.56364 -64.61252) (xy 374.537037 -64.612032) (xy 374.484346 -64.604656)
			(xy 374.433192 -64.590028) (xy 374.384568 -64.568432) (xy 374.339417 -64.540286) (xy 374.298616 -64.506139)
			(xy 374.262958 -64.466651) (xy 374.247664 -64.44488) (xy 374.23933 -64.4334) (xy 374.217586 -64.415196)
			(xy 374.191673 -64.403678) (xy 374.16359 -64.399738) (xy 374.135507 -64.403678) (xy 374.109594 -64.415196)
			(xy 374.08785 -64.4334) (xy 374.079516 -64.44488) (xy 374.064229 -64.466656) (xy 374.028561 -64.506134)
			(xy 373.987756 -64.540276) (xy 373.942604 -64.568421) (xy 373.893982 -64.590022) (xy 373.842831 -64.604662)
			(xy 373.790142 -64.612056) (xy 373.76354 -64.61252) (xy 373.736286 -64.612035) (xy 373.682333 -64.604283)
			(xy 373.630032 -64.588931) (xy 373.580448 -64.566292) (xy 373.534591 -64.536826) (xy 373.493395 -64.501133)
			(xy 373.457698 -64.459941) (xy 373.428227 -64.414087) (xy 373.405583 -64.364506) (xy 373.390225 -64.312207)
			(xy 373.382467 -64.258254) (xy 373.0878 -64.258254) (xy 373.083764 -64.272658) (xy 373.060257 -64.326776)
			(xy 373.0296 -64.377189) (xy 372.992364 -64.422959) (xy 372.949242 -64.463231) (xy 372.901038 -64.497257)
			(xy 372.848651 -64.524403) (xy 372.793054 -64.544161) (xy 372.735285 -64.556166) (xy 372.67642 -64.560193)
			(xy 372.617555 -64.556166) (xy 372.559786 -64.544161) (xy 372.504189 -64.524403) (xy 372.451802 -64.497257)
			(xy 372.403598 -64.463231) (xy 372.360476 -64.422959) (xy 372.32324 -64.377189) (xy 372.292583 -64.326776)
			(xy 372.269076 -64.272658) (xy 372.253158 -64.215843) (xy 372.245123 -64.15739) (xy 363.7639 -64.15739)
			(xy 363.757895 -64.161055) (xy 363.706566 -64.182867) (xy 363.652609 -64.196973) (xy 363.597172 -64.203073)
			(xy 363.541438 -64.201036) (xy 363.486595 -64.190906) (xy 363.433811 -64.172899) (xy 363.384211 -64.147398)
			(xy 363.338853 -64.114947) (xy 363.298704 -64.076238) (xy 363.264618 -64.032095) (xy 363.237322 -63.98346)
			(xy 363.217399 -63.931369) (xy 363.205273 -63.876932) (xy 363.201202 -63.82131) (xy 353.209038 -63.82131)
			(xy 353.207665 -63.826346) (xy 353.182577 -63.885787) (xy 353.149821 -63.941371) (xy 353.109977 -63.992116)
			(xy 353.063749 -64.037123) (xy 353.038156 -64.056768) (xy 353.027014 -64.065619) (xy 353.009726 -64.088206)
			(xy 352.999335 -64.114683) (xy 352.996648 -64.143) (xy 353.001872 -64.170959) (xy 353.014602 -64.196395)
			(xy 353.023932 -64.207136) (xy 353.042851 -64.228399) (xy 353.074817 -64.275487) (xy 353.099421 -64.326807)
			(xy 353.116116 -64.381217) (xy 353.124531 -64.437505) (xy 353.125024 -64.465962) (xy 353.125024 -65.329562)
			(xy 353.124532 -65.357533) (xy 353.116371 -65.412876) (xy 353.108768 -65.439798) (xy 353.105239 -65.452903)
			(xy 353.104478 -65.480024) (xy 353.110888 -65.506387) (xy 353.124016 -65.53013) (xy 353.142935 -65.549577)
			(xy 353.166308 -65.563354) (xy 353.192484 -65.570488) (xy 353.20605 -65.570862) (xy 362.944664 -65.570862)
			(xy 362.963497 -65.55218) (xy 363.004954 -65.519082) (xy 363.050159 -65.491321) (xy 363.098428 -65.469315)
			(xy 363.149032 -65.453397) (xy 363.175042 -65.44818) (xy 363.188391 -65.445285) (xy 363.212981 -65.433419)
			(xy 363.233549 -65.415461) (xy 363.248624 -65.392696) (xy 363.257128 -65.36675) (xy 363.258453 -65.339478)
			(xy 363.252506 -65.312829) (xy 363.246416 -65.300606) (xy 363.232322 -65.27284) (xy 363.212372 -65.213858)
			(xy 363.202289 -65.152415) (xy 363.201712 -65.121282) (xy 363.202198 -65.094031) (xy 363.209954 -65.040083)
			(xy 363.225309 -64.987788) (xy 363.247951 -64.938211) (xy 363.277417 -64.892361) (xy 363.313108 -64.85117)
			(xy 363.354299 -64.815479) (xy 363.400149 -64.786013) (xy 363.449726 -64.763371) (xy 363.502021 -64.748016)
			(xy 363.555969 -64.74026) (xy 363.610471 -64.74026) (xy 363.664419 -64.748016) (xy 363.716714 -64.763371)
			(xy 363.766291 -64.786013) (xy 363.812141 -64.815479) (xy 363.853332 -64.85117) (xy 363.889023 -64.892361)
			(xy 363.918489 -64.938211) (xy 363.941131 -64.987788) (xy 363.956486 -65.040083) (xy 363.964242 -65.094031)
			(xy 363.964728 -65.121282) (xy 363.964318 -65.146862) (xy 363.957484 -65.197562) (xy 363.943935 -65.246895)
			(xy 363.923916 -65.293975) (xy 363.897785 -65.337957) (xy 363.866011 -65.378053) (xy 363.847888 -65.39611)
			(xy 363.837384 -65.406978) (xy 363.822692 -65.433375) (xy 363.816365 -65.462915) (xy 363.818957 -65.493014)
			(xy 363.83024 -65.521038) (xy 363.849227 -65.544535) (xy 363.874258 -65.56145) (xy 363.903141 -65.570303)
			(xy 363.918246 -65.570862) (xy 363.992414 -65.570862) (xy 363.99724 -65.575688) (xy 371.461282 -65.575688)
			(xy 371.465353 -65.520066) (xy 371.477479 -65.465629) (xy 371.497402 -65.413538) (xy 371.524698 -65.364903)
			(xy 371.558784 -65.32076) (xy 371.598933 -65.282051) (xy 371.644291 -65.2496) (xy 371.693891 -65.224099)
			(xy 371.746675 -65.206092) (xy 371.801518 -65.195962) (xy 371.857252 -65.193925) (xy 371.912689 -65.200025)
			(xy 371.966646 -65.214131) (xy 372.017975 -65.235943) (xy 372.065581 -65.264997) (xy 372.108449 -65.300672)
			(xy 372.145666 -65.342209) (xy 372.176439 -65.388722) (xy 372.200111 -65.439219) (xy 372.216179 -65.492626)
			(xy 372.224299 -65.547802) (xy 372.224808 -65.575688) (xy 372.224299 -65.603574) (xy 372.216179 -65.65875)
			(xy 372.200111 -65.712157) (xy 372.182512 -65.7497) (xy 372.597428 -65.7497) (xy 372.601452 -65.690868)
			(xy 372.613449 -65.633132) (xy 372.633197 -65.577567) (xy 372.660326 -65.525208) (xy 372.694331 -65.477031)
			(xy 372.73458 -65.433933) (xy 372.780323 -65.396717) (xy 372.830706 -65.366076) (xy 372.884793 -65.342581)
			(xy 372.941575 -65.326669) (xy 372.999995 -65.318637) (xy 373.02948 -65.318132) (xy 373.060448 -65.318696)
			(xy 373.121749 -65.327548) (xy 373.181154 -65.345073) (xy 373.237443 -65.37091) (xy 373.289461 -65.40453)
			(xy 373.336138 -65.445241) (xy 373.376515 -65.492207) (xy 373.409763 -65.544463) (xy 373.435198 -65.600935)
			(xy 373.444262 -65.630552) (xy 373.448453 -65.64355) (xy 373.462685 -65.666848) (xy 373.482577 -65.685546)
			(xy 373.506709 -65.698311) (xy 373.53336 -65.704232) (xy 373.560627 -65.702886) (xy 373.586565 -65.694369)
			(xy 373.598186 -65.687194) (xy 373.621767 -65.672136) (xy 373.672383 -65.6483) (xy 373.72594 -65.632117)
			(xy 373.781286 -65.623935) (xy 373.80926 -65.62344) (xy 373.836518 -65.623804) (xy 373.89048 -65.631558)
			(xy 373.94279 -65.646912) (xy 373.992381 -65.669555) (xy 374.038245 -65.699026) (xy 374.079448 -65.734724)
			(xy 374.11515 -65.775923) (xy 374.144626 -65.821784) (xy 374.167274 -65.871373) (xy 374.182634 -65.923681)
			(xy 374.190393 -65.977642) (xy 374.190393 -66.032158) (xy 374.182634 -66.086119) (xy 374.169177 -66.131948)
			(xy 376.889262 -66.131948) (xy 376.893333 -66.076326) (xy 376.905459 -66.021889) (xy 376.925382 -65.969798)
			(xy 376.952678 -65.921163) (xy 376.986764 -65.87702) (xy 377.026913 -65.838311) (xy 377.072271 -65.80586)
			(xy 377.121871 -65.780359) (xy 377.174655 -65.762352) (xy 377.229498 -65.752222) (xy 377.285232 -65.750185)
			(xy 377.340669 -65.756285) (xy 377.394626 -65.770391) (xy 377.445955 -65.792203) (xy 377.493561 -65.821257)
			(xy 377.536429 -65.856932) (xy 377.573646 -65.898469) (xy 377.604419 -65.944982) (xy 377.628091 -65.995479)
			(xy 377.644159 -66.048886) (xy 377.652279 -66.104062) (xy 377.652788 -66.131948) (xy 377.652279 -66.159834)
			(xy 377.644159 -66.21501) (xy 377.628091 -66.268417) (xy 377.604419 -66.318914) (xy 377.573646 -66.365427)
			(xy 377.536429 -66.406964) (xy 377.493561 -66.442639) (xy 377.445955 -66.471693) (xy 377.394626 -66.493505)
			(xy 377.340669 -66.507611) (xy 377.285232 -66.513711) (xy 377.229498 -66.511674) (xy 377.174655 -66.501544)
			(xy 377.121871 -66.483537) (xy 377.072271 -66.458036) (xy 377.026913 -66.425585) (xy 376.986764 -66.386876)
			(xy 376.952678 -66.342733) (xy 376.925382 -66.294098) (xy 376.905459 -66.242007) (xy 376.893333 -66.18757)
			(xy 376.889262 -66.131948) (xy 374.169177 -66.131948) (xy 374.167274 -66.138427) (xy 374.144626 -66.188016)
			(xy 374.11515 -66.233877) (xy 374.079448 -66.275076) (xy 374.038245 -66.310774) (xy 373.992381 -66.340245)
			(xy 373.94279 -66.362888) (xy 373.89048 -66.378242) (xy 373.836518 -66.385996) (xy 373.80926 -66.386456)
			(xy 373.780183 -66.385927) (xy 373.722702 -66.37711) (xy 373.667225 -66.35967) (xy 373.615038 -66.334011)
			(xy 373.56735 -66.300729) (xy 373.525266 -66.260595) (xy 373.489761 -66.214538) (xy 373.461658 -66.163626)
			(xy 373.45112 -66.13652) (xy 373.445914 -66.123913) (xy 373.430066 -66.101735) (xy 373.408918 -66.084536)
			(xy 373.383975 -66.073541) (xy 373.357013 -66.069532) (xy 373.32995 -66.072794) (xy 373.304713 -66.083095)
			(xy 373.29364 -66.091054) (xy 373.270867 -66.108089) (xy 373.221707 -66.136684) (xy 373.169214 -66.158565)
			(xy 373.114299 -66.173352) (xy 373.057916 -66.18079) (xy 373.02948 -66.181224) (xy 372.999995 -66.180763)
			(xy 372.941575 -66.172731) (xy 372.884793 -66.156819) (xy 372.830706 -66.133324) (xy 372.780323 -66.102683)
			(xy 372.73458 -66.065467) (xy 372.694331 -66.022369) (xy 372.660326 -65.974192) (xy 372.633197 -65.921833)
			(xy 372.613449 -65.866268) (xy 372.601452 -65.808532) (xy 372.597428 -65.7497) (xy 372.182512 -65.7497)
			(xy 372.176439 -65.762654) (xy 372.145666 -65.809167) (xy 372.108449 -65.850704) (xy 372.065581 -65.886379)
			(xy 372.017975 -65.915433) (xy 371.966646 -65.937245) (xy 371.912689 -65.951351) (xy 371.857252 -65.957451)
			(xy 371.801518 -65.955414) (xy 371.746675 -65.945284) (xy 371.693891 -65.927277) (xy 371.644291 -65.901776)
			(xy 371.598933 -65.869325) (xy 371.558784 -65.830616) (xy 371.524698 -65.786473) (xy 371.497402 -65.737838)
			(xy 371.477479 -65.685747) (xy 371.465353 -65.63131) (xy 371.461282 -65.575688) (xy 363.99724 -65.575688)
			(xy 365.492792 -67.07124) (xy 371.303802 -67.07124) (xy 371.307873 -67.015618) (xy 371.319999 -66.961181)
			(xy 371.339922 -66.90909) (xy 371.367218 -66.860455) (xy 371.401304 -66.816312) (xy 371.441453 -66.777603)
			(xy 371.486811 -66.745152) (xy 371.536411 -66.719651) (xy 371.589195 -66.701644) (xy 371.644038 -66.691514)
			(xy 371.699772 -66.689477) (xy 371.755209 -66.695577) (xy 371.809166 -66.709683) (xy 371.860495 -66.731495)
			(xy 371.908101 -66.760549) (xy 371.950969 -66.796224) (xy 371.988186 -66.837761) (xy 372.018959 -66.884274)
			(xy 372.042631 -66.934771) (xy 372.054344 -66.973704) (xy 384.112768 -66.973704) (xy 384.116839 -66.918082)
			(xy 384.128965 -66.863645) (xy 384.148888 -66.811554) (xy 384.176184 -66.762919) (xy 384.21027 -66.718776)
			(xy 384.250419 -66.680067) (xy 384.295777 -66.647616) (xy 384.345377 -66.622115) (xy 384.398161 -66.604108)
			(xy 384.453004 -66.593978) (xy 384.508738 -66.591941) (xy 384.564175 -66.598041) (xy 384.618132 -66.612147)
			(xy 384.669461 -66.633959) (xy 384.717067 -66.663013) (xy 384.759935 -66.698688) (xy 384.797152 -66.740225)
			(xy 384.827925 -66.786738) (xy 384.851597 -66.837235) (xy 384.867665 -66.890642) (xy 384.875785 -66.945818)
			(xy 384.876294 -66.973704) (xy 384.875785 -67.00159) (xy 384.867665 -67.056766) (xy 384.851597 -67.110173)
			(xy 384.827925 -67.16067) (xy 384.797152 -67.207183) (xy 384.759935 -67.24872) (xy 384.717067 -67.284395)
			(xy 384.669461 -67.313449) (xy 384.618132 -67.335261) (xy 384.564175 -67.349367) (xy 384.508738 -67.355467)
			(xy 384.453004 -67.35343) (xy 384.398161 -67.3433) (xy 384.345377 -67.325293) (xy 384.295777 -67.299792)
			(xy 384.250419 -67.267341) (xy 384.21027 -67.228632) (xy 384.176184 -67.184489) (xy 384.148888 -67.135854)
			(xy 384.128965 -67.083763) (xy 384.116839 -67.029326) (xy 384.112768 -66.973704) (xy 372.054344 -66.973704)
			(xy 372.058699 -66.988178) (xy 372.066819 -67.043354) (xy 372.067328 -67.07124) (xy 372.066819 -67.099126)
			(xy 372.058699 -67.154302) (xy 372.042631 -67.207709) (xy 372.018959 -67.258206) (xy 371.988186 -67.304719)
			(xy 371.950969 -67.346256) (xy 371.908101 -67.381931) (xy 371.860495 -67.410985) (xy 371.809166 -67.432797)
			(xy 371.755209 -67.446903) (xy 371.699772 -67.453003) (xy 371.644038 -67.450966) (xy 371.589195 -67.440836)
			(xy 371.536411 -67.422829) (xy 371.486811 -67.397328) (xy 371.441453 -67.364877) (xy 371.401304 -67.326168)
			(xy 371.367218 -67.282025) (xy 371.339922 -67.23339) (xy 371.319999 -67.181299) (xy 371.307873 -67.126862)
			(xy 371.303802 -67.07124) (xy 365.492792 -67.07124) (xy 365.9759 -67.554348) (xy 373.968262 -67.554348)
			(xy 373.972333 -67.498726) (xy 373.984459 -67.444289) (xy 374.004382 -67.392198) (xy 374.031678 -67.343563)
			(xy 374.065764 -67.29942) (xy 374.105913 -67.260711) (xy 374.151271 -67.22826) (xy 374.200871 -67.202759)
			(xy 374.253655 -67.184752) (xy 374.308498 -67.174622) (xy 374.364232 -67.172585) (xy 374.419669 -67.178685)
			(xy 374.473626 -67.192791) (xy 374.524955 -67.214603) (xy 374.572561 -67.243657) (xy 374.615429 -67.279332)
			(xy 374.652646 -67.320869) (xy 374.683419 -67.367382) (xy 374.707091 -67.417879) (xy 374.723159 -67.471286)
			(xy 374.731279 -67.526462) (xy 374.731788 -67.554348) (xy 374.731279 -67.582234) (xy 374.723159 -67.63741)
			(xy 374.707091 -67.690817) (xy 374.683419 -67.741314) (xy 374.652646 -67.787827) (xy 374.615429 -67.829364)
			(xy 374.572561 -67.865039) (xy 374.524955 -67.894093) (xy 374.473626 -67.915905) (xy 374.419669 -67.930011)
			(xy 374.364232 -67.936111) (xy 374.308498 -67.934074) (xy 374.253655 -67.923944) (xy 374.200871 -67.905937)
			(xy 374.151271 -67.880436) (xy 374.105913 -67.847985) (xy 374.065764 -67.809276) (xy 374.031678 -67.765133)
			(xy 374.004382 -67.716498) (xy 373.984459 -67.664407) (xy 373.972333 -67.60997) (xy 373.968262 -67.554348)
			(xy 365.9759 -67.554348) (xy 367.033302 -68.61175) (xy 387.306566 -68.61175) (xy 388.1755 -67.742816)
			(xy 388.1755 -65.812162) (xy 387.901688 -65.538604) (xy 382.02108 -65.538604) (xy 381.992106 -65.538047)
			(xy 381.934876 -65.528943) (xy 381.879777 -65.510994) (xy 381.828166 -65.484642) (xy 381.781316 -65.450537)
			(xy 381.760476 -65.4304) (xy 380.529592 -64.199516) (xy 380.511319 -64.1806) (xy 380.479769 -64.138522)
			(xy 380.45451 -64.092392) (xy 380.436055 -64.043144) (xy 380.424776 -63.991775) (xy 380.422404 -63.965582)
			(xy 380.421134 -63.946786) (xy 380.018036 -63.543688) (xy 380.018036 -59.826906) (xy 379.873256 -59.682126)
			(xy 375.720102 -59.682126) (xy 375.70597 -59.682574) (xy 375.678785 -59.690302) (xy 375.654765 -59.705194)
			(xy 375.635753 -59.726106) (xy 375.62321 -59.751433) (xy 375.618098 -59.779229) (xy 375.620811 -59.807361)
			(xy 375.631139 -59.833669) (xy 375.63933 -59.845194) (xy 375.657679 -59.870298) (xy 375.686831 -59.925217)
			(xy 375.706689 -59.984138) (xy 375.716728 -60.045499) (xy 375.717308 -60.076588) (xy 375.716822 -60.103839)
			(xy 375.709066 -60.157787) (xy 375.693711 -60.210082) (xy 375.671069 -60.259659) (xy 375.641603 -60.305509)
			(xy 375.605912 -60.3467) (xy 375.564721 -60.382391) (xy 375.518871 -60.411857) (xy 375.469294 -60.434499)
			(xy 375.416999 -60.449854) (xy 375.363051 -60.45761) (xy 375.308549 -60.45761) (xy 375.254601 -60.449854)
			(xy 375.202306 -60.434499) (xy 375.152729 -60.411857) (xy 375.106879 -60.382391) (xy 375.065688 -60.3467)
			(xy 375.029997 -60.305509) (xy 375.000531 -60.259659) (xy 374.977889 -60.210082) (xy 374.962534 -60.157787)
			(xy 374.954778 -60.103839) (xy 374.954292 -60.076588) (xy 374.954881 -60.045499) (xy 374.964915 -59.984136)
			(xy 374.984764 -59.925211) (xy 375.013903 -59.870284) (xy 375.03227 -59.845194) (xy 375.040453 -59.833674)
			(xy 375.050737 -59.807367) (xy 375.05342 -59.779248) (xy 375.048298 -59.75147) (xy 375.035762 -59.726158)
			(xy 375.016771 -59.705249) (xy 374.992779 -59.690342) (xy 374.965621 -59.682578) (xy 374.951498 -59.682126)
			(xy 372.29415 -59.682126) (xy 372.279955 -59.682601) (xy 372.252665 -59.690424) (xy 372.228579 -59.705454)
			(xy 372.209558 -59.726529) (xy 372.197068 -59.752024) (xy 372.192075 -59.779972) (xy 372.193058 -59.79414)
			(xy 372.19402 -59.804018) (xy 372.195038 -59.82384) (xy 372.19509 -59.833764) (xy 372.194604 -59.861015)
			(xy 372.186848 -59.914963) (xy 372.171493 -59.967258) (xy 372.148851 -60.016835) (xy 372.119385 -60.062685)
			(xy 372.083694 -60.103876) (xy 372.042503 -60.139567) (xy 371.996653 -60.169033) (xy 371.947076 -60.191675)
			(xy 371.894781 -60.20703) (xy 371.840833 -60.214786) (xy 371.786331 -60.214786) (xy 371.732383 -60.20703)
			(xy 371.680088 -60.191675) (xy 371.630511 -60.169033) (xy 371.584661 -60.139567) (xy 371.54347 -60.103876)
			(xy 371.507779 -60.062685) (xy 371.478313 -60.016835) (xy 371.455671 -59.967258) (xy 371.440316 -59.914963)
			(xy 371.43256 -59.861015) (xy 371.432074 -59.833764) (xy 371.432134 -59.82384) (xy 371.433152 -59.804018)
			(xy 371.434106 -59.79414) (xy 371.435098 -59.779969) (xy 371.430123 -59.752014) (xy 371.417639 -59.72651)
			(xy 371.398612 -59.705433) (xy 371.374515 -59.690414) (xy 371.347212 -59.682614) (xy 371.333014 -59.682126)
			(xy 368.293904 -59.682126) (xy 368.26964 -59.6986) (xy 368.217118 -59.724693) (xy 368.161219 -59.742434)
			(xy 368.103263 -59.751406) (xy 368.07394 -59.751976) (xy 368.060368 -59.751863) (xy 368.033292 -59.749953)
			(xy 368.019838 -59.748166) (xy 368.005328 -59.746547) (xy 367.976441 -59.750708) (xy 367.94991 -59.762867)
			(xy 367.9279 -59.782033) (xy 367.912207 -59.80664) (xy 367.904113 -59.83468) (xy 367.904279 -59.863864)
			(xy 367.908078 -59.87796) (xy 367.916737 -59.908474) (xy 367.926039 -59.971215) (xy 367.92662 -60.002928)
			(xy 367.926156 -60.031199) (xy 367.918773 -60.087256) (xy 367.904136 -60.14187) (xy 367.882497 -60.194107)
			(xy 367.854225 -60.243072) (xy 367.819804 -60.287929) (xy 367.779823 -60.327909) (xy 367.734966 -60.362329)
			(xy 367.685999 -60.390601) (xy 367.633762 -60.412239) (xy 367.579148 -60.426875) (xy 367.523091 -60.434257)
			(xy 367.49482 -60.434728) (xy 367.476242 -60.434481) (xy 367.439233 -60.431177) (xy 367.420906 -60.428124)
			(xy 367.405921 -60.426108) (xy 367.375941 -60.429922) (xy 367.348384 -60.442326) (xy 367.325652 -60.462241)
			(xy 367.309729 -60.487927) (xy 367.302005 -60.517144) (xy 367.302034 -60.532264) (xy 367.302288 -60.546488)
			(xy 367.301803 -60.573738) (xy 367.294048 -60.627683) (xy 367.278696 -60.679975) (xy 367.256058 -60.72955)
			(xy 367.226595 -60.775399) (xy 367.190907 -60.816588) (xy 367.14972 -60.852279) (xy 367.103873 -60.881745)
			(xy 367.0543 -60.904386) (xy 367.002009 -60.919743) (xy 366.948064 -60.927501) (xy 366.893565 -60.927503)
			(xy 366.83962 -60.919749) (xy 366.787328 -60.904397) (xy 366.737753 -60.881759) (xy 366.691904 -60.852296)
			(xy 366.650714 -60.816608) (xy 366.615023 -60.775422) (xy 366.585556 -60.729576) (xy 366.562914 -60.680002)
			(xy 366.547558 -60.627711) (xy 366.539799 -60.573767) (xy 366.539797 -60.519268) (xy 366.547551 -60.465323)
			(xy 366.562902 -60.41303) (xy 366.58554 -60.363455) (xy 366.615002 -60.317606) (xy 366.65069 -60.276416)
			(xy 366.691876 -60.240725) (xy 366.737722 -60.211258) (xy 366.787295 -60.188615) (xy 366.839586 -60.173259)
			(xy 366.89353 -60.1655) (xy 366.92078 -60.16498) (xy 366.955832 -60.166504) (xy 366.970917 -60.16735)
			(xy 367.000484 -60.161221) (xy 367.026967 -60.146711) (xy 367.048047 -60.12509) (xy 367.061882 -60.09825)
			(xy 367.067262 -60.068536) (xy 367.066068 -60.053474) (xy 367.064651 -60.040885) (xy 367.063124 -60.015596)
			(xy 367.06302 -60.002928) (xy 367.063563 -59.972413) (xy 367.072201 -59.911996) (xy 367.08928 -59.853404)
			(xy 367.101374 -59.825382) (xy 367.106854 -59.811951) (xy 367.110838 -59.783232) (xy 367.106591 -59.754551)
			(xy 367.094456 -59.728218) (xy 367.075411 -59.706357) (xy 367.05099 -59.690727) (xy 367.023161 -59.68259)
			(xy 367.008664 -59.682126) (xy 365.412528 -59.682126) (xy 365.161576 -59.932824) (xy 365.140725 -59.952948)
			(xy 365.093875 -59.987047) (xy 365.042266 -60.013396) (xy 364.98717 -60.031346) (xy 364.929945 -60.040454)
			(xy 364.900972 -60.041028) (xy 364.052866 -60.041028) (xy 364.037891 -60.04155) (xy 364.009226 -60.050226)
			(xy 363.984314 -60.06685) (xy 363.965302 -60.08999) (xy 363.953826 -60.117654) (xy 363.950875 -60.147457)
			(xy 363.956704 -60.176834) (xy 363.97081 -60.203253) (xy 363.980984 -60.214256) (xy 364.001716 -60.235864)
			(xy 364.036867 -60.28434) (xy 364.064017 -60.337711) (xy 364.082498 -60.394667) (xy 364.091857 -60.45381)
			(xy 364.09249 -60.48375) (xy 364.092004 -60.511001) (xy 364.084248 -60.564949) (xy 364.068893 -60.617244)
			(xy 364.046251 -60.666821) (xy 364.016785 -60.712671) (xy 363.981094 -60.753862) (xy 363.939903 -60.789553)
			(xy 363.894053 -60.819019) (xy 363.844476 -60.841661) (xy 363.792181 -60.857016) (xy 363.738233 -60.864772)
			(xy 363.683731 -60.864772) (xy 363.629783 -60.857016) (xy 363.577488 -60.841661) (xy 363.527911 -60.819019)
			(xy 363.482061 -60.789553) (xy 363.44087 -60.753862) (xy 363.405179 -60.712671) (xy 363.375713 -60.666821)
			(xy 363.353071 -60.617244) (xy 363.337716 -60.564949) (xy 363.32996 -60.511001) (xy 363.329474 -60.48375)
			(xy 363.330056 -60.453807) (xy 363.33941 -60.394655) (xy 363.357896 -60.337693) (xy 363.385058 -60.284321)
			(xy 363.42023 -60.235852) (xy 363.44098 -60.214256) (xy 363.451164 -60.203276) (xy 363.465226 -60.176851)
			(xy 363.471023 -60.147484) (xy 363.468058 -60.117698) (xy 363.456585 -60.090051) (xy 363.43759 -60.066917)
			(xy 363.412704 -60.050283) (xy 363.384064 -60.041577) (xy 363.369098 -60.041028) (xy 358.657652 -60.041028)
			(xy 358.628678 -60.040469) (xy 358.571451 -60.031362) (xy 358.516354 -60.01341) (xy 358.464745 -59.987057)
			(xy 358.417896 -59.952952) (xy 358.397048 -59.932824) (xy 355.829108 -57.365138) (xy 355.30409 -57.365138)
			(xy 349.897954 -51.959002) (xy 349.897954 -51.958748) (xy 347.62948 -49.690274) (xy 345.468956 -49.690274)
			(xy 345.455748 -49.721008) (xy 345.445178 -49.744474) (xy 345.417852 -49.788086) (xy 345.3841 -49.826937)
			(xy 345.344737 -49.86009) (xy 345.300712 -49.886745) (xy 345.25309 -49.906258) (xy 345.203019 -49.918157)
			(xy 345.15171 -49.922156) (xy 345.100401 -49.918157) (xy 345.05033 -49.906258) (xy 345.002708 -49.886745)
			(xy 344.958683 -49.86009) (xy 344.91932 -49.826937) (xy 344.885568 -49.788086) (xy 344.858242 -49.744474)
			(xy 344.847672 -49.721008) (xy 344.834464 -49.690274) (xy 344.792808 -49.690274) (xy 344.778135 -49.690758)
			(xy 344.749999 -49.699094) (xy 344.725391 -49.715083) (xy 344.706342 -49.737404) (xy 344.69442 -49.764219)
			(xy 344.69061 -49.793316) (xy 344.692478 -49.807876) (xy 344.694378 -49.820746) (xy 344.696412 -49.846683)
			(xy 344.696542 -49.859692) (xy 344.696032 -49.885679) (xy 344.687902 -49.937014) (xy 344.671841 -49.986444)
			(xy 344.648245 -50.032754) (xy 344.617695 -50.074802) (xy 344.580944 -50.111553) (xy 344.538896 -50.142103)
			(xy 344.492586 -50.165699) (xy 344.443156 -50.18176) (xy 344.391821 -50.18989) (xy 344.339847 -50.18989)
			(xy 344.288512 -50.18176) (xy 344.239082 -50.165699) (xy 344.192772 -50.142103) (xy 344.150724 -50.111553)
			(xy 344.113973 -50.074802) (xy 344.083423 -50.032754) (xy 344.059827 -49.986444) (xy 344.043766 -49.937014)
			(xy 344.035636 -49.885679) (xy 344.035126 -49.859692) (xy 344.035563 -49.835576) (xy 344.042565 -49.787854)
			(xy 344.05642 -49.741653) (xy 344.076834 -49.697954) (xy 344.089736 -49.677574) (xy 344.112596 -49.642776)
			(xy 343.999312 -49.529492) (xy 343.989535 -49.52029) (xy 343.966269 -49.506908) (xy 343.940321 -49.500046)
			(xy 343.913482 -49.500178) (xy 343.887602 -49.507295) (xy 343.86447 -49.520906) (xy 343.845679 -49.540071)
			(xy 343.838784 -49.55159) (xy 343.826145 -49.573206) (xy 343.795363 -49.612699) (xy 343.758975 -49.647095)
			(xy 343.717813 -49.675607) (xy 343.672821 -49.697583) (xy 343.625029 -49.712518) (xy 343.57553 -49.720072)
			(xy 343.550494 -49.7205) (xy 343.524505 -49.720016) (xy 343.473168 -49.711884) (xy 343.423735 -49.695822)
			(xy 343.377423 -49.672223) (xy 343.335373 -49.641671) (xy 343.29862 -49.604916) (xy 343.268069 -49.562865)
			(xy 343.244473 -49.516552) (xy 343.228412 -49.467118) (xy 343.220282 -49.415781) (xy 343.219786 -49.389792)
			(xy 343.220248 -49.364758) (xy 343.227801 -49.315262) (xy 343.242734 -49.267471) (xy 343.264704 -49.22248)
			(xy 343.293208 -49.181317) (xy 343.327595 -49.144925) (xy 343.367078 -49.114135) (xy 343.388696 -49.101502)
			(xy 343.40019 -49.094575) (xy 343.419347 -49.075794) (xy 343.432951 -49.052671) (xy 343.440064 -49.026803)
			(xy 343.440193 -48.999976) (xy 343.433331 -48.97404) (xy 343.419951 -48.950787) (xy 343.410794 -48.940974)
			(xy 342.778334 -48.308514) (xy 342.755474 -48.310038) (xy 342.73363 -48.3108) (xy 342.707639 -48.310319)
			(xy 342.656298 -48.302192) (xy 342.60686 -48.286132) (xy 342.560543 -48.262536) (xy 342.518488 -48.231984)
			(xy 342.481731 -48.195229) (xy 342.451176 -48.153176) (xy 342.427577 -48.106861) (xy 342.411514 -48.057424)
			(xy 342.403383 -48.006083) (xy 342.402922 -47.980092) (xy 342.402988 -47.97029) (xy 342.404132 -47.950719)
			(xy 342.405208 -47.940976) (xy 342.366198 -47.926201) (xy 342.290653 -47.890807) (xy 342.218463 -47.848996)
			(xy 342.15017 -47.801082) (xy 342.117934 -47.774606) (xy 342.096275 -47.790267) (xy 342.048964 -47.81513)
			(xy 341.998274 -47.832073) (xy 341.945521 -47.840655) (xy 341.918798 -47.841154) (xy 341.89281 -47.840644)
			(xy 341.841473 -47.832514) (xy 341.792039 -47.816453) (xy 341.745727 -47.792858) (xy 341.703675 -47.762309)
			(xy 341.66692 -47.725558) (xy 341.636365 -47.683511) (xy 341.612764 -47.637201) (xy 341.596696 -47.58777)
			(xy 341.588559 -47.536434) (xy 341.58809 -47.510446) (xy 341.588555 -47.485088) (xy 341.596306 -47.434968)
			(xy 341.611617 -47.386619) (xy 341.634131 -47.341174) (xy 341.663319 -47.299699) (xy 341.680546 -47.281084)
			(xy 341.71509 -47.24527) (xy 341.584788 -47.114968) (xy 341.574102 -47.10495) (xy 341.548389 -47.090946)
			(xy 341.519763 -47.084796) (xy 341.490567 -47.087003) (xy 341.463191 -47.097386) (xy 341.439875 -47.115097)
			(xy 341.422528 -47.138684) (xy 341.417148 -47.152306) (xy 341.408162 -47.176017) (xy 341.383966 -47.220576)
			(xy 341.353245 -47.260914) (xy 341.316721 -47.296083) (xy 341.275251 -47.325258) (xy 341.229809 -47.347752)
			(xy 341.181464 -47.363038) (xy 341.13135 -47.370756) (xy 341.105998 -47.371254) (xy 341.08001 -47.370744)
			(xy 341.028673 -47.362614) (xy 340.979239 -47.346553) (xy 340.932927 -47.322958) (xy 340.890875 -47.292409)
			(xy 340.85412 -47.255658) (xy 340.823565 -47.213611) (xy 340.799964 -47.167301) (xy 340.783896 -47.11787)
			(xy 340.775759 -47.066534) (xy 340.77529 -47.040546) (xy 340.775755 -47.015196) (xy 340.783503 -46.965091)
			(xy 340.79881 -46.916757) (xy 340.821317 -46.871326) (xy 340.850496 -46.829864) (xy 340.885662 -46.793342)
			(xy 340.925992 -46.762618) (xy 340.97054 -46.73841) (xy 340.994238 -46.729396) (xy 341.00789 -46.724019)
			(xy 341.03158 -46.706729) (xy 341.049374 -46.683416) (xy 341.059803 -46.656004) (xy 341.062005 -46.626758)
			(xy 341.055797 -46.598094) (xy 341.041694 -46.572379) (xy 341.031576 -46.561756) (xy 340.79434 -46.32452)
			(xy 340.79434 -46.211744) (xy 340.7918 -46.20387) (xy 340.7841 -46.178787) (xy 340.77581 -46.126979)
			(xy 340.77529 -46.100746) (xy 340.775793 -46.074512) (xy 340.78409 -46.022703) (xy 340.7918 -45.997622)
			(xy 340.79434 -45.989748) (xy 340.79434 -45.271944) (xy 340.7918 -45.26407) (xy 340.7841 -45.238987)
			(xy 340.77581 -45.187179) (xy 340.77529 -45.160946) (xy 340.775793 -45.134712) (xy 340.78409 -45.082903)
			(xy 340.7918 -45.057822) (xy 340.79434 -45.049948) (xy 340.79434 -43.414188) (xy 340.79053 -43.405044)
			(xy 340.779359 -43.37535) (xy 340.767338 -43.313064) (xy 340.766654 -43.281346) (xy 340.766908 -43.26763)
			(xy 340.767924 -43.245532) (xy 340.547452 -43.02506) (xy 340.511638 -43.057318) (xy 340.493351 -43.073204)
			(xy 340.453 -43.100003) (xy 340.409169 -43.120624) (xy 340.362797 -43.134624) (xy 340.314878 -43.141705)
			(xy 340.290658 -43.142154) (xy 340.264683 -43.14165) (xy 340.213371 -43.133537) (xy 340.163958 -43.117502)
			(xy 340.11766 -43.093939) (xy 340.075614 -43.063428) (xy 340.038856 -43.026718) (xy 340.008289 -42.984713)
			(xy 339.996018 -42.961814) (xy 339.982048 -42.934128) (xy 339.518498 -42.934128) (xy 339.504528 -42.961814)
			(xy 339.492254 -42.984711) (xy 339.461675 -43.026707) (xy 339.424912 -43.063412) (xy 339.382869 -43.093925)
			(xy 339.336576 -43.117499) (xy 339.28717 -43.133553) (xy 339.235862 -43.141695) (xy 339.209888 -43.142154)
			(xy 339.1839 -43.141644) (xy 339.132564 -43.133512) (xy 339.083132 -43.11745) (xy 339.036821 -43.093855)
			(xy 338.994771 -43.063305) (xy 338.958017 -43.026555) (xy 338.927463 -42.984508) (xy 338.903863 -42.938199)
			(xy 338.887796 -42.888769) (xy 338.879659 -42.837434) (xy 338.87918 -42.811446) (xy 338.879434 -42.796206)
			(xy 338.879623 -42.782495) (xy 338.873564 -42.755764) (xy 338.860614 -42.731608) (xy 338.841705 -42.711765)
			(xy 338.8182 -42.697667) (xy 338.791792 -42.690328) (xy 338.778088 -42.68978) (xy 338.013548 -42.68978)
			(xy 337.999828 -42.690224) (xy 337.97338 -42.697534) (xy 337.949841 -42.711635) (xy 337.930918 -42.731507)
			(xy 337.917984 -42.755707) (xy 337.911977 -42.782481) (xy 337.912202 -42.796206) (xy 337.912456 -42.811446)
			(xy 337.911946 -42.837433) (xy 337.903816 -42.888768) (xy 337.887755 -42.938198) (xy 337.864159 -42.984508)
			(xy 337.833609 -43.026556) (xy 337.796858 -43.063307) (xy 337.75481 -43.093857) (xy 337.7085 -43.117453)
			(xy 337.65907 -43.133514) (xy 337.607735 -43.141644) (xy 337.555761 -43.141644) (xy 337.504426 -43.133514)
			(xy 337.454996 -43.117453) (xy 337.408686 -43.093857) (xy 337.366638 -43.063307) (xy 337.329887 -43.026556)
			(xy 337.299337 -42.984508) (xy 337.275741 -42.938198) (xy 337.25968 -42.888768) (xy 337.25155 -42.837433)
			(xy 337.25104 -42.811446) (xy 337.251294 -42.796206) (xy 337.251483 -42.782493) (xy 337.245425 -42.755756)
			(xy 337.232476 -42.731592) (xy 337.213569 -42.71174) (xy 337.190064 -42.69763) (xy 337.163654 -42.690276)
			(xy 337.149948 -42.68978) (xy 334.757268 -42.68978) (xy 334.743546 -42.690222) (xy 334.717093 -42.697528)
			(xy 334.69355 -42.711628) (xy 334.674623 -42.7315) (xy 334.661686 -42.755703) (xy 334.655677 -42.78248)
			(xy 334.655922 -42.796206) (xy 334.656176 -42.811446) (xy 334.655666 -42.837433) (xy 334.647536 -42.888768)
			(xy 334.631475 -42.938198) (xy 334.607879 -42.984508) (xy 334.577329 -43.026556) (xy 334.540578 -43.063307)
			(xy 334.49853 -43.093857) (xy 334.45222 -43.117453) (xy 334.40279 -43.133514) (xy 334.351455 -43.141644)
			(xy 334.299481 -43.141644) (xy 334.248146 -43.133514) (xy 334.198716 -43.117453) (xy 334.152406 -43.093857)
			(xy 334.110358 -43.063307) (xy 334.073607 -43.026556) (xy 334.043057 -42.984508) (xy 334.019461 -42.938198)
			(xy 334.0034 -42.888768) (xy 333.99527 -42.837433) (xy 333.99476 -42.811446) (xy 333.995014 -42.796206)
			(xy 333.995203 -42.782492) (xy 333.989145 -42.755753) (xy 333.976197 -42.731586) (xy 333.95729 -42.711731)
			(xy 333.933786 -42.697617) (xy 333.907375 -42.690259) (xy 333.893668 -42.68978) (xy 333.129128 -42.68978)
			(xy 333.115401 -42.690214) (xy 333.088934 -42.69751) (xy 333.065376 -42.711607) (xy 333.046437 -42.731481)
			(xy 333.03349 -42.755691) (xy 333.027477 -42.782478) (xy 333.027782 -42.796206) (xy 333.028036 -42.811446)
			(xy 333.027526 -42.837433) (xy 333.019396 -42.888768) (xy 333.003335 -42.938198) (xy 332.979739 -42.984508)
			(xy 332.949189 -43.026556) (xy 332.912438 -43.063307) (xy 332.87039 -43.093857) (xy 332.82408 -43.117453)
			(xy 332.77465 -43.133514) (xy 332.723315 -43.141644) (xy 332.671341 -43.141644) (xy 332.620006 -43.133514)
			(xy 332.570576 -43.117453) (xy 332.524266 -43.093857) (xy 332.482218 -43.063307) (xy 332.445467 -43.026556)
			(xy 332.414917 -42.984508) (xy 332.391321 -42.938198) (xy 332.37526 -42.888768) (xy 332.36713 -42.837433)
			(xy 332.36662 -42.811446) (xy 332.366874 -42.796206) (xy 332.367063 -42.782494) (xy 332.361005 -42.755759)
			(xy 332.348056 -42.731597) (xy 332.329148 -42.711748) (xy 332.305643 -42.697642) (xy 332.279233 -42.690294)
			(xy 332.265528 -42.68978) (xy 331.499718 -42.68978) (xy 331.485992 -42.690216) (xy 331.459527 -42.697513)
			(xy 331.435972 -42.711611) (xy 331.417034 -42.731485) (xy 331.40409 -42.755693) (xy 331.398077 -42.782478)
			(xy 331.398372 -42.796206) (xy 331.398626 -42.811446) (xy 331.398116 -42.837433) (xy 331.389986 -42.888768)
			(xy 331.373925 -42.938198) (xy 331.350329 -42.984508) (xy 331.319779 -43.026556) (xy 331.283028 -43.063307)
			(xy 331.24098 -43.093857) (xy 331.19467 -43.117453) (xy 331.14524 -43.133514) (xy 331.093905 -43.141644)
			(xy 331.041931 -43.141644) (xy 330.990596 -43.133514) (xy 330.941166 -43.117453) (xy 330.894856 -43.093857)
			(xy 330.852808 -43.063307) (xy 330.816057 -43.026556) (xy 330.785507 -42.984508) (xy 330.761911 -42.938198)
			(xy 330.74585 -42.888768) (xy 330.73772 -42.837433) (xy 330.73721 -42.811446) (xy 330.737464 -42.796206)
			(xy 330.737653 -42.782494) (xy 330.731595 -42.75576) (xy 330.718645 -42.7316) (xy 330.699737 -42.711753)
			(xy 330.676232 -42.697648) (xy 330.649823 -42.690302) (xy 330.636118 -42.68978) (xy 329.872848 -42.68978)
			(xy 329.859128 -42.690224) (xy 329.83268 -42.697534) (xy 329.809141 -42.711635) (xy 329.790218 -42.731507)
			(xy 329.777284 -42.755707) (xy 329.771277 -42.782481) (xy 329.771502 -42.796206) (xy 329.771756 -42.811446)
			(xy 329.771246 -42.837433) (xy 329.763116 -42.888768) (xy 329.747055 -42.938198) (xy 329.723459 -42.984508)
			(xy 329.692909 -43.026556) (xy 329.656158 -43.063307) (xy 329.61411 -43.093857) (xy 329.5678 -43.117453)
			(xy 329.51837 -43.133514) (xy 329.467035 -43.141644) (xy 329.415061 -43.141644) (xy 329.363726 -43.133514)
			(xy 329.314296 -43.117453) (xy 329.267986 -43.093857) (xy 329.225938 -43.063307) (xy 329.189187 -43.026556)
			(xy 329.158637 -42.984508) (xy 329.135041 -42.938198) (xy 329.11898 -42.888768) (xy 329.11085 -42.837433)
			(xy 329.11034 -42.811446) (xy 329.110594 -42.796206) (xy 329.110783 -42.782493) (xy 329.104725 -42.755756)
			(xy 329.091776 -42.731592) (xy 329.072869 -42.71174) (xy 329.049364 -42.69763) (xy 329.022954 -42.690276)
			(xy 329.009248 -42.68978) (xy 316.355222 -42.68978) (xy 316.343652 -42.714761) (xy 316.314384 -42.76139)
			(xy 316.278713 -42.803322) (xy 316.237379 -42.839687) (xy 316.191244 -42.869726) (xy 316.141268 -42.892816)
			(xy 316.088489 -42.908475) (xy 316.034007 -42.916378) (xy 316.00648 -42.916856) (xy 315.977787 -42.91633)
			(xy 315.921049 -42.90772) (xy 315.86624 -42.890713) (xy 315.814595 -42.865691) (xy 315.767278 -42.833219)
			(xy 315.725357 -42.794029) (xy 315.689775 -42.749004) (xy 315.661336 -42.69916) (xy 315.640679 -42.645619)
			(xy 315.628272 -42.589589) (xy 315.625734 -42.561002) (xy 315.624464 -42.541952) (xy 315.421772 -42.33926)
			(xy 315.415676 -42.335958) (xy 315.392427 -42.3226) (xy 315.349582 -42.290362) (xy 315.311673 -42.252444)
			(xy 315.279447 -42.20959) (xy 315.26607 -42.186352) (xy 315.262768 -42.180256) (xy 312.549794 -39.467282)
			(xy 311.80659 -39.467282) (xy 311.792365 -39.467798) (xy 311.765041 -39.47573) (xy 311.740964 -39.490892)
			(xy 311.722004 -39.512107) (xy 311.709632 -39.537728) (xy 311.704807 -39.565769) (xy 311.707904 -39.594052)
			(xy 311.718683 -39.620384) (xy 311.727088 -39.631874) (xy 311.742558 -39.652165) (xy 311.768549 -39.696073)
			(xy 311.788456 -39.743053) (xy 311.801927 -39.792266) (xy 311.808719 -39.842836) (xy 311.80913 -39.868348)
			(xy 311.808644 -39.895599) (xy 311.800888 -39.949547) (xy 311.785533 -40.001842) (xy 311.762891 -40.051419)
			(xy 311.733425 -40.097269) (xy 311.697734 -40.13846) (xy 311.656543 -40.174151) (xy 311.610693 -40.203617)
			(xy 311.561116 -40.226259) (xy 311.508821 -40.241614) (xy 311.454873 -40.24937) (xy 311.400371 -40.24937)
			(xy 311.346423 -40.241614) (xy 311.294128 -40.226259) (xy 311.244551 -40.203617) (xy 311.198701 -40.174151)
			(xy 311.15751 -40.13846) (xy 311.121819 -40.097269) (xy 311.092353 -40.051419) (xy 311.069711 -40.001842)
			(xy 311.054356 -39.949547) (xy 311.0466 -39.895599) (xy 311.046114 -39.868348) (xy 311.046542 -39.842838)
			(xy 311.053343 -39.792272) (xy 311.066815 -39.743063) (xy 311.086721 -39.696086) (xy 311.112704 -39.652177)
			(xy 311.128156 -39.631874) (xy 311.136604 -39.62041) (xy 311.147393 -39.59407) (xy 311.150495 -39.565775)
			(xy 311.145669 -39.537723) (xy 311.133288 -39.512092) (xy 311.114316 -39.490872) (xy 311.090224 -39.475712)
			(xy 311.062885 -39.467789) (xy 311.048654 -39.467282) (xy 310.787034 -39.467282) (xy 310.766192 -39.484495)
			(xy 310.720572 -39.513489) (xy 310.671319 -39.535757) (xy 310.619416 -39.550855) (xy 310.565903 -39.55848)
			(xy 310.511849 -39.55848) (xy 310.458336 -39.550855) (xy 310.406433 -39.535757) (xy 310.35718 -39.513489)
			(xy 310.31156 -39.484495) (xy 310.290718 -39.467282) (xy 308.585362 -39.467282) (xy 308.577742 -39.469822)
			(xy 308.549404 -39.478265) (xy 308.490974 -39.487318) (xy 308.46141 -39.487856) (xy 308.431844 -39.487343)
			(xy 308.373411 -39.478288) (xy 308.345078 -39.469822) (xy 308.337458 -39.467282) (xy 292.843712 -39.467282)
			(xy 292.188646 -40.122348) (xy 299.698662 -40.122348) (xy 299.702733 -40.066726) (xy 299.714859 -40.012289)
			(xy 299.734782 -39.960198) (xy 299.762078 -39.911563) (xy 299.796164 -39.86742) (xy 299.836313 -39.828711)
			(xy 299.881671 -39.79626) (xy 299.931271 -39.770759) (xy 299.984055 -39.752752) (xy 300.038898 -39.742622)
			(xy 300.094632 -39.740585) (xy 300.150069 -39.746685) (xy 300.204026 -39.760791) (xy 300.255355 -39.782603)
			(xy 300.302961 -39.811657) (xy 300.345829 -39.847332) (xy 300.383046 -39.888869) (xy 300.413819 -39.935382)
			(xy 300.437491 -39.985879) (xy 300.453559 -40.039286) (xy 300.461679 -40.094462) (xy 300.462188 -40.122348)
			(xy 300.461679 -40.150234) (xy 300.453559 -40.20541) (xy 300.437491 -40.258817) (xy 300.413819 -40.309314)
			(xy 300.383046 -40.355827) (xy 300.366935 -40.373808) (xy 306.110638 -40.373808) (xy 306.114709 -40.318186)
			(xy 306.126835 -40.263749) (xy 306.146758 -40.211658) (xy 306.174054 -40.163023) (xy 306.20814 -40.11888)
			(xy 306.248289 -40.080171) (xy 306.293647 -40.04772) (xy 306.343247 -40.022219) (xy 306.396031 -40.004212)
			(xy 306.450874 -39.994082) (xy 306.506608 -39.992045) (xy 306.536626 -39.995348) (xy 308.109618 -39.995348)
			(xy 308.113689 -39.939726) (xy 308.125815 -39.885289) (xy 308.145738 -39.833198) (xy 308.173034 -39.784563)
			(xy 308.20712 -39.74042) (xy 308.247269 -39.701711) (xy 308.292627 -39.66926) (xy 308.342227 -39.643759)
			(xy 308.395011 -39.625752) (xy 308.449854 -39.615622) (xy 308.505588 -39.613585) (xy 308.561025 -39.619685)
			(xy 308.614982 -39.633791) (xy 308.666311 -39.655603) (xy 308.713917 -39.684657) (xy 308.756785 -39.720332)
			(xy 308.794002 -39.761869) (xy 308.824775 -39.808382) (xy 308.848447 -39.858879) (xy 308.864515 -39.912286)
			(xy 308.872635 -39.967462) (xy 308.873144 -39.995348) (xy 308.872635 -40.023234) (xy 308.864515 -40.07841)
			(xy 308.848447 -40.131817) (xy 308.824775 -40.182314) (xy 308.794002 -40.228827) (xy 308.756785 -40.270364)
			(xy 308.713917 -40.306039) (xy 308.666311 -40.335093) (xy 308.614982 -40.356905) (xy 308.561025 -40.371011)
			(xy 308.505588 -40.377111) (xy 308.449854 -40.375074) (xy 308.395011 -40.364944) (xy 308.342227 -40.346937)
			(xy 308.292627 -40.321436) (xy 308.247269 -40.288985) (xy 308.20712 -40.250276) (xy 308.173034 -40.206133)
			(xy 308.145738 -40.157498) (xy 308.125815 -40.105407) (xy 308.113689 -40.05097) (xy 308.109618 -39.995348)
			(xy 306.536626 -39.995348) (xy 306.562045 -39.998145) (xy 306.616002 -40.012251) (xy 306.667331 -40.034063)
			(xy 306.714937 -40.063117) (xy 306.757805 -40.098792) (xy 306.795022 -40.140329) (xy 306.825795 -40.186842)
			(xy 306.849467 -40.237339) (xy 306.865535 -40.290746) (xy 306.873655 -40.345922) (xy 306.874164 -40.373808)
			(xy 306.873655 -40.401694) (xy 306.865535 -40.45687) (xy 306.849467 -40.510277) (xy 306.825795 -40.560774)
			(xy 306.795022 -40.607287) (xy 306.757805 -40.648824) (xy 306.714937 -40.684499) (xy 306.667331 -40.713553)
			(xy 306.616002 -40.735365) (xy 306.562045 -40.749471) (xy 306.506608 -40.755571) (xy 306.450874 -40.753534)
			(xy 306.396031 -40.743404) (xy 306.343247 -40.725397) (xy 306.293647 -40.699896) (xy 306.248289 -40.667445)
			(xy 306.20814 -40.628736) (xy 306.174054 -40.584593) (xy 306.146758 -40.535958) (xy 306.126835 -40.483867)
			(xy 306.114709 -40.42943) (xy 306.110638 -40.373808) (xy 300.366935 -40.373808) (xy 300.345829 -40.397364)
			(xy 300.302961 -40.433039) (xy 300.255355 -40.462093) (xy 300.204026 -40.483905) (xy 300.150069 -40.498011)
			(xy 300.094632 -40.504111) (xy 300.038898 -40.502074) (xy 299.984055 -40.491944) (xy 299.931271 -40.473937)
			(xy 299.881671 -40.448436) (xy 299.836313 -40.415985) (xy 299.796164 -40.377276) (xy 299.762078 -40.333133)
			(xy 299.734782 -40.284498) (xy 299.714859 -40.232407) (xy 299.702733 -40.17797) (xy 299.698662 -40.122348)
			(xy 292.188646 -40.122348) (xy 291.266626 -41.044368) (xy 303.761138 -41.044368) (xy 303.765209 -40.988746)
			(xy 303.777335 -40.934309) (xy 303.797258 -40.882218) (xy 303.824554 -40.833583) (xy 303.85864 -40.78944)
			(xy 303.898789 -40.750731) (xy 303.944147 -40.71828) (xy 303.993747 -40.692779) (xy 304.046531 -40.674772)
			(xy 304.101374 -40.664642) (xy 304.157108 -40.662605) (xy 304.212545 -40.668705) (xy 304.266502 -40.682811)
			(xy 304.317831 -40.704623) (xy 304.365437 -40.733677) (xy 304.408305 -40.769352) (xy 304.445522 -40.810889)
			(xy 304.476295 -40.857402) (xy 304.499967 -40.907899) (xy 304.516035 -40.961306) (xy 304.524155 -41.016482)
			(xy 304.524664 -41.044368) (xy 304.524155 -41.072254) (xy 304.516035 -41.12743) (xy 304.499967 -41.180837)
			(xy 304.476295 -41.231334) (xy 304.445522 -41.277847) (xy 304.408305 -41.319384) (xy 304.365437 -41.355059)
			(xy 304.317831 -41.384113) (xy 304.266502 -41.405925) (xy 304.212545 -41.420031) (xy 304.157108 -41.426131)
			(xy 304.101374 -41.424094) (xy 304.046531 -41.413964) (xy 303.993747 -41.395957) (xy 303.944147 -41.370456)
			(xy 303.898789 -41.338005) (xy 303.85864 -41.299296) (xy 303.824554 -41.255153) (xy 303.797258 -41.206518)
			(xy 303.777335 -41.154427) (xy 303.765209 -41.09999) (xy 303.761138 -41.044368) (xy 291.266626 -41.044368)
			(xy 290.410646 -41.900348) (xy 307.997096 -41.900348) (xy 308.001167 -41.844726) (xy 308.013293 -41.790289)
			(xy 308.033216 -41.738198) (xy 308.060512 -41.689563) (xy 308.094598 -41.64542) (xy 308.134747 -41.606711)
			(xy 308.180105 -41.57426) (xy 308.229705 -41.548759) (xy 308.282489 -41.530752) (xy 308.337332 -41.520622)
			(xy 308.393066 -41.518585) (xy 308.41635 -41.521147) (xy 310.189926 -41.521147) (xy 310.189926 -41.466653)
			(xy 310.197681 -41.412714) (xy 310.213033 -41.360427) (xy 310.23567 -41.310858) (xy 310.265131 -41.265014)
			(xy 310.300816 -41.22383) (xy 310.341998 -41.188143) (xy 310.38784 -41.15868) (xy 310.437409 -41.13604)
			(xy 310.489694 -41.120685) (xy 310.543633 -41.112928) (xy 310.57088 -41.11244) (xy 310.598417 -41.112916)
			(xy 310.65292 -41.12082) (xy 310.705719 -41.136483) (xy 310.755716 -41.159577) (xy 310.801871 -41.189623)
			(xy 310.843224 -41.225996) (xy 310.878915 -41.267939) (xy 310.893968 -41.291002) (xy 310.901984 -41.302741)
			(xy 310.923174 -41.321663) (xy 310.948755 -41.334022) (xy 310.976749 -41.338863) (xy 311.004995 -41.335812)
			(xy 311.031309 -41.325104) (xy 311.05366 -41.307567) (xy 311.06237 -41.296336) (xy 311.077844 -41.275678)
			(xy 311.113382 -41.23825) (xy 311.153642 -41.205954) (xy 311.197888 -41.17938) (xy 311.245312 -41.159013)
			(xy 311.295048 -41.145225) (xy 311.34619 -41.138267) (xy 311.371996 -41.13784) (xy 311.399252 -41.138207)
			(xy 311.453211 -41.145964) (xy 311.505516 -41.161322) (xy 311.555103 -41.183967) (xy 311.600962 -41.213439)
			(xy 311.64216 -41.249137) (xy 311.677859 -41.290335) (xy 311.707331 -41.336194) (xy 311.729977 -41.385781)
			(xy 311.745335 -41.438085) (xy 311.753093 -41.492044) (xy 311.753093 -41.546556) (xy 311.745335 -41.600515)
			(xy 311.729977 -41.652819) (xy 311.707331 -41.702406) (xy 311.677859 -41.748265) (xy 311.64216 -41.789463)
			(xy 311.600962 -41.825161) (xy 311.555103 -41.854633) (xy 311.505516 -41.877278) (xy 311.453211 -41.892636)
			(xy 311.399252 -41.900393) (xy 311.371996 -41.900856) (xy 311.344461 -41.900354) (xy 311.289961 -41.892448)
			(xy 311.237165 -41.876787) (xy 311.187169 -41.853696) (xy 311.141014 -41.823655) (xy 311.09966 -41.787289)
			(xy 311.063964 -41.745353) (xy 311.048908 -41.722294) (xy 311.040923 -41.710533) (xy 311.019725 -41.69161)
			(xy 310.994138 -41.679252) (xy 310.966138 -41.674414) (xy 310.937888 -41.67747) (xy 310.91157 -41.688183)
			(xy 310.889217 -41.705726) (xy 310.880506 -41.71696) (xy 310.865075 -41.737651) (xy 310.829526 -41.775073)
			(xy 310.789257 -41.807363) (xy 310.745004 -41.833932) (xy 310.697575 -41.854293) (xy 310.647833 -41.868077)
			(xy 310.596688 -41.875031) (xy 310.57088 -41.875456) (xy 310.543633 -41.874872) (xy 310.489694 -41.867115)
			(xy 310.437409 -41.85176) (xy 310.38784 -41.82912) (xy 310.341998 -41.799657) (xy 310.300816 -41.76397)
			(xy 310.265131 -41.722786) (xy 310.23567 -41.676942) (xy 310.213033 -41.627373) (xy 310.197681 -41.575086)
			(xy 310.189926 -41.521147) (xy 308.41635 -41.521147) (xy 308.448503 -41.524685) (xy 308.50246 -41.538791)
			(xy 308.553789 -41.560603) (xy 308.601395 -41.589657) (xy 308.644263 -41.625332) (xy 308.68148 -41.666869)
			(xy 308.712253 -41.713382) (xy 308.735925 -41.763879) (xy 308.751993 -41.817286) (xy 308.760113 -41.872462)
			(xy 308.760622 -41.900348) (xy 308.760113 -41.928234) (xy 308.751993 -41.98341) (xy 308.735925 -42.036817)
			(xy 308.712253 -42.087314) (xy 308.68148 -42.133827) (xy 308.644263 -42.175364) (xy 308.601395 -42.211039)
			(xy 308.553789 -42.240093) (xy 308.50246 -42.261905) (xy 308.448503 -42.276011) (xy 308.393066 -42.282111)
			(xy 308.337332 -42.280074) (xy 308.282489 -42.269944) (xy 308.229705 -42.251937) (xy 308.180105 -42.226436)
			(xy 308.134747 -42.193985) (xy 308.094598 -42.155276) (xy 308.060512 -42.111133) (xy 308.033216 -42.062498)
			(xy 308.013293 -42.010407) (xy 308.001167 -41.95597) (xy 307.997096 -41.900348) (xy 290.410646 -41.900348)
			(xy 289.394646 -42.916348) (xy 308.124604 -42.916348) (xy 308.128675 -42.860726) (xy 308.140801 -42.806289)
			(xy 308.160724 -42.754198) (xy 308.18802 -42.705563) (xy 308.222106 -42.66142) (xy 308.262255 -42.622711)
			(xy 308.307613 -42.59026) (xy 308.357213 -42.564759) (xy 308.409997 -42.546752) (xy 308.46484 -42.536622)
			(xy 308.520574 -42.534585) (xy 308.576011 -42.540685) (xy 308.629968 -42.554791) (xy 308.681297 -42.576603)
			(xy 308.728903 -42.605657) (xy 308.771771 -42.641332) (xy 308.808988 -42.682869) (xy 308.839761 -42.729382)
			(xy 308.863433 -42.779879) (xy 308.879501 -42.833286) (xy 308.887621 -42.888462) (xy 308.88813 -42.916348)
			(xy 310.156604 -42.916348) (xy 310.160675 -42.860726) (xy 310.172801 -42.806289) (xy 310.192724 -42.754198)
			(xy 310.22002 -42.705563) (xy 310.254106 -42.66142) (xy 310.294255 -42.622711) (xy 310.339613 -42.59026)
			(xy 310.389213 -42.564759) (xy 310.441997 -42.546752) (xy 310.49684 -42.536622) (xy 310.552574 -42.534585)
			(xy 310.608011 -42.540685) (xy 310.661968 -42.554791) (xy 310.713297 -42.576603) (xy 310.760903 -42.605657)
			(xy 310.803771 -42.641332) (xy 310.840988 -42.682869) (xy 310.861021 -42.713148) (xy 311.045604 -42.713148)
			(xy 311.049675 -42.657526) (xy 311.061801 -42.603089) (xy 311.081724 -42.550998) (xy 311.10902 -42.502363)
			(xy 311.143106 -42.45822) (xy 311.183255 -42.419511) (xy 311.228613 -42.38706) (xy 311.278213 -42.361559)
			(xy 311.330997 -42.343552) (xy 311.38584 -42.333422) (xy 311.441574 -42.331385) (xy 311.497011 -42.337485)
			(xy 311.550968 -42.351591) (xy 311.602297 -42.373403) (xy 311.649903 -42.402457) (xy 311.692771 -42.438132)
			(xy 311.729988 -42.479669) (xy 311.760761 -42.526182) (xy 311.784433 -42.576679) (xy 311.800501 -42.630086)
			(xy 311.808621 -42.685262) (xy 311.80913 -42.713148) (xy 311.808621 -42.741034) (xy 311.800501 -42.79621)
			(xy 311.784433 -42.849617) (xy 311.760761 -42.900114) (xy 311.729988 -42.946627) (xy 311.692771 -42.988164)
			(xy 311.649903 -43.023839) (xy 311.602297 -43.052893) (xy 311.550968 -43.074705) (xy 311.497011 -43.088811)
			(xy 311.441574 -43.094911) (xy 311.38584 -43.092874) (xy 311.330997 -43.082744) (xy 311.278213 -43.064737)
			(xy 311.228613 -43.039236) (xy 311.183255 -43.006785) (xy 311.143106 -42.968076) (xy 311.10902 -42.923933)
			(xy 311.081724 -42.875298) (xy 311.061801 -42.823207) (xy 311.049675 -42.76877) (xy 311.045604 -42.713148)
			(xy 310.861021 -42.713148) (xy 310.871761 -42.729382) (xy 310.895433 -42.779879) (xy 310.911501 -42.833286)
			(xy 310.919621 -42.888462) (xy 310.92013 -42.916348) (xy 310.919621 -42.944234) (xy 310.911501 -42.99941)
			(xy 310.895433 -43.052817) (xy 310.871761 -43.103314) (xy 310.840988 -43.149827) (xy 310.803771 -43.191364)
			(xy 310.760903 -43.227039) (xy 310.713297 -43.256093) (xy 310.661968 -43.277905) (xy 310.608011 -43.292011)
			(xy 310.552574 -43.298111) (xy 310.49684 -43.296074) (xy 310.441997 -43.285944) (xy 310.389213 -43.267937)
			(xy 310.339613 -43.242436) (xy 310.294255 -43.209985) (xy 310.254106 -43.171276) (xy 310.22002 -43.127133)
			(xy 310.192724 -43.078498) (xy 310.172801 -43.026407) (xy 310.160675 -42.97197) (xy 310.156604 -42.916348)
			(xy 308.88813 -42.916348) (xy 308.887621 -42.944234) (xy 308.879501 -42.99941) (xy 308.863433 -43.052817)
			(xy 308.839761 -43.103314) (xy 308.808988 -43.149827) (xy 308.771771 -43.191364) (xy 308.728903 -43.227039)
			(xy 308.681297 -43.256093) (xy 308.629968 -43.277905) (xy 308.576011 -43.292011) (xy 308.520574 -43.298111)
			(xy 308.46484 -43.296074) (xy 308.409997 -43.285944) (xy 308.357213 -43.267937) (xy 308.307613 -43.242436)
			(xy 308.262255 -43.209985) (xy 308.222106 -43.171276) (xy 308.18802 -43.127133) (xy 308.160724 -43.078498)
			(xy 308.140801 -43.026407) (xy 308.128675 -42.97197) (xy 308.124604 -42.916348) (xy 289.394646 -42.916348)
			(xy 288.912046 -43.398948) (xy 302.137062 -43.398948) (xy 302.141133 -43.343326) (xy 302.153259 -43.288889)
			(xy 302.173182 -43.236798) (xy 302.200478 -43.188163) (xy 302.234564 -43.14402) (xy 302.274713 -43.105311)
			(xy 302.320071 -43.07286) (xy 302.369671 -43.047359) (xy 302.422455 -43.029352) (xy 302.477298 -43.019222)
			(xy 302.533032 -43.017185) (xy 302.588469 -43.023285) (xy 302.642426 -43.037391) (xy 302.693755 -43.059203)
			(xy 302.741361 -43.088257) (xy 302.784229 -43.123932) (xy 302.821446 -43.165469) (xy 302.852219 -43.211982)
			(xy 302.875891 -43.262479) (xy 302.889386 -43.307333) (xy 328.29551 -43.307333) (xy 328.29551 -43.255359)
			(xy 328.30364 -43.204024) (xy 328.319701 -43.154594) (xy 328.343297 -43.108284) (xy 328.373847 -43.066236)
			(xy 328.410598 -43.029485) (xy 328.452646 -42.998935) (xy 328.498956 -42.975339) (xy 328.548386 -42.959278)
			(xy 328.599721 -42.951148) (xy 328.651695 -42.951148) (xy 328.70303 -42.959278) (xy 328.75246 -42.975339)
			(xy 328.79877 -42.998935) (xy 328.840818 -43.029485) (xy 328.877569 -43.066236) (xy 328.908119 -43.108284)
			(xy 328.931715 -43.154594) (xy 328.947776 -43.204024) (xy 328.955906 -43.255359) (xy 328.956416 -43.281346)
			(xy 328.955906 -43.307333) (xy 329.92365 -43.307333) (xy 329.92365 -43.255359) (xy 329.93178 -43.204024)
			(xy 329.947841 -43.154594) (xy 329.971437 -43.108284) (xy 330.001987 -43.066236) (xy 330.038738 -43.029485)
			(xy 330.080786 -42.998935) (xy 330.127096 -42.975339) (xy 330.176526 -42.959278) (xy 330.227861 -42.951148)
			(xy 330.279835 -42.951148) (xy 330.33117 -42.959278) (xy 330.3806 -42.975339) (xy 330.42691 -42.998935)
			(xy 330.468958 -43.029485) (xy 330.505709 -43.066236) (xy 330.536259 -43.108284) (xy 330.559855 -43.154594)
			(xy 330.575916 -43.204024) (xy 330.584046 -43.255359) (xy 330.584556 -43.281346) (xy 330.584046 -43.307333)
			(xy 331.552806 -43.307333) (xy 331.552806 -43.255359) (xy 331.560936 -43.204024) (xy 331.576997 -43.154594)
			(xy 331.600593 -43.108284) (xy 331.631143 -43.066236) (xy 331.667894 -43.029485) (xy 331.709942 -42.998935)
			(xy 331.756252 -42.975339) (xy 331.805682 -42.959278) (xy 331.857017 -42.951148) (xy 331.908991 -42.951148)
			(xy 331.960326 -42.959278) (xy 332.009756 -42.975339) (xy 332.056066 -42.998935) (xy 332.098114 -43.029485)
			(xy 332.134865 -43.066236) (xy 332.165415 -43.108284) (xy 332.189011 -43.154594) (xy 332.205072 -43.204024)
			(xy 332.213202 -43.255359) (xy 332.213712 -43.281346) (xy 332.213202 -43.307333) (xy 333.1812 -43.307333)
			(xy 333.1812 -43.255359) (xy 333.18933 -43.204024) (xy 333.205391 -43.154594) (xy 333.228987 -43.108284)
			(xy 333.259537 -43.066236) (xy 333.296288 -43.029485) (xy 333.338336 -42.998935) (xy 333.384646 -42.975339)
			(xy 333.434076 -42.959278) (xy 333.485411 -42.951148) (xy 333.537385 -42.951148) (xy 333.58872 -42.959278)
			(xy 333.63815 -42.975339) (xy 333.68446 -42.998935) (xy 333.726508 -43.029485) (xy 333.763259 -43.066236)
			(xy 333.793809 -43.108284) (xy 333.817405 -43.154594) (xy 333.833466 -43.204024) (xy 333.841596 -43.255359)
			(xy 333.842106 -43.281346) (xy 333.841596 -43.307333) (xy 334.80807 -43.307333) (xy 334.80807 -43.255359)
			(xy 334.8162 -43.204024) (xy 334.832261 -43.154594) (xy 334.855857 -43.108284) (xy 334.886407 -43.066236)
			(xy 334.923158 -43.029485) (xy 334.965206 -42.998935) (xy 335.011516 -42.975339) (xy 335.060946 -42.959278)
			(xy 335.112281 -42.951148) (xy 335.164255 -42.951148) (xy 335.21559 -42.959278) (xy 335.26502 -42.975339)
			(xy 335.31133 -42.998935) (xy 335.353378 -43.029485) (xy 335.390129 -43.066236) (xy 335.420679 -43.108284)
			(xy 335.444275 -43.154594) (xy 335.460336 -43.204024) (xy 335.468466 -43.255359) (xy 335.468976 -43.281346)
			(xy 335.468466 -43.307333) (xy 335.460336 -43.358668) (xy 335.444275 -43.408098) (xy 335.420679 -43.454408)
			(xy 335.390129 -43.496456) (xy 335.353378 -43.533207) (xy 335.31133 -43.563757) (xy 335.26502 -43.587353)
			(xy 335.21559 -43.603414) (xy 335.164255 -43.611544) (xy 335.112281 -43.611544) (xy 335.060946 -43.603414)
			(xy 335.011516 -43.587353) (xy 334.965206 -43.563757) (xy 334.923158 -43.533207) (xy 334.886407 -43.496456)
			(xy 334.855857 -43.454408) (xy 334.832261 -43.408098) (xy 334.8162 -43.358668) (xy 334.80807 -43.307333)
			(xy 333.841596 -43.307333) (xy 333.833466 -43.358668) (xy 333.817405 -43.408098) (xy 333.793809 -43.454408)
			(xy 333.763259 -43.496456) (xy 333.726508 -43.533207) (xy 333.68446 -43.563757) (xy 333.63815 -43.587353)
			(xy 333.58872 -43.603414) (xy 333.537385 -43.611544) (xy 333.485411 -43.611544) (xy 333.434076 -43.603414)
			(xy 333.384646 -43.587353) (xy 333.338336 -43.563757) (xy 333.296288 -43.533207) (xy 333.259537 -43.496456)
			(xy 333.228987 -43.454408) (xy 333.205391 -43.408098) (xy 333.18933 -43.358668) (xy 333.1812 -43.307333)
			(xy 332.213202 -43.307333) (xy 332.205072 -43.358668) (xy 332.189011 -43.408098) (xy 332.165415 -43.454408)
			(xy 332.134865 -43.496456) (xy 332.098114 -43.533207) (xy 332.056066 -43.563757) (xy 332.009756 -43.587353)
			(xy 331.960326 -43.603414) (xy 331.908991 -43.611544) (xy 331.857017 -43.611544) (xy 331.805682 -43.603414)
			(xy 331.756252 -43.587353) (xy 331.709942 -43.563757) (xy 331.667894 -43.533207) (xy 331.631143 -43.496456)
			(xy 331.600593 -43.454408) (xy 331.576997 -43.408098) (xy 331.560936 -43.358668) (xy 331.552806 -43.307333)
			(xy 330.584046 -43.307333) (xy 330.575916 -43.358668) (xy 330.559855 -43.408098) (xy 330.536259 -43.454408)
			(xy 330.505709 -43.496456) (xy 330.468958 -43.533207) (xy 330.42691 -43.563757) (xy 330.3806 -43.587353)
			(xy 330.33117 -43.603414) (xy 330.279835 -43.611544) (xy 330.227861 -43.611544) (xy 330.176526 -43.603414)
			(xy 330.127096 -43.587353) (xy 330.080786 -43.563757) (xy 330.038738 -43.533207) (xy 330.001987 -43.496456)
			(xy 329.971437 -43.454408) (xy 329.947841 -43.408098) (xy 329.93178 -43.358668) (xy 329.92365 -43.307333)
			(xy 328.955906 -43.307333) (xy 328.947776 -43.358668) (xy 328.931715 -43.408098) (xy 328.908119 -43.454408)
			(xy 328.877569 -43.496456) (xy 328.840818 -43.533207) (xy 328.79877 -43.563757) (xy 328.75246 -43.587353)
			(xy 328.70303 -43.603414) (xy 328.651695 -43.611544) (xy 328.599721 -43.611544) (xy 328.548386 -43.603414)
			(xy 328.498956 -43.587353) (xy 328.452646 -43.563757) (xy 328.410598 -43.533207) (xy 328.373847 -43.496456)
			(xy 328.343297 -43.454408) (xy 328.319701 -43.408098) (xy 328.30364 -43.358668) (xy 328.29551 -43.307333)
			(xy 302.889386 -43.307333) (xy 302.891959 -43.315886) (xy 302.900079 -43.371062) (xy 302.900588 -43.398948)
			(xy 302.900079 -43.426834) (xy 302.891959 -43.48201) (xy 302.875891 -43.535417) (xy 302.852219 -43.585914)
			(xy 302.821446 -43.632427) (xy 302.784229 -43.673964) (xy 302.741361 -43.709639) (xy 302.693755 -43.738693)
			(xy 302.642426 -43.760505) (xy 302.588469 -43.774611) (xy 302.533032 -43.780711) (xy 302.477298 -43.778674)
			(xy 302.422455 -43.768544) (xy 302.369671 -43.750537) (xy 302.320071 -43.725036) (xy 302.274713 -43.692585)
			(xy 302.234564 -43.653876) (xy 302.200478 -43.609733) (xy 302.173182 -43.561098) (xy 302.153259 -43.509007)
			(xy 302.141133 -43.45457) (xy 302.137062 -43.398948) (xy 288.912046 -43.398948) (xy 288.073846 -44.237148)
			(xy 306.581554 -44.237148) (xy 306.585625 -44.181526) (xy 306.597751 -44.127089) (xy 306.617674 -44.074998)
			(xy 306.64497 -44.026363) (xy 306.679056 -43.98222) (xy 306.719205 -43.943511) (xy 306.764563 -43.91106)
			(xy 306.814163 -43.885559) (xy 306.866947 -43.867552) (xy 306.92179 -43.857422) (xy 306.977524 -43.855385)
			(xy 307.032961 -43.861485) (xy 307.086918 -43.875591) (xy 307.138247 -43.897403) (xy 307.185853 -43.926457)
			(xy 307.192932 -43.932348) (xy 311.045604 -43.932348) (xy 311.049675 -43.876726) (xy 311.061801 -43.822289)
			(xy 311.081724 -43.770198) (xy 311.10902 -43.721563) (xy 311.143106 -43.67742) (xy 311.183255 -43.638711)
			(xy 311.228613 -43.60626) (xy 311.278213 -43.580759) (xy 311.330997 -43.562752) (xy 311.38584 -43.552622)
			(xy 311.441574 -43.550585) (xy 311.497011 -43.556685) (xy 311.550968 -43.570791) (xy 311.602297 -43.592603)
			(xy 311.649903 -43.621657) (xy 311.692771 -43.657332) (xy 311.729988 -43.698869) (xy 311.760761 -43.745382)
			(xy 311.775692 -43.777233) (xy 329.10958 -43.777233) (xy 329.10958 -43.725259) (xy 329.11771 -43.673924)
			(xy 329.133771 -43.624494) (xy 329.157367 -43.578184) (xy 329.187917 -43.536136) (xy 329.224668 -43.499385)
			(xy 329.266716 -43.468835) (xy 329.313026 -43.445239) (xy 329.362456 -43.429178) (xy 329.413791 -43.421048)
			(xy 329.465765 -43.421048) (xy 329.5171 -43.429178) (xy 329.56653 -43.445239) (xy 329.61284 -43.468835)
			(xy 329.654888 -43.499385) (xy 329.691639 -43.536136) (xy 329.722189 -43.578184) (xy 329.745785 -43.624494)
			(xy 329.761846 -43.673924) (xy 329.769976 -43.725259) (xy 329.770486 -43.751246) (xy 329.769976 -43.777233)
			(xy 330.73899 -43.777233) (xy 330.73899 -43.725259) (xy 330.74712 -43.673924) (xy 330.763181 -43.624494)
			(xy 330.786777 -43.578184) (xy 330.817327 -43.536136) (xy 330.854078 -43.499385) (xy 330.896126 -43.468835)
			(xy 330.942436 -43.445239) (xy 330.991866 -43.429178) (xy 331.043201 -43.421048) (xy 331.095175 -43.421048)
			(xy 331.14651 -43.429178) (xy 331.19594 -43.445239) (xy 331.24225 -43.468835) (xy 331.284298 -43.499385)
			(xy 331.321049 -43.536136) (xy 331.351599 -43.578184) (xy 331.375195 -43.624494) (xy 331.391256 -43.673924)
			(xy 331.399386 -43.725259) (xy 331.399896 -43.751246) (xy 331.399386 -43.777233) (xy 332.36713 -43.777233)
			(xy 332.36713 -43.725259) (xy 332.37526 -43.673924) (xy 332.391321 -43.624494) (xy 332.414917 -43.578184)
			(xy 332.445467 -43.536136) (xy 332.482218 -43.499385) (xy 332.524266 -43.468835) (xy 332.570576 -43.445239)
			(xy 332.620006 -43.429178) (xy 332.671341 -43.421048) (xy 332.723315 -43.421048) (xy 332.77465 -43.429178)
			(xy 332.82408 -43.445239) (xy 332.87039 -43.468835) (xy 332.912438 -43.499385) (xy 332.949189 -43.536136)
			(xy 332.979739 -43.578184) (xy 333.003335 -43.624494) (xy 333.019396 -43.673924) (xy 333.027526 -43.725259)
			(xy 333.028036 -43.751246) (xy 333.027526 -43.777233) (xy 333.994 -43.777233) (xy 333.994 -43.725259)
			(xy 334.00213 -43.673924) (xy 334.018191 -43.624494) (xy 334.041787 -43.578184) (xy 334.072337 -43.536136)
			(xy 334.109088 -43.499385) (xy 334.151136 -43.468835) (xy 334.197446 -43.445239) (xy 334.246876 -43.429178)
			(xy 334.298211 -43.421048) (xy 334.350185 -43.421048) (xy 334.40152 -43.429178) (xy 334.45095 -43.445239)
			(xy 334.49726 -43.468835) (xy 334.539308 -43.499385) (xy 334.576059 -43.536136) (xy 334.606609 -43.578184)
			(xy 334.630205 -43.624494) (xy 334.646266 -43.673924) (xy 334.654396 -43.725259) (xy 334.654906 -43.751246)
			(xy 334.654396 -43.777233) (xy 337.25155 -43.777233) (xy 337.25155 -43.725259) (xy 337.25968 -43.673924)
			(xy 337.275741 -43.624494) (xy 337.299337 -43.578184) (xy 337.329887 -43.536136) (xy 337.366638 -43.499385)
			(xy 337.408686 -43.468835) (xy 337.454996 -43.445239) (xy 337.504426 -43.429178) (xy 337.555761 -43.421048)
			(xy 337.607735 -43.421048) (xy 337.65907 -43.429178) (xy 337.7085 -43.445239) (xy 337.75481 -43.468835)
			(xy 337.796858 -43.499385) (xy 337.833609 -43.536136) (xy 337.864159 -43.578184) (xy 337.887755 -43.624494)
			(xy 337.903816 -43.673924) (xy 337.911946 -43.725259) (xy 337.912456 -43.751246) (xy 337.911946 -43.777233)
			(xy 338.87969 -43.777233) (xy 338.87969 -43.725259) (xy 338.88782 -43.673924) (xy 338.903881 -43.624494)
			(xy 338.927477 -43.578184) (xy 338.958027 -43.536136) (xy 338.994778 -43.499385) (xy 339.036826 -43.468835)
			(xy 339.083136 -43.445239) (xy 339.132566 -43.429178) (xy 339.183901 -43.421048) (xy 339.235875 -43.421048)
			(xy 339.28721 -43.429178) (xy 339.33664 -43.445239) (xy 339.38295 -43.468835) (xy 339.424998 -43.499385)
			(xy 339.461749 -43.536136) (xy 339.492299 -43.578184) (xy 339.515895 -43.624494) (xy 339.531956 -43.673924)
			(xy 339.540086 -43.725259) (xy 339.540596 -43.751246) (xy 339.540086 -43.777233) (xy 339.531956 -43.828568)
			(xy 339.515895 -43.877998) (xy 339.492299 -43.924308) (xy 339.461749 -43.966356) (xy 339.424998 -44.003107)
			(xy 339.38295 -44.033657) (xy 339.33664 -44.057253) (xy 339.28721 -44.073314) (xy 339.235875 -44.081444)
			(xy 339.183901 -44.081444) (xy 339.132566 -44.073314) (xy 339.083136 -44.057253) (xy 339.036826 -44.033657)
			(xy 338.994778 -44.003107) (xy 338.958027 -43.966356) (xy 338.927477 -43.924308) (xy 338.903881 -43.877998)
			(xy 338.88782 -43.828568) (xy 338.87969 -43.777233) (xy 337.911946 -43.777233) (xy 337.903816 -43.828568)
			(xy 337.887755 -43.877998) (xy 337.864159 -43.924308) (xy 337.833609 -43.966356) (xy 337.796858 -44.003107)
			(xy 337.75481 -44.033657) (xy 337.7085 -44.057253) (xy 337.65907 -44.073314) (xy 337.607735 -44.081444)
			(xy 337.555761 -44.081444) (xy 337.504426 -44.073314) (xy 337.454996 -44.057253) (xy 337.408686 -44.033657)
			(xy 337.366638 -44.003107) (xy 337.329887 -43.966356) (xy 337.299337 -43.924308) (xy 337.275741 -43.877998)
			(xy 337.25968 -43.828568) (xy 337.25155 -43.777233) (xy 334.654396 -43.777233) (xy 334.646266 -43.828568)
			(xy 334.630205 -43.877998) (xy 334.606609 -43.924308) (xy 334.576059 -43.966356) (xy 334.539308 -44.003107)
			(xy 334.49726 -44.033657) (xy 334.45095 -44.057253) (xy 334.40152 -44.073314) (xy 334.350185 -44.081444)
			(xy 334.298211 -44.081444) (xy 334.246876 -44.073314) (xy 334.197446 -44.057253) (xy 334.151136 -44.033657)
			(xy 334.109088 -44.003107) (xy 334.072337 -43.966356) (xy 334.041787 -43.924308) (xy 334.018191 -43.877998)
			(xy 334.00213 -43.828568) (xy 333.994 -43.777233) (xy 333.027526 -43.777233) (xy 333.019396 -43.828568)
			(xy 333.003335 -43.877998) (xy 332.979739 -43.924308) (xy 332.949189 -43.966356) (xy 332.912438 -44.003107)
			(xy 332.87039 -44.033657) (xy 332.82408 -44.057253) (xy 332.77465 -44.073314) (xy 332.723315 -44.081444)
			(xy 332.671341 -44.081444) (xy 332.620006 -44.073314) (xy 332.570576 -44.057253) (xy 332.524266 -44.033657)
			(xy 332.482218 -44.003107) (xy 332.445467 -43.966356) (xy 332.414917 -43.924308) (xy 332.391321 -43.877998)
			(xy 332.37526 -43.828568) (xy 332.36713 -43.777233) (xy 331.399386 -43.777233) (xy 331.391256 -43.828568)
			(xy 331.375195 -43.877998) (xy 331.351599 -43.924308) (xy 331.321049 -43.966356) (xy 331.284298 -44.003107)
			(xy 331.24225 -44.033657) (xy 331.19594 -44.057253) (xy 331.14651 -44.073314) (xy 331.095175 -44.081444)
			(xy 331.043201 -44.081444) (xy 330.991866 -44.073314) (xy 330.942436 -44.057253) (xy 330.896126 -44.033657)
			(xy 330.854078 -44.003107) (xy 330.817327 -43.966356) (xy 330.786777 -43.924308) (xy 330.763181 -43.877998)
			(xy 330.74712 -43.828568) (xy 330.73899 -43.777233) (xy 329.769976 -43.777233) (xy 329.761846 -43.828568)
			(xy 329.745785 -43.877998) (xy 329.722189 -43.924308) (xy 329.691639 -43.966356) (xy 329.654888 -44.003107)
			(xy 329.61284 -44.033657) (xy 329.56653 -44.057253) (xy 329.5171 -44.073314) (xy 329.465765 -44.081444)
			(xy 329.413791 -44.081444) (xy 329.362456 -44.073314) (xy 329.313026 -44.057253) (xy 329.266716 -44.033657)
			(xy 329.224668 -44.003107) (xy 329.187917 -43.966356) (xy 329.157367 -43.924308) (xy 329.133771 -43.877998)
			(xy 329.11771 -43.828568) (xy 329.10958 -43.777233) (xy 311.775692 -43.777233) (xy 311.784433 -43.795879)
			(xy 311.800501 -43.849286) (xy 311.808621 -43.904462) (xy 311.80913 -43.932348) (xy 311.808621 -43.960234)
			(xy 311.800501 -44.01541) (xy 311.784433 -44.068817) (xy 311.760761 -44.119314) (xy 311.729988 -44.165827)
			(xy 311.692771 -44.207364) (xy 311.649903 -44.243039) (xy 311.602297 -44.272093) (xy 311.550968 -44.293905)
			(xy 311.497011 -44.308011) (xy 311.441574 -44.314111) (xy 311.38584 -44.312074) (xy 311.330997 -44.301944)
			(xy 311.278213 -44.283937) (xy 311.228613 -44.258436) (xy 311.183255 -44.225985) (xy 311.143106 -44.187276)
			(xy 311.10902 -44.143133) (xy 311.081724 -44.094498) (xy 311.061801 -44.042407) (xy 311.049675 -43.98797)
			(xy 311.045604 -43.932348) (xy 307.192932 -43.932348) (xy 307.228721 -43.962132) (xy 307.265938 -44.003669)
			(xy 307.296711 -44.050182) (xy 307.320383 -44.100679) (xy 307.336451 -44.154086) (xy 307.344571 -44.209262)
			(xy 307.34508 -44.237148) (xy 307.344571 -44.265034) (xy 307.336451 -44.32021) (xy 307.320383 -44.373617)
			(xy 307.296711 -44.424114) (xy 307.265938 -44.470627) (xy 307.228721 -44.512164) (xy 307.185853 -44.547839)
			(xy 307.138247 -44.576893) (xy 307.086918 -44.598705) (xy 307.032961 -44.612811) (xy 306.977524 -44.618911)
			(xy 306.92179 -44.616874) (xy 306.866947 -44.606744) (xy 306.814163 -44.588737) (xy 306.764563 -44.563236)
			(xy 306.719205 -44.530785) (xy 306.679056 -44.492076) (xy 306.64497 -44.447933) (xy 306.617674 -44.399298)
			(xy 306.597751 -44.347207) (xy 306.585625 -44.29277) (xy 306.581554 -44.237148) (xy 288.073846 -44.237148)
			(xy 287.465445 -44.845549) (xy 295.640778 -44.845549) (xy 295.640778 -44.791051) (xy 295.648533 -44.737106)
			(xy 295.663886 -44.684815) (xy 295.686524 -44.63524) (xy 295.715987 -44.589392) (xy 295.751674 -44.548203)
			(xy 295.79286 -44.512511) (xy 295.838705 -44.483044) (xy 295.888277 -44.4604) (xy 295.940567 -44.445042)
			(xy 295.994511 -44.437281) (xy 296.02176 -44.436792) (xy 296.051181 -44.43737) (xy 296.109323 -44.446412)
			(xy 296.165389 -44.464272) (xy 296.218048 -44.490528) (xy 296.266053 -44.524555) (xy 296.308265 -44.565549)
			(xy 296.343683 -44.612537) (xy 296.358056 -44.638214) (xy 296.365647 -44.651242) (xy 296.387048 -44.672464)
			(xy 296.413704 -44.686529) (xy 296.443301 -44.692217) (xy 296.473272 -44.689034) (xy 296.501015 -44.677256)
			(xy 296.524122 -44.657906) (xy 296.532808 -44.64558) (xy 296.548007 -44.623172) (xy 296.583674 -44.582436)
			(xy 296.624743 -44.547154) (xy 296.67039 -44.518036) (xy 296.719696 -44.495667) (xy 296.771671 -44.480497)
			(xy 296.825268 -44.47283) (xy 296.85234 -44.472352) (xy 296.879586 -44.472921) (xy 296.933524 -44.480681)
			(xy 296.985809 -44.496038) (xy 297.035376 -44.518679) (xy 297.081216 -44.548143) (xy 297.122397 -44.583831)
			(xy 297.158081 -44.625016) (xy 297.18754 -44.67086) (xy 297.210176 -44.720429) (xy 297.225527 -44.772715)
			(xy 297.232154 -44.818808) (xy 297.639738 -44.818808) (xy 297.643809 -44.763186) (xy 297.655935 -44.708749)
			(xy 297.675858 -44.656658) (xy 297.703154 -44.608023) (xy 297.73724 -44.56388) (xy 297.777389 -44.525171)
			(xy 297.822747 -44.49272) (xy 297.872347 -44.467219) (xy 297.925131 -44.449212) (xy 297.979974 -44.439082)
			(xy 298.035708 -44.437045) (xy 298.091145 -44.443145) (xy 298.145102 -44.457251) (xy 298.196431 -44.479063)
			(xy 298.244037 -44.508117) (xy 298.286905 -44.543792) (xy 298.324122 -44.585329) (xy 298.354895 -44.631842)
			(xy 298.378567 -44.682339) (xy 298.392879 -44.729908) (xy 310.189878 -44.729908) (xy 310.193949 -44.674286)
			(xy 310.206075 -44.619849) (xy 310.225998 -44.567758) (xy 310.253294 -44.519123) (xy 310.28738 -44.47498)
			(xy 310.327529 -44.436271) (xy 310.372887 -44.40382) (xy 310.422487 -44.378319) (xy 310.475271 -44.360312)
			(xy 310.530114 -44.350182) (xy 310.585848 -44.348145) (xy 310.641285 -44.354245) (xy 310.695242 -44.368351)
			(xy 310.741142 -44.387856) (xy 320.141248 -44.387856) (xy 320.141248 -44.333344) (xy 320.149006 -44.279388)
			(xy 320.164365 -44.227086) (xy 320.187011 -44.177502) (xy 320.216484 -44.131645) (xy 320.252183 -44.090451)
			(xy 320.293382 -44.054756) (xy 320.339242 -44.025289) (xy 320.388829 -44.002648) (xy 320.441133 -43.987296)
			(xy 320.49509 -43.979544) (xy 320.522346 -43.979084) (xy 320.550305 -43.979571) (xy 320.605622 -43.987752)
			(xy 320.659153 -44.003919) (xy 320.709752 -44.027723) (xy 320.756335 -44.058657) (xy 320.797906 -44.096058)
			(xy 320.833573 -44.139124) (xy 320.862574 -44.186935) (xy 320.873882 -44.21251) (xy 320.880095 -44.225977)
			(xy 320.898954 -44.24885) (xy 320.923594 -44.265334) (xy 320.951932 -44.274038) (xy 320.981577 -44.274228)
			(xy 321.010024 -44.265887) (xy 321.022726 -44.25823) (xy 321.045992 -44.243746) (xy 321.095789 -44.220859)
			(xy 321.148348 -44.205335) (xy 321.202588 -44.197491) (xy 321.22999 -44.197016) (xy 321.257245 -44.19743)
			(xy 321.311201 -44.205187) (xy 321.363503 -44.220543) (xy 321.413087 -44.243186) (xy 321.419229 -44.247133)
			(xy 329.92365 -44.247133) (xy 329.92365 -44.195159) (xy 329.93178 -44.143824) (xy 329.947841 -44.094394)
			(xy 329.971437 -44.048084) (xy 330.001987 -44.006036) (xy 330.038738 -43.969285) (xy 330.080786 -43.938735)
			(xy 330.127096 -43.915139) (xy 330.176526 -43.899078) (xy 330.227861 -43.890948) (xy 330.279835 -43.890948)
			(xy 330.33117 -43.899078) (xy 330.3806 -43.915139) (xy 330.42691 -43.938735) (xy 330.468958 -43.969285)
			(xy 330.505709 -44.006036) (xy 330.536259 -44.048084) (xy 330.559855 -44.094394) (xy 330.575916 -44.143824)
			(xy 330.584046 -44.195159) (xy 330.584556 -44.221146) (xy 330.584046 -44.247133) (xy 331.55179 -44.247133)
			(xy 331.55179 -44.195159) (xy 331.55992 -44.143824) (xy 331.575981 -44.094394) (xy 331.599577 -44.048084)
			(xy 331.630127 -44.006036) (xy 331.666878 -43.969285) (xy 331.708926 -43.938735) (xy 331.755236 -43.915139)
			(xy 331.804666 -43.899078) (xy 331.856001 -43.890948) (xy 331.907975 -43.890948) (xy 331.95931 -43.899078)
			(xy 332.00874 -43.915139) (xy 332.05505 -43.938735) (xy 332.097098 -43.969285) (xy 332.133849 -44.006036)
			(xy 332.164399 -44.048084) (xy 332.187995 -44.094394) (xy 332.204056 -44.143824) (xy 332.212186 -44.195159)
			(xy 332.212696 -44.221146) (xy 332.212186 -44.247133) (xy 333.180184 -44.247133) (xy 333.180184 -44.195159)
			(xy 333.188314 -44.143824) (xy 333.204375 -44.094394) (xy 333.227971 -44.048084) (xy 333.258521 -44.006036)
			(xy 333.295272 -43.969285) (xy 333.33732 -43.938735) (xy 333.38363 -43.915139) (xy 333.43306 -43.899078)
			(xy 333.484395 -43.890948) (xy 333.536369 -43.890948) (xy 333.587704 -43.899078) (xy 333.637134 -43.915139)
			(xy 333.683444 -43.938735) (xy 333.725492 -43.969285) (xy 333.762243 -44.006036) (xy 333.792793 -44.048084)
			(xy 333.816389 -44.094394) (xy 333.83245 -44.143824) (xy 333.84058 -44.195159) (xy 333.84109 -44.221146)
			(xy 333.84058 -44.247133) (xy 333.83245 -44.298468) (xy 333.816389 -44.347898) (xy 333.792793 -44.394208)
			(xy 333.762243 -44.436256) (xy 333.725492 -44.473007) (xy 333.683444 -44.503557) (xy 333.637134 -44.527153)
			(xy 333.587704 -44.543214) (xy 333.536369 -44.551344) (xy 333.484395 -44.551344) (xy 333.43306 -44.543214)
			(xy 333.38363 -44.527153) (xy 333.33732 -44.503557) (xy 333.295272 -44.473007) (xy 333.258521 -44.436256)
			(xy 333.227971 -44.394208) (xy 333.204375 -44.347898) (xy 333.188314 -44.298468) (xy 333.180184 -44.247133)
			(xy 332.212186 -44.247133) (xy 332.204056 -44.298468) (xy 332.187995 -44.347898) (xy 332.164399 -44.394208)
			(xy 332.133849 -44.436256) (xy 332.097098 -44.473007) (xy 332.05505 -44.503557) (xy 332.00874 -44.527153)
			(xy 331.95931 -44.543214) (xy 331.907975 -44.551344) (xy 331.856001 -44.551344) (xy 331.804666 -44.543214)
			(xy 331.755236 -44.527153) (xy 331.708926 -44.503557) (xy 331.666878 -44.473007) (xy 331.630127 -44.436256)
			(xy 331.599577 -44.394208) (xy 331.575981 -44.347898) (xy 331.55992 -44.298468) (xy 331.55179 -44.247133)
			(xy 330.584046 -44.247133) (xy 330.575916 -44.298468) (xy 330.559855 -44.347898) (xy 330.536259 -44.394208)
			(xy 330.505709 -44.436256) (xy 330.468958 -44.473007) (xy 330.42691 -44.503557) (xy 330.3806 -44.527153)
			(xy 330.33117 -44.543214) (xy 330.279835 -44.551344) (xy 330.227861 -44.551344) (xy 330.176526 -44.543214)
			(xy 330.127096 -44.527153) (xy 330.080786 -44.503557) (xy 330.038738 -44.473007) (xy 330.001987 -44.436256)
			(xy 329.971437 -44.394208) (xy 329.947841 -44.347898) (xy 329.93178 -44.298468) (xy 329.92365 -44.247133)
			(xy 321.419229 -44.247133) (xy 321.458945 -44.272656) (xy 321.500141 -44.308352) (xy 321.535838 -44.349547)
			(xy 321.565309 -44.395404) (xy 321.587954 -44.444988) (xy 321.603311 -44.49729) (xy 321.611069 -44.551245)
			(xy 321.611069 -44.605755) (xy 321.603311 -44.65971) (xy 321.592747 -44.695689) (xy 328.387185 -44.695689)
			(xy 328.387185 -44.643711) (xy 328.395316 -44.592374) (xy 328.411378 -44.542941) (xy 328.434975 -44.496629)
			(xy 328.465527 -44.454579) (xy 328.50228 -44.417825) (xy 328.544331 -44.387274) (xy 328.590643 -44.363677)
			(xy 328.640076 -44.347616) (xy 328.691413 -44.339485) (xy 328.717402 -44.339002) (xy 328.741389 -44.339423)
			(xy 328.788859 -44.346355) (xy 328.83483 -44.360073) (xy 328.878335 -44.38029) (xy 328.918464 -44.406581)
			(xy 328.954372 -44.438394) (xy 328.985307 -44.475061) (xy 328.998326 -44.495212) (xy 329.006275 -44.507163)
			(xy 329.027571 -44.526388) (xy 329.053374 -44.538934) (xy 329.081647 -44.54381) (xy 329.110161 -44.540632)
			(xy 329.136667 -44.52965) (xy 329.159074 -44.511731) (xy 329.167744 -44.500292) (xy 329.183343 -44.479047)
			(xy 329.220172 -44.441349) (xy 329.262519 -44.409975) (xy 329.309311 -44.385723) (xy 329.359359 -44.369208)
			(xy 329.411395 -44.360848) (xy 329.437746 -44.360338) (xy 329.463734 -44.360759) (xy 329.51507 -44.368897)
			(xy 329.564502 -44.384964) (xy 329.610811 -44.408565) (xy 329.652859 -44.43912) (xy 329.68961 -44.475876)
			(xy 329.720159 -44.517928) (xy 329.743754 -44.564241) (xy 329.759814 -44.613674) (xy 329.767945 -44.665012)
			(xy 329.767945 -44.716989) (xy 329.767938 -44.717033) (xy 330.73518 -44.717033) (xy 330.73518 -44.665059)
			(xy 330.74331 -44.613724) (xy 330.759371 -44.564294) (xy 330.782967 -44.517984) (xy 330.813517 -44.475936)
			(xy 330.850268 -44.439185) (xy 330.892316 -44.408635) (xy 330.938626 -44.385039) (xy 330.988056 -44.368978)
			(xy 331.039391 -44.360848) (xy 331.091365 -44.360848) (xy 331.1427 -44.368978) (xy 331.19213 -44.385039)
			(xy 331.23844 -44.408635) (xy 331.280488 -44.439185) (xy 331.317239 -44.475936) (xy 331.347789 -44.517984)
			(xy 331.371385 -44.564294) (xy 331.387446 -44.613724) (xy 331.395576 -44.665059) (xy 331.396086 -44.691046)
			(xy 331.395576 -44.717033) (xy 332.36332 -44.717033) (xy 332.36332 -44.665059) (xy 332.37145 -44.613724)
			(xy 332.387511 -44.564294) (xy 332.411107 -44.517984) (xy 332.441657 -44.475936) (xy 332.478408 -44.439185)
			(xy 332.520456 -44.408635) (xy 332.566766 -44.385039) (xy 332.616196 -44.368978) (xy 332.667531 -44.360848)
			(xy 332.719505 -44.360848) (xy 332.77084 -44.368978) (xy 332.82027 -44.385039) (xy 332.86658 -44.408635)
			(xy 332.908628 -44.439185) (xy 332.945379 -44.475936) (xy 332.975929 -44.517984) (xy 332.999525 -44.564294)
			(xy 333.015586 -44.613724) (xy 333.023716 -44.665059) (xy 333.024226 -44.691046) (xy 333.023716 -44.717033)
			(xy 333.015586 -44.768368) (xy 332.999525 -44.817798) (xy 332.983221 -44.849796) (xy 334.5688 -44.849796)
			(xy 334.569296 -44.823855) (xy 334.577378 -44.772606) (xy 334.593373 -44.72325) (xy 334.616888 -44.677003)
			(xy 334.647345 -44.635001) (xy 334.683994 -44.598278) (xy 334.725935 -44.567737) (xy 334.772134 -44.544128)
			(xy 334.796638 -44.535598) (xy 334.810828 -44.530356) (xy 334.835514 -44.512895) (xy 334.854011 -44.488977)
			(xy 334.8647 -44.460693) (xy 334.866646 -44.430519) (xy 334.859679 -44.401096) (xy 334.852518 -44.38777)
			(xy 334.838376 -44.362304) (xy 334.818307 -44.307623) (xy 334.808147 -44.25027) (xy 334.80756 -44.221146)
			(xy 334.80807 -44.195159) (xy 334.8162 -44.143824) (xy 334.832261 -44.094394) (xy 334.855857 -44.048084)
			(xy 334.886407 -44.006036) (xy 334.923158 -43.969285) (xy 334.965206 -43.938735) (xy 335.011516 -43.915139)
			(xy 335.060946 -43.899078) (xy 335.112281 -43.890948) (xy 335.164255 -43.890948) (xy 335.21559 -43.899078)
			(xy 335.26502 -43.915139) (xy 335.31133 -43.938735) (xy 335.353378 -43.969285) (xy 335.390129 -44.006036)
			(xy 335.420679 -44.048084) (xy 335.444275 -44.094394) (xy 335.460336 -44.143824) (xy 335.468466 -44.195159)
			(xy 335.468976 -44.221146) (xy 335.468465 -44.247086) (xy 335.460379 -44.298332) (xy 335.444382 -44.347684)
			(xy 335.420868 -44.393928) (xy 335.390414 -44.435929) (xy 335.353768 -44.472653) (xy 335.311833 -44.503197)
			(xy 335.265639 -44.52681) (xy 335.241138 -44.535344) (xy 335.226976 -44.540651) (xy 335.202301 -44.558102)
			(xy 335.183808 -44.582007) (xy 335.173116 -44.610275) (xy 335.171159 -44.640435) (xy 335.178108 -44.669848)
			(xy 335.185258 -44.683172) (xy 335.199414 -44.708631) (xy 335.219478 -44.763315) (xy 335.229633 -44.820671)
			(xy 335.230216 -44.849796) (xy 337.7692 -44.849796) (xy 337.769624 -44.824539) (xy 337.777293 -44.774611)
			(xy 337.792467 -44.726431) (xy 337.814792 -44.681119) (xy 337.84375 -44.63973) (xy 337.878666 -44.603228)
			(xy 337.918728 -44.57246) (xy 337.963004 -44.548145) (xy 338.010463 -44.530846) (xy 338.035138 -44.525438)
			(xy 338.048358 -44.522389) (xy 338.07262 -44.510265) (xy 338.092828 -44.492175) (xy 338.107554 -44.469398)
			(xy 338.115757 -44.443546) (xy 338.116856 -44.416445) (xy 338.110773 -44.390014) (xy 338.104734 -44.377864)
			(xy 338.09235 -44.353615) (xy 338.074782 -44.302083) (xy 338.065898 -44.248369) (xy 338.065364 -44.221146)
			(xy 338.065874 -44.195159) (xy 338.074004 -44.143824) (xy 338.090065 -44.094394) (xy 338.113661 -44.048084)
			(xy 338.144211 -44.006036) (xy 338.180962 -43.969285) (xy 338.22301 -43.938735) (xy 338.26932 -43.915139)
			(xy 338.31875 -43.899078) (xy 338.370085 -43.890948) (xy 338.422059 -43.890948) (xy 338.473394 -43.899078)
			(xy 338.522824 -43.915139) (xy 338.569134 -43.938735) (xy 338.611182 -43.969285) (xy 338.647933 -44.006036)
			(xy 338.678483 -44.048084) (xy 338.702079 -44.094394) (xy 338.71814 -44.143824) (xy 338.72627 -44.195159)
			(xy 338.72678 -44.221146) (xy 338.726239 -44.246398) (xy 338.718581 -44.296317) (xy 338.70342 -44.344491)
			(xy 338.681108 -44.389799) (xy 338.652165 -44.431186) (xy 338.617264 -44.46769) (xy 338.577217 -44.498461)
			(xy 338.532956 -44.522783) (xy 338.485511 -44.54009) (xy 338.460842 -44.545504) (xy 338.447642 -44.548621)
			(xy 338.423391 -44.56074) (xy 338.40319 -44.578819) (xy 338.388466 -44.601582) (xy 338.380259 -44.62742)
			(xy 338.37915 -44.654508) (xy 338.385216 -44.68093) (xy 338.391246 -44.693078) (xy 338.403651 -44.717317)
			(xy 338.42121 -44.768854) (xy 338.430086 -44.822572) (xy 338.430616 -44.849796) (xy 338.430106 -44.875783)
			(xy 338.56981 -44.875783) (xy 338.56981 -44.823809) (xy 338.57794 -44.772474) (xy 338.594001 -44.723044)
			(xy 338.617597 -44.676734) (xy 338.648147 -44.634686) (xy 338.684898 -44.597935) (xy 338.726946 -44.567385)
			(xy 338.773256 -44.543789) (xy 338.822686 -44.527728) (xy 338.874021 -44.519598) (xy 338.925995 -44.519598)
			(xy 338.97733 -44.527728) (xy 339.02676 -44.543789) (xy 339.07307 -44.567385) (xy 339.115118 -44.597935)
			(xy 339.151869 -44.634686) (xy 339.182419 -44.676734) (xy 339.206015 -44.723044) (xy 339.210582 -44.737099)
			(xy 339.920074 -44.737099) (xy 339.920074 -44.685125) (xy 339.928204 -44.63379) (xy 339.944265 -44.58436)
			(xy 339.967861 -44.53805) (xy 339.998411 -44.496002) (xy 340.035162 -44.459251) (xy 340.07721 -44.428701)
			(xy 340.12352 -44.405105) (xy 340.17295 -44.389044) (xy 340.224285 -44.380914) (xy 340.276259 -44.380914)
			(xy 340.327594 -44.389044) (xy 340.377024 -44.405105) (xy 340.423334 -44.428701) (xy 340.465382 -44.459251)
			(xy 340.502133 -44.496002) (xy 340.532683 -44.53805) (xy 340.556279 -44.58436) (xy 340.57234 -44.63379)
			(xy 340.58047 -44.685125) (xy 340.58098 -44.711112) (xy 340.58047 -44.737099) (xy 340.57234 -44.788434)
			(xy 340.556279 -44.837864) (xy 340.532683 -44.884174) (xy 340.502133 -44.926222) (xy 340.465382 -44.962973)
			(xy 340.423334 -44.993523) (xy 340.377024 -45.017119) (xy 340.327594 -45.03318) (xy 340.276259 -45.04131)
			(xy 340.224285 -45.04131) (xy 340.17295 -45.03318) (xy 340.12352 -45.017119) (xy 340.07721 -44.993523)
			(xy 340.035162 -44.962973) (xy 339.998411 -44.926222) (xy 339.967861 -44.884174) (xy 339.944265 -44.837864)
			(xy 339.928204 -44.788434) (xy 339.920074 -44.737099) (xy 339.210582 -44.737099) (xy 339.222076 -44.772474)
			(xy 339.230206 -44.823809) (xy 339.230716 -44.849796) (xy 339.230206 -44.875783) (xy 339.222076 -44.927118)
			(xy 339.206015 -44.976548) (xy 339.182419 -45.022858) (xy 339.151869 -45.064906) (xy 339.115118 -45.101657)
			(xy 339.07307 -45.132207) (xy 339.02676 -45.155803) (xy 338.97733 -45.171864) (xy 338.925995 -45.179994)
			(xy 338.874021 -45.179994) (xy 338.822686 -45.171864) (xy 338.773256 -45.155803) (xy 338.726946 -45.132207)
			(xy 338.684898 -45.101657) (xy 338.648147 -45.064906) (xy 338.617597 -45.022858) (xy 338.594001 -44.976548)
			(xy 338.57794 -44.927118) (xy 338.56981 -44.875783) (xy 338.430106 -44.875783) (xy 338.421976 -44.927118)
			(xy 338.405915 -44.976548) (xy 338.382319 -45.022858) (xy 338.351769 -45.064906) (xy 338.315018 -45.101657)
			(xy 338.27297 -45.132207) (xy 338.22666 -45.155803) (xy 338.17723 -45.171864) (xy 338.125895 -45.179994)
			(xy 338.073921 -45.179994) (xy 338.022586 -45.171864) (xy 337.973156 -45.155803) (xy 337.926846 -45.132207)
			(xy 337.884798 -45.101657) (xy 337.848047 -45.064906) (xy 337.817497 -45.022858) (xy 337.793901 -44.976548)
			(xy 337.77784 -44.927118) (xy 337.76971 -44.875783) (xy 337.7692 -44.849796) (xy 335.230216 -44.849796)
			(xy 335.229706 -44.875783) (xy 335.221576 -44.927118) (xy 335.205515 -44.976548) (xy 335.181919 -45.022858)
			(xy 335.151369 -45.064906) (xy 335.114618 -45.101657) (xy 335.07257 -45.132207) (xy 335.02626 -45.155803)
			(xy 334.97683 -45.171864) (xy 334.925495 -45.179994) (xy 334.873521 -45.179994) (xy 334.822186 -45.171864)
			(xy 334.772756 -45.155803) (xy 334.726446 -45.132207) (xy 334.684398 -45.101657) (xy 334.647647 -45.064906)
			(xy 334.617097 -45.022858) (xy 334.593501 -44.976548) (xy 334.57744 -44.927118) (xy 334.56931 -44.875783)
			(xy 334.5688 -44.849796) (xy 332.983221 -44.849796) (xy 332.975929 -44.864108) (xy 332.945379 -44.906156)
			(xy 332.908628 -44.942907) (xy 332.86658 -44.973457) (xy 332.82027 -44.997053) (xy 332.77084 -45.013114)
			(xy 332.719505 -45.021244) (xy 332.667531 -45.021244) (xy 332.616196 -45.013114) (xy 332.566766 -44.997053)
			(xy 332.520456 -44.973457) (xy 332.478408 -44.942907) (xy 332.441657 -44.906156) (xy 332.411107 -44.864108)
			(xy 332.387511 -44.817798) (xy 332.37145 -44.768368) (xy 332.36332 -44.717033) (xy 331.395576 -44.717033)
			(xy 331.387446 -44.768368) (xy 331.371385 -44.817798) (xy 331.347789 -44.864108) (xy 331.317239 -44.906156)
			(xy 331.280488 -44.942907) (xy 331.23844 -44.973457) (xy 331.19213 -44.997053) (xy 331.1427 -45.013114)
			(xy 331.091365 -45.021244) (xy 331.039391 -45.021244) (xy 330.988056 -45.013114) (xy 330.938626 -44.997053)
			(xy 330.892316 -44.973457) (xy 330.850268 -44.942907) (xy 330.813517 -44.906156) (xy 330.782967 -44.864108)
			(xy 330.759371 -44.817798) (xy 330.74331 -44.768368) (xy 330.73518 -44.717033) (xy 329.767938 -44.717033)
			(xy 329.759814 -44.768326) (xy 329.743754 -44.817759) (xy 329.720159 -44.864072) (xy 329.68961 -44.906124)
			(xy 329.652859 -44.94288) (xy 329.610811 -44.973435) (xy 329.564502 -44.997036) (xy 329.51507 -45.013103)
			(xy 329.463734 -45.021241) (xy 329.437746 -45.021754) (xy 329.413762 -45.021269) (xy 329.366295 -45.014346)
			(xy 329.320328 -45.000636) (xy 329.276823 -44.98043) (xy 329.236694 -44.954149) (xy 329.200783 -44.922347)
			(xy 329.169844 -44.88569) (xy 329.156822 -44.865544) (xy 329.14881 -44.853641) (xy 329.127524 -44.834425)
			(xy 329.101736 -44.821884) (xy 329.073479 -44.817004) (xy 329.044978 -44.820172) (xy 329.018481 -44.831137)
			(xy 328.996077 -44.849036) (xy 328.987404 -44.860464) (xy 328.971792 -44.881698) (xy 328.934964 -44.919394)
			(xy 328.892618 -44.950767) (xy 328.84583 -44.97502) (xy 328.795785 -44.991539) (xy 328.743752 -44.999905)
			(xy 328.717402 -45.000418) (xy 328.691413 -44.999915) (xy 328.640076 -44.991784) (xy 328.590643 -44.975723)
			(xy 328.544331 -44.952126) (xy 328.50228 -44.921575) (xy 328.465527 -44.884821) (xy 328.434975 -44.842771)
			(xy 328.411378 -44.796459) (xy 328.395316 -44.747026) (xy 328.387185 -44.695689) (xy 321.592747 -44.695689)
			(xy 321.587954 -44.712012) (xy 321.565309 -44.761596) (xy 321.535838 -44.807453) (xy 321.500141 -44.848648)
			(xy 321.458945 -44.884344) (xy 321.413087 -44.913814) (xy 321.363503 -44.936457) (xy 321.311201 -44.951813)
			(xy 321.257245 -44.95957) (xy 321.22999 -44.960032) (xy 321.202032 -44.959505) (xy 321.146718 -44.951329)
			(xy 321.093188 -44.935168) (xy 321.04259 -44.911369) (xy 320.996007 -44.880441) (xy 320.954435 -44.843046)
			(xy 320.918766 -44.799985) (xy 320.889763 -44.752179) (xy 320.878454 -44.726606) (xy 320.872191 -44.713164)
			(xy 320.853343 -44.690293) (xy 320.828715 -44.673807) (xy 320.800387 -44.665098) (xy 320.770751 -44.664902)
			(xy 320.74231 -44.673234) (xy 320.72961 -44.680886) (xy 320.706361 -44.695399) (xy 320.656558 -44.718278)
			(xy 320.603993 -44.733795) (xy 320.549749 -44.74163) (xy 320.522346 -44.7421) (xy 320.49509 -44.741656)
			(xy 320.441133 -44.733904) (xy 320.388829 -44.718552) (xy 320.339242 -44.695911) (xy 320.293382 -44.666444)
			(xy 320.252183 -44.630749) (xy 320.216484 -44.589555) (xy 320.187011 -44.543698) (xy 320.164365 -44.494114)
			(xy 320.149006 -44.441812) (xy 320.141248 -44.387856) (xy 310.741142 -44.387856) (xy 310.746571 -44.390163)
			(xy 310.794177 -44.419217) (xy 310.837045 -44.454892) (xy 310.874262 -44.496429) (xy 310.905035 -44.542942)
			(xy 310.928707 -44.593439) (xy 310.944775 -44.646846) (xy 310.952895 -44.702022) (xy 310.953404 -44.729908)
			(xy 310.952895 -44.757794) (xy 310.944775 -44.81297) (xy 310.928707 -44.866377) (xy 310.905035 -44.916874)
			(xy 310.874262 -44.963387) (xy 310.837045 -45.004924) (xy 310.794177 -45.040599) (xy 310.746571 -45.069653)
			(xy 310.695242 -45.091465) (xy 310.641285 -45.105571) (xy 310.585848 -45.111671) (xy 310.530114 -45.109634)
			(xy 310.475271 -45.099504) (xy 310.422487 -45.081497) (xy 310.372887 -45.055996) (xy 310.327529 -45.023545)
			(xy 310.28738 -44.984836) (xy 310.253294 -44.940693) (xy 310.225998 -44.892058) (xy 310.206075 -44.839967)
			(xy 310.193949 -44.78553) (xy 310.189878 -44.729908) (xy 298.392879 -44.729908) (xy 298.394635 -44.735746)
			(xy 298.402755 -44.790922) (xy 298.403264 -44.818808) (xy 298.402755 -44.846694) (xy 298.394635 -44.90187)
			(xy 298.378567 -44.955277) (xy 298.354895 -45.005774) (xy 298.324122 -45.052287) (xy 298.286905 -45.093824)
			(xy 298.244037 -45.129499) (xy 298.196431 -45.158553) (xy 298.145102 -45.180365) (xy 298.091145 -45.194471)
			(xy 298.035708 -45.200571) (xy 297.979974 -45.198534) (xy 297.925131 -45.188404) (xy 297.872347 -45.170397)
			(xy 297.822747 -45.144896) (xy 297.777389 -45.112445) (xy 297.73724 -45.073736) (xy 297.703154 -45.029593)
			(xy 297.675858 -44.980958) (xy 297.655935 -44.928867) (xy 297.643809 -44.87443) (xy 297.639738 -44.818808)
			(xy 297.232154 -44.818808) (xy 297.233282 -44.826653) (xy 297.233282 -44.881147) (xy 297.225527 -44.935085)
			(xy 297.210176 -44.987371) (xy 297.18754 -45.03694) (xy 297.158081 -45.082784) (xy 297.122397 -45.123969)
			(xy 297.081216 -45.159657) (xy 297.035376 -45.189121) (xy 297.006419 -45.202348) (xy 311.045604 -45.202348)
			(xy 311.049675 -45.146726) (xy 311.061801 -45.092289) (xy 311.081724 -45.040198) (xy 311.10902 -44.991563)
			(xy 311.143106 -44.94742) (xy 311.183255 -44.908711) (xy 311.228613 -44.87626) (xy 311.278213 -44.850759)
			(xy 311.330997 -44.832752) (xy 311.38584 -44.822622) (xy 311.441574 -44.820585) (xy 311.497011 -44.826685)
			(xy 311.550968 -44.840791) (xy 311.602297 -44.862603) (xy 311.649903 -44.891657) (xy 311.692771 -44.927332)
			(xy 311.729988 -44.968869) (xy 311.760761 -45.015382) (xy 311.784433 -45.065879) (xy 311.800501 -45.119286)
			(xy 311.808621 -45.174462) (xy 311.80913 -45.202348) (xy 311.808621 -45.230234) (xy 311.800501 -45.28541)
			(xy 311.784433 -45.338817) (xy 311.760761 -45.389314) (xy 311.729988 -45.435827) (xy 311.692771 -45.477364)
			(xy 311.649903 -45.513039) (xy 311.613775 -45.535088) (xy 325.607932 -45.535088) (xy 325.612003 -45.479466)
			(xy 325.624129 -45.425029) (xy 325.644052 -45.372938) (xy 325.671348 -45.324303) (xy 325.705434 -45.28016)
			(xy 325.745583 -45.241451) (xy 325.790941 -45.209) (xy 325.840541 -45.183499) (xy 325.893325 -45.165492)
			(xy 325.948168 -45.155362) (xy 326.003902 -45.153325) (xy 326.059339 -45.159425) (xy 326.113296 -45.173531)
			(xy 326.164625 -45.195343) (xy 326.212231 -45.224397) (xy 326.255099 -45.260072) (xy 326.292316 -45.301609)
			(xy 326.323089 -45.348122) (xy 326.346761 -45.398619) (xy 326.362829 -45.452026) (xy 326.370504 -45.504179)
			(xy 328.221596 -45.504179) (xy 328.221596 -45.452205) (xy 328.229726 -45.40087) (xy 328.245787 -45.35144)
			(xy 328.269383 -45.30513) (xy 328.299933 -45.263082) (xy 328.336684 -45.226331) (xy 328.378732 -45.195781)
			(xy 328.425042 -45.172185) (xy 328.474472 -45.156124) (xy 328.525807 -45.147994) (xy 328.577781 -45.147994)
			(xy 328.629116 -45.156124) (xy 328.678546 -45.172185) (xy 328.707491 -45.186933) (xy 329.92238 -45.186933)
			(xy 329.92238 -45.134959) (xy 329.93051 -45.083624) (xy 329.946571 -45.034194) (xy 329.970167 -44.987884)
			(xy 330.000717 -44.945836) (xy 330.037468 -44.909085) (xy 330.079516 -44.878535) (xy 330.125826 -44.854939)
			(xy 330.175256 -44.838878) (xy 330.226591 -44.830748) (xy 330.278565 -44.830748) (xy 330.3299 -44.838878)
			(xy 330.37933 -44.854939) (xy 330.42564 -44.878535) (xy 330.467688 -44.909085) (xy 330.504439 -44.945836)
			(xy 330.534989 -44.987884) (xy 330.558585 -45.034194) (xy 330.574646 -45.083624) (xy 330.582776 -45.134959)
			(xy 330.583286 -45.160946) (xy 330.582776 -45.186933) (xy 331.55052 -45.186933) (xy 331.55052 -45.134959)
			(xy 331.55865 -45.083624) (xy 331.574711 -45.034194) (xy 331.598307 -44.987884) (xy 331.628857 -44.945836)
			(xy 331.665608 -44.909085) (xy 331.707656 -44.878535) (xy 331.753966 -44.854939) (xy 331.803396 -44.838878)
			(xy 331.854731 -44.830748) (xy 331.906705 -44.830748) (xy 331.95804 -44.838878) (xy 332.00747 -44.854939)
			(xy 332.05378 -44.878535) (xy 332.095828 -44.909085) (xy 332.132579 -44.945836) (xy 332.163129 -44.987884)
			(xy 332.186725 -45.034194) (xy 332.202786 -45.083624) (xy 332.210916 -45.134959) (xy 332.211426 -45.160946)
			(xy 332.210916 -45.186933) (xy 332.202786 -45.238268) (xy 332.186725 -45.287698) (xy 332.163129 -45.334008)
			(xy 332.132579 -45.376056) (xy 332.095828 -45.412807) (xy 332.05378 -45.443357) (xy 332.00747 -45.466953)
			(xy 331.95804 -45.483014) (xy 331.906705 -45.491144) (xy 331.854731 -45.491144) (xy 331.803396 -45.483014)
			(xy 331.753966 -45.466953) (xy 331.707656 -45.443357) (xy 331.665608 -45.412807) (xy 331.628857 -45.376056)
			(xy 331.598307 -45.334008) (xy 331.574711 -45.287698) (xy 331.55865 -45.238268) (xy 331.55052 -45.186933)
			(xy 330.582776 -45.186933) (xy 330.574646 -45.238268) (xy 330.558585 -45.287698) (xy 330.534989 -45.334008)
			(xy 330.504439 -45.376056) (xy 330.467688 -45.412807) (xy 330.42564 -45.443357) (xy 330.37933 -45.466953)
			(xy 330.3299 -45.483014) (xy 330.278565 -45.491144) (xy 330.226591 -45.491144) (xy 330.175256 -45.483014)
			(xy 330.125826 -45.466953) (xy 330.079516 -45.443357) (xy 330.037468 -45.412807) (xy 330.000717 -45.376056)
			(xy 329.970167 -45.334008) (xy 329.946571 -45.287698) (xy 329.93051 -45.238268) (xy 329.92238 -45.186933)
			(xy 328.707491 -45.186933) (xy 328.724856 -45.195781) (xy 328.766904 -45.226331) (xy 328.803655 -45.263082)
			(xy 328.834205 -45.30513) (xy 328.857801 -45.35144) (xy 328.873862 -45.40087) (xy 328.881992 -45.452205)
			(xy 328.882502 -45.478192) (xy 328.881992 -45.504179) (xy 328.873862 -45.555514) (xy 328.857801 -45.604944)
			(xy 328.834205 -45.651254) (xy 328.830152 -45.656833) (xy 329.107548 -45.656833) (xy 329.107548 -45.604859)
			(xy 329.115678 -45.553524) (xy 329.131739 -45.504094) (xy 329.155335 -45.457784) (xy 329.185885 -45.415736)
			(xy 329.222636 -45.378985) (xy 329.264684 -45.348435) (xy 329.310994 -45.324839) (xy 329.360424 -45.308778)
			(xy 329.411759 -45.300648) (xy 329.463733 -45.300648) (xy 329.515068 -45.308778) (xy 329.564498 -45.324839)
			(xy 329.610808 -45.348435) (xy 329.652856 -45.378985) (xy 329.689607 -45.415736) (xy 329.720157 -45.457784)
			(xy 329.743753 -45.504094) (xy 329.759814 -45.553524) (xy 329.767944 -45.604859) (xy 329.768454 -45.630846)
			(xy 329.767944 -45.656833) (xy 330.73518 -45.656833) (xy 330.73518 -45.604859) (xy 330.74331 -45.553524)
			(xy 330.759371 -45.504094) (xy 330.782967 -45.457784) (xy 330.813517 -45.415736) (xy 330.850268 -45.378985)
			(xy 330.892316 -45.348435) (xy 330.938626 -45.324839) (xy 330.988056 -45.308778) (xy 331.039391 -45.300648)
			(xy 331.091365 -45.300648) (xy 331.1427 -45.308778) (xy 331.19213 -45.324839) (xy 331.23844 -45.348435)
			(xy 331.280488 -45.378985) (xy 331.317239 -45.415736) (xy 331.347789 -45.457784) (xy 331.371385 -45.504094)
			(xy 331.387446 -45.553524) (xy 331.395576 -45.604859) (xy 331.396086 -45.630846) (xy 331.395576 -45.656833)
			(xy 332.36332 -45.656833) (xy 332.36332 -45.604859) (xy 332.37145 -45.553524) (xy 332.387511 -45.504094)
			(xy 332.411107 -45.457784) (xy 332.441657 -45.415736) (xy 332.478408 -45.378985) (xy 332.520456 -45.348435)
			(xy 332.566766 -45.324839) (xy 332.616196 -45.308778) (xy 332.667531 -45.300648) (xy 332.719505 -45.300648)
			(xy 332.77084 -45.308778) (xy 332.82027 -45.324839) (xy 332.86658 -45.348435) (xy 332.908628 -45.378985)
			(xy 332.945379 -45.415736) (xy 332.975929 -45.457784) (xy 332.999525 -45.504094) (xy 333.015586 -45.553524)
			(xy 333.023716 -45.604859) (xy 333.024226 -45.630846) (xy 333.023716 -45.656833) (xy 333.015586 -45.708168)
			(xy 332.999525 -45.757598) (xy 332.975929 -45.803908) (xy 332.945379 -45.845956) (xy 332.908628 -45.882707)
			(xy 332.86658 -45.913257) (xy 332.82027 -45.936853) (xy 332.77084 -45.952914) (xy 332.719505 -45.961044)
			(xy 332.667531 -45.961044) (xy 332.616196 -45.952914) (xy 332.566766 -45.936853) (xy 332.520456 -45.913257)
			(xy 332.478408 -45.882707) (xy 332.441657 -45.845956) (xy 332.411107 -45.803908) (xy 332.387511 -45.757598)
			(xy 332.37145 -45.708168) (xy 332.36332 -45.656833) (xy 331.395576 -45.656833) (xy 331.387446 -45.708168)
			(xy 331.371385 -45.757598) (xy 331.347789 -45.803908) (xy 331.317239 -45.845956) (xy 331.280488 -45.882707)
			(xy 331.23844 -45.913257) (xy 331.19213 -45.936853) (xy 331.1427 -45.952914) (xy 331.091365 -45.961044)
			(xy 331.039391 -45.961044) (xy 330.988056 -45.952914) (xy 330.938626 -45.936853) (xy 330.892316 -45.913257)
			(xy 330.850268 -45.882707) (xy 330.813517 -45.845956) (xy 330.782967 -45.803908) (xy 330.759371 -45.757598)
			(xy 330.74331 -45.708168) (xy 330.73518 -45.656833) (xy 329.767944 -45.656833) (xy 329.759814 -45.708168)
			(xy 329.743753 -45.757598) (xy 329.720157 -45.803908) (xy 329.689607 -45.845956) (xy 329.652856 -45.882707)
			(xy 329.610808 -45.913257) (xy 329.564498 -45.936853) (xy 329.515068 -45.952914) (xy 329.463733 -45.961044)
			(xy 329.411759 -45.961044) (xy 329.360424 -45.952914) (xy 329.310994 -45.936853) (xy 329.264684 -45.913257)
			(xy 329.222636 -45.882707) (xy 329.185885 -45.845956) (xy 329.155335 -45.803908) (xy 329.131739 -45.757598)
			(xy 329.115678 -45.708168) (xy 329.107548 -45.656833) (xy 328.830152 -45.656833) (xy 328.803655 -45.693302)
			(xy 328.766904 -45.730053) (xy 328.724856 -45.760603) (xy 328.678546 -45.784199) (xy 328.629116 -45.80026)
			(xy 328.577781 -45.80839) (xy 328.525807 -45.80839) (xy 328.474472 -45.80026) (xy 328.425042 -45.784199)
			(xy 328.378732 -45.760603) (xy 328.336684 -45.730053) (xy 328.299933 -45.693302) (xy 328.269383 -45.651254)
			(xy 328.245787 -45.604944) (xy 328.229726 -45.555514) (xy 328.221596 -45.504179) (xy 326.370504 -45.504179)
			(xy 326.370949 -45.507202) (xy 326.371458 -45.535088) (xy 326.370949 -45.562974) (xy 326.362829 -45.61815)
			(xy 326.346761 -45.671557) (xy 326.323089 -45.722054) (xy 326.292316 -45.768567) (xy 326.255099 -45.810104)
			(xy 326.212231 -45.845779) (xy 326.164625 -45.874833) (xy 326.113296 -45.896645) (xy 326.059339 -45.910751)
			(xy 326.003902 -45.916851) (xy 325.948168 -45.914814) (xy 325.893325 -45.904684) (xy 325.840541 -45.886677)
			(xy 325.790941 -45.861176) (xy 325.745583 -45.828725) (xy 325.705434 -45.790016) (xy 325.671348 -45.745873)
			(xy 325.644052 -45.697238) (xy 325.624129 -45.645147) (xy 325.612003 -45.59071) (xy 325.607932 -45.535088)
			(xy 311.613775 -45.535088) (xy 311.602297 -45.542093) (xy 311.550968 -45.563905) (xy 311.497011 -45.578011)
			(xy 311.441574 -45.584111) (xy 311.38584 -45.582074) (xy 311.330997 -45.571944) (xy 311.278213 -45.553937)
			(xy 311.228613 -45.528436) (xy 311.183255 -45.495985) (xy 311.143106 -45.457276) (xy 311.10902 -45.413133)
			(xy 311.081724 -45.364498) (xy 311.061801 -45.312407) (xy 311.049675 -45.25797) (xy 311.045604 -45.202348)
			(xy 297.006419 -45.202348) (xy 296.985809 -45.211762) (xy 296.933524 -45.227119) (xy 296.879586 -45.234879)
			(xy 296.85234 -45.235368) (xy 296.822918 -45.234811) (xy 296.764773 -45.225768) (xy 296.708706 -45.207905)
			(xy 296.656046 -45.181647) (xy 296.608042 -45.147616) (xy 296.565831 -45.106618) (xy 296.530415 -45.059625)
			(xy 296.516044 -45.033946) (xy 296.508454 -45.020915) (xy 296.487057 -44.999681) (xy 296.4604 -44.985607)
			(xy 296.430798 -44.979916) (xy 296.400823 -44.983101) (xy 296.373078 -44.994887) (xy 296.349974 -45.014248)
			(xy 296.341292 -45.02658) (xy 296.326112 -45.049001) (xy 296.290441 -45.089734) (xy 296.249367 -45.125013)
			(xy 296.203717 -45.154129) (xy 296.154408 -45.176496) (xy 296.102431 -45.191664) (xy 296.048832 -45.19933)
			(xy 296.02176 -45.199808) (xy 295.994511 -45.199319) (xy 295.940567 -45.191558) (xy 295.888277 -45.1762)
			(xy 295.838705 -45.153556) (xy 295.79286 -45.124089) (xy 295.751674 -45.088397) (xy 295.715987 -45.047208)
			(xy 295.686524 -45.00136) (xy 295.663886 -44.951785) (xy 295.648533 -44.899494) (xy 295.640778 -44.845549)
			(xy 287.465445 -44.845549) (xy 286.372046 -45.938948) (xy 292.408862 -45.938948) (xy 292.412933 -45.883326)
			(xy 292.425059 -45.828889) (xy 292.444982 -45.776798) (xy 292.472278 -45.728163) (xy 292.506364 -45.68402)
			(xy 292.546513 -45.645311) (xy 292.591871 -45.61286) (xy 292.641471 -45.587359) (xy 292.694255 -45.569352)
			(xy 292.749098 -45.559222) (xy 292.804832 -45.557185) (xy 292.860269 -45.563285) (xy 292.914226 -45.577391)
			(xy 292.965555 -45.599203) (xy 293.013161 -45.628257) (xy 293.056029 -45.663932) (xy 293.093246 -45.705469)
			(xy 293.124019 -45.751982) (xy 293.147691 -45.802479) (xy 293.163759 -45.855886) (xy 293.171879 -45.911062)
			(xy 293.172388 -45.938948) (xy 294.440862 -45.938948) (xy 294.444933 -45.883326) (xy 294.457059 -45.828889)
			(xy 294.476982 -45.776798) (xy 294.504278 -45.728163) (xy 294.538364 -45.68402) (xy 294.578513 -45.645311)
			(xy 294.623871 -45.61286) (xy 294.673471 -45.587359) (xy 294.726255 -45.569352) (xy 294.781098 -45.559222)
			(xy 294.836832 -45.557185) (xy 294.892269 -45.563285) (xy 294.946226 -45.577391) (xy 294.997555 -45.599203)
			(xy 295.045161 -45.628257) (xy 295.088029 -45.663932) (xy 295.125246 -45.705469) (xy 295.156019 -45.751982)
			(xy 295.179691 -45.802479) (xy 295.195759 -45.855886) (xy 295.203879 -45.911062) (xy 295.204388 -45.938948)
			(xy 295.203879 -45.966834) (xy 295.195759 -46.02201) (xy 295.179691 -46.075417) (xy 295.156019 -46.125914)
			(xy 295.155477 -46.126733) (xy 329.921618 -46.126733) (xy 329.921618 -46.074759) (xy 329.929748 -46.023424)
			(xy 329.945809 -45.973994) (xy 329.969405 -45.927684) (xy 329.999955 -45.885636) (xy 330.036706 -45.848885)
			(xy 330.078754 -45.818335) (xy 330.125064 -45.794739) (xy 330.174494 -45.778678) (xy 330.225829 -45.770548)
			(xy 330.277803 -45.770548) (xy 330.329138 -45.778678) (xy 330.378568 -45.794739) (xy 330.424878 -45.818335)
			(xy 330.466926 -45.848885) (xy 330.503677 -45.885636) (xy 330.534227 -45.927684) (xy 330.557823 -45.973994)
			(xy 330.573884 -46.023424) (xy 330.582014 -46.074759) (xy 330.582524 -46.100746) (xy 330.582014 -46.126733)
			(xy 331.55052 -46.126733) (xy 331.55052 -46.074759) (xy 331.55865 -46.023424) (xy 331.574711 -45.973994)
			(xy 331.598307 -45.927684) (xy 331.628857 -45.885636) (xy 331.665608 -45.848885) (xy 331.707656 -45.818335)
			(xy 331.753966 -45.794739) (xy 331.803396 -45.778678) (xy 331.854731 -45.770548) (xy 331.906705 -45.770548)
			(xy 331.95804 -45.778678) (xy 332.00747 -45.794739) (xy 332.05378 -45.818335) (xy 332.095828 -45.848885)
			(xy 332.132579 -45.885636) (xy 332.163129 -45.927684) (xy 332.186725 -45.973994) (xy 332.202786 -46.023424)
			(xy 332.210912 -46.074731) (xy 333.178747 -46.074731) (xy 333.186873 -46.023406) (xy 333.202928 -45.973984)
			(xy 333.226517 -45.927682) (xy 333.257057 -45.88564) (xy 333.293798 -45.848893) (xy 333.335835 -45.818345)
			(xy 333.382134 -45.794749) (xy 333.431553 -45.778686) (xy 333.482876 -45.770551) (xy 333.508858 -45.770038)
			(xy 333.540449 -45.770758) (xy 333.602476 -45.782779) (xy 333.632048 -45.793914) (xy 333.646191 -45.79911)
			(xy 333.676191 -45.801766) (xy 333.705663 -45.795557) (xy 333.732042 -45.781024) (xy 333.753037 -45.759429)
			(xy 333.766821 -45.732651) (xy 333.772197 -45.703016) (xy 333.770986 -45.687996) (xy 333.769935 -45.678506)
			(xy 333.768791 -45.659444) (xy 333.7687 -45.649896) (xy 333.769206 -45.623909) (xy 333.777337 -45.572576)
			(xy 333.793398 -45.523147) (xy 333.816994 -45.476838) (xy 333.847543 -45.434791) (xy 333.884294 -45.398041)
			(xy 333.926342 -45.367492) (xy 333.97265 -45.343896) (xy 334.02208 -45.327836) (xy 334.073413 -45.319706)
			(xy 334.125387 -45.319706) (xy 334.17672 -45.327836) (xy 334.22615 -45.343896) (xy 334.272458 -45.367492)
			(xy 334.314506 -45.398041) (xy 334.351257 -45.434791) (xy 334.381806 -45.476838) (xy 334.405402 -45.523147)
			(xy 334.421463 -45.572576) (xy 334.429594 -45.623909) (xy 334.429595 -45.656833) (xy 339.96046 -45.656833)
			(xy 339.96046 -45.604859) (xy 339.96859 -45.553524) (xy 339.984651 -45.504094) (xy 340.008247 -45.457784)
			(xy 340.038797 -45.415736) (xy 340.075548 -45.378985) (xy 340.117596 -45.348435) (xy 340.163906 -45.324839)
			(xy 340.213336 -45.308778) (xy 340.264671 -45.300648) (xy 340.316645 -45.300648) (xy 340.36798 -45.308778)
			(xy 340.41741 -45.324839) (xy 340.46372 -45.348435) (xy 340.505768 -45.378985) (xy 340.542519 -45.415736)
			(xy 340.573069 -45.457784) (xy 340.596665 -45.504094) (xy 340.612726 -45.553524) (xy 340.620856 -45.604859)
			(xy 340.621366 -45.630846) (xy 340.620856 -45.656833) (xy 340.612726 -45.708168) (xy 340.596665 -45.757598)
			(xy 340.573069 -45.803908) (xy 340.542519 -45.845956) (xy 340.505768 -45.882707) (xy 340.46372 -45.913257)
			(xy 340.41741 -45.936853) (xy 340.36798 -45.952914) (xy 340.316645 -45.961044) (xy 340.264671 -45.961044)
			(xy 340.213336 -45.952914) (xy 340.163906 -45.936853) (xy 340.117596 -45.913257) (xy 340.075548 -45.882707)
			(xy 340.038797 -45.845956) (xy 340.008247 -45.803908) (xy 339.984651 -45.757598) (xy 339.96859 -45.708168)
			(xy 339.96046 -45.656833) (xy 334.429595 -45.656833) (xy 334.429595 -45.675883) (xy 334.421465 -45.727216)
			(xy 334.405405 -45.776646) (xy 334.38181 -45.822955) (xy 334.351262 -45.865003) (xy 334.314512 -45.901754)
			(xy 334.272465 -45.932304) (xy 334.226157 -45.955901) (xy 334.176728 -45.971962) (xy 334.125395 -45.980094)
			(xy 334.099408 -45.980604) (xy 334.067817 -45.979897) (xy 334.005789 -45.967868) (xy 333.976218 -45.956728)
			(xy 333.962032 -45.95167) (xy 333.932055 -45.949004) (xy 333.902603 -45.955196) (xy 333.876238 -45.969707)
			(xy 333.855249 -45.991276) (xy 333.841463 -46.018027) (xy 333.836077 -46.047637) (xy 333.83728 -46.062646)
			(xy 333.838335 -46.072136) (xy 333.839476 -46.091198) (xy 333.839566 -46.100746) (xy 333.839049 -46.126728)
			(xy 333.830913 -46.178051) (xy 333.814849 -46.22747) (xy 333.791253 -46.273768) (xy 333.760705 -46.315805)
			(xy 333.723957 -46.352545) (xy 333.681914 -46.383085) (xy 333.635612 -46.406673) (xy 333.58619 -46.422728)
			(xy 333.534865 -46.430854) (xy 333.482901 -46.430851) (xy 333.431577 -46.42272) (xy 333.382157 -46.40666)
			(xy 333.335857 -46.383068) (xy 333.293818 -46.352524) (xy 333.257074 -46.315779) (xy 333.22653 -46.273739)
			(xy 333.202938 -46.227439) (xy 333.186879 -46.178019) (xy 333.178749 -46.126695) (xy 333.178747 -46.074731)
			(xy 332.210912 -46.074731) (xy 332.210916 -46.074759) (xy 332.211426 -46.100746) (xy 332.210916 -46.126733)
			(xy 332.202786 -46.178068) (xy 332.186725 -46.227498) (xy 332.163129 -46.273808) (xy 332.132579 -46.315856)
			(xy 332.095828 -46.352607) (xy 332.05378 -46.383157) (xy 332.00747 -46.406753) (xy 331.95804 -46.422814)
			(xy 331.906705 -46.430944) (xy 331.854731 -46.430944) (xy 331.803396 -46.422814) (xy 331.753966 -46.406753)
			(xy 331.707656 -46.383157) (xy 331.665608 -46.352607) (xy 331.628857 -46.315856) (xy 331.598307 -46.273808)
			(xy 331.574711 -46.227498) (xy 331.55865 -46.178068) (xy 331.55052 -46.126733) (xy 330.582014 -46.126733)
			(xy 330.573884 -46.178068) (xy 330.557823 -46.227498) (xy 330.534227 -46.273808) (xy 330.503677 -46.315856)
			(xy 330.466926 -46.352607) (xy 330.424878 -46.383157) (xy 330.378568 -46.406753) (xy 330.329138 -46.422814)
			(xy 330.277803 -46.430944) (xy 330.225829 -46.430944) (xy 330.174494 -46.422814) (xy 330.125064 -46.406753)
			(xy 330.078754 -46.383157) (xy 330.036706 -46.352607) (xy 329.999955 -46.315856) (xy 329.969405 -46.273808)
			(xy 329.945809 -46.227498) (xy 329.929748 -46.178068) (xy 329.921618 -46.126733) (xy 295.155477 -46.126733)
			(xy 295.125246 -46.172427) (xy 295.088029 -46.213964) (xy 295.045161 -46.249639) (xy 294.997555 -46.278693)
			(xy 294.946226 -46.300505) (xy 294.892269 -46.314611) (xy 294.836832 -46.320711) (xy 294.781098 -46.318674)
			(xy 294.726255 -46.308544) (xy 294.673471 -46.290537) (xy 294.623871 -46.265036) (xy 294.578513 -46.232585)
			(xy 294.538364 -46.193876) (xy 294.504278 -46.149733) (xy 294.476982 -46.101098) (xy 294.457059 -46.049007)
			(xy 294.444933 -45.99457) (xy 294.440862 -45.938948) (xy 293.172388 -45.938948) (xy 293.171879 -45.966834)
			(xy 293.163759 -46.02201) (xy 293.147691 -46.075417) (xy 293.124019 -46.125914) (xy 293.093246 -46.172427)
			(xy 293.056029 -46.213964) (xy 293.013161 -46.249639) (xy 292.965555 -46.278693) (xy 292.914226 -46.300505)
			(xy 292.860269 -46.314611) (xy 292.804832 -46.320711) (xy 292.749098 -46.318674) (xy 292.694255 -46.308544)
			(xy 292.641471 -46.290537) (xy 292.591871 -46.265036) (xy 292.546513 -46.232585) (xy 292.506364 -46.193876)
			(xy 292.472278 -46.149733) (xy 292.444982 -46.101098) (xy 292.425059 -46.049007) (xy 292.412933 -45.99457)
			(xy 292.408862 -45.938948) (xy 286.372046 -45.938948) (xy 284.822646 -47.488348) (xy 299.769782 -47.488348)
			(xy 299.773853 -47.432726) (xy 299.785979 -47.378289) (xy 299.805902 -47.326198) (xy 299.833198 -47.277563)
			(xy 299.867284 -47.23342) (xy 299.907433 -47.194711) (xy 299.952791 -47.16226) (xy 300.002391 -47.136759)
			(xy 300.055175 -47.118752) (xy 300.110018 -47.108622) (xy 300.165752 -47.106585) (xy 300.221189 -47.112685)
			(xy 300.275146 -47.126791) (xy 300.326475 -47.148603) (xy 300.374081 -47.177657) (xy 300.416949 -47.213332)
			(xy 300.454166 -47.254869) (xy 300.484939 -47.301382) (xy 300.508611 -47.351879) (xy 300.524679 -47.405286)
			(xy 300.532799 -47.460462) (xy 300.533308 -47.488348) (xy 300.532799 -47.516234) (xy 300.524679 -47.57141)
			(xy 300.508611 -47.624817) (xy 300.484939 -47.675314) (xy 300.454166 -47.721827) (xy 300.416949 -47.763364)
			(xy 300.374081 -47.799039) (xy 300.326475 -47.828093) (xy 300.275146 -47.849905) (xy 300.221189 -47.864011)
			(xy 300.165752 -47.870111) (xy 300.110018 -47.868074) (xy 300.055175 -47.857944) (xy 300.002391 -47.839937)
			(xy 299.952791 -47.814436) (xy 299.907433 -47.781985) (xy 299.867284 -47.743276) (xy 299.833198 -47.699133)
			(xy 299.805902 -47.650498) (xy 299.785979 -47.598407) (xy 299.773853 -47.54397) (xy 299.769782 -47.488348)
			(xy 284.822646 -47.488348) (xy 284.314646 -47.996348) (xy 300.483522 -47.996348) (xy 300.487593 -47.940726)
			(xy 300.499719 -47.886289) (xy 300.519642 -47.834198) (xy 300.546938 -47.785563) (xy 300.581024 -47.74142)
			(xy 300.621173 -47.702711) (xy 300.666531 -47.67026) (xy 300.716131 -47.644759) (xy 300.768915 -47.626752)
			(xy 300.823758 -47.616622) (xy 300.879492 -47.614585) (xy 300.934929 -47.620685) (xy 300.988886 -47.634791)
			(xy 301.040215 -47.656603) (xy 301.087821 -47.685657) (xy 301.130689 -47.721332) (xy 301.167906 -47.762869)
			(xy 301.198679 -47.809382) (xy 301.222351 -47.859879) (xy 301.238419 -47.913286) (xy 301.246539 -47.968462)
			(xy 301.247048 -47.996348) (xy 301.246552 -48.023548) (xy 302.768026 -48.023548) (xy 302.768026 -47.969052)
			(xy 302.775782 -47.915111) (xy 302.791135 -47.862823) (xy 302.813773 -47.813252) (xy 302.843236 -47.767408)
			(xy 302.878923 -47.726223) (xy 302.920108 -47.690536) (xy 302.965952 -47.661073) (xy 303.015523 -47.638435)
			(xy 303.067811 -47.623082) (xy 303.121752 -47.615326) (xy 303.149 -47.61484) (xy 303.177738 -47.61538)
			(xy 303.234564 -47.624001) (xy 303.289454 -47.641048) (xy 303.341166 -47.666136) (xy 303.38853 -47.698696)
			(xy 303.409858 -47.717964) (xy 303.421392 -47.728036) (xy 303.448938 -47.741378) (xy 303.4792 -47.745963)
			(xy 303.509462 -47.741378) (xy 303.537008 -47.728036) (xy 303.548542 -47.717964) (xy 303.569873 -47.698698)
			(xy 303.617233 -47.66613) (xy 303.668944 -47.641036) (xy 303.723834 -47.623984) (xy 303.780661 -47.615361)
			(xy 303.8094 -47.61484) (xy 303.836655 -47.61523) (xy 303.890609 -47.622987) (xy 303.942911 -47.638344)
			(xy 303.992494 -47.660988) (xy 304.03835 -47.690458) (xy 304.068922 -47.716948) (xy 304.601372 -47.716948)
			(xy 304.601898 -47.688031) (xy 304.610621 -47.630859) (xy 304.627876 -47.575659) (xy 304.653266 -47.523697)
			(xy 304.68621 -47.476163) (xy 304.725952 -47.434147) (xy 304.748438 -47.415958) (xy 304.7602 -47.406011)
			(xy 304.777727 -47.380703) (xy 304.786913 -47.351321) (xy 304.786921 -47.320537) (xy 304.777753 -47.29115)
			(xy 304.760241 -47.265832) (xy 304.748438 -47.255938) (xy 304.725981 -47.237716) (xy 304.686242 -47.195704)
			(xy 304.653299 -47.148176) (xy 304.627906 -47.09622) (xy 304.610644 -47.041028) (xy 304.60191 -46.983862)
			(xy 304.601372 -46.954948) (xy 304.6019 -46.927697) (xy 304.60965 -46.87375) (xy 304.624999 -46.821454)
			(xy 304.647634 -46.771876) (xy 304.677095 -46.726023) (xy 304.712782 -46.68483) (xy 304.753969 -46.649136)
			(xy 304.799816 -46.619667) (xy 304.84939 -46.597023) (xy 304.901683 -46.581664) (xy 304.955629 -46.573905)
			(xy 304.98288 -46.57344) (xy 305.01107 -46.573926) (xy 305.066834 -46.582242) (xy 305.120769 -46.598666)
			(xy 305.171703 -46.622841) (xy 305.21853 -46.654243) (xy 305.26023 -46.692188) (xy 305.295899 -46.735851)
			(xy 305.32476 -46.784285) (xy 305.33594 -46.810168) (xy 305.341976 -46.823344) (xy 305.360028 -46.845991)
			(xy 305.383714 -46.862655) (xy 305.411127 -46.871995) (xy 305.440061 -46.873258) (xy 305.468184 -46.866343)
			(xy 305.493232 -46.851806) (xy 305.50358 -46.841664) (xy 305.521621 -46.823255) (xy 305.561842 -46.791018)
			(xy 305.60604 -46.764495) (xy 305.653408 -46.744169) (xy 305.703083 -46.73041) (xy 305.754159 -46.723469)
			(xy 305.779932 -46.723046) (xy 305.807178 -46.723626) (xy 305.861116 -46.731386) (xy 305.913401 -46.746742)
			(xy 305.962968 -46.769382) (xy 306.008809 -46.798845) (xy 306.04999 -46.834533) (xy 306.066292 -46.853348)
			(xy 324.253604 -46.853348) (xy 324.257675 -46.797726) (xy 324.269801 -46.743289) (xy 324.289724 -46.691198)
			(xy 324.31702 -46.642563) (xy 324.351106 -46.59842) (xy 324.391255 -46.559711) (xy 324.436613 -46.52726)
			(xy 324.486213 -46.501759) (xy 324.538997 -46.483752) (xy 324.59384 -46.473622) (xy 324.649574 -46.471585)
			(xy 324.705011 -46.477685) (xy 324.758968 -46.491791) (xy 324.810297 -46.513603) (xy 324.857903 -46.542657)
			(xy 324.900771 -46.578332) (xy 324.917169 -46.596633) (xy 328.29551 -46.596633) (xy 328.29551 -46.544659)
			(xy 328.30364 -46.493324) (xy 328.319701 -46.443894) (xy 328.343297 -46.397584) (xy 328.373847 -46.355536)
			(xy 328.410598 -46.318785) (xy 328.452646 -46.288235) (xy 328.498956 -46.264639) (xy 328.548386 -46.248578)
			(xy 328.599721 -46.240448) (xy 328.651695 -46.240448) (xy 328.70303 -46.248578) (xy 328.75246 -46.264639)
			(xy 328.79877 -46.288235) (xy 328.840818 -46.318785) (xy 328.877569 -46.355536) (xy 328.908119 -46.397584)
			(xy 328.931715 -46.443894) (xy 328.947776 -46.493324) (xy 328.955906 -46.544659) (xy 328.956416 -46.570646)
			(xy 328.955906 -46.596633) (xy 329.107548 -46.596633) (xy 329.107548 -46.544659) (xy 329.115678 -46.493324)
			(xy 329.131739 -46.443894) (xy 329.155335 -46.397584) (xy 329.185885 -46.355536) (xy 329.222636 -46.318785)
			(xy 329.264684 -46.288235) (xy 329.310994 -46.264639) (xy 329.360424 -46.248578) (xy 329.411759 -46.240448)
			(xy 329.463733 -46.240448) (xy 329.515068 -46.248578) (xy 329.564498 -46.264639) (xy 329.610808 -46.288235)
			(xy 329.652856 -46.318785) (xy 329.689607 -46.355536) (xy 329.720157 -46.397584) (xy 329.743753 -46.443894)
			(xy 329.759814 -46.493324) (xy 329.767944 -46.544659) (xy 329.768454 -46.570646) (xy 329.767944 -46.596633)
			(xy 330.73518 -46.596633) (xy 330.73518 -46.544659) (xy 330.74331 -46.493324) (xy 330.759371 -46.443894)
			(xy 330.782967 -46.397584) (xy 330.813517 -46.355536) (xy 330.850268 -46.318785) (xy 330.892316 -46.288235)
			(xy 330.938626 -46.264639) (xy 330.988056 -46.248578) (xy 331.039391 -46.240448) (xy 331.091365 -46.240448)
			(xy 331.1427 -46.248578) (xy 331.19213 -46.264639) (xy 331.23844 -46.288235) (xy 331.280488 -46.318785)
			(xy 331.317239 -46.355536) (xy 331.347789 -46.397584) (xy 331.371385 -46.443894) (xy 331.381811 -46.475983)
			(xy 334.56931 -46.475983) (xy 334.56931 -46.424009) (xy 334.57744 -46.372674) (xy 334.593501 -46.323244)
			(xy 334.617097 -46.276934) (xy 334.647647 -46.234886) (xy 334.684398 -46.198135) (xy 334.726446 -46.167585)
			(xy 334.772756 -46.143989) (xy 334.822186 -46.127928) (xy 334.873521 -46.119798) (xy 334.925495 -46.119798)
			(xy 334.97683 -46.127928) (xy 335.02626 -46.143989) (xy 335.07257 -46.167585) (xy 335.114618 -46.198135)
			(xy 335.151369 -46.234886) (xy 335.181919 -46.276934) (xy 335.205515 -46.323244) (xy 335.221576 -46.372674)
			(xy 335.229706 -46.424009) (xy 335.230216 -46.449996) (xy 335.229706 -46.475983) (xy 336.96961 -46.475983)
			(xy 336.96961 -46.424009) (xy 336.97774 -46.372674) (xy 336.993801 -46.323244) (xy 337.017397 -46.276934)
			(xy 337.047947 -46.234886) (xy 337.084698 -46.198135) (xy 337.126746 -46.167585) (xy 337.173056 -46.143989)
			(xy 337.222486 -46.127928) (xy 337.273821 -46.119798) (xy 337.325795 -46.119798) (xy 337.37713 -46.127928)
			(xy 337.42656 -46.143989) (xy 337.47287 -46.167585) (xy 337.514918 -46.198135) (xy 337.551669 -46.234886)
			(xy 337.582219 -46.276934) (xy 337.605815 -46.323244) (xy 337.621876 -46.372674) (xy 337.630006 -46.424009)
			(xy 337.630516 -46.449996) (xy 337.630006 -46.475983) (xy 337.621876 -46.527318) (xy 337.605815 -46.576748)
			(xy 337.595683 -46.596633) (xy 339.96046 -46.596633) (xy 339.96046 -46.544659) (xy 339.96859 -46.493324)
			(xy 339.984651 -46.443894) (xy 340.008247 -46.397584) (xy 340.038797 -46.355536) (xy 340.075548 -46.318785)
			(xy 340.117596 -46.288235) (xy 340.163906 -46.264639) (xy 340.213336 -46.248578) (xy 340.264671 -46.240448)
			(xy 340.316645 -46.240448) (xy 340.36798 -46.248578) (xy 340.41741 -46.264639) (xy 340.46372 -46.288235)
			(xy 340.505768 -46.318785) (xy 340.542519 -46.355536) (xy 340.573069 -46.397584) (xy 340.596665 -46.443894)
			(xy 340.612726 -46.493324) (xy 340.620856 -46.544659) (xy 340.621366 -46.570646) (xy 340.620856 -46.596633)
			(xy 340.612726 -46.647968) (xy 340.596665 -46.697398) (xy 340.573069 -46.743708) (xy 340.542519 -46.785756)
			(xy 340.505768 -46.822507) (xy 340.46372 -46.853057) (xy 340.41741 -46.876653) (xy 340.36798 -46.892714)
			(xy 340.316645 -46.900844) (xy 340.264671 -46.900844) (xy 340.213336 -46.892714) (xy 340.163906 -46.876653)
			(xy 340.117596 -46.853057) (xy 340.075548 -46.822507) (xy 340.038797 -46.785756) (xy 340.008247 -46.743708)
			(xy 339.984651 -46.697398) (xy 339.96859 -46.647968) (xy 339.96046 -46.596633) (xy 337.595683 -46.596633)
			(xy 337.582219 -46.623058) (xy 337.551669 -46.665106) (xy 337.514918 -46.701857) (xy 337.47287 -46.732407)
			(xy 337.42656 -46.756003) (xy 337.37713 -46.772064) (xy 337.325795 -46.780194) (xy 337.273821 -46.780194)
			(xy 337.222486 -46.772064) (xy 337.173056 -46.756003) (xy 337.126746 -46.732407) (xy 337.084698 -46.701857)
			(xy 337.047947 -46.665106) (xy 337.017397 -46.623058) (xy 336.993801 -46.576748) (xy 336.97774 -46.527318)
			(xy 336.96961 -46.475983) (xy 335.229706 -46.475983) (xy 335.221576 -46.527318) (xy 335.205515 -46.576748)
			(xy 335.181919 -46.623058) (xy 335.151369 -46.665106) (xy 335.114618 -46.701857) (xy 335.07257 -46.732407)
			(xy 335.02626 -46.756003) (xy 334.97683 -46.772064) (xy 334.925495 -46.780194) (xy 334.873521 -46.780194)
			(xy 334.822186 -46.772064) (xy 334.772756 -46.756003) (xy 334.726446 -46.732407) (xy 334.684398 -46.701857)
			(xy 334.647647 -46.665106) (xy 334.617097 -46.623058) (xy 334.593501 -46.576748) (xy 334.57744 -46.527318)
			(xy 334.56931 -46.475983) (xy 331.381811 -46.475983) (xy 331.387446 -46.493324) (xy 331.395576 -46.544659)
			(xy 331.396086 -46.570646) (xy 331.395576 -46.596633) (xy 331.387446 -46.647968) (xy 331.371385 -46.697398)
			(xy 331.347789 -46.743708) (xy 331.317239 -46.785756) (xy 331.280488 -46.822507) (xy 331.23844 -46.853057)
			(xy 331.19213 -46.876653) (xy 331.1427 -46.892714) (xy 331.091365 -46.900844) (xy 331.039391 -46.900844)
			(xy 330.988056 -46.892714) (xy 330.938626 -46.876653) (xy 330.892316 -46.853057) (xy 330.850268 -46.822507)
			(xy 330.813517 -46.785756) (xy 330.782967 -46.743708) (xy 330.759371 -46.697398) (xy 330.74331 -46.647968)
			(xy 330.73518 -46.596633) (xy 329.767944 -46.596633) (xy 329.759814 -46.647968) (xy 329.743753 -46.697398)
			(xy 329.720157 -46.743708) (xy 329.689607 -46.785756) (xy 329.652856 -46.822507) (xy 329.610808 -46.853057)
			(xy 329.564498 -46.876653) (xy 329.515068 -46.892714) (xy 329.463733 -46.900844) (xy 329.411759 -46.900844)
			(xy 329.360424 -46.892714) (xy 329.310994 -46.876653) (xy 329.264684 -46.853057) (xy 329.222636 -46.822507)
			(xy 329.185885 -46.785756) (xy 329.155335 -46.743708) (xy 329.131739 -46.697398) (xy 329.115678 -46.647968)
			(xy 329.107548 -46.596633) (xy 328.955906 -46.596633) (xy 328.947776 -46.647968) (xy 328.931715 -46.697398)
			(xy 328.908119 -46.743708) (xy 328.877569 -46.785756) (xy 328.840818 -46.822507) (xy 328.79877 -46.853057)
			(xy 328.75246 -46.876653) (xy 328.70303 -46.892714) (xy 328.651695 -46.900844) (xy 328.599721 -46.900844)
			(xy 328.548386 -46.892714) (xy 328.498956 -46.876653) (xy 328.452646 -46.853057) (xy 328.410598 -46.822507)
			(xy 328.373847 -46.785756) (xy 328.343297 -46.743708) (xy 328.319701 -46.697398) (xy 328.30364 -46.647968)
			(xy 328.29551 -46.596633) (xy 324.917169 -46.596633) (xy 324.937988 -46.619869) (xy 324.968761 -46.666382)
			(xy 324.992433 -46.716879) (xy 325.008501 -46.770286) (xy 325.016621 -46.825462) (xy 325.01713 -46.853348)
			(xy 325.016621 -46.881234) (xy 325.008501 -46.93641) (xy 324.992433 -46.989817) (xy 324.968761 -47.040314)
			(xy 324.951415 -47.066533) (xy 329.92238 -47.066533) (xy 329.92238 -47.014559) (xy 329.93051 -46.963224)
			(xy 329.946571 -46.913794) (xy 329.970167 -46.867484) (xy 330.000717 -46.825436) (xy 330.037468 -46.788685)
			(xy 330.079516 -46.758135) (xy 330.125826 -46.734539) (xy 330.175256 -46.718478) (xy 330.226591 -46.710348)
			(xy 330.278565 -46.710348) (xy 330.3299 -46.718478) (xy 330.37933 -46.734539) (xy 330.42564 -46.758135)
			(xy 330.467688 -46.788685) (xy 330.504439 -46.825436) (xy 330.534989 -46.867484) (xy 330.558585 -46.913794)
			(xy 330.574646 -46.963224) (xy 330.582776 -47.014559) (xy 330.583286 -47.040546) (xy 330.582776 -47.066533)
			(xy 331.55052 -47.066533) (xy 331.55052 -47.014559) (xy 331.55865 -46.963224) (xy 331.574711 -46.913794)
			(xy 331.598307 -46.867484) (xy 331.628857 -46.825436) (xy 331.665608 -46.788685) (xy 331.707656 -46.758135)
			(xy 331.753966 -46.734539) (xy 331.803396 -46.718478) (xy 331.854731 -46.710348) (xy 331.906705 -46.710348)
			(xy 331.95804 -46.718478) (xy 332.00747 -46.734539) (xy 332.05378 -46.758135) (xy 332.095828 -46.788685)
			(xy 332.132579 -46.825436) (xy 332.163129 -46.867484) (xy 332.186725 -46.913794) (xy 332.202786 -46.963224)
			(xy 332.210916 -47.014559) (xy 332.211426 -47.040546) (xy 332.210917 -47.066481) (xy 333.178748 -47.066481)
			(xy 333.178748 -47.014519) (xy 333.186876 -46.963195) (xy 333.202932 -46.913775) (xy 333.226521 -46.867475)
			(xy 333.257062 -46.825435) (xy 333.293803 -46.788689) (xy 333.335839 -46.758143) (xy 333.382136 -46.734548)
			(xy 333.431554 -46.718486) (xy 333.482877 -46.710351) (xy 333.508858 -46.709838) (xy 333.53607 -46.710407)
			(xy 333.589755 -46.719339) (xy 333.641255 -46.736937) (xy 333.689181 -46.762726) (xy 333.732239 -46.796011)
			(xy 333.769271 -46.835894) (xy 333.799275 -46.881299) (xy 333.810864 -46.905926) (xy 333.816857 -46.91832)
			(xy 333.834393 -46.939532) (xy 333.856947 -46.955305) (xy 333.882888 -46.964499) (xy 333.91034 -46.966449)
			(xy 333.93732 -46.961014) (xy 333.949802 -46.955202) (xy 333.973114 -46.94393) (xy 334.022373 -46.92797)
			(xy 334.073518 -46.919891) (xy 334.099408 -46.919388) (xy 334.125394 -46.919906) (xy 334.176727 -46.928038)
			(xy 334.226156 -46.944099) (xy 334.272464 -46.967695) (xy 334.314511 -46.998245) (xy 334.351261 -47.034995)
			(xy 334.381809 -47.077043) (xy 334.405404 -47.123351) (xy 334.421464 -47.17278) (xy 334.429595 -47.224114)
			(xy 334.429595 -47.276083) (xy 334.56931 -47.276083) (xy 334.56931 -47.224109) (xy 334.57744 -47.172774)
			(xy 334.593501 -47.123344) (xy 334.617097 -47.077034) (xy 334.647647 -47.034986) (xy 334.684398 -46.998235)
			(xy 334.726446 -46.967685) (xy 334.772756 -46.944089) (xy 334.822186 -46.928028) (xy 334.873521 -46.919898)
			(xy 334.925495 -46.919898) (xy 334.97683 -46.928028) (xy 335.02626 -46.944089) (xy 335.07257 -46.967685)
			(xy 335.114618 -46.998235) (xy 335.151369 -47.034986) (xy 335.181919 -47.077034) (xy 335.205515 -47.123344)
			(xy 335.221576 -47.172774) (xy 335.229706 -47.224109) (xy 335.230216 -47.250096) (xy 335.229706 -47.276083)
			(xy 336.96961 -47.276083) (xy 336.96961 -47.224109) (xy 336.97774 -47.172774) (xy 336.993801 -47.123344)
			(xy 337.017397 -47.077034) (xy 337.047947 -47.034986) (xy 337.084698 -46.998235) (xy 337.126746 -46.967685)
			(xy 337.173056 -46.944089) (xy 337.222486 -46.928028) (xy 337.273821 -46.919898) (xy 337.325795 -46.919898)
			(xy 337.37713 -46.928028) (xy 337.42656 -46.944089) (xy 337.47287 -46.967685) (xy 337.514918 -46.998235)
			(xy 337.551669 -47.034986) (xy 337.582219 -47.077034) (xy 337.605815 -47.123344) (xy 337.621876 -47.172774)
			(xy 337.630006 -47.224109) (xy 337.630516 -47.250096) (xy 337.630006 -47.276083) (xy 337.621876 -47.327418)
			(xy 337.605815 -47.376848) (xy 337.582219 -47.423158) (xy 337.551669 -47.465206) (xy 337.514918 -47.501957)
			(xy 337.47287 -47.532507) (xy 337.465165 -47.536433) (xy 339.96046 -47.536433) (xy 339.96046 -47.484459)
			(xy 339.96859 -47.433124) (xy 339.984651 -47.383694) (xy 340.008247 -47.337384) (xy 340.038797 -47.295336)
			(xy 340.075548 -47.258585) (xy 340.117596 -47.228035) (xy 340.163906 -47.204439) (xy 340.213336 -47.188378)
			(xy 340.264671 -47.180248) (xy 340.316645 -47.180248) (xy 340.36798 -47.188378) (xy 340.41741 -47.204439)
			(xy 340.46372 -47.228035) (xy 340.505768 -47.258585) (xy 340.542519 -47.295336) (xy 340.573069 -47.337384)
			(xy 340.596665 -47.383694) (xy 340.612726 -47.433124) (xy 340.620856 -47.484459) (xy 340.621366 -47.510446)
			(xy 340.620856 -47.536433) (xy 340.612726 -47.587768) (xy 340.596665 -47.637198) (xy 340.573069 -47.683508)
			(xy 340.542519 -47.725556) (xy 340.505768 -47.762307) (xy 340.46372 -47.792857) (xy 340.41741 -47.816453)
			(xy 340.36798 -47.832514) (xy 340.316645 -47.840644) (xy 340.264671 -47.840644) (xy 340.213336 -47.832514)
			(xy 340.163906 -47.816453) (xy 340.117596 -47.792857) (xy 340.075548 -47.762307) (xy 340.038797 -47.725556)
			(xy 340.008247 -47.683508) (xy 339.984651 -47.637198) (xy 339.96859 -47.587768) (xy 339.96046 -47.536433)
			(xy 337.465165 -47.536433) (xy 337.42656 -47.556103) (xy 337.37713 -47.572164) (xy 337.325795 -47.580294)
			(xy 337.273821 -47.580294) (xy 337.222486 -47.572164) (xy 337.173056 -47.556103) (xy 337.126746 -47.532507)
			(xy 337.084698 -47.501957) (xy 337.047947 -47.465206) (xy 337.017397 -47.423158) (xy 336.993801 -47.376848)
			(xy 336.97774 -47.327418) (xy 336.96961 -47.276083) (xy 335.229706 -47.276083) (xy 335.221576 -47.327418)
			(xy 335.205515 -47.376848) (xy 335.181919 -47.423158) (xy 335.151369 -47.465206) (xy 335.114618 -47.501957)
			(xy 335.07257 -47.532507) (xy 335.02626 -47.556103) (xy 334.97683 -47.572164) (xy 334.925495 -47.580294)
			(xy 334.873521 -47.580294) (xy 334.822186 -47.572164) (xy 334.772756 -47.556103) (xy 334.726446 -47.532507)
			(xy 334.684398 -47.501957) (xy 334.647647 -47.465206) (xy 334.617097 -47.423158) (xy 334.593501 -47.376848)
			(xy 334.57744 -47.327418) (xy 334.56931 -47.276083) (xy 334.429595 -47.276083) (xy 334.429595 -47.276086)
			(xy 334.421464 -47.32742) (xy 334.405404 -47.376849) (xy 334.381809 -47.423157) (xy 334.351261 -47.465205)
			(xy 334.314511 -47.501955) (xy 334.272464 -47.532505) (xy 334.226156 -47.556101) (xy 334.176727 -47.572162)
			(xy 334.125394 -47.580294) (xy 334.099408 -47.580804) (xy 334.072197 -47.580214) (xy 334.01851 -47.571291)
			(xy 333.967009 -47.553699) (xy 333.919082 -47.527914) (xy 333.876022 -47.494632) (xy 333.838992 -47.454749)
			(xy 333.808989 -47.409343) (xy 333.797402 -47.384716) (xy 333.791319 -47.37237) (xy 333.773805 -47.351158)
			(xy 333.751271 -47.33538) (xy 333.725348 -47.326178) (xy 333.69791 -47.324216) (xy 333.670942 -47.329636)
			(xy 333.658464 -47.33544) (xy 333.635155 -47.34672) (xy 333.585895 -47.362678) (xy 333.534748 -47.370753)
			(xy 333.508858 -47.371254) (xy 333.482877 -47.370649) (xy 333.431554 -47.362514) (xy 333.382136 -47.346452)
			(xy 333.335839 -47.322857) (xy 333.293803 -47.292311) (xy 333.257062 -47.255565) (xy 333.226521 -47.213525)
			(xy 333.202932 -47.167225) (xy 333.186876 -47.117805) (xy 333.178748 -47.066481) (xy 332.210917 -47.066481)
			(xy 332.210916 -47.066533) (xy 332.202786 -47.117868) (xy 332.186725 -47.167298) (xy 332.163129 -47.213608)
			(xy 332.132579 -47.255656) (xy 332.095828 -47.292407) (xy 332.05378 -47.322957) (xy 332.00747 -47.346553)
			(xy 331.95804 -47.362614) (xy 331.906705 -47.370744) (xy 331.854731 -47.370744) (xy 331.803396 -47.362614)
			(xy 331.753966 -47.346553) (xy 331.707656 -47.322957) (xy 331.665608 -47.292407) (xy 331.628857 -47.255656)
			(xy 331.598307 -47.213608) (xy 331.574711 -47.167298) (xy 331.55865 -47.117868) (xy 331.55052 -47.066533)
			(xy 330.582776 -47.066533) (xy 330.574646 -47.117868) (xy 330.558585 -47.167298) (xy 330.534989 -47.213608)
			(xy 330.504439 -47.255656) (xy 330.467688 -47.292407) (xy 330.42564 -47.322957) (xy 330.37933 -47.346553)
			(xy 330.3299 -47.362614) (xy 330.278565 -47.370744) (xy 330.226591 -47.370744) (xy 330.175256 -47.362614)
			(xy 330.125826 -47.346553) (xy 330.079516 -47.322957) (xy 330.037468 -47.292407) (xy 330.000717 -47.255656)
			(xy 329.970167 -47.213608) (xy 329.946571 -47.167298) (xy 329.93051 -47.117868) (xy 329.92238 -47.066533)
			(xy 324.951415 -47.066533) (xy 324.937988 -47.086827) (xy 324.900771 -47.128364) (xy 324.857903 -47.164039)
			(xy 324.810297 -47.193093) (xy 324.758968 -47.214905) (xy 324.705011 -47.229011) (xy 324.649574 -47.235111)
			(xy 324.59384 -47.233074) (xy 324.538997 -47.222944) (xy 324.486213 -47.204937) (xy 324.436613 -47.179436)
			(xy 324.391255 -47.146985) (xy 324.351106 -47.108276) (xy 324.31702 -47.064133) (xy 324.289724 -47.015498)
			(xy 324.269801 -46.963407) (xy 324.257675 -46.90897) (xy 324.253604 -46.853348) (xy 306.066292 -46.853348)
			(xy 306.085674 -46.875717) (xy 306.115133 -46.92156) (xy 306.13777 -46.971129) (xy 306.153121 -47.023415)
			(xy 306.160876 -47.077354) (xy 306.160876 -47.131846) (xy 306.153121 -47.185785) (xy 306.13777 -47.238071)
			(xy 306.115134 -47.28764) (xy 306.085674 -47.333483) (xy 306.04999 -47.374667) (xy 306.008809 -47.410355)
			(xy 305.962968 -47.439818) (xy 305.913401 -47.462458) (xy 305.861116 -47.477814) (xy 305.807178 -47.485574)
			(xy 305.779932 -47.486062) (xy 305.751742 -47.485565) (xy 305.695979 -47.477251) (xy 305.642044 -47.460828)
			(xy 305.59111 -47.436655) (xy 305.544284 -47.405255) (xy 305.502583 -47.367311) (xy 305.466914 -47.323649)
			(xy 305.438053 -47.275217) (xy 305.426872 -47.249334) (xy 305.420961 -47.236095) (xy 305.402888 -47.213437)
			(xy 305.379177 -47.196769) (xy 305.351738 -47.187435) (xy 305.322782 -47.186184) (xy 305.294641 -47.19312)
			(xy 305.269582 -47.207682) (xy 305.259232 -47.217838) (xy 305.249388 -47.228038) (xy 305.228409 -47.247105)
			(xy 305.217322 -47.255938) (xy 305.205468 -47.265782) (xy 305.187949 -47.29112) (xy 305.178778 -47.320527)
			(xy 305.178787 -47.351331) (xy 305.187976 -47.380733) (xy 305.205509 -47.406061) (xy 305.217322 -47.415958)
			(xy 305.23979 -47.434167) (xy 305.279525 -47.476184) (xy 305.312465 -47.523715) (xy 305.337856 -47.575673)
			(xy 305.355116 -47.630867) (xy 305.36385 -47.688033) (xy 305.364388 -47.716948) (xy 305.363902 -47.744199)
			(xy 305.356146 -47.798147) (xy 305.340791 -47.850442) (xy 305.318149 -47.900019) (xy 305.288683 -47.945869)
			(xy 305.252992 -47.98706) (xy 305.211801 -48.022751) (xy 305.165951 -48.052217) (xy 305.116374 -48.074859)
			(xy 305.064079 -48.090214) (xy 305.010284 -48.097948) (xy 305.489862 -48.097948) (xy 305.493933 -48.042326)
			(xy 305.506059 -47.987889) (xy 305.525982 -47.935798) (xy 305.553278 -47.887163) (xy 305.587364 -47.84302)
			(xy 305.627513 -47.804311) (xy 305.672871 -47.77186) (xy 305.722471 -47.746359) (xy 305.775255 -47.728352)
			(xy 305.830098 -47.718222) (xy 305.885832 -47.716185) (xy 305.941269 -47.722285) (xy 305.995226 -47.736391)
			(xy 306.046555 -47.758203) (xy 306.094161 -47.787257) (xy 306.137029 -47.822932) (xy 306.174246 -47.864469)
			(xy 306.205019 -47.910982) (xy 306.228691 -47.961479) (xy 306.244759 -48.014886) (xy 306.252879 -48.070062)
			(xy 306.253388 -48.097948) (xy 307.903372 -48.097948) (xy 307.903823 -48.070627) (xy 307.911625 -48.016544)
			(xy 307.927063 -47.964128) (xy 307.94982 -47.91445) (xy 307.979431 -47.868527) (xy 308.015291 -47.827297)
			(xy 308.056665 -47.791605) (xy 308.102708 -47.76218) (xy 308.1274 -47.750476) (xy 308.140978 -47.743642)
			(xy 308.163771 -47.723568) (xy 308.179644 -47.697673) (xy 308.18719 -47.668253) (xy 308.18574 -47.637914)
			(xy 308.175422 -47.609348) (xy 308.157151 -47.585085) (xy 308.14518 -47.575724) (xy 308.121315 -47.55763)
			(xy 308.079001 -47.515253) (xy 308.043829 -47.466785) (xy 308.016661 -47.413417) (xy 307.998166 -47.356459)
			(xy 307.988798 -47.297311) (xy 307.988208 -47.267368) (xy 307.988694 -47.240117) (xy 307.99645 -47.186169)
			(xy 308.011805 -47.133874) (xy 308.034447 -47.084297) (xy 308.063913 -47.038447) (xy 308.099604 -46.997256)
			(xy 308.140795 -46.961565) (xy 308.186645 -46.932099) (xy 308.236222 -46.909457) (xy 308.288517 -46.894102)
			(xy 308.342465 -46.886346) (xy 308.396967 -46.886346) (xy 308.450915 -46.894102) (xy 308.50321 -46.909457)
			(xy 308.552787 -46.932099) (xy 308.598637 -46.961565) (xy 308.639828 -46.997256) (xy 308.675519 -47.038447)
			(xy 308.704985 -47.084297) (xy 308.727627 -47.133874) (xy 308.742982 -47.186169) (xy 308.750738 -47.240117)
			(xy 308.751224 -47.267368) (xy 308.750789 -47.29469) (xy 308.742984 -47.348773) (xy 308.727544 -47.40119)
			(xy 308.704785 -47.450868) (xy 308.675171 -47.496791) (xy 308.64069 -47.536433) (xy 328.29551 -47.536433)
			(xy 328.29551 -47.484459) (xy 328.30364 -47.433124) (xy 328.319701 -47.383694) (xy 328.343297 -47.337384)
			(xy 328.373847 -47.295336) (xy 328.410598 -47.258585) (xy 328.452646 -47.228035) (xy 328.498956 -47.204439)
			(xy 328.548386 -47.188378) (xy 328.599721 -47.180248) (xy 328.651695 -47.180248) (xy 328.70303 -47.188378)
			(xy 328.75246 -47.204439) (xy 328.79877 -47.228035) (xy 328.840818 -47.258585) (xy 328.877569 -47.295336)
			(xy 328.908119 -47.337384) (xy 328.931715 -47.383694) (xy 328.947776 -47.433124) (xy 328.955906 -47.484459)
			(xy 328.956416 -47.510446) (xy 328.955906 -47.536433) (xy 329.107548 -47.536433) (xy 329.107548 -47.484459)
			(xy 329.115678 -47.433124) (xy 329.131739 -47.383694) (xy 329.155335 -47.337384) (xy 329.185885 -47.295336)
			(xy 329.222636 -47.258585) (xy 329.264684 -47.228035) (xy 329.310994 -47.204439) (xy 329.360424 -47.188378)
			(xy 329.411759 -47.180248) (xy 329.463733 -47.180248) (xy 329.515068 -47.188378) (xy 329.564498 -47.204439)
			(xy 329.610808 -47.228035) (xy 329.652856 -47.258585) (xy 329.689607 -47.295336) (xy 329.720157 -47.337384)
			(xy 329.743753 -47.383694) (xy 329.759814 -47.433124) (xy 329.767944 -47.484459) (xy 329.768454 -47.510446)
			(xy 329.767944 -47.536433) (xy 330.73518 -47.536433) (xy 330.73518 -47.484459) (xy 330.74331 -47.433124)
			(xy 330.759371 -47.383694) (xy 330.782967 -47.337384) (xy 330.813517 -47.295336) (xy 330.850268 -47.258585)
			(xy 330.892316 -47.228035) (xy 330.938626 -47.204439) (xy 330.988056 -47.188378) (xy 331.039391 -47.180248)
			(xy 331.091365 -47.180248) (xy 331.1427 -47.188378) (xy 331.19213 -47.204439) (xy 331.23844 -47.228035)
			(xy 331.280488 -47.258585) (xy 331.317239 -47.295336) (xy 331.347789 -47.337384) (xy 331.371385 -47.383694)
			(xy 331.387446 -47.433124) (xy 331.395576 -47.484459) (xy 331.396086 -47.510446) (xy 331.395576 -47.536433)
			(xy 332.36332 -47.536433) (xy 332.36332 -47.484459) (xy 332.37145 -47.433124) (xy 332.387511 -47.383694)
			(xy 332.411107 -47.337384) (xy 332.441657 -47.295336) (xy 332.478408 -47.258585) (xy 332.520456 -47.228035)
			(xy 332.566766 -47.204439) (xy 332.616196 -47.188378) (xy 332.667531 -47.180248) (xy 332.719505 -47.180248)
			(xy 332.77084 -47.188378) (xy 332.82027 -47.204439) (xy 332.86658 -47.228035) (xy 332.908628 -47.258585)
			(xy 332.945379 -47.295336) (xy 332.975929 -47.337384) (xy 332.999525 -47.383694) (xy 333.015586 -47.433124)
			(xy 333.023716 -47.484459) (xy 333.024226 -47.510446) (xy 333.023716 -47.536433) (xy 333.015586 -47.587768)
			(xy 332.999525 -47.637198) (xy 332.975929 -47.683508) (xy 332.945379 -47.725556) (xy 332.908628 -47.762307)
			(xy 332.86658 -47.792857) (xy 332.82027 -47.816453) (xy 332.77084 -47.832514) (xy 332.719505 -47.840644)
			(xy 332.667531 -47.840644) (xy 332.616196 -47.832514) (xy 332.566766 -47.816453) (xy 332.520456 -47.792857)
			(xy 332.478408 -47.762307) (xy 332.441657 -47.725556) (xy 332.411107 -47.683508) (xy 332.387511 -47.637198)
			(xy 332.37145 -47.587768) (xy 332.36332 -47.536433) (xy 331.395576 -47.536433) (xy 331.387446 -47.587768)
			(xy 331.371385 -47.637198) (xy 331.347789 -47.683508) (xy 331.317239 -47.725556) (xy 331.280488 -47.762307)
			(xy 331.23844 -47.792857) (xy 331.19213 -47.816453) (xy 331.1427 -47.832514) (xy 331.091365 -47.840644)
			(xy 331.039391 -47.840644) (xy 330.988056 -47.832514) (xy 330.938626 -47.816453) (xy 330.892316 -47.792857)
			(xy 330.850268 -47.762307) (xy 330.813517 -47.725556) (xy 330.782967 -47.683508) (xy 330.759371 -47.637198)
			(xy 330.74331 -47.587768) (xy 330.73518 -47.536433) (xy 329.767944 -47.536433) (xy 329.759814 -47.587768)
			(xy 329.743753 -47.637198) (xy 329.720157 -47.683508) (xy 329.689607 -47.725556) (xy 329.652856 -47.762307)
			(xy 329.610808 -47.792857) (xy 329.564498 -47.816453) (xy 329.515068 -47.832514) (xy 329.463733 -47.840644)
			(xy 329.411759 -47.840644) (xy 329.360424 -47.832514) (xy 329.310994 -47.816453) (xy 329.264684 -47.792857)
			(xy 329.222636 -47.762307) (xy 329.185885 -47.725556) (xy 329.155335 -47.683508) (xy 329.131739 -47.637198)
			(xy 329.115678 -47.587768) (xy 329.107548 -47.536433) (xy 328.955906 -47.536433) (xy 328.947776 -47.587768)
			(xy 328.931715 -47.637198) (xy 328.908119 -47.683508) (xy 328.877569 -47.725556) (xy 328.840818 -47.762307)
			(xy 328.79877 -47.792857) (xy 328.75246 -47.816453) (xy 328.70303 -47.832514) (xy 328.651695 -47.840644)
			(xy 328.599721 -47.840644) (xy 328.548386 -47.832514) (xy 328.498956 -47.816453) (xy 328.452646 -47.792857)
			(xy 328.410598 -47.762307) (xy 328.373847 -47.725556) (xy 328.343297 -47.683508) (xy 328.319701 -47.637198)
			(xy 328.30364 -47.587768) (xy 328.29551 -47.536433) (xy 308.64069 -47.536433) (xy 308.63931 -47.53802)
			(xy 308.597933 -47.573712) (xy 308.551889 -47.603137) (xy 308.527196 -47.61484) (xy 308.513606 -47.62165)
			(xy 308.490811 -47.641729) (xy 308.474939 -47.667629) (xy 308.467394 -47.697054) (xy 308.468847 -47.727396)
			(xy 308.479168 -47.755966) (xy 308.497442 -47.780231) (xy 308.509416 -47.789592) (xy 308.533287 -47.807677)
			(xy 308.575601 -47.850056) (xy 308.610773 -47.898525) (xy 308.63794 -47.951896) (xy 308.656433 -48.008855)
			(xy 308.665799 -48.068005) (xy 308.666388 -48.097948) (xy 308.665902 -48.125199) (xy 308.658146 -48.179147)
			(xy 308.642791 -48.231442) (xy 308.620149 -48.281019) (xy 308.590683 -48.326869) (xy 308.554992 -48.36806)
			(xy 308.513801 -48.403751) (xy 308.467951 -48.433217) (xy 308.418374 -48.455859) (xy 308.366079 -48.471214)
			(xy 308.312131 -48.47897) (xy 308.257629 -48.47897) (xy 308.203681 -48.471214) (xy 308.151386 -48.455859)
			(xy 308.101809 -48.433217) (xy 308.055959 -48.403751) (xy 308.014768 -48.36806) (xy 307.979077 -48.326869)
			(xy 307.949611 -48.281019) (xy 307.926969 -48.231442) (xy 307.911614 -48.179147) (xy 307.903858 -48.125199)
			(xy 307.903372 -48.097948) (xy 306.253388 -48.097948) (xy 306.252879 -48.125834) (xy 306.244759 -48.18101)
			(xy 306.228691 -48.234417) (xy 306.205019 -48.284914) (xy 306.174246 -48.331427) (xy 306.137029 -48.372964)
			(xy 306.094161 -48.408639) (xy 306.046555 -48.437693) (xy 305.995226 -48.459505) (xy 305.941269 -48.473611)
			(xy 305.885832 -48.479711) (xy 305.830098 -48.477674) (xy 305.775255 -48.467544) (xy 305.722471 -48.449537)
			(xy 305.672871 -48.424036) (xy 305.627513 -48.391585) (xy 305.587364 -48.352876) (xy 305.553278 -48.308733)
			(xy 305.525982 -48.260098) (xy 305.506059 -48.208007) (xy 305.493933 -48.15357) (xy 305.489862 -48.097948)
			(xy 305.010284 -48.097948) (xy 305.010131 -48.09797) (xy 304.955629 -48.09797) (xy 304.901681 -48.090214)
			(xy 304.849386 -48.074859) (xy 304.799809 -48.052217) (xy 304.753959 -48.022751) (xy 304.712768 -47.98706)
			(xy 304.677077 -47.945869) (xy 304.647611 -47.900019) (xy 304.624969 -47.850442) (xy 304.609614 -47.798147)
			(xy 304.601858 -47.744199) (xy 304.601372 -47.716948) (xy 304.068922 -47.716948) (xy 304.079546 -47.726154)
			(xy 304.115242 -47.76735) (xy 304.144712 -47.813206) (xy 304.167356 -47.862789) (xy 304.182713 -47.915091)
			(xy 304.19047 -47.969045) (xy 304.19047 -48.023555) (xy 304.182713 -48.077509) (xy 304.167356 -48.129811)
			(xy 304.144712 -48.179394) (xy 304.115242 -48.22525) (xy 304.079546 -48.266446) (xy 304.03835 -48.302142)
			(xy 303.992494 -48.331612) (xy 303.942911 -48.354256) (xy 303.890609 -48.369613) (xy 303.836655 -48.37737)
			(xy 303.8094 -48.377856) (xy 303.780662 -48.377317) (xy 303.723836 -48.368696) (xy 303.668946 -48.351649)
			(xy 303.617234 -48.326561) (xy 303.56987 -48.294) (xy 303.548542 -48.274732) (xy 303.537008 -48.26466)
			(xy 303.509462 -48.251318) (xy 303.4792 -48.246733) (xy 303.448938 -48.251318) (xy 303.421392 -48.26466)
			(xy 303.409858 -48.274732) (xy 303.388527 -48.293998) (xy 303.341166 -48.326566) (xy 303.289456 -48.35166)
			(xy 303.234566 -48.368712) (xy 303.177739 -48.377335) (xy 303.149 -48.377856) (xy 303.121752 -48.377274)
			(xy 303.067811 -48.369518) (xy 303.015523 -48.354165) (xy 302.965952 -48.331527) (xy 302.920108 -48.302064)
			(xy 302.878923 -48.266377) (xy 302.843236 -48.225192) (xy 302.813773 -48.179348) (xy 302.791135 -48.129777)
			(xy 302.775782 -48.077489) (xy 302.768026 -48.023548) (xy 301.246552 -48.023548) (xy 301.246539 -48.024234)
			(xy 301.238419 -48.07941) (xy 301.222351 -48.132817) (xy 301.198679 -48.183314) (xy 301.167906 -48.229827)
			(xy 301.130689 -48.271364) (xy 301.087821 -48.307039) (xy 301.040215 -48.336093) (xy 300.988886 -48.357905)
			(xy 300.934929 -48.372011) (xy 300.879492 -48.378111) (xy 300.823758 -48.376074) (xy 300.768915 -48.365944)
			(xy 300.716131 -48.347937) (xy 300.666531 -48.322436) (xy 300.621173 -48.289985) (xy 300.581024 -48.251276)
			(xy 300.546938 -48.207133) (xy 300.519642 -48.158498) (xy 300.499719 -48.106407) (xy 300.487593 -48.05197)
			(xy 300.483522 -47.996348) (xy 284.314646 -47.996348) (xy 283.779446 -48.531548) (xy 294.894026 -48.531548)
			(xy 294.894026 -48.477052) (xy 294.901782 -48.423111) (xy 294.917135 -48.370823) (xy 294.939773 -48.321252)
			(xy 294.969236 -48.275408) (xy 295.004923 -48.234223) (xy 295.046108 -48.198536) (xy 295.091952 -48.169073)
			(xy 295.141523 -48.146435) (xy 295.193811 -48.131082) (xy 295.247752 -48.123326) (xy 295.275 -48.12284)
			(xy 295.302371 -48.123296) (xy 295.356551 -48.131115) (xy 295.409054 -48.146606) (xy 295.458801 -48.16945)
			(xy 295.504767 -48.199177) (xy 295.525698 -48.21682) (xy 295.537026 -48.226056) (xy 295.563583 -48.238232)
			(xy 295.5925 -48.242405) (xy 295.621417 -48.238232) (xy 295.647974 -48.226056) (xy 295.659302 -48.21682)
			(xy 295.680225 -48.19917) (xy 295.7262 -48.169459) (xy 295.77595 -48.146625) (xy 295.828453 -48.131136)
			(xy 295.88263 -48.123312) (xy 295.91 -48.12284) (xy 295.937255 -48.12323) (xy 295.991209 -48.130987)
			(xy 296.043511 -48.146344) (xy 296.093094 -48.168988) (xy 296.13895 -48.198458) (xy 296.180146 -48.234154)
			(xy 296.215842 -48.27535) (xy 296.245312 -48.321206) (xy 296.267956 -48.370789) (xy 296.283313 -48.423091)
			(xy 296.29107 -48.477045) (xy 296.29107 -48.490926) (xy 310.294961 -48.490926) (xy 310.294965 -48.436421)
			(xy 310.302726 -48.382471) (xy 310.318086 -48.330174) (xy 310.340732 -48.280596) (xy 310.370204 -48.234746)
			(xy 310.4059 -48.193556) (xy 310.447096 -48.157866) (xy 310.492951 -48.128402) (xy 310.542533 -48.105764)
			(xy 310.594832 -48.090413) (xy 310.648783 -48.082661) (xy 310.676036 -48.0822) (xy 310.704871 -48.082737)
			(xy 310.761886 -48.091403) (xy 310.789574 -48.099472) (xy 310.803913 -48.103394) (xy 310.833626 -48.103668)
			(xy 310.862162 -48.095384) (xy 310.88711 -48.079244) (xy 310.906362 -48.05661) (xy 310.918291 -48.029396)
			(xy 310.92189 -47.999901) (xy 310.919876 -47.985172) (xy 310.917256 -47.969044) (xy 310.91446 -47.936487)
			(xy 310.914288 -47.920148) (xy 310.914704 -47.892891) (xy 310.922455 -47.838931) (xy 310.937807 -47.786623)
			(xy 310.960448 -47.737032) (xy 310.989915 -47.691169) (xy 311.02561 -47.649966) (xy 311.066806 -47.614263)
			(xy 311.112663 -47.584786) (xy 311.162249 -47.562135) (xy 311.214554 -47.546772) (xy 311.268512 -47.539009)
			(xy 311.323026 -47.539005) (xy 311.376986 -47.546759) (xy 311.429293 -47.562114) (xy 311.478883 -47.584756)
			(xy 311.524745 -47.614226) (xy 311.565946 -47.649923) (xy 311.601648 -47.69112) (xy 311.631123 -47.736978)
			(xy 311.653771 -47.786565) (xy 311.669132 -47.838871) (xy 311.676892 -47.89283) (xy 311.676894 -47.947344)
			(xy 311.669137 -48.001303) (xy 311.66766 -48.006333) (xy 329.921618 -48.006333) (xy 329.921618 -47.954359)
			(xy 329.929748 -47.903024) (xy 329.945809 -47.853594) (xy 329.969405 -47.807284) (xy 329.999955 -47.765236)
			(xy 330.036706 -47.728485) (xy 330.078754 -47.697935) (xy 330.125064 -47.674339) (xy 330.174494 -47.658278)
			(xy 330.225829 -47.650148) (xy 330.277803 -47.650148) (xy 330.329138 -47.658278) (xy 330.378568 -47.674339)
			(xy 330.424878 -47.697935) (xy 330.466926 -47.728485) (xy 330.503677 -47.765236) (xy 330.534227 -47.807284)
			(xy 330.557823 -47.853594) (xy 330.573884 -47.903024) (xy 330.582014 -47.954359) (xy 330.582524 -47.980346)
			(xy 330.582014 -48.006333) (xy 331.55052 -48.006333) (xy 331.55052 -47.954359) (xy 331.55865 -47.903024)
			(xy 331.574711 -47.853594) (xy 331.598307 -47.807284) (xy 331.628857 -47.765236) (xy 331.665608 -47.728485)
			(xy 331.707656 -47.697935) (xy 331.753966 -47.674339) (xy 331.803396 -47.658278) (xy 331.854731 -47.650148)
			(xy 331.906705 -47.650148) (xy 331.95804 -47.658278) (xy 332.00747 -47.674339) (xy 332.05378 -47.697935)
			(xy 332.095828 -47.728485) (xy 332.132579 -47.765236) (xy 332.163129 -47.807284) (xy 332.186725 -47.853594)
			(xy 332.202786 -47.903024) (xy 332.210916 -47.954359) (xy 332.211426 -47.980346) (xy 332.210917 -48.006281)
			(xy 333.178248 -48.006281) (xy 333.178248 -47.954319) (xy 333.186376 -47.902997) (xy 333.202431 -47.853577)
			(xy 333.226019 -47.807278) (xy 333.256559 -47.765237) (xy 333.293299 -47.728492) (xy 333.335335 -47.697946)
			(xy 333.381631 -47.67435) (xy 333.431048 -47.658287) (xy 333.482369 -47.650152) (xy 333.50835 -47.649638)
			(xy 333.53373 -47.650135) (xy 333.583893 -47.657889) (xy 333.63228 -47.673225) (xy 333.677753 -47.695779)
			(xy 333.719242 -47.725022) (xy 333.75577 -47.760267) (xy 333.771494 -47.780194) (xy 333.779857 -47.790548)
			(xy 333.800904 -47.806826) (xy 333.825439 -47.817123) (xy 333.851801 -47.82074) (xy 333.878202 -47.817432)
			(xy 333.902856 -47.807424) (xy 333.913734 -47.799752) (xy 333.935378 -47.784053) (xy 333.982681 -47.75913)
			(xy 334.033373 -47.742128) (xy 334.086137 -47.733488) (xy 334.11287 -47.73295) (xy 334.138858 -47.733515)
			(xy 334.190193 -47.741641) (xy 334.239625 -47.757699) (xy 334.285937 -47.781292) (xy 334.327987 -47.81184)
			(xy 334.364741 -47.84859) (xy 334.395292 -47.890637) (xy 334.41889 -47.936947) (xy 334.434952 -47.986378)
			(xy 334.443083 -48.037713) (xy 334.443083 -48.076183) (xy 334.56931 -48.076183) (xy 334.56931 -48.024209)
			(xy 334.57744 -47.972874) (xy 334.593501 -47.923444) (xy 334.617097 -47.877134) (xy 334.647647 -47.835086)
			(xy 334.684398 -47.798335) (xy 334.726446 -47.767785) (xy 334.772756 -47.744189) (xy 334.822186 -47.728128)
			(xy 334.873521 -47.719998) (xy 334.925495 -47.719998) (xy 334.97683 -47.728128) (xy 335.02626 -47.744189)
			(xy 335.07257 -47.767785) (xy 335.114618 -47.798335) (xy 335.151369 -47.835086) (xy 335.181919 -47.877134)
			(xy 335.205515 -47.923444) (xy 335.221576 -47.972874) (xy 335.229706 -48.024209) (xy 335.230216 -48.050196)
			(xy 335.229706 -48.076183) (xy 336.96961 -48.076183) (xy 336.96961 -48.024209) (xy 336.97774 -47.972874)
			(xy 336.993801 -47.923444) (xy 337.017397 -47.877134) (xy 337.047947 -47.835086) (xy 337.084698 -47.798335)
			(xy 337.126746 -47.767785) (xy 337.173056 -47.744189) (xy 337.222486 -47.728128) (xy 337.273821 -47.719998)
			(xy 337.325795 -47.719998) (xy 337.37713 -47.728128) (xy 337.42656 -47.744189) (xy 337.47287 -47.767785)
			(xy 337.514918 -47.798335) (xy 337.551669 -47.835086) (xy 337.582219 -47.877134) (xy 337.605815 -47.923444)
			(xy 337.621876 -47.972874) (xy 337.627175 -48.006333) (xy 340.7758 -48.006333) (xy 340.7758 -47.954359)
			(xy 340.78393 -47.903024) (xy 340.799991 -47.853594) (xy 340.823587 -47.807284) (xy 340.854137 -47.765236)
			(xy 340.890888 -47.728485) (xy 340.932936 -47.697935) (xy 340.979246 -47.674339) (xy 341.028676 -47.658278)
			(xy 341.080011 -47.650148) (xy 341.131985 -47.650148) (xy 341.18332 -47.658278) (xy 341.23275 -47.674339)
			(xy 341.27906 -47.697935) (xy 341.321108 -47.728485) (xy 341.357859 -47.765236) (xy 341.388409 -47.807284)
			(xy 341.412005 -47.853594) (xy 341.428066 -47.903024) (xy 341.436196 -47.954359) (xy 341.436706 -47.980346)
			(xy 341.436196 -48.006333) (xy 341.428066 -48.057668) (xy 341.412005 -48.107098) (xy 341.388409 -48.153408)
			(xy 341.357859 -48.195456) (xy 341.321108 -48.232207) (xy 341.27906 -48.262757) (xy 341.23275 -48.286353)
			(xy 341.18332 -48.302414) (xy 341.131985 -48.310544) (xy 341.080011 -48.310544) (xy 341.028676 -48.302414)
			(xy 340.979246 -48.286353) (xy 340.932936 -48.262757) (xy 340.890888 -48.232207) (xy 340.854137 -48.195456)
			(xy 340.823587 -48.153408) (xy 340.799991 -48.107098) (xy 340.78393 -48.057668) (xy 340.7758 -48.006333)
			(xy 337.627175 -48.006333) (xy 337.630006 -48.024209) (xy 337.630516 -48.050196) (xy 337.630006 -48.076183)
			(xy 337.621876 -48.127518) (xy 337.605815 -48.176948) (xy 337.582219 -48.223258) (xy 337.551669 -48.265306)
			(xy 337.514918 -48.302057) (xy 337.47287 -48.332607) (xy 337.42656 -48.356203) (xy 337.37713 -48.372264)
			(xy 337.325795 -48.380394) (xy 337.273821 -48.380394) (xy 337.222486 -48.372264) (xy 337.173056 -48.356203)
			(xy 337.126746 -48.332607) (xy 337.084698 -48.302057) (xy 337.047947 -48.265306) (xy 337.017397 -48.223258)
			(xy 336.993801 -48.176948) (xy 336.97774 -48.127518) (xy 336.96961 -48.076183) (xy 335.229706 -48.076183)
			(xy 335.221576 -48.127518) (xy 335.205515 -48.176948) (xy 335.181919 -48.223258) (xy 335.151369 -48.265306)
			(xy 335.114618 -48.302057) (xy 335.07257 -48.332607) (xy 335.02626 -48.356203) (xy 334.97683 -48.372264)
			(xy 334.925495 -48.380394) (xy 334.873521 -48.380394) (xy 334.822186 -48.372264) (xy 334.772756 -48.356203)
			(xy 334.726446 -48.332607) (xy 334.684398 -48.302057) (xy 334.647647 -48.265306) (xy 334.617097 -48.223258)
			(xy 334.593501 -48.176948) (xy 334.57744 -48.127518) (xy 334.56931 -48.076183) (xy 334.443083 -48.076183)
			(xy 334.443083 -48.089687) (xy 334.434952 -48.141022) (xy 334.41889 -48.190453) (xy 334.395292 -48.236763)
			(xy 334.364741 -48.27881) (xy 334.327987 -48.31556) (xy 334.285937 -48.346108) (xy 334.239625 -48.369701)
			(xy 334.190193 -48.385759) (xy 334.138858 -48.393885) (xy 334.11287 -48.394366) (xy 334.087491 -48.393854)
			(xy 334.037329 -48.386102) (xy 333.988942 -48.37077) (xy 333.943469 -48.348218) (xy 333.90198 -48.318978)
			(xy 333.86545 -48.283736) (xy 333.849726 -48.26381) (xy 333.841352 -48.253469) (xy 333.820303 -48.237202)
			(xy 333.795771 -48.226913) (xy 333.769416 -48.223295) (xy 333.74302 -48.226595) (xy 333.718366 -48.236589)
			(xy 333.707486 -48.244252) (xy 333.685836 -48.259943) (xy 333.638535 -48.284868) (xy 333.587845 -48.301872)
			(xy 333.535082 -48.310515) (xy 333.50835 -48.311054) (xy 333.482369 -48.310448) (xy 333.431048 -48.302313)
			(xy 333.381631 -48.28625) (xy 333.335335 -48.262654) (xy 333.293299 -48.232108) (xy 333.256559 -48.195363)
			(xy 333.226019 -48.153322) (xy 333.202431 -48.107023) (xy 333.186376 -48.057604) (xy 333.178248 -48.006281)
			(xy 332.210917 -48.006281) (xy 332.210916 -48.006333) (xy 332.202786 -48.057668) (xy 332.186725 -48.107098)
			(xy 332.163129 -48.153408) (xy 332.132579 -48.195456) (xy 332.095828 -48.232207) (xy 332.05378 -48.262757)
			(xy 332.00747 -48.286353) (xy 331.95804 -48.302414) (xy 331.906705 -48.310544) (xy 331.854731 -48.310544)
			(xy 331.803396 -48.302414) (xy 331.753966 -48.286353) (xy 331.707656 -48.262757) (xy 331.665608 -48.232207)
			(xy 331.628857 -48.195456) (xy 331.598307 -48.153408) (xy 331.574711 -48.107098) (xy 331.55865 -48.057668)
			(xy 331.55052 -48.006333) (xy 330.582014 -48.006333) (xy 330.573884 -48.057668) (xy 330.557823 -48.107098)
			(xy 330.534227 -48.153408) (xy 330.503677 -48.195456) (xy 330.466926 -48.232207) (xy 330.424878 -48.262757)
			(xy 330.378568 -48.286353) (xy 330.329138 -48.302414) (xy 330.277803 -48.310544) (xy 330.225829 -48.310544)
			(xy 330.174494 -48.302414) (xy 330.125064 -48.286353) (xy 330.078754 -48.262757) (xy 330.036706 -48.232207)
			(xy 329.999955 -48.195456) (xy 329.969405 -48.153408) (xy 329.945809 -48.107098) (xy 329.929748 -48.057668)
			(xy 329.921618 -48.006333) (xy 311.66766 -48.006333) (xy 311.65378 -48.05361) (xy 311.631135 -48.103198)
			(xy 311.601664 -48.149059) (xy 311.565965 -48.190259) (xy 311.524766 -48.225958) (xy 311.478906 -48.255431)
			(xy 311.429318 -48.278077) (xy 311.377012 -48.293435) (xy 311.323053 -48.301193) (xy 311.295796 -48.301656)
			(xy 311.26696 -48.301136) (xy 311.209945 -48.292459) (xy 311.182258 -48.284384) (xy 311.167923 -48.280434)
			(xy 311.138201 -48.280151) (xy 311.109655 -48.288432) (xy 311.0847 -48.304577) (xy 311.065445 -48.32722)
			(xy 311.05352 -48.354446) (xy 311.049933 -48.383952) (xy 311.051956 -48.398684) (xy 311.05457 -48.414813)
			(xy 311.05737 -48.44737) (xy 311.057544 -48.463708) (xy 311.057036 -48.490961) (xy 311.049278 -48.544911)
			(xy 311.038813 -48.580548) (xy 322.932804 -48.580548) (xy 322.936875 -48.524926) (xy 322.949001 -48.470489)
			(xy 322.968924 -48.418398) (xy 322.99622 -48.369763) (xy 323.030306 -48.32562) (xy 323.070455 -48.286911)
			(xy 323.115813 -48.25446) (xy 323.165413 -48.228959) (xy 323.218197 -48.210952) (xy 323.27304 -48.200822)
			(xy 323.328774 -48.198785) (xy 323.384211 -48.204885) (xy 323.438168 -48.218991) (xy 323.489497 -48.240803)
			(xy 323.537103 -48.269857) (xy 323.579971 -48.305532) (xy 323.617188 -48.347069) (xy 323.647961 -48.393582)
			(xy 323.671633 -48.444079) (xy 323.681307 -48.476233) (xy 328.29551 -48.476233) (xy 328.29551 -48.424259)
			(xy 328.30364 -48.372924) (xy 328.319701 -48.323494) (xy 328.343297 -48.277184) (xy 328.373847 -48.235136)
			(xy 328.410598 -48.198385) (xy 328.452646 -48.167835) (xy 328.498956 -48.144239) (xy 328.548386 -48.128178)
			(xy 328.599721 -48.120048) (xy 328.651695 -48.120048) (xy 328.70303 -48.128178) (xy 328.75246 -48.144239)
			(xy 328.79877 -48.167835) (xy 328.840818 -48.198385) (xy 328.877569 -48.235136) (xy 328.908119 -48.277184)
			(xy 328.931715 -48.323494) (xy 328.947776 -48.372924) (xy 328.955906 -48.424259) (xy 328.956416 -48.450246)
			(xy 328.955906 -48.476233) (xy 329.107548 -48.476233) (xy 329.107548 -48.424259) (xy 329.115678 -48.372924)
			(xy 329.131739 -48.323494) (xy 329.155335 -48.277184) (xy 329.185885 -48.235136) (xy 329.222636 -48.198385)
			(xy 329.264684 -48.167835) (xy 329.310994 -48.144239) (xy 329.360424 -48.128178) (xy 329.411759 -48.120048)
			(xy 329.463733 -48.120048) (xy 329.515068 -48.128178) (xy 329.564498 -48.144239) (xy 329.610808 -48.167835)
			(xy 329.652856 -48.198385) (xy 329.689607 -48.235136) (xy 329.720157 -48.277184) (xy 329.743753 -48.323494)
			(xy 329.759814 -48.372924) (xy 329.767944 -48.424259) (xy 329.768454 -48.450246) (xy 329.767944 -48.476233)
			(xy 330.73518 -48.476233) (xy 330.73518 -48.424259) (xy 330.74331 -48.372924) (xy 330.759371 -48.323494)
			(xy 330.782967 -48.277184) (xy 330.813517 -48.235136) (xy 330.850268 -48.198385) (xy 330.892316 -48.167835)
			(xy 330.938626 -48.144239) (xy 330.988056 -48.128178) (xy 331.039391 -48.120048) (xy 331.091365 -48.120048)
			(xy 331.1427 -48.128178) (xy 331.19213 -48.144239) (xy 331.23844 -48.167835) (xy 331.280488 -48.198385)
			(xy 331.317239 -48.235136) (xy 331.347789 -48.277184) (xy 331.371385 -48.323494) (xy 331.387446 -48.372924)
			(xy 331.395576 -48.424259) (xy 331.396086 -48.450246) (xy 331.395576 -48.476233) (xy 332.36332 -48.476233)
			(xy 332.36332 -48.424259) (xy 332.37145 -48.372924) (xy 332.387511 -48.323494) (xy 332.411107 -48.277184)
			(xy 332.441657 -48.235136) (xy 332.478408 -48.198385) (xy 332.520456 -48.167835) (xy 332.566766 -48.144239)
			(xy 332.616196 -48.128178) (xy 332.667531 -48.120048) (xy 332.719505 -48.120048) (xy 332.77084 -48.128178)
			(xy 332.82027 -48.144239) (xy 332.86658 -48.167835) (xy 332.908628 -48.198385) (xy 332.945379 -48.235136)
			(xy 332.975929 -48.277184) (xy 332.999525 -48.323494) (xy 333.015586 -48.372924) (xy 333.023716 -48.424259)
			(xy 333.024226 -48.450246) (xy 333.023716 -48.476233) (xy 339.96046 -48.476233) (xy 339.96046 -48.424259)
			(xy 339.96859 -48.372924) (xy 339.984651 -48.323494) (xy 340.008247 -48.277184) (xy 340.038797 -48.235136)
			(xy 340.075548 -48.198385) (xy 340.117596 -48.167835) (xy 340.163906 -48.144239) (xy 340.213336 -48.128178)
			(xy 340.264671 -48.120048) (xy 340.316645 -48.120048) (xy 340.36798 -48.128178) (xy 340.41741 -48.144239)
			(xy 340.46372 -48.167835) (xy 340.505768 -48.198385) (xy 340.542519 -48.235136) (xy 340.573069 -48.277184)
			(xy 340.596665 -48.323494) (xy 340.612726 -48.372924) (xy 340.620856 -48.424259) (xy 340.621366 -48.450246)
			(xy 340.620856 -48.476233) (xy 341.5886 -48.476233) (xy 341.5886 -48.424259) (xy 341.59673 -48.372924)
			(xy 341.612791 -48.323494) (xy 341.636387 -48.277184) (xy 341.666937 -48.235136) (xy 341.703688 -48.198385)
			(xy 341.745736 -48.167835) (xy 341.792046 -48.144239) (xy 341.841476 -48.128178) (xy 341.892811 -48.120048)
			(xy 341.944785 -48.120048) (xy 341.99612 -48.128178) (xy 342.04555 -48.144239) (xy 342.09186 -48.167835)
			(xy 342.133908 -48.198385) (xy 342.170659 -48.235136) (xy 342.201209 -48.277184) (xy 342.224805 -48.323494)
			(xy 342.240866 -48.372924) (xy 342.248996 -48.424259) (xy 342.249506 -48.450246) (xy 342.248996 -48.476233)
			(xy 342.240866 -48.527568) (xy 342.224805 -48.576998) (xy 342.201209 -48.623308) (xy 342.170659 -48.665356)
			(xy 342.133908 -48.702107) (xy 342.09186 -48.732657) (xy 342.04555 -48.756253) (xy 341.99612 -48.772314)
			(xy 341.944785 -48.780444) (xy 341.892811 -48.780444) (xy 341.841476 -48.772314) (xy 341.792046 -48.756253)
			(xy 341.745736 -48.732657) (xy 341.703688 -48.702107) (xy 341.666937 -48.665356) (xy 341.636387 -48.623308)
			(xy 341.612791 -48.576998) (xy 341.59673 -48.527568) (xy 341.5886 -48.476233) (xy 340.620856 -48.476233)
			(xy 340.612726 -48.527568) (xy 340.596665 -48.576998) (xy 340.573069 -48.623308) (xy 340.542519 -48.665356)
			(xy 340.505768 -48.702107) (xy 340.46372 -48.732657) (xy 340.41741 -48.756253) (xy 340.36798 -48.772314)
			(xy 340.316645 -48.780444) (xy 340.264671 -48.780444) (xy 340.213336 -48.772314) (xy 340.163906 -48.756253)
			(xy 340.117596 -48.732657) (xy 340.075548 -48.702107) (xy 340.038797 -48.665356) (xy 340.008247 -48.623308)
			(xy 339.984651 -48.576998) (xy 339.96859 -48.527568) (xy 339.96046 -48.476233) (xy 333.023716 -48.476233)
			(xy 333.015586 -48.527568) (xy 332.999525 -48.576998) (xy 332.975929 -48.623308) (xy 332.945379 -48.665356)
			(xy 332.908628 -48.702107) (xy 332.86658 -48.732657) (xy 332.82027 -48.756253) (xy 332.77084 -48.772314)
			(xy 332.719505 -48.780444) (xy 332.667531 -48.780444) (xy 332.616196 -48.772314) (xy 332.566766 -48.756253)
			(xy 332.520456 -48.732657) (xy 332.478408 -48.702107) (xy 332.441657 -48.665356) (xy 332.411107 -48.623308)
			(xy 332.387511 -48.576998) (xy 332.37145 -48.527568) (xy 332.36332 -48.476233) (xy 331.395576 -48.476233)
			(xy 331.387446 -48.527568) (xy 331.371385 -48.576998) (xy 331.347789 -48.623308) (xy 331.317239 -48.665356)
			(xy 331.280488 -48.702107) (xy 331.23844 -48.732657) (xy 331.19213 -48.756253) (xy 331.1427 -48.772314)
			(xy 331.091365 -48.780444) (xy 331.039391 -48.780444) (xy 330.988056 -48.772314) (xy 330.938626 -48.756253)
			(xy 330.892316 -48.732657) (xy 330.850268 -48.702107) (xy 330.813517 -48.665356) (xy 330.782967 -48.623308)
			(xy 330.759371 -48.576998) (xy 330.74331 -48.527568) (xy 330.73518 -48.476233) (xy 329.767944 -48.476233)
			(xy 329.759814 -48.527568) (xy 329.743753 -48.576998) (xy 329.720157 -48.623308) (xy 329.689607 -48.665356)
			(xy 329.652856 -48.702107) (xy 329.610808 -48.732657) (xy 329.564498 -48.756253) (xy 329.515068 -48.772314)
			(xy 329.463733 -48.780444) (xy 329.411759 -48.780444) (xy 329.360424 -48.772314) (xy 329.310994 -48.756253)
			(xy 329.264684 -48.732657) (xy 329.222636 -48.702107) (xy 329.185885 -48.665356) (xy 329.155335 -48.623308)
			(xy 329.131739 -48.576998) (xy 329.115678 -48.527568) (xy 329.107548 -48.476233) (xy 328.955906 -48.476233)
			(xy 328.947776 -48.527568) (xy 328.931715 -48.576998) (xy 328.908119 -48.623308) (xy 328.877569 -48.665356)
			(xy 328.840818 -48.702107) (xy 328.79877 -48.732657) (xy 328.75246 -48.756253) (xy 328.70303 -48.772314)
			(xy 328.651695 -48.780444) (xy 328.599721 -48.780444) (xy 328.548386 -48.772314) (xy 328.498956 -48.756253)
			(xy 328.452646 -48.732657) (xy 328.410598 -48.702107) (xy 328.373847 -48.665356) (xy 328.343297 -48.623308)
			(xy 328.319701 -48.576998) (xy 328.30364 -48.527568) (xy 328.29551 -48.476233) (xy 323.681307 -48.476233)
			(xy 323.687701 -48.497486) (xy 323.695821 -48.552662) (xy 323.69633 -48.580548) (xy 323.695821 -48.608434)
			(xy 323.687701 -48.66361) (xy 323.671633 -48.717017) (xy 323.647961 -48.767514) (xy 323.617188 -48.814027)
			(xy 323.579971 -48.855564) (xy 323.537103 -48.891239) (xy 323.489497 -48.920293) (xy 323.438168 -48.942105)
			(xy 323.384211 -48.956211) (xy 323.328774 -48.962311) (xy 323.27304 -48.960274) (xy 323.218197 -48.950144)
			(xy 323.165413 -48.932137) (xy 323.115813 -48.906636) (xy 323.070455 -48.874185) (xy 323.030306 -48.835476)
			(xy 322.99622 -48.791333) (xy 322.968924 -48.742698) (xy 322.949001 -48.690607) (xy 322.936875 -48.63617)
			(xy 322.932804 -48.580548) (xy 311.038813 -48.580548) (xy 311.033921 -48.597208) (xy 311.011277 -48.646788)
			(xy 310.981808 -48.69264) (xy 310.946113 -48.733831) (xy 310.904919 -48.769523) (xy 310.859065 -48.798989)
			(xy 310.809485 -48.821629) (xy 310.757186 -48.836983) (xy 310.703235 -48.844738) (xy 310.64873 -48.844735)
			(xy 310.59478 -48.836976) (xy 310.542483 -48.821617) (xy 310.492904 -48.798972) (xy 310.447053 -48.769502)
			(xy 310.405863 -48.733806) (xy 310.370172 -48.692612) (xy 310.340706 -48.646757) (xy 310.318067 -48.597176)
			(xy 310.302715 -48.544877) (xy 310.294961 -48.490926) (xy 296.29107 -48.490926) (xy 296.29107 -48.531555)
			(xy 296.283313 -48.585509) (xy 296.267956 -48.637811) (xy 296.245312 -48.687394) (xy 296.215842 -48.73325)
			(xy 296.180146 -48.774446) (xy 296.13895 -48.810142) (xy 296.093094 -48.839612) (xy 296.043511 -48.862256)
			(xy 295.991209 -48.877613) (xy 295.937255 -48.88537) (xy 295.91 -48.885856) (xy 295.882629 -48.885401)
			(xy 295.828449 -48.877582) (xy 295.775946 -48.862091) (xy 295.726199 -48.839247) (xy 295.680233 -48.809519)
			(xy 295.659302 -48.791876) (xy 295.647974 -48.78264) (xy 295.621417 -48.770464) (xy 295.5925 -48.766291)
			(xy 295.563583 -48.770464) (xy 295.537026 -48.78264) (xy 295.525698 -48.791876) (xy 295.504774 -48.809526)
			(xy 295.4588 -48.839237) (xy 295.40905 -48.862071) (xy 295.356547 -48.87756) (xy 295.30237 -48.885384)
			(xy 295.275 -48.885856) (xy 295.247752 -48.885274) (xy 295.193811 -48.877518) (xy 295.141523 -48.862165)
			(xy 295.091952 -48.839527) (xy 295.046108 -48.810064) (xy 295.004923 -48.774377) (xy 294.969236 -48.733192)
			(xy 294.939773 -48.687348) (xy 294.917135 -48.637777) (xy 294.901782 -48.585489) (xy 294.894026 -48.531548)
			(xy 283.779446 -48.531548) (xy 283.000196 -49.310798) (xy 287.410396 -49.310798) (xy 287.414467 -49.255176)
			(xy 287.426593 -49.200739) (xy 287.446516 -49.148648) (xy 287.473812 -49.100013) (xy 287.507898 -49.05587)
			(xy 287.548047 -49.017161) (xy 287.593405 -48.98471) (xy 287.643005 -48.959209) (xy 287.695789 -48.941202)
			(xy 287.750632 -48.931072) (xy 287.806366 -48.929035) (xy 287.861803 -48.935135) (xy 287.91576 -48.949241)
			(xy 287.967089 -48.971053) (xy 288.014695 -49.000107) (xy 288.057563 -49.035782) (xy 288.09478 -49.077319)
			(xy 288.125553 -49.123832) (xy 288.149225 -49.174329) (xy 288.165293 -49.227736) (xy 288.173413 -49.282912)
			(xy 288.173704 -49.29886) (xy 294.120822 -49.29886) (xy 294.124893 -49.243238) (xy 294.137019 -49.188801)
			(xy 294.156942 -49.13671) (xy 294.184238 -49.088075) (xy 294.218324 -49.043932) (xy 294.258473 -49.005223)
			(xy 294.303831 -48.972772) (xy 294.353431 -48.947271) (xy 294.406215 -48.929264) (xy 294.461058 -48.919134)
			(xy 294.516792 -48.917097) (xy 294.572229 -48.923197) (xy 294.626186 -48.937303) (xy 294.677515 -48.959115)
			(xy 294.725121 -48.988169) (xy 294.767989 -49.023844) (xy 294.805206 -49.065381) (xy 294.835979 -49.111894)
			(xy 294.859651 -49.162391) (xy 294.875719 -49.215798) (xy 294.883839 -49.270974) (xy 294.884348 -49.29886)
			(xy 294.883959 -49.320196) (xy 297.576492 -49.320196) (xy 297.580563 -49.264574) (xy 297.592689 -49.210137)
			(xy 297.612612 -49.158046) (xy 297.639908 -49.109411) (xy 297.673994 -49.065268) (xy 297.714143 -49.026559)
			(xy 297.759501 -48.994108) (xy 297.809101 -48.968607) (xy 297.861885 -48.9506) (xy 297.916728 -48.94047)
			(xy 297.972462 -48.938433) (xy 298.027899 -48.944533) (xy 298.081856 -48.958639) (xy 298.133185 -48.980451)
			(xy 298.180791 -49.009505) (xy 298.223659 -49.04518) (xy 298.260876 -49.086717) (xy 298.291649 -49.13323)
			(xy 298.294517 -49.139348) (xy 311.045604 -49.139348) (xy 311.049675 -49.083726) (xy 311.061801 -49.029289)
			(xy 311.081724 -48.977198) (xy 311.10902 -48.928563) (xy 311.143106 -48.88442) (xy 311.183255 -48.845711)
			(xy 311.228613 -48.81326) (xy 311.278213 -48.787759) (xy 311.330997 -48.769752) (xy 311.38584 -48.759622)
			(xy 311.441574 -48.757585) (xy 311.497011 -48.763685) (xy 311.550968 -48.777791) (xy 311.602297 -48.799603)
			(xy 311.649903 -48.828657) (xy 311.692771 -48.864332) (xy 311.729988 -48.905869) (xy 311.760761 -48.952382)
			(xy 311.784433 -49.002879) (xy 311.800501 -49.056286) (xy 311.808621 -49.111462) (xy 311.80913 -49.139348)
			(xy 311.808621 -49.167234) (xy 311.800501 -49.22241) (xy 311.787282 -49.266348) (xy 323.593204 -49.266348)
			(xy 323.597275 -49.210726) (xy 323.609401 -49.156289) (xy 323.629324 -49.104198) (xy 323.65662 -49.055563)
			(xy 323.690706 -49.01142) (xy 323.730855 -48.972711) (xy 323.776213 -48.94026) (xy 323.825813 -48.914759)
			(xy 323.878597 -48.896752) (xy 323.93344 -48.886622) (xy 323.989174 -48.884585) (xy 324.044611 -48.890685)
			(xy 324.098568 -48.904791) (xy 324.149897 -48.926603) (xy 324.197503 -48.955657) (xy 324.240371 -48.991332)
			(xy 324.277588 -49.032869) (xy 324.308361 -49.079382) (xy 324.312658 -49.088548) (xy 324.482204 -49.088548)
			(xy 324.486275 -49.032926) (xy 324.498401 -48.978489) (xy 324.518324 -48.926398) (xy 324.54562 -48.877763)
			(xy 324.579706 -48.83362) (xy 324.619855 -48.794911) (xy 324.665213 -48.76246) (xy 324.714813 -48.736959)
			(xy 324.767597 -48.718952) (xy 324.82244 -48.708822) (xy 324.878174 -48.706785) (xy 324.933611 -48.712885)
			(xy 324.987568 -48.726991) (xy 325.038897 -48.748803) (xy 325.086503 -48.777857) (xy 325.129371 -48.813532)
			(xy 325.166588 -48.855069) (xy 325.197361 -48.901582) (xy 325.218246 -48.946133) (xy 329.92238 -48.946133)
			(xy 329.92238 -48.894159) (xy 329.93051 -48.842824) (xy 329.946571 -48.793394) (xy 329.970167 -48.747084)
			(xy 330.000717 -48.705036) (xy 330.037468 -48.668285) (xy 330.079516 -48.637735) (xy 330.125826 -48.614139)
			(xy 330.175256 -48.598078) (xy 330.226591 -48.589948) (xy 330.278565 -48.589948) (xy 330.3299 -48.598078)
			(xy 330.37933 -48.614139) (xy 330.42564 -48.637735) (xy 330.467688 -48.668285) (xy 330.504439 -48.705036)
			(xy 330.534989 -48.747084) (xy 330.558585 -48.793394) (xy 330.574646 -48.842824) (xy 330.582776 -48.894159)
			(xy 330.583286 -48.920146) (xy 330.582776 -48.946133) (xy 331.55052 -48.946133) (xy 331.55052 -48.894159)
			(xy 331.55865 -48.842824) (xy 331.574711 -48.793394) (xy 331.598307 -48.747084) (xy 331.628857 -48.705036)
			(xy 331.665608 -48.668285) (xy 331.707656 -48.637735) (xy 331.753966 -48.614139) (xy 331.803396 -48.598078)
			(xy 331.854731 -48.589948) (xy 331.906705 -48.589948) (xy 331.95804 -48.598078) (xy 332.00747 -48.614139)
			(xy 332.05378 -48.637735) (xy 332.095828 -48.668285) (xy 332.132579 -48.705036) (xy 332.163129 -48.747084)
			(xy 332.186725 -48.793394) (xy 332.202786 -48.842824) (xy 332.210916 -48.894159) (xy 332.211426 -48.920146)
			(xy 332.210916 -48.946133) (xy 333.17866 -48.946133) (xy 333.17866 -48.894159) (xy 333.18679 -48.842824)
			(xy 333.202851 -48.793394) (xy 333.226447 -48.747084) (xy 333.256997 -48.705036) (xy 333.293748 -48.668285)
			(xy 333.335796 -48.637735) (xy 333.382106 -48.614139) (xy 333.431536 -48.598078) (xy 333.482871 -48.589948)
			(xy 333.534845 -48.589948) (xy 333.58618 -48.598078) (xy 333.63561 -48.614139) (xy 333.68192 -48.637735)
			(xy 333.723968 -48.668285) (xy 333.760719 -48.705036) (xy 333.791269 -48.747084) (xy 333.814865 -48.793394)
			(xy 333.830926 -48.842824) (xy 333.839056 -48.894159) (xy 333.839566 -48.920146) (xy 333.839056 -48.946133)
			(xy 340.7758 -48.946133) (xy 340.7758 -48.894159) (xy 340.78393 -48.842824) (xy 340.799991 -48.793394)
			(xy 340.823587 -48.747084) (xy 340.854137 -48.705036) (xy 340.890888 -48.668285) (xy 340.932936 -48.637735)
			(xy 340.979246 -48.614139) (xy 341.028676 -48.598078) (xy 341.080011 -48.589948) (xy 341.131985 -48.589948)
			(xy 341.18332 -48.598078) (xy 341.23275 -48.614139) (xy 341.27906 -48.637735) (xy 341.321108 -48.668285)
			(xy 341.357859 -48.705036) (xy 341.388409 -48.747084) (xy 341.412005 -48.793394) (xy 341.428066 -48.842824)
			(xy 341.436196 -48.894159) (xy 341.436706 -48.920146) (xy 341.436201 -48.945879) (xy 342.404956 -48.945879)
			(xy 342.404956 -48.893905) (xy 342.413086 -48.84257) (xy 342.429147 -48.79314) (xy 342.452743 -48.74683)
			(xy 342.483293 -48.704782) (xy 342.520044 -48.668031) (xy 342.562092 -48.637481) (xy 342.608402 -48.613885)
			(xy 342.657832 -48.597824) (xy 342.709167 -48.589694) (xy 342.761141 -48.589694) (xy 342.812476 -48.597824)
			(xy 342.861906 -48.613885) (xy 342.908216 -48.637481) (xy 342.950264 -48.668031) (xy 342.987015 -48.704782)
			(xy 343.017565 -48.74683) (xy 343.041161 -48.79314) (xy 343.057222 -48.84257) (xy 343.065352 -48.893905)
			(xy 343.065862 -48.919892) (xy 343.065352 -48.945879) (xy 343.057222 -48.997214) (xy 343.041161 -49.046644)
			(xy 343.017565 -49.092954) (xy 342.987015 -49.135002) (xy 342.950264 -49.171753) (xy 342.908216 -49.202303)
			(xy 342.861906 -49.225899) (xy 342.812476 -49.24196) (xy 342.761141 -49.25009) (xy 342.709167 -49.25009)
			(xy 342.657832 -49.24196) (xy 342.608402 -49.225899) (xy 342.562092 -49.202303) (xy 342.520044 -49.171753)
			(xy 342.483293 -49.135002) (xy 342.452743 -49.092954) (xy 342.429147 -49.046644) (xy 342.413086 -48.997214)
			(xy 342.404956 -48.945879) (xy 341.436201 -48.945879) (xy 341.436196 -48.946133) (xy 341.428066 -48.997468)
			(xy 341.412005 -49.046898) (xy 341.388409 -49.093208) (xy 341.357859 -49.135256) (xy 341.321108 -49.172007)
			(xy 341.27906 -49.202557) (xy 341.23275 -49.226153) (xy 341.18332 -49.242214) (xy 341.131985 -49.250344)
			(xy 341.080011 -49.250344) (xy 341.028676 -49.242214) (xy 340.979246 -49.226153) (xy 340.932936 -49.202557)
			(xy 340.890888 -49.172007) (xy 340.854137 -49.135256) (xy 340.823587 -49.093208) (xy 340.799991 -49.046898)
			(xy 340.78393 -48.997468) (xy 340.7758 -48.946133) (xy 333.839056 -48.946133) (xy 333.830926 -48.997468)
			(xy 333.814865 -49.046898) (xy 333.791269 -49.093208) (xy 333.760719 -49.135256) (xy 333.723968 -49.172007)
			(xy 333.68192 -49.202557) (xy 333.63561 -49.226153) (xy 333.58618 -49.242214) (xy 333.534845 -49.250344)
			(xy 333.482871 -49.250344) (xy 333.431536 -49.242214) (xy 333.382106 -49.226153) (xy 333.335796 -49.202557)
			(xy 333.293748 -49.172007) (xy 333.256997 -49.135256) (xy 333.226447 -49.093208) (xy 333.202851 -49.046898)
			(xy 333.18679 -48.997468) (xy 333.17866 -48.946133) (xy 332.210916 -48.946133) (xy 332.202786 -48.997468)
			(xy 332.186725 -49.046898) (xy 332.163129 -49.093208) (xy 332.132579 -49.135256) (xy 332.095828 -49.172007)
			(xy 332.05378 -49.202557) (xy 332.00747 -49.226153) (xy 331.95804 -49.242214) (xy 331.906705 -49.250344)
			(xy 331.854731 -49.250344) (xy 331.803396 -49.242214) (xy 331.753966 -49.226153) (xy 331.707656 -49.202557)
			(xy 331.665608 -49.172007) (xy 331.628857 -49.135256) (xy 331.598307 -49.093208) (xy 331.574711 -49.046898)
			(xy 331.55865 -48.997468) (xy 331.55052 -48.946133) (xy 330.582776 -48.946133) (xy 330.574646 -48.997468)
			(xy 330.558585 -49.046898) (xy 330.534989 -49.093208) (xy 330.504439 -49.135256) (xy 330.467688 -49.172007)
			(xy 330.42564 -49.202557) (xy 330.37933 -49.226153) (xy 330.3299 -49.242214) (xy 330.278565 -49.250344)
			(xy 330.226591 -49.250344) (xy 330.175256 -49.242214) (xy 330.125826 -49.226153) (xy 330.079516 -49.202557)
			(xy 330.037468 -49.172007) (xy 330.000717 -49.135256) (xy 329.970167 -49.093208) (xy 329.946571 -49.046898)
			(xy 329.93051 -48.997468) (xy 329.92238 -48.946133) (xy 325.218246 -48.946133) (xy 325.221033 -48.952079)
			(xy 325.237101 -49.005486) (xy 325.245221 -49.060662) (xy 325.24573 -49.088548) (xy 325.245221 -49.116434)
			(xy 325.237101 -49.17161) (xy 325.221033 -49.225017) (xy 325.197361 -49.275514) (xy 325.166588 -49.322027)
			(xy 325.129371 -49.363564) (xy 325.086503 -49.399239) (xy 325.058985 -49.416033) (xy 328.29551 -49.416033)
			(xy 328.29551 -49.364059) (xy 328.30364 -49.312724) (xy 328.319701 -49.263294) (xy 328.343297 -49.216984)
			(xy 328.373847 -49.174936) (xy 328.410598 -49.138185) (xy 328.452646 -49.107635) (xy 328.498956 -49.084039)
			(xy 328.548386 -49.067978) (xy 328.599721 -49.059848) (xy 328.651695 -49.059848) (xy 328.70303 -49.067978)
			(xy 328.75246 -49.084039) (xy 328.79877 -49.107635) (xy 328.840818 -49.138185) (xy 328.877569 -49.174936)
			(xy 328.908119 -49.216984) (xy 328.931715 -49.263294) (xy 328.947776 -49.312724) (xy 328.955906 -49.364059)
			(xy 328.956416 -49.390046) (xy 328.955906 -49.416033) (xy 329.107548 -49.416033) (xy 329.107548 -49.364059)
			(xy 329.115678 -49.312724) (xy 329.131739 -49.263294) (xy 329.155335 -49.216984) (xy 329.185885 -49.174936)
			(xy 329.222636 -49.138185) (xy 329.264684 -49.107635) (xy 329.310994 -49.084039) (xy 329.360424 -49.067978)
			(xy 329.411759 -49.059848) (xy 329.463733 -49.059848) (xy 329.515068 -49.067978) (xy 329.564498 -49.084039)
			(xy 329.610808 -49.107635) (xy 329.652856 -49.138185) (xy 329.689607 -49.174936) (xy 329.720157 -49.216984)
			(xy 329.743753 -49.263294) (xy 329.759814 -49.312724) (xy 329.767944 -49.364059) (xy 329.768454 -49.390046)
			(xy 329.767944 -49.416033) (xy 330.73518 -49.416033) (xy 330.73518 -49.364059) (xy 330.74331 -49.312724)
			(xy 330.759371 -49.263294) (xy 330.782967 -49.216984) (xy 330.813517 -49.174936) (xy 330.850268 -49.138185)
			(xy 330.892316 -49.107635) (xy 330.938626 -49.084039) (xy 330.988056 -49.067978) (xy 331.039391 -49.059848)
			(xy 331.091365 -49.059848) (xy 331.1427 -49.067978) (xy 331.19213 -49.084039) (xy 331.23844 -49.107635)
			(xy 331.280488 -49.138185) (xy 331.317239 -49.174936) (xy 331.347789 -49.216984) (xy 331.371385 -49.263294)
			(xy 331.387446 -49.312724) (xy 331.395576 -49.364059) (xy 331.396086 -49.390046) (xy 331.395576 -49.416033)
			(xy 332.36332 -49.416033) (xy 332.36332 -49.364059) (xy 332.37145 -49.312724) (xy 332.387511 -49.263294)
			(xy 332.411107 -49.216984) (xy 332.441657 -49.174936) (xy 332.478408 -49.138185) (xy 332.520456 -49.107635)
			(xy 332.566766 -49.084039) (xy 332.616196 -49.067978) (xy 332.667531 -49.059848) (xy 332.719505 -49.059848)
			(xy 332.77084 -49.067978) (xy 332.82027 -49.084039) (xy 332.86658 -49.107635) (xy 332.908628 -49.138185)
			(xy 332.945379 -49.174936) (xy 332.975929 -49.216984) (xy 332.999525 -49.263294) (xy 333.015586 -49.312724)
			(xy 333.023716 -49.364059) (xy 333.024226 -49.390046) (xy 333.023716 -49.416033) (xy 333.015586 -49.467368)
			(xy 332.999525 -49.516798) (xy 332.975929 -49.563108) (xy 332.945379 -49.605156) (xy 332.908628 -49.641907)
			(xy 332.86658 -49.672457) (xy 332.858875 -49.676383) (xy 333.76921 -49.676383) (xy 333.76921 -49.624409)
			(xy 333.77734 -49.573074) (xy 333.793401 -49.523644) (xy 333.816997 -49.477334) (xy 333.847547 -49.435286)
			(xy 333.884298 -49.398535) (xy 333.926346 -49.367985) (xy 333.972656 -49.344389) (xy 334.022086 -49.328328)
			(xy 334.073421 -49.320198) (xy 334.125395 -49.320198) (xy 334.17673 -49.328328) (xy 334.22616 -49.344389)
			(xy 334.27247 -49.367985) (xy 334.314518 -49.398535) (xy 334.351269 -49.435286) (xy 334.381819 -49.477334)
			(xy 334.405415 -49.523644) (xy 334.421476 -49.573074) (xy 334.429606 -49.624409) (xy 334.430116 -49.650396)
			(xy 334.429606 -49.676383) (xy 337.76971 -49.676383) (xy 337.76971 -49.624409) (xy 337.77784 -49.573074)
			(xy 337.793901 -49.523644) (xy 337.817497 -49.477334) (xy 337.848047 -49.435286) (xy 337.884798 -49.398535)
			(xy 337.926846 -49.367985) (xy 337.973156 -49.344389) (xy 338.022586 -49.328328) (xy 338.073921 -49.320198)
			(xy 338.125895 -49.320198) (xy 338.17723 -49.328328) (xy 338.22666 -49.344389) (xy 338.27297 -49.367985)
			(xy 338.315018 -49.398535) (xy 338.351769 -49.435286) (xy 338.382319 -49.477334) (xy 338.405915 -49.523644)
			(xy 338.421976 -49.573074) (xy 338.430106 -49.624409) (xy 338.430616 -49.650396) (xy 338.430106 -49.676383)
			(xy 338.56981 -49.676383) (xy 338.56981 -49.624409) (xy 338.57794 -49.573074) (xy 338.594001 -49.523644)
			(xy 338.617597 -49.477334) (xy 338.648147 -49.435286) (xy 338.684898 -49.398535) (xy 338.726946 -49.367985)
			(xy 338.773256 -49.344389) (xy 338.822686 -49.328328) (xy 338.874021 -49.320198) (xy 338.925995 -49.320198)
			(xy 338.97733 -49.328328) (xy 339.02676 -49.344389) (xy 339.07307 -49.367985) (xy 339.115118 -49.398535)
			(xy 339.132616 -49.416033) (xy 341.5886 -49.416033) (xy 341.5886 -49.364059) (xy 341.59673 -49.312724)
			(xy 341.612791 -49.263294) (xy 341.636387 -49.216984) (xy 341.666937 -49.174936) (xy 341.703688 -49.138185)
			(xy 341.745736 -49.107635) (xy 341.792046 -49.084039) (xy 341.841476 -49.067978) (xy 341.892811 -49.059848)
			(xy 341.944785 -49.059848) (xy 341.99612 -49.067978) (xy 342.04555 -49.084039) (xy 342.09186 -49.107635)
			(xy 342.133908 -49.138185) (xy 342.170659 -49.174936) (xy 342.201209 -49.216984) (xy 342.224805 -49.263294)
			(xy 342.240866 -49.312724) (xy 342.248996 -49.364059) (xy 342.249506 -49.390046) (xy 342.248996 -49.416033)
			(xy 342.240866 -49.467368) (xy 342.224805 -49.516798) (xy 342.201209 -49.563108) (xy 342.170659 -49.605156)
			(xy 342.133908 -49.641907) (xy 342.09186 -49.672457) (xy 342.04555 -49.696053) (xy 341.99612 -49.712114)
			(xy 341.944785 -49.720244) (xy 341.892811 -49.720244) (xy 341.841476 -49.712114) (xy 341.792046 -49.696053)
			(xy 341.745736 -49.672457) (xy 341.703688 -49.641907) (xy 341.666937 -49.605156) (xy 341.636387 -49.563108)
			(xy 341.612791 -49.516798) (xy 341.59673 -49.467368) (xy 341.5886 -49.416033) (xy 339.132616 -49.416033)
			(xy 339.151869 -49.435286) (xy 339.182419 -49.477334) (xy 339.206015 -49.523644) (xy 339.222076 -49.573074)
			(xy 339.230206 -49.624409) (xy 339.230716 -49.650396) (xy 339.230206 -49.676383) (xy 339.222076 -49.727718)
			(xy 339.206015 -49.777148) (xy 339.182419 -49.823458) (xy 339.151869 -49.865506) (xy 339.115118 -49.902257)
			(xy 339.07307 -49.932807) (xy 339.02676 -49.956403) (xy 338.97733 -49.972464) (xy 338.925995 -49.980594)
			(xy 338.874021 -49.980594) (xy 338.822686 -49.972464) (xy 338.773256 -49.956403) (xy 338.726946 -49.932807)
			(xy 338.684898 -49.902257) (xy 338.648147 -49.865506) (xy 338.617597 -49.823458) (xy 338.594001 -49.777148)
			(xy 338.57794 -49.727718) (xy 338.56981 -49.676383) (xy 338.430106 -49.676383) (xy 338.421976 -49.727718)
			(xy 338.405915 -49.777148) (xy 338.382319 -49.823458) (xy 338.351769 -49.865506) (xy 338.315018 -49.902257)
			(xy 338.27297 -49.932807) (xy 338.22666 -49.956403) (xy 338.17723 -49.972464) (xy 338.125895 -49.980594)
			(xy 338.073921 -49.980594) (xy 338.022586 -49.972464) (xy 337.973156 -49.956403) (xy 337.926846 -49.932807)
			(xy 337.884798 -49.902257) (xy 337.848047 -49.865506) (xy 337.817497 -49.823458) (xy 337.793901 -49.777148)
			(xy 337.77784 -49.727718) (xy 337.76971 -49.676383) (xy 334.429606 -49.676383) (xy 334.421476 -49.727718)
			(xy 334.405415 -49.777148) (xy 334.381819 -49.823458) (xy 334.351269 -49.865506) (xy 334.314518 -49.902257)
			(xy 334.27247 -49.932807) (xy 334.22616 -49.956403) (xy 334.17673 -49.972464) (xy 334.125395 -49.980594)
			(xy 334.073421 -49.980594) (xy 334.022086 -49.972464) (xy 333.972656 -49.956403) (xy 333.926346 -49.932807)
			(xy 333.884298 -49.902257) (xy 333.847547 -49.865506) (xy 333.816997 -49.823458) (xy 333.793401 -49.777148)
			(xy 333.77734 -49.727718) (xy 333.76921 -49.676383) (xy 332.858875 -49.676383) (xy 332.82027 -49.696053)
			(xy 332.77084 -49.712114) (xy 332.719505 -49.720244) (xy 332.667531 -49.720244) (xy 332.616196 -49.712114)
			(xy 332.566766 -49.696053) (xy 332.520456 -49.672457) (xy 332.478408 -49.641907) (xy 332.441657 -49.605156)
			(xy 332.411107 -49.563108) (xy 332.387511 -49.516798) (xy 332.37145 -49.467368) (xy 332.36332 -49.416033)
			(xy 331.395576 -49.416033) (xy 331.387446 -49.467368) (xy 331.371385 -49.516798) (xy 331.347789 -49.563108)
			(xy 331.317239 -49.605156) (xy 331.280488 -49.641907) (xy 331.23844 -49.672457) (xy 331.19213 -49.696053)
			(xy 331.1427 -49.712114) (xy 331.091365 -49.720244) (xy 331.039391 -49.720244) (xy 330.988056 -49.712114)
			(xy 330.938626 -49.696053) (xy 330.892316 -49.672457) (xy 330.850268 -49.641907) (xy 330.813517 -49.605156)
			(xy 330.782967 -49.563108) (xy 330.759371 -49.516798) (xy 330.74331 -49.467368) (xy 330.73518 -49.416033)
			(xy 329.767944 -49.416033) (xy 329.759814 -49.467368) (xy 329.743753 -49.516798) (xy 329.720157 -49.563108)
			(xy 329.689607 -49.605156) (xy 329.652856 -49.641907) (xy 329.610808 -49.672457) (xy 329.564498 -49.696053)
			(xy 329.515068 -49.712114) (xy 329.463733 -49.720244) (xy 329.411759 -49.720244) (xy 329.360424 -49.712114)
			(xy 329.310994 -49.696053) (xy 329.264684 -49.672457) (xy 329.222636 -49.641907) (xy 329.185885 -49.605156)
			(xy 329.155335 -49.563108) (xy 329.131739 -49.516798) (xy 329.115678 -49.467368) (xy 329.107548 -49.416033)
			(xy 328.955906 -49.416033) (xy 328.947776 -49.467368) (xy 328.931715 -49.516798) (xy 328.908119 -49.563108)
			(xy 328.877569 -49.605156) (xy 328.840818 -49.641907) (xy 328.79877 -49.672457) (xy 328.75246 -49.696053)
			(xy 328.70303 -49.712114) (xy 328.651695 -49.720244) (xy 328.599721 -49.720244) (xy 328.548386 -49.712114)
			(xy 328.498956 -49.696053) (xy 328.452646 -49.672457) (xy 328.410598 -49.641907) (xy 328.373847 -49.605156)
			(xy 328.343297 -49.563108) (xy 328.319701 -49.516798) (xy 328.30364 -49.467368) (xy 328.29551 -49.416033)
			(xy 325.058985 -49.416033) (xy 325.038897 -49.428293) (xy 324.987568 -49.450105) (xy 324.933611 -49.464211)
			(xy 324.878174 -49.470311) (xy 324.82244 -49.468274) (xy 324.767597 -49.458144) (xy 324.714813 -49.440137)
			(xy 324.665213 -49.414636) (xy 324.619855 -49.382185) (xy 324.579706 -49.343476) (xy 324.54562 -49.299333)
			(xy 324.518324 -49.250698) (xy 324.498401 -49.198607) (xy 324.486275 -49.14417) (xy 324.482204 -49.088548)
			(xy 324.312658 -49.088548) (xy 324.332033 -49.129879) (xy 324.348101 -49.183286) (xy 324.356221 -49.238462)
			(xy 324.35673 -49.266348) (xy 324.356221 -49.294234) (xy 324.348101 -49.34941) (xy 324.332033 -49.402817)
			(xy 324.308361 -49.453314) (xy 324.277588 -49.499827) (xy 324.240371 -49.541364) (xy 324.197503 -49.577039)
			(xy 324.149897 -49.606093) (xy 324.098568 -49.627905) (xy 324.044611 -49.642011) (xy 323.989174 -49.648111)
			(xy 323.93344 -49.646074) (xy 323.878597 -49.635944) (xy 323.825813 -49.617937) (xy 323.776213 -49.592436)
			(xy 323.730855 -49.559985) (xy 323.690706 -49.521276) (xy 323.65662 -49.477133) (xy 323.629324 -49.428498)
			(xy 323.609401 -49.376407) (xy 323.597275 -49.32197) (xy 323.593204 -49.266348) (xy 311.787282 -49.266348)
			(xy 311.784433 -49.275817) (xy 311.760761 -49.326314) (xy 311.729988 -49.372827) (xy 311.692771 -49.414364)
			(xy 311.649903 -49.450039) (xy 311.602297 -49.479093) (xy 311.550968 -49.500905) (xy 311.497011 -49.515011)
			(xy 311.441574 -49.521111) (xy 311.38584 -49.519074) (xy 311.330997 -49.508944) (xy 311.278213 -49.490937)
			(xy 311.228613 -49.465436) (xy 311.183255 -49.432985) (xy 311.143106 -49.394276) (xy 311.10902 -49.350133)
			(xy 311.081724 -49.301498) (xy 311.061801 -49.249407) (xy 311.049675 -49.19497) (xy 311.045604 -49.139348)
			(xy 298.294517 -49.139348) (xy 298.315321 -49.183727) (xy 298.331389 -49.237134) (xy 298.339509 -49.29231)
			(xy 298.340018 -49.320196) (xy 298.339509 -49.348082) (xy 298.331389 -49.403258) (xy 298.315321 -49.456665)
			(xy 298.291649 -49.507162) (xy 298.260876 -49.553675) (xy 298.223659 -49.595212) (xy 298.191532 -49.621948)
			(xy 305.540662 -49.621948) (xy 305.544733 -49.566326) (xy 305.556859 -49.511889) (xy 305.576782 -49.459798)
			(xy 305.604078 -49.411163) (xy 305.638164 -49.36702) (xy 305.678313 -49.328311) (xy 305.723671 -49.29586)
			(xy 305.773271 -49.270359) (xy 305.826055 -49.252352) (xy 305.880898 -49.242222) (xy 305.936632 -49.240185)
			(xy 305.992069 -49.246285) (xy 306.046026 -49.260391) (xy 306.097355 -49.282203) (xy 306.144961 -49.311257)
			(xy 306.187829 -49.346932) (xy 306.225046 -49.388469) (xy 306.255819 -49.434982) (xy 306.279491 -49.485479)
			(xy 306.295559 -49.538886) (xy 306.303679 -49.594062) (xy 306.304188 -49.621948) (xy 307.902862 -49.621948)
			(xy 307.906933 -49.566326) (xy 307.919059 -49.511889) (xy 307.938982 -49.459798) (xy 307.966278 -49.411163)
			(xy 308.000364 -49.36702) (xy 308.040513 -49.328311) (xy 308.085871 -49.29586) (xy 308.135471 -49.270359)
			(xy 308.188255 -49.252352) (xy 308.243098 -49.242222) (xy 308.298832 -49.240185) (xy 308.354269 -49.246285)
			(xy 308.408226 -49.260391) (xy 308.459555 -49.282203) (xy 308.507161 -49.311257) (xy 308.550029 -49.346932)
			(xy 308.587246 -49.388469) (xy 308.618019 -49.434982) (xy 308.641691 -49.485479) (xy 308.657759 -49.538886)
			(xy 308.665879 -49.594062) (xy 308.666388 -49.621948) (xy 308.665879 -49.649834) (xy 308.657759 -49.70501)
			(xy 308.641691 -49.758417) (xy 308.618019 -49.808914) (xy 308.587246 -49.855427) (xy 308.550029 -49.896964)
			(xy 308.507161 -49.932639) (xy 308.459555 -49.961693) (xy 308.408226 -49.983505) (xy 308.354269 -49.997611)
			(xy 308.298832 -50.003711) (xy 308.243098 -50.001674) (xy 308.188255 -49.991544) (xy 308.135471 -49.973537)
			(xy 308.085871 -49.948036) (xy 308.040513 -49.915585) (xy 308.000364 -49.876876) (xy 307.966278 -49.832733)
			(xy 307.938982 -49.784098) (xy 307.919059 -49.732007) (xy 307.906933 -49.67757) (xy 307.902862 -49.621948)
			(xy 306.304188 -49.621948) (xy 306.303679 -49.649834) (xy 306.295559 -49.70501) (xy 306.279491 -49.758417)
			(xy 306.255819 -49.808914) (xy 306.225046 -49.855427) (xy 306.187829 -49.896964) (xy 306.144961 -49.932639)
			(xy 306.097355 -49.961693) (xy 306.046026 -49.983505) (xy 305.992069 -49.997611) (xy 305.936632 -50.003711)
			(xy 305.880898 -50.001674) (xy 305.826055 -49.991544) (xy 305.773271 -49.973537) (xy 305.723671 -49.948036)
			(xy 305.678313 -49.915585) (xy 305.638164 -49.876876) (xy 305.604078 -49.832733) (xy 305.576782 -49.784098)
			(xy 305.556859 -49.732007) (xy 305.544733 -49.67757) (xy 305.540662 -49.621948) (xy 298.191532 -49.621948)
			(xy 298.180791 -49.630887) (xy 298.133185 -49.659941) (xy 298.081856 -49.681753) (xy 298.027899 -49.695859)
			(xy 297.972462 -49.701959) (xy 297.916728 -49.699922) (xy 297.861885 -49.689792) (xy 297.809101 -49.671785)
			(xy 297.759501 -49.646284) (xy 297.714143 -49.613833) (xy 297.673994 -49.575124) (xy 297.639908 -49.530981)
			(xy 297.612612 -49.482346) (xy 297.592689 -49.430255) (xy 297.580563 -49.375818) (xy 297.576492 -49.320196)
			(xy 294.883959 -49.320196) (xy 294.883839 -49.326746) (xy 294.875719 -49.381922) (xy 294.859651 -49.435329)
			(xy 294.835979 -49.485826) (xy 294.805206 -49.532339) (xy 294.767989 -49.573876) (xy 294.725121 -49.609551)
			(xy 294.677515 -49.638605) (xy 294.626186 -49.660417) (xy 294.572229 -49.674523) (xy 294.516792 -49.680623)
			(xy 294.461058 -49.678586) (xy 294.406215 -49.668456) (xy 294.353431 -49.650449) (xy 294.303831 -49.624948)
			(xy 294.258473 -49.592497) (xy 294.218324 -49.553788) (xy 294.184238 -49.509645) (xy 294.156942 -49.46101)
			(xy 294.137019 -49.408919) (xy 294.124893 -49.354482) (xy 294.120822 -49.29886) (xy 288.173704 -49.29886)
			(xy 288.173922 -49.310798) (xy 288.173413 -49.338684) (xy 288.165293 -49.39386) (xy 288.149225 -49.447267)
			(xy 288.125553 -49.497764) (xy 288.09478 -49.544277) (xy 288.057563 -49.585814) (xy 288.014695 -49.621489)
			(xy 287.967089 -49.650543) (xy 287.91576 -49.672355) (xy 287.861803 -49.686461) (xy 287.806366 -49.692561)
			(xy 287.750632 -49.690524) (xy 287.695789 -49.680394) (xy 287.643005 -49.662387) (xy 287.593405 -49.636886)
			(xy 287.548047 -49.604435) (xy 287.507898 -49.565726) (xy 287.473812 -49.521583) (xy 287.446516 -49.472948)
			(xy 287.426593 -49.420857) (xy 287.414467 -49.36642) (xy 287.410396 -49.310798) (xy 283.000196 -49.310798)
			(xy 282.38704 -49.923954) (xy 282.38704 -50.116486) (xy 285.331914 -50.116486) (xy 285.335985 -50.060864)
			(xy 285.348111 -50.006427) (xy 285.368034 -49.954336) (xy 285.39533 -49.905701) (xy 285.429416 -49.861558)
			(xy 285.469565 -49.822849) (xy 285.514923 -49.790398) (xy 285.564523 -49.764897) (xy 285.617307 -49.74689)
			(xy 285.67215 -49.73676) (xy 285.727884 -49.734723) (xy 285.783321 -49.740823) (xy 285.837278 -49.754929)
			(xy 285.888607 -49.776741) (xy 285.936213 -49.805795) (xy 285.979081 -49.84147) (xy 286.016298 -49.883007)
			(xy 286.047071 -49.92952) (xy 286.070743 -49.980017) (xy 286.086811 -50.033424) (xy 286.094931 -50.0886)
			(xy 286.09544 -50.116486) (xy 286.094931 -50.144372) (xy 286.086811 -50.199548) (xy 286.070743 -50.252955)
			(xy 286.047071 -50.303452) (xy 286.027928 -50.332386) (xy 286.253172 -50.332386) (xy 286.257243 -50.276764)
			(xy 286.269369 -50.222327) (xy 286.289292 -50.170236) (xy 286.316588 -50.121601) (xy 286.350674 -50.077458)
			(xy 286.390823 -50.038749) (xy 286.436181 -50.006298) (xy 286.485781 -49.980797) (xy 286.538565 -49.96279)
			(xy 286.593408 -49.95266) (xy 286.649142 -49.950623) (xy 286.704579 -49.956723) (xy 286.758536 -49.970829)
			(xy 286.809865 -49.992641) (xy 286.857471 -50.021695) (xy 286.900339 -50.05737) (xy 286.937556 -50.098907)
			(xy 286.965655 -50.141378) (xy 291.950138 -50.141378) (xy 291.954209 -50.085756) (xy 291.966335 -50.031319)
			(xy 291.986258 -49.979228) (xy 292.013554 -49.930593) (xy 292.04764 -49.88645) (xy 292.087789 -49.847741)
			(xy 292.133147 -49.81529) (xy 292.182747 -49.789789) (xy 292.235531 -49.771782) (xy 292.290374 -49.761652)
			(xy 292.346108 -49.759615) (xy 292.401545 -49.765715) (xy 292.455502 -49.779821) (xy 292.506831 -49.801633)
			(xy 292.554437 -49.830687) (xy 292.597305 -49.866362) (xy 292.634522 -49.907899) (xy 292.665295 -49.954412)
			(xy 292.688967 -50.004909) (xy 292.705035 -50.058316) (xy 292.711839 -50.104548) (xy 295.350182 -50.104548)
			(xy 295.354253 -50.048926) (xy 295.366379 -49.994489) (xy 295.386302 -49.942398) (xy 295.413598 -49.893763)
			(xy 295.447684 -49.84962) (xy 295.487833 -49.810911) (xy 295.533191 -49.77846) (xy 295.582791 -49.752959)
			(xy 295.635575 -49.734952) (xy 295.690418 -49.724822) (xy 295.746152 -49.722785) (xy 295.801589 -49.728885)
			(xy 295.855546 -49.742991) (xy 295.906875 -49.764803) (xy 295.954481 -49.793857) (xy 295.997349 -49.829532)
			(xy 296.034566 -49.871069) (xy 296.065339 -49.917582) (xy 296.089011 -49.968079) (xy 296.105079 -50.021486)
			(xy 296.113199 -50.076662) (xy 296.113708 -50.104548) (xy 296.113523 -50.114708) (xy 311.966862 -50.114708)
			(xy 311.970933 -50.059086) (xy 311.983059 -50.004649) (xy 312.002982 -49.952558) (xy 312.030278 -49.903923)
			(xy 312.064364 -49.85978) (xy 312.104513 -49.821071) (xy 312.149871 -49.78862) (xy 312.199471 -49.763119)
			(xy 312.252255 -49.745112) (xy 312.307098 -49.734982) (xy 312.362832 -49.732945) (xy 312.418269 -49.739045)
			(xy 312.472226 -49.753151) (xy 312.523555 -49.774963) (xy 312.571161 -49.804017) (xy 312.614029 -49.839692)
			(xy 312.651246 -49.881229) (xy 312.682019 -49.927742) (xy 312.705691 -49.978239) (xy 312.721759 -50.031646)
			(xy 312.729879 -50.086822) (xy 312.730388 -50.114708) (xy 312.729879 -50.142594) (xy 312.728002 -50.155348)
			(xy 313.712604 -50.155348) (xy 313.716675 -50.099726) (xy 313.728801 -50.045289) (xy 313.748724 -49.993198)
			(xy 313.77602 -49.944563) (xy 313.810106 -49.90042) (xy 313.850255 -49.861711) (xy 313.895613 -49.82926)
			(xy 313.945213 -49.803759) (xy 313.997997 -49.785752) (xy 314.05284 -49.775622) (xy 314.108574 -49.773585)
			(xy 314.164011 -49.779685) (xy 314.217968 -49.793791) (xy 314.269297 -49.815603) (xy 314.316903 -49.844657)
			(xy 314.359771 -49.880332) (xy 314.364789 -49.885933) (xy 329.92238 -49.885933) (xy 329.92238 -49.833959)
			(xy 329.93051 -49.782624) (xy 329.946571 -49.733194) (xy 329.970167 -49.686884) (xy 330.000717 -49.644836)
			(xy 330.037468 -49.608085) (xy 330.079516 -49.577535) (xy 330.125826 -49.553939) (xy 330.175256 -49.537878)
			(xy 330.226591 -49.529748) (xy 330.278565 -49.529748) (xy 330.3299 -49.537878) (xy 330.37933 -49.553939)
			(xy 330.42564 -49.577535) (xy 330.467688 -49.608085) (xy 330.504439 -49.644836) (xy 330.534989 -49.686884)
			(xy 330.558585 -49.733194) (xy 330.574646 -49.782624) (xy 330.582776 -49.833959) (xy 330.583286 -49.859946)
			(xy 330.582776 -49.885933) (xy 331.55052 -49.885933) (xy 331.55052 -49.833959) (xy 331.55865 -49.782624)
			(xy 331.574711 -49.733194) (xy 331.598307 -49.686884) (xy 331.628857 -49.644836) (xy 331.665608 -49.608085)
			(xy 331.707656 -49.577535) (xy 331.753966 -49.553939) (xy 331.803396 -49.537878) (xy 331.854731 -49.529748)
			(xy 331.906705 -49.529748) (xy 331.95804 -49.537878) (xy 332.00747 -49.553939) (xy 332.05378 -49.577535)
			(xy 332.095828 -49.608085) (xy 332.132579 -49.644836) (xy 332.163129 -49.686884) (xy 332.186725 -49.733194)
			(xy 332.202786 -49.782624) (xy 332.210916 -49.833959) (xy 332.211426 -49.859946) (xy 332.210916 -49.885933)
			(xy 332.202786 -49.937268) (xy 332.186725 -49.986698) (xy 332.163129 -50.033008) (xy 332.132579 -50.075056)
			(xy 332.095828 -50.111807) (xy 332.05378 -50.142357) (xy 332.00747 -50.165953) (xy 331.95804 -50.182014)
			(xy 331.906705 -50.190144) (xy 331.854731 -50.190144) (xy 331.803396 -50.182014) (xy 331.753966 -50.165953)
			(xy 331.707656 -50.142357) (xy 331.665608 -50.111807) (xy 331.628857 -50.075056) (xy 331.598307 -50.033008)
			(xy 331.574711 -49.986698) (xy 331.55865 -49.937268) (xy 331.55052 -49.885933) (xy 330.582776 -49.885933)
			(xy 330.574646 -49.937268) (xy 330.558585 -49.986698) (xy 330.534989 -50.033008) (xy 330.504439 -50.075056)
			(xy 330.467688 -50.111807) (xy 330.42564 -50.142357) (xy 330.37933 -50.165953) (xy 330.3299 -50.182014)
			(xy 330.278565 -50.190144) (xy 330.226591 -50.190144) (xy 330.175256 -50.182014) (xy 330.125826 -50.165953)
			(xy 330.079516 -50.142357) (xy 330.037468 -50.111807) (xy 330.000717 -50.075056) (xy 329.970167 -50.033008)
			(xy 329.946571 -49.986698) (xy 329.93051 -49.937268) (xy 329.92238 -49.885933) (xy 314.364789 -49.885933)
			(xy 314.396988 -49.921869) (xy 314.427761 -49.968382) (xy 314.451433 -50.018879) (xy 314.467501 -50.072286)
			(xy 314.475621 -50.127462) (xy 314.47613 -50.155348) (xy 314.475621 -50.183234) (xy 314.467501 -50.23841)
			(xy 314.451433 -50.291817) (xy 314.427761 -50.342314) (xy 314.418817 -50.355833) (xy 328.29551 -50.355833)
			(xy 328.29551 -50.303859) (xy 328.30364 -50.252524) (xy 328.319701 -50.203094) (xy 328.343297 -50.156784)
			(xy 328.373847 -50.114736) (xy 328.410598 -50.077985) (xy 328.452646 -50.047435) (xy 328.498956 -50.023839)
			(xy 328.548386 -50.007778) (xy 328.599721 -49.999648) (xy 328.651695 -49.999648) (xy 328.70303 -50.007778)
			(xy 328.75246 -50.023839) (xy 328.79877 -50.047435) (xy 328.840818 -50.077985) (xy 328.877569 -50.114736)
			(xy 328.908119 -50.156784) (xy 328.931715 -50.203094) (xy 328.947776 -50.252524) (xy 328.955906 -50.303859)
			(xy 328.956416 -50.329846) (xy 328.955906 -50.355833) (xy 329.107548 -50.355833) (xy 329.107548 -50.303859)
			(xy 329.115678 -50.252524) (xy 329.131739 -50.203094) (xy 329.155335 -50.156784) (xy 329.185885 -50.114736)
			(xy 329.222636 -50.077985) (xy 329.264684 -50.047435) (xy 329.310994 -50.023839) (xy 329.360424 -50.007778)
			(xy 329.411759 -49.999648) (xy 329.463733 -49.999648) (xy 329.515068 -50.007778) (xy 329.564498 -50.023839)
			(xy 329.610808 -50.047435) (xy 329.652856 -50.077985) (xy 329.689607 -50.114736) (xy 329.720157 -50.156784)
			(xy 329.743753 -50.203094) (xy 329.759814 -50.252524) (xy 329.767944 -50.303859) (xy 329.768454 -50.329846)
			(xy 329.767944 -50.355833) (xy 330.73518 -50.355833) (xy 330.73518 -50.303859) (xy 330.74331 -50.252524)
			(xy 330.759371 -50.203094) (xy 330.782967 -50.156784) (xy 330.813517 -50.114736) (xy 330.850268 -50.077985)
			(xy 330.892316 -50.047435) (xy 330.938626 -50.023839) (xy 330.988056 -50.007778) (xy 331.039391 -49.999648)
			(xy 331.091365 -49.999648) (xy 331.1427 -50.007778) (xy 331.19213 -50.023839) (xy 331.23844 -50.047435)
			(xy 331.280488 -50.077985) (xy 331.317239 -50.114736) (xy 331.347789 -50.156784) (xy 331.371385 -50.203094)
			(xy 331.387446 -50.252524) (xy 331.395576 -50.303859) (xy 331.396086 -50.329846) (xy 331.395576 -50.355833)
			(xy 332.36332 -50.355833) (xy 332.36332 -50.303859) (xy 332.37145 -50.252524) (xy 332.387511 -50.203094)
			(xy 332.411107 -50.156784) (xy 332.441657 -50.114736) (xy 332.478408 -50.077985) (xy 332.520456 -50.047435)
			(xy 332.566766 -50.023839) (xy 332.616196 -50.007778) (xy 332.667531 -49.999648) (xy 332.719505 -49.999648)
			(xy 332.77084 -50.007778) (xy 332.82027 -50.023839) (xy 332.86658 -50.047435) (xy 332.908628 -50.077985)
			(xy 332.945379 -50.114736) (xy 332.975929 -50.156784) (xy 332.999525 -50.203094) (xy 333.015586 -50.252524)
			(xy 333.023716 -50.303859) (xy 333.024226 -50.329846) (xy 333.023716 -50.355833) (xy 333.015586 -50.407168)
			(xy 332.999525 -50.456598) (xy 332.975929 -50.502908) (xy 332.945379 -50.544956) (xy 332.908628 -50.581707)
			(xy 332.86658 -50.612257) (xy 332.82027 -50.635853) (xy 332.77084 -50.651914) (xy 332.719505 -50.660044)
			(xy 332.667531 -50.660044) (xy 332.616196 -50.651914) (xy 332.566766 -50.635853) (xy 332.520456 -50.612257)
			(xy 332.478408 -50.581707) (xy 332.441657 -50.544956) (xy 332.411107 -50.502908) (xy 332.387511 -50.456598)
			(xy 332.37145 -50.407168) (xy 332.36332 -50.355833) (xy 331.395576 -50.355833) (xy 331.387446 -50.407168)
			(xy 331.371385 -50.456598) (xy 331.347789 -50.502908) (xy 331.317239 -50.544956) (xy 331.280488 -50.581707)
			(xy 331.23844 -50.612257) (xy 331.19213 -50.635853) (xy 331.1427 -50.651914) (xy 331.091365 -50.660044)
			(xy 331.039391 -50.660044) (xy 330.988056 -50.651914) (xy 330.938626 -50.635853) (xy 330.892316 -50.612257)
			(xy 330.850268 -50.581707) (xy 330.813517 -50.544956) (xy 330.782967 -50.502908) (xy 330.759371 -50.456598)
			(xy 330.74331 -50.407168) (xy 330.73518 -50.355833) (xy 329.767944 -50.355833) (xy 329.759814 -50.407168)
			(xy 329.743753 -50.456598) (xy 329.720157 -50.502908) (xy 329.689607 -50.544956) (xy 329.652856 -50.581707)
			(xy 329.610808 -50.612257) (xy 329.564498 -50.635853) (xy 329.515068 -50.651914) (xy 329.463733 -50.660044)
			(xy 329.411759 -50.660044) (xy 329.360424 -50.651914) (xy 329.310994 -50.635853) (xy 329.264684 -50.612257)
			(xy 329.222636 -50.581707) (xy 329.185885 -50.544956) (xy 329.155335 -50.502908) (xy 329.131739 -50.456598)
			(xy 329.115678 -50.407168) (xy 329.107548 -50.355833) (xy 328.955906 -50.355833) (xy 328.947776 -50.407168)
			(xy 328.931715 -50.456598) (xy 328.908119 -50.502908) (xy 328.877569 -50.544956) (xy 328.840818 -50.581707)
			(xy 328.79877 -50.612257) (xy 328.75246 -50.635853) (xy 328.70303 -50.651914) (xy 328.651695 -50.660044)
			(xy 328.599721 -50.660044) (xy 328.548386 -50.651914) (xy 328.498956 -50.635853) (xy 328.452646 -50.612257)
			(xy 328.410598 -50.581707) (xy 328.373847 -50.544956) (xy 328.343297 -50.502908) (xy 328.319701 -50.456598)
			(xy 328.30364 -50.407168) (xy 328.29551 -50.355833) (xy 314.418817 -50.355833) (xy 314.396988 -50.388827)
			(xy 314.359771 -50.430364) (xy 314.316903 -50.466039) (xy 314.269297 -50.495093) (xy 314.217968 -50.516905)
			(xy 314.164011 -50.531011) (xy 314.108574 -50.537111) (xy 314.05284 -50.535074) (xy 313.997997 -50.524944)
			(xy 313.945213 -50.506937) (xy 313.895613 -50.481436) (xy 313.850255 -50.448985) (xy 313.810106 -50.410276)
			(xy 313.77602 -50.366133) (xy 313.748724 -50.317498) (xy 313.728801 -50.265407) (xy 313.716675 -50.21097)
			(xy 313.712604 -50.155348) (xy 312.728002 -50.155348) (xy 312.721759 -50.19777) (xy 312.705691 -50.251177)
			(xy 312.682019 -50.301674) (xy 312.651246 -50.348187) (xy 312.614029 -50.389724) (xy 312.571161 -50.425399)
			(xy 312.523555 -50.454453) (xy 312.472226 -50.476265) (xy 312.418269 -50.490371) (xy 312.362832 -50.496471)
			(xy 312.307098 -50.494434) (xy 312.252255 -50.484304) (xy 312.199471 -50.466297) (xy 312.149871 -50.440796)
			(xy 312.104513 -50.408345) (xy 312.064364 -50.369636) (xy 312.030278 -50.325493) (xy 312.002982 -50.276858)
			(xy 311.983059 -50.224767) (xy 311.970933 -50.17033) (xy 311.966862 -50.114708) (xy 296.113523 -50.114708)
			(xy 296.113199 -50.132434) (xy 296.105079 -50.18761) (xy 296.089011 -50.241017) (xy 296.065339 -50.291514)
			(xy 296.034566 -50.338027) (xy 295.997349 -50.379564) (xy 295.954481 -50.415239) (xy 295.906875 -50.444293)
			(xy 295.855546 -50.466105) (xy 295.801589 -50.480211) (xy 295.746152 -50.486311) (xy 295.690418 -50.484274)
			(xy 295.635575 -50.474144) (xy 295.582791 -50.456137) (xy 295.533191 -50.430636) (xy 295.487833 -50.398185)
			(xy 295.447684 -50.359476) (xy 295.413598 -50.315333) (xy 295.386302 -50.266698) (xy 295.366379 -50.214607)
			(xy 295.354253 -50.16017) (xy 295.350182 -50.104548) (xy 292.711839 -50.104548) (xy 292.713155 -50.113492)
			(xy 292.713664 -50.141378) (xy 292.713155 -50.169264) (xy 292.705035 -50.22444) (xy 292.688967 -50.277847)
			(xy 292.665295 -50.328344) (xy 292.634522 -50.374857) (xy 292.597305 -50.416394) (xy 292.554437 -50.452069)
			(xy 292.506831 -50.481123) (xy 292.455502 -50.502935) (xy 292.401545 -50.517041) (xy 292.346108 -50.523141)
			(xy 292.290374 -50.521104) (xy 292.235531 -50.510974) (xy 292.182747 -50.492967) (xy 292.133147 -50.467466)
			(xy 292.087789 -50.435015) (xy 292.04764 -50.396306) (xy 292.013554 -50.352163) (xy 291.986258 -50.303528)
			(xy 291.966335 -50.251437) (xy 291.954209 -50.197) (xy 291.950138 -50.141378) (xy 286.965655 -50.141378)
			(xy 286.968329 -50.14542) (xy 286.992001 -50.195917) (xy 287.008069 -50.249324) (xy 287.016189 -50.3045)
			(xy 287.016698 -50.332386) (xy 287.016189 -50.360272) (xy 287.008069 -50.415448) (xy 286.992001 -50.468855)
			(xy 286.968329 -50.519352) (xy 286.937556 -50.565865) (xy 286.900339 -50.607402) (xy 286.857471 -50.643077)
			(xy 286.809865 -50.672131) (xy 286.758536 -50.693943) (xy 286.704579 -50.708049) (xy 286.649142 -50.714149)
			(xy 286.593408 -50.712112) (xy 286.538565 -50.701982) (xy 286.485781 -50.683975) (xy 286.436181 -50.658474)
			(xy 286.390823 -50.626023) (xy 286.350674 -50.587314) (xy 286.316588 -50.543171) (xy 286.289292 -50.494536)
			(xy 286.269369 -50.442445) (xy 286.257243 -50.388008) (xy 286.253172 -50.332386) (xy 286.027928 -50.332386)
			(xy 286.016298 -50.349965) (xy 285.979081 -50.391502) (xy 285.936213 -50.427177) (xy 285.888607 -50.456231)
			(xy 285.837278 -50.478043) (xy 285.783321 -50.492149) (xy 285.727884 -50.498249) (xy 285.67215 -50.496212)
			(xy 285.617307 -50.486082) (xy 285.564523 -50.468075) (xy 285.514923 -50.442574) (xy 285.469565 -50.410123)
			(xy 285.429416 -50.371414) (xy 285.39533 -50.327271) (xy 285.368034 -50.278636) (xy 285.348111 -50.226545)
			(xy 285.335985 -50.172108) (xy 285.331914 -50.116486) (xy 282.38704 -50.116486) (xy 282.38704 -50.878486)
			(xy 307.902862 -50.878486) (xy 307.906933 -50.822864) (xy 307.919059 -50.768427) (xy 307.938982 -50.716336)
			(xy 307.966278 -50.667701) (xy 308.000364 -50.623558) (xy 308.040513 -50.584849) (xy 308.085871 -50.552398)
			(xy 308.135471 -50.526897) (xy 308.188255 -50.50889) (xy 308.243098 -50.49876) (xy 308.298832 -50.496723)
			(xy 308.354269 -50.502823) (xy 308.408226 -50.516929) (xy 308.459555 -50.538741) (xy 308.507161 -50.567795)
			(xy 308.550029 -50.60347) (xy 308.587246 -50.645007) (xy 308.618019 -50.69152) (xy 308.641691 -50.742017)
			(xy 308.657759 -50.795424) (xy 308.664488 -50.841148) (xy 310.849262 -50.841148) (xy 310.853333 -50.785526)
			(xy 310.865459 -50.731089) (xy 310.885382 -50.678998) (xy 310.912678 -50.630363) (xy 310.946764 -50.58622)
			(xy 310.986913 -50.547511) (xy 311.032271 -50.51506) (xy 311.081871 -50.489559) (xy 311.134655 -50.471552)
			(xy 311.189498 -50.461422) (xy 311.245232 -50.459385) (xy 311.300669 -50.465485) (xy 311.354626 -50.479591)
			(xy 311.405955 -50.501403) (xy 311.453561 -50.530457) (xy 311.496429 -50.566132) (xy 311.533646 -50.607669)
			(xy 311.564419 -50.654182) (xy 311.588091 -50.704679) (xy 311.604159 -50.758086) (xy 311.612279 -50.813262)
			(xy 311.612788 -50.841148) (xy 311.612279 -50.869034) (xy 311.604159 -50.92421) (xy 311.588091 -50.977617)
			(xy 311.564419 -51.028114) (xy 311.533646 -51.074627) (xy 311.496429 -51.116164) (xy 311.453561 -51.151839)
			(xy 311.405955 -51.180893) (xy 311.354626 -51.202705) (xy 311.300669 -51.216811) (xy 311.245232 -51.222911)
			(xy 311.189498 -51.220874) (xy 311.134655 -51.210744) (xy 311.081871 -51.192737) (xy 311.032271 -51.167236)
			(xy 310.986913 -51.134785) (xy 310.946764 -51.096076) (xy 310.912678 -51.051933) (xy 310.885382 -51.003298)
			(xy 310.865459 -50.951207) (xy 310.853333 -50.89677) (xy 310.849262 -50.841148) (xy 308.664488 -50.841148)
			(xy 308.665879 -50.8506) (xy 308.666388 -50.878486) (xy 308.665879 -50.906372) (xy 308.657759 -50.961548)
			(xy 308.641691 -51.014955) (xy 308.618019 -51.065452) (xy 308.587246 -51.111965) (xy 308.550029 -51.153502)
			(xy 308.507161 -51.189177) (xy 308.459555 -51.218231) (xy 308.408226 -51.240043) (xy 308.354269 -51.254149)
			(xy 308.298832 -51.260249) (xy 308.243098 -51.258212) (xy 308.188255 -51.248082) (xy 308.135471 -51.230075)
			(xy 308.085871 -51.204574) (xy 308.040513 -51.172123) (xy 308.000364 -51.133414) (xy 307.966278 -51.089271)
			(xy 307.938982 -51.040636) (xy 307.919059 -50.988545) (xy 307.906933 -50.934108) (xy 307.902862 -50.878486)
			(xy 282.38704 -50.878486) (xy 282.38704 -51.438556) (xy 305.230782 -51.438556) (xy 305.234853 -51.382934)
			(xy 305.246979 -51.328497) (xy 305.266902 -51.276406) (xy 305.294198 -51.227771) (xy 305.328284 -51.183628)
			(xy 305.368433 -51.144919) (xy 305.413791 -51.112468) (xy 305.463391 -51.086967) (xy 305.516175 -51.06896)
			(xy 305.571018 -51.05883) (xy 305.626752 -51.056793) (xy 305.682189 -51.062893) (xy 305.736146 -51.076999)
			(xy 305.787475 -51.098811) (xy 305.835081 -51.127865) (xy 305.877949 -51.16354) (xy 305.915166 -51.205077)
			(xy 305.945939 -51.25159) (xy 305.969611 -51.302087) (xy 305.98377 -51.349148) (xy 311.662062 -51.349148)
			(xy 311.666133 -51.293526) (xy 311.678259 -51.239089) (xy 311.698182 -51.186998) (xy 311.725478 -51.138363)
			(xy 311.759564 -51.09422) (xy 311.799713 -51.055511) (xy 311.845071 -51.02306) (xy 311.894671 -50.997559)
			(xy 311.947455 -50.979552) (xy 312.002298 -50.969422) (xy 312.058032 -50.967385) (xy 312.113469 -50.973485)
			(xy 312.167426 -50.987591) (xy 312.218755 -51.009403) (xy 312.266361 -51.038457) (xy 312.309229 -51.074132)
			(xy 312.346446 -51.115669) (xy 312.377219 -51.162182) (xy 312.400891 -51.212679) (xy 312.416959 -51.266086)
			(xy 312.422458 -51.303451) (xy 312.872605 -51.303451) (xy 312.872605 -51.248949) (xy 312.880362 -51.195003)
			(xy 312.895717 -51.14271) (xy 312.918359 -51.093134) (xy 312.947826 -51.047286) (xy 312.983518 -51.006098)
			(xy 313.024708 -50.970409) (xy 313.070559 -50.940946) (xy 313.120136 -50.918308) (xy 313.172431 -50.902956)
			(xy 313.226377 -50.895203) (xy 313.253628 -50.894742) (xy 313.280555 -50.895198) (xy 313.333873 -50.902786)
			(xy 313.385595 -50.917794) (xy 313.434693 -50.939924) (xy 313.480193 -50.968736) (xy 313.521191 -51.003657)
			(xy 313.539378 -51.02352) (xy 313.549172 -51.033844) (xy 313.57317 -51.049114) (xy 313.600447 -51.057178)
			(xy 313.62889 -51.057412) (xy 313.656296 -51.049797) (xy 313.680541 -51.034923) (xy 313.699748 -51.013942)
			(xy 313.70651 -51.001422) (xy 313.718721 -50.977944) (xy 313.748622 -50.934281) (xy 313.784268 -50.895167)
			(xy 313.824975 -50.861353) (xy 313.869964 -50.833488) (xy 313.918372 -50.812105) (xy 313.969269 -50.797615)
			(xy 314.02168 -50.790295) (xy 314.04814 -50.78984) (xy 314.075393 -50.790233) (xy 314.129343 -50.797995)
			(xy 314.18164 -50.813355) (xy 314.231218 -50.836002) (xy 314.277069 -50.865473) (xy 314.31826 -50.901169)
			(xy 314.353951 -50.942363) (xy 314.383418 -50.988217) (xy 314.406059 -51.037798) (xy 314.421414 -51.090096)
			(xy 314.42917 -51.144047) (xy 314.42917 -51.145948) (xy 318.038478 -51.145948) (xy 318.042549 -51.090326)
			(xy 318.054675 -51.035889) (xy 318.074598 -50.983798) (xy 318.101894 -50.935163) (xy 318.13598 -50.89102)
			(xy 318.176129 -50.852311) (xy 318.221487 -50.81986) (xy 318.271087 -50.794359) (xy 318.323871 -50.776352)
			(xy 318.378714 -50.766222) (xy 318.434448 -50.764185) (xy 318.489885 -50.770285) (xy 318.543842 -50.784391)
			(xy 318.595171 -50.806203) (xy 318.600822 -50.809652) (xy 322.983604 -50.809652) (xy 322.987675 -50.75403)
			(xy 322.999801 -50.699593) (xy 323.019724 -50.647502) (xy 323.04702 -50.598867) (xy 323.081106 -50.554724)
			(xy 323.121255 -50.516015) (xy 323.166613 -50.483564) (xy 323.216213 -50.458063) (xy 323.268997 -50.440056)
			(xy 323.32384 -50.429926) (xy 323.379574 -50.427889) (xy 323.435011 -50.433989) (xy 323.488968 -50.448095)
			(xy 323.540297 -50.469907) (xy 323.587903 -50.498961) (xy 323.630771 -50.534636) (xy 323.667988 -50.576173)
			(xy 323.698761 -50.622686) (xy 323.722433 -50.673183) (xy 323.738501 -50.72659) (xy 323.746621 -50.781766)
			(xy 323.74713 -50.809652) (xy 323.746621 -50.837538) (xy 323.738501 -50.892714) (xy 323.722433 -50.946121)
			(xy 323.698761 -50.996618) (xy 323.667988 -51.043131) (xy 323.630771 -51.084668) (xy 323.587903 -51.120343)
			(xy 323.587567 -51.120548) (xy 324.276464 -51.120548) (xy 324.280535 -51.064926) (xy 324.292661 -51.010489)
			(xy 324.312584 -50.958398) (xy 324.33988 -50.909763) (xy 324.373966 -50.86562) (xy 324.414115 -50.826911)
			(xy 324.459473 -50.79446) (xy 324.509073 -50.768959) (xy 324.561857 -50.750952) (xy 324.6167 -50.740822)
			(xy 324.672434 -50.738785) (xy 324.727871 -50.744885) (xy 324.781828 -50.758991) (xy 324.833157 -50.780803)
			(xy 324.880763 -50.809857) (xy 324.89984 -50.825733) (xy 329.92238 -50.825733) (xy 329.92238 -50.773759)
			(xy 329.93051 -50.722424) (xy 329.946571 -50.672994) (xy 329.970167 -50.626684) (xy 330.000717 -50.584636)
			(xy 330.037468 -50.547885) (xy 330.079516 -50.517335) (xy 330.125826 -50.493739) (xy 330.175256 -50.477678)
			(xy 330.226591 -50.469548) (xy 330.278565 -50.469548) (xy 330.3299 -50.477678) (xy 330.37933 -50.493739)
			(xy 330.42564 -50.517335) (xy 330.467688 -50.547885) (xy 330.504439 -50.584636) (xy 330.534989 -50.626684)
			(xy 330.558585 -50.672994) (xy 330.574646 -50.722424) (xy 330.582776 -50.773759) (xy 330.583286 -50.799746)
			(xy 330.582776 -50.825733) (xy 331.55052 -50.825733) (xy 331.55052 -50.773759) (xy 331.55865 -50.722424)
			(xy 331.574711 -50.672994) (xy 331.598307 -50.626684) (xy 331.628857 -50.584636) (xy 331.665608 -50.547885)
			(xy 331.707656 -50.517335) (xy 331.753966 -50.493739) (xy 331.803396 -50.477678) (xy 331.854731 -50.469548)
			(xy 331.906705 -50.469548) (xy 331.95804 -50.477678) (xy 332.00747 -50.493739) (xy 332.05378 -50.517335)
			(xy 332.095828 -50.547885) (xy 332.132579 -50.584636) (xy 332.163129 -50.626684) (xy 332.186725 -50.672994)
			(xy 332.202786 -50.722424) (xy 332.210916 -50.773759) (xy 332.211426 -50.799746) (xy 332.210916 -50.825733)
			(xy 333.177644 -50.825733) (xy 333.177644 -50.773759) (xy 333.185774 -50.722424) (xy 333.201835 -50.672994)
			(xy 333.225431 -50.626684) (xy 333.255981 -50.584636) (xy 333.292732 -50.547885) (xy 333.33478 -50.517335)
			(xy 333.38109 -50.493739) (xy 333.43052 -50.477678) (xy 333.481855 -50.469548) (xy 333.533829 -50.469548)
			(xy 333.577618 -50.476483) (xy 335.36941 -50.476483) (xy 335.36941 -50.424509) (xy 335.37754 -50.373174)
			(xy 335.393601 -50.323744) (xy 335.417197 -50.277434) (xy 335.447747 -50.235386) (xy 335.484498 -50.198635)
			(xy 335.526546 -50.168085) (xy 335.572856 -50.144489) (xy 335.622286 -50.128428) (xy 335.673621 -50.120298)
			(xy 335.725595 -50.120298) (xy 335.77693 -50.128428) (xy 335.82636 -50.144489) (xy 335.87267 -50.168085)
			(xy 335.914718 -50.198635) (xy 335.951469 -50.235386) (xy 335.982019 -50.277434) (xy 336.005615 -50.323744)
			(xy 336.021676 -50.373174) (xy 336.029806 -50.424509) (xy 336.030316 -50.450496) (xy 336.029806 -50.476483)
			(xy 336.96961 -50.476483) (xy 336.96961 -50.424509) (xy 336.97774 -50.373174) (xy 336.993801 -50.323744)
			(xy 337.017397 -50.277434) (xy 337.047947 -50.235386) (xy 337.084698 -50.198635) (xy 337.126746 -50.168085)
			(xy 337.173056 -50.144489) (xy 337.222486 -50.128428) (xy 337.273821 -50.120298) (xy 337.325795 -50.120298)
			(xy 337.37713 -50.128428) (xy 337.42656 -50.144489) (xy 337.47287 -50.168085) (xy 337.514918 -50.198635)
			(xy 337.551669 -50.235386) (xy 337.582219 -50.277434) (xy 337.605815 -50.323744) (xy 337.621876 -50.373174)
			(xy 337.630006 -50.424509) (xy 337.630516 -50.450496) (xy 339.3694 -50.450496) (xy 339.369856 -50.425058)
			(xy 339.377648 -50.374784) (xy 339.393047 -50.326295) (xy 339.41569 -50.280737) (xy 339.445044 -50.239183)
			(xy 339.480414 -50.202616) (xy 339.520968 -50.171896) (xy 339.543136 -50.159412) (xy 339.556115 -50.151782)
			(xy 339.577316 -50.130429) (xy 339.591389 -50.103833) (xy 339.597116 -50.074293) (xy 339.594003 -50.044364)
			(xy 339.582318 -50.016635) (xy 339.573108 -50.004726) (xy 339.555146 -49.982247) (xy 339.52644 -49.932387)
			(xy 339.506791 -49.878313) (xy 339.496791 -49.821656) (xy 339.496146 -49.79289) (xy 339.496656 -49.766903)
			(xy 339.504786 -49.715568) (xy 339.520847 -49.666138) (xy 339.544443 -49.619828) (xy 339.574993 -49.57778)
			(xy 339.611744 -49.541029) (xy 339.653792 -49.510479) (xy 339.700102 -49.486883) (xy 339.749532 -49.470822)
			(xy 339.800867 -49.462692) (xy 339.852841 -49.462692) (xy 339.904176 -49.470822) (xy 339.953606 -49.486883)
			(xy 339.999916 -49.510479) (xy 340.041964 -49.541029) (xy 340.078715 -49.57778) (xy 340.109265 -49.619828)
			(xy 340.132861 -49.666138) (xy 340.148922 -49.715568) (xy 340.157052 -49.766903) (xy 340.157562 -49.79289)
			(xy 340.157115 -49.818328) (xy 340.149324 -49.868604) (xy 340.143901 -49.885679) (xy 342.404956 -49.885679)
			(xy 342.404956 -49.833705) (xy 342.413086 -49.78237) (xy 342.429147 -49.73294) (xy 342.452743 -49.68663)
			(xy 342.483293 -49.644582) (xy 342.520044 -49.607831) (xy 342.562092 -49.577281) (xy 342.608402 -49.553685)
			(xy 342.657832 -49.537624) (xy 342.709167 -49.529494) (xy 342.761141 -49.529494) (xy 342.812476 -49.537624)
			(xy 342.861906 -49.553685) (xy 342.908216 -49.577281) (xy 342.950264 -49.607831) (xy 342.987015 -49.644582)
			(xy 343.017565 -49.68663) (xy 343.041161 -49.73294) (xy 343.057222 -49.78237) (xy 343.065352 -49.833705)
			(xy 343.065862 -49.859692) (xy 343.065352 -49.885679) (xy 343.057222 -49.937014) (xy 343.041161 -49.986444)
			(xy 343.017565 -50.032754) (xy 342.987015 -50.074802) (xy 342.950264 -50.111553) (xy 342.908216 -50.142103)
			(xy 342.861906 -50.165699) (xy 342.812476 -50.18176) (xy 342.761141 -50.18989) (xy 342.709167 -50.18989)
			(xy 342.657832 -50.18176) (xy 342.608402 -50.165699) (xy 342.562092 -50.142103) (xy 342.520044 -50.111553)
			(xy 342.483293 -50.074802) (xy 342.452743 -50.032754) (xy 342.429147 -49.986444) (xy 342.413086 -49.937014)
			(xy 342.404956 -49.885679) (xy 340.143901 -49.885679) (xy 340.133925 -49.917094) (xy 340.11128 -49.962653)
			(xy 340.081925 -50.004207) (xy 340.046552 -50.040774) (xy 340.005996 -50.071491) (xy 339.983826 -50.083974)
			(xy 339.970855 -50.091615) (xy 339.949661 -50.112968) (xy 339.935592 -50.139562) (xy 339.929864 -50.169097)
			(xy 339.932973 -50.199022) (xy 339.944649 -50.22675) (xy 339.953854 -50.23866) (xy 339.971804 -50.261148)
			(xy 340.000514 -50.311004) (xy 340.016807 -50.355833) (xy 341.59114 -50.355833) (xy 341.59114 -50.303859)
			(xy 341.59927 -50.252524) (xy 341.615331 -50.203094) (xy 341.638927 -50.156784) (xy 341.669477 -50.114736)
			(xy 341.706228 -50.077985) (xy 341.748276 -50.047435) (xy 341.794586 -50.023839) (xy 341.844016 -50.007778)
			(xy 341.895351 -49.999648) (xy 341.947325 -49.999648) (xy 341.99866 -50.007778) (xy 342.04809 -50.023839)
			(xy 342.0944 -50.047435) (xy 342.136448 -50.077985) (xy 342.173199 -50.114736) (xy 342.203749 -50.156784)
			(xy 342.227345 -50.203094) (xy 342.243406 -50.252524) (xy 342.251536 -50.303859) (xy 342.252046 -50.329846)
			(xy 342.251541 -50.355579) (xy 343.220296 -50.355579) (xy 343.220296 -50.303605) (xy 343.228426 -50.25227)
			(xy 343.244487 -50.20284) (xy 343.268083 -50.15653) (xy 343.298633 -50.114482) (xy 343.335384 -50.077731)
			(xy 343.377432 -50.047181) (xy 343.423742 -50.023585) (xy 343.473172 -50.007524) (xy 343.524507 -49.999394)
			(xy 343.576481 -49.999394) (xy 343.627816 -50.007524) (xy 343.677246 -50.023585) (xy 343.723556 -50.047181)
			(xy 343.765604 -50.077731) (xy 343.802355 -50.114482) (xy 343.832905 -50.15653) (xy 343.856501 -50.20284)
			(xy 343.872562 -50.25227) (xy 343.880692 -50.303605) (xy 343.881202 -50.329592) (xy 343.880692 -50.355579)
			(xy 343.872562 -50.406914) (xy 343.856501 -50.456344) (xy 343.832905 -50.502654) (xy 343.802355 -50.544702)
			(xy 343.765604 -50.581453) (xy 343.723556 -50.612003) (xy 343.677246 -50.635599) (xy 343.627816 -50.65166)
			(xy 343.576481 -50.65979) (xy 343.524507 -50.65979) (xy 343.473172 -50.65166) (xy 343.423742 -50.635599)
			(xy 343.377432 -50.612003) (xy 343.335384 -50.581453) (xy 343.298633 -50.544702) (xy 343.268083 -50.502654)
			(xy 343.244487 -50.456344) (xy 343.228426 -50.406914) (xy 343.220296 -50.355579) (xy 342.251541 -50.355579)
			(xy 342.251536 -50.355833) (xy 342.243406 -50.407168) (xy 342.227345 -50.456598) (xy 342.203749 -50.502908)
			(xy 342.173199 -50.544956) (xy 342.136448 -50.581707) (xy 342.0944 -50.612257) (xy 342.04809 -50.635853)
			(xy 341.99866 -50.651914) (xy 341.947325 -50.660044) (xy 341.895351 -50.660044) (xy 341.844016 -50.651914)
			(xy 341.794586 -50.635853) (xy 341.748276 -50.612257) (xy 341.706228 -50.581707) (xy 341.669477 -50.544956)
			(xy 341.638927 -50.502908) (xy 341.615331 -50.456598) (xy 341.59927 -50.407168) (xy 341.59114 -50.355833)
			(xy 340.016807 -50.355833) (xy 340.020166 -50.365075) (xy 340.03017 -50.421731) (xy 340.030816 -50.450496)
			(xy 340.030306 -50.476483) (xy 340.022176 -50.527818) (xy 340.006115 -50.577248) (xy 339.982519 -50.623558)
			(xy 339.951969 -50.665606) (xy 339.915218 -50.702357) (xy 339.87317 -50.732907) (xy 339.82686 -50.756503)
			(xy 339.77743 -50.772564) (xy 339.726095 -50.780694) (xy 339.674121 -50.780694) (xy 339.622786 -50.772564)
			(xy 339.573356 -50.756503) (xy 339.527046 -50.732907) (xy 339.484998 -50.702357) (xy 339.448247 -50.665606)
			(xy 339.417697 -50.623558) (xy 339.394101 -50.577248) (xy 339.37804 -50.527818) (xy 339.36991 -50.476483)
			(xy 339.3694 -50.450496) (xy 337.630516 -50.450496) (xy 337.630006 -50.476483) (xy 337.621876 -50.527818)
			(xy 337.605815 -50.577248) (xy 337.582219 -50.623558) (xy 337.551669 -50.665606) (xy 337.514918 -50.702357)
			(xy 337.47287 -50.732907) (xy 337.42656 -50.756503) (xy 337.37713 -50.772564) (xy 337.325795 -50.780694)
			(xy 337.273821 -50.780694) (xy 337.222486 -50.772564) (xy 337.173056 -50.756503) (xy 337.126746 -50.732907)
			(xy 337.084698 -50.702357) (xy 337.047947 -50.665606) (xy 337.017397 -50.623558) (xy 336.993801 -50.577248)
			(xy 336.97774 -50.527818) (xy 336.96961 -50.476483) (xy 336.029806 -50.476483) (xy 336.021676 -50.527818)
			(xy 336.005615 -50.577248) (xy 335.982019 -50.623558) (xy 335.951469 -50.665606) (xy 335.914718 -50.702357)
			(xy 335.87267 -50.732907) (xy 335.82636 -50.756503) (xy 335.77693 -50.772564) (xy 335.725595 -50.780694)
			(xy 335.673621 -50.780694) (xy 335.622286 -50.772564) (xy 335.572856 -50.756503) (xy 335.526546 -50.732907)
			(xy 335.484498 -50.702357) (xy 335.447747 -50.665606) (xy 335.417197 -50.623558) (xy 335.393601 -50.577248)
			(xy 335.37754 -50.527818) (xy 335.36941 -50.476483) (xy 333.577618 -50.476483) (xy 333.585164 -50.477678)
			(xy 333.634594 -50.493739) (xy 333.680904 -50.517335) (xy 333.722952 -50.547885) (xy 333.759703 -50.584636)
			(xy 333.790253 -50.626684) (xy 333.813849 -50.672994) (xy 333.82991 -50.722424) (xy 333.83804 -50.773759)
			(xy 333.83855 -50.799746) (xy 333.838045 -50.825479) (xy 342.407496 -50.825479) (xy 342.407496 -50.773505)
			(xy 342.415626 -50.72217) (xy 342.431687 -50.67274) (xy 342.455283 -50.62643) (xy 342.485833 -50.584382)
			(xy 342.522584 -50.547631) (xy 342.564632 -50.517081) (xy 342.610942 -50.493485) (xy 342.660372 -50.477424)
			(xy 342.711707 -50.469294) (xy 342.763681 -50.469294) (xy 342.815016 -50.477424) (xy 342.864446 -50.493485)
			(xy 342.910756 -50.517081) (xy 342.952804 -50.547631) (xy 342.989555 -50.584382) (xy 343.020105 -50.62643)
			(xy 343.043701 -50.67274) (xy 343.059762 -50.72217) (xy 343.067892 -50.773505) (xy 343.068402 -50.799492)
			(xy 343.067892 -50.825479) (xy 343.067852 -50.825733) (xy 344.034112 -50.825733) (xy 344.034112 -50.773759)
			(xy 344.042242 -50.722424) (xy 344.058303 -50.672994) (xy 344.081899 -50.626684) (xy 344.112449 -50.584636)
			(xy 344.1492 -50.547885) (xy 344.191248 -50.517335) (xy 344.237558 -50.493739) (xy 344.286988 -50.477678)
			(xy 344.338323 -50.469548) (xy 344.390297 -50.469548) (xy 344.441632 -50.477678) (xy 344.491062 -50.493739)
			(xy 344.537372 -50.517335) (xy 344.57942 -50.547885) (xy 344.616171 -50.584636) (xy 344.640199 -50.617707)
			(xy 344.821512 -50.617707) (xy 344.821512 -50.565733) (xy 344.829642 -50.514398) (xy 344.845703 -50.464968)
			(xy 344.869299 -50.418658) (xy 344.899849 -50.37661) (xy 344.9366 -50.339859) (xy 344.978648 -50.309309)
			(xy 345.024958 -50.285713) (xy 345.074388 -50.269652) (xy 345.125723 -50.261522) (xy 345.177697 -50.261522)
			(xy 345.229032 -50.269652) (xy 345.278462 -50.285713) (xy 345.324772 -50.309309) (xy 345.36682 -50.339859)
			(xy 345.403571 -50.37661) (xy 345.434121 -50.418658) (xy 345.457717 -50.464968) (xy 345.473778 -50.514398)
			(xy 345.481908 -50.565733) (xy 345.482418 -50.59172) (xy 345.481908 -50.617707) (xy 345.473778 -50.669042)
			(xy 345.457717 -50.718472) (xy 345.434121 -50.764782) (xy 345.403571 -50.80683) (xy 345.36682 -50.843581)
			(xy 345.324772 -50.874131) (xy 345.278462 -50.897727) (xy 345.229032 -50.913788) (xy 345.177697 -50.921918)
			(xy 345.125723 -50.921918) (xy 345.074388 -50.913788) (xy 345.024958 -50.897727) (xy 344.978648 -50.874131)
			(xy 344.9366 -50.843581) (xy 344.899849 -50.80683) (xy 344.869299 -50.764782) (xy 344.845703 -50.718472)
			(xy 344.829642 -50.669042) (xy 344.821512 -50.617707) (xy 344.640199 -50.617707) (xy 344.646721 -50.626684)
			(xy 344.670317 -50.672994) (xy 344.686378 -50.722424) (xy 344.694508 -50.773759) (xy 344.695018 -50.799746)
			(xy 344.694508 -50.825733) (xy 344.686378 -50.877068) (xy 344.670317 -50.926498) (xy 344.646721 -50.972808)
			(xy 344.616171 -51.014856) (xy 344.57942 -51.051607) (xy 344.537372 -51.082157) (xy 344.491062 -51.105753)
			(xy 344.441632 -51.121814) (xy 344.390297 -51.129944) (xy 344.338323 -51.129944) (xy 344.286988 -51.121814)
			(xy 344.237558 -51.105753) (xy 344.191248 -51.082157) (xy 344.1492 -51.051607) (xy 344.112449 -51.014856)
			(xy 344.081899 -50.972808) (xy 344.058303 -50.926498) (xy 344.042242 -50.877068) (xy 344.034112 -50.825733)
			(xy 343.067852 -50.825733) (xy 343.059762 -50.876814) (xy 343.043701 -50.926244) (xy 343.020105 -50.972554)
			(xy 342.989555 -51.014602) (xy 342.952804 -51.051353) (xy 342.910756 -51.081903) (xy 342.864446 -51.105499)
			(xy 342.815016 -51.12156) (xy 342.763681 -51.12969) (xy 342.711707 -51.12969) (xy 342.660372 -51.12156)
			(xy 342.610942 -51.105499) (xy 342.564632 -51.081903) (xy 342.522584 -51.051353) (xy 342.485833 -51.014602)
			(xy 342.455283 -50.972554) (xy 342.431687 -50.926244) (xy 342.415626 -50.876814) (xy 342.407496 -50.825479)
			(xy 333.838045 -50.825479) (xy 333.83804 -50.825733) (xy 333.82991 -50.877068) (xy 333.813849 -50.926498)
			(xy 333.790253 -50.972808) (xy 333.759703 -51.014856) (xy 333.722952 -51.051607) (xy 333.680904 -51.082157)
			(xy 333.634594 -51.105753) (xy 333.585164 -51.121814) (xy 333.533829 -51.129944) (xy 333.481855 -51.129944)
			(xy 333.43052 -51.121814) (xy 333.38109 -51.105753) (xy 333.33478 -51.082157) (xy 333.292732 -51.051607)
			(xy 333.255981 -51.014856) (xy 333.225431 -50.972808) (xy 333.201835 -50.926498) (xy 333.185774 -50.877068)
			(xy 333.177644 -50.825733) (xy 332.210916 -50.825733) (xy 332.202786 -50.877068) (xy 332.186725 -50.926498)
			(xy 332.163129 -50.972808) (xy 332.132579 -51.014856) (xy 332.095828 -51.051607) (xy 332.05378 -51.082157)
			(xy 332.00747 -51.105753) (xy 331.95804 -51.121814) (xy 331.906705 -51.129944) (xy 331.854731 -51.129944)
			(xy 331.803396 -51.121814) (xy 331.753966 -51.105753) (xy 331.707656 -51.082157) (xy 331.665608 -51.051607)
			(xy 331.628857 -51.014856) (xy 331.598307 -50.972808) (xy 331.574711 -50.926498) (xy 331.55865 -50.877068)
			(xy 331.55052 -50.825733) (xy 330.582776 -50.825733) (xy 330.574646 -50.877068) (xy 330.558585 -50.926498)
			(xy 330.534989 -50.972808) (xy 330.504439 -51.014856) (xy 330.467688 -51.051607) (xy 330.42564 -51.082157)
			(xy 330.37933 -51.105753) (xy 330.3299 -51.121814) (xy 330.278565 -51.129944) (xy 330.226591 -51.129944)
			(xy 330.175256 -51.121814) (xy 330.125826 -51.105753) (xy 330.079516 -51.082157) (xy 330.037468 -51.051607)
			(xy 330.000717 -51.014856) (xy 329.970167 -50.972808) (xy 329.946571 -50.926498) (xy 329.93051 -50.877068)
			(xy 329.92238 -50.825733) (xy 324.89984 -50.825733) (xy 324.923631 -50.845532) (xy 324.960848 -50.887069)
			(xy 324.991621 -50.933582) (xy 325.015293 -50.984079) (xy 325.031361 -51.037486) (xy 325.039481 -51.092662)
			(xy 325.03999 -51.120548) (xy 325.039481 -51.148434) (xy 325.031361 -51.20361) (xy 325.015293 -51.257017)
			(xy 324.991621 -51.307514) (xy 324.977016 -51.32959) (xy 325.609722 -51.32959) (xy 325.613698 -51.275264)
			(xy 325.625541 -51.222095) (xy 325.645 -51.171218) (xy 325.67166 -51.123716) (xy 325.704951 -51.080602)
			(xy 325.744165 -51.042795) (xy 325.788467 -51.0111) (xy 325.83691 -50.986194) (xy 325.888464 -50.968606)
			(xy 325.94203 -50.958712) (xy 325.996465 -50.956722) (xy 326.05061 -50.96268) (xy 326.10331 -50.976458)
			(xy 326.153443 -50.997762) (xy 326.199939 -51.026138) (xy 326.241809 -51.060982) (xy 326.278158 -51.101551)
			(xy 326.308214 -51.14698) (xy 326.331335 -51.196301) (xy 326.347028 -51.248463) (xy 326.35397 -51.295633)
			(xy 328.29551 -51.295633) (xy 328.29551 -51.243659) (xy 328.30364 -51.192324) (xy 328.319701 -51.142894)
			(xy 328.343297 -51.096584) (xy 328.373847 -51.054536) (xy 328.410598 -51.017785) (xy 328.452646 -50.987235)
			(xy 328.498956 -50.963639) (xy 328.548386 -50.947578) (xy 328.599721 -50.939448) (xy 328.651695 -50.939448)
			(xy 328.70303 -50.947578) (xy 328.75246 -50.963639) (xy 328.79877 -50.987235) (xy 328.840818 -51.017785)
			(xy 328.877569 -51.054536) (xy 328.908119 -51.096584) (xy 328.931715 -51.142894) (xy 328.947776 -51.192324)
			(xy 328.955906 -51.243659) (xy 328.956416 -51.269646) (xy 328.955906 -51.295633) (xy 329.107548 -51.295633)
			(xy 329.107548 -51.243659) (xy 329.115678 -51.192324) (xy 329.131739 -51.142894) (xy 329.155335 -51.096584)
			(xy 329.185885 -51.054536) (xy 329.222636 -51.017785) (xy 329.264684 -50.987235) (xy 329.310994 -50.963639)
			(xy 329.360424 -50.947578) (xy 329.411759 -50.939448) (xy 329.463733 -50.939448) (xy 329.515068 -50.947578)
			(xy 329.564498 -50.963639) (xy 329.610808 -50.987235) (xy 329.652856 -51.017785) (xy 329.689607 -51.054536)
			(xy 329.720157 -51.096584) (xy 329.743753 -51.142894) (xy 329.759814 -51.192324) (xy 329.767944 -51.243659)
			(xy 329.768454 -51.269646) (xy 329.767944 -51.295633) (xy 330.73518 -51.295633) (xy 330.73518 -51.243659)
			(xy 330.74331 -51.192324) (xy 330.759371 -51.142894) (xy 330.782967 -51.096584) (xy 330.813517 -51.054536)
			(xy 330.850268 -51.017785) (xy 330.892316 -50.987235) (xy 330.938626 -50.963639) (xy 330.988056 -50.947578)
			(xy 331.039391 -50.939448) (xy 331.091365 -50.939448) (xy 331.1427 -50.947578) (xy 331.19213 -50.963639)
			(xy 331.23844 -50.987235) (xy 331.280488 -51.017785) (xy 331.317239 -51.054536) (xy 331.347789 -51.096584)
			(xy 331.371385 -51.142894) (xy 331.387446 -51.192324) (xy 331.395576 -51.243659) (xy 331.396086 -51.269646)
			(xy 331.395665 -51.291093) (xy 339.355349 -51.291093) (xy 339.355349 -51.239107) (xy 339.363482 -51.187762)
			(xy 339.379547 -51.138321) (xy 339.40315 -51.092002) (xy 339.433708 -51.049946) (xy 339.470469 -51.013188)
			(xy 339.512528 -50.982634) (xy 339.558849 -50.959036) (xy 339.608291 -50.942975) (xy 339.659637 -50.934847)
			(xy 339.68563 -50.934366) (xy 339.711527 -50.934859) (xy 339.762688 -50.942932) (xy 339.811962 -50.95889)
			(xy 339.858142 -50.982343) (xy 339.900096 -51.012715) (xy 339.918802 -51.030632) (xy 339.928386 -51.039646)
			(xy 339.951169 -51.052793) (xy 339.976554 -51.059686) (xy 340.002857 -51.059866) (xy 340.028335 -51.053322)
			(xy 340.051295 -51.040488) (xy 340.061042 -51.031648) (xy 340.079664 -51.014376) (xy 340.121171 -50.985109)
			(xy 340.166664 -50.962532) (xy 340.215075 -50.947177) (xy 340.265264 -50.939405) (xy 340.290658 -50.938938)
			(xy 340.316653 -50.939326) (xy 340.368004 -50.947453) (xy 340.417451 -50.963514) (xy 340.463776 -50.987113)
			(xy 340.505839 -51.017669) (xy 340.542604 -51.054429) (xy 340.573165 -51.096488) (xy 340.59677 -51.14281)
			(xy 340.612837 -51.192255) (xy 340.620971 -51.243605) (xy 340.620971 -51.295595) (xy 340.620965 -51.295633)
			(xy 341.59114 -51.295633) (xy 341.59114 -51.243659) (xy 341.59927 -51.192324) (xy 341.615331 -51.142894)
			(xy 341.638927 -51.096584) (xy 341.669477 -51.054536) (xy 341.706228 -51.017785) (xy 341.748276 -50.987235)
			(xy 341.794586 -50.963639) (xy 341.844016 -50.947578) (xy 341.895351 -50.939448) (xy 341.947325 -50.939448)
			(xy 341.99866 -50.947578) (xy 342.04809 -50.963639) (xy 342.0944 -50.987235) (xy 342.136448 -51.017785)
			(xy 342.173199 -51.054536) (xy 342.203749 -51.096584) (xy 342.227345 -51.142894) (xy 342.243406 -51.192324)
			(xy 342.251536 -51.243659) (xy 342.252046 -51.269646) (xy 342.251541 -51.295379) (xy 343.220296 -51.295379)
			(xy 343.220296 -51.243405) (xy 343.228426 -51.19207) (xy 343.244487 -51.14264) (xy 343.268083 -51.09633)
			(xy 343.298633 -51.054282) (xy 343.335384 -51.017531) (xy 343.377432 -50.986981) (xy 343.423742 -50.963385)
			(xy 343.473172 -50.947324) (xy 343.524507 -50.939194) (xy 343.576481 -50.939194) (xy 343.627816 -50.947324)
			(xy 343.677246 -50.963385) (xy 343.723556 -50.986981) (xy 343.765604 -51.017531) (xy 343.802355 -51.054282)
			(xy 343.832905 -51.09633) (xy 343.856501 -51.14264) (xy 343.872562 -51.19207) (xy 343.880692 -51.243405)
			(xy 343.881202 -51.269392) (xy 343.880692 -51.295379) (xy 343.872562 -51.346714) (xy 343.856501 -51.396144)
			(xy 343.832905 -51.442454) (xy 343.802355 -51.484502) (xy 343.765604 -51.521253) (xy 343.723556 -51.551803)
			(xy 343.677246 -51.575399) (xy 343.627816 -51.59146) (xy 343.576481 -51.59959) (xy 343.524507 -51.59959)
			(xy 343.473172 -51.59146) (xy 343.423742 -51.575399) (xy 343.377432 -51.551803) (xy 343.335384 -51.521253)
			(xy 343.298633 -51.484502) (xy 343.268083 -51.442454) (xy 343.244487 -51.396144) (xy 343.228426 -51.346714)
			(xy 343.220296 -51.295379) (xy 342.251541 -51.295379) (xy 342.251536 -51.295633) (xy 342.243406 -51.346968)
			(xy 342.227345 -51.396398) (xy 342.203749 -51.442708) (xy 342.173199 -51.484756) (xy 342.136448 -51.521507)
			(xy 342.0944 -51.552057) (xy 342.04809 -51.575653) (xy 341.99866 -51.591714) (xy 341.947325 -51.599844)
			(xy 341.895351 -51.599844) (xy 341.844016 -51.591714) (xy 341.794586 -51.575653) (xy 341.748276 -51.552057)
			(xy 341.706228 -51.521507) (xy 341.669477 -51.484756) (xy 341.638927 -51.442708) (xy 341.615331 -51.396398)
			(xy 341.59927 -51.346968) (xy 341.59114 -51.295633) (xy 340.620965 -51.295633) (xy 340.612837 -51.346945)
			(xy 340.59677 -51.39639) (xy 340.573165 -51.442712) (xy 340.542604 -51.484771) (xy 340.505839 -51.521531)
			(xy 340.463776 -51.552087) (xy 340.417451 -51.575686) (xy 340.368004 -51.591747) (xy 340.316653 -51.599874)
			(xy 340.290658 -51.600354) (xy 340.264761 -51.599863) (xy 340.2136 -51.591789) (xy 340.164326 -51.57583)
			(xy 340.118146 -51.552377) (xy 340.076192 -51.522005) (xy 340.057486 -51.504088) (xy 340.047827 -51.49516)
			(xy 340.025067 -51.482003) (xy 339.999701 -51.475098) (xy 339.973412 -51.474901) (xy 339.947946 -51.481427)
			(xy 339.924991 -51.494242) (xy 339.915246 -51.503072) (xy 339.896633 -51.520354) (xy 339.855123 -51.549619)
			(xy 339.809627 -51.572193) (xy 339.761215 -51.587546) (xy 339.711024 -51.595316) (xy 339.68563 -51.595782)
			(xy 339.659637 -51.595353) (xy 339.608291 -51.587225) (xy 339.558849 -51.571164) (xy 339.512528 -51.547566)
			(xy 339.470469 -51.517012) (xy 339.433708 -51.480254) (xy 339.40315 -51.438198) (xy 339.379547 -51.391879)
			(xy 339.363482 -51.342438) (xy 339.355349 -51.291093) (xy 331.395665 -51.291093) (xy 331.395576 -51.295633)
			(xy 331.387446 -51.346968) (xy 331.371385 -51.396398) (xy 331.347789 -51.442708) (xy 331.317239 -51.484756)
			(xy 331.280488 -51.521507) (xy 331.23844 -51.552057) (xy 331.19213 -51.575653) (xy 331.1427 -51.591714)
			(xy 331.091365 -51.599844) (xy 331.039391 -51.599844) (xy 330.988056 -51.591714) (xy 330.938626 -51.575653)
			(xy 330.892316 -51.552057) (xy 330.850268 -51.521507) (xy 330.813517 -51.484756) (xy 330.782967 -51.442708)
			(xy 330.759371 -51.396398) (xy 330.74331 -51.346968) (xy 330.73518 -51.295633) (xy 329.767944 -51.295633)
			(xy 329.759814 -51.346968) (xy 329.743753 -51.396398) (xy 329.720157 -51.442708) (xy 329.689607 -51.484756)
			(xy 329.652856 -51.521507) (xy 329.610808 -51.552057) (xy 329.564498 -51.575653) (xy 329.515068 -51.591714)
			(xy 329.463733 -51.599844) (xy 329.411759 -51.599844) (xy 329.360424 -51.591714) (xy 329.310994 -51.575653)
			(xy 329.264684 -51.552057) (xy 329.222636 -51.521507) (xy 329.185885 -51.484756) (xy 329.155335 -51.442708)
			(xy 329.131739 -51.396398) (xy 329.115678 -51.346968) (xy 329.107548 -51.295633) (xy 328.955906 -51.295633)
			(xy 328.947776 -51.346968) (xy 328.931715 -51.396398) (xy 328.908119 -51.442708) (xy 328.877569 -51.484756)
			(xy 328.840818 -51.521507) (xy 328.79877 -51.552057) (xy 328.75246 -51.575653) (xy 328.70303 -51.591714)
			(xy 328.651695 -51.599844) (xy 328.599721 -51.599844) (xy 328.548386 -51.591714) (xy 328.498956 -51.575653)
			(xy 328.452646 -51.552057) (xy 328.410598 -51.521507) (xy 328.373847 -51.484756) (xy 328.343297 -51.442708)
			(xy 328.319701 -51.396398) (xy 328.30364 -51.346968) (xy 328.29551 -51.295633) (xy 326.35397 -51.295633)
			(xy 326.354959 -51.302354) (xy 326.355456 -51.32959) (xy 326.354959 -51.356826) (xy 326.347028 -51.410717)
			(xy 326.331335 -51.462879) (xy 326.308214 -51.5122) (xy 326.278158 -51.557629) (xy 326.241809 -51.598198)
			(xy 326.199939 -51.633042) (xy 326.153443 -51.661418) (xy 326.10331 -51.682722) (xy 326.05061 -51.6965)
			(xy 325.996465 -51.702458) (xy 325.94203 -51.700468) (xy 325.888464 -51.690574) (xy 325.83691 -51.672986)
			(xy 325.788467 -51.64808) (xy 325.744165 -51.616385) (xy 325.704951 -51.578578) (xy 325.67166 -51.535464)
			(xy 325.645 -51.487962) (xy 325.625541 -51.437085) (xy 325.613698 -51.383916) (xy 325.609722 -51.32959)
			(xy 324.977016 -51.32959) (xy 324.960848 -51.354027) (xy 324.923631 -51.395564) (xy 324.880763 -51.431239)
			(xy 324.833157 -51.460293) (xy 324.781828 -51.482105) (xy 324.727871 -51.496211) (xy 324.672434 -51.502311)
			(xy 324.6167 -51.500274) (xy 324.561857 -51.490144) (xy 324.509073 -51.472137) (xy 324.459473 -51.446636)
			(xy 324.414115 -51.414185) (xy 324.373966 -51.375476) (xy 324.33988 -51.331333) (xy 324.312584 -51.282698)
			(xy 324.292661 -51.230607) (xy 324.280535 -51.17617) (xy 324.276464 -51.120548) (xy 323.587567 -51.120548)
			(xy 323.540297 -51.149397) (xy 323.488968 -51.171209) (xy 323.435011 -51.185315) (xy 323.379574 -51.191415)
			(xy 323.32384 -51.189378) (xy 323.268997 -51.179248) (xy 323.216213 -51.161241) (xy 323.166613 -51.13574)
			(xy 323.121255 -51.103289) (xy 323.081106 -51.06458) (xy 323.04702 -51.020437) (xy 323.019724 -50.971802)
			(xy 322.999801 -50.919711) (xy 322.987675 -50.865274) (xy 322.983604 -50.809652) (xy 318.600822 -50.809652)
			(xy 318.642777 -50.835257) (xy 318.685645 -50.870932) (xy 318.722862 -50.912469) (xy 318.753635 -50.958982)
			(xy 318.777307 -51.009479) (xy 318.793375 -51.062886) (xy 318.801495 -51.118062) (xy 318.802004 -51.145948)
			(xy 318.801495 -51.173834) (xy 318.793375 -51.22901) (xy 318.777307 -51.282417) (xy 318.753635 -51.332914)
			(xy 318.722862 -51.379427) (xy 318.685645 -51.420964) (xy 318.642777 -51.456639) (xy 318.595171 -51.485693)
			(xy 318.543842 -51.507505) (xy 318.489885 -51.521611) (xy 318.434448 -51.527711) (xy 318.378714 -51.525674)
			(xy 318.323871 -51.515544) (xy 318.271087 -51.497537) (xy 318.221487 -51.472036) (xy 318.176129 -51.439585)
			(xy 318.13598 -51.400876) (xy 318.101894 -51.356733) (xy 318.074598 -51.308098) (xy 318.054675 -51.256007)
			(xy 318.042549 -51.20157) (xy 318.038478 -51.145948) (xy 314.42917 -51.145948) (xy 314.42917 -51.198553)
			(xy 314.421414 -51.252504) (xy 314.406059 -51.304802) (xy 314.383418 -51.354383) (xy 314.353951 -51.400237)
			(xy 314.31826 -51.441431) (xy 314.277069 -51.477127) (xy 314.231218 -51.506598) (xy 314.18164 -51.529245)
			(xy 314.129343 -51.544605) (xy 314.075393 -51.552367) (xy 314.04814 -51.552856) (xy 314.021214 -51.552354)
			(xy 313.967899 -51.544775) (xy 313.916178 -51.529777) (xy 313.867079 -51.507655) (xy 313.821578 -51.478852)
			(xy 313.780578 -51.443937) (xy 313.76239 -51.424078) (xy 313.75263 -51.413719) (xy 313.728624 -51.39845)
			(xy 313.701339 -51.390389) (xy 313.672888 -51.390161) (xy 313.645477 -51.397782) (xy 313.621228 -51.412663)
			(xy 313.60202 -51.433652) (xy 313.595258 -51.446176) (xy 313.58307 -51.469667) (xy 313.553167 -51.513331)
			(xy 313.517518 -51.552444) (xy 313.506012 -51.562) (xy 315.971426 -51.562) (xy 315.975497 -51.506378)
			(xy 315.987623 -51.451941) (xy 316.007546 -51.39985) (xy 316.034842 -51.351215) (xy 316.068928 -51.307072)
			(xy 316.109077 -51.268363) (xy 316.154435 -51.235912) (xy 316.204035 -51.210411) (xy 316.256819 -51.192404)
			(xy 316.311662 -51.182274) (xy 316.367396 -51.180237) (xy 316.422833 -51.186337) (xy 316.47679 -51.200443)
			(xy 316.528119 -51.222255) (xy 316.575725 -51.251309) (xy 316.618593 -51.286984) (xy 316.65581 -51.328521)
			(xy 316.686583 -51.375034) (xy 316.710255 -51.425531) (xy 316.726323 -51.478938) (xy 316.734443 -51.534114)
			(xy 316.734952 -51.562) (xy 316.734443 -51.589886) (xy 316.726323 -51.645062) (xy 316.710255 -51.698469)
			(xy 316.686583 -51.748966) (xy 316.675622 -51.765533) (xy 329.92238 -51.765533) (xy 329.92238 -51.713559)
			(xy 329.93051 -51.662224) (xy 329.946571 -51.612794) (xy 329.970167 -51.566484) (xy 330.000717 -51.524436)
			(xy 330.037468 -51.487685) (xy 330.079516 -51.457135) (xy 330.125826 -51.433539) (xy 330.175256 -51.417478)
			(xy 330.226591 -51.409348) (xy 330.278565 -51.409348) (xy 330.3299 -51.417478) (xy 330.37933 -51.433539)
			(xy 330.42564 -51.457135) (xy 330.467688 -51.487685) (xy 330.504439 -51.524436) (xy 330.534989 -51.566484)
			(xy 330.558585 -51.612794) (xy 330.574646 -51.662224) (xy 330.582776 -51.713559) (xy 330.583286 -51.739546)
			(xy 330.582776 -51.765533) (xy 331.549758 -51.765533) (xy 331.549758 -51.713559) (xy 331.557888 -51.662224)
			(xy 331.573949 -51.612794) (xy 331.597545 -51.566484) (xy 331.628095 -51.524436) (xy 331.664846 -51.487685)
			(xy 331.706894 -51.457135) (xy 331.753204 -51.433539) (xy 331.802634 -51.417478) (xy 331.853969 -51.409348)
			(xy 331.905943 -51.409348) (xy 331.957278 -51.417478) (xy 332.006708 -51.433539) (xy 332.053018 -51.457135)
			(xy 332.095066 -51.487685) (xy 332.131817 -51.524436) (xy 332.162367 -51.566484) (xy 332.185963 -51.612794)
			(xy 332.202024 -51.662224) (xy 332.210154 -51.713559) (xy 332.210664 -51.739546) (xy 332.210155 -51.765481)
			(xy 333.178748 -51.765481) (xy 333.178748 -51.713519) (xy 333.186876 -51.662195) (xy 333.202932 -51.612775)
			(xy 333.226521 -51.566475) (xy 333.257062 -51.524435) (xy 333.293803 -51.487689) (xy 333.335839 -51.457143)
			(xy 333.382136 -51.433548) (xy 333.431554 -51.417486) (xy 333.482877 -51.409351) (xy 333.508858 -51.408838)
			(xy 333.533981 -51.409296) (xy 333.583649 -51.416891) (xy 333.631596 -51.431913) (xy 333.676718 -51.454016)
			(xy 333.717978 -51.482692) (xy 333.754424 -51.517279) (xy 333.785217 -51.556982) (xy 333.80965 -51.600887)
			(xy 333.827159 -51.647983) (xy 333.832708 -51.67249) (xy 333.836263 -51.687019) (xy 333.85057 -51.713269)
			(xy 333.871855 -51.734265) (xy 333.898299 -51.748211) (xy 333.927646 -51.75392) (xy 333.95739 -51.750902)
			(xy 333.971392 -51.745642) (xy 333.991743 -51.737512) (xy 334.03405 -51.726081) (xy 334.077496 -51.720329)
			(xy 334.099408 -51.719988) (xy 334.125394 -51.720506) (xy 334.176727 -51.728638) (xy 334.226156 -51.744699)
			(xy 334.272464 -51.768295) (xy 334.314511 -51.798845) (xy 334.351261 -51.835595) (xy 334.381809 -51.877643)
			(xy 334.405404 -51.923951) (xy 334.421464 -51.97338) (xy 334.429595 -52.024714) (xy 334.429595 -52.076686)
			(xy 334.421464 -52.12802) (xy 334.405404 -52.177449) (xy 334.381809 -52.223757) (xy 334.351261 -52.265805)
			(xy 334.314511 -52.302555) (xy 334.272464 -52.333105) (xy 334.226156 -52.356701) (xy 334.176727 -52.372762)
			(xy 334.125394 -52.380894) (xy 334.099408 -52.381404) (xy 334.074286 -52.380944) (xy 334.02462 -52.373345)
			(xy 333.976675 -52.35832) (xy 333.931554 -52.336216) (xy 333.890296 -52.307541) (xy 333.853851 -52.272955)
			(xy 333.823056 -52.233253) (xy 333.798622 -52.189351) (xy 333.781109 -52.142257) (xy 333.775558 -52.117752)
			(xy 333.772022 -52.103216) (xy 333.757717 -52.076957) (xy 333.73643 -52.055956) (xy 333.70998 -52.042008)
			(xy 333.680626 -52.036305) (xy 333.650877 -52.039333) (xy 333.636874 -52.0446) (xy 333.616527 -52.052742)
			(xy 333.574218 -52.064168) (xy 333.530771 -52.069916) (xy 333.508858 -52.070254) (xy 333.482877 -52.069649)
			(xy 333.431554 -52.061514) (xy 333.382136 -52.045452) (xy 333.335839 -52.021857) (xy 333.293803 -51.991311)
			(xy 333.257062 -51.954565) (xy 333.226521 -51.912525) (xy 333.202932 -51.866225) (xy 333.186876 -51.816805)
			(xy 333.178748 -51.765481) (xy 332.210155 -51.765481) (xy 332.210154 -51.765533) (xy 332.202024 -51.816868)
			(xy 332.185963 -51.866298) (xy 332.162367 -51.912608) (xy 332.131817 -51.954656) (xy 332.095066 -51.991407)
			(xy 332.053018 -52.021957) (xy 332.006708 -52.045553) (xy 331.957278 -52.061614) (xy 331.905943 -52.069744)
			(xy 331.853969 -52.069744) (xy 331.802634 -52.061614) (xy 331.753204 -52.045553) (xy 331.706894 -52.021957)
			(xy 331.664846 -51.991407) (xy 331.628095 -51.954656) (xy 331.597545 -51.912608) (xy 331.573949 -51.866298)
			(xy 331.557888 -51.816868) (xy 331.549758 -51.765533) (xy 330.582776 -51.765533) (xy 330.574646 -51.816868)
			(xy 330.558585 -51.866298) (xy 330.534989 -51.912608) (xy 330.504439 -51.954656) (xy 330.467688 -51.991407)
			(xy 330.42564 -52.021957) (xy 330.37933 -52.045553) (xy 330.3299 -52.061614) (xy 330.278565 -52.069744)
			(xy 330.226591 -52.069744) (xy 330.175256 -52.061614) (xy 330.125826 -52.045553) (xy 330.079516 -52.021957)
			(xy 330.037468 -51.991407) (xy 330.000717 -51.954656) (xy 329.970167 -51.912608) (xy 329.946571 -51.866298)
			(xy 329.93051 -51.816868) (xy 329.92238 -51.765533) (xy 316.675622 -51.765533) (xy 316.65581 -51.795479)
			(xy 316.618593 -51.837016) (xy 316.575725 -51.872691) (xy 316.528119 -51.901745) (xy 316.47679 -51.923557)
			(xy 316.422833 -51.937663) (xy 316.367396 -51.943763) (xy 316.311662 -51.941726) (xy 316.256819 -51.931596)
			(xy 316.204035 -51.913589) (xy 316.154435 -51.888088) (xy 316.109077 -51.855637) (xy 316.068928 -51.816928)
			(xy 316.034842 -51.772785) (xy 316.007546 -51.72415) (xy 315.987623 -51.672059) (xy 315.975497 -51.617622)
			(xy 315.971426 -51.562) (xy 313.506012 -51.562) (xy 313.476806 -51.586257) (xy 313.431814 -51.614122)
			(xy 313.383403 -51.635502) (xy 313.332503 -51.649989) (xy 313.280089 -51.657305) (xy 313.253628 -51.657758)
			(xy 313.226377 -51.657197) (xy 313.172431 -51.649444) (xy 313.120136 -51.634092) (xy 313.070559 -51.611454)
			(xy 313.024708 -51.581991) (xy 312.983518 -51.546302) (xy 312.947826 -51.505114) (xy 312.918359 -51.459266)
			(xy 312.895717 -51.40969) (xy 312.880362 -51.357397) (xy 312.872605 -51.303451) (xy 312.422458 -51.303451)
			(xy 312.425079 -51.321262) (xy 312.425588 -51.349148) (xy 312.425079 -51.377034) (xy 312.416959 -51.43221)
			(xy 312.400891 -51.485617) (xy 312.377219 -51.536114) (xy 312.346446 -51.582627) (xy 312.309229 -51.624164)
			(xy 312.266361 -51.659839) (xy 312.218755 -51.688893) (xy 312.167426 -51.710705) (xy 312.113469 -51.724811)
			(xy 312.058032 -51.730911) (xy 312.002298 -51.728874) (xy 311.947455 -51.718744) (xy 311.894671 -51.700737)
			(xy 311.845071 -51.675236) (xy 311.799713 -51.642785) (xy 311.759564 -51.604076) (xy 311.725478 -51.559933)
			(xy 311.698182 -51.511298) (xy 311.678259 -51.459207) (xy 311.666133 -51.40477) (xy 311.662062 -51.349148)
			(xy 305.98377 -51.349148) (xy 305.985679 -51.355494) (xy 305.993799 -51.41067) (xy 305.994308 -51.438556)
			(xy 305.993799 -51.466442) (xy 305.985679 -51.521618) (xy 305.969611 -51.575025) (xy 305.945939 -51.625522)
			(xy 305.915166 -51.672035) (xy 305.877949 -51.713572) (xy 305.835081 -51.749247) (xy 305.787475 -51.778301)
			(xy 305.736146 -51.800113) (xy 305.682189 -51.814219) (xy 305.626752 -51.820319) (xy 305.571018 -51.818282)
			(xy 305.516175 -51.808152) (xy 305.463391 -51.790145) (xy 305.413791 -51.764644) (xy 305.368433 -51.732193)
			(xy 305.328284 -51.693484) (xy 305.294198 -51.649341) (xy 305.266902 -51.600706) (xy 305.246979 -51.548615)
			(xy 305.234853 -51.494178) (xy 305.230782 -51.438556) (xy 282.38704 -51.438556) (xy 282.38704 -52.068554)
			(xy 294.444853 -52.068554) (xy 294.444853 -52.014046) (xy 294.452611 -51.960092) (xy 294.467969 -51.907792)
			(xy 294.490613 -51.858209) (xy 294.520084 -51.812355) (xy 294.555781 -51.771161) (xy 294.596977 -51.735467)
			(xy 294.642834 -51.706) (xy 294.692418 -51.683359) (xy 294.744719 -51.668005) (xy 294.798674 -51.660251)
			(xy 294.825928 -51.65979) (xy 294.854845 -51.660326) (xy 294.912017 -51.669047) (xy 294.967217 -51.686299)
			(xy 295.019179 -51.711687) (xy 295.066713 -51.744629) (xy 295.108729 -51.78437) (xy 295.126918 -51.806856)
			(xy 295.136815 -51.818661) (xy 295.162139 -51.83618) (xy 295.191532 -51.845356) (xy 295.222324 -51.845356)
			(xy 295.251717 -51.83618) (xy 295.277041 -51.818661) (xy 295.286938 -51.806856) (xy 295.305096 -51.784345)
			(xy 295.347124 -51.744614) (xy 295.394666 -51.711679) (xy 295.446634 -51.686296) (xy 295.501837 -51.669045)
			(xy 295.55901 -51.660322) (xy 295.587928 -51.65979) (xy 295.615178 -51.660282) (xy 295.669122 -51.668041)
			(xy 295.721413 -51.683399) (xy 295.770987 -51.706041) (xy 295.816833 -51.735508) (xy 295.85802 -51.7712)
			(xy 295.893708 -51.812389) (xy 295.923172 -51.858238) (xy 295.945811 -51.907813) (xy 295.961165 -51.960105)
			(xy 295.96892 -52.01405) (xy 295.96892 -52.06855) (xy 295.961165 -52.122495) (xy 295.951072 -52.156868)
			(xy 300.216822 -52.156868) (xy 300.220893 -52.101246) (xy 300.233019 -52.046809) (xy 300.252942 -51.994718)
			(xy 300.280238 -51.946083) (xy 300.314324 -51.90194) (xy 300.354473 -51.863231) (xy 300.399831 -51.83078)
			(xy 300.449431 -51.805279) (xy 300.502215 -51.787272) (xy 300.557058 -51.777142) (xy 300.612792 -51.775105)
			(xy 300.668229 -51.781205) (xy 300.722186 -51.795311) (xy 300.773515 -51.817123) (xy 300.821121 -51.846177)
			(xy 300.863989 -51.881852) (xy 300.901206 -51.923389) (xy 300.929826 -51.966648) (xy 302.641022 -51.966648)
			(xy 302.641022 -51.912152) (xy 302.648778 -51.85821) (xy 302.664131 -51.805922) (xy 302.68677 -51.75635)
			(xy 302.716232 -51.710505) (xy 302.75192 -51.66932) (xy 302.793105 -51.633632) (xy 302.83895 -51.60417)
			(xy 302.888522 -51.581531) (xy 302.94081 -51.566178) (xy 302.994752 -51.558422) (xy 303.022 -51.557936)
			(xy 303.049371 -51.558393) (xy 303.10355 -51.566212) (xy 303.156054 -51.581703) (xy 303.205801 -51.604546)
			(xy 303.251767 -51.634273) (xy 303.272698 -51.651916) (xy 303.284026 -51.661152) (xy 303.310583 -51.673328)
			(xy 303.3395 -51.677501) (xy 303.368417 -51.673328) (xy 303.394974 -51.661152) (xy 303.406302 -51.651916)
			(xy 303.427225 -51.634265) (xy 303.4732 -51.604554) (xy 303.52295 -51.58172) (xy 303.575452 -51.566232)
			(xy 303.62963 -51.558408) (xy 303.657 -51.557936) (xy 303.684254 -51.558334) (xy 303.738208 -51.566091)
			(xy 303.790509 -51.581448) (xy 303.840092 -51.604092) (xy 303.885948 -51.633562) (xy 303.927143 -51.669257)
			(xy 303.962838 -51.710452) (xy 303.992308 -51.756308) (xy 304.014952 -51.805891) (xy 304.030309 -51.858192)
			(xy 304.038066 -51.912146) (xy 304.038066 -51.966654) (xy 304.030309 -52.020608) (xy 304.014952 -52.072909)
			(xy 303.992308 -52.122492) (xy 303.962838 -52.168348) (xy 303.927143 -52.209543) (xy 303.885948 -52.245238)
			(xy 303.840092 -52.274708) (xy 303.790509 -52.297352) (xy 303.738208 -52.312709) (xy 303.684254 -52.320466)
			(xy 303.657 -52.320952) (xy 303.629629 -52.320498) (xy 303.575449 -52.312679) (xy 303.522945 -52.297188)
			(xy 303.473199 -52.274343) (xy 303.427233 -52.244615) (xy 303.406302 -52.226972) (xy 303.394974 -52.217736)
			(xy 303.368417 -52.20556) (xy 303.3395 -52.201387) (xy 303.310583 -52.20556) (xy 303.284026 -52.217736)
			(xy 303.272698 -52.226972) (xy 303.251774 -52.244621) (xy 303.205799 -52.274332) (xy 303.15605 -52.297167)
			(xy 303.103547 -52.312655) (xy 303.04937 -52.32048) (xy 303.022 -52.320952) (xy 302.994752 -52.320378)
			(xy 302.94081 -52.312622) (xy 302.888522 -52.297269) (xy 302.83895 -52.27463) (xy 302.793105 -52.245168)
			(xy 302.75192 -52.20948) (xy 302.716232 -52.168295) (xy 302.68677 -52.12245) (xy 302.664131 -52.072878)
			(xy 302.648778 -52.02059) (xy 302.641022 -51.966648) (xy 300.929826 -51.966648) (xy 300.931979 -51.969902)
			(xy 300.955651 -52.020399) (xy 300.971719 -52.073806) (xy 300.979839 -52.128982) (xy 300.980348 -52.156868)
			(xy 300.979839 -52.184754) (xy 300.971719 -52.23993) (xy 300.955651 -52.293337) (xy 300.941039 -52.324508)
			(xy 304.628802 -52.324508) (xy 304.632873 -52.268886) (xy 304.644999 -52.214449) (xy 304.664922 -52.162358)
			(xy 304.692218 -52.113723) (xy 304.726304 -52.06958) (xy 304.766453 -52.030871) (xy 304.811811 -51.99842)
			(xy 304.861411 -51.972919) (xy 304.914195 -51.954912) (xy 304.969038 -51.944782) (xy 305.024772 -51.942745)
			(xy 305.080209 -51.948845) (xy 305.134166 -51.962951) (xy 305.185495 -51.984763) (xy 305.233101 -52.013817)
			(xy 305.258493 -52.034948) (xy 308.410862 -52.034948) (xy 308.414933 -51.979326) (xy 308.427059 -51.924889)
			(xy 308.446982 -51.872798) (xy 308.474278 -51.824163) (xy 308.508364 -51.78002) (xy 308.548513 -51.741311)
			(xy 308.593871 -51.70886) (xy 308.643471 -51.683359) (xy 308.696255 -51.665352) (xy 308.751098 -51.655222)
			(xy 308.806832 -51.653185) (xy 308.862269 -51.659285) (xy 308.916226 -51.673391) (xy 308.967555 -51.695203)
			(xy 309.015161 -51.724257) (xy 309.058029 -51.759932) (xy 309.095246 -51.801469) (xy 309.126019 -51.847982)
			(xy 309.149691 -51.898479) (xy 309.165759 -51.951886) (xy 309.173879 -52.007062) (xy 309.174388 -52.034948)
			(xy 309.173879 -52.062834) (xy 309.165759 -52.11801) (xy 309.149691 -52.171417) (xy 309.126019 -52.221914)
			(xy 309.095246 -52.268427) (xy 309.076859 -52.288948) (xy 310.442862 -52.288948) (xy 310.446933 -52.233326)
			(xy 310.459059 -52.178889) (xy 310.478982 -52.126798) (xy 310.506278 -52.078163) (xy 310.540364 -52.03402)
			(xy 310.580513 -51.995311) (xy 310.625871 -51.96286) (xy 310.675471 -51.937359) (xy 310.728255 -51.919352)
			(xy 310.783098 -51.909222) (xy 310.838832 -51.907185) (xy 310.894269 -51.913285) (xy 310.948226 -51.927391)
			(xy 310.999555 -51.949203) (xy 311.047161 -51.978257) (xy 311.090029 -52.013932) (xy 311.127246 -52.055469)
			(xy 311.158019 -52.101982) (xy 311.181691 -52.152479) (xy 311.197759 -52.205886) (xy 311.205879 -52.261062)
			(xy 311.205924 -52.263548) (xy 313.710318 -52.263548) (xy 313.714389 -52.207926) (xy 313.726515 -52.153489)
			(xy 313.746438 -52.101398) (xy 313.773734 -52.052763) (xy 313.80782 -52.00862) (xy 313.847969 -51.969911)
			(xy 313.893327 -51.93746) (xy 313.942927 -51.911959) (xy 313.995711 -51.893952) (xy 314.050554 -51.883822)
			(xy 314.106288 -51.881785) (xy 314.161725 -51.887885) (xy 314.215682 -51.901991) (xy 314.267011 -51.923803)
			(xy 314.314617 -51.952857) (xy 314.357485 -51.988532) (xy 314.394702 -52.030069) (xy 314.425475 -52.076582)
			(xy 314.449147 -52.127079) (xy 314.465215 -52.180486) (xy 314.473335 -52.235662) (xy 314.473844 -52.263548)
			(xy 314.473335 -52.291434) (xy 314.47096 -52.307569) (xy 328.294494 -52.307569) (xy 328.294494 -52.255595)
			(xy 328.302624 -52.20426) (xy 328.318685 -52.15483) (xy 328.342281 -52.10852) (xy 328.372831 -52.066472)
			(xy 328.409582 -52.029721) (xy 328.45163 -51.999171) (xy 328.49794 -51.975575) (xy 328.54737 -51.959514)
			(xy 328.598705 -51.951384) (xy 328.650679 -51.951384) (xy 328.702014 -51.959514) (xy 328.751444 -51.975575)
			(xy 328.797754 -51.999171) (xy 328.839802 -52.029721) (xy 328.876553 -52.066472) (xy 328.907103 -52.10852)
			(xy 328.930699 -52.15483) (xy 328.94676 -52.20426) (xy 328.951697 -52.235433) (xy 329.107548 -52.235433)
			(xy 329.107548 -52.183459) (xy 329.115678 -52.132124) (xy 329.131739 -52.082694) (xy 329.155335 -52.036384)
			(xy 329.185885 -51.994336) (xy 329.222636 -51.957585) (xy 329.264684 -51.927035) (xy 329.310994 -51.903439)
			(xy 329.360424 -51.887378) (xy 329.411759 -51.879248) (xy 329.463733 -51.879248) (xy 329.515068 -51.887378)
			(xy 329.564498 -51.903439) (xy 329.610808 -51.927035) (xy 329.652856 -51.957585) (xy 329.689607 -51.994336)
			(xy 329.720157 -52.036384) (xy 329.743753 -52.082694) (xy 329.759814 -52.132124) (xy 329.767944 -52.183459)
			(xy 329.768454 -52.209446) (xy 329.767944 -52.235433) (xy 330.737466 -52.235433) (xy 330.737466 -52.183459)
			(xy 330.745596 -52.132124) (xy 330.761657 -52.082694) (xy 330.785253 -52.036384) (xy 330.815803 -51.994336)
			(xy 330.852554 -51.957585) (xy 330.894602 -51.927035) (xy 330.940912 -51.903439) (xy 330.990342 -51.887378)
			(xy 331.041677 -51.879248) (xy 331.093651 -51.879248) (xy 331.144986 -51.887378) (xy 331.194416 -51.903439)
			(xy 331.240726 -51.927035) (xy 331.282774 -51.957585) (xy 331.319525 -51.994336) (xy 331.350075 -52.036384)
			(xy 331.373671 -52.082694) (xy 331.389732 -52.132124) (xy 331.397862 -52.183459) (xy 331.398372 -52.209446)
			(xy 331.397862 -52.235433) (xy 331.389732 -52.286768) (xy 331.373671 -52.336198) (xy 331.350075 -52.382508)
			(xy 331.319525 -52.424556) (xy 331.282774 -52.461307) (xy 331.240726 -52.491857) (xy 331.194416 -52.515453)
			(xy 331.144986 -52.531514) (xy 331.093651 -52.539644) (xy 331.041677 -52.539644) (xy 330.990342 -52.531514)
			(xy 330.940912 -52.515453) (xy 330.894602 -52.491857) (xy 330.852554 -52.461307) (xy 330.815803 -52.424556)
			(xy 330.785253 -52.382508) (xy 330.761657 -52.336198) (xy 330.745596 -52.286768) (xy 330.737466 -52.235433)
			(xy 329.767944 -52.235433) (xy 329.759814 -52.286768) (xy 329.743753 -52.336198) (xy 329.720157 -52.382508)
			(xy 329.689607 -52.424556) (xy 329.652856 -52.461307) (xy 329.610808 -52.491857) (xy 329.564498 -52.515453)
			(xy 329.515068 -52.531514) (xy 329.463733 -52.539644) (xy 329.411759 -52.539644) (xy 329.360424 -52.531514)
			(xy 329.310994 -52.515453) (xy 329.264684 -52.491857) (xy 329.222636 -52.461307) (xy 329.185885 -52.424556)
			(xy 329.155335 -52.382508) (xy 329.131739 -52.336198) (xy 329.115678 -52.286768) (xy 329.107548 -52.235433)
			(xy 328.951697 -52.235433) (xy 328.95489 -52.255595) (xy 328.9554 -52.281582) (xy 328.95489 -52.307569)
			(xy 328.94676 -52.358904) (xy 328.930699 -52.408334) (xy 328.907103 -52.454644) (xy 328.876553 -52.496692)
			(xy 328.839802 -52.533443) (xy 328.797754 -52.563993) (xy 328.751444 -52.587589) (xy 328.702014 -52.60365)
			(xy 328.650679 -52.61178) (xy 328.598705 -52.61178) (xy 328.54737 -52.60365) (xy 328.49794 -52.587589)
			(xy 328.45163 -52.563993) (xy 328.409582 -52.533443) (xy 328.372831 -52.496692) (xy 328.342281 -52.454644)
			(xy 328.318685 -52.408334) (xy 328.302624 -52.358904) (xy 328.294494 -52.307569) (xy 314.47096 -52.307569)
			(xy 314.465215 -52.34661) (xy 314.449147 -52.400017) (xy 314.425475 -52.450514) (xy 314.394702 -52.497027)
			(xy 314.357485 -52.538564) (xy 314.314617 -52.574239) (xy 314.267011 -52.603293) (xy 314.215682 -52.625105)
			(xy 314.161725 -52.639211) (xy 314.106288 -52.645311) (xy 314.050554 -52.643274) (xy 313.995711 -52.633144)
			(xy 313.942927 -52.615137) (xy 313.893327 -52.589636) (xy 313.847969 -52.557185) (xy 313.80782 -52.518476)
			(xy 313.773734 -52.474333) (xy 313.746438 -52.425698) (xy 313.726515 -52.373607) (xy 313.714389 -52.31917)
			(xy 313.710318 -52.263548) (xy 311.205924 -52.263548) (xy 311.206388 -52.288948) (xy 311.205879 -52.316834)
			(xy 311.197759 -52.37201) (xy 311.181691 -52.425417) (xy 311.158019 -52.475914) (xy 311.127246 -52.522427)
			(xy 311.090029 -52.563964) (xy 311.047161 -52.599639) (xy 310.999555 -52.628693) (xy 310.948226 -52.650505)
			(xy 310.894269 -52.664611) (xy 310.838832 -52.670711) (xy 310.783098 -52.668674) (xy 310.728255 -52.658544)
			(xy 310.675471 -52.640537) (xy 310.625871 -52.615036) (xy 310.580513 -52.582585) (xy 310.540364 -52.543876)
			(xy 310.506278 -52.499733) (xy 310.478982 -52.451098) (xy 310.459059 -52.399007) (xy 310.446933 -52.34457)
			(xy 310.442862 -52.288948) (xy 309.076859 -52.288948) (xy 309.058029 -52.309964) (xy 309.015161 -52.345639)
			(xy 308.967555 -52.374693) (xy 308.916226 -52.396505) (xy 308.862269 -52.410611) (xy 308.806832 -52.416711)
			(xy 308.751098 -52.414674) (xy 308.696255 -52.404544) (xy 308.643471 -52.386537) (xy 308.593871 -52.361036)
			(xy 308.548513 -52.328585) (xy 308.508364 -52.289876) (xy 308.474278 -52.245733) (xy 308.446982 -52.197098)
			(xy 308.427059 -52.145007) (xy 308.414933 -52.09057) (xy 308.410862 -52.034948) (xy 305.258493 -52.034948)
			(xy 305.275969 -52.049492) (xy 305.313186 -52.091029) (xy 305.343959 -52.137542) (xy 305.367631 -52.188039)
			(xy 305.383699 -52.241446) (xy 305.391819 -52.296622) (xy 305.392328 -52.324508) (xy 305.391819 -52.352394)
			(xy 305.383699 -52.40757) (xy 305.367631 -52.460977) (xy 305.343959 -52.511474) (xy 305.313186 -52.557987)
			(xy 305.275969 -52.599524) (xy 305.233101 -52.635199) (xy 305.185495 -52.664253) (xy 305.134166 -52.686065)
			(xy 305.080209 -52.700171) (xy 305.024772 -52.706271) (xy 304.969038 -52.704234) (xy 304.914195 -52.694104)
			(xy 304.861411 -52.676097) (xy 304.811811 -52.650596) (xy 304.766453 -52.618145) (xy 304.726304 -52.579436)
			(xy 304.692218 -52.535293) (xy 304.664922 -52.486658) (xy 304.644999 -52.434567) (xy 304.632873 -52.38013)
			(xy 304.628802 -52.324508) (xy 300.941039 -52.324508) (xy 300.931979 -52.343834) (xy 300.901206 -52.390347)
			(xy 300.863989 -52.431884) (xy 300.821121 -52.467559) (xy 300.773515 -52.496613) (xy 300.722186 -52.518425)
			(xy 300.668229 -52.532531) (xy 300.612792 -52.538631) (xy 300.557058 -52.536594) (xy 300.502215 -52.526464)
			(xy 300.449431 -52.508457) (xy 300.399831 -52.482956) (xy 300.354473 -52.450505) (xy 300.314324 -52.411796)
			(xy 300.280238 -52.367653) (xy 300.252942 -52.319018) (xy 300.233019 -52.266927) (xy 300.220893 -52.21249)
			(xy 300.216822 -52.156868) (xy 295.951072 -52.156868) (xy 295.945811 -52.174787) (xy 295.923172 -52.224362)
			(xy 295.893708 -52.270211) (xy 295.85802 -52.3114) (xy 295.816833 -52.347092) (xy 295.770987 -52.376559)
			(xy 295.721413 -52.399201) (xy 295.669122 -52.414559) (xy 295.615178 -52.422318) (xy 295.587928 -52.422806)
			(xy 295.55901 -52.422303) (xy 295.501837 -52.413576) (xy 295.446636 -52.396317) (xy 295.394674 -52.370923)
			(xy 295.34714 -52.337975) (xy 295.305126 -52.298228) (xy 295.286938 -52.27574) (xy 295.277041 -52.263935)
			(xy 295.251717 -52.246416) (xy 295.222324 -52.23724) (xy 295.191532 -52.23724) (xy 295.162139 -52.246416)
			(xy 295.136815 -52.263935) (xy 295.126918 -52.27574) (xy 295.108727 -52.298223) (xy 295.066706 -52.337957)
			(xy 295.019171 -52.370894) (xy 294.96721 -52.396282) (xy 294.912013 -52.413539) (xy 294.854844 -52.42227)
			(xy 294.825928 -52.422806) (xy 294.798674 -52.422349) (xy 294.744719 -52.414595) (xy 294.692418 -52.399241)
			(xy 294.642834 -52.3766) (xy 294.596977 -52.347133) (xy 294.555781 -52.311439) (xy 294.520084 -52.270245)
			(xy 294.490613 -52.224391) (xy 294.467969 -52.174808) (xy 294.452611 -52.122508) (xy 294.444853 -52.068554)
			(xy 282.38704 -52.068554) (xy 282.38704 -53.071268) (xy 283.713426 -53.071268) (xy 283.717497 -53.015646)
			(xy 283.729623 -52.961209) (xy 283.749546 -52.909118) (xy 283.776842 -52.860483) (xy 283.810928 -52.81634)
			(xy 283.851077 -52.777631) (xy 283.896435 -52.74518) (xy 283.946035 -52.719679) (xy 283.998819 -52.701672)
			(xy 284.053662 -52.691542) (xy 284.109396 -52.689505) (xy 284.164833 -52.695605) (xy 284.21879 -52.709711)
			(xy 284.270119 -52.731523) (xy 284.317725 -52.760577) (xy 284.360593 -52.796252) (xy 284.39781 -52.837789)
			(xy 284.428583 -52.884302) (xy 284.452255 -52.934799) (xy 284.468323 -52.988206) (xy 284.476443 -53.043382)
			(xy 284.476952 -53.071268) (xy 284.476443 -53.099154) (xy 284.468323 -53.15433) (xy 284.452255 -53.207737)
			(xy 284.428583 -53.258234) (xy 284.39781 -53.304747) (xy 284.360593 -53.346284) (xy 284.317725 -53.381959)
			(xy 284.31406 -53.384196) (xy 297.525692 -53.384196) (xy 297.529763 -53.328574) (xy 297.541889 -53.274137)
			(xy 297.561812 -53.222046) (xy 297.589108 -53.173411) (xy 297.623194 -53.129268) (xy 297.663343 -53.090559)
			(xy 297.708701 -53.058108) (xy 297.758301 -53.032607) (xy 297.811085 -53.0146) (xy 297.865928 -53.00447)
			(xy 297.921662 -53.002433) (xy 297.977099 -53.008533) (xy 298.031056 -53.022639) (xy 298.061811 -53.035708)
			(xy 299.711362 -53.035708) (xy 299.715433 -52.980086) (xy 299.727559 -52.925649) (xy 299.747482 -52.873558)
			(xy 299.774778 -52.824923) (xy 299.808864 -52.78078) (xy 299.849013 -52.742071) (xy 299.894371 -52.70962)
			(xy 299.943971 -52.684119) (xy 299.996755 -52.666112) (xy 300.051598 -52.655982) (xy 300.107332 -52.653945)
			(xy 300.162769 -52.660045) (xy 300.216726 -52.674151) (xy 300.268055 -52.695963) (xy 300.315661 -52.725017)
			(xy 300.358529 -52.760692) (xy 300.395746 -52.802229) (xy 300.426519 -52.848742) (xy 300.450191 -52.899239)
			(xy 300.466259 -52.952646) (xy 300.474379 -53.007822) (xy 300.474888 -53.035708) (xy 300.474379 -53.063594)
			(xy 300.466259 -53.11877) (xy 300.450191 -53.172177) (xy 300.426519 -53.222674) (xy 300.395746 -53.269187)
			(xy 300.358529 -53.310724) (xy 300.315661 -53.346399) (xy 300.268055 -53.375453) (xy 300.216726 -53.397265)
			(xy 300.162769 -53.411371) (xy 300.107332 -53.417471) (xy 300.051598 -53.415434) (xy 299.996755 -53.405304)
			(xy 299.943971 -53.387297) (xy 299.894371 -53.361796) (xy 299.849013 -53.329345) (xy 299.808864 -53.290636)
			(xy 299.774778 -53.246493) (xy 299.747482 -53.197858) (xy 299.727559 -53.145767) (xy 299.715433 -53.09133)
			(xy 299.711362 -53.035708) (xy 298.061811 -53.035708) (xy 298.082385 -53.044451) (xy 298.129991 -53.073505)
			(xy 298.172859 -53.10918) (xy 298.210076 -53.150717) (xy 298.240849 -53.19723) (xy 298.264521 -53.247727)
			(xy 298.280589 -53.301134) (xy 298.288709 -53.35631) (xy 298.289218 -53.384196) (xy 298.288709 -53.412082)
			(xy 298.280589 -53.467258) (xy 298.276693 -53.480208) (xy 310.305702 -53.480208) (xy 310.309773 -53.424586)
			(xy 310.321899 -53.370149) (xy 310.341822 -53.318058) (xy 310.369118 -53.269423) (xy 310.403204 -53.22528)
			(xy 310.443353 -53.186571) (xy 310.488711 -53.15412) (xy 310.538311 -53.128619) (xy 310.591095 -53.110612)
			(xy 310.645938 -53.100482) (xy 310.701672 -53.098445) (xy 310.757109 -53.104545) (xy 310.811066 -53.118651)
			(xy 310.862395 -53.140463) (xy 310.910001 -53.169517) (xy 310.952869 -53.205192) (xy 310.990086 -53.246729)
			(xy 311.020859 -53.293242) (xy 311.026347 -53.304948) (xy 312.474862 -53.304948) (xy 312.478933 -53.249326)
			(xy 312.491059 -53.194889) (xy 312.510982 -53.142798) (xy 312.538278 -53.094163) (xy 312.572364 -53.05002)
			(xy 312.612513 -53.011311) (xy 312.657871 -52.97886) (xy 312.707471 -52.953359) (xy 312.760255 -52.935352)
			(xy 312.815098 -52.925222) (xy 312.870832 -52.923185) (xy 312.926269 -52.929285) (xy 312.980226 -52.943391)
			(xy 313.031555 -52.965203) (xy 313.079161 -52.994257) (xy 313.122029 -53.029932) (xy 313.159246 -53.071469)
			(xy 313.190019 -53.117982) (xy 313.213691 -53.168479) (xy 313.229759 -53.221886) (xy 313.230769 -53.228748)
			(xy 313.712604 -53.228748) (xy 313.716675 -53.173126) (xy 313.728801 -53.118689) (xy 313.748724 -53.066598)
			(xy 313.77602 -53.017963) (xy 313.810106 -52.97382) (xy 313.850255 -52.935111) (xy 313.895613 -52.90266)
			(xy 313.945213 -52.877159) (xy 313.997997 -52.859152) (xy 314.05284 -52.849022) (xy 314.108574 -52.846985)
			(xy 314.164011 -52.853085) (xy 314.217968 -52.867191) (xy 314.269297 -52.889003) (xy 314.316903 -52.918057)
			(xy 314.359771 -52.953732) (xy 314.396988 -52.995269) (xy 314.427761 -53.041782) (xy 314.451433 -53.092279)
			(xy 314.467501 -53.145686) (xy 314.475621 -53.200862) (xy 314.47613 -53.228748) (xy 314.476102 -53.230272)
			(xy 318.543684 -53.230272) (xy 318.547755 -53.17465) (xy 318.559881 -53.120213) (xy 318.579804 -53.068122)
			(xy 318.6071 -53.019487) (xy 318.641186 -52.975344) (xy 318.681335 -52.936635) (xy 318.726693 -52.904184)
			(xy 318.776293 -52.878683) (xy 318.829077 -52.860676) (xy 318.88392 -52.850546) (xy 318.939654 -52.848509)
			(xy 318.995091 -52.854609) (xy 319.049048 -52.868715) (xy 319.100377 -52.890527) (xy 319.147983 -52.919581)
			(xy 319.190851 -52.955256) (xy 319.228068 -52.996793) (xy 319.258841 -53.043306) (xy 319.282513 -53.093803)
			(xy 319.298581 -53.14721) (xy 319.306701 -53.202386) (xy 319.30721 -53.230272) (xy 319.306701 -53.258158)
			(xy 319.301834 -53.291232) (xy 319.582544 -53.291232) (xy 319.586615 -53.23561) (xy 319.598741 -53.181173)
			(xy 319.618664 -53.129082) (xy 319.64596 -53.080447) (xy 319.680046 -53.036304) (xy 319.720195 -52.997595)
			(xy 319.765553 -52.965144) (xy 319.815153 -52.939643) (xy 319.867937 -52.921636) (xy 319.92278 -52.911506)
			(xy 319.978514 -52.909469) (xy 320.033951 -52.915569) (xy 320.087908 -52.929675) (xy 320.139237 -52.951487)
			(xy 320.172116 -52.971553) (xy 320.981546 -52.971553) (xy 320.981546 -52.917047) (xy 320.989302 -52.863097)
			(xy 321.004658 -52.8108) (xy 321.027299 -52.76122) (xy 321.056766 -52.715367) (xy 321.092458 -52.674174)
			(xy 321.133649 -52.638479) (xy 321.179501 -52.60901) (xy 321.229079 -52.586365) (xy 321.281376 -52.571007)
			(xy 321.335325 -52.563247) (xy 321.362578 -52.56276) (xy 321.389817 -52.563238) (xy 321.44374 -52.571004)
			(xy 321.496008 -52.586367) (xy 321.545557 -52.609013) (xy 321.591377 -52.638482) (xy 321.61226 -52.655978)
			(xy 321.624074 -52.665373) (xy 321.651661 -52.677572) (xy 321.681606 -52.681197) (xy 321.711307 -52.675936)
			(xy 321.738184 -52.662244) (xy 321.74942 -52.652168) (xy 321.770884 -52.632219) (xy 321.818785 -52.598471)
			(xy 321.871281 -52.57244) (xy 321.927138 -52.554735) (xy 321.985044 -52.545773) (xy 322.014342 -52.545234)
			(xy 322.041594 -52.545639) (xy 322.095543 -52.553401) (xy 322.147839 -52.568761) (xy 322.197416 -52.591407)
			(xy 322.243266 -52.620878) (xy 322.284456 -52.656574) (xy 322.320147 -52.697767) (xy 322.325009 -52.705333)
			(xy 329.92238 -52.705333) (xy 329.92238 -52.653359) (xy 329.93051 -52.602024) (xy 329.946571 -52.552594)
			(xy 329.970167 -52.506284) (xy 330.000717 -52.464236) (xy 330.037468 -52.427485) (xy 330.079516 -52.396935)
			(xy 330.125826 -52.373339) (xy 330.175256 -52.357278) (xy 330.226591 -52.349148) (xy 330.278565 -52.349148)
			(xy 330.3299 -52.357278) (xy 330.37933 -52.373339) (xy 330.42564 -52.396935) (xy 330.467688 -52.427485)
			(xy 330.504439 -52.464236) (xy 330.534989 -52.506284) (xy 330.558585 -52.552594) (xy 330.574646 -52.602024)
			(xy 330.582776 -52.653359) (xy 330.583286 -52.679346) (xy 330.582776 -52.705333) (xy 330.574646 -52.756668)
			(xy 330.558585 -52.806098) (xy 330.534989 -52.852408) (xy 330.504439 -52.894456) (xy 330.467688 -52.931207)
			(xy 330.42564 -52.961757) (xy 330.37933 -52.985353) (xy 330.3299 -53.001414) (xy 330.278565 -53.009544)
			(xy 330.226591 -53.009544) (xy 330.175256 -53.001414) (xy 330.125826 -52.985353) (xy 330.079516 -52.961757)
			(xy 330.037468 -52.931207) (xy 330.000717 -52.894456) (xy 329.970167 -52.852408) (xy 329.946571 -52.806098)
			(xy 329.93051 -52.756668) (xy 329.92238 -52.705333) (xy 322.325009 -52.705333) (xy 322.349613 -52.743621)
			(xy 322.372253 -52.793201) (xy 322.387608 -52.845498) (xy 322.395364 -52.899448) (xy 322.395364 -52.953952)
			(xy 322.387608 -53.007902) (xy 322.372253 -53.060199) (xy 322.349613 -53.109779) (xy 322.320147 -53.155633)
			(xy 322.284456 -53.196826) (xy 322.243266 -53.232522) (xy 322.235307 -53.237638) (xy 323.65264 -53.237638)
			(xy 323.656711 -53.182016) (xy 323.668837 -53.127579) (xy 323.68876 -53.075488) (xy 323.716056 -53.026853)
			(xy 323.750142 -52.98271) (xy 323.790291 -52.944001) (xy 323.835649 -52.91155) (xy 323.885249 -52.886049)
			(xy 323.938033 -52.868042) (xy 323.992876 -52.857912) (xy 324.04861 -52.855875) (xy 324.104047 -52.861975)
			(xy 324.158004 -52.876081) (xy 324.209333 -52.897893) (xy 324.256939 -52.926947) (xy 324.299807 -52.962622)
			(xy 324.337024 -53.004159) (xy 324.367797 -53.050672) (xy 324.391469 -53.101169) (xy 324.407537 -53.154576)
			(xy 324.410577 -53.175233) (xy 329.107548 -53.175233) (xy 329.107548 -53.123259) (xy 329.115678 -53.071924)
			(xy 329.131739 -53.022494) (xy 329.155335 -52.976184) (xy 329.185885 -52.934136) (xy 329.222636 -52.897385)
			(xy 329.264684 -52.866835) (xy 329.310994 -52.843239) (xy 329.360424 -52.827178) (xy 329.411759 -52.819048)
			(xy 329.463733 -52.819048) (xy 329.515068 -52.827178) (xy 329.564498 -52.843239) (xy 329.610808 -52.866835)
			(xy 329.652856 -52.897385) (xy 329.689607 -52.934136) (xy 329.720157 -52.976184) (xy 329.743753 -53.022494)
			(xy 329.759814 -53.071924) (xy 329.767944 -53.123259) (xy 329.768454 -53.149246) (xy 329.767944 -53.175233)
			(xy 330.73899 -53.175233) (xy 330.73899 -53.123259) (xy 330.74712 -53.071924) (xy 330.763181 -53.022494)
			(xy 330.786777 -52.976184) (xy 330.817327 -52.934136) (xy 330.854078 -52.897385) (xy 330.896126 -52.866835)
			(xy 330.942436 -52.843239) (xy 330.991866 -52.827178) (xy 331.043201 -52.819048) (xy 331.095175 -52.819048)
			(xy 331.14651 -52.827178) (xy 331.19594 -52.843239) (xy 331.24225 -52.866835) (xy 331.284298 -52.897385)
			(xy 331.321049 -52.934136) (xy 331.351599 -52.976184) (xy 331.375195 -53.022494) (xy 331.391256 -53.071924)
			(xy 331.399386 -53.123259) (xy 331.399896 -53.149246) (xy 331.399386 -53.175233) (xy 331.391256 -53.226568)
			(xy 331.375195 -53.275998) (xy 331.351599 -53.322308) (xy 331.321049 -53.364356) (xy 331.284298 -53.401107)
			(xy 331.24225 -53.431657) (xy 331.19594 -53.455253) (xy 331.14651 -53.471314) (xy 331.095175 -53.479444)
			(xy 331.043201 -53.479444) (xy 330.991866 -53.471314) (xy 330.942436 -53.455253) (xy 330.896126 -53.431657)
			(xy 330.854078 -53.401107) (xy 330.817327 -53.364356) (xy 330.786777 -53.322308) (xy 330.763181 -53.275998)
			(xy 330.74712 -53.226568) (xy 330.73899 -53.175233) (xy 329.767944 -53.175233) (xy 329.759814 -53.226568)
			(xy 329.743753 -53.275998) (xy 329.720157 -53.322308) (xy 329.689607 -53.364356) (xy 329.652856 -53.401107)
			(xy 329.610808 -53.431657) (xy 329.564498 -53.455253) (xy 329.515068 -53.471314) (xy 329.463733 -53.479444)
			(xy 329.411759 -53.479444) (xy 329.360424 -53.471314) (xy 329.310994 -53.455253) (xy 329.264684 -53.431657)
			(xy 329.222636 -53.401107) (xy 329.185885 -53.364356) (xy 329.155335 -53.322308) (xy 329.131739 -53.275998)
			(xy 329.115678 -53.226568) (xy 329.107548 -53.175233) (xy 324.410577 -53.175233) (xy 324.415657 -53.209752)
			(xy 324.416166 -53.237638) (xy 324.415657 -53.265524) (xy 324.407537 -53.3207) (xy 324.391469 -53.374107)
			(xy 324.367797 -53.424604) (xy 324.337024 -53.471117) (xy 324.299807 -53.512654) (xy 324.256939 -53.548329)
			(xy 324.209333 -53.577383) (xy 324.158004 -53.599195) (xy 324.104047 -53.613301) (xy 324.04861 -53.619401)
			(xy 323.992876 -53.617364) (xy 323.938033 -53.607234) (xy 323.885249 -53.589227) (xy 323.835649 -53.563726)
			(xy 323.790291 -53.531275) (xy 323.750142 -53.492566) (xy 323.716056 -53.448423) (xy 323.68876 -53.399788)
			(xy 323.668837 -53.347697) (xy 323.656711 -53.29326) (xy 323.65264 -53.237638) (xy 322.235307 -53.237638)
			(xy 322.197416 -53.261993) (xy 322.147839 -53.284639) (xy 322.095543 -53.299999) (xy 322.041594 -53.307761)
			(xy 322.014342 -53.30825) (xy 321.987103 -53.307758) (xy 321.933181 -53.299995) (xy 321.880914 -53.284635)
			(xy 321.831365 -53.261992) (xy 321.785543 -53.232526) (xy 321.76466 -53.215032) (xy 321.752906 -53.205556)
			(xy 321.725297 -53.193366) (xy 321.695333 -53.189755) (xy 321.665619 -53.195038) (xy 321.638735 -53.208754)
			(xy 321.6275 -53.218842) (xy 321.60603 -53.238784) (xy 321.55813 -53.272532) (xy 321.505636 -53.298565)
			(xy 321.44978 -53.316272) (xy 321.391875 -53.325236) (xy 321.362578 -53.325776) (xy 321.335325 -53.325353)
			(xy 321.281376 -53.317593) (xy 321.229079 -53.302235) (xy 321.179501 -53.27959) (xy 321.133649 -53.250121)
			(xy 321.092458 -53.214426) (xy 321.056766 -53.173233) (xy 321.027299 -53.12738) (xy 321.004658 -53.0778)
			(xy 320.989302 -53.025503) (xy 320.981546 -52.971553) (xy 320.172116 -52.971553) (xy 320.186843 -52.980541)
			(xy 320.229711 -53.016216) (xy 320.266928 -53.057753) (xy 320.297701 -53.104266) (xy 320.321373 -53.154763)
			(xy 320.337441 -53.20817) (xy 320.345561 -53.263346) (xy 320.34607 -53.291232) (xy 320.345561 -53.319118)
			(xy 320.337441 -53.374294) (xy 320.321373 -53.427701) (xy 320.297701 -53.478198) (xy 320.266928 -53.524711)
			(xy 320.229711 -53.566248) (xy 320.186843 -53.601923) (xy 320.139237 -53.630977) (xy 320.105924 -53.645133)
			(xy 328.296272 -53.645133) (xy 328.296272 -53.593159) (xy 328.304402 -53.541824) (xy 328.320463 -53.492394)
			(xy 328.344059 -53.446084) (xy 328.374609 -53.404036) (xy 328.41136 -53.367285) (xy 328.453408 -53.336735)
			(xy 328.499718 -53.313139) (xy 328.549148 -53.297078) (xy 328.600483 -53.288948) (xy 328.652457 -53.288948)
			(xy 328.703792 -53.297078) (xy 328.753222 -53.313139) (xy 328.799532 -53.336735) (xy 328.84158 -53.367285)
			(xy 328.878331 -53.404036) (xy 328.908881 -53.446084) (xy 328.932477 -53.492394) (xy 328.948538 -53.541824)
			(xy 328.956668 -53.593159) (xy 328.957178 -53.619146) (xy 328.956668 -53.645133) (xy 329.92238 -53.645133)
			(xy 329.92238 -53.593159) (xy 329.93051 -53.541824) (xy 329.946571 -53.492394) (xy 329.970167 -53.446084)
			(xy 330.000717 -53.404036) (xy 330.037468 -53.367285) (xy 330.079516 -53.336735) (xy 330.125826 -53.313139)
			(xy 330.175256 -53.297078) (xy 330.226591 -53.288948) (xy 330.278565 -53.288948) (xy 330.3299 -53.297078)
			(xy 330.37933 -53.313139) (xy 330.42564 -53.336735) (xy 330.467688 -53.367285) (xy 330.504439 -53.404036)
			(xy 330.534989 -53.446084) (xy 330.558585 -53.492394) (xy 330.574646 -53.541824) (xy 330.582776 -53.593159)
			(xy 330.583286 -53.619146) (xy 330.582776 -53.645133) (xy 330.574646 -53.696468) (xy 330.558585 -53.745898)
			(xy 330.534989 -53.792208) (xy 330.504439 -53.834256) (xy 330.467688 -53.871007) (xy 330.42564 -53.901557)
			(xy 330.37933 -53.925153) (xy 330.3299 -53.941214) (xy 330.278565 -53.949344) (xy 330.226591 -53.949344)
			(xy 330.175256 -53.941214) (xy 330.125826 -53.925153) (xy 330.079516 -53.901557) (xy 330.037468 -53.871007)
			(xy 330.000717 -53.834256) (xy 329.970167 -53.792208) (xy 329.946571 -53.745898) (xy 329.93051 -53.696468)
			(xy 329.92238 -53.645133) (xy 328.956668 -53.645133) (xy 328.948538 -53.696468) (xy 328.932477 -53.745898)
			(xy 328.908881 -53.792208) (xy 328.878331 -53.834256) (xy 328.84158 -53.871007) (xy 328.799532 -53.901557)
			(xy 328.753222 -53.925153) (xy 328.703792 -53.941214) (xy 328.652457 -53.949344) (xy 328.600483 -53.949344)
			(xy 328.549148 -53.941214) (xy 328.499718 -53.925153) (xy 328.453408 -53.901557) (xy 328.41136 -53.871007)
			(xy 328.374609 -53.834256) (xy 328.344059 -53.792208) (xy 328.320463 -53.745898) (xy 328.304402 -53.696468)
			(xy 328.296272 -53.645133) (xy 320.105924 -53.645133) (xy 320.087908 -53.652789) (xy 320.033951 -53.666895)
			(xy 319.978514 -53.672995) (xy 319.92278 -53.670958) (xy 319.867937 -53.660828) (xy 319.815153 -53.642821)
			(xy 319.765553 -53.61732) (xy 319.720195 -53.584869) (xy 319.680046 -53.54616) (xy 319.64596 -53.502017)
			(xy 319.618664 -53.453382) (xy 319.598741 -53.401291) (xy 319.586615 -53.346854) (xy 319.582544 -53.291232)
			(xy 319.301834 -53.291232) (xy 319.298581 -53.313334) (xy 319.282513 -53.366741) (xy 319.258841 -53.417238)
			(xy 319.228068 -53.463751) (xy 319.190851 -53.505288) (xy 319.147983 -53.540963) (xy 319.100377 -53.570017)
			(xy 319.049048 -53.591829) (xy 318.995091 -53.605935) (xy 318.939654 -53.612035) (xy 318.88392 -53.609998)
			(xy 318.829077 -53.599868) (xy 318.776293 -53.581861) (xy 318.726693 -53.55636) (xy 318.681335 -53.523909)
			(xy 318.641186 -53.4852) (xy 318.6071 -53.441057) (xy 318.579804 -53.392422) (xy 318.559881 -53.340331)
			(xy 318.547755 -53.285894) (xy 318.543684 -53.230272) (xy 314.476102 -53.230272) (xy 314.475621 -53.256634)
			(xy 314.467501 -53.31181) (xy 314.451433 -53.365217) (xy 314.427761 -53.415714) (xy 314.396988 -53.462227)
			(xy 314.359771 -53.503764) (xy 314.316903 -53.539439) (xy 314.269297 -53.568493) (xy 314.217968 -53.590305)
			(xy 314.164011 -53.604411) (xy 314.108574 -53.610511) (xy 314.05284 -53.608474) (xy 313.997997 -53.598344)
			(xy 313.945213 -53.580337) (xy 313.895613 -53.554836) (xy 313.850255 -53.522385) (xy 313.810106 -53.483676)
			(xy 313.77602 -53.439533) (xy 313.748724 -53.390898) (xy 313.728801 -53.338807) (xy 313.716675 -53.28437)
			(xy 313.712604 -53.228748) (xy 313.230769 -53.228748) (xy 313.237879 -53.277062) (xy 313.238388 -53.304948)
			(xy 313.237879 -53.332834) (xy 313.229759 -53.38801) (xy 313.213691 -53.441417) (xy 313.190019 -53.491914)
			(xy 313.159246 -53.538427) (xy 313.122029 -53.579964) (xy 313.079161 -53.615639) (xy 313.031555 -53.644693)
			(xy 312.980226 -53.666505) (xy 312.926269 -53.680611) (xy 312.870832 -53.686711) (xy 312.815098 -53.684674)
			(xy 312.760255 -53.674544) (xy 312.707471 -53.656537) (xy 312.657871 -53.631036) (xy 312.612513 -53.598585)
			(xy 312.572364 -53.559876) (xy 312.538278 -53.515733) (xy 312.510982 -53.467098) (xy 312.491059 -53.415007)
			(xy 312.478933 -53.36057) (xy 312.474862 -53.304948) (xy 311.026347 -53.304948) (xy 311.044531 -53.343739)
			(xy 311.060599 -53.397146) (xy 311.068719 -53.452322) (xy 311.069228 -53.480208) (xy 311.068719 -53.508094)
			(xy 311.060599 -53.56327) (xy 311.044531 -53.616677) (xy 311.020859 -53.667174) (xy 310.990086 -53.713687)
			(xy 310.952869 -53.755224) (xy 310.914028 -53.787548) (xy 315.998604 -53.787548) (xy 316.002675 -53.731926)
			(xy 316.014801 -53.677489) (xy 316.034724 -53.625398) (xy 316.06202 -53.576763) (xy 316.096106 -53.53262)
			(xy 316.136255 -53.493911) (xy 316.181613 -53.46146) (xy 316.231213 -53.435959) (xy 316.283997 -53.417952)
			(xy 316.33884 -53.407822) (xy 316.394574 -53.405785) (xy 316.450011 -53.411885) (xy 316.503968 -53.425991)
			(xy 316.555297 -53.447803) (xy 316.602903 -53.476857) (xy 316.645771 -53.512532) (xy 316.682988 -53.554069)
			(xy 316.713761 -53.600582) (xy 316.737433 -53.651079) (xy 316.753501 -53.704486) (xy 316.761621 -53.759662)
			(xy 316.76213 -53.787548) (xy 316.761621 -53.815434) (xy 316.753501 -53.87061) (xy 316.737433 -53.924017)
			(xy 316.713761 -53.974514) (xy 316.682988 -54.021027) (xy 316.645771 -54.062564) (xy 316.602903 -54.098239)
			(xy 316.555297 -54.127293) (xy 316.503968 -54.149105) (xy 316.450011 -54.163211) (xy 316.394574 -54.169311)
			(xy 316.33884 -54.167274) (xy 316.283997 -54.157144) (xy 316.231213 -54.139137) (xy 316.181613 -54.113636)
			(xy 316.136255 -54.081185) (xy 316.096106 -54.042476) (xy 316.06202 -53.998333) (xy 316.034724 -53.949698)
			(xy 316.014801 -53.897607) (xy 316.002675 -53.84317) (xy 315.998604 -53.787548) (xy 310.914028 -53.787548)
			(xy 310.910001 -53.790899) (xy 310.862395 -53.819953) (xy 310.811066 -53.841765) (xy 310.757109 -53.855871)
			(xy 310.701672 -53.861971) (xy 310.645938 -53.859934) (xy 310.591095 -53.849804) (xy 310.538311 -53.831797)
			(xy 310.488711 -53.806296) (xy 310.443353 -53.773845) (xy 310.403204 -53.735136) (xy 310.369118 -53.690993)
			(xy 310.341822 -53.642358) (xy 310.321899 -53.590267) (xy 310.309773 -53.53583) (xy 310.305702 -53.480208)
			(xy 298.276693 -53.480208) (xy 298.264521 -53.520665) (xy 298.240849 -53.571162) (xy 298.210076 -53.617675)
			(xy 298.172859 -53.659212) (xy 298.129991 -53.694887) (xy 298.082385 -53.723941) (xy 298.031056 -53.745753)
			(xy 297.977099 -53.759859) (xy 297.921662 -53.765959) (xy 297.865928 -53.763922) (xy 297.811085 -53.753792)
			(xy 297.758301 -53.735785) (xy 297.708701 -53.710284) (xy 297.663343 -53.677833) (xy 297.623194 -53.639124)
			(xy 297.589108 -53.594981) (xy 297.561812 -53.546346) (xy 297.541889 -53.494255) (xy 297.529763 -53.439818)
			(xy 297.525692 -53.384196) (xy 284.31406 -53.384196) (xy 284.270119 -53.411013) (xy 284.21879 -53.432825)
			(xy 284.164833 -53.446931) (xy 284.109396 -53.453031) (xy 284.053662 -53.450994) (xy 283.998819 -53.440864)
			(xy 283.946035 -53.422857) (xy 283.896435 -53.397356) (xy 283.851077 -53.364905) (xy 283.810928 -53.326196)
			(xy 283.776842 -53.282053) (xy 283.749546 -53.233418) (xy 283.729623 -53.181327) (xy 283.717497 -53.12689)
			(xy 283.713426 -53.071268) (xy 282.38704 -53.071268) (xy 282.38704 -54.287674) (xy 291.411912 -54.287674)
			(xy 291.415983 -54.232052) (xy 291.428109 -54.177615) (xy 291.448032 -54.125524) (xy 291.475328 -54.076889)
			(xy 291.509414 -54.032746) (xy 291.549563 -53.994037) (xy 291.594921 -53.961586) (xy 291.644521 -53.936085)
			(xy 291.697305 -53.918078) (xy 291.752148 -53.907948) (xy 291.807882 -53.905911) (xy 291.863319 -53.912011)
			(xy 291.917276 -53.926117) (xy 291.968605 -53.947929) (xy 292.016211 -53.976983) (xy 292.059079 -54.012658)
			(xy 292.096296 -54.054195) (xy 292.127069 -54.100708) (xy 292.150741 -54.151205) (xy 292.166809 -54.204612)
			(xy 292.174929 -54.259788) (xy 292.175438 -54.287674) (xy 292.174929 -54.31556) (xy 292.173837 -54.32298)
			(xy 294.418002 -54.32298) (xy 294.422073 -54.267358) (xy 294.434199 -54.212921) (xy 294.454122 -54.16083)
			(xy 294.481418 -54.112195) (xy 294.515504 -54.068052) (xy 294.555653 -54.029343) (xy 294.601011 -53.996892)
			(xy 294.650611 -53.971391) (xy 294.703395 -53.953384) (xy 294.758238 -53.943254) (xy 294.813972 -53.941217)
			(xy 294.869409 -53.947317) (xy 294.923366 -53.961423) (xy 294.974695 -53.983235) (xy 295.022301 -54.012289)
			(xy 295.022665 -54.012592) (xy 304.662584 -54.012592) (xy 304.666655 -53.95697) (xy 304.678781 -53.902533)
			(xy 304.698704 -53.850442) (xy 304.726 -53.801807) (xy 304.760086 -53.757664) (xy 304.800235 -53.718955)
			(xy 304.845593 -53.686504) (xy 304.895193 -53.661003) (xy 304.947977 -53.642996) (xy 305.00282 -53.632866)
			(xy 305.058554 -53.630829) (xy 305.113991 -53.636929) (xy 305.167948 -53.651035) (xy 305.219277 -53.672847)
			(xy 305.266883 -53.701901) (xy 305.309751 -53.737576) (xy 305.346968 -53.779113) (xy 305.377741 -53.825626)
			(xy 305.401413 -53.876123) (xy 305.417481 -53.92953) (xy 305.425601 -53.984706) (xy 305.42611 -54.012592)
			(xy 305.425601 -54.040478) (xy 305.417481 -54.095654) (xy 305.401413 -54.149061) (xy 305.386324 -54.181248)
			(xy 309.259222 -54.181248) (xy 309.263293 -54.125626) (xy 309.275419 -54.071189) (xy 309.295342 -54.019098)
			(xy 309.322638 -53.970463) (xy 309.356724 -53.92632) (xy 309.396873 -53.887611) (xy 309.442231 -53.85516)
			(xy 309.491831 -53.829659) (xy 309.544615 -53.811652) (xy 309.599458 -53.801522) (xy 309.655192 -53.799485)
			(xy 309.710629 -53.805585) (xy 309.764586 -53.819691) (xy 309.815915 -53.841503) (xy 309.863521 -53.870557)
			(xy 309.906389 -53.906232) (xy 309.943606 -53.947769) (xy 309.974379 -53.994282) (xy 309.998051 -54.044779)
			(xy 310.014119 -54.098186) (xy 310.022239 -54.153362) (xy 310.022748 -54.181248) (xy 310.022239 -54.209134)
			(xy 310.014119 -54.26431) (xy 309.998051 -54.317717) (xy 309.974379 -54.368214) (xy 309.943606 -54.414727)
			(xy 309.906389 -54.456264) (xy 309.863521 -54.491939) (xy 309.815915 -54.520993) (xy 309.79812 -54.528555)
			(xy 312.999043 -54.528555) (xy 312.999043 -54.474045) (xy 313.006801 -54.420091) (xy 313.022158 -54.36779)
			(xy 313.044803 -54.318207) (xy 313.074274 -54.272351) (xy 313.109971 -54.231157) (xy 313.151167 -54.195462)
			(xy 313.197024 -54.165993) (xy 313.246609 -54.143351) (xy 313.29891 -54.127996) (xy 313.352865 -54.120242)
			(xy 313.38012 -54.11978) (xy 313.412271 -54.120429) (xy 313.475661 -54.131231) (xy 313.536335 -54.152526)
			(xy 313.564778 -54.167532) (xy 313.578231 -54.17444) (xy 313.60781 -54.180693) (xy 313.637922 -54.178008)
			(xy 313.665927 -54.16662) (xy 313.689369 -54.147529) (xy 313.70619 -54.122409) (xy 313.711082 -54.108096)
			(xy 313.719404 -54.082369) (xy 313.74233 -54.033397) (xy 313.771938 -53.988152) (xy 313.807635 -53.947538)
			(xy 313.848708 -53.912369) (xy 313.894333 -53.883349) (xy 313.943597 -53.86106) (xy 313.995514 -53.845946)
			(xy 314.049044 -53.838311) (xy 314.07608 -53.83784) (xy 314.103337 -53.838206) (xy 314.157297 -53.845961)
			(xy 314.209604 -53.861317) (xy 314.259193 -53.883962) (xy 314.305054 -53.913433) (xy 314.346255 -53.949131)
			(xy 314.381955 -53.99033) (xy 314.411429 -54.036189) (xy 314.434076 -54.085777) (xy 314.449435 -54.138083)
			(xy 314.457193 -54.192043) (xy 314.457193 -54.246557) (xy 314.449435 -54.300517) (xy 314.435977 -54.346348)
			(xy 322.983604 -54.346348) (xy 322.987675 -54.290726) (xy 322.999801 -54.236289) (xy 323.019724 -54.184198)
			(xy 323.04702 -54.135563) (xy 323.081106 -54.09142) (xy 323.121255 -54.052711) (xy 323.166613 -54.02026)
			(xy 323.216213 -53.994759) (xy 323.268997 -53.976752) (xy 323.32384 -53.966622) (xy 323.379574 -53.964585)
			(xy 323.435011 -53.970685) (xy 323.488968 -53.984791) (xy 323.540297 -54.006603) (xy 323.580908 -54.031388)
			(xy 325.399156 -54.031388) (xy 325.403132 -53.977062) (xy 325.414975 -53.923893) (xy 325.434434 -53.873016)
			(xy 325.461094 -53.825514) (xy 325.494385 -53.7824) (xy 325.533599 -53.744593) (xy 325.577901 -53.712898)
			(xy 325.626344 -53.687992) (xy 325.677898 -53.670404) (xy 325.731464 -53.66051) (xy 325.785899 -53.65852)
			(xy 325.840044 -53.664478) (xy 325.892744 -53.678256) (xy 325.942877 -53.69956) (xy 325.989373 -53.727936)
			(xy 326.031243 -53.76278) (xy 326.067592 -53.803349) (xy 326.097648 -53.848778) (xy 326.120769 -53.898099)
			(xy 326.136462 -53.950261) (xy 326.144393 -54.004152) (xy 326.14489 -54.031388) (xy 326.144393 -54.058624)
			(xy 326.136462 -54.112515) (xy 326.135704 -54.115033) (xy 329.107548 -54.115033) (xy 329.107548 -54.063059)
			(xy 329.115678 -54.011724) (xy 329.131739 -53.962294) (xy 329.155335 -53.915984) (xy 329.185885 -53.873936)
			(xy 329.222636 -53.837185) (xy 329.264684 -53.806635) (xy 329.310994 -53.783039) (xy 329.360424 -53.766978)
			(xy 329.411759 -53.758848) (xy 329.463733 -53.758848) (xy 329.515068 -53.766978) (xy 329.564498 -53.783039)
			(xy 329.610808 -53.806635) (xy 329.652856 -53.837185) (xy 329.689607 -53.873936) (xy 329.720157 -53.915984)
			(xy 329.743753 -53.962294) (xy 329.759814 -54.011724) (xy 329.767944 -54.063059) (xy 329.768454 -54.089046)
			(xy 329.767944 -54.115033) (xy 330.73772 -54.115033) (xy 330.73772 -54.063059) (xy 330.74585 -54.011724)
			(xy 330.761911 -53.962294) (xy 330.785507 -53.915984) (xy 330.816057 -53.873936) (xy 330.852808 -53.837185)
			(xy 330.894856 -53.806635) (xy 330.941166 -53.783039) (xy 330.990596 -53.766978) (xy 331.041931 -53.758848)
			(xy 331.093905 -53.758848) (xy 331.14524 -53.766978) (xy 331.19467 -53.783039) (xy 331.24098 -53.806635)
			(xy 331.283028 -53.837185) (xy 331.319779 -53.873936) (xy 331.350329 -53.915984) (xy 331.373925 -53.962294)
			(xy 331.389986 -54.011724) (xy 331.398116 -54.063059) (xy 331.398626 -54.089046) (xy 331.398116 -54.115033)
			(xy 331.389986 -54.166368) (xy 331.373925 -54.215798) (xy 331.350329 -54.262108) (xy 331.319779 -54.304156)
			(xy 331.283028 -54.340907) (xy 331.24098 -54.371457) (xy 331.19467 -54.395053) (xy 331.14524 -54.411114)
			(xy 331.093905 -54.419244) (xy 331.041931 -54.419244) (xy 330.990596 -54.411114) (xy 330.941166 -54.395053)
			(xy 330.894856 -54.371457) (xy 330.852808 -54.340907) (xy 330.816057 -54.304156) (xy 330.785507 -54.262108)
			(xy 330.761911 -54.215798) (xy 330.74585 -54.166368) (xy 330.73772 -54.115033) (xy 329.767944 -54.115033)
			(xy 329.759814 -54.166368) (xy 329.743753 -54.215798) (xy 329.720157 -54.262108) (xy 329.689607 -54.304156)
			(xy 329.652856 -54.340907) (xy 329.610808 -54.371457) (xy 329.564498 -54.395053) (xy 329.515068 -54.411114)
			(xy 329.463733 -54.419244) (xy 329.411759 -54.419244) (xy 329.360424 -54.411114) (xy 329.310994 -54.395053)
			(xy 329.264684 -54.371457) (xy 329.222636 -54.340907) (xy 329.185885 -54.304156) (xy 329.155335 -54.262108)
			(xy 329.131739 -54.215798) (xy 329.115678 -54.166368) (xy 329.107548 -54.115033) (xy 326.135704 -54.115033)
			(xy 326.120769 -54.164677) (xy 326.097648 -54.213998) (xy 326.067592 -54.259427) (xy 326.031243 -54.299996)
			(xy 325.989373 -54.33484) (xy 325.942877 -54.363216) (xy 325.892744 -54.38452) (xy 325.840044 -54.398298)
			(xy 325.785899 -54.404256) (xy 325.731464 -54.402266) (xy 325.677898 -54.392372) (xy 325.626344 -54.374784)
			(xy 325.577901 -54.349878) (xy 325.533599 -54.318183) (xy 325.494385 -54.280376) (xy 325.461094 -54.237262)
			(xy 325.434434 -54.18976) (xy 325.414975 -54.138883) (xy 325.403132 -54.085714) (xy 325.399156 -54.031388)
			(xy 323.580908 -54.031388) (xy 323.587903 -54.035657) (xy 323.630771 -54.071332) (xy 323.667988 -54.112869)
			(xy 323.698761 -54.159382) (xy 323.722433 -54.209879) (xy 323.738501 -54.263286) (xy 323.746621 -54.318462)
			(xy 323.74713 -54.346348) (xy 323.746621 -54.374234) (xy 323.738501 -54.42941) (xy 323.722433 -54.482817)
			(xy 323.698761 -54.533314) (xy 323.667988 -54.579827) (xy 323.663413 -54.584933) (xy 328.29678 -54.584933)
			(xy 328.29678 -54.532959) (xy 328.30491 -54.481624) (xy 328.320971 -54.432194) (xy 328.344567 -54.385884)
			(xy 328.375117 -54.343836) (xy 328.411868 -54.307085) (xy 328.453916 -54.276535) (xy 328.500226 -54.252939)
			(xy 328.549656 -54.236878) (xy 328.600991 -54.228748) (xy 328.652965 -54.228748) (xy 328.7043 -54.236878)
			(xy 328.75373 -54.252939) (xy 328.80004 -54.276535) (xy 328.842088 -54.307085) (xy 328.878839 -54.343836)
			(xy 328.909389 -54.385884) (xy 328.932985 -54.432194) (xy 328.949046 -54.481624) (xy 328.957176 -54.532959)
			(xy 328.957686 -54.558946) (xy 328.957176 -54.584933) (xy 329.92238 -54.584933) (xy 329.92238 -54.532959)
			(xy 329.93051 -54.481624) (xy 329.946571 -54.432194) (xy 329.970167 -54.385884) (xy 330.000717 -54.343836)
			(xy 330.037468 -54.307085) (xy 330.079516 -54.276535) (xy 330.125826 -54.252939) (xy 330.175256 -54.236878)
			(xy 330.226591 -54.228748) (xy 330.278565 -54.228748) (xy 330.3299 -54.236878) (xy 330.37933 -54.252939)
			(xy 330.42564 -54.276535) (xy 330.467688 -54.307085) (xy 330.504439 -54.343836) (xy 330.534989 -54.385884)
			(xy 330.558585 -54.432194) (xy 330.574646 -54.481624) (xy 330.582776 -54.532959) (xy 330.583286 -54.558946)
			(xy 330.582776 -54.584933) (xy 331.55306 -54.584933) (xy 331.55306 -54.532959) (xy 331.56119 -54.481624)
			(xy 331.577251 -54.432194) (xy 331.600847 -54.385884) (xy 331.631397 -54.343836) (xy 331.668148 -54.307085)
			(xy 331.710196 -54.276535) (xy 331.756506 -54.252939) (xy 331.805936 -54.236878) (xy 331.857271 -54.228748)
			(xy 331.909245 -54.228748) (xy 331.96058 -54.236878) (xy 332.01001 -54.252939) (xy 332.05632 -54.276535)
			(xy 332.098368 -54.307085) (xy 332.135119 -54.343836) (xy 332.165669 -54.385884) (xy 332.189265 -54.432194)
			(xy 332.205326 -54.481624) (xy 332.213456 -54.532959) (xy 332.213966 -54.558946) (xy 332.213456 -54.584933)
			(xy 332.205326 -54.636268) (xy 332.189265 -54.685698) (xy 332.165669 -54.732008) (xy 332.135119 -54.774056)
			(xy 332.098368 -54.810807) (xy 332.05632 -54.841357) (xy 332.01001 -54.864953) (xy 331.96058 -54.881014)
			(xy 331.909245 -54.889144) (xy 331.857271 -54.889144) (xy 331.805936 -54.881014) (xy 331.756506 -54.864953)
			(xy 331.710196 -54.841357) (xy 331.668148 -54.810807) (xy 331.631397 -54.774056) (xy 331.600847 -54.732008)
			(xy 331.577251 -54.685698) (xy 331.56119 -54.636268) (xy 331.55306 -54.584933) (xy 330.582776 -54.584933)
			(xy 330.574646 -54.636268) (xy 330.558585 -54.685698) (xy 330.534989 -54.732008) (xy 330.504439 -54.774056)
			(xy 330.467688 -54.810807) (xy 330.42564 -54.841357) (xy 330.37933 -54.864953) (xy 330.3299 -54.881014)
			(xy 330.278565 -54.889144) (xy 330.226591 -54.889144) (xy 330.175256 -54.881014) (xy 330.125826 -54.864953)
			(xy 330.079516 -54.841357) (xy 330.037468 -54.810807) (xy 330.000717 -54.774056) (xy 329.970167 -54.732008)
			(xy 329.946571 -54.685698) (xy 329.93051 -54.636268) (xy 329.92238 -54.584933) (xy 328.957176 -54.584933)
			(xy 328.949046 -54.636268) (xy 328.932985 -54.685698) (xy 328.909389 -54.732008) (xy 328.878839 -54.774056)
			(xy 328.842088 -54.810807) (xy 328.80004 -54.841357) (xy 328.75373 -54.864953) (xy 328.7043 -54.881014)
			(xy 328.652965 -54.889144) (xy 328.600991 -54.889144) (xy 328.549656 -54.881014) (xy 328.500226 -54.864953)
			(xy 328.453916 -54.841357) (xy 328.411868 -54.810807) (xy 328.375117 -54.774056) (xy 328.344567 -54.732008)
			(xy 328.320971 -54.685698) (xy 328.30491 -54.636268) (xy 328.29678 -54.584933) (xy 323.663413 -54.584933)
			(xy 323.630771 -54.621364) (xy 323.587903 -54.657039) (xy 323.540297 -54.686093) (xy 323.488968 -54.707905)
			(xy 323.435011 -54.722011) (xy 323.379574 -54.728111) (xy 323.32384 -54.726074) (xy 323.268997 -54.715944)
			(xy 323.216213 -54.697937) (xy 323.166613 -54.672436) (xy 323.121255 -54.639985) (xy 323.081106 -54.601276)
			(xy 323.04702 -54.557133) (xy 323.019724 -54.508498) (xy 322.999801 -54.456407) (xy 322.987675 -54.40197)
			(xy 322.983604 -54.346348) (xy 314.435977 -54.346348) (xy 314.434076 -54.352823) (xy 314.411429 -54.402411)
			(xy 314.381955 -54.44827) (xy 314.346255 -54.489469) (xy 314.305054 -54.525167) (xy 314.259193 -54.554638)
			(xy 314.209604 -54.577283) (xy 314.157297 -54.592639) (xy 314.103337 -54.600394) (xy 314.07608 -54.600856)
			(xy 314.043929 -54.600203) (xy 313.98054 -54.589401) (xy 313.919865 -54.568109) (xy 313.891422 -54.553104)
			(xy 313.877953 -54.546234) (xy 313.848383 -54.539988) (xy 313.818281 -54.542672) (xy 313.790283 -54.554052)
			(xy 313.766843 -54.57313) (xy 313.750016 -54.598234) (xy 313.745118 -54.61254) (xy 313.736818 -54.638274)
			(xy 313.713888 -54.687245) (xy 313.684276 -54.73249) (xy 313.648575 -54.773102) (xy 313.6075 -54.80827)
			(xy 313.561873 -54.837289) (xy 313.512607 -54.859578) (xy 313.460688 -54.87469) (xy 313.407157 -54.882325)
			(xy 313.38012 -54.882796) (xy 313.352865 -54.882358) (xy 313.29891 -54.874604) (xy 313.246609 -54.859249)
			(xy 313.197024 -54.836607) (xy 313.151167 -54.807138) (xy 313.109971 -54.771443) (xy 313.074274 -54.730249)
			(xy 313.044803 -54.684393) (xy 313.022158 -54.63481) (xy 313.006801 -54.582509) (xy 312.999043 -54.528555)
			(xy 309.79812 -54.528555) (xy 309.764586 -54.542805) (xy 309.710629 -54.556911) (xy 309.655192 -54.563011)
			(xy 309.599458 -54.560974) (xy 309.544615 -54.550844) (xy 309.491831 -54.532837) (xy 309.442231 -54.507336)
			(xy 309.396873 -54.474885) (xy 309.356724 -54.436176) (xy 309.322638 -54.392033) (xy 309.295342 -54.343398)
			(xy 309.275419 -54.291307) (xy 309.263293 -54.23687) (xy 309.259222 -54.181248) (xy 305.386324 -54.181248)
			(xy 305.377741 -54.199558) (xy 305.346968 -54.246071) (xy 305.309751 -54.287608) (xy 305.266883 -54.323283)
			(xy 305.219277 -54.352337) (xy 305.167948 -54.374149) (xy 305.113991 -54.388255) (xy 305.058554 -54.394355)
			(xy 305.00282 -54.392318) (xy 304.947977 -54.382188) (xy 304.895193 -54.364181) (xy 304.845593 -54.33868)
			(xy 304.800235 -54.306229) (xy 304.760086 -54.26752) (xy 304.726 -54.223377) (xy 304.698704 -54.174742)
			(xy 304.678781 -54.122651) (xy 304.666655 -54.068214) (xy 304.662584 -54.012592) (xy 295.022665 -54.012592)
			(xy 295.065169 -54.047964) (xy 295.102386 -54.089501) (xy 295.133159 -54.136014) (xy 295.156831 -54.186511)
			(xy 295.172899 -54.239918) (xy 295.181019 -54.295094) (xy 295.181528 -54.32298) (xy 295.181019 -54.350866)
			(xy 295.172899 -54.406042) (xy 295.156831 -54.459449) (xy 295.133159 -54.509946) (xy 295.102386 -54.556459)
			(xy 295.065169 -54.597996) (xy 295.022301 -54.633671) (xy 294.974695 -54.662725) (xy 294.923366 -54.684537)
			(xy 294.869409 -54.698643) (xy 294.813972 -54.704743) (xy 294.758238 -54.702706) (xy 294.703395 -54.692576)
			(xy 294.650611 -54.674569) (xy 294.601011 -54.649068) (xy 294.555653 -54.616617) (xy 294.515504 -54.577908)
			(xy 294.481418 -54.533765) (xy 294.454122 -54.48513) (xy 294.434199 -54.433039) (xy 294.422073 -54.378602)
			(xy 294.418002 -54.32298) (xy 292.173837 -54.32298) (xy 292.166809 -54.370736) (xy 292.150741 -54.424143)
			(xy 292.127069 -54.47464) (xy 292.096296 -54.521153) (xy 292.059079 -54.56269) (xy 292.016211 -54.598365)
			(xy 291.968605 -54.627419) (xy 291.917276 -54.649231) (xy 291.863319 -54.663337) (xy 291.807882 -54.669437)
			(xy 291.752148 -54.6674) (xy 291.697305 -54.65727) (xy 291.644521 -54.639263) (xy 291.594921 -54.613762)
			(xy 291.549563 -54.581311) (xy 291.509414 -54.542602) (xy 291.475328 -54.498459) (xy 291.448032 -54.449824)
			(xy 291.428109 -54.397733) (xy 291.415983 -54.343296) (xy 291.411912 -54.287674) (xy 282.38704 -54.287674)
			(xy 282.38704 -54.437788) (xy 281.51148 -55.313348) (xy 302.539426 -55.313348) (xy 302.539426 -55.258852)
			(xy 302.547182 -55.204911) (xy 302.562535 -55.152623) (xy 302.585173 -55.103052) (xy 302.614636 -55.057208)
			(xy 302.650323 -55.016023) (xy 302.691508 -54.980336) (xy 302.737352 -54.950873) (xy 302.786923 -54.928235)
			(xy 302.839211 -54.912882) (xy 302.893152 -54.905126) (xy 302.9204 -54.90464) (xy 302.947771 -54.905096)
			(xy 303.001951 -54.912915) (xy 303.054454 -54.928406) (xy 303.104201 -54.95125) (xy 303.150167 -54.980977)
			(xy 303.171098 -54.99862) (xy 303.182426 -55.007856) (xy 303.208983 -55.020032) (xy 303.2379 -55.024205)
			(xy 303.266817 -55.020032) (xy 303.293374 -55.007856) (xy 303.304702 -54.99862) (xy 303.325625 -54.98097)
			(xy 303.3716 -54.951259) (xy 303.42135 -54.928425) (xy 303.473853 -54.912936) (xy 303.52803 -54.905112)
			(xy 303.5554 -54.90464) (xy 303.582655 -54.90503) (xy 303.636609 -54.912787) (xy 303.688911 -54.928144)
			(xy 303.738494 -54.950788) (xy 303.78435 -54.980258) (xy 303.825546 -55.015954) (xy 303.861242 -55.05715)
			(xy 303.890712 -55.103006) (xy 303.913356 -55.152589) (xy 303.928713 -55.204891) (xy 303.93647 -55.258845)
			(xy 303.93647 -55.313355) (xy 303.933078 -55.336948) (xy 310.442862 -55.336948) (xy 310.446933 -55.281326)
			(xy 310.459059 -55.226889) (xy 310.478982 -55.174798) (xy 310.506278 -55.126163) (xy 310.540364 -55.08202)
			(xy 310.580513 -55.043311) (xy 310.625871 -55.01086) (xy 310.675471 -54.985359) (xy 310.728255 -54.967352)
			(xy 310.783098 -54.957222) (xy 310.838832 -54.955185) (xy 310.894269 -54.961285) (xy 310.948226 -54.975391)
			(xy 310.999555 -54.997203) (xy 311.047161 -55.026257) (xy 311.090029 -55.061932) (xy 311.127246 -55.103469)
			(xy 311.158019 -55.149982) (xy 311.181691 -55.200479) (xy 311.197759 -55.253886) (xy 311.205879 -55.309062)
			(xy 311.206388 -55.336948) (xy 312.474862 -55.336948) (xy 312.478933 -55.281326) (xy 312.491059 -55.226889)
			(xy 312.510982 -55.174798) (xy 312.538278 -55.126163) (xy 312.572364 -55.08202) (xy 312.612513 -55.043311)
			(xy 312.657871 -55.01086) (xy 312.707471 -54.985359) (xy 312.760255 -54.967352) (xy 312.815098 -54.957222)
			(xy 312.870832 -54.955185) (xy 312.926269 -54.961285) (xy 312.980226 -54.975391) (xy 313.031555 -54.997203)
			(xy 313.079161 -55.026257) (xy 313.122029 -55.061932) (xy 313.159246 -55.103469) (xy 313.190019 -55.149982)
			(xy 313.213691 -55.200479) (xy 313.224182 -55.235348) (xy 313.710318 -55.235348) (xy 313.714389 -55.179726)
			(xy 313.726515 -55.125289) (xy 313.746438 -55.073198) (xy 313.773734 -55.024563) (xy 313.80782 -54.98042)
			(xy 313.847969 -54.941711) (xy 313.893327 -54.90926) (xy 313.942927 -54.883759) (xy 313.995711 -54.865752)
			(xy 314.050554 -54.855622) (xy 314.106288 -54.853585) (xy 314.161725 -54.859685) (xy 314.215682 -54.873791)
			(xy 314.267011 -54.895603) (xy 314.314617 -54.924657) (xy 314.357485 -54.960332) (xy 314.394702 -55.001869)
			(xy 314.425475 -55.048382) (xy 314.449147 -55.098879) (xy 314.465215 -55.152286) (xy 314.473335 -55.207462)
			(xy 314.473844 -55.235348) (xy 318.769998 -55.235348) (xy 318.774069 -55.179726) (xy 318.786195 -55.125289)
			(xy 318.806118 -55.073198) (xy 318.833414 -55.024563) (xy 318.8675 -54.98042) (xy 318.907649 -54.941711)
			(xy 318.953007 -54.90926) (xy 319.002607 -54.883759) (xy 319.055391 -54.865752) (xy 319.110234 -54.855622)
			(xy 319.165968 -54.853585) (xy 319.221405 -54.859685) (xy 319.275362 -54.873791) (xy 319.326691 -54.895603)
			(xy 319.374297 -54.924657) (xy 319.417165 -54.960332) (xy 319.454382 -55.001869) (xy 319.485155 -55.048382)
			(xy 319.508827 -55.098879) (xy 319.524895 -55.152286) (xy 319.533015 -55.207462) (xy 319.533524 -55.235348)
			(xy 320.895978 -55.235348) (xy 320.900049 -55.179726) (xy 320.912175 -55.125289) (xy 320.932098 -55.073198)
			(xy 320.959394 -55.024563) (xy 320.99348 -54.98042) (xy 321.033629 -54.941711) (xy 321.078987 -54.90926)
			(xy 321.128587 -54.883759) (xy 321.181371 -54.865752) (xy 321.236214 -54.855622) (xy 321.291948 -54.853585)
			(xy 321.347385 -54.859685) (xy 321.401342 -54.873791) (xy 321.452671 -54.895603) (xy 321.500277 -54.924657)
			(xy 321.543145 -54.960332) (xy 321.580362 -55.001869) (xy 321.611135 -55.048382) (xy 321.614159 -55.054833)
			(xy 329.107548 -55.054833) (xy 329.107548 -55.002859) (xy 329.115678 -54.951524) (xy 329.131739 -54.902094)
			(xy 329.155335 -54.855784) (xy 329.185885 -54.813736) (xy 329.222636 -54.776985) (xy 329.264684 -54.746435)
			(xy 329.310994 -54.722839) (xy 329.360424 -54.706778) (xy 329.411759 -54.698648) (xy 329.463733 -54.698648)
			(xy 329.515068 -54.706778) (xy 329.564498 -54.722839) (xy 329.610808 -54.746435) (xy 329.652856 -54.776985)
			(xy 329.689607 -54.813736) (xy 329.720157 -54.855784) (xy 329.743753 -54.902094) (xy 329.759814 -54.951524)
			(xy 329.767944 -55.002859) (xy 329.768454 -55.028846) (xy 329.767944 -55.054833) (xy 330.73772 -55.054833)
			(xy 330.73772 -55.002859) (xy 330.74585 -54.951524) (xy 330.761911 -54.902094) (xy 330.785507 -54.855784)
			(xy 330.816057 -54.813736) (xy 330.852808 -54.776985) (xy 330.894856 -54.746435) (xy 330.941166 -54.722839)
			(xy 330.990596 -54.706778) (xy 331.041931 -54.698648) (xy 331.093905 -54.698648) (xy 331.14524 -54.706778)
			(xy 331.19467 -54.722839) (xy 331.24098 -54.746435) (xy 331.283028 -54.776985) (xy 331.319779 -54.813736)
			(xy 331.350329 -54.855784) (xy 331.373925 -54.902094) (xy 331.389986 -54.951524) (xy 331.398116 -55.002859)
			(xy 331.398626 -55.028846) (xy 331.398116 -55.054833) (xy 331.389986 -55.106168) (xy 331.373925 -55.155598)
			(xy 331.350329 -55.201908) (xy 331.319779 -55.243956) (xy 331.283028 -55.280707) (xy 331.24098 -55.311257)
			(xy 331.19467 -55.334853) (xy 331.14524 -55.350914) (xy 331.093905 -55.359044) (xy 331.041931 -55.359044)
			(xy 330.990596 -55.350914) (xy 330.941166 -55.334853) (xy 330.894856 -55.311257) (xy 330.852808 -55.280707)
			(xy 330.816057 -55.243956) (xy 330.785507 -55.201908) (xy 330.761911 -55.155598) (xy 330.74585 -55.106168)
			(xy 330.73772 -55.054833) (xy 329.767944 -55.054833) (xy 329.759814 -55.106168) (xy 329.743753 -55.155598)
			(xy 329.720157 -55.201908) (xy 329.689607 -55.243956) (xy 329.652856 -55.280707) (xy 329.610808 -55.311257)
			(xy 329.564498 -55.334853) (xy 329.515068 -55.350914) (xy 329.463733 -55.359044) (xy 329.411759 -55.359044)
			(xy 329.360424 -55.350914) (xy 329.310994 -55.334853) (xy 329.264684 -55.311257) (xy 329.222636 -55.280707)
			(xy 329.185885 -55.243956) (xy 329.155335 -55.201908) (xy 329.131739 -55.155598) (xy 329.115678 -55.106168)
			(xy 329.107548 -55.054833) (xy 321.614159 -55.054833) (xy 321.634807 -55.098879) (xy 321.650875 -55.152286)
			(xy 321.658995 -55.207462) (xy 321.659504 -55.235348) (xy 321.658995 -55.263234) (xy 321.650875 -55.31841)
			(xy 321.634807 -55.371817) (xy 321.611135 -55.422314) (xy 321.580362 -55.468827) (xy 321.543145 -55.510364)
			(xy 321.525879 -55.524733) (xy 328.29678 -55.524733) (xy 328.29678 -55.472759) (xy 328.30491 -55.421424)
			(xy 328.320971 -55.371994) (xy 328.344567 -55.325684) (xy 328.375117 -55.283636) (xy 328.411868 -55.246885)
			(xy 328.453916 -55.216335) (xy 328.500226 -55.192739) (xy 328.549656 -55.176678) (xy 328.600991 -55.168548)
			(xy 328.652965 -55.168548) (xy 328.7043 -55.176678) (xy 328.75373 -55.192739) (xy 328.80004 -55.216335)
			(xy 328.842088 -55.246885) (xy 328.878839 -55.283636) (xy 328.909389 -55.325684) (xy 328.932985 -55.371994)
			(xy 328.949046 -55.421424) (xy 328.957176 -55.472759) (xy 328.957686 -55.498746) (xy 328.957176 -55.524733)
			(xy 329.925682 -55.524733) (xy 329.925682 -55.472759) (xy 329.933812 -55.421424) (xy 329.949873 -55.371994)
			(xy 329.973469 -55.325684) (xy 330.004019 -55.283636) (xy 330.04077 -55.246885) (xy 330.082818 -55.216335)
			(xy 330.129128 -55.192739) (xy 330.178558 -55.176678) (xy 330.229893 -55.168548) (xy 330.281867 -55.168548)
			(xy 330.333202 -55.176678) (xy 330.382632 -55.192739) (xy 330.428942 -55.216335) (xy 330.47099 -55.246885)
			(xy 330.507741 -55.283636) (xy 330.538291 -55.325684) (xy 330.561887 -55.371994) (xy 330.577948 -55.421424)
			(xy 330.586078 -55.472759) (xy 330.586588 -55.498746) (xy 330.586078 -55.524733) (xy 331.55179 -55.524733)
			(xy 331.55179 -55.472759) (xy 331.55992 -55.421424) (xy 331.575981 -55.371994) (xy 331.599577 -55.325684)
			(xy 331.630127 -55.283636) (xy 331.666878 -55.246885) (xy 331.708926 -55.216335) (xy 331.755236 -55.192739)
			(xy 331.804666 -55.176678) (xy 331.856001 -55.168548) (xy 331.907975 -55.168548) (xy 331.95931 -55.176678)
			(xy 332.00874 -55.192739) (xy 332.05505 -55.216335) (xy 332.097098 -55.246885) (xy 332.133849 -55.283636)
			(xy 332.164399 -55.325684) (xy 332.187995 -55.371994) (xy 332.204056 -55.421424) (xy 332.212186 -55.472759)
			(xy 332.212696 -55.498746) (xy 332.212186 -55.524733) (xy 332.204056 -55.576068) (xy 332.187995 -55.625498)
			(xy 332.164399 -55.671808) (xy 332.133849 -55.713856) (xy 332.097098 -55.750607) (xy 332.05505 -55.781157)
			(xy 332.00874 -55.804753) (xy 331.95931 -55.820814) (xy 331.907975 -55.828944) (xy 331.856001 -55.828944)
			(xy 331.804666 -55.820814) (xy 331.755236 -55.804753) (xy 331.708926 -55.781157) (xy 331.666878 -55.750607)
			(xy 331.630127 -55.713856) (xy 331.599577 -55.671808) (xy 331.575981 -55.625498) (xy 331.55992 -55.576068)
			(xy 331.55179 -55.524733) (xy 330.586078 -55.524733) (xy 330.577948 -55.576068) (xy 330.561887 -55.625498)
			(xy 330.538291 -55.671808) (xy 330.507741 -55.713856) (xy 330.47099 -55.750607) (xy 330.428942 -55.781157)
			(xy 330.382632 -55.804753) (xy 330.333202 -55.820814) (xy 330.281867 -55.828944) (xy 330.229893 -55.828944)
			(xy 330.178558 -55.820814) (xy 330.129128 -55.804753) (xy 330.082818 -55.781157) (xy 330.04077 -55.750607)
			(xy 330.004019 -55.713856) (xy 329.973469 -55.671808) (xy 329.949873 -55.625498) (xy 329.933812 -55.576068)
			(xy 329.925682 -55.524733) (xy 328.957176 -55.524733) (xy 328.949046 -55.576068) (xy 328.932985 -55.625498)
			(xy 328.909389 -55.671808) (xy 328.878839 -55.713856) (xy 328.842088 -55.750607) (xy 328.80004 -55.781157)
			(xy 328.75373 -55.804753) (xy 328.7043 -55.820814) (xy 328.652965 -55.828944) (xy 328.600991 -55.828944)
			(xy 328.549656 -55.820814) (xy 328.500226 -55.804753) (xy 328.453916 -55.781157) (xy 328.411868 -55.750607)
			(xy 328.375117 -55.713856) (xy 328.344567 -55.671808) (xy 328.320971 -55.625498) (xy 328.30491 -55.576068)
			(xy 328.29678 -55.524733) (xy 321.525879 -55.524733) (xy 321.500277 -55.546039) (xy 321.452671 -55.575093)
			(xy 321.401342 -55.596905) (xy 321.347385 -55.611011) (xy 321.291948 -55.617111) (xy 321.236214 -55.615074)
			(xy 321.181371 -55.604944) (xy 321.128587 -55.586937) (xy 321.078987 -55.561436) (xy 321.033629 -55.528985)
			(xy 320.99348 -55.490276) (xy 320.959394 -55.446133) (xy 320.932098 -55.397498) (xy 320.912175 -55.345407)
			(xy 320.900049 -55.29097) (xy 320.895978 -55.235348) (xy 319.533524 -55.235348) (xy 319.533015 -55.263234)
			(xy 319.524895 -55.31841) (xy 319.508827 -55.371817) (xy 319.485155 -55.422314) (xy 319.454382 -55.468827)
			(xy 319.417165 -55.510364) (xy 319.374297 -55.546039) (xy 319.326691 -55.575093) (xy 319.275362 -55.596905)
			(xy 319.221405 -55.611011) (xy 319.165968 -55.617111) (xy 319.110234 -55.615074) (xy 319.055391 -55.604944)
			(xy 319.002607 -55.586937) (xy 318.953007 -55.561436) (xy 318.907649 -55.528985) (xy 318.8675 -55.490276)
			(xy 318.833414 -55.446133) (xy 318.806118 -55.397498) (xy 318.786195 -55.345407) (xy 318.774069 -55.29097)
			(xy 318.769998 -55.235348) (xy 314.473844 -55.235348) (xy 314.473335 -55.263234) (xy 314.465215 -55.31841)
			(xy 314.449147 -55.371817) (xy 314.425475 -55.422314) (xy 314.394702 -55.468827) (xy 314.357485 -55.510364)
			(xy 314.314617 -55.546039) (xy 314.267011 -55.575093) (xy 314.215682 -55.596905) (xy 314.161725 -55.611011)
			(xy 314.106288 -55.617111) (xy 314.050554 -55.615074) (xy 313.995711 -55.604944) (xy 313.942927 -55.586937)
			(xy 313.893327 -55.561436) (xy 313.847969 -55.528985) (xy 313.80782 -55.490276) (xy 313.773734 -55.446133)
			(xy 313.746438 -55.397498) (xy 313.726515 -55.345407) (xy 313.714389 -55.29097) (xy 313.710318 -55.235348)
			(xy 313.224182 -55.235348) (xy 313.229759 -55.253886) (xy 313.237879 -55.309062) (xy 313.238388 -55.336948)
			(xy 313.237879 -55.364834) (xy 313.229759 -55.42001) (xy 313.213691 -55.473417) (xy 313.190019 -55.523914)
			(xy 313.159246 -55.570427) (xy 313.122029 -55.611964) (xy 313.079161 -55.647639) (xy 313.031555 -55.676693)
			(xy 312.980226 -55.698505) (xy 312.926269 -55.712611) (xy 312.870832 -55.718711) (xy 312.815098 -55.716674)
			(xy 312.760255 -55.706544) (xy 312.707471 -55.688537) (xy 312.657871 -55.663036) (xy 312.612513 -55.630585)
			(xy 312.572364 -55.591876) (xy 312.538278 -55.547733) (xy 312.510982 -55.499098) (xy 312.491059 -55.447007)
			(xy 312.478933 -55.39257) (xy 312.474862 -55.336948) (xy 311.206388 -55.336948) (xy 311.205879 -55.364834)
			(xy 311.197759 -55.42001) (xy 311.181691 -55.473417) (xy 311.158019 -55.523914) (xy 311.127246 -55.570427)
			(xy 311.090029 -55.611964) (xy 311.047161 -55.647639) (xy 310.999555 -55.676693) (xy 310.948226 -55.698505)
			(xy 310.894269 -55.712611) (xy 310.838832 -55.718711) (xy 310.783098 -55.716674) (xy 310.728255 -55.706544)
			(xy 310.675471 -55.688537) (xy 310.625871 -55.663036) (xy 310.580513 -55.630585) (xy 310.540364 -55.591876)
			(xy 310.506278 -55.547733) (xy 310.478982 -55.499098) (xy 310.459059 -55.447007) (xy 310.446933 -55.39257)
			(xy 310.442862 -55.336948) (xy 303.933078 -55.336948) (xy 303.928713 -55.367309) (xy 303.913356 -55.419611)
			(xy 303.890712 -55.469194) (xy 303.861242 -55.51505) (xy 303.825546 -55.556246) (xy 303.78435 -55.591942)
			(xy 303.738494 -55.621412) (xy 303.688911 -55.644056) (xy 303.636609 -55.659413) (xy 303.582655 -55.66717)
			(xy 303.5554 -55.667656) (xy 303.528029 -55.667201) (xy 303.473849 -55.659382) (xy 303.421346 -55.643891)
			(xy 303.371599 -55.621047) (xy 303.325633 -55.591319) (xy 303.304702 -55.573676) (xy 303.293374 -55.56444)
			(xy 303.266817 -55.552264) (xy 303.2379 -55.548091) (xy 303.208983 -55.552264) (xy 303.182426 -55.56444)
			(xy 303.171098 -55.573676) (xy 303.150174 -55.591326) (xy 303.1042 -55.621037) (xy 303.05445 -55.643871)
			(xy 303.001947 -55.65936) (xy 302.94777 -55.667184) (xy 302.9204 -55.667656) (xy 302.893152 -55.667074)
			(xy 302.839211 -55.659318) (xy 302.786923 -55.643965) (xy 302.737352 -55.621327) (xy 302.691508 -55.591864)
			(xy 302.650323 -55.556177) (xy 302.614636 -55.514992) (xy 302.585173 -55.469148) (xy 302.562535 -55.419577)
			(xy 302.547182 -55.367289) (xy 302.539426 -55.313348) (xy 281.51148 -55.313348) (xy 281.03068 -55.794148)
			(xy 315.998604 -55.794148) (xy 316.002675 -55.738526) (xy 316.014801 -55.684089) (xy 316.034724 -55.631998)
			(xy 316.06202 -55.583363) (xy 316.096106 -55.53922) (xy 316.136255 -55.500511) (xy 316.181613 -55.46806)
			(xy 316.231213 -55.442559) (xy 316.283997 -55.424552) (xy 316.33884 -55.414422) (xy 316.394574 -55.412385)
			(xy 316.450011 -55.418485) (xy 316.503968 -55.432591) (xy 316.555297 -55.454403) (xy 316.602903 -55.483457)
			(xy 316.645771 -55.519132) (xy 316.682988 -55.560669) (xy 316.713761 -55.607182) (xy 316.737433 -55.657679)
			(xy 316.753501 -55.711086) (xy 316.761621 -55.766262) (xy 316.76213 -55.794148) (xy 316.761621 -55.822034)
			(xy 316.753501 -55.87721) (xy 316.737433 -55.930617) (xy 316.713761 -55.981114) (xy 316.682988 -56.027627)
			(xy 316.655726 -56.058054) (xy 321.515992 -56.058054) (xy 321.520063 -56.002432) (xy 321.532189 -55.947995)
			(xy 321.552112 -55.895904) (xy 321.579408 -55.847269) (xy 321.613494 -55.803126) (xy 321.653643 -55.764417)
			(xy 321.699001 -55.731966) (xy 321.748601 -55.706465) (xy 321.801385 -55.688458) (xy 321.856228 -55.678328)
			(xy 321.911962 -55.676291) (xy 321.967399 -55.682391) (xy 322.021356 -55.696497) (xy 322.072685 -55.718309)
			(xy 322.120291 -55.747363) (xy 322.163159 -55.783038) (xy 322.200376 -55.824575) (xy 322.231149 -55.871088)
			(xy 322.254821 -55.921585) (xy 322.270889 -55.974992) (xy 322.279009 -56.030168) (xy 322.279518 -56.058054)
			(xy 322.531992 -56.058054) (xy 322.536063 -56.002432) (xy 322.548189 -55.947995) (xy 322.568112 -55.895904)
			(xy 322.595408 -55.847269) (xy 322.629494 -55.803126) (xy 322.669643 -55.764417) (xy 322.715001 -55.731966)
			(xy 322.764601 -55.706465) (xy 322.817385 -55.688458) (xy 322.872228 -55.678328) (xy 322.927962 -55.676291)
			(xy 322.983399 -55.682391) (xy 323.037356 -55.696497) (xy 323.088685 -55.718309) (xy 323.136291 -55.747363)
			(xy 323.179159 -55.783038) (xy 323.216376 -55.824575) (xy 323.247149 -55.871088) (xy 323.270821 -55.921585)
			(xy 323.286889 -55.974992) (xy 323.295009 -56.030168) (xy 323.295518 -56.058054) (xy 323.295009 -56.08594)
			(xy 323.286889 -56.141116) (xy 323.270821 -56.194523) (xy 323.247149 -56.24502) (xy 323.237736 -56.259247)
			(xy 324.429922 -56.259247) (xy 324.429922 -56.204753) (xy 324.437677 -56.150813) (xy 324.45303 -56.098526)
			(xy 324.475667 -56.048955) (xy 324.505128 -56.003111) (xy 324.540813 -55.961926) (xy 324.581997 -55.926239)
			(xy 324.62784 -55.896776) (xy 324.677409 -55.874136) (xy 324.729695 -55.858781) (xy 324.783635 -55.851023)
			(xy 324.810882 -55.850536) (xy 324.837526 -55.850931) (xy 324.890297 -55.858332) (xy 324.941523 -55.873006)
			(xy 324.990209 -55.894668) (xy 325.035405 -55.922896) (xy 325.076233 -55.957141) (xy 325.111896 -55.996734)
			(xy 325.1417 -56.040907) (xy 325.153782 -56.064658) (xy 325.160263 -56.077086) (xy 325.178944 -56.097974)
			(xy 325.2026 -56.112998) (xy 325.229449 -56.121025) (xy 325.257469 -56.121452) (xy 325.28455 -56.114247)
			(xy 325.308652 -56.099951) (xy 325.327961 -56.079642) (xy 325.334884 -56.067452) (xy 325.347306 -56.044674)
			(xy 325.377425 -56.002428) (xy 325.412991 -55.964652) (xy 325.453347 -55.932045) (xy 325.497749 -55.905206)
			(xy 325.545379 -55.884632) (xy 325.595357 -55.870701) (xy 325.646762 -55.863672) (xy 325.672704 -55.863236)
			(xy 325.699958 -55.863634) (xy 325.753912 -55.871392) (xy 325.806212 -55.886749) (xy 325.855794 -55.909393)
			(xy 325.90165 -55.938863) (xy 325.942844 -55.974559) (xy 325.960238 -55.994633) (xy 330.73899 -55.994633)
			(xy 330.73899 -55.942659) (xy 330.74712 -55.891324) (xy 330.763181 -55.841894) (xy 330.786777 -55.795584)
			(xy 330.817327 -55.753536) (xy 330.854078 -55.716785) (xy 330.896126 -55.686235) (xy 330.942436 -55.662639)
			(xy 330.991866 -55.646578) (xy 331.043201 -55.638448) (xy 331.095175 -55.638448) (xy 331.14651 -55.646578)
			(xy 331.19594 -55.662639) (xy 331.24225 -55.686235) (xy 331.284298 -55.716785) (xy 331.321049 -55.753536)
			(xy 331.351599 -55.795584) (xy 331.375195 -55.841894) (xy 331.391256 -55.891324) (xy 331.399386 -55.942659)
			(xy 331.399896 -55.968646) (xy 331.399386 -55.994633) (xy 332.367384 -55.994633) (xy 332.367384 -55.942659)
			(xy 332.375514 -55.891324) (xy 332.391575 -55.841894) (xy 332.415171 -55.795584) (xy 332.445721 -55.753536)
			(xy 332.482472 -55.716785) (xy 332.52452 -55.686235) (xy 332.57083 -55.662639) (xy 332.62026 -55.646578)
			(xy 332.671595 -55.638448) (xy 332.723569 -55.638448) (xy 332.774904 -55.646578) (xy 332.824334 -55.662639)
			(xy 332.870644 -55.686235) (xy 332.912692 -55.716785) (xy 332.949443 -55.753536) (xy 332.979993 -55.795584)
			(xy 333.003589 -55.841894) (xy 333.01965 -55.891324) (xy 333.02778 -55.942659) (xy 333.02829 -55.968646)
			(xy 333.02778 -55.994633) (xy 333.01965 -56.045968) (xy 333.003589 -56.095398) (xy 332.979993 -56.141708)
			(xy 332.949443 -56.183756) (xy 332.912692 -56.220507) (xy 332.870644 -56.251057) (xy 332.824334 -56.274653)
			(xy 332.774904 -56.290714) (xy 332.723569 -56.298844) (xy 332.671595 -56.298844) (xy 332.62026 -56.290714)
			(xy 332.57083 -56.274653) (xy 332.52452 -56.251057) (xy 332.482472 -56.220507) (xy 332.445721 -56.183756)
			(xy 332.415171 -56.141708) (xy 332.391575 -56.095398) (xy 332.375514 -56.045968) (xy 332.367384 -55.994633)
			(xy 331.399386 -55.994633) (xy 331.391256 -56.045968) (xy 331.375195 -56.095398) (xy 331.351599 -56.141708)
			(xy 331.321049 -56.183756) (xy 331.284298 -56.220507) (xy 331.24225 -56.251057) (xy 331.19594 -56.274653)
			(xy 331.14651 -56.290714) (xy 331.095175 -56.298844) (xy 331.043201 -56.298844) (xy 330.991866 -56.290714)
			(xy 330.942436 -56.274653) (xy 330.896126 -56.251057) (xy 330.854078 -56.220507) (xy 330.817327 -56.183756)
			(xy 330.786777 -56.141708) (xy 330.763181 -56.095398) (xy 330.74712 -56.045968) (xy 330.73899 -55.994633)
			(xy 325.960238 -55.994633) (xy 325.978539 -56.015754) (xy 326.008009 -56.061609) (xy 326.030652 -56.111192)
			(xy 326.046009 -56.163492) (xy 326.053766 -56.217446) (xy 326.053766 -56.271954) (xy 326.046009 -56.325908)
			(xy 326.030652 -56.378208) (xy 326.008009 -56.427791) (xy 326.001097 -56.438546) (xy 328.29627 -56.438546)
			(xy 328.29678 -56.412559) (xy 328.30491 -56.361224) (xy 328.320971 -56.311794) (xy 328.344567 -56.265484)
			(xy 328.375117 -56.223436) (xy 328.411868 -56.186685) (xy 328.453916 -56.156135) (xy 328.500226 -56.132539)
			(xy 328.549656 -56.116478) (xy 328.600991 -56.108348) (xy 328.652965 -56.108348) (xy 328.7043 -56.116478)
			(xy 328.75373 -56.132539) (xy 328.80004 -56.156135) (xy 328.842088 -56.186685) (xy 328.878839 -56.223436)
			(xy 328.909389 -56.265484) (xy 328.932985 -56.311794) (xy 328.949046 -56.361224) (xy 328.957176 -56.412559)
			(xy 328.957686 -56.438546) (xy 328.957164 -56.464533) (xy 329.925682 -56.464533) (xy 329.925682 -56.412559)
			(xy 329.933812 -56.361224) (xy 329.949873 -56.311794) (xy 329.973469 -56.265484) (xy 330.004019 -56.223436)
			(xy 330.04077 -56.186685) (xy 330.082818 -56.156135) (xy 330.129128 -56.132539) (xy 330.178558 -56.116478)
			(xy 330.229893 -56.108348) (xy 330.281867 -56.108348) (xy 330.333202 -56.116478) (xy 330.382632 -56.132539)
			(xy 330.428942 -56.156135) (xy 330.47099 -56.186685) (xy 330.507741 -56.223436) (xy 330.538291 -56.265484)
			(xy 330.561887 -56.311794) (xy 330.577948 -56.361224) (xy 330.586078 -56.412559) (xy 330.586588 -56.438546)
			(xy 330.586078 -56.464533) (xy 331.55179 -56.464533) (xy 331.55179 -56.412559) (xy 331.55992 -56.361224)
			(xy 331.575981 -56.311794) (xy 331.599577 -56.265484) (xy 331.630127 -56.223436) (xy 331.666878 -56.186685)
			(xy 331.708926 -56.156135) (xy 331.755236 -56.132539) (xy 331.804666 -56.116478) (xy 331.856001 -56.108348)
			(xy 331.907975 -56.108348) (xy 331.95931 -56.116478) (xy 332.00874 -56.132539) (xy 332.05505 -56.156135)
			(xy 332.097098 -56.186685) (xy 332.133849 -56.223436) (xy 332.164399 -56.265484) (xy 332.187995 -56.311794)
			(xy 332.204056 -56.361224) (xy 332.212186 -56.412559) (xy 332.212696 -56.438546) (xy 332.212186 -56.464533)
			(xy 332.204056 -56.515868) (xy 332.187995 -56.565298) (xy 332.164399 -56.611608) (xy 332.133849 -56.653656)
			(xy 332.097098 -56.690407) (xy 332.05505 -56.720957) (xy 332.00874 -56.744553) (xy 331.95931 -56.760614)
			(xy 331.907975 -56.768744) (xy 331.856001 -56.768744) (xy 331.804666 -56.760614) (xy 331.755236 -56.744553)
			(xy 331.708926 -56.720957) (xy 331.666878 -56.690407) (xy 331.630127 -56.653656) (xy 331.599577 -56.611608)
			(xy 331.575981 -56.565298) (xy 331.55992 -56.515868) (xy 331.55179 -56.464533) (xy 330.586078 -56.464533)
			(xy 330.577948 -56.515868) (xy 330.561887 -56.565298) (xy 330.538291 -56.611608) (xy 330.507741 -56.653656)
			(xy 330.47099 -56.690407) (xy 330.428942 -56.720957) (xy 330.382632 -56.744553) (xy 330.333202 -56.760614)
			(xy 330.281867 -56.768744) (xy 330.229893 -56.768744) (xy 330.178558 -56.760614) (xy 330.129128 -56.744553)
			(xy 330.082818 -56.720957) (xy 330.04077 -56.690407) (xy 330.004019 -56.653656) (xy 329.973469 -56.611608)
			(xy 329.949873 -56.565298) (xy 329.933812 -56.515868) (xy 329.925682 -56.464533) (xy 328.957164 -56.464533)
			(xy 328.957163 -56.464558) (xy 328.949019 -56.515939) (xy 328.932938 -56.565415) (xy 328.909317 -56.611767)
			(xy 328.89444 -56.63311) (xy 328.886365 -56.645004) (xy 328.876535 -56.672005) (xy 328.874637 -56.700676)
			(xy 328.880823 -56.728737) (xy 328.894599 -56.753953) (xy 328.91487 -56.774318) (xy 328.927206 -56.7817)
			(xy 328.940166 -56.789099) (xy 328.964841 -56.80589) (xy 328.976482 -56.815228) (xy 328.98715 -56.823424)
			(xy 329.011664 -56.834477) (xy 329.038215 -56.838745) (xy 329.064958 -56.835932) (xy 329.090039 -56.826232)
			(xy 329.111717 -56.81032) (xy 329.128488 -56.7893) (xy 329.134216 -56.777128) (xy 329.145652 -56.752138)
			(xy 329.175512 -56.706005) (xy 329.212585 -56.665441) (xy 329.255853 -56.631562) (xy 329.304125 -56.6053)
			(xy 329.356073 -56.587377) (xy 329.410269 -56.578286) (xy 329.437746 -56.577738) (xy 329.463734 -56.578159)
			(xy 329.51507 -56.586297) (xy 329.564502 -56.602364) (xy 329.610811 -56.625965) (xy 329.652859 -56.65652)
			(xy 329.68961 -56.693276) (xy 329.720159 -56.735328) (xy 329.743754 -56.781641) (xy 329.759814 -56.831074)
			(xy 329.767945 -56.882412) (xy 329.767945 -56.934389) (xy 329.759814 -56.985726) (xy 329.743754 -57.035159)
			(xy 329.720159 -57.081472) (xy 329.68961 -57.123524) (xy 329.652859 -57.16028) (xy 329.610811 -57.190835)
			(xy 329.564502 -57.214436) (xy 329.51507 -57.230503) (xy 329.463734 -57.238641) (xy 329.437746 -57.239154)
			(xy 329.409315 -57.238528) (xy 329.353297 -57.228764) (xy 329.299767 -57.209583) (xy 329.250295 -57.181549)
			(xy 329.227942 -57.16397) (xy 329.217253 -57.155803) (xy 329.192745 -57.144748) (xy 329.1662 -57.140477)
			(xy 329.139461 -57.143286) (xy 329.114383 -57.15298) (xy 329.092706 -57.168886) (xy 329.075936 -57.189901)
			(xy 329.070208 -57.20207) (xy 329.058831 -57.227089) (xy 329.028963 -57.273225) (xy 329.013367 -57.290285)
			(xy 330.162201 -57.290285) (xy 330.162201 -57.238315) (xy 330.170331 -57.186985) (xy 330.186389 -57.137558)
			(xy 330.209981 -57.091252) (xy 330.240525 -57.049206) (xy 330.277271 -57.012455) (xy 330.319313 -56.981905)
			(xy 330.365616 -56.958306) (xy 330.41504 -56.942241) (xy 330.466369 -56.934105) (xy 330.492354 -56.933592)
			(xy 330.521285 -56.9342) (xy 330.57826 -56.944288) (xy 330.605638 -56.953658) (xy 330.620221 -56.958355)
			(xy 330.650803 -56.959863) (xy 330.680464 -56.952261) (xy 330.70655 -56.936228) (xy 330.726729 -56.913199)
			(xy 330.739195 -56.885232) (xy 330.741528 -56.870092) (xy 330.745155 -56.843594) (xy 330.759806 -56.792162)
			(xy 330.782546 -56.743759) (xy 330.81278 -56.699648) (xy 330.849721 -56.660979) (xy 330.892406 -56.628761)
			(xy 330.939719 -56.603835) (xy 330.990429 -56.58685) (xy 331.043211 -56.578249) (xy 331.06995 -56.577738)
			(xy 331.095945 -56.578126) (xy 331.147297 -56.586252) (xy 331.196745 -56.602312) (xy 331.243072 -56.62591)
			(xy 331.285136 -56.656466) (xy 331.321902 -56.693226) (xy 331.352464 -56.735285) (xy 331.376069 -56.781608)
			(xy 331.392137 -56.831054) (xy 331.400271 -56.882405) (xy 331.400271 -56.934395) (xy 331.392137 -56.985746)
			(xy 331.376069 -57.035192) (xy 331.352464 -57.081515) (xy 331.321902 -57.123574) (xy 331.285136 -57.160334)
			(xy 331.243072 -57.19089) (xy 331.196745 -57.214488) (xy 331.147297 -57.230548) (xy 331.095945 -57.238674)
			(xy 331.06995 -57.239154) (xy 331.041019 -57.238547) (xy 330.984044 -57.228459) (xy 330.956666 -57.219088)
			(xy 330.942091 -57.214357) (xy 330.911501 -57.212846) (xy 330.881833 -57.22045) (xy 330.855742 -57.236491)
			(xy 330.835563 -57.259531) (xy 330.823103 -57.287509) (xy 330.820776 -57.302654) (xy 330.817182 -57.329156)
			(xy 330.802524 -57.380589) (xy 330.779778 -57.428991) (xy 330.749539 -57.473101) (xy 330.712594 -57.511769)
			(xy 330.669906 -57.543986) (xy 330.62259 -57.568911) (xy 330.571878 -57.585896) (xy 330.519094 -57.594497)
			(xy 330.492354 -57.595008) (xy 330.466369 -57.594495) (xy 330.41504 -57.586359) (xy 330.365616 -57.570294)
			(xy 330.319313 -57.546695) (xy 330.277271 -57.516145) (xy 330.240525 -57.479394) (xy 330.209981 -57.437348)
			(xy 330.186389 -57.391042) (xy 330.170331 -57.341615) (xy 330.162201 -57.290285) (xy 329.013367 -57.290285)
			(xy 328.99188 -57.313789) (xy 328.948602 -57.347665) (xy 328.90032 -57.373922) (xy 328.848362 -57.391838)
			(xy 328.794158 -57.400918) (xy 328.766678 -57.40146) (xy 328.740686 -57.401045) (xy 328.689342 -57.392909)
			(xy 328.639903 -57.376841) (xy 328.593586 -57.353236) (xy 328.551533 -57.322676) (xy 328.514778 -57.285914)
			(xy 328.484227 -57.243854) (xy 328.460632 -57.197532) (xy 328.444575 -57.14809) (xy 328.43645 -57.096744)
			(xy 328.43597 -57.070752) (xy 328.436482 -57.04474) (xy 328.444628 -56.993357) (xy 328.460711 -56.943881)
			(xy 328.484336 -56.89753) (xy 328.499216 -56.876188) (xy 328.507274 -56.864285) (xy 328.517096 -56.837288)
			(xy 328.518992 -56.808621) (xy 328.512809 -56.780566) (xy 328.49904 -56.755352) (xy 328.47878 -56.734984)
			(xy 328.46645 -56.727598) (xy 328.4447 -56.71498) (xy 328.404938 -56.684205) (xy 328.370294 -56.647765)
			(xy 328.341568 -56.606499) (xy 328.31942 -56.561359) (xy 328.304363 -56.513386) (xy 328.296743 -56.463686)
			(xy 328.29627 -56.438546) (xy 326.001097 -56.438546) (xy 325.978539 -56.473646) (xy 325.942844 -56.514841)
			(xy 325.90165 -56.550537) (xy 325.855794 -56.580007) (xy 325.806212 -56.602651) (xy 325.753912 -56.618008)
			(xy 325.699958 -56.625766) (xy 325.672704 -56.626252) (xy 325.646062 -56.625793) (xy 325.593294 -56.618403)
			(xy 325.542068 -56.603739) (xy 325.493383 -56.582087) (xy 325.448186 -56.553868) (xy 325.407357 -56.519632)
			(xy 325.371693 -56.480045) (xy 325.341886 -56.435878) (xy 325.329804 -56.41213) (xy 325.323194 -56.399777)
			(xy 325.304534 -56.3789) (xy 325.280902 -56.363881) (xy 325.254078 -56.35585) (xy 325.22608 -56.355413)
			(xy 325.199018 -56.362602) (xy 325.174929 -56.376875) (xy 325.155625 -56.397159) (xy 325.148702 -56.409336)
			(xy 325.136285 -56.432117) (xy 325.106166 -56.474364) (xy 325.0706 -56.51214) (xy 325.030243 -56.544748)
			(xy 324.98584 -56.571586) (xy 324.938209 -56.592159) (xy 324.88823 -56.606089) (xy 324.836824 -56.613117)
			(xy 324.810882 -56.613552) (xy 324.783635 -56.612977) (xy 324.729695 -56.605219) (xy 324.677409 -56.589864)
			(xy 324.62784 -56.567224) (xy 324.581997 -56.537761) (xy 324.540813 -56.502074) (xy 324.505128 -56.460889)
			(xy 324.475667 -56.415045) (xy 324.45303 -56.365474) (xy 324.437677 -56.313187) (xy 324.429922 -56.259247)
			(xy 323.237736 -56.259247) (xy 323.216376 -56.291533) (xy 323.179159 -56.33307) (xy 323.136291 -56.368745)
			(xy 323.088685 -56.397799) (xy 323.037356 -56.419611) (xy 322.983399 -56.433717) (xy 322.927962 -56.439817)
			(xy 322.872228 -56.43778) (xy 322.817385 -56.42765) (xy 322.764601 -56.409643) (xy 322.715001 -56.384142)
			(xy 322.669643 -56.351691) (xy 322.629494 -56.312982) (xy 322.595408 -56.268839) (xy 322.568112 -56.220204)
			(xy 322.548189 -56.168113) (xy 322.536063 -56.113676) (xy 322.531992 -56.058054) (xy 322.279518 -56.058054)
			(xy 322.279009 -56.08594) (xy 322.270889 -56.141116) (xy 322.254821 -56.194523) (xy 322.231149 -56.24502)
			(xy 322.200376 -56.291533) (xy 322.163159 -56.33307) (xy 322.120291 -56.368745) (xy 322.072685 -56.397799)
			(xy 322.021356 -56.419611) (xy 321.967399 -56.433717) (xy 321.911962 -56.439817) (xy 321.856228 -56.43778)
			(xy 321.801385 -56.42765) (xy 321.748601 -56.409643) (xy 321.699001 -56.384142) (xy 321.653643 -56.351691)
			(xy 321.613494 -56.312982) (xy 321.579408 -56.268839) (xy 321.552112 -56.220204) (xy 321.532189 -56.168113)
			(xy 321.520063 -56.113676) (xy 321.515992 -56.058054) (xy 316.655726 -56.058054) (xy 316.645771 -56.069164)
			(xy 316.602903 -56.104839) (xy 316.555297 -56.133893) (xy 316.503968 -56.155705) (xy 316.450011 -56.169811)
			(xy 316.394574 -56.175911) (xy 316.33884 -56.173874) (xy 316.283997 -56.163744) (xy 316.231213 -56.145737)
			(xy 316.181613 -56.120236) (xy 316.136255 -56.087785) (xy 316.096106 -56.049076) (xy 316.06202 -56.004933)
			(xy 316.034724 -55.956298) (xy 316.014801 -55.904207) (xy 316.002675 -55.84977) (xy 315.998604 -55.794148)
			(xy 281.03068 -55.794148) (xy 280.26487 -56.559958) (xy 291.299898 -56.559958) (xy 291.303969 -56.504336)
			(xy 291.316095 -56.449899) (xy 291.336018 -56.397808) (xy 291.363314 -56.349173) (xy 291.3974 -56.30503)
			(xy 291.437549 -56.266321) (xy 291.482907 -56.23387) (xy 291.532507 -56.208369) (xy 291.585291 -56.190362)
			(xy 291.640134 -56.180232) (xy 291.695868 -56.178195) (xy 291.751305 -56.184295) (xy 291.805262 -56.198401)
			(xy 291.856591 -56.220213) (xy 291.904197 -56.249267) (xy 291.947065 -56.284942) (xy 291.984282 -56.326479)
			(xy 292.015055 -56.372992) (xy 292.038727 -56.423489) (xy 292.041347 -56.432196) (xy 297.507912 -56.432196)
			(xy 297.511983 -56.376574) (xy 297.524109 -56.322137) (xy 297.544032 -56.270046) (xy 297.571328 -56.221411)
			(xy 297.605414 -56.177268) (xy 297.645563 -56.138559) (xy 297.690921 -56.106108) (xy 297.740521 -56.080607)
			(xy 297.793305 -56.0626) (xy 297.848148 -56.05247) (xy 297.903882 -56.050433) (xy 297.959319 -56.056533)
			(xy 298.013276 -56.070639) (xy 298.064605 -56.092451) (xy 298.112211 -56.121505) (xy 298.155079 -56.15718)
			(xy 298.192296 -56.198717) (xy 298.223069 -56.24523) (xy 298.246741 -56.295727) (xy 298.262809 -56.349134)
			(xy 298.270929 -56.40431) (xy 298.271382 -56.429148) (xy 299.718982 -56.429148) (xy 299.723053 -56.373526)
			(xy 299.735179 -56.319089) (xy 299.755102 -56.266998) (xy 299.782398 -56.218363) (xy 299.816484 -56.17422)
			(xy 299.856633 -56.135511) (xy 299.901991 -56.10306) (xy 299.951591 -56.077559) (xy 300.004375 -56.059552)
			(xy 300.059218 -56.049422) (xy 300.114952 -56.047385) (xy 300.170389 -56.053485) (xy 300.224346 -56.067591)
			(xy 300.275675 -56.089403) (xy 300.323281 -56.118457) (xy 300.366149 -56.154132) (xy 300.403366 -56.195669)
			(xy 300.434139 -56.242182) (xy 300.450343 -56.276748) (xy 313.719462 -56.276748) (xy 313.723533 -56.221126)
			(xy 313.735659 -56.166689) (xy 313.755582 -56.114598) (xy 313.782878 -56.065963) (xy 313.816964 -56.02182)
			(xy 313.857113 -55.983111) (xy 313.902471 -55.95066) (xy 313.952071 -55.925159) (xy 314.004855 -55.907152)
			(xy 314.059698 -55.897022) (xy 314.115432 -55.894985) (xy 314.170869 -55.901085) (xy 314.224826 -55.915191)
			(xy 314.276155 -55.937003) (xy 314.323761 -55.966057) (xy 314.366629 -56.001732) (xy 314.403846 -56.043269)
			(xy 314.434619 -56.089782) (xy 314.458291 -56.140279) (xy 314.474359 -56.193686) (xy 314.482479 -56.248862)
			(xy 314.482988 -56.276748) (xy 314.482479 -56.304634) (xy 314.474359 -56.35981) (xy 314.458291 -56.413217)
			(xy 314.434619 -56.463714) (xy 314.403846 -56.510227) (xy 314.366629 -56.551764) (xy 314.323761 -56.587439)
			(xy 314.276155 -56.616493) (xy 314.224826 -56.638305) (xy 314.170869 -56.652411) (xy 314.115432 -56.658511)
			(xy 314.059698 -56.656474) (xy 314.004855 -56.646344) (xy 313.952071 -56.628337) (xy 313.902471 -56.602836)
			(xy 313.857113 -56.570385) (xy 313.816964 -56.531676) (xy 313.782878 -56.487533) (xy 313.755582 -56.438898)
			(xy 313.735659 -56.386807) (xy 313.723533 -56.33237) (xy 313.719462 -56.276748) (xy 300.450343 -56.276748)
			(xy 300.457811 -56.292679) (xy 300.473879 -56.346086) (xy 300.481999 -56.401262) (xy 300.482508 -56.429148)
			(xy 300.481999 -56.457034) (xy 300.473879 -56.51221) (xy 300.457811 -56.565617) (xy 300.434139 -56.616114)
			(xy 300.403366 -56.662627) (xy 300.366149 -56.704164) (xy 300.323281 -56.739839) (xy 300.275675 -56.768893)
			(xy 300.224346 -56.790705) (xy 300.170389 -56.804811) (xy 300.114952 -56.810911) (xy 300.059218 -56.808874)
			(xy 300.004375 -56.798744) (xy 299.951591 -56.780737) (xy 299.901991 -56.755236) (xy 299.856633 -56.722785)
			(xy 299.816484 -56.684076) (xy 299.782398 -56.639933) (xy 299.755102 -56.591298) (xy 299.735179 -56.539207)
			(xy 299.723053 -56.48477) (xy 299.718982 -56.429148) (xy 298.271382 -56.429148) (xy 298.271438 -56.432196)
			(xy 298.270929 -56.460082) (xy 298.262809 -56.515258) (xy 298.246741 -56.568665) (xy 298.223069 -56.619162)
			(xy 298.192296 -56.665675) (xy 298.155079 -56.707212) (xy 298.112211 -56.742887) (xy 298.064605 -56.771941)
			(xy 298.013276 -56.793753) (xy 297.959319 -56.807859) (xy 297.903882 -56.813959) (xy 297.848148 -56.811922)
			(xy 297.793305 -56.801792) (xy 297.740521 -56.783785) (xy 297.690921 -56.758284) (xy 297.645563 -56.725833)
			(xy 297.605414 -56.687124) (xy 297.571328 -56.642981) (xy 297.544032 -56.594346) (xy 297.524109 -56.542255)
			(xy 297.511983 -56.487818) (xy 297.507912 -56.432196) (xy 292.041347 -56.432196) (xy 292.054795 -56.476896)
			(xy 292.062915 -56.532072) (xy 292.063424 -56.559958) (xy 292.062915 -56.587844) (xy 292.054795 -56.64302)
			(xy 292.038727 -56.696427) (xy 292.015055 -56.746924) (xy 291.984282 -56.793437) (xy 291.947065 -56.834974)
			(xy 291.904197 -56.870649) (xy 291.856591 -56.899703) (xy 291.805262 -56.921515) (xy 291.751305 -56.935621)
			(xy 291.695868 -56.941721) (xy 291.640134 -56.939684) (xy 291.585291 -56.929554) (xy 291.532507 -56.911547)
			(xy 291.482907 -56.886046) (xy 291.437549 -56.853595) (xy 291.3974 -56.814886) (xy 291.363314 -56.770743)
			(xy 291.336018 -56.722108) (xy 291.316095 -56.670017) (xy 291.303969 -56.61558) (xy 291.299898 -56.559958)
			(xy 280.26487 -56.559958) (xy 279.147778 -57.67705) (xy 279.115221 -57.755653) (xy 289.041036 -57.755653)
			(xy 289.041036 -57.701147) (xy 289.048793 -57.647195) (xy 289.064148 -57.594896) (xy 289.08679 -57.545315)
			(xy 289.116258 -57.499461) (xy 289.151951 -57.458266) (xy 289.193143 -57.422571) (xy 289.238996 -57.393101)
			(xy 289.288576 -57.370456) (xy 289.340873 -57.355097) (xy 289.394825 -57.347337) (xy 289.422078 -57.34685)
			(xy 289.449448 -57.347317) (xy 289.503628 -57.355133) (xy 289.556131 -57.370621) (xy 289.605878 -57.393463)
			(xy 289.651845 -57.423188) (xy 289.672776 -57.44083) (xy 289.684104 -57.450066) (xy 289.710661 -57.462242)
			(xy 289.739578 -57.466415) (xy 289.768495 -57.462242) (xy 289.795052 -57.450066) (xy 289.80638 -57.44083)
			(xy 289.827313 -57.423189) (xy 289.873281 -57.393465) (xy 289.923027 -57.370619) (xy 289.975529 -57.355123)
			(xy 290.029707 -57.347294) (xy 290.084449 -57.347294) (xy 290.138627 -57.355123) (xy 290.191129 -57.370619)
			(xy 290.240875 -57.393465) (xy 290.286843 -57.423189) (xy 290.307776 -57.44083) (xy 290.319104 -57.450066)
			(xy 290.345661 -57.462242) (xy 290.374578 -57.466415) (xy 290.403495 -57.462242) (xy 290.430052 -57.450066)
			(xy 290.44138 -57.44083) (xy 290.462313 -57.423191) (xy 290.508285 -57.393479) (xy 290.558032 -57.370642)
			(xy 290.610533 -57.355151) (xy 290.664709 -57.347323) (xy 290.692078 -57.34685) (xy 290.719329 -57.347396)
			(xy 290.773276 -57.355149) (xy 290.825571 -57.370502) (xy 290.875148 -57.39314) (xy 290.877028 -57.394348)
			(xy 301.522382 -57.394348) (xy 301.526453 -57.338726) (xy 301.538579 -57.284289) (xy 301.558502 -57.232198)
			(xy 301.585798 -57.183563) (xy 301.619884 -57.13942) (xy 301.660033 -57.100711) (xy 301.705391 -57.06826)
			(xy 301.754991 -57.042759) (xy 301.807775 -57.024752) (xy 301.862618 -57.014622) (xy 301.918352 -57.012585)
			(xy 301.973789 -57.018685) (xy 302.027746 -57.032791) (xy 302.079075 -57.054603) (xy 302.126681 -57.083657)
			(xy 302.127656 -57.084468) (xy 306.109622 -57.084468) (xy 306.113693 -57.028846) (xy 306.125819 -56.974409)
			(xy 306.145742 -56.922318) (xy 306.173038 -56.873683) (xy 306.207124 -56.82954) (xy 306.247273 -56.790831)
			(xy 306.292631 -56.75838) (xy 306.342231 -56.732879) (xy 306.395015 -56.714872) (xy 306.449858 -56.704742)
			(xy 306.505592 -56.702705) (xy 306.561029 -56.708805) (xy 306.614986 -56.722911) (xy 306.666315 -56.744723)
			(xy 306.713921 -56.773777) (xy 306.756789 -56.809452) (xy 306.794006 -56.850989) (xy 306.824779 -56.897502)
			(xy 306.848451 -56.947999) (xy 306.86047 -56.987948) (xy 306.979318 -56.987948) (xy 306.983389 -56.932326)
			(xy 306.995515 -56.877889) (xy 307.015438 -56.825798) (xy 307.042734 -56.777163) (xy 307.07682 -56.73302)
			(xy 307.116969 -56.694311) (xy 307.162327 -56.66186) (xy 307.211927 -56.636359) (xy 307.264711 -56.618352)
			(xy 307.319554 -56.608222) (xy 307.375288 -56.606185) (xy 307.430725 -56.612285) (xy 307.484682 -56.626391)
			(xy 307.536011 -56.648203) (xy 307.583617 -56.677257) (xy 307.626485 -56.712932) (xy 307.663702 -56.754469)
			(xy 307.694475 -56.800982) (xy 307.718147 -56.851479) (xy 307.734215 -56.904886) (xy 307.742335 -56.960062)
			(xy 307.742844 -56.987948) (xy 307.742335 -57.015834) (xy 307.734215 -57.07101) (xy 307.726345 -57.097168)
			(xy 307.857142 -57.097168) (xy 307.861213 -57.041546) (xy 307.873339 -56.987109) (xy 307.893262 -56.935018)
			(xy 307.920558 -56.886383) (xy 307.954644 -56.84224) (xy 307.994793 -56.803531) (xy 308.040151 -56.77108)
			(xy 308.089751 -56.745579) (xy 308.142535 -56.727572) (xy 308.197378 -56.717442) (xy 308.253112 -56.715405)
			(xy 308.308549 -56.721505) (xy 308.362506 -56.735611) (xy 308.413835 -56.757423) (xy 308.461441 -56.786477)
			(xy 308.504309 -56.822152) (xy 308.541526 -56.863689) (xy 308.572299 -56.910202) (xy 308.573024 -56.911748)
			(xy 314.335412 -56.911748) (xy 314.339483 -56.856126) (xy 314.351609 -56.801689) (xy 314.371532 -56.749598)
			(xy 314.398828 -56.700963) (xy 314.432914 -56.65682) (xy 314.473063 -56.618111) (xy 314.518421 -56.58566)
			(xy 314.568021 -56.560159) (xy 314.620805 -56.542152) (xy 314.675648 -56.532022) (xy 314.731382 -56.529985)
			(xy 314.786819 -56.536085) (xy 314.840776 -56.550191) (xy 314.892105 -56.572003) (xy 314.939711 -56.601057)
			(xy 314.982579 -56.636732) (xy 315.019796 -56.678269) (xy 315.050569 -56.724782) (xy 315.074241 -56.775279)
			(xy 315.090309 -56.828686) (xy 315.098429 -56.883862) (xy 315.098938 -56.911748) (xy 315.098429 -56.939634)
			(xy 315.090309 -56.99481) (xy 315.074241 -57.048217) (xy 315.050569 -57.098714) (xy 315.019796 -57.145227)
			(xy 314.982579 -57.186764) (xy 314.939711 -57.222439) (xy 314.892105 -57.251493) (xy 314.840776 -57.273305)
			(xy 314.786819 -57.287411) (xy 314.731382 -57.293511) (xy 314.675648 -57.291474) (xy 314.620805 -57.281344)
			(xy 314.568021 -57.263337) (xy 314.518421 -57.237836) (xy 314.473063 -57.205385) (xy 314.432914 -57.166676)
			(xy 314.398828 -57.122533) (xy 314.371532 -57.073898) (xy 314.351609 -57.021807) (xy 314.339483 -56.96737)
			(xy 314.335412 -56.911748) (xy 308.573024 -56.911748) (xy 308.595971 -56.960699) (xy 308.612039 -57.014106)
			(xy 308.620159 -57.069282) (xy 308.620668 -57.097168) (xy 308.620159 -57.125054) (xy 308.612039 -57.18023)
			(xy 308.595971 -57.233637) (xy 308.572299 -57.284134) (xy 308.541526 -57.330647) (xy 308.504309 -57.372184)
			(xy 308.461441 -57.407859) (xy 308.413835 -57.436913) (xy 308.362506 -57.458725) (xy 308.308549 -57.472831)
			(xy 308.253112 -57.478931) (xy 308.197378 -57.476894) (xy 308.142535 -57.466764) (xy 308.089751 -57.448757)
			(xy 308.040151 -57.423256) (xy 307.994793 -57.390805) (xy 307.954644 -57.352096) (xy 307.920558 -57.307953)
			(xy 307.893262 -57.259318) (xy 307.873339 -57.207227) (xy 307.861213 -57.15279) (xy 307.857142 -57.097168)
			(xy 307.726345 -57.097168) (xy 307.718147 -57.124417) (xy 307.694475 -57.174914) (xy 307.663702 -57.221427)
			(xy 307.626485 -57.262964) (xy 307.583617 -57.298639) (xy 307.536011 -57.327693) (xy 307.484682 -57.349505)
			(xy 307.430725 -57.363611) (xy 307.375288 -57.369711) (xy 307.319554 -57.367674) (xy 307.264711 -57.357544)
			(xy 307.211927 -57.339537) (xy 307.162327 -57.314036) (xy 307.116969 -57.281585) (xy 307.07682 -57.242876)
			(xy 307.042734 -57.198733) (xy 307.015438 -57.150098) (xy 306.995515 -57.098007) (xy 306.983389 -57.04357)
			(xy 306.979318 -56.987948) (xy 306.86047 -56.987948) (xy 306.864519 -57.001406) (xy 306.872639 -57.056582)
			(xy 306.873148 -57.084468) (xy 306.872639 -57.112354) (xy 306.864519 -57.16753) (xy 306.848451 -57.220937)
			(xy 306.824779 -57.271434) (xy 306.794006 -57.317947) (xy 306.756789 -57.359484) (xy 306.713921 -57.395159)
			(xy 306.666315 -57.424213) (xy 306.614986 -57.446025) (xy 306.561029 -57.460131) (xy 306.505592 -57.466231)
			(xy 306.449858 -57.464194) (xy 306.395015 -57.454064) (xy 306.342231 -57.436057) (xy 306.292631 -57.410556)
			(xy 306.247273 -57.378105) (xy 306.207124 -57.339396) (xy 306.173038 -57.295253) (xy 306.145742 -57.246618)
			(xy 306.125819 -57.194527) (xy 306.113693 -57.14009) (xy 306.109622 -57.084468) (xy 302.127656 -57.084468)
			(xy 302.169549 -57.119332) (xy 302.206766 -57.160869) (xy 302.237539 -57.207382) (xy 302.261211 -57.257879)
			(xy 302.277279 -57.311286) (xy 302.285399 -57.366462) (xy 302.285908 -57.394348) (xy 302.285399 -57.422234)
			(xy 302.277279 -57.47741) (xy 302.261211 -57.530817) (xy 302.237539 -57.581314) (xy 302.206766 -57.627827)
			(xy 302.169549 -57.669364) (xy 302.126681 -57.705039) (xy 302.079075 -57.734093) (xy 302.027746 -57.755905)
			(xy 301.973789 -57.770011) (xy 301.918352 -57.776111) (xy 301.862618 -57.774074) (xy 301.807775 -57.763944)
			(xy 301.754991 -57.745937) (xy 301.705391 -57.720436) (xy 301.660033 -57.687985) (xy 301.619884 -57.649276)
			(xy 301.585798 -57.605133) (xy 301.558502 -57.556498) (xy 301.538579 -57.504407) (xy 301.526453 -57.44997)
			(xy 301.522382 -57.394348) (xy 290.877028 -57.394348) (xy 290.920999 -57.422605) (xy 290.96219 -57.458294)
			(xy 290.997882 -57.499483) (xy 291.027349 -57.545332) (xy 291.049991 -57.594908) (xy 291.065346 -57.647202)
			(xy 291.073103 -57.701149) (xy 291.073103 -57.755651) (xy 291.065346 -57.809598) (xy 291.049991 -57.861892)
			(xy 291.027349 -57.911468) (xy 290.997882 -57.957317) (xy 290.96219 -57.998506) (xy 290.920999 -58.034195)
			(xy 290.875148 -58.06366) (xy 290.825571 -58.086298) (xy 290.773276 -58.101651) (xy 290.719329 -58.109404)
			(xy 290.692078 -58.109866) (xy 290.664707 -58.109421) (xy 290.610527 -58.101599) (xy 290.558023 -58.086106)
			(xy 290.508276 -58.063259) (xy 290.462311 -58.03353) (xy 290.44138 -58.015886) (xy 290.430052 -58.00665)
			(xy 290.403495 -57.994474) (xy 290.374578 -57.990301) (xy 290.345661 -57.994474) (xy 290.319104 -58.00665)
			(xy 290.307776 -58.015886) (xy 290.286843 -58.033527) (xy 290.240875 -58.063251) (xy 290.191129 -58.086097)
			(xy 290.138627 -58.101593) (xy 290.084449 -58.109422) (xy 290.029707 -58.109422) (xy 289.975529 -58.101593)
			(xy 289.923027 -58.086097) (xy 289.873281 -58.063251) (xy 289.827313 -58.033527) (xy 289.80638 -58.015886)
			(xy 289.795052 -58.00665) (xy 289.768495 -57.994474) (xy 289.739578 -57.990301) (xy 289.710661 -57.994474)
			(xy 289.684104 -58.00665) (xy 289.672776 -58.015886) (xy 289.651824 -58.033501) (xy 289.605857 -58.063217)
			(xy 289.556115 -58.086058) (xy 289.503618 -58.101554) (xy 289.449446 -58.109389) (xy 289.422078 -58.109866)
			(xy 289.394825 -58.109463) (xy 289.340873 -58.101703) (xy 289.288576 -58.086344) (xy 289.238996 -58.063699)
			(xy 289.193143 -58.034229) (xy 289.151951 -57.998534) (xy 289.116258 -57.957339) (xy 289.08679 -57.911485)
			(xy 289.064148 -57.861904) (xy 289.048793 -57.809605) (xy 289.041036 -57.755653) (xy 279.115221 -57.755653)
			(xy 279.012904 -58.002678) (xy 279.000316 -58.031266) (xy 278.965651 -58.083219) (xy 278.94407 -58.105802)
			(xy 278.601932 -58.44794) (xy 290.872162 -58.44794) (xy 290.876233 -58.392318) (xy 290.888359 -58.337881)
			(xy 290.908282 -58.28579) (xy 290.935578 -58.237155) (xy 290.969664 -58.193012) (xy 291.009813 -58.154303)
			(xy 291.055171 -58.121852) (xy 291.104771 -58.096351) (xy 291.157555 -58.078344) (xy 291.212398 -58.068214)
			(xy 291.268132 -58.066177) (xy 291.323569 -58.072277) (xy 291.377526 -58.086383) (xy 291.428855 -58.108195)
			(xy 291.476461 -58.137249) (xy 291.519329 -58.172924) (xy 291.556546 -58.214461) (xy 291.587319 -58.260974)
			(xy 291.610991 -58.311471) (xy 291.627059 -58.364878) (xy 291.635179 -58.420054) (xy 291.635688 -58.44794)
			(xy 291.63547 -58.459878) (xy 293.79367 -58.459878) (xy 293.797741 -58.404256) (xy 293.809867 -58.349819)
			(xy 293.82979 -58.297728) (xy 293.857086 -58.249093) (xy 293.891172 -58.20495) (xy 293.931321 -58.166241)
			(xy 293.976679 -58.13379) (xy 294.026279 -58.108289) (xy 294.079063 -58.090282) (xy 294.133906 -58.080152)
			(xy 294.18964 -58.078115) (xy 294.245077 -58.084215) (xy 294.299034 -58.098321) (xy 294.350363 -58.120133)
			(xy 294.397969 -58.149187) (xy 294.440837 -58.184862) (xy 294.478054 -58.226399) (xy 294.508827 -58.272912)
			(xy 294.532499 -58.323409) (xy 294.548567 -58.376816) (xy 294.556687 -58.431992) (xy 294.557196 -58.459878)
			(xy 294.556687 -58.487764) (xy 294.553128 -58.511948) (xy 315.777372 -58.511948) (xy 315.777904 -58.482773)
			(xy 315.786796 -58.425106) (xy 315.804364 -58.369464) (xy 315.830199 -58.317146) (xy 315.863699 -58.269371)
			(xy 315.904082 -58.227254) (xy 315.950407 -58.191777) (xy 316.001594 -58.163766) (xy 316.028832 -58.1533)
			(xy 316.041333 -58.148371) (xy 316.063314 -58.132924) (xy 316.080507 -58.11228) (xy 316.091722 -58.087867)
			(xy 316.096185 -58.061374) (xy 316.093586 -58.034635) (xy 316.084105 -58.009497) (xy 316.076584 -57.99836)
			(xy 316.059604 -57.973869) (xy 316.032677 -57.920707) (xy 316.014341 -57.864006) (xy 316.00504 -57.805144)
			(xy 316.004448 -57.775348) (xy 316.004934 -57.748097) (xy 316.01269 -57.694149) (xy 316.028045 -57.641854)
			(xy 316.050687 -57.592277) (xy 316.080153 -57.546427) (xy 316.115844 -57.505236) (xy 316.157035 -57.469545)
			(xy 316.202885 -57.440079) (xy 316.252462 -57.417437) (xy 316.304757 -57.402082) (xy 316.358705 -57.394326)
			(xy 316.413207 -57.394326) (xy 316.431027 -57.396888) (xy 318.792604 -57.396888) (xy 318.796675 -57.341266)
			(xy 318.808801 -57.286829) (xy 318.828724 -57.234738) (xy 318.85602 -57.186103) (xy 318.890106 -57.14196)
			(xy 318.930255 -57.103251) (xy 318.975613 -57.0708) (xy 319.025213 -57.045299) (xy 319.077997 -57.027292)
			(xy 319.13284 -57.017162) (xy 319.188574 -57.015125) (xy 319.244011 -57.021225) (xy 319.297968 -57.035331)
			(xy 319.349297 -57.057143) (xy 319.396903 -57.086197) (xy 319.439771 -57.121872) (xy 319.476988 -57.163409)
			(xy 319.507761 -57.209922) (xy 319.525156 -57.247028) (xy 321.592954 -57.247028) (xy 321.597025 -57.191406)
			(xy 321.609151 -57.136969) (xy 321.629074 -57.084878) (xy 321.65637 -57.036243) (xy 321.690456 -56.9921)
			(xy 321.730605 -56.953391) (xy 321.775963 -56.92094) (xy 321.825563 -56.895439) (xy 321.878347 -56.877432)
			(xy 321.93319 -56.867302) (xy 321.988924 -56.865265) (xy 322.044361 -56.871365) (xy 322.098318 -56.885471)
			(xy 322.149647 -56.907283) (xy 322.197253 -56.936337) (xy 322.240121 -56.972012) (xy 322.277338 -57.013549)
			(xy 322.308111 -57.060062) (xy 322.331783 -57.110559) (xy 322.347851 -57.163966) (xy 322.355971 -57.219142)
			(xy 322.35648 -57.247028) (xy 322.355971 -57.274914) (xy 322.348749 -57.32399) (xy 324.143876 -57.32399)
			(xy 324.147947 -57.268368) (xy 324.160073 -57.213931) (xy 324.179996 -57.16184) (xy 324.207292 -57.113205)
			(xy 324.241378 -57.069062) (xy 324.281527 -57.030353) (xy 324.326885 -56.997902) (xy 324.376485 -56.972401)
			(xy 324.429269 -56.954394) (xy 324.484112 -56.944264) (xy 324.539846 -56.942227) (xy 324.595283 -56.948327)
			(xy 324.64924 -56.962433) (xy 324.700569 -56.984245) (xy 324.748175 -57.013299) (xy 324.791043 -57.048974)
			(xy 324.82826 -57.090511) (xy 324.859033 -57.137024) (xy 324.882705 -57.187521) (xy 324.898773 -57.240928)
			(xy 324.906893 -57.296104) (xy 324.907402 -57.32399) (xy 324.906893 -57.351876) (xy 324.898773 -57.407052)
			(xy 324.882705 -57.460459) (xy 324.872379 -57.482486) (xy 325.421 -57.482486) (xy 325.424976 -57.42816)
			(xy 325.436819 -57.374991) (xy 325.456278 -57.324114) (xy 325.482938 -57.276612) (xy 325.516229 -57.233498)
			(xy 325.555443 -57.195691) (xy 325.599745 -57.163996) (xy 325.648188 -57.13909) (xy 325.699742 -57.121502)
			(xy 325.753308 -57.111608) (xy 325.807743 -57.109618) (xy 325.861888 -57.115576) (xy 325.914588 -57.129354)
			(xy 325.964721 -57.150658) (xy 326.011217 -57.179034) (xy 326.053087 -57.213878) (xy 326.089436 -57.254447)
			(xy 326.119492 -57.299876) (xy 326.142613 -57.349197) (xy 326.158306 -57.401359) (xy 326.166237 -57.45525)
			(xy 326.166734 -57.482486) (xy 326.166237 -57.509722) (xy 326.158306 -57.563613) (xy 326.142613 -57.615775)
			(xy 326.119492 -57.665096) (xy 326.089436 -57.710525) (xy 326.053087 -57.751094) (xy 326.011217 -57.785938)
			(xy 325.964721 -57.814314) (xy 325.914588 -57.835618) (xy 325.861888 -57.849396) (xy 325.807743 -57.855354)
			(xy 325.753308 -57.853364) (xy 325.699742 -57.84347) (xy 325.648188 -57.825882) (xy 325.599745 -57.800976)
			(xy 325.555443 -57.769281) (xy 325.516229 -57.731474) (xy 325.482938 -57.68836) (xy 325.456278 -57.640858)
			(xy 325.436819 -57.589981) (xy 325.424976 -57.536812) (xy 325.421 -57.482486) (xy 324.872379 -57.482486)
			(xy 324.859033 -57.510956) (xy 324.82826 -57.557469) (xy 324.791043 -57.599006) (xy 324.748175 -57.634681)
			(xy 324.700569 -57.663735) (xy 324.64924 -57.685547) (xy 324.595283 -57.699653) (xy 324.539846 -57.705753)
			(xy 324.484112 -57.703716) (xy 324.429269 -57.693586) (xy 324.376485 -57.675579) (xy 324.326885 -57.650078)
			(xy 324.281527 -57.617627) (xy 324.241378 -57.578918) (xy 324.207292 -57.534775) (xy 324.179996 -57.48614)
			(xy 324.160073 -57.434049) (xy 324.147947 -57.379612) (xy 324.143876 -57.32399) (xy 322.348749 -57.32399)
			(xy 322.347851 -57.33009) (xy 322.331783 -57.383497) (xy 322.308111 -57.433994) (xy 322.277338 -57.480507)
			(xy 322.240121 -57.522044) (xy 322.197253 -57.557719) (xy 322.149647 -57.586773) (xy 322.098318 -57.608585)
			(xy 322.044361 -57.622691) (xy 321.988924 -57.628791) (xy 321.93319 -57.626754) (xy 321.878347 -57.616624)
			(xy 321.825563 -57.598617) (xy 321.775963 -57.573116) (xy 321.730605 -57.540665) (xy 321.690456 -57.501956)
			(xy 321.65637 -57.457813) (xy 321.629074 -57.409178) (xy 321.609151 -57.357087) (xy 321.597025 -57.30265)
			(xy 321.592954 -57.247028) (xy 319.525156 -57.247028) (xy 319.531433 -57.260419) (xy 319.547501 -57.313826)
			(xy 319.555621 -57.369002) (xy 319.55613 -57.396888) (xy 319.555621 -57.424774) (xy 319.547501 -57.47995)
			(xy 319.531433 -57.533357) (xy 319.507761 -57.583854) (xy 319.476988 -57.630367) (xy 319.439771 -57.671904)
			(xy 319.396903 -57.707579) (xy 319.349297 -57.736633) (xy 319.297968 -57.758445) (xy 319.244011 -57.772551)
			(xy 319.188574 -57.778651) (xy 319.13284 -57.776614) (xy 319.077997 -57.766484) (xy 319.025213 -57.748477)
			(xy 318.975613 -57.722976) (xy 318.930255 -57.690525) (xy 318.890106 -57.651816) (xy 318.85602 -57.607673)
			(xy 318.828724 -57.559038) (xy 318.808801 -57.506947) (xy 318.796675 -57.45251) (xy 318.792604 -57.396888)
			(xy 316.431027 -57.396888) (xy 316.467155 -57.402082) (xy 316.51945 -57.417437) (xy 316.569027 -57.440079)
			(xy 316.614877 -57.469545) (xy 316.656068 -57.505236) (xy 316.691759 -57.546427) (xy 316.721225 -57.592277)
			(xy 316.743867 -57.641854) (xy 316.759222 -57.694149) (xy 316.766978 -57.748097) (xy 316.767464 -57.775348)
			(xy 316.766905 -57.804521) (xy 316.758015 -57.862187) (xy 316.740449 -57.917826) (xy 316.714617 -57.970143)
			(xy 316.681121 -58.017917) (xy 316.640742 -58.060035) (xy 316.594422 -58.095514) (xy 316.54324 -58.123528)
			(xy 316.516004 -58.133996) (xy 316.503509 -58.138942) (xy 316.481525 -58.154383) (xy 316.464329 -58.175023)
			(xy 316.45311 -58.199434) (xy 316.448646 -58.225926) (xy 316.451246 -58.252665) (xy 316.460729 -58.2778)
			(xy 316.468252 -58.288936) (xy 316.485235 -58.313425) (xy 316.51216 -58.366588) (xy 316.530495 -58.42329)
			(xy 316.539795 -58.482152) (xy 316.540388 -58.511948) (xy 316.539902 -58.539199) (xy 316.532965 -58.587449)
			(xy 317.992786 -58.587449) (xy 317.992786 -58.532951) (xy 318.000541 -58.479008) (xy 318.015894 -58.426718)
			(xy 318.038531 -58.377144) (xy 318.067993 -58.331297) (xy 318.10368 -58.290108) (xy 318.144864 -58.254417)
			(xy 318.190709 -58.224951) (xy 318.24028 -58.202308) (xy 318.292569 -58.186949) (xy 318.346511 -58.179188)
			(xy 318.37376 -58.1787) (xy 318.403128 -58.179226) (xy 318.461174 -58.188197) (xy 318.517152 -58.20598)
			(xy 318.543686 -58.218578) (xy 318.556591 -58.224561) (xy 318.584552 -58.229747) (xy 318.612858 -58.227016)
			(xy 318.639312 -58.216579) (xy 318.661858 -58.199247) (xy 318.678745 -58.176367) (xy 318.684148 -58.163206)
			(xy 318.69479 -58.136236) (xy 318.722961 -58.085567) (xy 318.758475 -58.039743) (xy 318.800515 -57.999821)
			(xy 318.848111 -57.966721) (xy 318.900168 -57.941203) (xy 318.955486 -57.923857) (xy 319.012793 -57.915081)
			(xy 319.04178 -57.91454) (xy 319.069037 -57.914906) (xy 319.122997 -57.922661) (xy 319.175304 -57.938017)
			(xy 319.224893 -57.960662) (xy 319.270754 -57.990133) (xy 319.311955 -58.025831) (xy 319.347655 -58.06703)
			(xy 319.377129 -58.112889) (xy 319.399776 -58.162477) (xy 319.415135 -58.214783) (xy 319.422893 -58.268743)
			(xy 319.422893 -58.283348) (xy 321.586604 -58.283348) (xy 321.590675 -58.227726) (xy 321.602801 -58.173289)
			(xy 321.622724 -58.121198) (xy 321.65002 -58.072563) (xy 321.684106 -58.02842) (xy 321.724255 -57.989711)
			(xy 321.769613 -57.95726) (xy 321.819213 -57.931759) (xy 321.871997 -57.913752) (xy 321.92684 -57.903622)
			(xy 321.982574 -57.901585) (xy 322.038011 -57.907685) (xy 322.091968 -57.921791) (xy 322.143297 -57.943603)
			(xy 322.190903 -57.972657) (xy 322.233771 -58.008332) (xy 322.270988 -58.049869) (xy 322.301761 -58.096382)
			(xy 322.325433 -58.146879) (xy 322.341501 -58.200286) (xy 322.349621 -58.255462) (xy 322.35013 -58.283348)
			(xy 322.349621 -58.311234) (xy 322.341501 -58.36641) (xy 322.325433 -58.419817) (xy 322.301761 -58.470314)
			(xy 322.287996 -58.49112) (xy 325.86498 -58.49112) (xy 325.869051 -58.435498) (xy 325.881177 -58.381061)
			(xy 325.9011 -58.32897) (xy 325.928396 -58.280335) (xy 325.962482 -58.236192) (xy 326.002631 -58.197483)
			(xy 326.047989 -58.165032) (xy 326.097589 -58.139531) (xy 326.150373 -58.121524) (xy 326.205216 -58.111394)
			(xy 326.26095 -58.109357) (xy 326.316387 -58.115457) (xy 326.370344 -58.129563) (xy 326.421673 -58.151375)
			(xy 326.469279 -58.180429) (xy 326.512147 -58.216104) (xy 326.549364 -58.257641) (xy 326.580137 -58.304154)
			(xy 326.603809 -58.354651) (xy 326.619877 -58.408058) (xy 326.627997 -58.463234) (xy 326.628506 -58.49112)
			(xy 326.627997 -58.519006) (xy 326.619877 -58.574182) (xy 326.603809 -58.627589) (xy 326.580137 -58.678086)
			(xy 326.549364 -58.724599) (xy 326.512147 -58.766136) (xy 326.469279 -58.801811) (xy 326.421673 -58.830865)
			(xy 326.370344 -58.852677) (xy 326.316387 -58.866783) (xy 326.26095 -58.872883) (xy 326.205216 -58.870846)
			(xy 326.150373 -58.860716) (xy 326.097589 -58.842709) (xy 326.047989 -58.817208) (xy 326.002631 -58.784757)
			(xy 325.962482 -58.746048) (xy 325.928396 -58.701905) (xy 325.9011 -58.65327) (xy 325.881177 -58.601179)
			(xy 325.869051 -58.546742) (xy 325.86498 -58.49112) (xy 322.287996 -58.49112) (xy 322.270988 -58.516827)
			(xy 322.233771 -58.558364) (xy 322.190903 -58.594039) (xy 322.143297 -58.623093) (xy 322.091968 -58.644905)
			(xy 322.038011 -58.659011) (xy 321.982574 -58.665111) (xy 321.92684 -58.663074) (xy 321.871997 -58.652944)
			(xy 321.819213 -58.634937) (xy 321.769613 -58.609436) (xy 321.724255 -58.576985) (xy 321.684106 -58.538276)
			(xy 321.65002 -58.494133) (xy 321.622724 -58.445498) (xy 321.602801 -58.393407) (xy 321.590675 -58.33897)
			(xy 321.586604 -58.283348) (xy 319.422893 -58.283348) (xy 319.422893 -58.323257) (xy 319.415135 -58.377217)
			(xy 319.399776 -58.429523) (xy 319.377129 -58.479111) (xy 319.347655 -58.52497) (xy 319.311955 -58.566169)
			(xy 319.270754 -58.601867) (xy 319.224893 -58.631338) (xy 319.175304 -58.653983) (xy 319.122997 -58.669339)
			(xy 319.069037 -58.677094) (xy 319.04178 -58.677556) (xy 319.012411 -58.677047) (xy 318.954365 -58.668068)
			(xy 318.898387 -58.650279) (xy 318.871854 -58.637678) (xy 318.85892 -58.631766) (xy 318.830973 -58.626576)
			(xy 318.802678 -58.629298) (xy 318.776233 -58.639721) (xy 318.75369 -58.657035) (xy 318.736799 -58.679898)
			(xy 318.731392 -58.69305) (xy 318.720831 -58.720053) (xy 318.692646 -58.770723) (xy 318.65712 -58.816546)
			(xy 318.615068 -58.856465) (xy 318.567461 -58.889561) (xy 318.515393 -58.915073) (xy 318.460065 -58.932412)
			(xy 318.402751 -58.941179) (xy 318.37376 -58.941716) (xy 318.346511 -58.941212) (xy 318.292569 -58.933451)
			(xy 318.24028 -58.918092) (xy 318.190709 -58.895449) (xy 318.144864 -58.865983) (xy 318.10368 -58.830292)
			(xy 318.067993 -58.789103) (xy 318.038531 -58.743256) (xy 318.015894 -58.693682) (xy 318.000541 -58.641392)
			(xy 317.992786 -58.587449) (xy 316.532965 -58.587449) (xy 316.532146 -58.593147) (xy 316.516791 -58.645442)
			(xy 316.494149 -58.695019) (xy 316.464683 -58.740869) (xy 316.428992 -58.78206) (xy 316.387801 -58.817751)
			(xy 316.341951 -58.847217) (xy 316.292374 -58.869859) (xy 316.240079 -58.885214) (xy 316.186131 -58.89297)
			(xy 316.131629 -58.89297) (xy 316.077681 -58.885214) (xy 316.025386 -58.869859) (xy 315.975809 -58.847217)
			(xy 315.929959 -58.817751) (xy 315.888768 -58.78206) (xy 315.853077 -58.740869) (xy 315.823611 -58.695019)
			(xy 315.800969 -58.645442) (xy 315.785614 -58.593147) (xy 315.777858 -58.539199) (xy 315.777372 -58.511948)
			(xy 294.553128 -58.511948) (xy 294.548567 -58.54294) (xy 294.532499 -58.596347) (xy 294.508827 -58.646844)
			(xy 294.478054 -58.693357) (xy 294.440837 -58.734894) (xy 294.397969 -58.770569) (xy 294.350363 -58.799623)
			(xy 294.299034 -58.821435) (xy 294.245077 -58.835541) (xy 294.18964 -58.841641) (xy 294.133906 -58.839604)
			(xy 294.079063 -58.829474) (xy 294.026279 -58.811467) (xy 293.976679 -58.785966) (xy 293.931321 -58.753515)
			(xy 293.891172 -58.714806) (xy 293.857086 -58.670663) (xy 293.82979 -58.622028) (xy 293.809867 -58.569937)
			(xy 293.797741 -58.5155) (xy 293.79367 -58.459878) (xy 291.63547 -58.459878) (xy 291.635179 -58.475826)
			(xy 291.627059 -58.531002) (xy 291.610991 -58.584409) (xy 291.587319 -58.634906) (xy 291.556546 -58.681419)
			(xy 291.519329 -58.722956) (xy 291.476461 -58.758631) (xy 291.428855 -58.787685) (xy 291.377526 -58.809497)
			(xy 291.323569 -58.823603) (xy 291.268132 -58.829703) (xy 291.212398 -58.827666) (xy 291.157555 -58.817536)
			(xy 291.104771 -58.799529) (xy 291.055171 -58.774028) (xy 291.009813 -58.741577) (xy 290.969664 -58.702868)
			(xy 290.935578 -58.658725) (xy 290.908282 -58.61009) (xy 290.888359 -58.557999) (xy 290.876233 -58.503562)
			(xy 290.872162 -58.44794) (xy 278.601932 -58.44794) (xy 277.603204 -59.446668) (xy 315.993778 -59.446668)
			(xy 315.997849 -59.391046) (xy 316.009975 -59.336609) (xy 316.029898 -59.284518) (xy 316.057194 -59.235883)
			(xy 316.09128 -59.19174) (xy 316.131429 -59.153031) (xy 316.176787 -59.12058) (xy 316.226387 -59.095079)
			(xy 316.279171 -59.077072) (xy 316.334014 -59.066942) (xy 316.389748 -59.064905) (xy 316.445185 -59.071005)
			(xy 316.499142 -59.085111) (xy 316.550471 -59.106923) (xy 316.598077 -59.135977) (xy 316.640945 -59.171652)
			(xy 316.678162 -59.213189) (xy 316.708935 -59.259702) (xy 316.732607 -59.310199) (xy 316.748675 -59.363606)
			(xy 316.756795 -59.418782) (xy 316.757304 -59.446668) (xy 316.756795 -59.474554) (xy 316.748675 -59.52973)
			(xy 316.732607 -59.583137) (xy 316.708935 -59.633634) (xy 316.678162 -59.680147) (xy 316.640945 -59.721684)
			(xy 316.598077 -59.757359) (xy 316.550471 -59.786413) (xy 316.499142 -59.808225) (xy 316.445185 -59.822331)
			(xy 316.389748 -59.828431) (xy 316.334014 -59.826394) (xy 316.279171 -59.816264) (xy 316.226387 -59.798257)
			(xy 316.176787 -59.772756) (xy 316.131429 -59.740305) (xy 316.09128 -59.701596) (xy 316.057194 -59.657453)
			(xy 316.029898 -59.608818) (xy 316.009975 -59.556727) (xy 315.997849 -59.50229) (xy 315.993778 -59.446668)
			(xy 277.603204 -59.446668) (xy 276.955504 -60.094368) (xy 303.107342 -60.094368) (xy 303.111413 -60.038746)
			(xy 303.123539 -59.984309) (xy 303.143462 -59.932218) (xy 303.170758 -59.883583) (xy 303.204844 -59.83944)
			(xy 303.244993 -59.800731) (xy 303.290351 -59.76828) (xy 303.339951 -59.742779) (xy 303.392735 -59.724772)
			(xy 303.447578 -59.714642) (xy 303.503312 -59.712605) (xy 303.558749 -59.718705) (xy 303.612706 -59.732811)
			(xy 303.664035 -59.754623) (xy 303.711641 -59.783677) (xy 303.754509 -59.819352) (xy 303.791726 -59.860889)
			(xy 303.801231 -59.875256) (xy 318.099343 -59.875256) (xy 318.099343 -59.820744) (xy 318.107101 -59.766788)
			(xy 318.12246 -59.714485) (xy 318.145106 -59.664901) (xy 318.174579 -59.619045) (xy 318.210278 -59.577849)
			(xy 318.251477 -59.542155) (xy 318.297336 -59.512687) (xy 318.346923 -59.490046) (xy 318.399227 -59.474693)
			(xy 318.453184 -59.46694) (xy 318.48044 -59.46648) (xy 318.509238 -59.466988) (xy 318.566181 -59.475635)
			(xy 318.621183 -59.492728) (xy 318.647318 -59.504834) (xy 318.660535 -59.510779) (xy 318.689102 -59.515611)
			(xy 318.717878 -59.512236) (xy 318.744552 -59.500925) (xy 318.766982 -59.482585) (xy 318.783366 -59.45869)
			(xy 318.79239 -59.431158) (xy 318.793368 -59.416696) (xy 318.794666 -59.390027) (xy 318.803787 -59.337419)
			(xy 318.820155 -59.286598) (xy 318.843451 -59.238555) (xy 318.873219 -59.194231) (xy 318.908878 -59.154492)
			(xy 318.949731 -59.120114) (xy 318.994979 -59.09177) (xy 319.043738 -59.070013) (xy 319.095054 -59.055269)
			(xy 319.147926 -59.047826) (xy 319.174622 -59.04738) (xy 319.201871 -59.047892) (xy 319.255815 -59.055651)
			(xy 319.308105 -59.071007) (xy 319.357678 -59.093649) (xy 319.403524 -59.123115) (xy 319.444711 -59.158805)
			(xy 319.480399 -59.199993) (xy 319.509862 -59.245841) (xy 319.532501 -59.295415) (xy 319.547854 -59.347707)
			(xy 319.551346 -59.371992) (xy 326.755504 -59.371992) (xy 326.759575 -59.31637) (xy 326.771701 -59.261933)
			(xy 326.791624 -59.209842) (xy 326.81892 -59.161207) (xy 326.853006 -59.117064) (xy 326.893155 -59.078355)
			(xy 326.938513 -59.045904) (xy 326.988113 -59.020403) (xy 327.040897 -59.002396) (xy 327.09574 -58.992266)
			(xy 327.151474 -58.990229) (xy 327.206911 -58.996329) (xy 327.260868 -59.010435) (xy 327.312197 -59.032247)
			(xy 327.359803 -59.061301) (xy 327.402671 -59.096976) (xy 327.439888 -59.138513) (xy 327.470661 -59.185026)
			(xy 327.494333 -59.235523) (xy 327.510401 -59.28893) (xy 327.518521 -59.344106) (xy 327.51903 -59.371992)
			(xy 327.518521 -59.399878) (xy 327.510401 -59.455054) (xy 327.494333 -59.508461) (xy 327.470661 -59.558958)
			(xy 327.439888 -59.605471) (xy 327.402671 -59.647008) (xy 327.359803 -59.682683) (xy 327.312197 -59.711737)
			(xy 327.260868 -59.733549) (xy 327.206911 -59.747655) (xy 327.151474 -59.753755) (xy 327.09574 -59.751718)
			(xy 327.040897 -59.741588) (xy 326.988113 -59.723581) (xy 326.938513 -59.69808) (xy 326.893155 -59.665629)
			(xy 326.853006 -59.62692) (xy 326.81892 -59.582777) (xy 326.791624 -59.534142) (xy 326.771701 -59.482051)
			(xy 326.759575 -59.427614) (xy 326.755504 -59.371992) (xy 319.551346 -59.371992) (xy 319.55561 -59.401651)
			(xy 319.55561 -59.456149) (xy 319.547854 -59.510093) (xy 319.532501 -59.562385) (xy 319.509862 -59.611959)
			(xy 319.480399 -59.657807) (xy 319.444711 -59.698995) (xy 319.403524 -59.734685) (xy 319.357678 -59.764151)
			(xy 319.308105 -59.786793) (xy 319.255815 -59.802149) (xy 319.201871 -59.809908) (xy 319.174622 -59.810396)
			(xy 319.145825 -59.809858) (xy 319.088883 -59.801222) (xy 319.033881 -59.784141) (xy 319.007744 -59.772042)
			(xy 318.994488 -59.766193) (xy 318.965937 -59.761351) (xy 318.937175 -59.764713) (xy 318.910511 -59.776009)
			(xy 318.888086 -59.794332) (xy 318.871702 -59.81821) (xy 318.862675 -59.845725) (xy 318.861694 -59.86018)
			(xy 318.860412 -59.88685) (xy 318.851294 -59.939461) (xy 318.834926 -59.990285) (xy 318.81163 -60.03833)
			(xy 318.781861 -60.082656) (xy 318.7462 -60.122396) (xy 318.705344 -60.156774) (xy 318.660093 -60.185118)
			(xy 318.611331 -60.206873) (xy 318.605082 -60.208668) (xy 321.313554 -60.208668) (xy 321.317625 -60.153046)
			(xy 321.329751 -60.098609) (xy 321.349674 -60.046518) (xy 321.37697 -59.997883) (xy 321.411056 -59.95374)
			(xy 321.451205 -59.915031) (xy 321.496563 -59.88258) (xy 321.546163 -59.857079) (xy 321.598947 -59.839072)
			(xy 321.65379 -59.828942) (xy 321.709524 -59.826905) (xy 321.764961 -59.833005) (xy 321.818918 -59.847111)
			(xy 321.870247 -59.868923) (xy 321.917853 -59.897977) (xy 321.960721 -59.933652) (xy 321.997938 -59.975189)
			(xy 322.028711 -60.021702) (xy 322.052383 -60.072199) (xy 322.068451 -60.125606) (xy 322.076571 -60.180782)
			(xy 322.07708 -60.208668) (xy 322.076571 -60.236554) (xy 322.068451 -60.29173) (xy 322.052383 -60.345137)
			(xy 322.028711 -60.395634) (xy 321.997938 -60.442147) (xy 321.960721 -60.483684) (xy 321.917853 -60.519359)
			(xy 321.870247 -60.548413) (xy 321.818918 -60.570225) (xy 321.764961 -60.584331) (xy 321.709524 -60.590431)
			(xy 321.65379 -60.588394) (xy 321.598947 -60.578264) (xy 321.546163 -60.560257) (xy 321.496563 -60.534756)
			(xy 321.451205 -60.502305) (xy 321.411056 -60.463596) (xy 321.37697 -60.419453) (xy 321.349674 -60.370818)
			(xy 321.329751 -60.318727) (xy 321.317625 -60.26429) (xy 321.313554 -60.208668) (xy 318.605082 -60.208668)
			(xy 318.560012 -60.221614) (xy 318.507137 -60.229053) (xy 318.48044 -60.229496) (xy 318.453184 -60.22906)
			(xy 318.399227 -60.221307) (xy 318.346923 -60.205954) (xy 318.297336 -60.183313) (xy 318.251477 -60.153845)
			(xy 318.210278 -60.118151) (xy 318.174579 -60.076955) (xy 318.145106 -60.031099) (xy 318.12246 -59.981515)
			(xy 318.107101 -59.929212) (xy 318.099343 -59.875256) (xy 303.801231 -59.875256) (xy 303.822499 -59.907402)
			(xy 303.846171 -59.957899) (xy 303.862239 -60.011306) (xy 303.870359 -60.066482) (xy 303.870868 -60.094368)
			(xy 303.870359 -60.122254) (xy 303.862239 -60.17743) (xy 303.846171 -60.230837) (xy 303.822499 -60.281334)
			(xy 303.799995 -60.315348) (xy 315.998604 -60.315348) (xy 316.002675 -60.259726) (xy 316.014801 -60.205289)
			(xy 316.034724 -60.153198) (xy 316.06202 -60.104563) (xy 316.096106 -60.06042) (xy 316.136255 -60.021711)
			(xy 316.181613 -59.98926) (xy 316.231213 -59.963759) (xy 316.283997 -59.945752) (xy 316.33884 -59.935622)
			(xy 316.394574 -59.933585) (xy 316.450011 -59.939685) (xy 316.503968 -59.953791) (xy 316.555297 -59.975603)
			(xy 316.602903 -60.004657) (xy 316.645771 -60.040332) (xy 316.682988 -60.081869) (xy 316.713761 -60.128382)
			(xy 316.737433 -60.178879) (xy 316.753501 -60.232286) (xy 316.761621 -60.287462) (xy 316.76213 -60.315348)
			(xy 316.761621 -60.343234) (xy 316.753501 -60.39841) (xy 316.737433 -60.451817) (xy 316.713761 -60.502314)
			(xy 316.682988 -60.548827) (xy 316.645771 -60.590364) (xy 316.609982 -60.620148) (xy 318.787778 -60.620148)
			(xy 318.791849 -60.564526) (xy 318.803975 -60.510089) (xy 318.823898 -60.457998) (xy 318.851194 -60.409363)
			(xy 318.88528 -60.36522) (xy 318.925429 -60.326511) (xy 318.970787 -60.29406) (xy 319.020387 -60.268559)
			(xy 319.073171 -60.250552) (xy 319.128014 -60.240422) (xy 319.183748 -60.238385) (xy 319.239185 -60.244485)
			(xy 319.293142 -60.258591) (xy 319.344471 -60.280403) (xy 319.392077 -60.309457) (xy 319.434945 -60.345132)
			(xy 319.472162 -60.386669) (xy 319.502935 -60.433182) (xy 319.526607 -60.483679) (xy 319.542675 -60.537086)
			(xy 319.550795 -60.592262) (xy 319.551304 -60.620148) (xy 319.550795 -60.648034) (xy 319.542675 -60.70321)
			(xy 319.526607 -60.756617) (xy 319.502935 -60.807114) (xy 319.472162 -60.853627) (xy 319.434945 -60.895164)
			(xy 319.392077 -60.930839) (xy 319.344471 -60.959893) (xy 319.293142 -60.981705) (xy 319.239185 -60.995811)
			(xy 319.183748 -61.001911) (xy 319.128014 -60.999874) (xy 319.073171 -60.989744) (xy 319.020387 -60.971737)
			(xy 318.970787 -60.946236) (xy 318.925429 -60.913785) (xy 318.88528 -60.875076) (xy 318.851194 -60.830933)
			(xy 318.823898 -60.782298) (xy 318.803975 -60.730207) (xy 318.791849 -60.67577) (xy 318.787778 -60.620148)
			(xy 316.609982 -60.620148) (xy 316.602903 -60.626039) (xy 316.555297 -60.655093) (xy 316.503968 -60.676905)
			(xy 316.450011 -60.691011) (xy 316.394574 -60.697111) (xy 316.33884 -60.695074) (xy 316.283997 -60.684944)
			(xy 316.231213 -60.666937) (xy 316.181613 -60.641436) (xy 316.136255 -60.608985) (xy 316.096106 -60.570276)
			(xy 316.06202 -60.526133) (xy 316.034724 -60.477498) (xy 316.014801 -60.425407) (xy 316.002675 -60.37097)
			(xy 315.998604 -60.315348) (xy 303.799995 -60.315348) (xy 303.791726 -60.327847) (xy 303.754509 -60.369384)
			(xy 303.711641 -60.405059) (xy 303.664035 -60.434113) (xy 303.612706 -60.455925) (xy 303.558749 -60.470031)
			(xy 303.503312 -60.476131) (xy 303.447578 -60.474094) (xy 303.392735 -60.463964) (xy 303.339951 -60.445957)
			(xy 303.290351 -60.420456) (xy 303.244993 -60.388005) (xy 303.204844 -60.349296) (xy 303.170758 -60.305153)
			(xy 303.143462 -60.256518) (xy 303.123539 -60.204427) (xy 303.111413 -60.14999) (xy 303.107342 -60.094368)
			(xy 276.955504 -60.094368) (xy 276.893274 -60.156598) (xy 276.882078 -60.167518) (xy 276.857904 -60.187364)
			(xy 276.845014 -60.196222) (xy 276.192996 -60.631832) (xy 274.559268 -62.26556) (xy 278.771602 -62.26556)
			(xy 278.775673 -62.209938) (xy 278.787799 -62.155501) (xy 278.807722 -62.10341) (xy 278.835018 -62.054775)
			(xy 278.869104 -62.010632) (xy 278.909253 -61.971923) (xy 278.954611 -61.939472) (xy 279.004211 -61.913971)
			(xy 279.056995 -61.895964) (xy 279.111838 -61.885834) (xy 279.167572 -61.883797) (xy 279.223009 -61.889897)
			(xy 279.276966 -61.904003) (xy 279.328295 -61.925815) (xy 279.375901 -61.954869) (xy 279.418769 -61.990544)
			(xy 279.455986 -62.032081) (xy 279.486759 -62.078594) (xy 279.510431 -62.129091) (xy 279.526499 -62.182498)
			(xy 279.534619 -62.237674) (xy 279.535128 -62.26556) (xy 279.534619 -62.293446) (xy 279.526499 -62.348622)
			(xy 279.510431 -62.402029) (xy 279.486759 -62.452526) (xy 279.455986 -62.499039) (xy 279.418769 -62.540576)
			(xy 279.375901 -62.576251) (xy 279.328295 -62.605305) (xy 279.276966 -62.627117) (xy 279.223009 -62.641223)
			(xy 279.167572 -62.647323) (xy 279.111838 -62.645286) (xy 279.056995 -62.635156) (xy 279.004211 -62.617149)
			(xy 278.954611 -62.591648) (xy 278.909253 -62.559197) (xy 278.869104 -62.520488) (xy 278.835018 -62.476345)
			(xy 278.807722 -62.42771) (xy 278.787799 -62.375619) (xy 278.775673 -62.321182) (xy 278.771602 -62.26556)
			(xy 274.559268 -62.26556) (xy 274.49526 -62.329568) (xy 273.74596 -62.329568) (xy 273.02714 -63.048388)
			(xy 273.02714 -63.877952) (xy 278.687789 -63.877952) (xy 278.691811 -63.792232) (xy 278.703842 -63.707264)
			(xy 278.723778 -63.623797) (xy 278.751441 -63.542563) (xy 278.78659 -63.464277) (xy 278.828916 -63.389626)
			(xy 278.878045 -63.319267) (xy 278.933548 -63.253817) (xy 278.994935 -63.193853) (xy 279.061668 -63.1399)
			(xy 279.13316 -63.092433) (xy 279.208782 -63.051869) (xy 279.287871 -63.018565) (xy 279.369731 -62.992813)
			(xy 279.453642 -62.97484) (xy 279.538868 -62.964804) (xy 279.62466 -62.962792) (xy 279.710262 -62.968823)
			(xy 279.794924 -62.982843) (xy 279.877901 -63.004729) (xy 279.958464 -63.03429) (xy 280.035904 -63.071264)
			(xy 280.109543 -63.115328) (xy 280.178731 -63.166094) (xy 280.242862 -63.223115) (xy 280.301371 -63.285891)
			(xy 280.353744 -63.353871) (xy 280.399522 -63.426456) (xy 280.438302 -63.503008) (xy 280.469743 -63.582856)
			(xy 280.493569 -63.665297) (xy 280.50957 -63.749607) (xy 280.517605 -63.835045) (xy 280.518108 -63.877952)
			(xy 280.517605 -63.920859) (xy 280.50957 -64.006297) (xy 280.493569 -64.090607) (xy 280.469743 -64.173048)
			(xy 280.438302 -64.252896) (xy 280.399522 -64.329448) (xy 280.353744 -64.402033) (xy 280.301371 -64.470013)
			(xy 280.242862 -64.532789) (xy 280.178731 -64.58981) (xy 280.109543 -64.640576) (xy 280.035904 -64.68464)
			(xy 279.958464 -64.721614) (xy 279.877901 -64.751175) (xy 279.794924 -64.773061) (xy 279.710262 -64.787081)
			(xy 279.62466 -64.793112) (xy 279.538868 -64.7911) (xy 279.453642 -64.781064) (xy 279.369731 -64.763091)
			(xy 279.287871 -64.737339) (xy 279.208782 -64.704035) (xy 279.13316 -64.663471) (xy 279.061668 -64.616004)
			(xy 278.994935 -64.562051) (xy 278.933548 -64.502087) (xy 278.878045 -64.436637) (xy 278.828916 -64.366278)
			(xy 278.78659 -64.291627) (xy 278.751441 -64.213341) (xy 278.723778 -64.132107) (xy 278.703842 -64.04864)
			(xy 278.691811 -63.963672) (xy 278.687789 -63.877952) (xy 273.02714 -63.877952) (xy 273.02714 -64.935608)
			(xy 284.146242 -64.935608) (xy 284.150313 -64.879986) (xy 284.162439 -64.825549) (xy 284.182362 -64.773458)
			(xy 284.209658 -64.724823) (xy 284.243744 -64.68068) (xy 284.283893 -64.641971) (xy 284.329251 -64.60952)
			(xy 284.378851 -64.584019) (xy 284.431635 -64.566012) (xy 284.486478 -64.555882) (xy 284.542212 -64.553845)
			(xy 284.597649 -64.559945) (xy 284.651606 -64.574051) (xy 284.702935 -64.595863) (xy 284.750541 -64.624917)
			(xy 284.793409 -64.660592) (xy 284.830626 -64.702129) (xy 284.861399 -64.748642) (xy 284.885071 -64.799139)
			(xy 284.901139 -64.852546) (xy 284.909259 -64.907722) (xy 284.909768 -64.935608) (xy 284.909259 -64.963494)
			(xy 284.901139 -65.01867) (xy 284.885071 -65.072077) (xy 284.861399 -65.122574) (xy 284.830626 -65.169087)
			(xy 284.793409 -65.210624) (xy 284.750541 -65.246299) (xy 284.702935 -65.275353) (xy 284.651606 -65.297165)
			(xy 284.597649 -65.311271) (xy 284.542212 -65.317371) (xy 284.486478 -65.315334) (xy 284.431635 -65.305204)
			(xy 284.378851 -65.287197) (xy 284.329251 -65.261696) (xy 284.283893 -65.229245) (xy 284.243744 -65.190536)
			(xy 284.209658 -65.146393) (xy 284.182362 -65.097758) (xy 284.162439 -65.045667) (xy 284.150313 -64.99123)
			(xy 284.146242 -64.935608) (xy 273.02714 -64.935608) (xy 273.02714 -65.920296) (xy 278.714196 -65.920296)
			(xy 278.714196 -65.8356) (xy 278.722247 -65.751286) (xy 278.738276 -65.66812) (xy 278.762137 -65.586853)
			(xy 278.793616 -65.508223) (xy 278.832427 -65.432942) (xy 278.878217 -65.36169) (xy 278.930573 -65.295114)
			(xy 278.989021 -65.233816) (xy 279.053031 -65.178351) (xy 279.122023 -65.129222) (xy 279.195373 -65.086873)
			(xy 279.272416 -65.051689) (xy 279.352455 -65.023987) (xy 279.434764 -65.004019) (xy 279.518599 -64.991966)
			(xy 279.6032 -64.987936) (xy 279.687801 -64.991966) (xy 279.771636 -65.004019) (xy 279.853945 -65.023987)
			(xy 279.933984 -65.051689) (xy 280.011027 -65.086873) (xy 280.084377 -65.129222) (xy 280.153369 -65.178351)
			(xy 280.217379 -65.233816) (xy 280.275827 -65.295114) (xy 280.328183 -65.36169) (xy 280.373973 -65.432942)
			(xy 280.412784 -65.508223) (xy 280.444263 -65.586853) (xy 280.468124 -65.66812) (xy 280.484153 -65.751286)
			(xy 280.492204 -65.8356) (xy 280.492708 -65.877948) (xy 280.492204 -65.920296) (xy 280.487759 -65.966848)
			(xy 285.205422 -65.966848) (xy 285.209493 -65.911226) (xy 285.221619 -65.856789) (xy 285.241542 -65.804698)
			(xy 285.268838 -65.756063) (xy 285.302924 -65.71192) (xy 285.343073 -65.673211) (xy 285.388431 -65.64076)
			(xy 285.438031 -65.615259) (xy 285.490815 -65.597252) (xy 285.545658 -65.587122) (xy 285.601392 -65.585085)
			(xy 285.656829 -65.591185) (xy 285.710786 -65.605291) (xy 285.762115 -65.627103) (xy 285.809721 -65.656157)
			(xy 285.852589 -65.691832) (xy 285.889806 -65.733369) (xy 285.920579 -65.779882) (xy 285.944251 -65.830379)
			(xy 285.960319 -65.883786) (xy 285.968439 -65.938962) (xy 285.968948 -65.966848) (xy 285.968439 -65.994734)
			(xy 285.960319 -66.04991) (xy 285.944251 -66.103317) (xy 285.920579 -66.153814) (xy 285.889806 -66.200327)
			(xy 285.852589 -66.241864) (xy 285.809721 -66.277539) (xy 285.762115 -66.306593) (xy 285.710786 -66.328405)
			(xy 285.656829 -66.342511) (xy 285.601392 -66.348611) (xy 285.545658 -66.346574) (xy 285.490815 -66.336444)
			(xy 285.438031 -66.318437) (xy 285.388431 -66.292936) (xy 285.343073 -66.260485) (xy 285.302924 -66.221776)
			(xy 285.268838 -66.177633) (xy 285.241542 -66.128998) (xy 285.221619 -66.076907) (xy 285.209493 -66.02247)
			(xy 285.205422 -65.966848) (xy 280.487759 -65.966848) (xy 280.484153 -66.00461) (xy 280.468124 -66.087776)
			(xy 280.444263 -66.169043) (xy 280.412784 -66.247673) (xy 280.373973 -66.322954) (xy 280.328183 -66.394206)
			(xy 280.275827 -66.460782) (xy 280.217379 -66.52208) (xy 280.153369 -66.577545) (xy 280.084377 -66.626674)
			(xy 280.011027 -66.669023) (xy 279.933984 -66.704207) (xy 279.853945 -66.731909) (xy 279.771636 -66.751877)
			(xy 279.687801 -66.76393) (xy 279.6032 -66.767961) (xy 279.518599 -66.76393) (xy 279.434764 -66.751877)
			(xy 279.352455 -66.731909) (xy 279.272416 -66.704207) (xy 279.195373 -66.669023) (xy 279.122023 -66.626674)
			(xy 279.053031 -66.577545) (xy 278.989021 -66.52208) (xy 278.930573 -66.460782) (xy 278.878217 -66.394206)
			(xy 278.832427 -66.322954) (xy 278.793616 -66.247673) (xy 278.762137 -66.169043) (xy 278.738276 -66.087776)
			(xy 278.722247 -66.00461) (xy 278.714196 -65.920296) (xy 273.02714 -65.920296) (xy 273.02714 -70.050152)
			(xy 278.662389 -70.050152) (xy 278.666411 -69.964432) (xy 278.678442 -69.879464) (xy 278.698378 -69.795997)
			(xy 278.726041 -69.714763) (xy 278.76119 -69.636477) (xy 278.803516 -69.561826) (xy 278.852645 -69.491467)
			(xy 278.908148 -69.426017) (xy 278.969535 -69.366053) (xy 279.036268 -69.3121) (xy 279.10776 -69.264633)
			(xy 279.183382 -69.224069) (xy 279.262471 -69.190765) (xy 279.344331 -69.165013) (xy 279.428242 -69.14704)
			(xy 279.513468 -69.137004) (xy 279.59926 -69.134992) (xy 279.684862 -69.141023) (xy 279.769524 -69.155043)
			(xy 279.852501 -69.176929) (xy 279.933064 -69.20649) (xy 280.010504 -69.243464) (xy 280.084143 -69.287528)
			(xy 280.153331 -69.338294) (xy 280.217462 -69.395315) (xy 280.275971 -69.458091) (xy 280.328344 -69.526071)
			(xy 280.374122 -69.598656) (xy 280.412902 -69.675208) (xy 280.444343 -69.755056) (xy 280.468169 -69.837497)
			(xy 280.48417 -69.921807) (xy 280.492205 -70.007245) (xy 280.492708 -70.050152) (xy 280.492205 -70.093059)
			(xy 280.48417 -70.178497) (xy 280.468169 -70.262807) (xy 280.444343 -70.345248) (xy 280.412902 -70.425096)
			(xy 280.374122 -70.501648) (xy 280.328344 -70.574233) (xy 280.275971 -70.642213) (xy 280.217462 -70.704989)
			(xy 280.153331 -70.76201) (xy 280.084143 -70.812776) (xy 280.010504 -70.85684) (xy 279.933064 -70.893814)
			(xy 279.852501 -70.923375) (xy 279.769524 -70.945261) (xy 279.684862 -70.959281) (xy 279.59926 -70.965312)
			(xy 279.513468 -70.9633) (xy 279.428242 -70.953264) (xy 279.344331 -70.935291) (xy 279.262471 -70.909539)
			(xy 279.183382 -70.876235) (xy 279.10776 -70.835671) (xy 279.036268 -70.788204) (xy 278.969535 -70.734251)
			(xy 278.908148 -70.674287) (xy 278.852645 -70.608837) (xy 278.803516 -70.538478) (xy 278.76119 -70.463827)
			(xy 278.726041 -70.385541) (xy 278.698378 -70.304307) (xy 278.678442 -70.22084) (xy 278.666411 -70.135872)
			(xy 278.662389 -70.050152) (xy 273.02714 -70.050152) (xy 273.02714 -72.092496) (xy 278.688796 -72.092496)
			(xy 278.688796 -72.0078) (xy 278.696847 -71.923486) (xy 278.712876 -71.84032) (xy 278.736737 -71.759053)
			(xy 278.768216 -71.680423) (xy 278.807027 -71.605142) (xy 278.852817 -71.53389) (xy 278.905173 -71.467314)
			(xy 278.963621 -71.406016) (xy 279.027631 -71.350551) (xy 279.096623 -71.301422) (xy 279.169973 -71.259073)
			(xy 279.247016 -71.223889) (xy 279.327055 -71.196187) (xy 279.409364 -71.176219) (xy 279.493199 -71.164166)
			(xy 279.5778 -71.160136) (xy 279.662401 -71.164166) (xy 279.746236 -71.176219) (xy 279.828545 -71.196187)
			(xy 279.908584 -71.223889) (xy 279.985627 -71.259073) (xy 280.058977 -71.301422) (xy 280.127969 -71.350551)
			(xy 280.191979 -71.406016) (xy 280.250427 -71.467314) (xy 280.302783 -71.53389) (xy 280.348573 -71.605142)
			(xy 280.387384 -71.680423) (xy 280.418863 -71.759053) (xy 280.442724 -71.84032) (xy 280.458753 -71.923486)
			(xy 280.466804 -72.0078) (xy 280.467308 -72.050148) (xy 280.466804 -72.092496) (xy 280.458753 -72.17681)
			(xy 280.442724 -72.259976) (xy 280.418863 -72.341243) (xy 280.387384 -72.419873) (xy 280.348573 -72.495154)
			(xy 280.302783 -72.566406) (xy 280.250427 -72.632982) (xy 280.191979 -72.69428) (xy 280.127969 -72.749745)
			(xy 280.058977 -72.798874) (xy 279.985627 -72.841223) (xy 279.908584 -72.876407) (xy 279.828545 -72.904109)
			(xy 279.746236 -72.924077) (xy 279.662401 -72.93613) (xy 279.5778 -72.940161) (xy 279.493199 -72.93613)
			(xy 279.409364 -72.924077) (xy 279.327055 -72.904109) (xy 279.247016 -72.876407) (xy 279.169973 -72.841223)
			(xy 279.096623 -72.798874) (xy 279.027631 -72.749745) (xy 278.963621 -72.69428) (xy 278.905173 -72.632982)
			(xy 278.852817 -72.566406) (xy 278.807027 -72.495154) (xy 278.768216 -72.419873) (xy 278.736737 -72.341243)
			(xy 278.712876 -72.259976) (xy 278.696847 -72.17681) (xy 278.688796 -72.092496) (xy 273.02714 -72.092496)
			(xy 273.02714 -74.760836) (xy 287.494472 -74.760836) (xy 287.494472 -66.060828) (xy 287.494977 -65.955304)
			(xy 287.503061 -65.74441) (xy 287.519217 -65.533981) (xy 287.54342 -65.324324) (xy 287.575637 -65.115749)
			(xy 287.615819 -64.908561) (xy 287.663907 -64.703064) (xy 287.719831 -64.49956) (xy 287.783508 -64.298347)
			(xy 287.854846 -64.09972) (xy 287.93374 -63.903972) (xy 288.020073 -63.71139) (xy 288.11372 -63.522255)
			(xy 288.214542 -63.336846) (xy 288.322392 -63.155435) (xy 288.437111 -62.978288) (xy 288.558531 -62.805666)
			(xy 288.686474 -62.63782) (xy 288.820752 -62.474998) (xy 288.961168 -62.317439) (xy 289.107516 -62.165374)
			(xy 289.259581 -62.019026) (xy 289.41714 -61.87861) (xy 289.579962 -61.744332) (xy 289.747808 -61.616389)
			(xy 289.92043 -61.494969) (xy 290.097577 -61.38025) (xy 290.278988 -61.2724) (xy 290.464397 -61.171578)
			(xy 290.653532 -61.077931) (xy 290.846114 -60.991598) (xy 291.041862 -60.912704) (xy 291.240489 -60.841366)
			(xy 291.441702 -60.777689) (xy 291.645206 -60.721765) (xy 291.850703 -60.673677) (xy 292.057891 -60.633495)
			(xy 292.266466 -60.601278) (xy 292.476123 -60.577075) (xy 292.686552 -60.560919) (xy 292.897446 -60.552835)
			(xy 293.108494 -60.552835) (xy 293.319388 -60.560919) (xy 293.529817 -60.577075) (xy 293.739474 -60.601278)
			(xy 293.948049 -60.633495) (xy 294.155237 -60.673677) (xy 294.262973 -60.698888) (xy 301.119284 -60.698888)
			(xy 301.123355 -60.643266) (xy 301.135481 -60.588829) (xy 301.155404 -60.536738) (xy 301.1827 -60.488103)
			(xy 301.216786 -60.44396) (xy 301.256935 -60.405251) (xy 301.302293 -60.3728) (xy 301.351893 -60.347299)
			(xy 301.404677 -60.329292) (xy 301.45952 -60.319162) (xy 301.515254 -60.317125) (xy 301.570691 -60.323225)
			(xy 301.624648 -60.337331) (xy 301.675977 -60.359143) (xy 301.723583 -60.388197) (xy 301.766451 -60.423872)
			(xy 301.803668 -60.465409) (xy 301.834441 -60.511922) (xy 301.858113 -60.562419) (xy 301.874181 -60.615826)
			(xy 301.882301 -60.671002) (xy 301.88281 -60.698888) (xy 301.882301 -60.726774) (xy 301.874181 -60.78195)
			(xy 301.858113 -60.835357) (xy 301.834441 -60.885854) (xy 301.803668 -60.932367) (xy 301.766451 -60.973904)
			(xy 301.723583 -61.009579) (xy 301.675977 -61.038633) (xy 301.624648 -61.060445) (xy 301.570691 -61.074551)
			(xy 301.515254 -61.080651) (xy 301.45952 -61.078614) (xy 301.404677 -61.068484) (xy 301.351893 -61.050477)
			(xy 301.302293 -61.024976) (xy 301.256935 -60.992525) (xy 301.216786 -60.953816) (xy 301.1827 -60.909673)
			(xy 301.155404 -60.861038) (xy 301.135481 -60.808947) (xy 301.123355 -60.75451) (xy 301.119284 -60.698888)
			(xy 294.262973 -60.698888) (xy 294.360734 -60.721765) (xy 294.564238 -60.777689) (xy 294.765451 -60.841366)
			(xy 294.964078 -60.912704) (xy 295.159826 -60.991598) (xy 295.352408 -61.077931) (xy 295.458959 -61.130688)
			(xy 303.107342 -61.130688) (xy 303.111413 -61.075066) (xy 303.123539 -61.020629) (xy 303.143462 -60.968538)
			(xy 303.170758 -60.919903) (xy 303.204844 -60.87576) (xy 303.244993 -60.837051) (xy 303.290351 -60.8046)
			(xy 303.339951 -60.779099) (xy 303.392735 -60.761092) (xy 303.447578 -60.750962) (xy 303.503312 -60.748925)
			(xy 303.558749 -60.755025) (xy 303.612706 -60.769131) (xy 303.664035 -60.790943) (xy 303.711641 -60.819997)
			(xy 303.754509 -60.855672) (xy 303.791726 -60.897209) (xy 303.822499 -60.943722) (xy 303.846171 -60.994219)
			(xy 303.862239 -61.047626) (xy 303.870359 -61.102802) (xy 303.870868 -61.130688) (xy 303.870359 -61.158574)
			(xy 303.862239 -61.21375) (xy 303.846171 -61.267157) (xy 303.822499 -61.317654) (xy 303.813439 -61.331348)
			(xy 315.998604 -61.331348) (xy 316.002675 -61.275726) (xy 316.014801 -61.221289) (xy 316.034724 -61.169198)
			(xy 316.06202 -61.120563) (xy 316.096106 -61.07642) (xy 316.136255 -61.037711) (xy 316.181613 -61.00526)
			(xy 316.231213 -60.979759) (xy 316.283997 -60.961752) (xy 316.33884 -60.951622) (xy 316.394574 -60.949585)
			(xy 316.450011 -60.955685) (xy 316.503968 -60.969791) (xy 316.555297 -60.991603) (xy 316.602903 -61.020657)
			(xy 316.645771 -61.056332) (xy 316.682988 -61.097869) (xy 316.713761 -61.144382) (xy 316.737433 -61.194879)
			(xy 316.753501 -61.248286) (xy 316.761621 -61.303462) (xy 316.761885 -61.31795) (xy 318.228986 -61.31795)
			(xy 318.228986 -61.26345) (xy 318.236742 -61.209505) (xy 318.252095 -61.157213) (xy 318.274735 -61.107638)
			(xy 318.304198 -61.06179) (xy 318.339887 -61.020601) (xy 318.381074 -60.98491) (xy 318.426921 -60.955444)
			(xy 318.476495 -60.932802) (xy 318.528786 -60.917446) (xy 318.58273 -60.909687) (xy 318.60998 -60.9092)
			(xy 318.637105 -60.909678) (xy 318.690808 -60.91736) (xy 318.742881 -60.932573) (xy 318.792274 -60.955009)
			(xy 318.837991 -60.984216) (xy 318.879109 -61.019604) (xy 318.914799 -61.060461) (xy 318.944342 -61.105961)
			(xy 318.96714 -61.155188) (xy 318.982735 -61.207148) (xy 318.990813 -61.260793) (xy 318.991488 -61.287914)
			(xy 318.992102 -61.302163) (xy 319.000201 -61.329494) (xy 319.01554 -61.353522) (xy 319.036923 -61.372374)
			(xy 319.062684 -61.38458) (xy 319.090815 -61.389189) (xy 319.105026 -61.38799) (xy 319.116098 -61.386782)
			(xy 319.138338 -61.385514) (xy 319.149476 -61.38545) (xy 319.176727 -61.385996) (xy 319.230675 -61.393749)
			(xy 319.28297 -61.409101) (xy 319.332547 -61.43174) (xy 319.378398 -61.461204) (xy 319.419589 -61.496894)
			(xy 319.455282 -61.538082) (xy 319.484749 -61.583932) (xy 319.50739 -61.633508) (xy 319.522746 -61.685802)
			(xy 319.530503 -61.739749) (xy 319.530503 -61.794251) (xy 319.522746 -61.848198) (xy 319.50739 -61.900492)
			(xy 319.484749 -61.950068) (xy 319.455282 -61.995918) (xy 319.419589 -62.037106) (xy 319.378398 -62.072796)
			(xy 319.332547 -62.10226) (xy 319.28297 -62.124899) (xy 319.230675 -62.140251) (xy 319.176727 -62.148004)
			(xy 319.149476 -62.148466) (xy 319.122348 -62.148063) (xy 319.068641 -62.140374) (xy 319.016564 -62.125154)
			(xy 318.967168 -62.102711) (xy 318.92145 -62.073496) (xy 318.880332 -62.0381) (xy 318.844642 -61.997235)
			(xy 318.815102 -61.951727) (xy 318.792305 -61.902493) (xy 318.776714 -61.850527) (xy 318.768641 -61.796875)
			(xy 318.767968 -61.769752) (xy 318.767321 -61.755508) (xy 318.759219 -61.728185) (xy 318.743884 -61.704164)
			(xy 318.722509 -61.685315) (xy 318.696759 -61.673105) (xy 318.668637 -61.668485) (xy 318.65443 -61.669676)
			(xy 318.643357 -61.670879) (xy 318.621118 -61.67215) (xy 318.60998 -61.672216) (xy 318.58273 -61.671713)
			(xy 318.528786 -61.663954) (xy 318.476495 -61.648598) (xy 318.426921 -61.625956) (xy 318.381074 -61.59649)
			(xy 318.339887 -61.560799) (xy 318.304198 -61.51961) (xy 318.274735 -61.473762) (xy 318.252095 -61.424187)
			(xy 318.236742 -61.371895) (xy 318.228986 -61.31795) (xy 316.761885 -61.31795) (xy 316.76213 -61.331348)
			(xy 316.761621 -61.359234) (xy 316.753501 -61.41441) (xy 316.737433 -61.467817) (xy 316.713761 -61.518314)
			(xy 316.682988 -61.564827) (xy 316.645771 -61.606364) (xy 316.602903 -61.642039) (xy 316.555297 -61.671093)
			(xy 316.503968 -61.692905) (xy 316.450011 -61.707011) (xy 316.394574 -61.713111) (xy 316.33884 -61.711074)
			(xy 316.283997 -61.700944) (xy 316.231213 -61.682937) (xy 316.181613 -61.657436) (xy 316.136255 -61.624985)
			(xy 316.096106 -61.586276) (xy 316.06202 -61.542133) (xy 316.034724 -61.493498) (xy 316.014801 -61.441407)
			(xy 316.002675 -61.38697) (xy 315.998604 -61.331348) (xy 303.813439 -61.331348) (xy 303.791726 -61.364167)
			(xy 303.754509 -61.405704) (xy 303.711641 -61.441379) (xy 303.664035 -61.470433) (xy 303.612706 -61.492245)
			(xy 303.558749 -61.506351) (xy 303.503312 -61.512451) (xy 303.447578 -61.510414) (xy 303.392735 -61.500284)
			(xy 303.339951 -61.482277) (xy 303.290351 -61.456776) (xy 303.244993 -61.424325) (xy 303.204844 -61.385616)
			(xy 303.170758 -61.341473) (xy 303.143462 -61.292838) (xy 303.123539 -61.240747) (xy 303.111413 -61.18631)
			(xy 303.107342 -61.130688) (xy 295.458959 -61.130688) (xy 295.541543 -61.171578) (xy 295.726952 -61.2724)
			(xy 295.908363 -61.38025) (xy 296.08551 -61.494969) (xy 296.258132 -61.616389) (xy 296.425978 -61.744332)
			(xy 296.5888 -61.87861) (xy 296.746359 -62.019026) (xy 296.898424 -62.165374) (xy 297.044772 -62.317439)
			(xy 297.185188 -62.474998) (xy 297.319466 -62.63782) (xy 297.424485 -62.775592) (xy 306.252372 -62.775592)
			(xy 306.252783 -62.748986) (xy 306.260168 -62.69629) (xy 306.274806 -62.645132) (xy 306.296414 -62.596506)
			(xy 306.324572 -62.551356) (xy 306.358733 -62.510559) (xy 306.398234 -62.474906) (xy 306.420012 -62.459616)
			(xy 306.43145 -62.451229) (xy 306.44965 -62.429496) (xy 306.461168 -62.403595) (xy 306.465113 -62.375524)
			(xy 306.461181 -62.347451) (xy 306.449675 -62.321544) (xy 306.431485 -62.299803) (xy 306.420012 -62.291468)
			(xy 306.398258 -62.276151) (xy 306.35878 -62.240487) (xy 306.324637 -62.199687) (xy 306.29649 -62.154541)
			(xy 306.274884 -62.105924) (xy 306.26024 -62.054777) (xy 306.252839 -62.002093) (xy 306.252372 -61.975492)
			(xy 306.252858 -61.948241) (xy 306.260614 -61.894293) (xy 306.275969 -61.841998) (xy 306.298611 -61.792421)
			(xy 306.328077 -61.746571) (xy 306.363768 -61.70538) (xy 306.404959 -61.669689) (xy 306.450809 -61.640223)
			(xy 306.500386 -61.617581) (xy 306.552681 -61.602226) (xy 306.606629 -61.59447) (xy 306.661131 -61.59447)
			(xy 306.715079 -61.602226) (xy 306.767374 -61.617581) (xy 306.816951 -61.640223) (xy 306.862801 -61.669689)
			(xy 306.903992 -61.70538) (xy 306.939683 -61.746571) (xy 306.969149 -61.792421) (xy 306.991791 -61.841998)
			(xy 307.007146 -61.894293) (xy 307.014902 -61.948241) (xy 307.015388 -61.975492) (xy 307.014938 -62.002096)
			(xy 307.007557 -62.054789) (xy 306.992924 -62.105945) (xy 306.971321 -62.15457) (xy 306.94317 -62.199721)
			(xy 306.909016 -62.24052) (xy 306.869522 -62.276175) (xy 306.847748 -62.291468) (xy 306.836222 -62.299748)
			(xy 306.818009 -62.3215) (xy 306.806489 -62.347427) (xy 306.802551 -62.375524) (xy 306.806502 -62.403618)
			(xy 306.818034 -62.42954) (xy 306.836258 -62.451284) (xy 306.847748 -62.459616) (xy 306.869532 -62.474892)
			(xy 306.909011 -62.510561) (xy 306.943154 -62.551368) (xy 306.971298 -62.596521) (xy 306.992898 -62.645145)
			(xy 307.007535 -62.696299) (xy 307.014926 -62.748989) (xy 307.015388 -62.775592) (xy 307.014902 -62.802843)
			(xy 307.007146 -62.856791) (xy 306.991791 -62.909086) (xy 306.969149 -62.958663) (xy 306.939683 -63.004513)
			(xy 306.903992 -63.045704) (xy 306.862801 -63.081395) (xy 306.816951 -63.110861) (xy 306.767374 -63.133503)
			(xy 306.715079 -63.148858) (xy 306.661131 -63.156614) (xy 306.606629 -63.156614) (xy 306.552681 -63.148858)
			(xy 306.500386 -63.133503) (xy 306.450809 -63.110861) (xy 306.404959 -63.081395) (xy 306.363768 -63.045704)
			(xy 306.328077 -63.004513) (xy 306.298611 -62.958663) (xy 306.275969 -62.909086) (xy 306.260614 -62.856791)
			(xy 306.252858 -62.802843) (xy 306.252372 -62.775592) (xy 297.424485 -62.775592) (xy 297.447409 -62.805666)
			(xy 297.568829 -62.978288) (xy 297.683548 -63.155435) (xy 297.791398 -63.336846) (xy 297.861058 -63.464948)
			(xy 308.90972 -63.464948) (xy 308.910205 -63.436546) (xy 308.918409 -63.380336) (xy 308.934653 -63.325904)
			(xy 308.958595 -63.274391) (xy 308.989732 -63.22688) (xy 309.02741 -63.18437) (xy 309.070838 -63.147753)
			(xy 309.119103 -63.117798) (xy 309.171191 -63.095134) (xy 309.226008 -63.080239) (xy 309.254144 -63.076328)
			(xy 309.267641 -63.074274) (xy 309.292921 -63.063993) (xy 309.31457 -63.047376) (xy 309.331038 -63.025615)
			(xy 309.341146 -63.000265) (xy 309.344171 -62.973143) (xy 309.339896 -62.946189) (xy 309.334662 -62.93358)
			(xy 309.323827 -62.908667) (xy 309.308554 -62.856532) (xy 309.300847 -62.802755) (xy 309.300372 -62.775592)
			(xy 309.300923 -62.747171) (xy 309.309338 -62.690956) (xy 309.326009 -62.636614) (xy 309.350566 -62.585352)
			(xy 309.382466 -62.538305) (xy 309.420999 -62.496519) (xy 309.465312 -62.460919) (xy 309.489602 -62.446154)
			(xy 309.502482 -62.438073) (xy 309.523103 -62.415744) (xy 309.536249 -62.388342) (xy 309.540762 -62.358285)
			(xy 309.536241 -62.328229) (xy 309.523085 -62.30083) (xy 309.502458 -62.278508) (xy 309.489602 -62.270386)
			(xy 309.465304 -62.255635) (xy 309.421007 -62.220018) (xy 309.382484 -62.178223) (xy 309.350588 -62.131175)
			(xy 309.326025 -62.079915) (xy 309.309339 -62.025579) (xy 309.300899 -61.969368) (xy 309.300372 -61.940948)
			(xy 309.300858 -61.913697) (xy 309.308614 -61.859749) (xy 309.323969 -61.807454) (xy 309.346611 -61.757877)
			(xy 309.376077 -61.712027) (xy 309.411768 -61.670836) (xy 309.452959 -61.635145) (xy 309.498809 -61.605679)
			(xy 309.548386 -61.583037) (xy 309.600681 -61.567682) (xy 309.654629 -61.559926) (xy 309.709131 -61.559926)
			(xy 309.763079 -61.567682) (xy 309.815374 -61.583037) (xy 309.864951 -61.605679) (xy 309.910801 -61.635145)
			(xy 309.951992 -61.670836) (xy 309.987683 -61.712027) (xy 310.017149 -61.757877) (xy 310.039791 -61.807454)
			(xy 310.055146 -61.859749) (xy 310.062902 -61.913697) (xy 310.063388 -61.940948) (xy 310.062888 -61.969371)
			(xy 310.054467 -62.025589) (xy 310.043805 -62.060328) (xy 312.545982 -62.060328) (xy 312.550053 -62.004706)
			(xy 312.562179 -61.950269) (xy 312.582102 -61.898178) (xy 312.609398 -61.849543) (xy 312.643484 -61.8054)
			(xy 312.683633 -61.766691) (xy 312.728991 -61.73424) (xy 312.778591 -61.708739) (xy 312.831375 -61.690732)
			(xy 312.886218 -61.680602) (xy 312.941952 -61.678565) (xy 312.997389 -61.684665) (xy 313.051346 -61.698771)
			(xy 313.102675 -61.720583) (xy 313.150281 -61.749637) (xy 313.193149 -61.785312) (xy 313.230366 -61.826849)
			(xy 313.261139 -61.873362) (xy 313.284811 -61.923859) (xy 313.300879 -61.977266) (xy 313.308999 -62.032442)
			(xy 313.309508 -62.060328) (xy 314.704982 -62.060328) (xy 314.709053 -62.004706) (xy 314.721179 -61.950269)
			(xy 314.741102 -61.898178) (xy 314.768398 -61.849543) (xy 314.802484 -61.8054) (xy 314.842633 -61.766691)
			(xy 314.887991 -61.73424) (xy 314.937591 -61.708739) (xy 314.990375 -61.690732) (xy 315.045218 -61.680602)
			(xy 315.100952 -61.678565) (xy 315.156389 -61.684665) (xy 315.210346 -61.698771) (xy 315.261675 -61.720583)
			(xy 315.309281 -61.749637) (xy 315.352149 -61.785312) (xy 315.389366 -61.826849) (xy 315.420139 -61.873362)
			(xy 315.443811 -61.923859) (xy 315.459879 -61.977266) (xy 315.467999 -62.032442) (xy 315.468508 -62.060328)
			(xy 315.467999 -62.088214) (xy 315.459879 -62.14339) (xy 315.457358 -62.151768) (xy 321.363592 -62.151768)
			(xy 321.367663 -62.096146) (xy 321.379789 -62.041709) (xy 321.399712 -61.989618) (xy 321.427008 -61.940983)
			(xy 321.461094 -61.89684) (xy 321.501243 -61.858131) (xy 321.546601 -61.82568) (xy 321.596201 -61.800179)
			(xy 321.648985 -61.782172) (xy 321.703828 -61.772042) (xy 321.759562 -61.770005) (xy 321.814999 -61.776105)
			(xy 321.868956 -61.790211) (xy 321.920285 -61.812023) (xy 321.967891 -61.841077) (xy 322.010759 -61.876752)
			(xy 322.047976 -61.918289) (xy 322.078749 -61.964802) (xy 322.102421 -62.015299) (xy 322.118489 -62.068706)
			(xy 322.126609 -62.123882) (xy 322.127118 -62.151768) (xy 322.126609 -62.179654) (xy 322.118489 -62.23483)
			(xy 322.102421 -62.288237) (xy 322.078749 -62.338734) (xy 322.047976 -62.385247) (xy 322.010759 -62.426784)
			(xy 321.967891 -62.462459) (xy 321.920285 -62.491513) (xy 321.868956 -62.513325) (xy 321.814999 -62.527431)
			(xy 321.759562 -62.533531) (xy 321.703828 -62.531494) (xy 321.648985 -62.521364) (xy 321.596201 -62.503357)
			(xy 321.546601 -62.477856) (xy 321.501243 -62.445405) (xy 321.461094 -62.406696) (xy 321.427008 -62.362553)
			(xy 321.399712 -62.313918) (xy 321.379789 -62.261827) (xy 321.367663 -62.20739) (xy 321.363592 -62.151768)
			(xy 315.457358 -62.151768) (xy 315.443811 -62.196797) (xy 315.420139 -62.247294) (xy 315.389366 -62.293807)
			(xy 315.352149 -62.335344) (xy 315.309281 -62.371019) (xy 315.261675 -62.400073) (xy 315.210346 -62.421885)
			(xy 315.156389 -62.435991) (xy 315.100952 -62.442091) (xy 315.045218 -62.440054) (xy 314.990375 -62.429924)
			(xy 314.937591 -62.411917) (xy 314.887991 -62.386416) (xy 314.842633 -62.353965) (xy 314.802484 -62.315256)
			(xy 314.768398 -62.271113) (xy 314.741102 -62.222478) (xy 314.721179 -62.170387) (xy 314.709053 -62.11595)
			(xy 314.704982 -62.060328) (xy 313.309508 -62.060328) (xy 313.308999 -62.088214) (xy 313.300879 -62.14339)
			(xy 313.284811 -62.196797) (xy 313.261139 -62.247294) (xy 313.230366 -62.293807) (xy 313.193149 -62.335344)
			(xy 313.150281 -62.371019) (xy 313.102675 -62.400073) (xy 313.051346 -62.421885) (xy 312.997389 -62.435991)
			(xy 312.941952 -62.442091) (xy 312.886218 -62.440054) (xy 312.831375 -62.429924) (xy 312.778591 -62.411917)
			(xy 312.728991 -62.386416) (xy 312.683633 -62.353965) (xy 312.643484 -62.315256) (xy 312.609398 -62.271113)
			(xy 312.582102 -62.222478) (xy 312.562179 -62.170387) (xy 312.550053 -62.11595) (xy 312.545982 -62.060328)
			(xy 310.043805 -62.060328) (xy 310.037788 -62.079933) (xy 310.013222 -62.131197) (xy 309.981315 -62.178243)
			(xy 309.942773 -62.220027) (xy 309.898452 -62.255623) (xy 309.874158 -62.270386) (xy 309.861328 -62.278544)
			(xy 309.8407 -62.300852) (xy 309.827543 -62.32824) (xy 309.823021 -62.358285) (xy 309.827534 -62.388332)
			(xy 309.840682 -62.415723) (xy 309.861304 -62.438037) (xy 309.874158 -62.446154) (xy 309.89842 -62.460961)
			(xy 309.942719 -62.496568) (xy 309.981246 -62.538353) (xy 310.013146 -62.585391) (xy 310.037715 -62.636642)
			(xy 310.053205 -62.687054) (xy 318.122246 -62.687054) (xy 318.122246 -62.632546) (xy 318.130003 -62.578594)
			(xy 318.145359 -62.526295) (xy 318.168002 -62.476714) (xy 318.197471 -62.430859) (xy 318.233166 -62.389666)
			(xy 318.274359 -62.353971) (xy 318.320214 -62.324502) (xy 318.369795 -62.301859) (xy 318.422094 -62.286503)
			(xy 318.476046 -62.278746) (xy 318.5033 -62.27826) (xy 318.531837 -62.278768) (xy 318.588272 -62.287284)
			(xy 318.64281 -62.304111) (xy 318.694232 -62.328874) (xy 318.741393 -62.361019) (xy 318.783239 -62.399831)
			(xy 318.818838 -62.444443) (xy 318.847394 -62.49386) (xy 318.868271 -62.546979) (xy 318.875156 -62.574678)
			(xy 318.879039 -62.589169) (xy 318.893973 -62.61517) (xy 318.915809 -62.63572) (xy 318.942668 -62.649051)
			(xy 318.972239 -62.654017) (xy 319.001979 -62.650189) (xy 319.015872 -62.644528) (xy 319.040587 -62.633949)
			(xy 319.092229 -62.619011) (xy 319.145456 -62.611462) (xy 319.172336 -62.611) (xy 319.199586 -62.611472)
			(xy 319.253531 -62.619233) (xy 319.305823 -62.634592) (xy 319.355396 -62.657235) (xy 319.401243 -62.686703)
			(xy 319.44243 -62.722395) (xy 319.478118 -62.763586) (xy 319.507582 -62.809435) (xy 319.530221 -62.859011)
			(xy 319.545575 -62.911304) (xy 319.55333 -62.96525) (xy 319.55333 -63.01975) (xy 319.545575 -63.073696)
			(xy 319.530221 -63.125989) (xy 319.507582 -63.175565) (xy 319.478118 -63.221414) (xy 319.44243 -63.262605)
			(xy 319.401243 -63.298297) (xy 319.355396 -63.327765) (xy 319.305823 -63.350408) (xy 319.253531 -63.365767)
			(xy 319.199586 -63.373528) (xy 319.172336 -63.374016) (xy 319.143799 -63.373494) (xy 319.087363 -63.364983)
			(xy 319.032825 -63.348159) (xy 318.981402 -63.323399) (xy 318.934241 -63.291255) (xy 318.892394 -63.252445)
			(xy 318.856795 -63.207833) (xy 318.82824 -63.158416) (xy 318.807364 -63.105297) (xy 318.80048 -63.077598)
			(xy 318.796564 -63.063119) (xy 318.781632 -63.037125) (xy 318.759802 -63.016579) (xy 318.732952 -63.003248)
			(xy 318.703389 -62.998277) (xy 318.673656 -63.002094) (xy 318.659764 -63.007748) (xy 318.635059 -63.018352)
			(xy 318.583411 -63.03328) (xy 318.530181 -63.040818) (xy 318.5033 -63.041276) (xy 318.476046 -63.040854)
			(xy 318.422094 -63.033097) (xy 318.369795 -63.017741) (xy 318.320214 -62.995098) (xy 318.274359 -62.965629)
			(xy 318.233166 -62.929934) (xy 318.197471 -62.888741) (xy 318.168002 -62.842886) (xy 318.145359 -62.793305)
			(xy 318.130003 -62.741006) (xy 318.122246 -62.687054) (xy 310.053205 -62.687054) (xy 310.054408 -62.69097)
			(xy 310.062857 -62.747174) (xy 310.063388 -62.775592) (xy 310.06289 -62.803008) (xy 310.05502 -62.857274)
			(xy 310.03947 -62.909856) (xy 310.016559 -62.959673) (xy 309.986758 -63.005701) (xy 309.95068 -63.046993)
			(xy 309.916494 -63.076328) (xy 312.545982 -63.076328) (xy 312.550053 -63.020706) (xy 312.562179 -62.966269)
			(xy 312.582102 -62.914178) (xy 312.609398 -62.865543) (xy 312.643484 -62.8214) (xy 312.683633 -62.782691)
			(xy 312.728991 -62.75024) (xy 312.778591 -62.724739) (xy 312.831375 -62.706732) (xy 312.886218 -62.696602)
			(xy 312.941952 -62.694565) (xy 312.997389 -62.700665) (xy 313.051346 -62.714771) (xy 313.102675 -62.736583)
			(xy 313.150281 -62.765637) (xy 313.193149 -62.801312) (xy 313.230366 -62.842849) (xy 313.261139 -62.889362)
			(xy 313.284811 -62.939859) (xy 313.300879 -62.993266) (xy 313.308999 -63.048442) (xy 313.309508 -63.076328)
			(xy 314.704982 -63.076328) (xy 314.709053 -63.020706) (xy 314.721179 -62.966269) (xy 314.741102 -62.914178)
			(xy 314.768398 -62.865543) (xy 314.802484 -62.8214) (xy 314.842633 -62.782691) (xy 314.887991 -62.75024)
			(xy 314.937591 -62.724739) (xy 314.990375 -62.706732) (xy 315.045218 -62.696602) (xy 315.100952 -62.694565)
			(xy 315.156389 -62.700665) (xy 315.210346 -62.714771) (xy 315.261675 -62.736583) (xy 315.309281 -62.765637)
			(xy 315.352149 -62.801312) (xy 315.389366 -62.842849) (xy 315.420139 -62.889362) (xy 315.443811 -62.939859)
			(xy 315.459879 -62.993266) (xy 315.467999 -63.048442) (xy 315.468508 -63.076328) (xy 315.467999 -63.104214)
			(xy 315.459879 -63.15939) (xy 315.443811 -63.212797) (xy 315.420139 -63.263294) (xy 315.389366 -63.309807)
			(xy 315.352149 -63.351344) (xy 315.309281 -63.387019) (xy 315.261675 -63.416073) (xy 315.210346 -63.437885)
			(xy 315.156389 -63.451991) (xy 315.100952 -63.458091) (xy 315.045218 -63.456054) (xy 314.990375 -63.445924)
			(xy 314.937591 -63.427917) (xy 314.887991 -63.402416) (xy 314.842633 -63.369965) (xy 314.802484 -63.331256)
			(xy 314.768398 -63.287113) (xy 314.741102 -63.238478) (xy 314.721179 -63.186387) (xy 314.709053 -63.13195)
			(xy 314.704982 -63.076328) (xy 313.309508 -63.076328) (xy 313.308999 -63.104214) (xy 313.300879 -63.15939)
			(xy 313.284811 -63.212797) (xy 313.261139 -63.263294) (xy 313.230366 -63.309807) (xy 313.193149 -63.351344)
			(xy 313.150281 -63.387019) (xy 313.102675 -63.416073) (xy 313.051346 -63.437885) (xy 312.997389 -63.451991)
			(xy 312.941952 -63.458091) (xy 312.886218 -63.456054) (xy 312.831375 -63.445924) (xy 312.778591 -63.427917)
			(xy 312.728991 -63.402416) (xy 312.683633 -63.369965) (xy 312.643484 -63.331256) (xy 312.609398 -63.287113)
			(xy 312.582102 -63.238478) (xy 312.562179 -63.186387) (xy 312.550053 -63.13195) (xy 312.545982 -63.076328)
			(xy 309.916494 -63.076328) (xy 309.909067 -63.082701) (xy 309.862775 -63.11209) (xy 309.812755 -63.134555)
			(xy 309.760037 -63.149636) (xy 309.732934 -63.153798) (xy 309.719472 -63.156087) (xy 309.694351 -63.166757)
			(xy 309.672961 -63.183709) (xy 309.656836 -63.20573) (xy 309.647132 -63.23124) (xy 309.644545 -63.258411)
			(xy 309.64926 -63.285293) (xy 309.654702 -63.297816) (xy 309.666503 -63.324079) (xy 309.683144 -63.379199)
			(xy 309.691543 -63.436159) (xy 309.69204 -63.464948) (xy 309.691542 -63.492889) (xy 309.691177 -63.495428)
			(xy 320.944492 -63.495428) (xy 320.948563 -63.439806) (xy 320.960689 -63.385369) (xy 320.980612 -63.333278)
			(xy 321.007908 -63.284643) (xy 321.041994 -63.2405) (xy 321.082143 -63.201791) (xy 321.127501 -63.16934)
			(xy 321.177101 -63.143839) (xy 321.229885 -63.125832) (xy 321.284728 -63.115702) (xy 321.340462 -63.113665)
			(xy 321.395899 -63.119765) (xy 321.449856 -63.133871) (xy 321.501185 -63.155683) (xy 321.548791 -63.184737)
			(xy 321.591659 -63.220412) (xy 321.628876 -63.261949) (xy 321.659649 -63.308462) (xy 321.683321 -63.358959)
			(xy 321.699389 -63.412366) (xy 321.707509 -63.467542) (xy 321.708018 -63.495428) (xy 321.707509 -63.523314)
			(xy 321.699389 -63.57849) (xy 321.683321 -63.631897) (xy 321.659649 -63.682394) (xy 321.628876 -63.728907)
			(xy 321.591659 -63.770444) (xy 321.548791 -63.806119) (xy 321.501185 -63.835173) (xy 321.449856 -63.856985)
			(xy 321.395899 -63.871091) (xy 321.340462 -63.877191) (xy 321.284728 -63.875154) (xy 321.229885 -63.865024)
			(xy 321.177101 -63.847017) (xy 321.127501 -63.821516) (xy 321.082143 -63.789065) (xy 321.041994 -63.750356)
			(xy 321.007908 -63.706213) (xy 320.980612 -63.657578) (xy 320.960689 -63.605487) (xy 320.948563 -63.55105)
			(xy 320.944492 -63.495428) (xy 309.691177 -63.495428) (xy 309.683589 -63.548201) (xy 309.667845 -63.601819)
			(xy 309.644631 -63.65265) (xy 309.61442 -63.699661) (xy 309.577825 -63.741893) (xy 309.535593 -63.778488)
			(xy 309.488582 -63.808699) (xy 309.437751 -63.831913) (xy 309.384133 -63.847657) (xy 309.328821 -63.85561)
			(xy 309.272939 -63.85561) (xy 309.217627 -63.847657) (xy 309.164009 -63.831913) (xy 309.113178 -63.808699)
			(xy 309.066167 -63.778488) (xy 309.023935 -63.741893) (xy 308.98734 -63.699661) (xy 308.957129 -63.65265)
			(xy 308.933915 -63.601819) (xy 308.918171 -63.548201) (xy 308.910218 -63.492889) (xy 308.90972 -63.464948)
			(xy 297.861058 -63.464948) (xy 297.89222 -63.522255) (xy 297.985867 -63.71139) (xy 298.0722 -63.903972)
			(xy 298.151094 -64.09972) (xy 298.160945 -64.127147) (xy 303.585926 -64.127147) (xy 303.585926 -64.072653)
			(xy 303.593681 -64.018714) (xy 303.609033 -63.966427) (xy 303.63167 -63.916858) (xy 303.661131 -63.871014)
			(xy 303.696816 -63.82983) (xy 303.737998 -63.794143) (xy 303.78384 -63.76468) (xy 303.833409 -63.74204)
			(xy 303.885694 -63.726685) (xy 303.939633 -63.718928) (xy 303.96688 -63.71844) (xy 303.995797 -63.718958)
			(xy 304.052969 -63.727685) (xy 304.108169 -63.744942) (xy 304.160131 -63.770333) (xy 304.207664 -63.803278)
			(xy 304.24968 -63.84302) (xy 304.26787 -63.865506) (xy 304.277767 -63.877311) (xy 304.303091 -63.89483)
			(xy 304.332484 -63.904006) (xy 304.363276 -63.904006) (xy 304.392669 -63.89483) (xy 304.417993 -63.877311)
			(xy 304.42789 -63.865506) (xy 304.446088 -63.843029) (xy 304.488106 -63.803293) (xy 304.53564 -63.770353)
			(xy 304.5876 -63.744963) (xy 304.642796 -63.727706) (xy 304.699964 -63.718976) (xy 304.72888 -63.71844)
			(xy 304.756137 -63.718806) (xy 304.810097 -63.726561) (xy 304.862404 -63.741917) (xy 304.911993 -63.764562)
			(xy 304.957854 -63.794033) (xy 304.999055 -63.829731) (xy 305.034755 -63.87093) (xy 305.064229 -63.916789)
			(xy 305.086876 -63.966377) (xy 305.102235 -64.018683) (xy 305.105154 -64.038988) (xy 318.757298 -64.038988)
			(xy 318.761369 -63.983366) (xy 318.773495 -63.928929) (xy 318.793418 -63.876838) (xy 318.820714 -63.828203)
			(xy 318.8548 -63.78406) (xy 318.894949 -63.745351) (xy 318.940307 -63.7129) (xy 318.989907 -63.687399)
			(xy 319.042691 -63.669392) (xy 319.097534 -63.659262) (xy 319.153268 -63.657225) (xy 319.208705 -63.663325)
			(xy 319.262662 -63.677431) (xy 319.313991 -63.699243) (xy 319.361597 -63.728297) (xy 319.404465 -63.763972)
			(xy 319.441682 -63.805509) (xy 319.472455 -63.852022) (xy 319.496127 -63.902519) (xy 319.512195 -63.955926)
			(xy 319.520315 -64.011102) (xy 319.520824 -64.038988) (xy 319.520315 -64.066874) (xy 319.512195 -64.12205)
			(xy 319.496127 -64.175457) (xy 319.472455 -64.225954) (xy 319.441682 -64.272467) (xy 319.404465 -64.314004)
			(xy 319.361597 -64.349679) (xy 319.313991 -64.378733) (xy 319.262662 -64.400545) (xy 319.208705 -64.414651)
			(xy 319.153268 -64.420751) (xy 319.097534 -64.418714) (xy 319.042691 -64.408584) (xy 318.989907 -64.390577)
			(xy 318.940307 -64.365076) (xy 318.894949 -64.332625) (xy 318.8548 -64.293916) (xy 318.820714 -64.249773)
			(xy 318.793418 -64.201138) (xy 318.773495 -64.149047) (xy 318.761369 -64.09461) (xy 318.757298 -64.038988)
			(xy 305.105154 -64.038988) (xy 305.109993 -64.072643) (xy 305.109993 -64.127157) (xy 305.102235 -64.181117)
			(xy 305.086876 -64.233423) (xy 305.064229 -64.283011) (xy 305.034755 -64.32887) (xy 304.999055 -64.370069)
			(xy 304.957854 -64.405767) (xy 304.911993 -64.435238) (xy 304.862404 -64.457883) (xy 304.810097 -64.473239)
			(xy 304.756137 -64.480994) (xy 304.72888 -64.481456) (xy 304.699964 -64.480897) (xy 304.642794 -64.472178)
			(xy 304.587596 -64.45493) (xy 304.535633 -64.429546) (xy 304.488099 -64.396609) (xy 304.446081 -64.356873)
			(xy 304.42789 -64.33439) (xy 304.417993 -64.322585) (xy 304.392669 -64.305066) (xy 304.363276 -64.29589)
			(xy 304.332484 -64.29589) (xy 304.303091 -64.305066) (xy 304.277767 -64.322585) (xy 304.26787 -64.33439)
			(xy 304.249693 -64.356886) (xy 304.207671 -64.396621) (xy 304.160133 -64.429559) (xy 304.108169 -64.454945)
			(xy 304.052969 -64.472198) (xy 303.995797 -64.480923) (xy 303.96688 -64.481456) (xy 303.939633 -64.480872)
			(xy 303.885694 -64.473115) (xy 303.833409 -64.45776) (xy 303.78384 -64.43512) (xy 303.737998 -64.405657)
			(xy 303.696816 -64.36997) (xy 303.661131 -64.328786) (xy 303.63167 -64.282942) (xy 303.609033 -64.233373)
			(xy 303.593681 -64.181086) (xy 303.585926 -64.127147) (xy 298.160945 -64.127147) (xy 298.222432 -64.298347)
			(xy 298.286109 -64.49956) (xy 298.342033 -64.703064) (xy 298.390121 -64.908561) (xy 298.430303 -65.115749)
			(xy 298.46252 -65.324324) (xy 298.467787 -65.369948) (xy 313.744862 -65.369948) (xy 313.748933 -65.314326)
			(xy 313.761059 -65.259889) (xy 313.780982 -65.207798) (xy 313.808278 -65.159163) (xy 313.842364 -65.11502)
			(xy 313.882513 -65.076311) (xy 313.927871 -65.04386) (xy 313.977471 -65.018359) (xy 314.030255 -65.000352)
			(xy 314.085098 -64.990222) (xy 314.140832 -64.988185) (xy 314.196269 -64.994285) (xy 314.250226 -65.008391)
			(xy 314.301555 -65.030203) (xy 314.332178 -65.048892) (xy 316.214758 -65.048892) (xy 316.218829 -64.99327)
			(xy 316.230955 -64.938833) (xy 316.250878 -64.886742) (xy 316.278174 -64.838107) (xy 316.31226 -64.793964)
			(xy 316.352409 -64.755255) (xy 316.397767 -64.722804) (xy 316.447367 -64.697303) (xy 316.500151 -64.679296)
			(xy 316.554994 -64.669166) (xy 316.610728 -64.667129) (xy 316.666165 -64.673229) (xy 316.720122 -64.687335)
			(xy 316.771451 -64.709147) (xy 316.819057 -64.738201) (xy 316.861925 -64.773876) (xy 316.899142 -64.815413)
			(xy 316.929915 -64.861926) (xy 316.953587 -64.912423) (xy 316.969655 -64.96583) (xy 316.977775 -65.021006)
			(xy 316.978284 -65.048892) (xy 316.977775 -65.076778) (xy 316.969655 -65.131954) (xy 316.964231 -65.149984)
			(xy 320.891408 -65.149984) (xy 320.891863 -65.122613) (xy 320.899683 -65.068434) (xy 320.915175 -65.01593)
			(xy 320.938019 -64.966184) (xy 320.967746 -64.920217) (xy 320.985388 -64.899286) (xy 320.994641 -64.887971)
			(xy 321.006818 -64.861409) (xy 321.010988 -64.832488) (xy 321.006811 -64.803568) (xy 320.994628 -64.777009)
			(xy 320.985388 -64.765682) (xy 320.967772 -64.744731) (xy 320.938057 -64.698763) (xy 320.915217 -64.649021)
			(xy 320.89972 -64.596524) (xy 320.891886 -64.542352) (xy 320.891408 -64.514984) (xy 320.891894 -64.487733)
			(xy 320.89965 -64.433785) (xy 320.915005 -64.38149) (xy 320.937647 -64.331913) (xy 320.967113 -64.286063)
			(xy 321.002804 -64.244872) (xy 321.043995 -64.209181) (xy 321.089845 -64.179715) (xy 321.139422 -64.157073)
			(xy 321.191717 -64.141718) (xy 321.245665 -64.133962) (xy 321.300167 -64.133962) (xy 321.354115 -64.141718)
			(xy 321.40641 -64.157073) (xy 321.455987 -64.179715) (xy 321.501837 -64.209181) (xy 321.543028 -64.244872)
			(xy 321.578719 -64.286063) (xy 321.608185 -64.331913) (xy 321.630827 -64.38149) (xy 321.646182 -64.433785)
			(xy 321.653938 -64.487733) (xy 321.654424 -64.514984) (xy 321.653967 -64.542355) (xy 321.64615 -64.596535)
			(xy 321.63066 -64.649039) (xy 321.607815 -64.698786) (xy 321.578087 -64.744751) (xy 321.560444 -64.765682)
			(xy 321.551227 -64.777023) (xy 321.539055 -64.803577) (xy 321.534881 -64.832488) (xy 321.539048 -64.8614)
			(xy 321.551214 -64.887957) (xy 321.560444 -64.899286) (xy 321.578097 -64.920207) (xy 321.607806 -64.966183)
			(xy 321.630638 -65.015934) (xy 321.646126 -65.068437) (xy 321.653952 -65.122614) (xy 321.654424 -65.149984)
			(xy 321.653938 -65.177235) (xy 321.646182 -65.231183) (xy 321.630827 -65.283478) (xy 321.608185 -65.333055)
			(xy 321.578719 -65.378905) (xy 321.543028 -65.420096) (xy 321.501837 -65.455787) (xy 321.455987 -65.485253)
			(xy 321.40641 -65.507895) (xy 321.354115 -65.52325) (xy 321.300167 -65.531006) (xy 321.245665 -65.531006)
			(xy 321.191717 -65.52325) (xy 321.139422 -65.507895) (xy 321.089845 -65.485253) (xy 321.043995 -65.455787)
			(xy 321.002804 -65.420096) (xy 320.967113 -65.378905) (xy 320.937647 -65.333055) (xy 320.915005 -65.283478)
			(xy 320.89965 -65.231183) (xy 320.891894 -65.177235) (xy 320.891408 -65.149984) (xy 316.964231 -65.149984)
			(xy 316.953587 -65.185361) (xy 316.929915 -65.235858) (xy 316.899142 -65.282371) (xy 316.861925 -65.323908)
			(xy 316.819057 -65.359583) (xy 316.771451 -65.388637) (xy 316.720122 -65.410449) (xy 316.666165 -65.424555)
			(xy 316.610728 -65.430655) (xy 316.554994 -65.428618) (xy 316.500151 -65.418488) (xy 316.447367 -65.400481)
			(xy 316.397767 -65.37498) (xy 316.352409 -65.342529) (xy 316.31226 -65.30382) (xy 316.278174 -65.259677)
			(xy 316.250878 -65.211042) (xy 316.230955 -65.158951) (xy 316.218829 -65.104514) (xy 316.214758 -65.048892)
			(xy 314.332178 -65.048892) (xy 314.349161 -65.059257) (xy 314.392029 -65.094932) (xy 314.429246 -65.136469)
			(xy 314.460019 -65.182982) (xy 314.483691 -65.233479) (xy 314.499759 -65.286886) (xy 314.507879 -65.342062)
			(xy 314.508388 -65.369948) (xy 314.507879 -65.397834) (xy 314.499759 -65.45301) (xy 314.483691 -65.506417)
			(xy 314.460019 -65.556914) (xy 314.429246 -65.603427) (xy 314.392029 -65.644964) (xy 314.349161 -65.680639)
			(xy 314.301555 -65.709693) (xy 314.250226 -65.731505) (xy 314.196269 -65.745611) (xy 314.140832 -65.751711)
			(xy 314.085098 -65.749674) (xy 314.030255 -65.739544) (xy 313.977471 -65.721537) (xy 313.927871 -65.696036)
			(xy 313.882513 -65.663585) (xy 313.842364 -65.624876) (xy 313.808278 -65.580733) (xy 313.780982 -65.532098)
			(xy 313.761059 -65.480007) (xy 313.748933 -65.42557) (xy 313.744862 -65.369948) (xy 298.467787 -65.369948)
			(xy 298.486723 -65.533981) (xy 298.502879 -65.74441) (xy 298.510963 -65.955304) (xy 298.511468 -66.060828)
			(xy 298.511468 -67.3862) (xy 307.186582 -67.3862) (xy 307.190653 -67.330578) (xy 307.202779 -67.276141)
			(xy 307.222702 -67.22405) (xy 307.249998 -67.175415) (xy 307.284084 -67.131272) (xy 307.324233 -67.092563)
			(xy 307.369591 -67.060112) (xy 307.419191 -67.034611) (xy 307.471975 -67.016604) (xy 307.526818 -67.006474)
			(xy 307.582552 -67.004437) (xy 307.637989 -67.010537) (xy 307.691946 -67.024643) (xy 307.743275 -67.046455)
			(xy 307.790881 -67.075509) (xy 307.833749 -67.111184) (xy 307.870966 -67.152721) (xy 307.901739 -67.199234)
			(xy 307.925411 -67.249731) (xy 307.941479 -67.303138) (xy 307.949599 -67.358314) (xy 307.950108 -67.3862)
			(xy 307.949599 -67.414086) (xy 307.941479 -67.469262) (xy 307.925411 -67.522669) (xy 307.901739 -67.573166)
			(xy 307.870966 -67.619679) (xy 307.833749 -67.661216) (xy 307.790881 -67.696891) (xy 307.743275 -67.725945)
			(xy 307.691946 -67.747757) (xy 307.637989 -67.761863) (xy 307.582552 -67.767963) (xy 307.526818 -67.765926)
			(xy 307.471975 -67.755796) (xy 307.419191 -67.737789) (xy 307.369591 -67.712288) (xy 307.324233 -67.679837)
			(xy 307.284084 -67.641128) (xy 307.249998 -67.596985) (xy 307.222702 -67.54835) (xy 307.202779 -67.496259)
			(xy 307.190653 -67.441822) (xy 307.186582 -67.3862) (xy 298.511468 -67.3862) (xy 298.511468 -68.449952)
			(xy 314.840884 -68.449952) (xy 314.844867 -68.321934) (xy 314.856802 -68.194412) (xy 314.876641 -68.067878)
			(xy 314.904308 -67.942822) (xy 314.939697 -67.819729) (xy 314.98267 -67.699073) (xy 315.033061 -67.581323)
			(xy 315.090675 -67.466933) (xy 315.155289 -67.356346) (xy 315.226653 -67.24999) (xy 315.304491 -67.148277)
			(xy 315.388502 -67.051599) (xy 315.478361 -66.960332) (xy 315.57372 -66.874827) (xy 315.674211 -66.795417)
			(xy 315.779444 -66.722407) (xy 315.889013 -66.656081) (xy 316.002493 -66.596695) (xy 316.119445 -66.544479)
			(xy 316.239418 -66.499635) (xy 316.361946 -66.462337) (xy 316.486557 -66.432728) (xy 316.612766 -66.410923)
			(xy 316.740088 -66.397007) (xy 316.868028 -66.391033) (xy 316.996092 -66.393025) (xy 317.123785 -66.402975)
			(xy 317.250612 -66.420844) (xy 317.376083 -66.446563) (xy 317.499712 -66.480033) (xy 317.621021 -66.521124)
			(xy 317.739541 -66.569678) (xy 317.854813 -66.625506) (xy 317.966391 -66.688392) (xy 318.073844 -66.758094)
			(xy 318.176756 -66.834341) (xy 318.274728 -66.916838) (xy 318.367382 -67.005267) (xy 318.454359 -67.099285)
			(xy 318.535323 -67.198528) (xy 318.60996 -67.302613) (xy 318.677982 -67.411137) (xy 318.739126 -67.52368)
			(xy 318.793154 -67.639806) (xy 318.839859 -67.759067) (xy 318.879059 -67.881) (xy 318.910602 -68.005135)
			(xy 318.934367 -68.130991) (xy 318.950261 -68.25808) (xy 318.958224 -68.385912) (xy 318.958722 -68.449952)
			(xy 318.958224 -68.513992) (xy 318.950261 -68.641824) (xy 318.934367 -68.768913) (xy 318.910602 -68.894769)
			(xy 318.879059 -69.018904) (xy 318.839859 -69.140837) (xy 318.793154 -69.260098) (xy 318.739126 -69.376224)
			(xy 318.677982 -69.488767) (xy 318.60996 -69.597291) (xy 318.535323 -69.701376) (xy 318.454359 -69.800619)
			(xy 318.367382 -69.894637) (xy 318.274728 -69.983066) (xy 318.176756 -70.065563) (xy 318.073844 -70.14181)
			(xy 317.966391 -70.211512) (xy 317.854813 -70.274398) (xy 317.739541 -70.330226) (xy 317.621021 -70.37878)
			(xy 317.499712 -70.419871) (xy 317.376083 -70.453341) (xy 317.250612 -70.47906) (xy 317.123785 -70.496929)
			(xy 316.996092 -70.506879) (xy 316.868028 -70.508871) (xy 316.740088 -70.502897) (xy 316.612766 -70.488981)
			(xy 316.486557 -70.467176) (xy 316.361946 -70.437567) (xy 316.239418 -70.400269) (xy 316.119445 -70.355425)
			(xy 316.002493 -70.303209) (xy 315.889013 -70.243823) (xy 315.779444 -70.177497) (xy 315.674211 -70.104487)
			(xy 315.57372 -70.025077) (xy 315.478361 -69.939572) (xy 315.388502 -69.848305) (xy 315.304491 -69.751627)
			(xy 315.226653 -69.649914) (xy 315.155289 -69.543558) (xy 315.090675 -69.432971) (xy 315.033061 -69.318581)
			(xy 314.98267 -69.200831) (xy 314.939697 -69.080175) (xy 314.904308 -68.957082) (xy 314.876641 -68.832026)
			(xy 314.856802 -68.705492) (xy 314.844867 -68.57797) (xy 314.840884 -68.449952) (xy 298.511468 -68.449952)
			(xy 298.511468 -68.872354) (xy 306.542692 -68.872354) (xy 306.546763 -68.816732) (xy 306.558889 -68.762295)
			(xy 306.578812 -68.710204) (xy 306.606108 -68.661569) (xy 306.640194 -68.617426) (xy 306.680343 -68.578717)
			(xy 306.725701 -68.546266) (xy 306.775301 -68.520765) (xy 306.828085 -68.502758) (xy 306.882928 -68.492628)
			(xy 306.938662 -68.490591) (xy 306.994099 -68.496691) (xy 307.048056 -68.510797) (xy 307.099385 -68.532609)
			(xy 307.146991 -68.561663) (xy 307.189859 -68.597338) (xy 307.227076 -68.638875) (xy 307.257849 -68.685388)
			(xy 307.281521 -68.735885) (xy 307.297589 -68.789292) (xy 307.305709 -68.844468) (xy 307.306218 -68.872354)
			(xy 307.305709 -68.90024) (xy 307.297589 -68.955416) (xy 307.281521 -69.008823) (xy 307.257849 -69.05932)
			(xy 307.227076 -69.105833) (xy 307.189859 -69.14737) (xy 307.146991 -69.183045) (xy 307.099385 -69.212099)
			(xy 307.048056 -69.233911) (xy 306.994099 -69.248017) (xy 306.938662 -69.254117) (xy 306.882928 -69.25208)
			(xy 306.828085 -69.24195) (xy 306.775301 -69.223943) (xy 306.725701 -69.198442) (xy 306.680343 -69.165991)
			(xy 306.640194 -69.127282) (xy 306.606108 -69.083139) (xy 306.578812 -69.034504) (xy 306.558889 -68.982413)
			(xy 306.546763 -68.927976) (xy 306.542692 -68.872354) (xy 298.511468 -68.872354) (xy 298.511468 -71.261732)
			(xy 319.374264 -71.261732) (xy 319.378335 -71.20611) (xy 319.390461 -71.151673) (xy 319.410384 -71.099582)
			(xy 319.43768 -71.050947) (xy 319.471766 -71.006804) (xy 319.511915 -70.968095) (xy 319.557273 -70.935644)
			(xy 319.606873 -70.910143) (xy 319.659657 -70.892136) (xy 319.7145 -70.882006) (xy 319.770234 -70.879969)
			(xy 319.825671 -70.886069) (xy 319.879628 -70.900175) (xy 319.930957 -70.921987) (xy 319.978563 -70.951041)
			(xy 320.021431 -70.986716) (xy 320.058648 -71.028253) (xy 320.089421 -71.074766) (xy 320.113093 -71.125263)
			(xy 320.129161 -71.17867) (xy 320.137281 -71.233846) (xy 320.13779 -71.261732) (xy 320.137281 -71.289618)
			(xy 320.129161 -71.344794) (xy 320.113093 -71.398201) (xy 320.089421 -71.448698) (xy 320.058648 -71.495211)
			(xy 320.021431 -71.536748) (xy 319.978563 -71.572423) (xy 319.930957 -71.601477) (xy 319.879628 -71.623289)
			(xy 319.825671 -71.637395) (xy 319.770234 -71.643495) (xy 319.7145 -71.641458) (xy 319.659657 -71.631328)
			(xy 319.606873 -71.613321) (xy 319.557273 -71.58782) (xy 319.511915 -71.555369) (xy 319.471766 -71.51666)
			(xy 319.43768 -71.472517) (xy 319.410384 -71.423882) (xy 319.390461 -71.371791) (xy 319.378335 -71.317354)
			(xy 319.374264 -71.261732) (xy 298.511468 -71.261732) (xy 298.511468 -73.612756) (xy 299.439074 -73.612756)
			(xy 299.443145 -73.557134) (xy 299.455271 -73.502697) (xy 299.475194 -73.450606) (xy 299.50249 -73.401971)
			(xy 299.536576 -73.357828) (xy 299.576725 -73.319119) (xy 299.622083 -73.286668) (xy 299.671683 -73.261167)
			(xy 299.724467 -73.24316) (xy 299.77931 -73.23303) (xy 299.835044 -73.230993) (xy 299.890481 -73.237093)
			(xy 299.944438 -73.251199) (xy 299.995767 -73.273011) (xy 300.043373 -73.302065) (xy 300.086241 -73.33774)
			(xy 300.123458 -73.379277) (xy 300.154231 -73.42579) (xy 300.177903 -73.476287) (xy 300.193971 -73.529694)
			(xy 300.202091 -73.58487) (xy 300.2026 -73.612756) (xy 300.202091 -73.640642) (xy 300.193971 -73.695818)
			(xy 300.177903 -73.749225) (xy 300.154231 -73.799722) (xy 300.123458 -73.846235) (xy 300.086241 -73.887772)
			(xy 300.043373 -73.923447) (xy 299.995767 -73.952501) (xy 299.944438 -73.974313) (xy 299.890481 -73.988419)
			(xy 299.835044 -73.994519) (xy 299.77931 -73.992482) (xy 299.724467 -73.982352) (xy 299.671683 -73.964345)
			(xy 299.622083 -73.938844) (xy 299.576725 -73.906393) (xy 299.536576 -73.867684) (xy 299.50249 -73.823541)
			(xy 299.475194 -73.774906) (xy 299.455271 -73.722815) (xy 299.443145 -73.668378) (xy 299.439074 -73.612756)
			(xy 298.511468 -73.612756) (xy 298.511468 -74.418444) (xy 319.213482 -74.418444) (xy 319.217553 -74.362822)
			(xy 319.229679 -74.308385) (xy 319.249602 -74.256294) (xy 319.276898 -74.207659) (xy 319.310984 -74.163516)
			(xy 319.351133 -74.124807) (xy 319.396491 -74.092356) (xy 319.446091 -74.066855) (xy 319.498875 -74.048848)
			(xy 319.553718 -74.038718) (xy 319.609452 -74.036681) (xy 319.664889 -74.042781) (xy 319.718846 -74.056887)
			(xy 319.770175 -74.078699) (xy 319.817781 -74.107753) (xy 319.860649 -74.143428) (xy 319.897866 -74.184965)
			(xy 319.928639 -74.231478) (xy 319.952311 -74.281975) (xy 319.968379 -74.335382) (xy 319.976499 -74.390558)
			(xy 319.977008 -74.418444) (xy 319.976499 -74.44633) (xy 319.968379 -74.501506) (xy 319.952311 -74.554913)
			(xy 319.928639 -74.60541) (xy 319.897866 -74.651923) (xy 319.860649 -74.69346) (xy 319.817781 -74.729135)
			(xy 319.770175 -74.758189) (xy 319.718846 -74.780001) (xy 319.664889 -74.794107) (xy 319.609452 -74.800207)
			(xy 319.553718 -74.79817) (xy 319.498875 -74.78804) (xy 319.446091 -74.770033) (xy 319.396491 -74.744532)
			(xy 319.351133 -74.712081) (xy 319.310984 -74.673372) (xy 319.276898 -74.629229) (xy 319.249602 -74.580594)
			(xy 319.229679 -74.528503) (xy 319.217553 -74.474066) (xy 319.213482 -74.418444) (xy 298.511468 -74.418444)
			(xy 298.511468 -74.760836) (xy 298.510963 -74.86636) (xy 298.502879 -75.077254) (xy 298.492967 -75.206352)
			(xy 301.575722 -75.206352) (xy 301.579793 -75.15073) (xy 301.591919 -75.096293) (xy 301.611842 -75.044202)
			(xy 301.639138 -74.995567) (xy 301.673224 -74.951424) (xy 301.713373 -74.912715) (xy 301.758731 -74.880264)
			(xy 301.808331 -74.854763) (xy 301.861115 -74.836756) (xy 301.915958 -74.826626) (xy 301.971692 -74.824589)
			(xy 302.027129 -74.830689) (xy 302.081086 -74.844795) (xy 302.117818 -74.860404) (xy 320.458082 -74.860404)
			(xy 320.462153 -74.804782) (xy 320.474279 -74.750345) (xy 320.494202 -74.698254) (xy 320.521498 -74.649619)
			(xy 320.555584 -74.605476) (xy 320.595733 -74.566767) (xy 320.641091 -74.534316) (xy 320.690691 -74.508815)
			(xy 320.743475 -74.490808) (xy 320.798318 -74.480678) (xy 320.854052 -74.478641) (xy 320.909489 -74.484741)
			(xy 320.963446 -74.498847) (xy 321.014775 -74.520659) (xy 321.062381 -74.549713) (xy 321.105249 -74.585388)
			(xy 321.142466 -74.626925) (xy 321.173239 -74.673438) (xy 321.196911 -74.723935) (xy 321.212979 -74.777342)
			(xy 321.218101 -74.812144) (xy 322.187822 -74.812144) (xy 322.191893 -74.756522) (xy 322.204019 -74.702085)
			(xy 322.223942 -74.649994) (xy 322.251238 -74.601359) (xy 322.285324 -74.557216) (xy 322.325473 -74.518507)
			(xy 322.370831 -74.486056) (xy 322.420431 -74.460555) (xy 322.473215 -74.442548) (xy 322.528058 -74.432418)
			(xy 322.583792 -74.430381) (xy 322.639229 -74.436481) (xy 322.693186 -74.450587) (xy 322.744515 -74.472399)
			(xy 322.792121 -74.501453) (xy 322.834989 -74.537128) (xy 322.872206 -74.578665) (xy 322.902979 -74.625178)
			(xy 322.926651 -74.675675) (xy 322.942719 -74.729082) (xy 322.950839 -74.784258) (xy 322.951348 -74.812144)
			(xy 322.950839 -74.84003) (xy 322.942719 -74.895206) (xy 322.926651 -74.948613) (xy 322.902979 -74.99911)
			(xy 322.872206 -75.045623) (xy 322.834989 -75.08716) (xy 322.792121 -75.122835) (xy 322.744515 -75.151889)
			(xy 322.693186 -75.173701) (xy 322.639229 -75.187807) (xy 322.583792 -75.193907) (xy 322.528058 -75.19187)
			(xy 322.473215 -75.18174) (xy 322.420431 -75.163733) (xy 322.370831 -75.138232) (xy 322.325473 -75.105781)
			(xy 322.285324 -75.067072) (xy 322.251238 -75.022929) (xy 322.223942 -74.974294) (xy 322.204019 -74.922203)
			(xy 322.191893 -74.867766) (xy 322.187822 -74.812144) (xy 321.218101 -74.812144) (xy 321.221099 -74.832518)
			(xy 321.221608 -74.860404) (xy 321.221099 -74.88829) (xy 321.212979 -74.943466) (xy 321.196911 -74.996873)
			(xy 321.173239 -75.04737) (xy 321.142466 -75.093883) (xy 321.105249 -75.13542) (xy 321.062381 -75.171095)
			(xy 321.014775 -75.200149) (xy 320.963446 -75.221961) (xy 320.909489 -75.236067) (xy 320.854052 -75.242167)
			(xy 320.798318 -75.24013) (xy 320.743475 -75.23) (xy 320.690691 -75.211993) (xy 320.641091 -75.186492)
			(xy 320.595733 -75.154041) (xy 320.555584 -75.115332) (xy 320.521498 -75.071189) (xy 320.494202 -75.022554)
			(xy 320.474279 -74.970463) (xy 320.462153 -74.916026) (xy 320.458082 -74.860404) (xy 302.117818 -74.860404)
			(xy 302.132415 -74.866607) (xy 302.180021 -74.895661) (xy 302.222889 -74.931336) (xy 302.260106 -74.972873)
			(xy 302.290879 -75.019386) (xy 302.314551 -75.069883) (xy 302.330619 -75.12329) (xy 302.338739 -75.178466)
			(xy 302.339248 -75.206352) (xy 302.338739 -75.234238) (xy 302.330619 -75.289414) (xy 302.314551 -75.342821)
			(xy 302.290879 -75.393318) (xy 302.260106 -75.439831) (xy 302.222889 -75.481368) (xy 302.180021 -75.517043)
			(xy 302.132415 -75.546097) (xy 302.081086 -75.567909) (xy 302.027129 -75.582015) (xy 301.971692 -75.588115)
			(xy 301.915958 -75.586078) (xy 301.861115 -75.575948) (xy 301.808331 -75.557941) (xy 301.758731 -75.53244)
			(xy 301.713373 -75.499989) (xy 301.673224 -75.46128) (xy 301.639138 -75.417137) (xy 301.611842 -75.368502)
			(xy 301.591919 -75.316411) (xy 301.579793 -75.261974) (xy 301.575722 -75.206352) (xy 298.492967 -75.206352)
			(xy 298.486723 -75.287683) (xy 298.46252 -75.49734) (xy 298.430303 -75.705915) (xy 298.390121 -75.913103)
			(xy 298.384087 -75.938888) (xy 300.933612 -75.938888) (xy 300.934098 -75.911637) (xy 300.941854 -75.857689)
			(xy 300.957209 -75.805394) (xy 300.979851 -75.755817) (xy 301.009317 -75.709967) (xy 301.045008 -75.668776)
			(xy 301.086199 -75.633085) (xy 301.132049 -75.603619) (xy 301.181626 -75.580977) (xy 301.233921 -75.565622)
			(xy 301.287869 -75.557866) (xy 301.342371 -75.557866) (xy 301.396319 -75.565622) (xy 301.448614 -75.580977)
			(xy 301.498191 -75.603619) (xy 301.544041 -75.633085) (xy 301.585232 -75.668776) (xy 301.620923 -75.709967)
			(xy 301.650389 -75.755817) (xy 301.673031 -75.805394) (xy 301.688386 -75.857689) (xy 301.696142 -75.911637)
			(xy 301.696628 -75.938888) (xy 301.696075 -75.968532) (xy 301.686911 -76.027108) (xy 301.6688 -76.083562)
			(xy 301.642179 -76.136538) (xy 301.607688 -76.184761) (xy 301.566156 -76.227071) (xy 301.542704 -76.245212)
			(xy 301.530826 -76.254694) (xy 301.512843 -76.279177) (xy 301.50286 -76.307868) (xy 301.50176 -76.338226)
			(xy 301.509643 -76.367563) (xy 301.525808 -76.393283) (xy 301.548826 -76.413107) (xy 301.562516 -76.41971)
			(xy 301.587683 -76.431193) (xy 301.634644 -76.460431) (xy 301.676893 -76.496142) (xy 301.713543 -76.537578)
			(xy 301.743827 -76.583871) (xy 301.767111 -76.634051) (xy 301.782907 -76.687067) (xy 301.790883 -76.741808)
			(xy 301.79137 -76.769468) (xy 301.790884 -76.796719) (xy 301.783128 -76.850667) (xy 301.767773 -76.902962)
			(xy 301.745131 -76.952539) (xy 301.715665 -76.998389) (xy 301.679974 -77.03958) (xy 301.638783 -77.075271)
			(xy 301.592933 -77.104737) (xy 301.543356 -77.127379) (xy 301.491061 -77.142734) (xy 301.437113 -77.15049)
			(xy 301.382611 -77.15049) (xy 301.328663 -77.142734) (xy 301.276368 -77.127379) (xy 301.226791 -77.104737)
			(xy 301.180941 -77.075271) (xy 301.13975 -77.03958) (xy 301.104059 -76.998389) (xy 301.074593 -76.952539)
			(xy 301.051951 -76.902962) (xy 301.036596 -76.850667) (xy 301.02884 -76.796719) (xy 301.028354 -76.769468)
			(xy 301.028882 -76.739823) (xy 301.038052 -76.681246) (xy 301.056168 -76.624792) (xy 301.082794 -76.571816)
			(xy 301.117289 -76.523594) (xy 301.158824 -76.481284) (xy 301.182278 -76.463144) (xy 301.1941 -76.453596)
			(xy 301.212087 -76.42913) (xy 301.222076 -76.400454) (xy 301.223184 -76.370108) (xy 301.215312 -76.34078)
			(xy 301.199157 -76.315067) (xy 301.176151 -76.295247) (xy 301.162466 -76.288646) (xy 301.137339 -76.277079)
			(xy 301.090377 -76.247856) (xy 301.048125 -76.212159) (xy 301.011471 -76.170735) (xy 300.981181 -76.124454)
			(xy 300.95789 -76.074284) (xy 300.942087 -76.021277) (xy 300.934103 -75.966544) (xy 300.933612 -75.938888)
			(xy 298.384087 -75.938888) (xy 298.342033 -76.1186) (xy 298.286109 -76.322104) (xy 298.222432 -76.523317)
			(xy 298.151094 -76.721944) (xy 298.0722 -76.917692) (xy 297.985867 -77.110274) (xy 297.89222 -77.299409)
			(xy 297.791398 -77.484818) (xy 297.683548 -77.666229) (xy 297.637583 -77.737208) (xy 299.706282 -77.737208)
			(xy 299.710353 -77.681586) (xy 299.722479 -77.627149) (xy 299.742402 -77.575058) (xy 299.769698 -77.526423)
			(xy 299.803784 -77.48228) (xy 299.843933 -77.443571) (xy 299.889291 -77.41112) (xy 299.938891 -77.385619)
			(xy 299.991675 -77.367612) (xy 300.046518 -77.357482) (xy 300.102252 -77.355445) (xy 300.157689 -77.361545)
			(xy 300.211646 -77.375651) (xy 300.262975 -77.397463) (xy 300.310581 -77.426517) (xy 300.353449 -77.462192)
			(xy 300.390666 -77.503729) (xy 300.421439 -77.550242) (xy 300.445111 -77.600739) (xy 300.461179 -77.654146)
			(xy 300.469299 -77.709322) (xy 300.469808 -77.737208) (xy 300.469299 -77.765094) (xy 300.461179 -77.82027)
			(xy 300.445111 -77.873677) (xy 300.421439 -77.924174) (xy 300.390666 -77.970687) (xy 300.353449 -78.012224)
			(xy 300.310581 -78.047899) (xy 300.262975 -78.076953) (xy 300.211646 -78.098765) (xy 300.157689 -78.112871)
			(xy 300.102252 -78.118971) (xy 300.046518 -78.116934) (xy 299.991675 -78.106804) (xy 299.938891 -78.088797)
			(xy 299.889291 -78.063296) (xy 299.843933 -78.030845) (xy 299.803784 -77.992136) (xy 299.769698 -77.947993)
			(xy 299.742402 -77.899358) (xy 299.722479 -77.847267) (xy 299.710353 -77.79283) (xy 299.706282 -77.737208)
			(xy 297.637583 -77.737208) (xy 297.568829 -77.843376) (xy 297.447409 -78.015998) (xy 297.319466 -78.183844)
			(xy 297.185188 -78.346666) (xy 297.044772 -78.504225) (xy 296.898424 -78.65629) (xy 296.746359 -78.802638)
			(xy 296.5888 -78.943054) (xy 296.557208 -78.969108) (xy 297.189142 -78.969108) (xy 297.193213 -78.913486)
			(xy 297.205339 -78.859049) (xy 297.225262 -78.806958) (xy 297.252558 -78.758323) (xy 297.286644 -78.71418)
			(xy 297.326793 -78.675471) (xy 297.372151 -78.64302) (xy 297.421751 -78.617519) (xy 297.474535 -78.599512)
			(xy 297.529378 -78.589382) (xy 297.585112 -78.587345) (xy 297.640549 -78.593445) (xy 297.694506 -78.607551)
			(xy 297.745835 -78.629363) (xy 297.793441 -78.658417) (xy 297.836309 -78.694092) (xy 297.873526 -78.735629)
			(xy 297.904299 -78.782142) (xy 297.927971 -78.832639) (xy 297.944039 -78.886046) (xy 297.952159 -78.941222)
			(xy 297.952668 -78.969108) (xy 297.952159 -78.996994) (xy 297.944039 -79.05217) (xy 297.927971 -79.105577)
			(xy 297.904299 -79.156074) (xy 297.873526 -79.202587) (xy 297.836309 -79.244124) (xy 297.793441 -79.279799)
			(xy 297.745835 -79.308853) (xy 297.694506 -79.330665) (xy 297.640549 -79.344771) (xy 297.585112 -79.350871)
			(xy 297.529378 -79.348834) (xy 297.474535 -79.338704) (xy 297.421751 -79.320697) (xy 297.372151 -79.295196)
			(xy 297.326793 -79.262745) (xy 297.286644 -79.224036) (xy 297.252558 -79.179893) (xy 297.225262 -79.131258)
			(xy 297.205339 -79.079167) (xy 297.193213 -79.02473) (xy 297.189142 -78.969108) (xy 296.557208 -78.969108)
			(xy 296.425978 -79.077332) (xy 296.258132 -79.205275) (xy 296.08551 -79.326695) (xy 295.908363 -79.441414)
			(xy 295.726952 -79.549264) (xy 295.541543 -79.650086) (xy 295.352408 -79.743733) (xy 295.159826 -79.830066)
			(xy 294.964078 -79.90896) (xy 294.765451 -79.980298) (xy 294.564238 -80.043975) (xy 294.360734 -80.099899)
			(xy 294.155237 -80.147987) (xy 293.948049 -80.188169) (xy 293.739474 -80.220386) (xy 293.529817 -80.244589)
			(xy 293.319388 -80.260745) (xy 293.108494 -80.268829) (xy 292.897446 -80.268829) (xy 292.686552 -80.260745)
			(xy 292.476123 -80.244589) (xy 292.266466 -80.220386) (xy 292.057891 -80.188169) (xy 291.850703 -80.147987)
			(xy 291.645206 -80.099899) (xy 291.441702 -80.043975) (xy 291.240489 -79.980298) (xy 291.041862 -79.90896)
			(xy 290.846114 -79.830066) (xy 290.653532 -79.743733) (xy 290.464397 -79.650086) (xy 290.278988 -79.549264)
			(xy 290.097577 -79.441414) (xy 289.92043 -79.326695) (xy 289.747808 -79.205275) (xy 289.579962 -79.077332)
			(xy 289.41714 -78.943054) (xy 289.259581 -78.802638) (xy 289.107516 -78.65629) (xy 288.961168 -78.504225)
			(xy 288.820752 -78.346666) (xy 288.686474 -78.183844) (xy 288.558531 -78.015998) (xy 288.437111 -77.843376)
			(xy 288.322392 -77.666229) (xy 288.214542 -77.484818) (xy 288.11372 -77.299409) (xy 288.020073 -77.110274)
			(xy 287.93374 -76.917692) (xy 287.854846 -76.721944) (xy 287.783508 -76.523317) (xy 287.719831 -76.322104)
			(xy 287.663907 -76.1186) (xy 287.615819 -75.913103) (xy 287.575637 -75.705915) (xy 287.54342 -75.49734)
			(xy 287.519217 -75.287683) (xy 287.503061 -75.077254) (xy 287.494977 -74.86636) (xy 287.494472 -74.760836)
			(xy 273.02714 -74.760836) (xy 273.02714 -75.806156) (xy 274.987923 -75.806156) (xy 274.987923 -75.751644)
			(xy 274.995681 -75.697687) (xy 275.011039 -75.645383) (xy 275.033685 -75.595797) (xy 275.063158 -75.549939)
			(xy 275.098857 -75.508742) (xy 275.140055 -75.473046) (xy 275.185915 -75.443576) (xy 275.235502 -75.420932)
			(xy 275.287806 -75.405577) (xy 275.341764 -75.397822) (xy 275.36902 -75.39736) (xy 275.396391 -75.3978)
			(xy 275.450572 -75.405622) (xy 275.503076 -75.421116) (xy 275.552823 -75.443964) (xy 275.598788 -75.473695)
			(xy 275.619718 -75.49134) (xy 275.631046 -75.500576) (xy 275.657603 -75.512752) (xy 275.68652 -75.516925)
			(xy 275.715437 -75.512752) (xy 275.741994 -75.500576) (xy 275.753322 -75.49134) (xy 275.774255 -75.473699)
			(xy 275.820223 -75.443975) (xy 275.869969 -75.421129) (xy 275.922471 -75.405633) (xy 275.976649 -75.397804)
			(xy 276.031391 -75.397804) (xy 276.085569 -75.405633) (xy 276.138071 -75.421129) (xy 276.187817 -75.443975)
			(xy 276.233785 -75.473699) (xy 276.254718 -75.49134) (xy 276.266046 -75.500576) (xy 276.292603 -75.512752)
			(xy 276.32152 -75.516925) (xy 276.350437 -75.512752) (xy 276.376994 -75.500576) (xy 276.388322 -75.49134)
			(xy 276.409255 -75.473699) (xy 276.455223 -75.443975) (xy 276.504969 -75.421129) (xy 276.557471 -75.405633)
			(xy 276.611649 -75.397804) (xy 276.666391 -75.397804) (xy 276.720569 -75.405633) (xy 276.773071 -75.421129)
			(xy 276.822817 -75.443975) (xy 276.868785 -75.473699) (xy 276.889718 -75.49134) (xy 276.901046 -75.500576)
			(xy 276.927603 -75.512752) (xy 276.95652 -75.516925) (xy 276.985437 -75.512752) (xy 277.011994 -75.500576)
			(xy 277.023322 -75.49134) (xy 277.044255 -75.473699) (xy 277.090223 -75.443975) (xy 277.139969 -75.421129)
			(xy 277.192471 -75.405633) (xy 277.246649 -75.397804) (xy 277.301391 -75.397804) (xy 277.355569 -75.405633)
			(xy 277.408071 -75.421129) (xy 277.457817 -75.443975) (xy 277.503785 -75.473699) (xy 277.524718 -75.49134)
			(xy 277.536046 -75.500576) (xy 277.562603 -75.512752) (xy 277.59152 -75.516925) (xy 277.620437 -75.512752)
			(xy 277.646994 -75.500576) (xy 277.658322 -75.49134) (xy 277.679278 -75.47373) (xy 277.725243 -75.444013)
			(xy 277.774985 -75.42117) (xy 277.827481 -75.405673) (xy 277.881652 -75.397837) (xy 277.90902 -75.39736)
			(xy 277.936268 -75.397912) (xy 277.990209 -75.40567) (xy 278.042497 -75.421025) (xy 278.092067 -75.443666)
			(xy 278.137911 -75.47313) (xy 278.179096 -75.508818) (xy 278.214782 -75.550005) (xy 278.244244 -75.59585)
			(xy 278.266882 -75.645422) (xy 278.282235 -75.697711) (xy 278.28999 -75.751652) (xy 278.28999 -75.806148)
			(xy 278.282235 -75.860089) (xy 278.266882 -75.912378) (xy 278.244244 -75.96195) (xy 278.214782 -76.007795)
			(xy 278.179096 -76.048982) (xy 278.137911 -76.08467) (xy 278.092067 -76.114134) (xy 278.042497 -76.136775)
			(xy 277.990209 -76.15213) (xy 277.936268 -76.159888) (xy 277.90902 -76.160376) (xy 277.88165 -76.159904)
			(xy 277.827471 -76.152089) (xy 277.774968 -76.136601) (xy 277.725221 -76.113761) (xy 277.679254 -76.084037)
			(xy 277.658322 -76.066396) (xy 277.646994 -76.05716) (xy 277.620437 -76.044984) (xy 277.59152 -76.040811)
			(xy 277.562603 -76.044984) (xy 277.536046 -76.05716) (xy 277.524718 -76.066396) (xy 277.503785 -76.084037)
			(xy 277.457817 -76.113761) (xy 277.408071 -76.136607) (xy 277.355569 -76.152103) (xy 277.301391 -76.159932)
			(xy 277.246649 -76.159932) (xy 277.192471 -76.152103) (xy 277.139969 -76.136607) (xy 277.090223 -76.113761)
			(xy 277.044255 -76.084037) (xy 277.023322 -76.066396) (xy 277.011994 -76.05716) (xy 276.985437 -76.044984)
			(xy 276.95652 -76.040811) (xy 276.927603 -76.044984) (xy 276.901046 -76.05716) (xy 276.889718 -76.066396)
			(xy 276.868785 -76.084037) (xy 276.822817 -76.113761) (xy 276.773071 -76.136607) (xy 276.720569 -76.152103)
			(xy 276.666391 -76.159932) (xy 276.611649 -76.159932) (xy 276.557471 -76.152103) (xy 276.504969 -76.136607)
			(xy 276.455223 -76.113761) (xy 276.409255 -76.084037) (xy 276.388322 -76.066396) (xy 276.376994 -76.05716)
			(xy 276.350437 -76.044984) (xy 276.32152 -76.040811) (xy 276.292603 -76.044984) (xy 276.266046 -76.05716)
			(xy 276.254718 -76.066396) (xy 276.233785 -76.084037) (xy 276.187817 -76.113761) (xy 276.138071 -76.136607)
			(xy 276.085569 -76.152103) (xy 276.031391 -76.159932) (xy 275.976649 -76.159932) (xy 275.922471 -76.152103)
			(xy 275.869969 -76.136607) (xy 275.820223 -76.113761) (xy 275.774255 -76.084037) (xy 275.753322 -76.066396)
			(xy 275.741994 -76.05716) (xy 275.715437 -76.044984) (xy 275.68652 -76.040811) (xy 275.657603 -76.044984)
			(xy 275.631046 -76.05716) (xy 275.619718 -76.066396) (xy 275.598789 -76.084039) (xy 275.552816 -76.113751)
			(xy 275.503067 -76.136586) (xy 275.450566 -76.152076) (xy 275.396389 -76.159903) (xy 275.36902 -76.160376)
			(xy 275.341764 -76.159978) (xy 275.287806 -76.152223) (xy 275.235502 -76.136868) (xy 275.185915 -76.114224)
			(xy 275.140055 -76.084754) (xy 275.098857 -76.049058) (xy 275.063158 -76.007861) (xy 275.033685 -75.962003)
			(xy 275.011039 -75.912417) (xy 274.995681 -75.860113) (xy 274.987923 -75.806156) (xy 273.02714 -75.806156)
			(xy 273.02714 -77.668148) (xy 284.62202 -77.668148) (xy 284.62202 -77.613652) (xy 284.629775 -77.559712)
			(xy 284.645128 -77.507424) (xy 284.667766 -77.457853) (xy 284.697227 -77.412009) (xy 284.732913 -77.370823)
			(xy 284.774097 -77.335136) (xy 284.819941 -77.305672) (xy 284.869511 -77.283033) (xy 284.921798 -77.267678)
			(xy 284.975738 -77.259921) (xy 285.002986 -77.259434) (xy 285.029597 -77.259964) (xy 285.0823 -77.267372)
			(xy 285.133463 -77.282031) (xy 285.182092 -77.303658) (xy 285.227245 -77.331832) (xy 285.268044 -77.366007)
			(xy 285.303698 -77.405521) (xy 285.333516 -77.449605) (xy 285.345632 -77.473302) (xy 285.352049 -77.485424)
			(xy 285.370239 -77.505939) (xy 285.393234 -77.52087) (xy 285.419375 -77.529139) (xy 285.446774 -77.530149)
			(xy 285.473453 -77.523827) (xy 285.497485 -77.51063) (xy 285.517136 -77.491511) (xy 285.524448 -77.479906)
			(xy 285.5364 -77.460137) (xy 285.564365 -77.423367) (xy 285.596582 -77.390258) (xy 285.614364 -77.375512)
			(xy 285.625639 -77.365781) (xy 285.642478 -77.341231) (xy 285.651515 -77.312866) (xy 285.651981 -77.2831)
			(xy 285.643838 -77.254466) (xy 285.627778 -77.2294) (xy 285.605167 -77.210036) (xy 285.591758 -77.203554)
			(xy 285.566767 -77.192007) (xy 285.520152 -77.162723) (xy 285.47823 -77.12704) (xy 285.441874 -77.085702)
			(xy 285.411839 -77.039566) (xy 285.388748 -76.989592) (xy 285.373082 -76.936817) (xy 285.365166 -76.882338)
			(xy 285.364682 -76.854812) (xy 285.365168 -76.827561) (xy 285.372924 -76.773613) (xy 285.388279 -76.721318)
			(xy 285.410921 -76.671741) (xy 285.440387 -76.625891) (xy 285.476078 -76.5847) (xy 285.517269 -76.549009)
			(xy 285.563119 -76.519543) (xy 285.612696 -76.496901) (xy 285.664991 -76.481546) (xy 285.718939 -76.47379)
			(xy 285.773441 -76.47379) (xy 285.827389 -76.481546) (xy 285.879684 -76.496901) (xy 285.929261 -76.519543)
			(xy 285.975111 -76.549009) (xy 286.016302 -76.5847) (xy 286.043248 -76.615798) (xy 286.636712 -76.615798)
			(xy 286.640783 -76.560176) (xy 286.652909 -76.505739) (xy 286.672832 -76.453648) (xy 286.700128 -76.405013)
			(xy 286.734214 -76.36087) (xy 286.774363 -76.322161) (xy 286.819721 -76.28971) (xy 286.869321 -76.264209)
			(xy 286.922105 -76.246202) (xy 286.976948 -76.236072) (xy 287.032682 -76.234035) (xy 287.088119 -76.240135)
			(xy 287.142076 -76.254241) (xy 287.193405 -76.276053) (xy 287.241011 -76.305107) (xy 287.283879 -76.340782)
			(xy 287.321096 -76.382319) (xy 287.351869 -76.428832) (xy 287.375541 -76.479329) (xy 287.391609 -76.532736)
			(xy 287.399729 -76.587912) (xy 287.400238 -76.615798) (xy 287.399729 -76.643684) (xy 287.391609 -76.69886)
			(xy 287.375541 -76.752267) (xy 287.351869 -76.802764) (xy 287.321096 -76.849277) (xy 287.283879 -76.890814)
			(xy 287.241011 -76.926489) (xy 287.193405 -76.955543) (xy 287.142076 -76.977355) (xy 287.088119 -76.991461)
			(xy 287.032682 -76.997561) (xy 286.976948 -76.995524) (xy 286.922105 -76.985394) (xy 286.869321 -76.967387)
			(xy 286.819721 -76.941886) (xy 286.774363 -76.909435) (xy 286.734214 -76.870726) (xy 286.700128 -76.826583)
			(xy 286.672832 -76.777948) (xy 286.652909 -76.725857) (xy 286.640783 -76.67142) (xy 286.636712 -76.615798)
			(xy 286.043248 -76.615798) (xy 286.051993 -76.625891) (xy 286.081459 -76.671741) (xy 286.104101 -76.721318)
			(xy 286.119456 -76.773613) (xy 286.127212 -76.827561) (xy 286.127698 -76.854812) (xy 286.127137 -76.883182)
			(xy 286.118733 -76.939296) (xy 286.102111 -76.993546) (xy 286.07764 -77.044737) (xy 286.045857 -77.09174)
			(xy 286.007464 -77.133518) (xy 285.985712 -77.151738) (xy 285.974388 -77.161416) (xy 285.957555 -77.18598)
			(xy 285.948525 -77.214356) (xy 285.948066 -77.244131) (xy 285.956218 -77.272772) (xy 285.972286 -77.297843)
			(xy 285.994905 -77.317212) (xy 286.008318 -77.323696) (xy 286.033284 -77.335294) (xy 286.079899 -77.364571)
			(xy 286.121821 -77.400245) (xy 286.158179 -77.441576) (xy 286.188218 -77.487705) (xy 286.211312 -77.537672)
			(xy 286.226984 -77.590441) (xy 286.234906 -77.644915) (xy 286.235394 -77.672438) (xy 286.234957 -77.699691)
			(xy 286.227195 -77.753641) (xy 286.211835 -77.805938) (xy 286.189188 -77.855516) (xy 286.159717 -77.901367)
			(xy 286.12402 -77.942557) (xy 286.082825 -77.978248) (xy 286.03697 -78.007713) (xy 285.987389 -78.030353)
			(xy 285.93509 -78.045707) (xy 285.881139 -78.053461) (xy 285.853886 -78.053946) (xy 285.827274 -78.05345)
			(xy 285.774569 -78.046038) (xy 285.723404 -78.031375) (xy 285.674774 -78.009743) (xy 285.629622 -77.981564)
			(xy 285.588823 -77.947384) (xy 285.55317 -77.907866) (xy 285.523355 -77.863777) (xy 285.51124 -77.840078)
			(xy 285.504864 -77.827934) (xy 285.486666 -77.80742) (xy 285.463663 -77.792491) (xy 285.437515 -77.784225)
			(xy 285.410111 -77.783218) (xy 285.383428 -77.789543) (xy 285.359392 -77.802744) (xy 285.339737 -77.821867)
			(xy 285.332424 -77.833474) (xy 285.317609 -77.857718) (xy 285.28198 -77.901973) (xy 285.240183 -77.940455)
			(xy 285.193142 -77.972314) (xy 285.141896 -77.996845) (xy 285.08758 -78.013506) (xy 285.031393 -78.021929)
			(xy 285.002986 -78.02245) (xy 284.975738 -78.021879) (xy 284.921798 -78.014122) (xy 284.869511 -77.998767)
			(xy 284.819941 -77.976128) (xy 284.774097 -77.946664) (xy 284.732913 -77.910977) (xy 284.697227 -77.869791)
			(xy 284.667766 -77.823947) (xy 284.645128 -77.774376) (xy 284.629775 -77.722088) (xy 284.62202 -77.668148)
			(xy 273.02714 -77.668148) (xy 273.02714 -79.2988) (xy 284.236158 -79.2988) (xy 284.240229 -79.243178)
			(xy 284.252355 -79.188741) (xy 284.272278 -79.13665) (xy 284.299574 -79.088015) (xy 284.33366 -79.043872)
			(xy 284.373809 -79.005163) (xy 284.419167 -78.972712) (xy 284.468767 -78.947211) (xy 284.521551 -78.929204)
			(xy 284.576394 -78.919074) (xy 284.632128 -78.917037) (xy 284.687565 -78.923137) (xy 284.741522 -78.937243)
			(xy 284.792851 -78.959055) (xy 284.840457 -78.988109) (xy 284.883325 -79.023784) (xy 284.920542 -79.065321)
			(xy 284.951315 -79.111834) (xy 284.974987 -79.162331) (xy 284.991055 -79.215738) (xy 284.999175 -79.270914)
			(xy 284.999684 -79.2988) (xy 284.999175 -79.326686) (xy 284.991055 -79.381862) (xy 284.974987 -79.435269)
			(xy 284.951315 -79.485766) (xy 284.920542 -79.532279) (xy 284.883325 -79.573816) (xy 284.840457 -79.609491)
			(xy 284.792851 -79.638545) (xy 284.741522 -79.660357) (xy 284.687565 -79.674463) (xy 284.632128 -79.680563)
			(xy 284.576394 -79.678526) (xy 284.521551 -79.668396) (xy 284.468767 -79.650389) (xy 284.419167 -79.624888)
			(xy 284.373809 -79.592437) (xy 284.33366 -79.553728) (xy 284.299574 -79.509585) (xy 284.272278 -79.46095)
			(xy 284.252355 -79.408859) (xy 284.240229 -79.354422) (xy 284.236158 -79.2988) (xy 273.02714 -79.2988)
			(xy 273.02714 -80.829912) (xy 274.716748 -82.51952) (xy 303.301146 -82.51952)
		)
		(stroke
			(width 0)
			(type solid)
		)
		(fill yes)
		(layer "In4.Cu")
		(net "P1V05_PCH_AUX")
	)
	(gr_poly
		(pts
			(xy 373.634 -270.63827) (xy 373.644496 -270.627042) (xy 373.658809 -270.599858) (xy 373.664411 -270.569652)
			(xy 373.660797 -270.539143) (xy 373.648295 -270.511081) (xy 373.628028 -270.487992) (xy 373.615204 -270.47952)
			(xy 373.594805 -270.466592) (xy 373.557673 -270.435714) (xy 373.525436 -270.399755) (xy 373.498784 -270.359482)
			(xy 373.478285 -270.315755) (xy 373.464377 -270.269507) (xy 373.457357 -270.221727) (xy 373.456962 -270.19758)
			(xy 373.457414 -270.172686) (xy 373.464882 -270.123462) (xy 373.479645 -270.075914) (xy 373.501371 -270.031117)
			(xy 373.529568 -269.990084) (xy 373.563598 -269.953742) (xy 373.602692 -269.922914) (xy 373.645967 -269.898295)
			(xy 373.669052 -269.88897) (xy 373.701564 -269.876524) (xy 373.701564 -269.710154) (xy 373.701104 -269.695607)
			(xy 373.692916 -269.66769) (xy 373.677189 -269.643213) (xy 373.6552 -269.624164) (xy 373.628731 -269.612087)
			(xy 373.599932 -269.607963) (xy 373.571138 -269.612125) (xy 373.544685 -269.624237) (xy 373.533416 -269.633446)
			(xy 373.515312 -269.648548) (xy 373.475632 -269.674004) (xy 373.432737 -269.693566) (xy 373.387499 -269.706834)
			(xy 373.340834 -269.713541) (xy 373.317262 -269.713964) (xy 373.291296 -269.713452) (xy 373.240004 -269.705323)
			(xy 373.190615 -269.68927) (xy 373.144345 -269.66569) (xy 373.102333 -269.635162) (xy 373.065614 -269.598438)
			(xy 373.03509 -269.556423) (xy 373.011515 -269.51015) (xy 372.995469 -269.460759) (xy 372.987345 -269.409466)
			(xy 372.987345 -269.357534) (xy 372.995469 -269.306241) (xy 373.011515 -269.25685) (xy 373.03509 -269.210577)
			(xy 373.065614 -269.168562) (xy 373.102333 -269.131838) (xy 373.144345 -269.10131) (xy 373.190615 -269.07773)
			(xy 373.240004 -269.061677) (xy 373.291296 -269.053548) (xy 373.317262 -269.053056) (xy 373.340835 -269.053472)
			(xy 373.387504 -269.06017) (xy 373.432746 -269.073435) (xy 373.475642 -269.092997) (xy 373.515322 -269.118459)
			(xy 373.533416 -269.133574) (xy 373.544736 -269.142707) (xy 373.571175 -269.154796) (xy 373.599948 -269.158948)
			(xy 373.628726 -269.154825) (xy 373.655177 -269.142763) (xy 373.677159 -269.123738) (xy 373.692891 -269.09929)
			(xy 373.701099 -269.071401) (xy 373.701564 -269.056866) (xy 373.701564 -268.89075) (xy 373.669052 -268.878304)
			(xy 373.644445 -268.8683) (xy 373.598531 -268.841595) (xy 373.55748 -268.807891) (xy 373.522346 -268.768055)
			(xy 373.494036 -268.723114) (xy 373.473277 -268.674223) (xy 373.460604 -268.622642) (xy 373.456344 -268.569698)
			(xy 373.460605 -268.516754) (xy 373.473278 -268.465173) (xy 373.494038 -268.416282) (xy 373.522349 -268.371341)
			(xy 373.557483 -268.331506) (xy 373.598535 -268.297803) (xy 373.644449 -268.271098) (xy 373.669052 -268.261084)
			(xy 373.701564 -268.248638) (xy 373.701564 -268.082522) (xy 373.7011 -268.067978) (xy 373.692907 -268.040069)
			(xy 373.677179 -268.015601) (xy 373.655192 -267.996559) (xy 373.628729 -267.984486) (xy 373.599936 -267.980363)
			(xy 373.571148 -267.984522) (xy 373.5447 -267.996628) (xy 373.533416 -268.005814) (xy 373.515312 -268.020917)
			(xy 373.475633 -268.046376) (xy 373.432739 -268.065939) (xy 373.3875 -268.079209) (xy 373.340834 -268.085917)
			(xy 373.317262 -268.086332) (xy 373.291298 -268.08582) (xy 373.240011 -268.077691) (xy 373.190627 -268.061641)
			(xy 373.144362 -268.038062) (xy 373.102354 -268.007537) (xy 373.065638 -267.970817) (xy 373.035118 -267.928806)
			(xy 373.011545 -267.882538) (xy 372.9955 -267.833152) (xy 372.987377 -267.781864) (xy 372.987377 -267.729936)
			(xy 372.9955 -267.678648) (xy 373.011545 -267.629262) (xy 373.035118 -267.582994) (xy 373.065638 -267.540983)
			(xy 373.102354 -267.504263) (xy 373.144362 -267.473738) (xy 373.190627 -267.450159) (xy 373.240011 -267.434109)
			(xy 373.291298 -267.42598) (xy 373.317262 -267.425424) (xy 373.340835 -267.42584) (xy 373.387504 -267.432537)
			(xy 373.432747 -267.445801) (xy 373.475645 -267.465362) (xy 373.515326 -267.490822) (xy 373.533416 -267.505942)
			(xy 373.544706 -267.515121) (xy 373.571156 -267.527219) (xy 373.599944 -267.531375) (xy 373.628736 -267.527251)
			(xy 373.6552 -267.515181) (xy 373.67719 -267.496144) (xy 373.692925 -267.471682) (xy 373.70113 -267.443777)
			(xy 373.701564 -267.429234) (xy 373.701564 -267.262864) (xy 373.669052 -267.250418) (xy 373.644432 -267.240425)
			(xy 373.598492 -267.213735) (xy 373.557414 -267.180039) (xy 373.522256 -267.140204) (xy 373.493925 -267.095257)
			(xy 373.47315 -267.046357) (xy 373.460467 -266.994762) (xy 373.456202 -266.941803) (xy 373.460466 -266.888844)
			(xy 373.473148 -266.837249) (xy 373.493922 -266.788348) (xy 373.522252 -266.743401) (xy 373.557409 -266.703565)
			(xy 373.598487 -266.669868) (xy 373.644427 -266.643177) (xy 373.669052 -266.633198) (xy 373.701564 -266.620752)
			(xy 373.701564 -266.45489) (xy 373.701096 -266.44035) (xy 373.692898 -266.412449) (xy 373.677169 -266.38799)
			(xy 373.655185 -266.368954) (xy 373.628727 -266.356886) (xy 373.599941 -266.352763) (xy 373.571159 -266.356919)
			(xy 373.544715 -266.369018) (xy 373.533416 -266.378182) (xy 373.515313 -266.393286) (xy 373.475634 -266.418748)
			(xy 373.43274 -266.438313) (xy 373.387501 -266.451584) (xy 373.340835 -266.458292) (xy 373.317262 -266.4587)
			(xy 373.291293 -266.458188) (xy 373.239996 -266.450058) (xy 373.190601 -266.434003) (xy 373.144326 -266.41042)
			(xy 373.10231 -266.379889) (xy 373.065586 -266.343161) (xy 373.03506 -266.301141) (xy 373.011482 -266.254864)
			(xy 372.995434 -266.205467) (xy 372.987309 -266.154169) (xy 372.987309 -266.102231) (xy 372.995434 -266.050933)
			(xy 373.011482 -266.001536) (xy 373.03506 -265.955259) (xy 373.065586 -265.913239) (xy 373.10231 -265.876511)
			(xy 373.144326 -265.84598) (xy 373.190601 -265.822397) (xy 373.239996 -265.806342) (xy 373.291293 -265.798212)
			(xy 373.317262 -265.797792) (xy 373.340835 -265.798208) (xy 373.387503 -265.804907) (xy 373.432744 -265.818173)
			(xy 373.475639 -265.837736) (xy 373.515317 -265.863201) (xy 373.533416 -265.87831) (xy 373.544705 -265.88749)
			(xy 373.571153 -265.899592) (xy 373.59994 -265.90375) (xy 373.628731 -265.899627) (xy 373.655194 -265.887556)
			(xy 373.677181 -265.868516) (xy 373.692912 -265.844051) (xy 373.70111 -265.816145) (xy 373.701564 -265.801602)
			(xy 373.701564 -265.635232) (xy 373.669052 -265.622786) (xy 373.644446 -265.612782) (xy 373.598536 -265.586078)
			(xy 373.557487 -265.552374) (xy 373.522356 -265.51254) (xy 373.494048 -265.4676) (xy 373.473291 -265.418712)
			(xy 373.46062 -265.367133) (xy 373.456361 -265.314191) (xy 373.460623 -265.26125) (xy 373.473296 -265.209672)
			(xy 373.494056 -265.160785) (xy 373.522366 -265.115846) (xy 373.557499 -265.076014) (xy 373.59855 -265.042313)
			(xy 373.644462 -265.01561) (xy 373.669052 -265.005566) (xy 373.701564 -264.99312) (xy 373.701564 -264.827004)
			(xy 373.701098 -264.812462) (xy 373.692902 -264.784558) (xy 373.677174 -264.760095) (xy 373.655188 -264.741056)
			(xy 373.628728 -264.728986) (xy 373.599939 -264.724863) (xy 373.571154 -264.72902) (xy 373.544709 -264.741122)
			(xy 373.533416 -264.750296) (xy 373.515313 -264.7654) (xy 373.475634 -264.79086) (xy 373.432739 -264.810424)
			(xy 373.3875 -264.823695) (xy 373.340835 -264.830403) (xy 373.317262 -264.830814) (xy 373.2913 -264.830302)
			(xy 373.240016 -264.822174) (xy 373.190634 -264.806124) (xy 373.144371 -264.782547) (xy 373.102365 -264.752024)
			(xy 373.065652 -264.715306) (xy 373.035133 -264.673296) (xy 373.011562 -264.627031) (xy 372.995517 -264.577647)
			(xy 372.987395 -264.526362) (xy 372.987395 -264.474438) (xy 372.995517 -264.423153) (xy 373.011562 -264.373769)
			(xy 373.035133 -264.327504) (xy 373.065652 -264.285494) (xy 373.102365 -264.248776) (xy 373.144371 -264.218253)
			(xy 373.190634 -264.194676) (xy 373.240016 -264.178626) (xy 373.2913 -264.170498) (xy 373.317262 -264.169906)
			(xy 373.340835 -264.170322) (xy 373.387503 -264.177021) (xy 373.432743 -264.190287) (xy 373.475638 -264.209852)
			(xy 373.515315 -264.235317) (xy 373.533416 -264.250424) (xy 373.544706 -264.259603) (xy 373.571154 -264.271704)
			(xy 373.599942 -264.275861) (xy 373.628733 -264.271737) (xy 373.655196 -264.259666) (xy 373.677185 -264.240628)
			(xy 373.692917 -264.216164) (xy 373.701118 -264.188259) (xy 373.701564 -264.173716) (xy 373.701564 -264.0076)
			(xy 373.669052 -263.995154) (xy 373.644441 -263.98515) (xy 373.598519 -263.958444) (xy 373.55746 -263.924737)
			(xy 373.52232 -263.884898) (xy 373.494003 -263.839951) (xy 373.473238 -263.791055) (xy 373.460561 -263.739467)
			(xy 373.456297 -263.686516) (xy 373.460556 -263.633564) (xy 373.473228 -263.581975) (xy 373.493988 -263.533077)
			(xy 373.522301 -263.488128) (xy 373.557437 -263.448285) (xy 373.598494 -263.414574) (xy 373.644412 -263.387864)
			(xy 373.669052 -263.377934) (xy 373.701564 -263.365488) (xy 373.701564 -263.199372) (xy 373.701046 -263.184863)
			(xy 373.692874 -263.157021) (xy 373.677198 -263.132602) (xy 373.655285 -263.11358) (xy 373.628906 -263.101492)
			(xy 373.600191 -263.097314) (xy 373.57146 -263.101385) (xy 373.545036 -263.113374) (xy 373.53367 -263.12241)
			(xy 373.515566 -263.13751) (xy 373.475885 -263.162965) (xy 373.43299 -263.182522) (xy 373.387752 -263.195786)
			(xy 373.341087 -263.202487) (xy 373.317516 -263.202928) (xy 373.291548 -263.202446) (xy 373.240251 -263.194324)
			(xy 373.190856 -263.178277) (xy 373.14458 -263.1547) (xy 373.102562 -263.124174) (xy 373.065837 -263.08745)
			(xy 373.035308 -263.045434) (xy 373.011729 -262.999159) (xy 372.99568 -262.949765) (xy 372.987555 -262.898468)
			(xy 372.987555 -262.846532) (xy 372.99568 -262.795235) (xy 373.011729 -262.745841) (xy 373.035308 -262.699566)
			(xy 373.065837 -262.65755) (xy 373.102562 -262.620826) (xy 373.14458 -262.5903) (xy 373.190856 -262.566723)
			(xy 373.240251 -262.550676) (xy 373.291548 -262.542554) (xy 373.317516 -262.54202) (xy 373.341088 -262.54244)
			(xy 373.387753 -262.549144) (xy 373.432992 -262.562413) (xy 373.475884 -262.581979) (xy 373.51556 -262.607443)
			(xy 373.53367 -262.622538) (xy 373.545001 -262.631627) (xy 373.571438 -262.643629) (xy 373.600184 -262.647705)
			(xy 373.628915 -262.643526) (xy 373.655308 -262.631429) (xy 373.677229 -262.612392) (xy 373.692907 -262.587955)
			(xy 373.701072 -262.560093) (xy 373.701564 -262.545576) (xy 373.701564 -262.379714) (xy 373.669052 -262.367268)
			(xy 373.644436 -262.357275) (xy 373.598504 -262.330587) (xy 373.557433 -262.296893) (xy 373.522283 -262.257062)
			(xy 373.493958 -262.21212) (xy 373.473189 -262.163225) (xy 373.46051 -262.111637) (xy 373.456249 -262.058685)
			(xy 373.460515 -262.005733) (xy 373.473198 -261.954147) (xy 373.493972 -261.905254) (xy 373.522301 -261.860314)
			(xy 373.557455 -261.820486) (xy 373.598528 -261.786796) (xy 373.644463 -261.760112) (xy 373.669052 -261.750048)
			(xy 373.701564 -261.737602) (xy 373.701564 -261.571486) (xy 373.701095 -261.556946) (xy 373.692897 -261.529047)
			(xy 373.677168 -261.504588) (xy 373.655184 -261.485553) (xy 373.628727 -261.473486) (xy 373.599941 -261.469363)
			(xy 373.57116 -261.473519) (xy 373.544717 -261.485617) (xy 373.533416 -261.494778) (xy 373.515311 -261.509878)
			(xy 373.47563 -261.535333) (xy 373.432736 -261.554892) (xy 373.387498 -261.568159) (xy 373.340834 -261.574865)
			(xy 373.317262 -261.575296) (xy 373.291293 -261.574784) (xy 373.239996 -261.566654) (xy 373.190603 -261.5506)
			(xy 373.144328 -261.527017) (xy 373.102312 -261.496486) (xy 373.065589 -261.459759) (xy 373.035063 -261.417739)
			(xy 373.011486 -261.371462) (xy 372.995437 -261.322067) (xy 372.987313 -261.270769) (xy 372.987313 -261.218831)
			(xy 372.995437 -261.167534) (xy 373.011486 -261.118138) (xy 373.035063 -261.071861) (xy 373.065589 -261.029841)
			(xy 373.102312 -260.993114) (xy 373.144328 -260.962583) (xy 373.190603 -260.939) (xy 373.239996 -260.922946)
			(xy 373.291293 -260.914816) (xy 373.317262 -260.914388) (xy 373.340835 -260.914804) (xy 373.387503 -260.921503)
			(xy 373.432744 -260.934768) (xy 373.47564 -260.954332) (xy 373.515318 -260.979796) (xy 373.533416 -260.994906)
			(xy 373.544738 -261.004037) (xy 373.571179 -261.016123) (xy 373.599953 -261.020272) (xy 373.628731 -261.016149)
			(xy 373.655183 -261.004088) (xy 373.677167 -260.985065) (xy 373.692904 -260.960621) (xy 373.701118 -260.932734)
			(xy 373.701564 -260.918198) (xy 373.701564 -260.751828) (xy 373.669052 -260.739382) (xy 373.644447 -260.729378)
			(xy 373.598537 -260.702674) (xy 373.557488 -260.668971) (xy 373.522358 -260.629137) (xy 373.49405 -260.584197)
			(xy 373.473294 -260.535309) (xy 373.460623 -260.483731) (xy 373.456364 -260.43079) (xy 373.460627 -260.377849)
			(xy 373.4733 -260.326272) (xy 373.49406 -260.277385) (xy 373.52237 -260.232447) (xy 373.557503 -260.192615)
			(xy 373.598553 -260.158915) (xy 373.644465 -260.132213) (xy 373.669052 -260.122162) (xy 373.701564 -260.109716)
			(xy 373.701564 -259.9436) (xy 373.701097 -259.929059) (xy 373.692901 -259.901155) (xy 373.677172 -259.876693)
			(xy 373.655187 -259.857656) (xy 373.628728 -259.845586) (xy 373.599939 -259.841463) (xy 373.571156 -259.84562)
			(xy 373.544711 -259.857721) (xy 373.533416 -259.866892) (xy 373.515313 -259.881996) (xy 373.475634 -259.907457)
			(xy 373.432739 -259.927021) (xy 373.3875 -259.940292) (xy 373.340835 -259.947) (xy 373.317262 -259.94741)
			(xy 373.2913 -259.946898) (xy 373.240017 -259.93877) (xy 373.190636 -259.92272) (xy 373.144373 -259.899144)
			(xy 373.102368 -259.868621) (xy 373.065655 -259.831903) (xy 373.035137 -259.789894) (xy 373.011565 -259.743629)
			(xy 372.995521 -259.694246) (xy 372.987399 -259.642962) (xy 372.987399 -259.591038) (xy 372.995521 -259.539754)
			(xy 373.011565 -259.490371) (xy 373.035137 -259.444106) (xy 373.065655 -259.402097) (xy 373.102368 -259.365379)
			(xy 373.144373 -259.334856) (xy 373.190636 -259.31128) (xy 373.240017 -259.29523) (xy 373.2913 -259.287102)
			(xy 373.317262 -259.286502) (xy 373.340835 -259.286918) (xy 373.387503 -259.293617) (xy 373.432744 -259.306883)
			(xy 373.475639 -259.326447) (xy 373.515316 -259.351912) (xy 373.533416 -259.36702) (xy 373.544705 -259.3762)
			(xy 373.571154 -259.388301) (xy 373.599941 -259.392458) (xy 373.628733 -259.388334) (xy 373.655195 -259.376263)
			(xy 373.677184 -259.357224) (xy 373.692916 -259.332761) (xy 373.701116 -259.304855) (xy 373.701564 -259.290312)
			(xy 373.701564 -259.124196) (xy 373.669052 -259.11175) (xy 373.644441 -259.101746) (xy 373.59852 -259.07504)
			(xy 373.557462 -259.041333) (xy 373.522322 -259.001494) (xy 373.494005 -258.956548) (xy 373.473242 -258.907652)
			(xy 373.460565 -258.856065) (xy 373.456301 -258.803114) (xy 373.46056 -258.750163) (xy 373.473232 -258.698575)
			(xy 373.493992 -258.649677) (xy 373.522305 -258.604729) (xy 373.557441 -258.564887) (xy 373.598497 -258.531177)
			(xy 373.644415 -258.504466) (xy 373.669052 -258.49453) (xy 373.701564 -258.482084) (xy 373.701564 -258.315968)
			(xy 373.701045 -258.30146) (xy 373.692873 -258.273618) (xy 373.677197 -258.2492) (xy 373.655284 -258.230179)
			(xy 373.628905 -258.218092) (xy 373.600191 -258.213914) (xy 373.571462 -258.217984) (xy 373.545038 -258.229973)
			(xy 373.53367 -258.239006) (xy 373.515566 -258.254107) (xy 373.475885 -258.279561) (xy 373.43299 -258.299119)
			(xy 373.387752 -258.312383) (xy 373.341087 -258.319084) (xy 373.317516 -258.319524) (xy 373.291548 -258.319042)
			(xy 373.240252 -258.31092) (xy 373.190858 -258.294873) (xy 373.144582 -258.271297) (xy 373.102564 -258.240771)
			(xy 373.06584 -258.204048) (xy 373.035312 -258.162032) (xy 373.011733 -258.115757) (xy 372.995684 -258.066364)
			(xy 372.987559 -258.015068) (xy 372.987559 -257.963132) (xy 372.995684 -257.911836) (xy 373.011733 -257.862443)
			(xy 373.035312 -257.816168) (xy 373.06584 -257.774152) (xy 373.102564 -257.737429) (xy 373.144582 -257.706903)
			(xy 373.190858 -257.683327) (xy 373.240252 -257.66728) (xy 373.291548 -257.659158) (xy 373.317516 -257.658616)
			(xy 373.341088 -257.659036) (xy 373.387753 -257.66574) (xy 373.432992 -257.679009) (xy 373.475885 -257.698575)
			(xy 373.51556 -257.724038) (xy 373.53367 -257.739134) (xy 373.545006 -257.748217) (xy 373.571449 -257.760208)
			(xy 373.600197 -257.764278) (xy 373.628929 -257.760098) (xy 373.655325 -257.748004) (xy 373.677254 -257.728975)
			(xy 373.692945 -257.704545) (xy 373.701131 -257.676689) (xy 373.701564 -257.662172) (xy 373.701564 -257.49631)
			(xy 373.669052 -257.483864) (xy 373.644436 -257.473871) (xy 373.598505 -257.447183) (xy 373.557435 -257.413489)
			(xy 373.522285 -257.373658) (xy 373.49396 -257.328717) (xy 373.473192 -257.279822) (xy 373.460514 -257.228235)
			(xy 373.456253 -257.175284) (xy 373.460519 -257.122333) (xy 373.473202 -257.070746) (xy 373.493976 -257.021854)
			(xy 373.522304 -256.976915) (xy 373.557458 -256.937088) (xy 373.598532 -256.903398) (xy 373.644466 -256.876715)
			(xy 373.669052 -256.866644) (xy 373.701564 -256.854198) (xy 373.701564 -256.688082) (xy 373.701095 -256.673543)
			(xy 373.692895 -256.645644) (xy 373.677167 -256.621187) (xy 373.655183 -256.602153) (xy 373.628727 -256.590085)
			(xy 373.599942 -256.585963) (xy 373.571162 -256.590118) (xy 373.544719 -256.602216) (xy 373.533416 -256.611374)
			(xy 373.515311 -256.626474) (xy 373.47563 -256.651929) (xy 373.432736 -256.671489) (xy 373.387498 -256.684756)
			(xy 373.340834 -256.691462) (xy 373.317262 -256.691892) (xy 373.291294 -256.69138) (xy 373.239997 -256.68325)
			(xy 373.190604 -256.667196) (xy 373.14433 -256.643614) (xy 373.102315 -256.613083) (xy 373.065592 -256.576356)
			(xy 373.035067 -256.534337) (xy 373.011489 -256.488061) (xy 372.995441 -256.438666) (xy 372.987317 -256.387368)
			(xy 372.987317 -256.335432) (xy 372.995441 -256.284134) (xy 373.011489 -256.234739) (xy 373.035067 -256.188463)
			(xy 373.065592 -256.146444) (xy 373.102315 -256.109717) (xy 373.14433 -256.079186) (xy 373.190604 -256.055604)
			(xy 373.239997 -256.03955) (xy 373.291294 -256.03142) (xy 373.317262 -256.030984) (xy 373.340835 -256.0314)
			(xy 373.387503 -256.038099) (xy 373.432744 -256.051364) (xy 373.47564 -256.070928) (xy 373.515318 -256.096392)
			(xy 373.533416 -256.111502) (xy 373.544738 -256.120633) (xy 373.571178 -256.132719) (xy 373.599952 -256.136869)
			(xy 373.62873 -256.132746) (xy 373.655182 -256.120685) (xy 373.677166 -256.101662) (xy 373.692902 -256.077217)
			(xy 373.701116 -256.04933) (xy 373.701564 -256.034794) (xy 373.701564 -255.868678) (xy 373.669052 -255.856232)
			(xy 373.644443 -255.846228) (xy 373.598525 -255.819522) (xy 373.557469 -255.785817) (xy 373.522331 -255.745979)
			(xy 373.494017 -255.701035) (xy 373.473255 -255.652141) (xy 373.46058 -255.600556) (xy 373.456318 -255.547608)
			(xy 373.460578 -255.49466) (xy 373.47325 -255.443074) (xy 373.49401 -255.394179) (xy 373.522322 -255.349234)
			(xy 373.557457 -255.309394) (xy 373.598512 -255.275687) (xy 373.644428 -255.248979) (xy 373.669052 -255.239012)
			(xy 373.701564 -255.226566) (xy 373.701564 -255.060196) (xy 373.701097 -255.045655) (xy 373.6929 -255.017753)
			(xy 373.677171 -254.993292) (xy 373.655186 -254.974255) (xy 373.628728 -254.962186) (xy 373.59994 -254.958063)
			(xy 373.571157 -254.96222) (xy 373.544713 -254.97432) (xy 373.533416 -254.983488) (xy 373.515313 -254.998592)
			(xy 373.475634 -255.024053) (xy 373.43274 -255.043618) (xy 373.387501 -255.056889) (xy 373.340835 -255.063597)
			(xy 373.317262 -255.064006) (xy 373.291301 -255.063494) (xy 373.240018 -255.055366) (xy 373.190637 -255.039317)
			(xy 373.144375 -255.01574) (xy 373.102371 -254.985218) (xy 373.065658 -254.9485) (xy 373.03514 -254.906492)
			(xy 373.011569 -254.860228) (xy 372.995525 -254.810845) (xy 372.987403 -254.759562) (xy 372.987403 -254.707638)
			(xy 372.995525 -254.656355) (xy 373.011569 -254.606972) (xy 373.03514 -254.560708) (xy 373.065658 -254.5187)
			(xy 373.102371 -254.481982) (xy 373.144375 -254.45146) (xy 373.190637 -254.427883) (xy 373.240018 -254.411834)
			(xy 373.291301 -254.403706) (xy 373.317262 -254.403098) (xy 373.340835 -254.403514) (xy 373.387503 -254.410213)
			(xy 373.432744 -254.423479) (xy 373.475639 -254.443043) (xy 373.515316 -254.468508) (xy 373.533416 -254.483616)
			(xy 373.544705 -254.492796) (xy 373.571154 -254.504897) (xy 373.59994 -254.509055) (xy 373.628732 -254.504931)
			(xy 373.655195 -254.49286) (xy 373.677183 -254.473821) (xy 373.692914 -254.449357) (xy 373.701113 -254.421451)
			(xy 373.701564 -254.406908) (xy 373.701564 -254.240792) (xy 373.669052 -254.228346) (xy 373.645968 -254.219012)
			(xy 373.602677 -254.194413) (xy 373.563569 -254.163595) (xy 373.529529 -254.127257) (xy 373.501328 -254.086222)
			(xy 373.479605 -254.041419) (xy 373.464853 -253.993863) (xy 373.457404 -253.944632) (xy 373.456962 -253.919736)
			(xy 373.457456 -253.89402) (xy 373.46543 -253.843211) (xy 373.481175 -253.794249) (xy 373.504311 -253.748315)
			(xy 373.534281 -253.706518) (xy 373.551958 -253.687834) (xy 373.560966 -253.678089) (xy 373.574091 -253.655035)
			(xy 373.580831 -253.629378) (xy 373.58073 -253.60285) (xy 373.573794 -253.577245) (xy 373.560494 -253.554293)
			(xy 373.55145 -253.544578) (xy 371.969284 -251.962412) (xy 371.969284 -249.762772) (xy 371.964966 -249.75312)
			(xy 371.956115 -249.732061) (xy 371.943652 -249.688113) (xy 371.93738 -249.642865) (xy 371.937026 -249.620024)
			(xy 371.937413 -249.597186) (xy 371.943696 -249.551943) (xy 371.95613 -249.507991) (xy 371.964966 -249.486928)
			(xy 371.969284 -249.477276) (xy 371.969284 -249.232674) (xy 371.96879 -249.217959) (xy 371.960402 -249.189751)
			(xy 371.944327 -249.1651) (xy 371.921897 -249.146048) (xy 371.89497 -249.134172) (xy 371.865776 -249.130458)
			(xy 371.851174 -249.132344) (xy 371.837933 -249.134379) (xy 371.81123 -249.136542) (xy 371.797834 -249.136662)
			(xy 371.771862 -249.136182) (xy 371.720558 -249.128061) (xy 371.671156 -249.112013) (xy 371.624872 -249.088435)
			(xy 371.582847 -249.057906) (xy 371.546116 -249.021179) (xy 371.515583 -248.979157) (xy 371.492 -248.932876)
			(xy 371.475947 -248.883475) (xy 371.467821 -248.832172) (xy 371.467821 -248.780228) (xy 371.475947 -248.728925)
			(xy 371.492 -248.679524) (xy 371.515583 -248.633243) (xy 371.546116 -248.591221) (xy 371.582847 -248.554494)
			(xy 371.624872 -248.523965) (xy 371.671156 -248.500387) (xy 371.720558 -248.484339) (xy 371.771862 -248.476218)
			(xy 371.797834 -248.475754) (xy 371.823824 -248.47624) (xy 371.875164 -248.484379) (xy 371.924598 -248.50045)
			(xy 371.970908 -248.524059) (xy 372.012954 -248.554623) (xy 372.049699 -248.591389) (xy 372.080239 -248.633453)
			(xy 372.103822 -248.679776) (xy 372.112286 -248.704354) (xy 372.117385 -248.718289) (xy 372.134321 -248.742637)
			(xy 372.157533 -248.761101) (xy 372.185067 -248.772125) (xy 372.214607 -248.774782) (xy 372.243667 -248.768849)
			(xy 372.269801 -248.754824) (xy 372.280688 -248.74474) (xy 372.902226 -248.123202) (xy 372.892828 -248.093484)
			(xy 372.885373 -248.068812) (xy 372.877331 -248.017906) (xy 372.876826 -247.992138) (xy 372.877306 -247.966166)
			(xy 372.885426 -247.914861) (xy 372.901472 -247.865458) (xy 372.92505 -247.819174) (xy 372.955577 -247.777148)
			(xy 372.992304 -247.740415) (xy 373.034325 -247.70988) (xy 373.080605 -247.686295) (xy 373.130005 -247.67024)
			(xy 373.181308 -247.662111) (xy 373.20728 -247.661684) (xy 373.233048 -247.662199) (xy 373.283953 -247.670239)
			(xy 373.308626 -247.677686) (xy 373.338344 -247.687084) (xy 373.456962 -247.568466) (xy 373.466348 -247.558477)
			(xy 373.479907 -247.534667) (xy 373.486647 -247.508109) (xy 373.486081 -247.480715) (xy 373.478252 -247.454458)
			(xy 373.463722 -247.431228) (xy 373.453914 -247.421654) (xy 373.434109 -247.402752) (xy 373.40043 -247.359592)
			(xy 373.374336 -247.311466) (xy 373.356543 -247.259694) (xy 373.347537 -247.205695) (xy 373.34698 -247.178322)
			(xy 373.347461 -247.152353) (xy 373.355584 -247.101053) (xy 373.371632 -247.051655) (xy 373.395211 -247.005377)
			(xy 373.42574 -246.963358) (xy 373.462467 -246.926632) (xy 373.504487 -246.896105) (xy 373.550767 -246.872527)
			(xy 373.600164 -246.856481) (xy 373.651465 -246.84836) (xy 373.677434 -246.847868) (xy 373.704806 -246.848407)
			(xy 373.758801 -246.857435) (xy 373.81057 -246.875238) (xy 373.858696 -246.90133) (xy 373.901864 -246.934997)
			(xy 373.920766 -246.954802) (xy 373.930344 -246.964614) (xy 373.95356 -246.979182) (xy 373.97982 -246.987032)
			(xy 374.007222 -246.987596) (xy 374.033783 -246.980834) (xy 374.05758 -246.967235) (xy 374.067578 -246.95785)
			(xy 374.16105 -246.864378) (xy 374.170738 -246.854052) (xy 374.18451 -246.829323) (xy 374.190961 -246.801764)
			(xy 374.189597 -246.773492) (xy 374.180522 -246.746682) (xy 374.164434 -246.723394) (xy 374.14257 -246.705419)
			(xy 374.116611 -246.694139) (xy 374.10263 -246.691912) (xy 374.076565 -246.687853) (xy 374.026087 -246.672545)
			(xy 373.978682 -246.649413) (xy 373.935552 -246.619046) (xy 373.897793 -246.582214) (xy 373.866362 -246.539853)
			(xy 373.842059 -246.493037) (xy 373.8255 -246.442956) (xy 373.817106 -246.39088) (xy 373.816626 -246.364506)
			(xy 373.817135 -246.338538) (xy 373.825258 -246.287241) (xy 373.841306 -246.237846) (xy 373.864883 -246.19157)
			(xy 373.895409 -246.149552) (xy 373.932132 -246.112826) (xy 373.974148 -246.082297) (xy 374.020422 -246.058716)
			(xy 374.069816 -246.042664) (xy 374.121112 -246.034537) (xy 374.14708 -246.034052) (xy 374.173454 -246.034566)
			(xy 374.225531 -246.042944) (xy 374.275615 -246.059492) (xy 374.322433 -246.083787) (xy 374.364796 -246.115214)
			(xy 374.401627 -246.152973) (xy 374.431989 -246.196105) (xy 374.455112 -246.243513) (xy 374.470408 -246.293994)
			(xy 374.474486 -246.320056) (xy 374.476827 -246.334001) (xy 374.48813 -246.359907) (xy 374.5061 -246.381724)
			(xy 374.529361 -246.397782) (xy 374.556132 -246.406849) (xy 374.584363 -246.408233) (xy 374.611892 -246.401827)
			(xy 374.636612 -246.388122) (xy 374.646952 -246.378476) (xy 374.777508 -246.24792) (xy 374.781318 -246.238522)
			(xy 374.791713 -246.214596) (xy 374.818924 -246.17009) (xy 374.852787 -246.130411) (xy 374.892463 -246.096544)
			(xy 374.936965 -246.069329) (xy 374.960896 -246.058944) (xy 374.970294 -246.055134) (xy 375.284238 -245.74119)
			(xy 375.266204 -245.707916) (xy 375.253642 -245.683634) (xy 375.235857 -245.631942) (xy 375.226841 -245.578023)
			(xy 375.226326 -245.55069) (xy 375.226836 -245.524723) (xy 375.234961 -245.473428) (xy 375.251011 -245.424035)
			(xy 375.274589 -245.377761) (xy 375.305115 -245.335745) (xy 375.341837 -245.299021) (xy 375.383853 -245.268494)
			(xy 375.430126 -245.244915) (xy 375.479518 -245.228864) (xy 375.530813 -245.220737) (xy 375.55678 -245.220236)
			(xy 375.584107 -245.220826) (xy 375.63801 -245.229857) (xy 375.689701 -245.24761) (xy 375.714006 -245.260114)
			(xy 375.74728 -245.278148) (xy 375.858024 -245.167404) (xy 375.868235 -245.156441) (xy 375.882354 -245.130034)
			(xy 375.888208 -245.100668) (xy 375.885294 -245.070866) (xy 375.873861 -245.04319) (xy 375.854893 -245.020019)
			(xy 375.842784 -245.011194) (xy 375.820631 -244.995711) (xy 375.781219 -244.958731) (xy 375.748352 -244.915831)
			(xy 375.722906 -244.868152) (xy 375.70556 -244.816967) (xy 375.696776 -244.763642) (xy 375.696226 -244.73662)
			(xy 375.696683 -244.71164) (xy 375.704205 -244.662249) (xy 375.71908 -244.614555) (xy 375.740969 -244.569645)
			(xy 375.769372 -244.528544) (xy 375.803641 -244.49219) (xy 375.842995 -244.461412) (xy 375.886536 -244.436913)
			(xy 375.93327 -244.419251) (xy 375.957592 -244.413532) (xy 375.997724 -244.404896) (xy 375.997724 -243.440712)
			(xy 375.957592 -243.432076) (xy 375.931839 -243.426034) (xy 375.882539 -243.406871) (xy 375.836922 -243.380097)
			(xy 375.796153 -243.346397) (xy 375.761274 -243.306632) (xy 375.733177 -243.261818) (xy 375.712578 -243.2131)
			(xy 375.700005 -243.161722) (xy 375.695778 -243.108997) (xy 375.700005 -243.056273) (xy 375.71258 -243.004895)
			(xy 375.733179 -242.956177) (xy 375.761277 -242.911364) (xy 375.796156 -242.871599) (xy 375.836926 -242.8379)
			(xy 375.882543 -242.811127) (xy 375.931844 -242.791964) (xy 375.957592 -242.7859) (xy 375.997724 -242.777264)
			(xy 375.997724 -241.812826) (xy 375.957592 -241.80419) (xy 375.931838 -241.798148) (xy 375.882535 -241.778984)
			(xy 375.836916 -241.75221) (xy 375.796145 -241.718509) (xy 375.761265 -241.678743) (xy 375.733166 -241.633927)
			(xy 375.712566 -241.585207) (xy 375.699992 -241.533827) (xy 375.695764 -241.4811) (xy 375.699991 -241.428373)
			(xy 375.712566 -241.376994) (xy 375.733165 -241.328273) (xy 375.761264 -241.283458) (xy 375.796145 -241.243692)
			(xy 375.836915 -241.209991) (xy 375.882535 -241.183216) (xy 375.931837 -241.164052) (xy 375.957592 -241.158014)
			(xy 375.997724 -241.149378) (xy 375.997724 -240.18494) (xy 375.957592 -240.176304) (xy 375.931837 -240.170262)
			(xy 375.882532 -240.151098) (xy 375.836911 -240.124323) (xy 375.796138 -240.090621) (xy 375.761256 -240.050853)
			(xy 375.733155 -240.006036) (xy 375.712554 -239.957314) (xy 375.699979 -239.905932) (xy 375.69575 -239.853203)
			(xy 375.699978 -239.800474) (xy 375.712552 -239.749092) (xy 375.733152 -239.70037) (xy 375.761252 -239.655552)
			(xy 375.796133 -239.615784) (xy 375.836905 -239.582081) (xy 375.882526 -239.555305) (xy 375.93183 -239.53614)
			(xy 375.957592 -239.530128) (xy 375.997724 -239.521492) (xy 375.997724 -238.557308) (xy 375.957592 -238.548672)
			(xy 375.931839 -238.542631) (xy 375.88254 -238.523467) (xy 375.836923 -238.496693) (xy 375.796155 -238.462994)
			(xy 375.761277 -238.423229) (xy 375.73318 -238.378416) (xy 375.712581 -238.329698) (xy 375.700008 -238.278321)
			(xy 375.695782 -238.225597) (xy 375.700009 -238.172873) (xy 375.712584 -238.121496) (xy 375.733183 -238.072778)
			(xy 375.761281 -238.027965) (xy 375.79616 -237.988202) (xy 375.836929 -237.954503) (xy 375.882546 -237.92773)
			(xy 375.931846 -237.908568) (xy 375.957592 -237.902496) (xy 375.997724 -237.89386) (xy 375.997724 -236.929676)
			(xy 375.957592 -236.92104) (xy 375.931842 -236.914999) (xy 375.882547 -236.895836) (xy 375.836936 -236.869064)
			(xy 375.796172 -236.835367) (xy 375.761298 -236.795605) (xy 375.733204 -236.750795) (xy 375.712609 -236.702082)
			(xy 375.700038 -236.650709) (xy 375.695813 -236.59799) (xy 375.700041 -236.545271) (xy 375.712615 -236.493899)
			(xy 375.733214 -236.445187) (xy 375.76131 -236.400379) (xy 375.796186 -236.360619) (xy 375.836952 -236.326925)
			(xy 375.882565 -236.300155) (xy 375.931861 -236.280996) (xy 375.957592 -236.274864) (xy 375.997724 -236.266228)
			(xy 375.997724 -235.30179) (xy 375.957592 -235.293154) (xy 375.931841 -235.287113) (xy 375.882544 -235.267949)
			(xy 375.83693 -235.241177) (xy 375.796164 -235.207479) (xy 375.761289 -235.167716) (xy 375.733193 -235.122904)
			(xy 375.712597 -235.074189) (xy 375.700025 -235.022814) (xy 375.695799 -234.970093) (xy 375.700027 -234.917372)
			(xy 375.712601 -234.865998) (xy 375.7332 -234.817283) (xy 375.761297 -234.772473) (xy 375.796175 -234.732712)
			(xy 375.836942 -234.699015) (xy 375.882557 -234.672244) (xy 375.931854 -234.653083) (xy 375.957592 -234.646978)
			(xy 375.997724 -234.638342) (xy 375.997724 -233.673904) (xy 375.957592 -233.665268) (xy 375.93184 -233.659227)
			(xy 375.882541 -233.640063) (xy 375.836925 -233.61329) (xy 375.796157 -233.57959) (xy 375.761279 -233.539826)
			(xy 375.733183 -233.495013) (xy 375.712585 -233.446296) (xy 375.700012 -233.394919) (xy 375.695786 -233.342196)
			(xy 375.700013 -233.289472) (xy 375.712588 -233.238096) (xy 375.733187 -233.189379) (xy 375.761284 -233.144567)
			(xy 375.796163 -233.104804) (xy 375.836931 -233.071106) (xy 375.882548 -233.044333) (xy 375.931848 -233.025171)
			(xy 375.957592 -233.019092) (xy 375.997724 -233.010456) (xy 375.997724 -232.046272) (xy 375.957592 -232.037636)
			(xy 375.931834 -232.031594) (xy 375.882525 -232.012429) (xy 375.836898 -231.985652) (xy 375.796121 -231.951948)
			(xy 375.761235 -231.912177) (xy 375.73313 -231.867357) (xy 375.712526 -231.81863) (xy 375.699949 -231.767244)
			(xy 375.695719 -231.71451) (xy 375.699946 -231.661776) (xy 375.71252 -231.610389) (xy 375.733121 -231.561661)
			(xy 375.761223 -231.516839) (xy 375.796106 -231.477066) (xy 375.836882 -231.443359) (xy 375.882506 -231.41658)
			(xy 375.931815 -231.397411) (xy 375.957592 -231.39146) (xy 375.997724 -231.382824) (xy 375.997724 -230.418386)
			(xy 375.957592 -230.40975) (xy 375.931841 -230.403709) (xy 375.882545 -230.384546) (xy 375.836932 -230.357773)
			(xy 375.796167 -230.324075) (xy 375.761291 -230.284313) (xy 375.733197 -230.239502) (xy 375.7126 -230.190787)
			(xy 375.700029 -230.139413) (xy 375.695803 -230.086692) (xy 375.700031 -230.033971) (xy 375.712605 -229.982598)
			(xy 375.733204 -229.933884) (xy 375.761301 -229.889074) (xy 375.796178 -229.849314) (xy 375.836945 -229.815618)
			(xy 375.882559 -229.788848) (xy 375.931856 -229.769687) (xy 375.957592 -229.763574) (xy 375.997724 -229.754938)
			(xy 375.997724 -228.790754) (xy 375.957592 -228.782118) (xy 375.931836 -228.776076) (xy 375.882529 -228.756912)
			(xy 375.836905 -228.730136) (xy 375.79613 -228.696433) (xy 375.761246 -228.656664) (xy 375.733144 -228.611845)
			(xy 375.712542 -228.563121) (xy 375.699966 -228.511737) (xy 375.695737 -228.459006) (xy 375.699964 -228.406275)
			(xy 375.712538 -228.354891) (xy 375.733138 -228.306166) (xy 375.761239 -228.261346) (xy 375.796121 -228.221576)
			(xy 375.836895 -228.187871) (xy 375.882517 -228.161094) (xy 375.931824 -228.141927) (xy 375.957592 -228.135942)
			(xy 375.997724 -228.127306) (xy 375.997724 -227.162868) (xy 375.957592 -227.154232) (xy 375.931846 -227.148178)
			(xy 375.882562 -227.128993) (xy 375.836962 -227.102204) (xy 375.796211 -227.068494) (xy 375.761349 -227.028726)
			(xy 375.733264 -226.983912) (xy 375.712675 -226.935198) (xy 375.700107 -226.883827) (xy 375.695881 -226.831109)
			(xy 375.700105 -226.778392) (xy 375.71267 -226.72702) (xy 375.733256 -226.678304) (xy 375.761337 -226.633489)
			(xy 375.796198 -226.593718) (xy 375.836947 -226.560007) (xy 375.882545 -226.533215) (xy 375.931828 -226.514028)
			(xy 375.957592 -226.508056) (xy 375.997724 -226.49942) (xy 375.997724 -225.534982) (xy 375.957592 -225.526346)
			(xy 375.931841 -225.520305) (xy 375.882546 -225.501142) (xy 375.836933 -225.474369) (xy 375.796169 -225.440672)
			(xy 375.761294 -225.40091) (xy 375.7332 -225.356099) (xy 375.712604 -225.307385) (xy 375.700033 -225.256011)
			(xy 375.695807 -225.203291) (xy 375.700035 -225.150571) (xy 375.712609 -225.099198) (xy 375.733208 -225.050485)
			(xy 375.761304 -225.005676) (xy 375.796181 -224.965916) (xy 375.836948 -224.932221) (xy 375.882562 -224.905451)
			(xy 375.931858 -224.88629) (xy 375.957592 -224.88017) (xy 375.997724 -224.871534) (xy 375.997724 -224.210372)
			(xy 375.99734 -224.200838) (xy 375.990392 -224.183084) (xy 375.977432 -224.1691) (xy 375.960256 -224.160824)
			(xy 375.941243 -224.159404) (xy 375.923028 -224.165035) (xy 375.908134 -224.176938) (xy 375.902982 -224.184972)
			(xy 375.861072 -224.257616) (xy 375.868692 -224.279714) (xy 375.877482 -224.306289) (xy 375.886926 -224.361457)
			(xy 375.887488 -224.389442) (xy 375.886979 -224.415409) (xy 375.878854 -224.466704) (xy 375.862806 -224.516097)
			(xy 375.839228 -224.562371) (xy 375.808702 -224.604387) (xy 375.771979 -224.64111) (xy 375.729963 -224.671636)
			(xy 375.683689 -224.695214) (xy 375.634296 -224.711262) (xy 375.583001 -224.719387) (xy 375.531067 -224.719387)
			(xy 375.479772 -224.711262) (xy 375.430379 -224.695214) (xy 375.384105 -224.671636) (xy 375.342089 -224.64111)
			(xy 375.305366 -224.604387) (xy 375.27484 -224.562371) (xy 375.251262 -224.516097) (xy 375.235214 -224.466704)
			(xy 375.227089 -224.415409) (xy 375.22658 -224.389442) (xy 375.227053 -224.363995) (xy 375.234861 -224.313702)
			(xy 375.250284 -224.2652) (xy 375.272958 -224.219635) (xy 375.302346 -224.178082) (xy 375.337756 -224.141524)
			(xy 375.378349 -224.110824) (xy 375.423168 -224.086708) (xy 375.471152 -224.069745) (xy 375.496074 -224.064576)
			(xy 375.518934 -224.060258) (xy 375.722642 -223.707198) (xy 375.715022 -223.685354) (xy 375.706226 -223.65878)
			(xy 375.696771 -223.603612) (xy 375.696226 -223.575626) (xy 375.696683 -223.550646) (xy 375.704204 -223.501254)
			(xy 375.719078 -223.453559) (xy 375.740966 -223.408649) (xy 375.769369 -223.367547) (xy 375.803639 -223.331192)
			(xy 375.842993 -223.300414) (xy 375.886534 -223.275914) (xy 375.933268 -223.258252) (xy 375.957592 -223.252538)
			(xy 375.997724 -223.243902) (xy 375.997724 -222.279464) (xy 375.957592 -222.270828) (xy 375.931835 -222.264786)
			(xy 375.882526 -222.245621) (xy 375.836901 -222.218845) (xy 375.796125 -222.185141) (xy 375.76124 -222.145371)
			(xy 375.733136 -222.100551) (xy 375.712533 -222.051826) (xy 375.699956 -222.000441) (xy 375.695727 -221.947708)
			(xy 375.699954 -221.894975) (xy 375.712528 -221.843589) (xy 375.733129 -221.794863) (xy 375.76123 -221.750042)
			(xy 375.796113 -221.71027) (xy 375.836888 -221.676565) (xy 375.882511 -221.649786) (xy 375.931819 -221.630618)
			(xy 375.957592 -221.624652) (xy 375.997724 -221.616016) (xy 375.997724 -221.454726) (xy 375.922286 -221.379288)
			(xy 375.910844 -221.368646) (xy 375.883129 -221.354246) (xy 375.852364 -221.348864) (xy 375.821406 -221.353002)
			(xy 375.793134 -221.366274) (xy 375.781316 -221.376494) (xy 375.764001 -221.391989) (xy 375.725815 -221.418465)
			(xy 375.684292 -221.43932) (xy 375.640253 -221.45414) (xy 375.617486 -221.45879) (xy 375.594372 -221.463108)
			(xy 375.390918 -221.815914) (xy 375.398538 -221.838012) (xy 375.40733 -221.864586) (xy 375.416775 -221.919754)
			(xy 375.417334 -221.94774) (xy 375.416825 -221.973707) (xy 375.4087 -222.025002) (xy 375.392652 -222.074395)
			(xy 375.369074 -222.120669) (xy 375.338548 -222.162685) (xy 375.301825 -222.199408) (xy 375.259809 -222.229934)
			(xy 375.213535 -222.253512) (xy 375.164142 -222.26956) (xy 375.112847 -222.277685) (xy 375.060913 -222.277685)
			(xy 375.009618 -222.26956) (xy 374.960225 -222.253512) (xy 374.913951 -222.229934) (xy 374.871935 -222.199408)
			(xy 374.835212 -222.162685) (xy 374.804686 -222.120669) (xy 374.781108 -222.074395) (xy 374.76506 -222.025002)
			(xy 374.756935 -221.973707) (xy 374.756426 -221.94774) (xy 374.756898 -221.922291) (xy 374.764706 -221.871997)
			(xy 374.780129 -221.823492) (xy 374.802801 -221.777923) (xy 374.832188 -221.736367) (xy 374.867596 -221.699804)
			(xy 374.908188 -221.669099) (xy 374.953006 -221.644976) (xy 375.00099 -221.628005) (xy 375.02592 -221.622874)
			(xy 375.04878 -221.618556) (xy 375.252742 -221.264988) (xy 375.245122 -221.243144) (xy 375.23882 -221.224283)
			(xy 375.230292 -221.18544) (xy 375.228104 -221.165674) (xy 375.226136 -221.150779) (xy 375.214702 -221.12301)
			(xy 375.195694 -221.099761) (xy 375.170752 -221.083037) (xy 375.142027 -221.074281) (xy 375.127012 -221.073726)
			(xy 375.047256 -221.073726) (xy 375.032235 -221.074256) (xy 375.00349 -221.082988) (xy 374.978533 -221.099712)
			(xy 374.959527 -221.122979) (xy 374.94812 -221.150771) (xy 374.946164 -221.165674) (xy 374.943216 -221.191169)
			(xy 374.930447 -221.240876) (xy 374.910147 -221.288012) (xy 374.882804 -221.331442) (xy 374.849076 -221.370123)
			(xy 374.809774 -221.403126) (xy 374.765842 -221.429655) (xy 374.718336 -221.449074) (xy 374.6684 -221.460915)
			(xy 374.617234 -221.464894) (xy 374.566068 -221.460915) (xy 374.516132 -221.449074) (xy 374.468626 -221.429655)
			(xy 374.424694 -221.403126) (xy 374.385392 -221.370123) (xy 374.351664 -221.331442) (xy 374.324321 -221.288012)
			(xy 374.304021 -221.240876) (xy 374.291252 -221.191169) (xy 374.288304 -221.165674) (xy 374.286336 -221.150779)
			(xy 374.274902 -221.12301) (xy 374.255894 -221.099761) (xy 374.230952 -221.083037) (xy 374.202227 -221.074281)
			(xy 374.187212 -221.073726) (xy 374.107456 -221.073726) (xy 374.092435 -221.074256) (xy 374.06369 -221.082988)
			(xy 374.038733 -221.099712) (xy 374.019727 -221.122979) (xy 374.00832 -221.150771) (xy 374.006364 -221.165674)
			(xy 374.003291 -221.192171) (xy 373.9897 -221.243749) (xy 373.967999 -221.292474) (xy 373.938753 -221.33708)
			(xy 373.902721 -221.376409) (xy 373.86084 -221.409439) (xy 373.814196 -221.435313) (xy 373.764002 -221.453357)
			(xy 373.737886 -221.45879) (xy 373.714772 -221.463108) (xy 373.511318 -221.815914) (xy 373.518938 -221.838012)
			(xy 373.52773 -221.864586) (xy 373.537175 -221.919754) (xy 373.537734 -221.94774) (xy 373.537225 -221.973707)
			(xy 373.5291 -222.025002) (xy 373.513052 -222.074395) (xy 373.489474 -222.120669) (xy 373.458948 -222.162685)
			(xy 373.422225 -222.199408) (xy 373.380209 -222.229934) (xy 373.333935 -222.253512) (xy 373.284542 -222.26956)
			(xy 373.233247 -222.277685) (xy 373.181313 -222.277685) (xy 373.130018 -222.26956) (xy 373.080625 -222.253512)
			(xy 373.034351 -222.229934) (xy 372.992335 -222.199408) (xy 372.955612 -222.162685) (xy 372.925086 -222.120669)
			(xy 372.901508 -222.074395) (xy 372.88546 -222.025002) (xy 372.877335 -221.973707) (xy 372.876826 -221.94774)
			(xy 372.877298 -221.922291) (xy 372.885106 -221.871997) (xy 372.900529 -221.823492) (xy 372.923201 -221.777923)
			(xy 372.952588 -221.736367) (xy 372.987996 -221.699804) (xy 373.028588 -221.669099) (xy 373.073406 -221.644976)
			(xy 373.12139 -221.628005) (xy 373.14632 -221.622874) (xy 373.16918 -221.618556) (xy 373.373142 -221.264988)
			(xy 373.365522 -221.243144) (xy 373.35922 -221.224283) (xy 373.350692 -221.18544) (xy 373.348504 -221.165674)
			(xy 373.346536 -221.150779) (xy 373.335102 -221.12301) (xy 373.316094 -221.099761) (xy 373.291152 -221.083037)
			(xy 373.262427 -221.074281) (xy 373.247412 -221.073726) (xy 373.167656 -221.073726) (xy 373.152635 -221.074256)
			(xy 373.12389 -221.082988) (xy 373.098933 -221.099712) (xy 373.079927 -221.122979) (xy 373.06852 -221.150771)
			(xy 373.066564 -221.165674) (xy 373.063616 -221.191169) (xy 373.050847 -221.240876) (xy 373.030547 -221.288012)
			(xy 373.003204 -221.331442) (xy 372.969476 -221.370123) (xy 372.930174 -221.403126) (xy 372.886242 -221.429655)
			(xy 372.838736 -221.449074) (xy 372.7888 -221.460915) (xy 372.737634 -221.464894) (xy 372.686468 -221.460915)
			(xy 372.636532 -221.449074) (xy 372.589026 -221.429655) (xy 372.545094 -221.403126) (xy 372.505792 -221.370123)
			(xy 372.472064 -221.331442) (xy 372.444721 -221.288012) (xy 372.424421 -221.240876) (xy 372.411652 -221.191169)
			(xy 372.408704 -221.165674) (xy 372.406736 -221.150779) (xy 372.395302 -221.12301) (xy 372.376294 -221.099761)
			(xy 372.351352 -221.083037) (xy 372.322627 -221.074281) (xy 372.307612 -221.073726) (xy 372.227856 -221.073726)
			(xy 372.212835 -221.074256) (xy 372.18409 -221.082988) (xy 372.159133 -221.099712) (xy 372.140127 -221.122979)
			(xy 372.12872 -221.150771) (xy 372.126764 -221.165674) (xy 372.123691 -221.192171) (xy 372.1101 -221.243749)
			(xy 372.088399 -221.292474) (xy 372.059153 -221.33708) (xy 372.023121 -221.376409) (xy 371.98124 -221.409439)
			(xy 371.934596 -221.435313) (xy 371.884402 -221.453357) (xy 371.858286 -221.45879) (xy 371.835172 -221.463108)
			(xy 371.631718 -221.815914) (xy 371.639338 -221.838012) (xy 371.64813 -221.864586) (xy 371.657575 -221.919754)
			(xy 371.658134 -221.94774) (xy 371.657625 -221.973707) (xy 371.6495 -222.025002) (xy 371.633452 -222.074395)
			(xy 371.609874 -222.120669) (xy 371.579348 -222.162685) (xy 371.542625 -222.199408) (xy 371.500609 -222.229934)
			(xy 371.454335 -222.253512) (xy 371.404942 -222.26956) (xy 371.353647 -222.277685) (xy 371.301713 -222.277685)
			(xy 371.250418 -222.26956) (xy 371.201025 -222.253512) (xy 371.154751 -222.229934) (xy 371.112735 -222.199408)
			(xy 371.076012 -222.162685) (xy 371.045486 -222.120669) (xy 371.021908 -222.074395) (xy 371.00586 -222.025002)
			(xy 370.997735 -221.973707) (xy 370.997226 -221.94774) (xy 370.997698 -221.922291) (xy 371.005506 -221.871997)
			(xy 371.020929 -221.823492) (xy 371.043601 -221.777923) (xy 371.072988 -221.736367) (xy 371.108396 -221.699804)
			(xy 371.148988 -221.669099) (xy 371.193806 -221.644976) (xy 371.24179 -221.628005) (xy 371.26672 -221.622874)
			(xy 371.28958 -221.618556) (xy 371.493542 -221.264988) (xy 371.485922 -221.243144) (xy 371.47962 -221.224283)
			(xy 371.471092 -221.18544) (xy 371.468904 -221.165674) (xy 371.466936 -221.150779) (xy 371.455502 -221.12301)
			(xy 371.436494 -221.099761) (xy 371.411552 -221.083037) (xy 371.382827 -221.074281) (xy 371.367812 -221.073726)
			(xy 371.288056 -221.073726) (xy 371.273035 -221.074256) (xy 371.24429 -221.082988) (xy 371.219333 -221.099712)
			(xy 371.200327 -221.122979) (xy 371.18892 -221.150771) (xy 371.186964 -221.165674) (xy 371.184016 -221.191169)
			(xy 371.171247 -221.240876) (xy 371.150947 -221.288012) (xy 371.123604 -221.331442) (xy 371.089876 -221.370123)
			(xy 371.050574 -221.403126) (xy 371.006642 -221.429655) (xy 370.959136 -221.449074) (xy 370.9092 -221.460915)
			(xy 370.858034 -221.464894) (xy 370.806868 -221.460915) (xy 370.756932 -221.449074) (xy 370.709426 -221.429655)
			(xy 370.665494 -221.403126) (xy 370.626192 -221.370123) (xy 370.592464 -221.331442) (xy 370.565121 -221.288012)
			(xy 370.544821 -221.240876) (xy 370.532052 -221.191169) (xy 370.529104 -221.165674) (xy 370.527136 -221.150779)
			(xy 370.515702 -221.12301) (xy 370.496694 -221.099761) (xy 370.471752 -221.083037) (xy 370.443027 -221.074281)
			(xy 370.428012 -221.073726) (xy 370.348256 -221.073726) (xy 370.333235 -221.074256) (xy 370.30449 -221.082988)
			(xy 370.279533 -221.099712) (xy 370.260527 -221.122979) (xy 370.24912 -221.150771) (xy 370.247164 -221.165674)
			(xy 370.244091 -221.192171) (xy 370.2305 -221.243749) (xy 370.208799 -221.292474) (xy 370.179553 -221.33708)
			(xy 370.143521 -221.376409) (xy 370.10164 -221.409439) (xy 370.054996 -221.435313) (xy 370.004802 -221.453357)
			(xy 369.978686 -221.45879) (xy 369.955572 -221.463108) (xy 369.752118 -221.815914) (xy 369.759738 -221.838012)
			(xy 369.76853 -221.864586) (xy 369.777975 -221.919754) (xy 369.778534 -221.94774) (xy 369.778025 -221.973707)
			(xy 369.7699 -222.025002) (xy 369.753852 -222.074395) (xy 369.730274 -222.120669) (xy 369.699748 -222.162685)
			(xy 369.663025 -222.199408) (xy 369.621009 -222.229934) (xy 369.574735 -222.253512) (xy 369.525342 -222.26956)
			(xy 369.474047 -222.277685) (xy 369.422113 -222.277685) (xy 369.370818 -222.26956) (xy 369.321425 -222.253512)
			(xy 369.275151 -222.229934) (xy 369.233135 -222.199408) (xy 369.196412 -222.162685) (xy 369.165886 -222.120669)
			(xy 369.142308 -222.074395) (xy 369.12626 -222.025002) (xy 369.118135 -221.973707) (xy 369.117626 -221.94774)
			(xy 369.118098 -221.922291) (xy 369.125906 -221.871997) (xy 369.141329 -221.823492) (xy 369.164001 -221.777923)
			(xy 369.193388 -221.736367) (xy 369.228796 -221.699804) (xy 369.269388 -221.669099) (xy 369.314206 -221.644976)
			(xy 369.36219 -221.628005) (xy 369.38712 -221.622874) (xy 369.40998 -221.618556) (xy 369.613942 -221.264988)
			(xy 369.606322 -221.243144) (xy 369.60002 -221.224283) (xy 369.591492 -221.18544) (xy 369.589304 -221.165674)
			(xy 369.587336 -221.150779) (xy 369.575902 -221.12301) (xy 369.556894 -221.099761) (xy 369.531952 -221.083037)
			(xy 369.503227 -221.074281) (xy 369.488212 -221.073726) (xy 369.408456 -221.073726) (xy 369.393435 -221.074256)
			(xy 369.36469 -221.082988) (xy 369.339733 -221.099712) (xy 369.320727 -221.122979) (xy 369.30932 -221.150771)
			(xy 369.307364 -221.165674) (xy 369.304416 -221.191169) (xy 369.291647 -221.240876) (xy 369.271347 -221.288012)
			(xy 369.244004 -221.331442) (xy 369.210276 -221.370123) (xy 369.170974 -221.403126) (xy 369.127042 -221.429655)
			(xy 369.079536 -221.449074) (xy 369.0296 -221.460915) (xy 368.978434 -221.464894) (xy 368.927268 -221.460915)
			(xy 368.877332 -221.449074) (xy 368.829826 -221.429655) (xy 368.785894 -221.403126) (xy 368.746592 -221.370123)
			(xy 368.712864 -221.331442) (xy 368.685521 -221.288012) (xy 368.665221 -221.240876) (xy 368.652452 -221.191169)
			(xy 368.649504 -221.165674) (xy 368.647536 -221.150779) (xy 368.636102 -221.12301) (xy 368.617094 -221.099761)
			(xy 368.592152 -221.083037) (xy 368.563427 -221.074281) (xy 368.548412 -221.073726) (xy 368.468402 -221.073726)
			(xy 368.453386 -221.074264) (xy 368.424654 -221.083005) (xy 368.399711 -221.099732) (xy 368.380717 -221.122996)
			(xy 368.369318 -221.15078) (xy 368.36731 -221.165674) (xy 368.364362 -221.191169) (xy 368.351593 -221.240876)
			(xy 368.331293 -221.288012) (xy 368.30395 -221.331442) (xy 368.270222 -221.370123) (xy 368.23092 -221.403126)
			(xy 368.186988 -221.429655) (xy 368.139482 -221.449074) (xy 368.089546 -221.460915) (xy 368.03838 -221.464894)
			(xy 367.987214 -221.460915) (xy 367.937278 -221.449074) (xy 367.889772 -221.429655) (xy 367.84584 -221.403126)
			(xy 367.806538 -221.370123) (xy 367.77281 -221.331442) (xy 367.745467 -221.288012) (xy 367.725167 -221.240876)
			(xy 367.712398 -221.191169) (xy 367.70945 -221.165674) (xy 367.707481 -221.150782) (xy 367.696046 -221.123021)
			(xy 367.677036 -221.099781) (xy 367.652093 -221.083069) (xy 367.62337 -221.074327) (xy 367.608358 -221.073726)
			(xy 367.528856 -221.073726) (xy 367.513835 -221.074256) (xy 367.48509 -221.082988) (xy 367.460133 -221.099712)
			(xy 367.441127 -221.122979) (xy 367.42972 -221.150771) (xy 367.427764 -221.165674) (xy 367.424816 -221.191169)
			(xy 367.412047 -221.240876) (xy 367.391747 -221.288012) (xy 367.364404 -221.331442) (xy 367.330676 -221.370123)
			(xy 367.291374 -221.403126) (xy 367.247442 -221.429655) (xy 367.199936 -221.449074) (xy 367.15 -221.460915)
			(xy 367.098834 -221.464894) (xy 367.047668 -221.460915) (xy 366.997732 -221.449074) (xy 366.950226 -221.429655)
			(xy 366.906294 -221.403126) (xy 366.866992 -221.370123) (xy 366.833264 -221.331442) (xy 366.805921 -221.288012)
			(xy 366.785621 -221.240876) (xy 366.772852 -221.191169) (xy 366.769904 -221.165674) (xy 366.767936 -221.150779)
			(xy 366.756502 -221.12301) (xy 366.737494 -221.099761) (xy 366.712552 -221.083037) (xy 366.683827 -221.074281)
			(xy 366.668812 -221.073726) (xy 366.589056 -221.073726) (xy 366.574035 -221.074256) (xy 366.54529 -221.082988)
			(xy 366.520333 -221.099712) (xy 366.501327 -221.122979) (xy 366.48992 -221.150771) (xy 366.487964 -221.165674)
			(xy 366.484891 -221.192171) (xy 366.4713 -221.243749) (xy 366.449599 -221.292474) (xy 366.420353 -221.33708)
			(xy 366.384321 -221.376409) (xy 366.34244 -221.409439) (xy 366.295796 -221.435313) (xy 366.245602 -221.453357)
			(xy 366.219486 -221.45879) (xy 366.196372 -221.463108) (xy 365.992918 -221.815914) (xy 366.000538 -221.838012)
			(xy 366.00933 -221.864586) (xy 366.018775 -221.919754) (xy 366.019334 -221.94774) (xy 366.018825 -221.973707)
			(xy 367.238789 -221.973707) (xy 367.238789 -221.921773) (xy 367.246914 -221.870478) (xy 367.262962 -221.821085)
			(xy 367.28654 -221.774811) (xy 367.317066 -221.732795) (xy 367.353789 -221.696072) (xy 367.395805 -221.665546)
			(xy 367.442079 -221.641968) (xy 367.491472 -221.62592) (xy 367.542767 -221.617795) (xy 367.594701 -221.617795)
			(xy 367.645996 -221.62592) (xy 367.695389 -221.641968) (xy 367.741663 -221.665546) (xy 367.783679 -221.696072)
			(xy 367.820402 -221.732795) (xy 367.850928 -221.774811) (xy 367.874506 -221.821085) (xy 367.890554 -221.870478)
			(xy 367.898679 -221.921773) (xy 367.899188 -221.94774) (xy 367.898679 -221.973707) (xy 367.890554 -222.025002)
			(xy 367.874506 -222.074395) (xy 367.850928 -222.120669) (xy 367.820402 -222.162685) (xy 367.783679 -222.199408)
			(xy 367.741663 -222.229934) (xy 367.695389 -222.253512) (xy 367.645996 -222.26956) (xy 367.594701 -222.277685)
			(xy 367.542767 -222.277685) (xy 367.491472 -222.26956) (xy 367.442079 -222.253512) (xy 367.395805 -222.229934)
			(xy 367.353789 -222.199408) (xy 367.317066 -222.162685) (xy 367.28654 -222.120669) (xy 367.262962 -222.074395)
			(xy 367.246914 -222.025002) (xy 367.238789 -221.973707) (xy 366.018825 -221.973707) (xy 366.0107 -222.025002)
			(xy 365.994652 -222.074395) (xy 365.971074 -222.120669) (xy 365.940548 -222.162685) (xy 365.903825 -222.199408)
			(xy 365.861809 -222.229934) (xy 365.815535 -222.253512) (xy 365.766142 -222.26956) (xy 365.714847 -222.277685)
			(xy 365.662913 -222.277685) (xy 365.611618 -222.26956) (xy 365.562225 -222.253512) (xy 365.515951 -222.229934)
			(xy 365.473935 -222.199408) (xy 365.437212 -222.162685) (xy 365.406686 -222.120669) (xy 365.383108 -222.074395)
			(xy 365.36706 -222.025002) (xy 365.358935 -221.973707) (xy 365.358426 -221.94774) (xy 365.358898 -221.922291)
			(xy 365.366706 -221.871997) (xy 365.382129 -221.823492) (xy 365.404801 -221.777923) (xy 365.434188 -221.736367)
			(xy 365.469596 -221.699804) (xy 365.510188 -221.669099) (xy 365.555006 -221.644976) (xy 365.60299 -221.628005)
			(xy 365.62792 -221.622874) (xy 365.65078 -221.618556) (xy 365.854742 -221.264988) (xy 365.847122 -221.243144)
			(xy 365.84082 -221.224283) (xy 365.832292 -221.18544) (xy 365.830104 -221.165674) (xy 365.828136 -221.150779)
			(xy 365.816702 -221.12301) (xy 365.797694 -221.099761) (xy 365.772752 -221.083037) (xy 365.744027 -221.074281)
			(xy 365.729012 -221.073726) (xy 365.649256 -221.073726) (xy 365.634235 -221.074256) (xy 365.60549 -221.082988)
			(xy 365.580533 -221.099712) (xy 365.561527 -221.122979) (xy 365.55012 -221.150771) (xy 365.548164 -221.165674)
			(xy 365.545216 -221.191169) (xy 365.532447 -221.240876) (xy 365.512147 -221.288012) (xy 365.484804 -221.331442)
			(xy 365.451076 -221.370123) (xy 365.411774 -221.403126) (xy 365.367842 -221.429655) (xy 365.320336 -221.449074)
			(xy 365.2704 -221.460915) (xy 365.219234 -221.464894) (xy 365.168068 -221.460915) (xy 365.118132 -221.449074)
			(xy 365.070626 -221.429655) (xy 365.026694 -221.403126) (xy 364.987392 -221.370123) (xy 364.953664 -221.331442)
			(xy 364.926321 -221.288012) (xy 364.906021 -221.240876) (xy 364.893252 -221.191169) (xy 364.890304 -221.165674)
			(xy 364.888336 -221.150779) (xy 364.876902 -221.12301) (xy 364.857894 -221.099761) (xy 364.832952 -221.083037)
			(xy 364.804227 -221.074281) (xy 364.789212 -221.073726) (xy 364.709456 -221.073726) (xy 364.694435 -221.074256)
			(xy 364.66569 -221.082988) (xy 364.640733 -221.099712) (xy 364.621727 -221.122979) (xy 364.61032 -221.150771)
			(xy 364.608364 -221.165674) (xy 364.605291 -221.192171) (xy 364.5917 -221.243749) (xy 364.569999 -221.292474)
			(xy 364.540753 -221.33708) (xy 364.504721 -221.376409) (xy 364.46284 -221.409439) (xy 364.416196 -221.435313)
			(xy 364.366002 -221.453357) (xy 364.339886 -221.45879) (xy 364.316772 -221.463108) (xy 364.113318 -221.815914)
			(xy 364.120938 -221.838012) (xy 364.12973 -221.864586) (xy 364.139175 -221.919754) (xy 364.139734 -221.94774)
			(xy 364.139225 -221.973707) (xy 364.1311 -222.025002) (xy 364.115052 -222.074395) (xy 364.091474 -222.120669)
			(xy 364.060948 -222.162685) (xy 364.024225 -222.199408) (xy 363.982209 -222.229934) (xy 363.935935 -222.253512)
			(xy 363.886542 -222.26956) (xy 363.835247 -222.277685) (xy 363.783313 -222.277685) (xy 363.732018 -222.26956)
			(xy 363.682625 -222.253512) (xy 363.636351 -222.229934) (xy 363.594335 -222.199408) (xy 363.557612 -222.162685)
			(xy 363.527086 -222.120669) (xy 363.503508 -222.074395) (xy 363.48746 -222.025002) (xy 363.479335 -221.973707)
			(xy 363.478826 -221.94774) (xy 363.479298 -221.922291) (xy 363.487106 -221.871997) (xy 363.502529 -221.823492)
			(xy 363.525201 -221.777923) (xy 363.554588 -221.736367) (xy 363.589996 -221.699804) (xy 363.630588 -221.669099)
			(xy 363.675406 -221.644976) (xy 363.72339 -221.628005) (xy 363.74832 -221.622874) (xy 363.77118 -221.618556)
			(xy 363.975142 -221.264988) (xy 363.967522 -221.243144) (xy 363.96122 -221.224283) (xy 363.952692 -221.18544)
			(xy 363.950504 -221.165674) (xy 363.948536 -221.150779) (xy 363.937102 -221.12301) (xy 363.918094 -221.099761)
			(xy 363.893152 -221.083037) (xy 363.864427 -221.074281) (xy 363.849412 -221.073726) (xy 363.769656 -221.073726)
			(xy 363.754635 -221.074256) (xy 363.72589 -221.082988) (xy 363.700933 -221.099712) (xy 363.681927 -221.122979)
			(xy 363.67052 -221.150771) (xy 363.668564 -221.165674) (xy 363.665616 -221.191169) (xy 363.652847 -221.240876)
			(xy 363.632547 -221.288012) (xy 363.605204 -221.331442) (xy 363.571476 -221.370123) (xy 363.532174 -221.403126)
			(xy 363.488242 -221.429655) (xy 363.440736 -221.449074) (xy 363.3908 -221.460915) (xy 363.339634 -221.464894)
			(xy 363.288468 -221.460915) (xy 363.238532 -221.449074) (xy 363.191026 -221.429655) (xy 363.147094 -221.403126)
			(xy 363.107792 -221.370123) (xy 363.074064 -221.331442) (xy 363.046721 -221.288012) (xy 363.026421 -221.240876)
			(xy 363.013652 -221.191169) (xy 363.010704 -221.165674) (xy 363.008736 -221.150779) (xy 362.997302 -221.12301)
			(xy 362.978294 -221.099761) (xy 362.953352 -221.083037) (xy 362.924627 -221.074281) (xy 362.909612 -221.073726)
			(xy 362.829856 -221.073726) (xy 362.814835 -221.074256) (xy 362.78609 -221.082988) (xy 362.761133 -221.099712)
			(xy 362.742127 -221.122979) (xy 362.73072 -221.150771) (xy 362.728764 -221.165674) (xy 362.725695 -221.192158)
			(xy 362.712118 -221.243713) (xy 362.690442 -221.292421) (xy 362.661229 -221.337017) (xy 362.625236 -221.376346)
			(xy 362.583397 -221.409388) (xy 362.536797 -221.435286) (xy 362.486645 -221.453368) (xy 362.46054 -221.45879)
			(xy 362.437426 -221.463108) (xy 362.233972 -221.815914) (xy 362.241592 -221.838012) (xy 362.250382 -221.864587)
			(xy 362.259826 -221.919755) (xy 362.260388 -221.94774) (xy 362.259879 -221.973707) (xy 362.539789 -221.973707)
			(xy 362.539789 -221.921773) (xy 362.547914 -221.870478) (xy 362.563962 -221.821085) (xy 362.58754 -221.774811)
			(xy 362.618066 -221.732795) (xy 362.654789 -221.696072) (xy 362.696805 -221.665546) (xy 362.743079 -221.641968)
			(xy 362.792472 -221.62592) (xy 362.843767 -221.617795) (xy 362.895701 -221.617795) (xy 362.946996 -221.62592)
			(xy 362.996389 -221.641968) (xy 363.042663 -221.665546) (xy 363.084679 -221.696072) (xy 363.121402 -221.732795)
			(xy 363.151928 -221.774811) (xy 363.175506 -221.821085) (xy 363.191554 -221.870478) (xy 363.199679 -221.921773)
			(xy 363.200188 -221.94774) (xy 363.199679 -221.973707) (xy 363.191554 -222.025002) (xy 363.175506 -222.074395)
			(xy 363.151928 -222.120669) (xy 363.121402 -222.162685) (xy 363.084679 -222.199408) (xy 363.042663 -222.229934)
			(xy 362.996389 -222.253512) (xy 362.946996 -222.26956) (xy 362.895701 -222.277685) (xy 362.843767 -222.277685)
			(xy 362.792472 -222.26956) (xy 362.743079 -222.253512) (xy 362.696805 -222.229934) (xy 362.654789 -222.199408)
			(xy 362.618066 -222.162685) (xy 362.58754 -222.120669) (xy 362.563962 -222.074395) (xy 362.547914 -222.025002)
			(xy 362.539789 -221.973707) (xy 362.259879 -221.973707) (xy 362.251754 -222.025002) (xy 362.235706 -222.074395)
			(xy 362.212128 -222.120669) (xy 362.181602 -222.162685) (xy 362.144879 -222.199408) (xy 362.102863 -222.229934)
			(xy 362.056589 -222.253512) (xy 362.007196 -222.26956) (xy 361.955901 -222.277685) (xy 361.903967 -222.277685)
			(xy 361.852672 -222.26956) (xy 361.803279 -222.253512) (xy 361.757005 -222.229934) (xy 361.714989 -222.199408)
			(xy 361.678266 -222.162685) (xy 361.64774 -222.120669) (xy 361.624162 -222.074395) (xy 361.608114 -222.025002)
			(xy 361.599989 -221.973707) (xy 361.59948 -221.94774) (xy 361.599953 -221.922293) (xy 361.607761 -221.872)
			(xy 361.623185 -221.823499) (xy 361.645859 -221.777934) (xy 361.675247 -221.736381) (xy 361.710656 -221.699824)
			(xy 361.75125 -221.669124) (xy 361.796068 -221.645008) (xy 361.844053 -221.628044) (xy 361.868974 -221.622874)
			(xy 361.891834 -221.618556) (xy 362.095796 -221.265242) (xy 362.087922 -221.243398) (xy 362.081628 -221.224469)
			(xy 362.073098 -221.185501) (xy 362.070904 -221.165674) (xy 362.068936 -221.150779) (xy 362.057502 -221.12301)
			(xy 362.038494 -221.099761) (xy 362.013552 -221.083037) (xy 361.984827 -221.074281) (xy 361.969812 -221.073726)
			(xy 361.890056 -221.073726) (xy 361.875035 -221.074256) (xy 361.84629 -221.082988) (xy 361.821333 -221.099712)
			(xy 361.802327 -221.122979) (xy 361.79092 -221.150771) (xy 361.788964 -221.165674) (xy 361.786016 -221.191169)
			(xy 361.773247 -221.240876) (xy 361.752947 -221.288012) (xy 361.725604 -221.331442) (xy 361.691876 -221.370123)
			(xy 361.652574 -221.403126) (xy 361.608642 -221.429655) (xy 361.561136 -221.449074) (xy 361.5112 -221.460915)
			(xy 361.460034 -221.464894) (xy 361.408868 -221.460915) (xy 361.358932 -221.449074) (xy 361.311426 -221.429655)
			(xy 361.267494 -221.403126) (xy 361.228192 -221.370123) (xy 361.194464 -221.331442) (xy 361.167121 -221.288012)
			(xy 361.146821 -221.240876) (xy 361.134052 -221.191169) (xy 361.131104 -221.165674) (xy 361.129136 -221.150779)
			(xy 361.117702 -221.12301) (xy 361.098694 -221.099761) (xy 361.073752 -221.083037) (xy 361.045027 -221.074281)
			(xy 361.030012 -221.073726) (xy 360.950256 -221.073726) (xy 360.935235 -221.074256) (xy 360.90649 -221.082988)
			(xy 360.881533 -221.099712) (xy 360.862527 -221.122979) (xy 360.85112 -221.150771) (xy 360.849164 -221.165674)
			(xy 360.846354 -221.190255) (xy 360.834321 -221.238244) (xy 360.815267 -221.283901) (xy 360.789618 -221.326208)
			(xy 360.757948 -221.364217) (xy 360.720964 -221.397078) (xy 360.679493 -221.424058) (xy 360.65714 -221.43466)
			(xy 360.644078 -221.479648) (xy 360.611411 -221.567454) (xy 360.57151 -221.652218) (xy 360.524655 -221.733346)
			(xy 360.471175 -221.810267) (xy 360.411445 -221.882443) (xy 360.37901 -221.916244) (xy 360.380534 -221.94774)
			(xy 360.380022 -221.973705) (xy 360.380022 -221.973707) (xy 360.659935 -221.973707) (xy 360.659935 -221.921773)
			(xy 360.66806 -221.870478) (xy 360.684108 -221.821085) (xy 360.707686 -221.774811) (xy 360.738212 -221.732795)
			(xy 360.774935 -221.696072) (xy 360.816951 -221.665546) (xy 360.863225 -221.641968) (xy 360.912618 -221.62592)
			(xy 360.963913 -221.617795) (xy 361.015847 -221.617795) (xy 361.067142 -221.62592) (xy 361.116535 -221.641968)
			(xy 361.162809 -221.665546) (xy 361.204825 -221.696072) (xy 361.241548 -221.732795) (xy 361.272074 -221.774811)
			(xy 361.295652 -221.821085) (xy 361.3117 -221.870478) (xy 361.319825 -221.921773) (xy 361.320334 -221.94774)
			(xy 361.319825 -221.973707) (xy 361.3117 -222.025002) (xy 361.295652 -222.074395) (xy 361.272074 -222.120669)
			(xy 361.241548 -222.162685) (xy 361.204825 -222.199408) (xy 361.162809 -222.229934) (xy 361.116535 -222.253512)
			(xy 361.067142 -222.26956) (xy 361.015847 -222.277685) (xy 360.963913 -222.277685) (xy 360.912618 -222.26956)
			(xy 360.863225 -222.253512) (xy 360.816951 -222.229934) (xy 360.774935 -222.199408) (xy 360.738212 -222.162685)
			(xy 360.707686 -222.120669) (xy 360.684108 -222.074395) (xy 360.66806 -222.025002) (xy 360.659935 -221.973707)
			(xy 360.380022 -221.973707) (xy 360.371892 -222.024994) (xy 360.35584 -222.07438) (xy 360.33226 -222.120646)
			(xy 360.301732 -222.162655) (xy 360.26501 -222.199371) (xy 360.222995 -222.229891) (xy 360.176724 -222.253463)
			(xy 360.127335 -222.269506) (xy 360.076045 -222.277626) (xy 360.05008 -222.278194) (xy 360.024494 -222.277742)
			(xy 359.973927 -222.269901) (xy 359.925176 -222.254348) (xy 359.879411 -222.231457) (xy 359.85831 -222.21698)
			(xy 359.812826 -222.22814) (xy 359.720472 -222.243742) (xy 359.627138 -222.251571) (xy 359.533476 -222.251571)
			(xy 359.440142 -222.243742) (xy 359.347788 -222.22814) (xy 359.302304 -222.21698) (xy 359.289338 -222.225989)
			(xy 359.261985 -222.241763) (xy 359.247694 -222.248476) (xy 359.234639 -222.293466) (xy 359.201982 -222.381278)
			(xy 359.162086 -222.466046) (xy 359.115231 -222.547175) (xy 359.061746 -222.624096) (xy 359.002008 -222.696267)
			(xy 358.969564 -222.73006) (xy 358.971088 -222.761556) (xy 358.970608 -222.787523) (xy 359.250489 -222.787523)
			(xy 359.250489 -222.735589) (xy 359.258614 -222.684294) (xy 359.274662 -222.634901) (xy 359.29824 -222.588627)
			(xy 359.328766 -222.546611) (xy 359.365489 -222.509888) (xy 359.407505 -222.479362) (xy 359.453779 -222.455784)
			(xy 359.503172 -222.439736) (xy 359.554467 -222.431611) (xy 359.606401 -222.431611) (xy 359.657696 -222.439736)
			(xy 359.707089 -222.455784) (xy 359.753363 -222.479362) (xy 359.795379 -222.509888) (xy 359.832102 -222.546611)
			(xy 359.862628 -222.588627) (xy 359.886206 -222.634901) (xy 359.902254 -222.684294) (xy 359.910379 -222.735589)
			(xy 359.910888 -222.761556) (xy 359.910379 -222.787523) (xy 360.190289 -222.787523) (xy 360.190289 -222.735589)
			(xy 360.198414 -222.684294) (xy 360.214462 -222.634901) (xy 360.23804 -222.588627) (xy 360.268566 -222.546611)
			(xy 360.305289 -222.509888) (xy 360.347305 -222.479362) (xy 360.393579 -222.455784) (xy 360.442972 -222.439736)
			(xy 360.494267 -222.431611) (xy 360.546201 -222.431611) (xy 360.597496 -222.439736) (xy 360.646889 -222.455784)
			(xy 360.693163 -222.479362) (xy 360.735179 -222.509888) (xy 360.771902 -222.546611) (xy 360.802428 -222.588627)
			(xy 360.826006 -222.634901) (xy 360.842054 -222.684294) (xy 360.850179 -222.735589) (xy 360.850688 -222.761556)
			(xy 360.850179 -222.787523) (xy 361.130089 -222.787523) (xy 361.130089 -222.735589) (xy 361.138214 -222.684294)
			(xy 361.154262 -222.634901) (xy 361.17784 -222.588627) (xy 361.208366 -222.546611) (xy 361.245089 -222.509888)
			(xy 361.287105 -222.479362) (xy 361.333379 -222.455784) (xy 361.382772 -222.439736) (xy 361.434067 -222.431611)
			(xy 361.486001 -222.431611) (xy 361.537296 -222.439736) (xy 361.586689 -222.455784) (xy 361.632963 -222.479362)
			(xy 361.674979 -222.509888) (xy 361.711702 -222.546611) (xy 361.742228 -222.588627) (xy 361.765806 -222.634901)
			(xy 361.781854 -222.684294) (xy 361.789979 -222.735589) (xy 361.790488 -222.761556) (xy 361.789979 -222.787523)
			(xy 362.069889 -222.787523) (xy 362.069889 -222.735589) (xy 362.078014 -222.684294) (xy 362.094062 -222.634901)
			(xy 362.11764 -222.588627) (xy 362.148166 -222.546611) (xy 362.184889 -222.509888) (xy 362.226905 -222.479362)
			(xy 362.273179 -222.455784) (xy 362.322572 -222.439736) (xy 362.373867 -222.431611) (xy 362.425801 -222.431611)
			(xy 362.477096 -222.439736) (xy 362.526489 -222.455784) (xy 362.572763 -222.479362) (xy 362.614779 -222.509888)
			(xy 362.651502 -222.546611) (xy 362.682028 -222.588627) (xy 362.705606 -222.634901) (xy 362.721654 -222.684294)
			(xy 362.729779 -222.735589) (xy 362.730288 -222.761556) (xy 362.729779 -222.787523) (xy 363.009689 -222.787523)
			(xy 363.009689 -222.735589) (xy 363.017814 -222.684294) (xy 363.033862 -222.634901) (xy 363.05744 -222.588627)
			(xy 363.087966 -222.546611) (xy 363.124689 -222.509888) (xy 363.166705 -222.479362) (xy 363.212979 -222.455784)
			(xy 363.262372 -222.439736) (xy 363.313667 -222.431611) (xy 363.365601 -222.431611) (xy 363.416896 -222.439736)
			(xy 363.466289 -222.455784) (xy 363.512563 -222.479362) (xy 363.554579 -222.509888) (xy 363.591302 -222.546611)
			(xy 363.621828 -222.588627) (xy 363.645406 -222.634901) (xy 363.661454 -222.684294) (xy 363.669579 -222.735589)
			(xy 363.670088 -222.761556) (xy 363.669579 -222.787523) (xy 363.949489 -222.787523) (xy 363.949489 -222.735589)
			(xy 363.957614 -222.684294) (xy 363.973662 -222.634901) (xy 363.99724 -222.588627) (xy 364.027766 -222.546611)
			(xy 364.064489 -222.509888) (xy 364.106505 -222.479362) (xy 364.152779 -222.455784) (xy 364.202172 -222.439736)
			(xy 364.253467 -222.431611) (xy 364.305401 -222.431611) (xy 364.356696 -222.439736) (xy 364.406089 -222.455784)
			(xy 364.452363 -222.479362) (xy 364.494379 -222.509888) (xy 364.531102 -222.546611) (xy 364.561628 -222.588627)
			(xy 364.585206 -222.634901) (xy 364.601254 -222.684294) (xy 364.609379 -222.735589) (xy 364.609888 -222.761556)
			(xy 364.609379 -222.787523) (xy 364.889289 -222.787523) (xy 364.889289 -222.735589) (xy 364.897414 -222.684294)
			(xy 364.913462 -222.634901) (xy 364.93704 -222.588627) (xy 364.967566 -222.546611) (xy 365.004289 -222.509888)
			(xy 365.046305 -222.479362) (xy 365.092579 -222.455784) (xy 365.141972 -222.439736) (xy 365.193267 -222.431611)
			(xy 365.245201 -222.431611) (xy 365.296496 -222.439736) (xy 365.345889 -222.455784) (xy 365.392163 -222.479362)
			(xy 365.434179 -222.509888) (xy 365.470902 -222.546611) (xy 365.501428 -222.588627) (xy 365.525006 -222.634901)
			(xy 365.541054 -222.684294) (xy 365.549179 -222.735589) (xy 365.549688 -222.761556) (xy 365.549179 -222.787523)
			(xy 365.829089 -222.787523) (xy 365.829089 -222.735589) (xy 365.837214 -222.684294) (xy 365.853262 -222.634901)
			(xy 365.87684 -222.588627) (xy 365.907366 -222.546611) (xy 365.944089 -222.509888) (xy 365.986105 -222.479362)
			(xy 366.032379 -222.455784) (xy 366.081772 -222.439736) (xy 366.133067 -222.431611) (xy 366.185001 -222.431611)
			(xy 366.236296 -222.439736) (xy 366.285689 -222.455784) (xy 366.331963 -222.479362) (xy 366.373979 -222.509888)
			(xy 366.410702 -222.546611) (xy 366.441228 -222.588627) (xy 366.464806 -222.634901) (xy 366.480854 -222.684294)
			(xy 366.488979 -222.735589) (xy 366.489488 -222.761556) (xy 366.488979 -222.787523) (xy 366.768889 -222.787523)
			(xy 366.768889 -222.735589) (xy 366.777014 -222.684294) (xy 366.793062 -222.634901) (xy 366.81664 -222.588627)
			(xy 366.847166 -222.546611) (xy 366.883889 -222.509888) (xy 366.925905 -222.479362) (xy 366.972179 -222.455784)
			(xy 367.021572 -222.439736) (xy 367.072867 -222.431611) (xy 367.124801 -222.431611) (xy 367.176096 -222.439736)
			(xy 367.225489 -222.455784) (xy 367.271763 -222.479362) (xy 367.313779 -222.509888) (xy 367.350502 -222.546611)
			(xy 367.381028 -222.588627) (xy 367.404606 -222.634901) (xy 367.420654 -222.684294) (xy 367.428779 -222.735589)
			(xy 367.429288 -222.761556) (xy 367.428779 -222.787523) (xy 367.708689 -222.787523) (xy 367.708689 -222.735589)
			(xy 367.716814 -222.684294) (xy 367.732862 -222.634901) (xy 367.75644 -222.588627) (xy 367.786966 -222.546611)
			(xy 367.823689 -222.509888) (xy 367.865705 -222.479362) (xy 367.911979 -222.455784) (xy 367.961372 -222.439736)
			(xy 368.012667 -222.431611) (xy 368.064601 -222.431611) (xy 368.115896 -222.439736) (xy 368.165289 -222.455784)
			(xy 368.211563 -222.479362) (xy 368.253579 -222.509888) (xy 368.290302 -222.546611) (xy 368.320828 -222.588627)
			(xy 368.344406 -222.634901) (xy 368.360454 -222.684294) (xy 368.368579 -222.735589) (xy 368.369088 -222.761556)
			(xy 368.368579 -222.787523) (xy 368.648489 -222.787523) (xy 368.648489 -222.735589) (xy 368.656614 -222.684294)
			(xy 368.672662 -222.634901) (xy 368.69624 -222.588627) (xy 368.726766 -222.546611) (xy 368.763489 -222.509888)
			(xy 368.805505 -222.479362) (xy 368.851779 -222.455784) (xy 368.901172 -222.439736) (xy 368.952467 -222.431611)
			(xy 369.004401 -222.431611) (xy 369.055696 -222.439736) (xy 369.105089 -222.455784) (xy 369.151363 -222.479362)
			(xy 369.193379 -222.509888) (xy 369.230102 -222.546611) (xy 369.260628 -222.588627) (xy 369.284206 -222.634901)
			(xy 369.300254 -222.684294) (xy 369.308379 -222.735589) (xy 369.308888 -222.761556) (xy 369.308379 -222.787523)
			(xy 369.588289 -222.787523) (xy 369.588289 -222.735589) (xy 369.596414 -222.684294) (xy 369.612462 -222.634901)
			(xy 369.63604 -222.588627) (xy 369.666566 -222.546611) (xy 369.703289 -222.509888) (xy 369.745305 -222.479362)
			(xy 369.791579 -222.455784) (xy 369.840972 -222.439736) (xy 369.892267 -222.431611) (xy 369.944201 -222.431611)
			(xy 369.995496 -222.439736) (xy 370.044889 -222.455784) (xy 370.091163 -222.479362) (xy 370.133179 -222.509888)
			(xy 370.169902 -222.546611) (xy 370.200428 -222.588627) (xy 370.224006 -222.634901) (xy 370.240054 -222.684294)
			(xy 370.248179 -222.735589) (xy 370.248688 -222.761556) (xy 370.248179 -222.787523) (xy 370.528089 -222.787523)
			(xy 370.528089 -222.735589) (xy 370.536214 -222.684294) (xy 370.552262 -222.634901) (xy 370.57584 -222.588627)
			(xy 370.606366 -222.546611) (xy 370.643089 -222.509888) (xy 370.685105 -222.479362) (xy 370.731379 -222.455784)
			(xy 370.780772 -222.439736) (xy 370.832067 -222.431611) (xy 370.884001 -222.431611) (xy 370.935296 -222.439736)
			(xy 370.984689 -222.455784) (xy 371.030963 -222.479362) (xy 371.072979 -222.509888) (xy 371.109702 -222.546611)
			(xy 371.140228 -222.588627) (xy 371.163806 -222.634901) (xy 371.179854 -222.684294) (xy 371.187979 -222.735589)
			(xy 371.188488 -222.761556) (xy 371.187979 -222.787523) (xy 371.467889 -222.787523) (xy 371.467889 -222.735589)
			(xy 371.476014 -222.684294) (xy 371.492062 -222.634901) (xy 371.51564 -222.588627) (xy 371.546166 -222.546611)
			(xy 371.582889 -222.509888) (xy 371.624905 -222.479362) (xy 371.671179 -222.455784) (xy 371.720572 -222.439736)
			(xy 371.771867 -222.431611) (xy 371.823801 -222.431611) (xy 371.875096 -222.439736) (xy 371.924489 -222.455784)
			(xy 371.970763 -222.479362) (xy 372.012779 -222.509888) (xy 372.049502 -222.546611) (xy 372.080028 -222.588627)
			(xy 372.103606 -222.634901) (xy 372.119654 -222.684294) (xy 372.127779 -222.735589) (xy 372.128288 -222.761556)
			(xy 372.127779 -222.787523) (xy 372.407689 -222.787523) (xy 372.407689 -222.735589) (xy 372.415814 -222.684294)
			(xy 372.431862 -222.634901) (xy 372.45544 -222.588627) (xy 372.485966 -222.546611) (xy 372.522689 -222.509888)
			(xy 372.564705 -222.479362) (xy 372.610979 -222.455784) (xy 372.660372 -222.439736) (xy 372.711667 -222.431611)
			(xy 372.763601 -222.431611) (xy 372.814896 -222.439736) (xy 372.864289 -222.455784) (xy 372.910563 -222.479362)
			(xy 372.952579 -222.509888) (xy 372.989302 -222.546611) (xy 373.019828 -222.588627) (xy 373.043406 -222.634901)
			(xy 373.059454 -222.684294) (xy 373.067579 -222.735589) (xy 373.068088 -222.761556) (xy 373.067579 -222.787523)
			(xy 373.347489 -222.787523) (xy 373.347489 -222.735589) (xy 373.355614 -222.684294) (xy 373.371662 -222.634901)
			(xy 373.39524 -222.588627) (xy 373.425766 -222.546611) (xy 373.462489 -222.509888) (xy 373.504505 -222.479362)
			(xy 373.550779 -222.455784) (xy 373.600172 -222.439736) (xy 373.651467 -222.431611) (xy 373.703401 -222.431611)
			(xy 373.754696 -222.439736) (xy 373.804089 -222.455784) (xy 373.850363 -222.479362) (xy 373.892379 -222.509888)
			(xy 373.929102 -222.546611) (xy 373.959628 -222.588627) (xy 373.983206 -222.634901) (xy 373.999254 -222.684294)
			(xy 374.007379 -222.735589) (xy 374.007888 -222.761556) (xy 374.007379 -222.787523) (xy 374.287289 -222.787523)
			(xy 374.287289 -222.735589) (xy 374.295414 -222.684294) (xy 374.311462 -222.634901) (xy 374.33504 -222.588627)
			(xy 374.365566 -222.546611) (xy 374.402289 -222.509888) (xy 374.444305 -222.479362) (xy 374.490579 -222.455784)
			(xy 374.539972 -222.439736) (xy 374.591267 -222.431611) (xy 374.643201 -222.431611) (xy 374.694496 -222.439736)
			(xy 374.743889 -222.455784) (xy 374.790163 -222.479362) (xy 374.832179 -222.509888) (xy 374.868902 -222.546611)
			(xy 374.899428 -222.588627) (xy 374.923006 -222.634901) (xy 374.939054 -222.684294) (xy 374.947179 -222.735589)
			(xy 374.947688 -222.761556) (xy 374.947179 -222.787523) (xy 375.227089 -222.787523) (xy 375.227089 -222.735589)
			(xy 375.235214 -222.684294) (xy 375.251262 -222.634901) (xy 375.27484 -222.588627) (xy 375.305366 -222.546611)
			(xy 375.342089 -222.509888) (xy 375.384105 -222.479362) (xy 375.430379 -222.455784) (xy 375.479772 -222.439736)
			(xy 375.531067 -222.431611) (xy 375.583001 -222.431611) (xy 375.634296 -222.439736) (xy 375.683689 -222.455784)
			(xy 375.729963 -222.479362) (xy 375.771979 -222.509888) (xy 375.808702 -222.546611) (xy 375.839228 -222.588627)
			(xy 375.862806 -222.634901) (xy 375.878854 -222.684294) (xy 375.886979 -222.735589) (xy 375.887488 -222.761556)
			(xy 375.886979 -222.787523) (xy 375.878854 -222.838818) (xy 375.862806 -222.888211) (xy 375.839228 -222.934485)
			(xy 375.808702 -222.976501) (xy 375.771979 -223.013224) (xy 375.729963 -223.04375) (xy 375.683689 -223.067328)
			(xy 375.634296 -223.083376) (xy 375.583001 -223.091501) (xy 375.531067 -223.091501) (xy 375.479772 -223.083376)
			(xy 375.430379 -223.067328) (xy 375.384105 -223.04375) (xy 375.342089 -223.013224) (xy 375.305366 -222.976501)
			(xy 375.27484 -222.934485) (xy 375.251262 -222.888211) (xy 375.235214 -222.838818) (xy 375.227089 -222.787523)
			(xy 374.947179 -222.787523) (xy 374.939054 -222.838818) (xy 374.923006 -222.888211) (xy 374.899428 -222.934485)
			(xy 374.868902 -222.976501) (xy 374.832179 -223.013224) (xy 374.790163 -223.04375) (xy 374.743889 -223.067328)
			(xy 374.694496 -223.083376) (xy 374.643201 -223.091501) (xy 374.591267 -223.091501) (xy 374.539972 -223.083376)
			(xy 374.490579 -223.067328) (xy 374.444305 -223.04375) (xy 374.402289 -223.013224) (xy 374.365566 -222.976501)
			(xy 374.33504 -222.934485) (xy 374.311462 -222.888211) (xy 374.295414 -222.838818) (xy 374.287289 -222.787523)
			(xy 374.007379 -222.787523) (xy 373.999254 -222.838818) (xy 373.983206 -222.888211) (xy 373.959628 -222.934485)
			(xy 373.929102 -222.976501) (xy 373.892379 -223.013224) (xy 373.850363 -223.04375) (xy 373.804089 -223.067328)
			(xy 373.754696 -223.083376) (xy 373.703401 -223.091501) (xy 373.651467 -223.091501) (xy 373.600172 -223.083376)
			(xy 373.550779 -223.067328) (xy 373.504505 -223.04375) (xy 373.462489 -223.013224) (xy 373.425766 -222.976501)
			(xy 373.39524 -222.934485) (xy 373.371662 -222.888211) (xy 373.355614 -222.838818) (xy 373.347489 -222.787523)
			(xy 373.067579 -222.787523) (xy 373.059454 -222.838818) (xy 373.043406 -222.888211) (xy 373.019828 -222.934485)
			(xy 372.989302 -222.976501) (xy 372.952579 -223.013224) (xy 372.910563 -223.04375) (xy 372.864289 -223.067328)
			(xy 372.814896 -223.083376) (xy 372.763601 -223.091501) (xy 372.711667 -223.091501) (xy 372.660372 -223.083376)
			(xy 372.610979 -223.067328) (xy 372.564705 -223.04375) (xy 372.522689 -223.013224) (xy 372.485966 -222.976501)
			(xy 372.45544 -222.934485) (xy 372.431862 -222.888211) (xy 372.415814 -222.838818) (xy 372.407689 -222.787523)
			(xy 372.127779 -222.787523) (xy 372.119654 -222.838818) (xy 372.103606 -222.888211) (xy 372.080028 -222.934485)
			(xy 372.049502 -222.976501) (xy 372.012779 -223.013224) (xy 371.970763 -223.04375) (xy 371.924489 -223.067328)
			(xy 371.875096 -223.083376) (xy 371.823801 -223.091501) (xy 371.771867 -223.091501) (xy 371.720572 -223.083376)
			(xy 371.671179 -223.067328) (xy 371.624905 -223.04375) (xy 371.582889 -223.013224) (xy 371.546166 -222.976501)
			(xy 371.51564 -222.934485) (xy 371.492062 -222.888211) (xy 371.476014 -222.838818) (xy 371.467889 -222.787523)
			(xy 371.187979 -222.787523) (xy 371.179854 -222.838818) (xy 371.163806 -222.888211) (xy 371.140228 -222.934485)
			(xy 371.109702 -222.976501) (xy 371.072979 -223.013224) (xy 371.030963 -223.04375) (xy 370.984689 -223.067328)
			(xy 370.935296 -223.083376) (xy 370.884001 -223.091501) (xy 370.832067 -223.091501) (xy 370.780772 -223.083376)
			(xy 370.731379 -223.067328) (xy 370.685105 -223.04375) (xy 370.643089 -223.013224) (xy 370.606366 -222.976501)
			(xy 370.57584 -222.934485) (xy 370.552262 -222.888211) (xy 370.536214 -222.838818) (xy 370.528089 -222.787523)
			(xy 370.248179 -222.787523) (xy 370.240054 -222.838818) (xy 370.224006 -222.888211) (xy 370.200428 -222.934485)
			(xy 370.169902 -222.976501) (xy 370.133179 -223.013224) (xy 370.091163 -223.04375) (xy 370.044889 -223.067328)
			(xy 369.995496 -223.083376) (xy 369.944201 -223.091501) (xy 369.892267 -223.091501) (xy 369.840972 -223.083376)
			(xy 369.791579 -223.067328) (xy 369.745305 -223.04375) (xy 369.703289 -223.013224) (xy 369.666566 -222.976501)
			(xy 369.63604 -222.934485) (xy 369.612462 -222.888211) (xy 369.596414 -222.838818) (xy 369.588289 -222.787523)
			(xy 369.308379 -222.787523) (xy 369.300254 -222.838818) (xy 369.284206 -222.888211) (xy 369.260628 -222.934485)
			(xy 369.230102 -222.976501) (xy 369.193379 -223.013224) (xy 369.151363 -223.04375) (xy 369.105089 -223.067328)
			(xy 369.055696 -223.083376) (xy 369.004401 -223.091501) (xy 368.952467 -223.091501) (xy 368.901172 -223.083376)
			(xy 368.851779 -223.067328) (xy 368.805505 -223.04375) (xy 368.763489 -223.013224) (xy 368.726766 -222.976501)
			(xy 368.69624 -222.934485) (xy 368.672662 -222.888211) (xy 368.656614 -222.838818) (xy 368.648489 -222.787523)
			(xy 368.368579 -222.787523) (xy 368.360454 -222.838818) (xy 368.344406 -222.888211) (xy 368.320828 -222.934485)
			(xy 368.290302 -222.976501) (xy 368.253579 -223.013224) (xy 368.211563 -223.04375) (xy 368.165289 -223.067328)
			(xy 368.115896 -223.083376) (xy 368.064601 -223.091501) (xy 368.012667 -223.091501) (xy 367.961372 -223.083376)
			(xy 367.911979 -223.067328) (xy 367.865705 -223.04375) (xy 367.823689 -223.013224) (xy 367.786966 -222.976501)
			(xy 367.75644 -222.934485) (xy 367.732862 -222.888211) (xy 367.716814 -222.838818) (xy 367.708689 -222.787523)
			(xy 367.428779 -222.787523) (xy 367.420654 -222.838818) (xy 367.404606 -222.888211) (xy 367.381028 -222.934485)
			(xy 367.350502 -222.976501) (xy 367.313779 -223.013224) (xy 367.271763 -223.04375) (xy 367.225489 -223.067328)
			(xy 367.176096 -223.083376) (xy 367.124801 -223.091501) (xy 367.072867 -223.091501) (xy 367.021572 -223.083376)
			(xy 366.972179 -223.067328) (xy 366.925905 -223.04375) (xy 366.883889 -223.013224) (xy 366.847166 -222.976501)
			(xy 366.81664 -222.934485) (xy 366.793062 -222.888211) (xy 366.777014 -222.838818) (xy 366.768889 -222.787523)
			(xy 366.488979 -222.787523) (xy 366.480854 -222.838818) (xy 366.464806 -222.888211) (xy 366.441228 -222.934485)
			(xy 366.410702 -222.976501) (xy 366.373979 -223.013224) (xy 366.331963 -223.04375) (xy 366.285689 -223.067328)
			(xy 366.236296 -223.083376) (xy 366.185001 -223.091501) (xy 366.133067 -223.091501) (xy 366.081772 -223.083376)
			(xy 366.032379 -223.067328) (xy 365.986105 -223.04375) (xy 365.944089 -223.013224) (xy 365.907366 -222.976501)
			(xy 365.87684 -222.934485) (xy 365.853262 -222.888211) (xy 365.837214 -222.838818) (xy 365.829089 -222.787523)
			(xy 365.549179 -222.787523) (xy 365.541054 -222.838818) (xy 365.525006 -222.888211) (xy 365.501428 -222.934485)
			(xy 365.470902 -222.976501) (xy 365.434179 -223.013224) (xy 365.392163 -223.04375) (xy 365.345889 -223.067328)
			(xy 365.296496 -223.083376) (xy 365.245201 -223.091501) (xy 365.193267 -223.091501) (xy 365.141972 -223.083376)
			(xy 365.092579 -223.067328) (xy 365.046305 -223.04375) (xy 365.004289 -223.013224) (xy 364.967566 -222.976501)
			(xy 364.93704 -222.934485) (xy 364.913462 -222.888211) (xy 364.897414 -222.838818) (xy 364.889289 -222.787523)
			(xy 364.609379 -222.787523) (xy 364.601254 -222.838818) (xy 364.585206 -222.888211) (xy 364.561628 -222.934485)
			(xy 364.531102 -222.976501) (xy 364.494379 -223.013224) (xy 364.452363 -223.04375) (xy 364.406089 -223.067328)
			(xy 364.356696 -223.083376) (xy 364.305401 -223.091501) (xy 364.253467 -223.091501) (xy 364.202172 -223.083376)
			(xy 364.152779 -223.067328) (xy 364.106505 -223.04375) (xy 364.064489 -223.013224) (xy 364.027766 -222.976501)
			(xy 363.99724 -222.934485) (xy 363.973662 -222.888211) (xy 363.957614 -222.838818) (xy 363.949489 -222.787523)
			(xy 363.669579 -222.787523) (xy 363.661454 -222.838818) (xy 363.645406 -222.888211) (xy 363.621828 -222.934485)
			(xy 363.591302 -222.976501) (xy 363.554579 -223.013224) (xy 363.512563 -223.04375) (xy 363.466289 -223.067328)
			(xy 363.416896 -223.083376) (xy 363.365601 -223.091501) (xy 363.313667 -223.091501) (xy 363.262372 -223.083376)
			(xy 363.212979 -223.067328) (xy 363.166705 -223.04375) (xy 363.124689 -223.013224) (xy 363.087966 -222.976501)
			(xy 363.05744 -222.934485) (xy 363.033862 -222.888211) (xy 363.017814 -222.838818) (xy 363.009689 -222.787523)
			(xy 362.729779 -222.787523) (xy 362.721654 -222.838818) (xy 362.705606 -222.888211) (xy 362.682028 -222.934485)
			(xy 362.651502 -222.976501) (xy 362.614779 -223.013224) (xy 362.572763 -223.04375) (xy 362.526489 -223.067328)
			(xy 362.477096 -223.083376) (xy 362.425801 -223.091501) (xy 362.373867 -223.091501) (xy 362.322572 -223.083376)
			(xy 362.273179 -223.067328) (xy 362.226905 -223.04375) (xy 362.184889 -223.013224) (xy 362.148166 -222.976501)
			(xy 362.11764 -222.934485) (xy 362.094062 -222.888211) (xy 362.078014 -222.838818) (xy 362.069889 -222.787523)
			(xy 361.789979 -222.787523) (xy 361.781854 -222.838818) (xy 361.765806 -222.888211) (xy 361.742228 -222.934485)
			(xy 361.711702 -222.976501) (xy 361.674979 -223.013224) (xy 361.632963 -223.04375) (xy 361.586689 -223.067328)
			(xy 361.537296 -223.083376) (xy 361.486001 -223.091501) (xy 361.434067 -223.091501) (xy 361.382772 -223.083376)
			(xy 361.333379 -223.067328) (xy 361.287105 -223.04375) (xy 361.245089 -223.013224) (xy 361.208366 -222.976501)
			(xy 361.17784 -222.934485) (xy 361.154262 -222.888211) (xy 361.138214 -222.838818) (xy 361.130089 -222.787523)
			(xy 360.850179 -222.787523) (xy 360.842054 -222.838818) (xy 360.826006 -222.888211) (xy 360.802428 -222.934485)
			(xy 360.771902 -222.976501) (xy 360.735179 -223.013224) (xy 360.693163 -223.04375) (xy 360.646889 -223.067328)
			(xy 360.597496 -223.083376) (xy 360.546201 -223.091501) (xy 360.494267 -223.091501) (xy 360.442972 -223.083376)
			(xy 360.393579 -223.067328) (xy 360.347305 -223.04375) (xy 360.305289 -223.013224) (xy 360.268566 -222.976501)
			(xy 360.23804 -222.934485) (xy 360.214462 -222.888211) (xy 360.198414 -222.838818) (xy 360.190289 -222.787523)
			(xy 359.910379 -222.787523) (xy 359.902254 -222.838818) (xy 359.886206 -222.888211) (xy 359.862628 -222.934485)
			(xy 359.832102 -222.976501) (xy 359.795379 -223.013224) (xy 359.753363 -223.04375) (xy 359.707089 -223.067328)
			(xy 359.657696 -223.083376) (xy 359.606401 -223.091501) (xy 359.554467 -223.091501) (xy 359.503172 -223.083376)
			(xy 359.453779 -223.067328) (xy 359.407505 -223.04375) (xy 359.365489 -223.013224) (xy 359.328766 -222.976501)
			(xy 359.29824 -222.934485) (xy 359.274662 -222.888211) (xy 359.258614 -222.838818) (xy 359.250489 -222.787523)
			(xy 358.970608 -222.787523) (xy 358.970608 -222.787529) (xy 358.962489 -222.838835) (xy 358.946444 -222.88824)
			(xy 358.922867 -222.934526) (xy 358.892339 -222.976554) (xy 358.855613 -223.013289) (xy 358.813592 -223.043826)
			(xy 358.767312 -223.067414) (xy 358.717911 -223.083471) (xy 358.666606 -223.091602) (xy 358.640634 -223.09201)
			(xy 358.615043 -223.091504) (xy 358.56448 -223.083567) (xy 358.515741 -223.06794) (xy 358.46999 -223.044994)
			(xy 358.448864 -223.030542) (xy 358.403362 -223.041739) (xy 358.31097 -223.057414) (xy 358.21759 -223.065315)
			(xy 358.170734 -223.065848) (xy 358.120931 -223.065278) (xy 358.021723 -223.056371) (xy 357.972614 -223.048068)
			(xy 357.946452 -223.043496) (xy 357.538528 -223.45142) (xy 357.547164 -223.48063) (xy 357.553671 -223.503839)
			(xy 357.56068 -223.551526) (xy 357.561134 -223.575626) (xy 357.560664 -223.601075) (xy 357.560584 -223.601593)
			(xy 357.840789 -223.601593) (xy 357.840789 -223.549659) (xy 357.848914 -223.498364) (xy 357.864962 -223.448971)
			(xy 357.88854 -223.402697) (xy 357.919066 -223.360681) (xy 357.955789 -223.323958) (xy 357.997805 -223.293432)
			(xy 358.044079 -223.269854) (xy 358.093472 -223.253806) (xy 358.144767 -223.245681) (xy 358.196701 -223.245681)
			(xy 358.247996 -223.253806) (xy 358.297389 -223.269854) (xy 358.343663 -223.293432) (xy 358.385679 -223.323958)
			(xy 358.422402 -223.360681) (xy 358.452928 -223.402697) (xy 358.476506 -223.448971) (xy 358.492554 -223.498364)
			(xy 358.500679 -223.549659) (xy 358.501188 -223.575626) (xy 358.500679 -223.601593) (xy 358.492554 -223.652888)
			(xy 358.476506 -223.702281) (xy 358.452928 -223.748555) (xy 358.422402 -223.790571) (xy 358.385679 -223.827294)
			(xy 358.343663 -223.85782) (xy 358.297389 -223.881398) (xy 358.247996 -223.897446) (xy 358.196701 -223.905571)
			(xy 358.144767 -223.905571) (xy 358.093472 -223.897446) (xy 358.044079 -223.881398) (xy 357.997805 -223.85782)
			(xy 357.955789 -223.827294) (xy 357.919066 -223.790571) (xy 357.88854 -223.748555) (xy 357.864962 -223.702281)
			(xy 357.848914 -223.652888) (xy 357.840789 -223.601593) (xy 357.560584 -223.601593) (xy 357.552859 -223.651372)
			(xy 357.53744 -223.699878) (xy 357.514768 -223.745449) (xy 357.485381 -223.787007) (xy 357.449972 -223.82357)
			(xy 357.409378 -223.854275) (xy 357.364558 -223.878396) (xy 357.316571 -223.895364) (xy 357.29164 -223.900492)
			(xy 357.268526 -223.90481) (xy 357.065072 -224.257616) (xy 357.072692 -224.279714) (xy 357.081482 -224.306289)
			(xy 357.090926 -224.361457) (xy 357.091488 -224.389442) (xy 357.37038 -224.389442) (xy 357.370889 -224.363475)
			(xy 357.379014 -224.31218) (xy 357.395062 -224.262787) (xy 357.41864 -224.216513) (xy 357.449166 -224.174497)
			(xy 357.485889 -224.137774) (xy 357.527905 -224.107248) (xy 357.574179 -224.08367) (xy 357.623572 -224.067622)
			(xy 357.674867 -224.059497) (xy 357.726801 -224.059497) (xy 357.778096 -224.067622) (xy 357.827489 -224.08367)
			(xy 357.873763 -224.107248) (xy 357.915779 -224.137774) (xy 357.952502 -224.174497) (xy 357.983028 -224.216513)
			(xy 358.006606 -224.262787) (xy 358.022654 -224.31218) (xy 358.030779 -224.363475) (xy 358.031288 -224.389442)
			(xy 358.31018 -224.389442) (xy 358.310587 -224.363988) (xy 358.318374 -224.31368) (xy 358.333787 -224.265161)
			(xy 358.35646 -224.219581) (xy 358.385856 -224.178019) (xy 358.42128 -224.141457) (xy 358.461893 -224.110763)
			(xy 358.506734 -224.086661) (xy 358.554742 -224.069724) (xy 358.579674 -224.064576) (xy 358.602534 -224.060258)
			(xy 358.806242 -223.707198) (xy 358.798622 -223.685354) (xy 358.789898 -223.658762) (xy 358.780441 -223.603606)
			(xy 358.779826 -223.575626) (xy 358.780335 -223.549659) (xy 358.78846 -223.498364) (xy 358.804508 -223.448971)
			(xy 358.828086 -223.402697) (xy 358.858612 -223.360681) (xy 358.895335 -223.323958) (xy 358.937351 -223.293432)
			(xy 358.983625 -223.269854) (xy 359.033018 -223.253806) (xy 359.084313 -223.245681) (xy 359.136247 -223.245681)
			(xy 359.187542 -223.253806) (xy 359.236935 -223.269854) (xy 359.283209 -223.293432) (xy 359.325225 -223.323958)
			(xy 359.361948 -223.360681) (xy 359.392474 -223.402697) (xy 359.416052 -223.448971) (xy 359.4321 -223.498364)
			(xy 359.440225 -223.549659) (xy 359.440734 -223.575626) (xy 359.440286 -223.601078) (xy 359.440206 -223.601593)
			(xy 359.720389 -223.601593) (xy 359.720389 -223.549659) (xy 359.728514 -223.498364) (xy 359.744562 -223.448971)
			(xy 359.76814 -223.402697) (xy 359.798666 -223.360681) (xy 359.835389 -223.323958) (xy 359.877405 -223.293432)
			(xy 359.923679 -223.269854) (xy 359.973072 -223.253806) (xy 360.024367 -223.245681) (xy 360.076301 -223.245681)
			(xy 360.127596 -223.253806) (xy 360.176989 -223.269854) (xy 360.223263 -223.293432) (xy 360.265279 -223.323958)
			(xy 360.302002 -223.360681) (xy 360.332528 -223.402697) (xy 360.356106 -223.448971) (xy 360.372154 -223.498364)
			(xy 360.380279 -223.549659) (xy 360.380788 -223.575626) (xy 360.380279 -223.601593) (xy 360.372154 -223.652888)
			(xy 360.356106 -223.702281) (xy 360.332528 -223.748555) (xy 360.302002 -223.790571) (xy 360.265279 -223.827294)
			(xy 360.223263 -223.85782) (xy 360.176989 -223.881398) (xy 360.127596 -223.897446) (xy 360.076301 -223.905571)
			(xy 360.024367 -223.905571) (xy 359.973072 -223.897446) (xy 359.923679 -223.881398) (xy 359.877405 -223.85782)
			(xy 359.835389 -223.827294) (xy 359.798666 -223.790571) (xy 359.76814 -223.748555) (xy 359.744562 -223.702281)
			(xy 359.728514 -223.652888) (xy 359.720389 -223.601593) (xy 359.440206 -223.601593) (xy 359.432504 -223.651385)
			(xy 359.417097 -223.699901) (xy 359.394429 -223.74548) (xy 359.365038 -223.787043) (xy 359.329619 -223.823605)
			(xy 359.28901 -223.8543) (xy 359.244174 -223.878403) (xy 359.19617 -223.895342) (xy 359.17124 -223.900492)
			(xy 359.148126 -223.90481) (xy 358.944672 -224.257616) (xy 358.952292 -224.279714) (xy 358.961033 -224.306301)
			(xy 358.970478 -224.361461) (xy 358.971088 -224.389442) (xy 359.24998 -224.389442) (xy 359.250489 -224.363475)
			(xy 359.258614 -224.31218) (xy 359.274662 -224.262787) (xy 359.29824 -224.216513) (xy 359.328766 -224.174497)
			(xy 359.365489 -224.137774) (xy 359.407505 -224.107248) (xy 359.453779 -224.08367) (xy 359.503172 -224.067622)
			(xy 359.554467 -224.059497) (xy 359.606401 -224.059497) (xy 359.657696 -224.067622) (xy 359.707089 -224.08367)
			(xy 359.753363 -224.107248) (xy 359.795379 -224.137774) (xy 359.832102 -224.174497) (xy 359.862628 -224.216513)
			(xy 359.886206 -224.262787) (xy 359.902254 -224.31218) (xy 359.910379 -224.363475) (xy 359.910888 -224.389442)
			(xy 360.18978 -224.389442) (xy 360.190187 -224.363988) (xy 360.197974 -224.31368) (xy 360.213387 -224.265161)
			(xy 360.23606 -224.219581) (xy 360.265456 -224.178019) (xy 360.30088 -224.141457) (xy 360.341493 -224.110763)
			(xy 360.386334 -224.086661) (xy 360.434342 -224.069724) (xy 360.459274 -224.064576) (xy 360.482134 -224.060258)
			(xy 360.685842 -223.707198) (xy 360.678222 -223.685354) (xy 360.669498 -223.658762) (xy 360.660041 -223.603606)
			(xy 360.659426 -223.575626) (xy 360.659935 -223.549659) (xy 360.66806 -223.498364) (xy 360.684108 -223.448971)
			(xy 360.707686 -223.402697) (xy 360.738212 -223.360681) (xy 360.774935 -223.323958) (xy 360.816951 -223.293432)
			(xy 360.863225 -223.269854) (xy 360.912618 -223.253806) (xy 360.963913 -223.245681) (xy 361.015847 -223.245681)
			(xy 361.067142 -223.253806) (xy 361.116535 -223.269854) (xy 361.162809 -223.293432) (xy 361.204825 -223.323958)
			(xy 361.241548 -223.360681) (xy 361.272074 -223.402697) (xy 361.295652 -223.448971) (xy 361.3117 -223.498364)
			(xy 361.319825 -223.549659) (xy 361.320334 -223.575626) (xy 361.319886 -223.601078) (xy 361.319806 -223.601593)
			(xy 361.599989 -223.601593) (xy 361.599989 -223.549659) (xy 361.608114 -223.498364) (xy 361.624162 -223.448971)
			(xy 361.64774 -223.402697) (xy 361.678266 -223.360681) (xy 361.714989 -223.323958) (xy 361.757005 -223.293432)
			(xy 361.803279 -223.269854) (xy 361.852672 -223.253806) (xy 361.903967 -223.245681) (xy 361.955901 -223.245681)
			(xy 362.007196 -223.253806) (xy 362.056589 -223.269854) (xy 362.102863 -223.293432) (xy 362.144879 -223.323958)
			(xy 362.181602 -223.360681) (xy 362.212128 -223.402697) (xy 362.235706 -223.448971) (xy 362.251754 -223.498364)
			(xy 362.259879 -223.549659) (xy 362.260388 -223.575626) (xy 362.259879 -223.601593) (xy 362.251754 -223.652888)
			(xy 362.235706 -223.702281) (xy 362.212128 -223.748555) (xy 362.181602 -223.790571) (xy 362.144879 -223.827294)
			(xy 362.102863 -223.85782) (xy 362.056589 -223.881398) (xy 362.007196 -223.897446) (xy 361.955901 -223.905571)
			(xy 361.903967 -223.905571) (xy 361.852672 -223.897446) (xy 361.803279 -223.881398) (xy 361.757005 -223.85782)
			(xy 361.714989 -223.827294) (xy 361.678266 -223.790571) (xy 361.64774 -223.748555) (xy 361.624162 -223.702281)
			(xy 361.608114 -223.652888) (xy 361.599989 -223.601593) (xy 361.319806 -223.601593) (xy 361.312104 -223.651385)
			(xy 361.296697 -223.699901) (xy 361.274029 -223.74548) (xy 361.244638 -223.787043) (xy 361.209219 -223.823605)
			(xy 361.16861 -223.8543) (xy 361.123774 -223.878403) (xy 361.07577 -223.895342) (xy 361.05084 -223.900492)
			(xy 361.027726 -223.90481) (xy 360.824272 -224.257616) (xy 360.831892 -224.279714) (xy 360.840633 -224.306301)
			(xy 360.850078 -224.361461) (xy 360.850688 -224.389442) (xy 361.12958 -224.389442) (xy 361.130089 -224.363475)
			(xy 361.138214 -224.31218) (xy 361.154262 -224.262787) (xy 361.17784 -224.216513) (xy 361.208366 -224.174497)
			(xy 361.245089 -224.137774) (xy 361.287105 -224.107248) (xy 361.333379 -224.08367) (xy 361.382772 -224.067622)
			(xy 361.434067 -224.059497) (xy 361.486001 -224.059497) (xy 361.537296 -224.067622) (xy 361.586689 -224.08367)
			(xy 361.632963 -224.107248) (xy 361.674979 -224.137774) (xy 361.711702 -224.174497) (xy 361.742228 -224.216513)
			(xy 361.765806 -224.262787) (xy 361.781854 -224.31218) (xy 361.789979 -224.363475) (xy 361.790488 -224.389442)
			(xy 362.06938 -224.389442) (xy 362.069787 -224.363988) (xy 362.077574 -224.31368) (xy 362.092987 -224.265161)
			(xy 362.11566 -224.219581) (xy 362.145056 -224.178019) (xy 362.18048 -224.141457) (xy 362.221093 -224.110763)
			(xy 362.265934 -224.086661) (xy 362.313942 -224.069724) (xy 362.338874 -224.064576) (xy 362.361734 -224.060258)
			(xy 362.565696 -223.706944) (xy 362.557822 -223.6851) (xy 362.549162 -223.658564) (xy 362.539841 -223.603534)
			(xy 362.53928 -223.575626) (xy 362.539789 -223.549659) (xy 362.547914 -223.498364) (xy 362.563962 -223.448971)
			(xy 362.58754 -223.402697) (xy 362.618066 -223.360681) (xy 362.654789 -223.323958) (xy 362.696805 -223.293432)
			(xy 362.743079 -223.269854) (xy 362.792472 -223.253806) (xy 362.843767 -223.245681) (xy 362.895701 -223.245681)
			(xy 362.946996 -223.253806) (xy 362.996389 -223.269854) (xy 363.042663 -223.293432) (xy 363.084679 -223.323958)
			(xy 363.121402 -223.360681) (xy 363.151928 -223.402697) (xy 363.175506 -223.448971) (xy 363.191554 -223.498364)
			(xy 363.199679 -223.549659) (xy 363.200188 -223.575626) (xy 363.19974 -223.60109) (xy 363.199662 -223.601593)
			(xy 363.479589 -223.601593) (xy 363.479589 -223.549659) (xy 363.487714 -223.498364) (xy 363.503762 -223.448971)
			(xy 363.52734 -223.402697) (xy 363.557866 -223.360681) (xy 363.594589 -223.323958) (xy 363.636605 -223.293432)
			(xy 363.682879 -223.269854) (xy 363.732272 -223.253806) (xy 363.783567 -223.245681) (xy 363.835501 -223.245681)
			(xy 363.886796 -223.253806) (xy 363.936189 -223.269854) (xy 363.982463 -223.293432) (xy 364.024479 -223.323958)
			(xy 364.061202 -223.360681) (xy 364.091728 -223.402697) (xy 364.115306 -223.448971) (xy 364.131354 -223.498364)
			(xy 364.139479 -223.549659) (xy 364.139988 -223.575626) (xy 364.139479 -223.601593) (xy 364.131354 -223.652888)
			(xy 364.115306 -223.702281) (xy 364.091728 -223.748555) (xy 364.061202 -223.790571) (xy 364.024479 -223.827294)
			(xy 363.982463 -223.85782) (xy 363.936189 -223.881398) (xy 363.886796 -223.897446) (xy 363.835501 -223.905571)
			(xy 363.783567 -223.905571) (xy 363.732272 -223.897446) (xy 363.682879 -223.881398) (xy 363.636605 -223.85782)
			(xy 363.594589 -223.827294) (xy 363.557866 -223.790571) (xy 363.52734 -223.748555) (xy 363.503762 -223.702281)
			(xy 363.487714 -223.652888) (xy 363.479589 -223.601593) (xy 363.199662 -223.601593) (xy 363.191937 -223.651415)
			(xy 363.176504 -223.699947) (xy 363.153808 -223.745537) (xy 363.124385 -223.787104) (xy 363.088932 -223.823664)
			(xy 363.048289 -223.854351) (xy 363.003419 -223.878439) (xy 362.955385 -223.895356) (xy 362.93044 -223.900492)
			(xy 362.907326 -223.90481) (xy 362.703872 -224.257616) (xy 362.711492 -224.279714) (xy 362.720233 -224.306301)
			(xy 362.729678 -224.361461) (xy 362.730288 -224.389442) (xy 363.00918 -224.389442) (xy 363.009689 -224.363475)
			(xy 363.017814 -224.31218) (xy 363.033862 -224.262787) (xy 363.05744 -224.216513) (xy 363.087966 -224.174497)
			(xy 363.124689 -224.137774) (xy 363.166705 -224.107248) (xy 363.212979 -224.08367) (xy 363.262372 -224.067622)
			(xy 363.313667 -224.059497) (xy 363.365601 -224.059497) (xy 363.416896 -224.067622) (xy 363.466289 -224.08367)
			(xy 363.512563 -224.107248) (xy 363.554579 -224.137774) (xy 363.591302 -224.174497) (xy 363.621828 -224.216513)
			(xy 363.645406 -224.262787) (xy 363.661454 -224.31218) (xy 363.669579 -224.363475) (xy 363.670088 -224.389442)
			(xy 363.94898 -224.389442) (xy 363.949387 -224.363988) (xy 363.957174 -224.31368) (xy 363.972587 -224.265161)
			(xy 363.99526 -224.219581) (xy 364.024656 -224.178019) (xy 364.06008 -224.141457) (xy 364.100693 -224.110763)
			(xy 364.145534 -224.086661) (xy 364.193542 -224.069724) (xy 364.218474 -224.064576) (xy 364.241334 -224.060258)
			(xy 364.445042 -223.707198) (xy 364.437422 -223.685354) (xy 364.428698 -223.658762) (xy 364.419241 -223.603606)
			(xy 364.418626 -223.575626) (xy 364.419135 -223.549659) (xy 364.42726 -223.498364) (xy 364.443308 -223.448971)
			(xy 364.466886 -223.402697) (xy 364.497412 -223.360681) (xy 364.534135 -223.323958) (xy 364.576151 -223.293432)
			(xy 364.622425 -223.269854) (xy 364.671818 -223.253806) (xy 364.723113 -223.245681) (xy 364.775047 -223.245681)
			(xy 364.826342 -223.253806) (xy 364.875735 -223.269854) (xy 364.922009 -223.293432) (xy 364.964025 -223.323958)
			(xy 365.000748 -223.360681) (xy 365.031274 -223.402697) (xy 365.054852 -223.448971) (xy 365.0709 -223.498364)
			(xy 365.079025 -223.549659) (xy 365.079534 -223.575626) (xy 365.079086 -223.601078) (xy 365.079006 -223.601593)
			(xy 365.359189 -223.601593) (xy 365.359189 -223.549659) (xy 365.367314 -223.498364) (xy 365.383362 -223.448971)
			(xy 365.40694 -223.402697) (xy 365.437466 -223.360681) (xy 365.474189 -223.323958) (xy 365.516205 -223.293432)
			(xy 365.562479 -223.269854) (xy 365.611872 -223.253806) (xy 365.663167 -223.245681) (xy 365.715101 -223.245681)
			(xy 365.766396 -223.253806) (xy 365.815789 -223.269854) (xy 365.862063 -223.293432) (xy 365.904079 -223.323958)
			(xy 365.940802 -223.360681) (xy 365.971328 -223.402697) (xy 365.994906 -223.448971) (xy 366.010954 -223.498364)
			(xy 366.019079 -223.549659) (xy 366.019588 -223.575626) (xy 366.019079 -223.601593) (xy 366.010954 -223.652888)
			(xy 365.994906 -223.702281) (xy 365.971328 -223.748555) (xy 365.940802 -223.790571) (xy 365.904079 -223.827294)
			(xy 365.862063 -223.85782) (xy 365.815789 -223.881398) (xy 365.766396 -223.897446) (xy 365.715101 -223.905571)
			(xy 365.663167 -223.905571) (xy 365.611872 -223.897446) (xy 365.562479 -223.881398) (xy 365.516205 -223.85782)
			(xy 365.474189 -223.827294) (xy 365.437466 -223.790571) (xy 365.40694 -223.748555) (xy 365.383362 -223.702281)
			(xy 365.367314 -223.652888) (xy 365.359189 -223.601593) (xy 365.079006 -223.601593) (xy 365.071304 -223.651385)
			(xy 365.055897 -223.699901) (xy 365.033229 -223.74548) (xy 365.003838 -223.787043) (xy 364.968419 -223.823605)
			(xy 364.92781 -223.8543) (xy 364.882974 -223.878403) (xy 364.83497 -223.895342) (xy 364.81004 -223.900492)
			(xy 364.786926 -223.90481) (xy 364.583472 -224.257616) (xy 364.591092 -224.279714) (xy 364.599833 -224.306301)
			(xy 364.609278 -224.361461) (xy 364.609888 -224.389442) (xy 364.88878 -224.389442) (xy 364.889289 -224.363475)
			(xy 364.897414 -224.31218) (xy 364.913462 -224.262787) (xy 364.93704 -224.216513) (xy 364.967566 -224.174497)
			(xy 365.004289 -224.137774) (xy 365.046305 -224.107248) (xy 365.092579 -224.08367) (xy 365.141972 -224.067622)
			(xy 365.193267 -224.059497) (xy 365.245201 -224.059497) (xy 365.296496 -224.067622) (xy 365.345889 -224.08367)
			(xy 365.392163 -224.107248) (xy 365.434179 -224.137774) (xy 365.470902 -224.174497) (xy 365.501428 -224.216513)
			(xy 365.525006 -224.262787) (xy 365.541054 -224.31218) (xy 365.549179 -224.363475) (xy 365.549688 -224.389442)
			(xy 365.82858 -224.389442) (xy 365.828987 -224.363988) (xy 365.836774 -224.31368) (xy 365.852187 -224.265161)
			(xy 365.87486 -224.219581) (xy 365.904256 -224.178019) (xy 365.93968 -224.141457) (xy 365.980293 -224.110763)
			(xy 366.025134 -224.086661) (xy 366.073142 -224.069724) (xy 366.098074 -224.064576) (xy 366.120934 -224.060258)
			(xy 366.324642 -223.707198) (xy 366.317022 -223.685354) (xy 366.308298 -223.658762) (xy 366.298841 -223.603606)
			(xy 366.298226 -223.575626) (xy 366.298735 -223.549659) (xy 366.30686 -223.498364) (xy 366.322908 -223.448971)
			(xy 366.346486 -223.402697) (xy 366.377012 -223.360681) (xy 366.413735 -223.323958) (xy 366.455751 -223.293432)
			(xy 366.502025 -223.269854) (xy 366.551418 -223.253806) (xy 366.602713 -223.245681) (xy 366.654647 -223.245681)
			(xy 366.705942 -223.253806) (xy 366.755335 -223.269854) (xy 366.801609 -223.293432) (xy 366.843625 -223.323958)
			(xy 366.880348 -223.360681) (xy 366.910874 -223.402697) (xy 366.934452 -223.448971) (xy 366.9505 -223.498364)
			(xy 366.958625 -223.549659) (xy 366.959134 -223.575626) (xy 366.958686 -223.601078) (xy 366.958606 -223.601593)
			(xy 367.238789 -223.601593) (xy 367.238789 -223.549659) (xy 367.246914 -223.498364) (xy 367.262962 -223.448971)
			(xy 367.28654 -223.402697) (xy 367.317066 -223.360681) (xy 367.353789 -223.323958) (xy 367.395805 -223.293432)
			(xy 367.442079 -223.269854) (xy 367.491472 -223.253806) (xy 367.542767 -223.245681) (xy 367.594701 -223.245681)
			(xy 367.645996 -223.253806) (xy 367.695389 -223.269854) (xy 367.741663 -223.293432) (xy 367.783679 -223.323958)
			(xy 367.820402 -223.360681) (xy 367.850928 -223.402697) (xy 367.874506 -223.448971) (xy 367.890554 -223.498364)
			(xy 367.898679 -223.549659) (xy 367.899188 -223.575626) (xy 367.898679 -223.601593) (xy 367.890554 -223.652888)
			(xy 367.874506 -223.702281) (xy 367.850928 -223.748555) (xy 367.820402 -223.790571) (xy 367.783679 -223.827294)
			(xy 367.741663 -223.85782) (xy 367.695389 -223.881398) (xy 367.645996 -223.897446) (xy 367.594701 -223.905571)
			(xy 367.542767 -223.905571) (xy 367.491472 -223.897446) (xy 367.442079 -223.881398) (xy 367.395805 -223.85782)
			(xy 367.353789 -223.827294) (xy 367.317066 -223.790571) (xy 367.28654 -223.748555) (xy 367.262962 -223.702281)
			(xy 367.246914 -223.652888) (xy 367.238789 -223.601593) (xy 366.958606 -223.601593) (xy 366.950904 -223.651385)
			(xy 366.935497 -223.699901) (xy 366.912829 -223.74548) (xy 366.883438 -223.787043) (xy 366.848019 -223.823605)
			(xy 366.80741 -223.8543) (xy 366.762574 -223.878403) (xy 366.71457 -223.895342) (xy 366.68964 -223.900492)
			(xy 366.666526 -223.90481) (xy 366.463072 -224.257616) (xy 366.470692 -224.279714) (xy 366.479433 -224.306301)
			(xy 366.488878 -224.361461) (xy 366.489488 -224.389442) (xy 366.76838 -224.389442) (xy 366.768889 -224.363475)
			(xy 366.777014 -224.31218) (xy 366.793062 -224.262787) (xy 366.81664 -224.216513) (xy 366.847166 -224.174497)
			(xy 366.883889 -224.137774) (xy 366.925905 -224.107248) (xy 366.972179 -224.08367) (xy 367.021572 -224.067622)
			(xy 367.072867 -224.059497) (xy 367.124801 -224.059497) (xy 367.176096 -224.067622) (xy 367.225489 -224.08367)
			(xy 367.271763 -224.107248) (xy 367.313779 -224.137774) (xy 367.350502 -224.174497) (xy 367.381028 -224.216513)
			(xy 367.404606 -224.262787) (xy 367.420654 -224.31218) (xy 367.428779 -224.363475) (xy 367.429288 -224.389442)
			(xy 367.70818 -224.389442) (xy 367.708587 -224.363988) (xy 367.716374 -224.31368) (xy 367.731787 -224.265161)
			(xy 367.75446 -224.219581) (xy 367.783856 -224.178019) (xy 367.81928 -224.141457) (xy 367.859893 -224.110763)
			(xy 367.904734 -224.086661) (xy 367.952742 -224.069724) (xy 367.977674 -224.064576) (xy 368.000534 -224.060258)
			(xy 368.204242 -223.707198) (xy 368.196622 -223.685354) (xy 368.187898 -223.658762) (xy 368.178441 -223.603606)
			(xy 368.177826 -223.575626) (xy 368.178335 -223.549659) (xy 368.18646 -223.498364) (xy 368.202508 -223.448971)
			(xy 368.226086 -223.402697) (xy 368.256612 -223.360681) (xy 368.293335 -223.323958) (xy 368.335351 -223.293432)
			(xy 368.381625 -223.269854) (xy 368.431018 -223.253806) (xy 368.482313 -223.245681) (xy 368.534247 -223.245681)
			(xy 368.585542 -223.253806) (xy 368.634935 -223.269854) (xy 368.681209 -223.293432) (xy 368.723225 -223.323958)
			(xy 368.759948 -223.360681) (xy 368.790474 -223.402697) (xy 368.814052 -223.448971) (xy 368.8301 -223.498364)
			(xy 368.838225 -223.549659) (xy 368.838734 -223.575626) (xy 368.838286 -223.601078) (xy 368.838206 -223.601593)
			(xy 369.118389 -223.601593) (xy 369.118389 -223.549659) (xy 369.126514 -223.498364) (xy 369.142562 -223.448971)
			(xy 369.16614 -223.402697) (xy 369.196666 -223.360681) (xy 369.233389 -223.323958) (xy 369.275405 -223.293432)
			(xy 369.321679 -223.269854) (xy 369.371072 -223.253806) (xy 369.422367 -223.245681) (xy 369.474301 -223.245681)
			(xy 369.525596 -223.253806) (xy 369.574989 -223.269854) (xy 369.621263 -223.293432) (xy 369.663279 -223.323958)
			(xy 369.700002 -223.360681) (xy 369.730528 -223.402697) (xy 369.754106 -223.448971) (xy 369.770154 -223.498364)
			(xy 369.778279 -223.549659) (xy 369.778788 -223.575626) (xy 369.778279 -223.601593) (xy 369.770154 -223.652888)
			(xy 369.754106 -223.702281) (xy 369.730528 -223.748555) (xy 369.700002 -223.790571) (xy 369.663279 -223.827294)
			(xy 369.621263 -223.85782) (xy 369.574989 -223.881398) (xy 369.525596 -223.897446) (xy 369.474301 -223.905571)
			(xy 369.422367 -223.905571) (xy 369.371072 -223.897446) (xy 369.321679 -223.881398) (xy 369.275405 -223.85782)
			(xy 369.233389 -223.827294) (xy 369.196666 -223.790571) (xy 369.16614 -223.748555) (xy 369.142562 -223.702281)
			(xy 369.126514 -223.652888) (xy 369.118389 -223.601593) (xy 368.838206 -223.601593) (xy 368.830504 -223.651385)
			(xy 368.815097 -223.699901) (xy 368.792429 -223.74548) (xy 368.763038 -223.787043) (xy 368.727619 -223.823605)
			(xy 368.68701 -223.8543) (xy 368.642174 -223.878403) (xy 368.59417 -223.895342) (xy 368.56924 -223.900492)
			(xy 368.546126 -223.90481) (xy 368.342672 -224.257616) (xy 368.350292 -224.279714) (xy 368.359033 -224.306301)
			(xy 368.368478 -224.361461) (xy 368.369088 -224.389442) (xy 368.64798 -224.389442) (xy 368.648489 -224.363475)
			(xy 368.656614 -224.31218) (xy 368.672662 -224.262787) (xy 368.69624 -224.216513) (xy 368.726766 -224.174497)
			(xy 368.763489 -224.137774) (xy 368.805505 -224.107248) (xy 368.851779 -224.08367) (xy 368.901172 -224.067622)
			(xy 368.952467 -224.059497) (xy 369.004401 -224.059497) (xy 369.055696 -224.067622) (xy 369.105089 -224.08367)
			(xy 369.151363 -224.107248) (xy 369.193379 -224.137774) (xy 369.230102 -224.174497) (xy 369.260628 -224.216513)
			(xy 369.284206 -224.262787) (xy 369.300254 -224.31218) (xy 369.308379 -224.363475) (xy 369.308888 -224.389442)
			(xy 369.58778 -224.389442) (xy 369.588187 -224.363988) (xy 369.595974 -224.31368) (xy 369.611387 -224.265161)
			(xy 369.63406 -224.219581) (xy 369.663456 -224.178019) (xy 369.69888 -224.141457) (xy 369.739493 -224.110763)
			(xy 369.784334 -224.086661) (xy 369.832342 -224.069724) (xy 369.857274 -224.064576) (xy 369.880134 -224.060258)
			(xy 370.083842 -223.707198) (xy 370.076222 -223.685354) (xy 370.067498 -223.658762) (xy 370.058041 -223.603606)
			(xy 370.057426 -223.575626) (xy 370.057935 -223.549659) (xy 370.06606 -223.498364) (xy 370.082108 -223.448971)
			(xy 370.105686 -223.402697) (xy 370.136212 -223.360681) (xy 370.172935 -223.323958) (xy 370.214951 -223.293432)
			(xy 370.261225 -223.269854) (xy 370.310618 -223.253806) (xy 370.361913 -223.245681) (xy 370.413847 -223.245681)
			(xy 370.465142 -223.253806) (xy 370.514535 -223.269854) (xy 370.560809 -223.293432) (xy 370.602825 -223.323958)
			(xy 370.639548 -223.360681) (xy 370.670074 -223.402697) (xy 370.693652 -223.448971) (xy 370.7097 -223.498364)
			(xy 370.717825 -223.549659) (xy 370.718334 -223.575626) (xy 370.717886 -223.601078) (xy 370.717806 -223.601593)
			(xy 370.997989 -223.601593) (xy 370.997989 -223.549659) (xy 371.006114 -223.498364) (xy 371.022162 -223.448971)
			(xy 371.04574 -223.402697) (xy 371.076266 -223.360681) (xy 371.112989 -223.323958) (xy 371.155005 -223.293432)
			(xy 371.201279 -223.269854) (xy 371.250672 -223.253806) (xy 371.301967 -223.245681) (xy 371.353901 -223.245681)
			(xy 371.405196 -223.253806) (xy 371.454589 -223.269854) (xy 371.500863 -223.293432) (xy 371.542879 -223.323958)
			(xy 371.579602 -223.360681) (xy 371.610128 -223.402697) (xy 371.633706 -223.448971) (xy 371.649754 -223.498364)
			(xy 371.657879 -223.549659) (xy 371.658388 -223.575626) (xy 371.657879 -223.601593) (xy 371.649754 -223.652888)
			(xy 371.633706 -223.702281) (xy 371.610128 -223.748555) (xy 371.579602 -223.790571) (xy 371.542879 -223.827294)
			(xy 371.500863 -223.85782) (xy 371.454589 -223.881398) (xy 371.405196 -223.897446) (xy 371.353901 -223.905571)
			(xy 371.301967 -223.905571) (xy 371.250672 -223.897446) (xy 371.201279 -223.881398) (xy 371.155005 -223.85782)
			(xy 371.112989 -223.827294) (xy 371.076266 -223.790571) (xy 371.04574 -223.748555) (xy 371.022162 -223.702281)
			(xy 371.006114 -223.652888) (xy 370.997989 -223.601593) (xy 370.717806 -223.601593) (xy 370.710104 -223.651385)
			(xy 370.694697 -223.699901) (xy 370.672029 -223.74548) (xy 370.642638 -223.787043) (xy 370.607219 -223.823605)
			(xy 370.56661 -223.8543) (xy 370.521774 -223.878403) (xy 370.47377 -223.895342) (xy 370.44884 -223.900492)
			(xy 370.425726 -223.90481) (xy 370.222272 -224.257616) (xy 370.229892 -224.279714) (xy 370.238633 -224.306301)
			(xy 370.248078 -224.361461) (xy 370.248688 -224.389442) (xy 370.52758 -224.389442) (xy 370.528089 -224.363475)
			(xy 370.536214 -224.31218) (xy 370.552262 -224.262787) (xy 370.57584 -224.216513) (xy 370.606366 -224.174497)
			(xy 370.643089 -224.137774) (xy 370.685105 -224.107248) (xy 370.731379 -224.08367) (xy 370.780772 -224.067622)
			(xy 370.832067 -224.059497) (xy 370.884001 -224.059497) (xy 370.935296 -224.067622) (xy 370.984689 -224.08367)
			(xy 371.030963 -224.107248) (xy 371.072979 -224.137774) (xy 371.109702 -224.174497) (xy 371.140228 -224.216513)
			(xy 371.163806 -224.262787) (xy 371.179854 -224.31218) (xy 371.187979 -224.363475) (xy 371.188488 -224.389442)
			(xy 371.46738 -224.389442) (xy 371.467787 -224.363988) (xy 371.475574 -224.31368) (xy 371.490987 -224.265161)
			(xy 371.51366 -224.219581) (xy 371.543056 -224.178019) (xy 371.57848 -224.141457) (xy 371.619093 -224.110763)
			(xy 371.663934 -224.086661) (xy 371.711942 -224.069724) (xy 371.736874 -224.064576) (xy 371.759734 -224.060258)
			(xy 371.963442 -223.707198) (xy 371.955822 -223.685354) (xy 371.947098 -223.658762) (xy 371.937641 -223.603606)
			(xy 371.937026 -223.575626) (xy 371.937535 -223.549659) (xy 371.94566 -223.498364) (xy 371.961708 -223.448971)
			(xy 371.985286 -223.402697) (xy 372.015812 -223.360681) (xy 372.052535 -223.323958) (xy 372.094551 -223.293432)
			(xy 372.140825 -223.269854) (xy 372.190218 -223.253806) (xy 372.241513 -223.245681) (xy 372.293447 -223.245681)
			(xy 372.344742 -223.253806) (xy 372.394135 -223.269854) (xy 372.440409 -223.293432) (xy 372.482425 -223.323958)
			(xy 372.519148 -223.360681) (xy 372.549674 -223.402697) (xy 372.573252 -223.448971) (xy 372.5893 -223.498364)
			(xy 372.597425 -223.549659) (xy 372.597934 -223.575626) (xy 372.597486 -223.601078) (xy 372.597406 -223.601593)
			(xy 372.877589 -223.601593) (xy 372.877589 -223.549659) (xy 372.885714 -223.498364) (xy 372.901762 -223.448971)
			(xy 372.92534 -223.402697) (xy 372.955866 -223.360681) (xy 372.992589 -223.323958) (xy 373.034605 -223.293432)
			(xy 373.080879 -223.269854) (xy 373.130272 -223.253806) (xy 373.181567 -223.245681) (xy 373.233501 -223.245681)
			(xy 373.284796 -223.253806) (xy 373.334189 -223.269854) (xy 373.380463 -223.293432) (xy 373.422479 -223.323958)
			(xy 373.459202 -223.360681) (xy 373.489728 -223.402697) (xy 373.513306 -223.448971) (xy 373.529354 -223.498364)
			(xy 373.537479 -223.549659) (xy 373.537988 -223.575626) (xy 373.537479 -223.601593) (xy 373.529354 -223.652888)
			(xy 373.513306 -223.702281) (xy 373.489728 -223.748555) (xy 373.459202 -223.790571) (xy 373.422479 -223.827294)
			(xy 373.380463 -223.85782) (xy 373.334189 -223.881398) (xy 373.284796 -223.897446) (xy 373.233501 -223.905571)
			(xy 373.181567 -223.905571) (xy 373.130272 -223.897446) (xy 373.080879 -223.881398) (xy 373.034605 -223.85782)
			(xy 372.992589 -223.827294) (xy 372.955866 -223.790571) (xy 372.92534 -223.748555) (xy 372.901762 -223.702281)
			(xy 372.885714 -223.652888) (xy 372.877589 -223.601593) (xy 372.597406 -223.601593) (xy 372.589704 -223.651385)
			(xy 372.574297 -223.699901) (xy 372.551629 -223.74548) (xy 372.522238 -223.787043) (xy 372.486819 -223.823605)
			(xy 372.44621 -223.8543) (xy 372.401374 -223.878403) (xy 372.35337 -223.895342) (xy 372.32844 -223.900492)
			(xy 372.305326 -223.90481) (xy 372.101872 -224.257616) (xy 372.109492 -224.279714) (xy 372.118233 -224.306301)
			(xy 372.127678 -224.361461) (xy 372.128288 -224.389442) (xy 372.40718 -224.389442) (xy 372.407689 -224.363475)
			(xy 372.415814 -224.31218) (xy 372.431862 -224.262787) (xy 372.45544 -224.216513) (xy 372.485966 -224.174497)
			(xy 372.522689 -224.137774) (xy 372.564705 -224.107248) (xy 372.610979 -224.08367) (xy 372.660372 -224.067622)
			(xy 372.711667 -224.059497) (xy 372.763601 -224.059497) (xy 372.814896 -224.067622) (xy 372.864289 -224.08367)
			(xy 372.910563 -224.107248) (xy 372.952579 -224.137774) (xy 372.989302 -224.174497) (xy 373.019828 -224.216513)
			(xy 373.043406 -224.262787) (xy 373.059454 -224.31218) (xy 373.067579 -224.363475) (xy 373.068088 -224.389442)
			(xy 373.34698 -224.389442) (xy 373.347387 -224.363988) (xy 373.355174 -224.31368) (xy 373.370587 -224.265161)
			(xy 373.39326 -224.219581) (xy 373.422656 -224.178019) (xy 373.45808 -224.141457) (xy 373.498693 -224.110763)
			(xy 373.543534 -224.086661) (xy 373.591542 -224.069724) (xy 373.616474 -224.064576) (xy 373.639334 -224.060258)
			(xy 373.843042 -223.707198) (xy 373.835422 -223.685354) (xy 373.826698 -223.658762) (xy 373.817241 -223.603606)
			(xy 373.816626 -223.575626) (xy 373.817135 -223.549659) (xy 373.82526 -223.498364) (xy 373.841308 -223.448971)
			(xy 373.864886 -223.402697) (xy 373.895412 -223.360681) (xy 373.932135 -223.323958) (xy 373.974151 -223.293432)
			(xy 374.020425 -223.269854) (xy 374.069818 -223.253806) (xy 374.121113 -223.245681) (xy 374.173047 -223.245681)
			(xy 374.224342 -223.253806) (xy 374.273735 -223.269854) (xy 374.320009 -223.293432) (xy 374.362025 -223.323958)
			(xy 374.398748 -223.360681) (xy 374.429274 -223.402697) (xy 374.452852 -223.448971) (xy 374.4689 -223.498364)
			(xy 374.477025 -223.549659) (xy 374.477534 -223.575626) (xy 374.477086 -223.601078) (xy 374.477006 -223.601593)
			(xy 374.757189 -223.601593) (xy 374.757189 -223.549659) (xy 374.765314 -223.498364) (xy 374.781362 -223.448971)
			(xy 374.80494 -223.402697) (xy 374.835466 -223.360681) (xy 374.872189 -223.323958) (xy 374.914205 -223.293432)
			(xy 374.960479 -223.269854) (xy 375.009872 -223.253806) (xy 375.061167 -223.245681) (xy 375.113101 -223.245681)
			(xy 375.164396 -223.253806) (xy 375.213789 -223.269854) (xy 375.260063 -223.293432) (xy 375.302079 -223.323958)
			(xy 375.338802 -223.360681) (xy 375.369328 -223.402697) (xy 375.392906 -223.448971) (xy 375.408954 -223.498364)
			(xy 375.417079 -223.549659) (xy 375.417588 -223.575626) (xy 375.417079 -223.601593) (xy 375.408954 -223.652888)
			(xy 375.392906 -223.702281) (xy 375.369328 -223.748555) (xy 375.338802 -223.790571) (xy 375.302079 -223.827294)
			(xy 375.260063 -223.85782) (xy 375.213789 -223.881398) (xy 375.164396 -223.897446) (xy 375.113101 -223.905571)
			(xy 375.061167 -223.905571) (xy 375.009872 -223.897446) (xy 374.960479 -223.881398) (xy 374.914205 -223.85782)
			(xy 374.872189 -223.827294) (xy 374.835466 -223.790571) (xy 374.80494 -223.748555) (xy 374.781362 -223.702281)
			(xy 374.765314 -223.652888) (xy 374.757189 -223.601593) (xy 374.477006 -223.601593) (xy 374.469304 -223.651385)
			(xy 374.453897 -223.699901) (xy 374.431229 -223.74548) (xy 374.401838 -223.787043) (xy 374.366419 -223.823605)
			(xy 374.32581 -223.8543) (xy 374.280974 -223.878403) (xy 374.23297 -223.895342) (xy 374.20804 -223.900492)
			(xy 374.184926 -223.90481) (xy 373.981472 -224.257616) (xy 373.989092 -224.279714) (xy 373.997833 -224.306301)
			(xy 374.007278 -224.361461) (xy 374.007888 -224.389442) (xy 374.28678 -224.389442) (xy 374.287289 -224.363475)
			(xy 374.295414 -224.31218) (xy 374.311462 -224.262787) (xy 374.33504 -224.216513) (xy 374.365566 -224.174497)
			(xy 374.402289 -224.137774) (xy 374.444305 -224.107248) (xy 374.490579 -224.08367) (xy 374.539972 -224.067622)
			(xy 374.591267 -224.059497) (xy 374.643201 -224.059497) (xy 374.694496 -224.067622) (xy 374.743889 -224.08367)
			(xy 374.790163 -224.107248) (xy 374.832179 -224.137774) (xy 374.868902 -224.174497) (xy 374.899428 -224.216513)
			(xy 374.923006 -224.262787) (xy 374.939054 -224.31218) (xy 374.947179 -224.363475) (xy 374.947688 -224.389442)
			(xy 374.947146 -224.417428) (xy 374.937689 -224.472596) (xy 374.928892 -224.49917) (xy 374.921272 -224.521268)
			(xy 375.12498 -224.874074) (xy 375.14784 -224.878392) (xy 375.172767 -224.883535) (xy 375.220753 -224.900502)
			(xy 375.265572 -224.924622) (xy 375.306166 -224.955325) (xy 375.341575 -224.991886) (xy 375.370962 -225.033442)
			(xy 375.393635 -225.07901) (xy 375.409056 -225.127515) (xy 375.416862 -225.17781) (xy 375.417334 -225.203258)
			(xy 375.416825 -225.229225) (xy 375.4087 -225.28052) (xy 375.392652 -225.329913) (xy 375.369074 -225.376187)
			(xy 375.338548 -225.418203) (xy 375.301825 -225.454926) (xy 375.259809 -225.485452) (xy 375.213535 -225.50903)
			(xy 375.164142 -225.525078) (xy 375.112847 -225.533203) (xy 375.060913 -225.533203) (xy 375.009618 -225.525078)
			(xy 374.960225 -225.50903) (xy 374.913951 -225.485452) (xy 374.871935 -225.454926) (xy 374.835212 -225.418203)
			(xy 374.804686 -225.376187) (xy 374.781108 -225.329913) (xy 374.76506 -225.28052) (xy 374.756935 -225.229225)
			(xy 374.756426 -225.203258) (xy 374.756967 -225.175272) (xy 374.766425 -225.120104) (xy 374.775222 -225.09353)
			(xy 374.782842 -225.071432) (xy 374.579134 -224.718626) (xy 374.556274 -224.714308) (xy 374.531349 -224.709155)
			(xy 374.483363 -224.69219) (xy 374.438544 -224.668072) (xy 374.39795 -224.63737) (xy 374.36254 -224.60081)
			(xy 374.333152 -224.559256) (xy 374.31048 -224.513688) (xy 374.295058 -224.465184) (xy 374.287252 -224.41489)
			(xy 374.28678 -224.389442) (xy 374.007888 -224.389442) (xy 374.007379 -224.415409) (xy 373.999254 -224.466704)
			(xy 373.983206 -224.516097) (xy 373.959628 -224.562371) (xy 373.929102 -224.604387) (xy 373.892379 -224.64111)
			(xy 373.850363 -224.671636) (xy 373.804089 -224.695214) (xy 373.754696 -224.711262) (xy 373.703401 -224.719387)
			(xy 373.651467 -224.719387) (xy 373.600172 -224.711262) (xy 373.550779 -224.695214) (xy 373.504505 -224.671636)
			(xy 373.462489 -224.64111) (xy 373.425766 -224.604387) (xy 373.39524 -224.562371) (xy 373.371662 -224.516097)
			(xy 373.355614 -224.466704) (xy 373.347489 -224.415409) (xy 373.34698 -224.389442) (xy 373.068088 -224.389442)
			(xy 373.067546 -224.417428) (xy 373.058089 -224.472596) (xy 373.049292 -224.49917) (xy 373.041672 -224.521268)
			(xy 373.24538 -224.874074) (xy 373.26824 -224.878392) (xy 373.293167 -224.883535) (xy 373.341153 -224.900502)
			(xy 373.385972 -224.924622) (xy 373.426566 -224.955325) (xy 373.461975 -224.991886) (xy 373.491362 -225.033442)
			(xy 373.514035 -225.07901) (xy 373.529456 -225.127515) (xy 373.537262 -225.17781) (xy 373.537734 -225.203258)
			(xy 373.537225 -225.229225) (xy 373.5291 -225.28052) (xy 373.513052 -225.329913) (xy 373.489474 -225.376187)
			(xy 373.458948 -225.418203) (xy 373.422225 -225.454926) (xy 373.380209 -225.485452) (xy 373.333935 -225.50903)
			(xy 373.284542 -225.525078) (xy 373.233247 -225.533203) (xy 373.181313 -225.533203) (xy 373.130018 -225.525078)
			(xy 373.080625 -225.50903) (xy 373.034351 -225.485452) (xy 372.992335 -225.454926) (xy 372.955612 -225.418203)
			(xy 372.925086 -225.376187) (xy 372.901508 -225.329913) (xy 372.88546 -225.28052) (xy 372.877335 -225.229225)
			(xy 372.876826 -225.203258) (xy 372.877367 -225.175272) (xy 372.886825 -225.120104) (xy 372.895622 -225.09353)
			(xy 372.903242 -225.071432) (xy 372.699534 -224.718626) (xy 372.676674 -224.714308) (xy 372.651749 -224.709155)
			(xy 372.603763 -224.69219) (xy 372.558944 -224.668072) (xy 372.51835 -224.63737) (xy 372.48294 -224.60081)
			(xy 372.453552 -224.559256) (xy 372.43088 -224.513688) (xy 372.415458 -224.465184) (xy 372.407652 -224.41489)
			(xy 372.40718 -224.389442) (xy 372.128288 -224.389442) (xy 372.127779 -224.415409) (xy 372.119654 -224.466704)
			(xy 372.103606 -224.516097) (xy 372.080028 -224.562371) (xy 372.049502 -224.604387) (xy 372.012779 -224.64111)
			(xy 371.970763 -224.671636) (xy 371.924489 -224.695214) (xy 371.875096 -224.711262) (xy 371.823801 -224.719387)
			(xy 371.771867 -224.719387) (xy 371.720572 -224.711262) (xy 371.671179 -224.695214) (xy 371.624905 -224.671636)
			(xy 371.582889 -224.64111) (xy 371.546166 -224.604387) (xy 371.51564 -224.562371) (xy 371.492062 -224.516097)
			(xy 371.476014 -224.466704) (xy 371.467889 -224.415409) (xy 371.46738 -224.389442) (xy 371.188488 -224.389442)
			(xy 371.187946 -224.417428) (xy 371.178489 -224.472596) (xy 371.169692 -224.49917) (xy 371.162072 -224.521268)
			(xy 371.36578 -224.874074) (xy 371.38864 -224.878392) (xy 371.413567 -224.883535) (xy 371.461553 -224.900502)
			(xy 371.506372 -224.924622) (xy 371.546966 -224.955325) (xy 371.582375 -224.991886) (xy 371.611762 -225.033442)
			(xy 371.634435 -225.07901) (xy 371.649856 -225.127515) (xy 371.657662 -225.17781) (xy 371.658134 -225.203258)
			(xy 371.657625 -225.229225) (xy 371.6495 -225.28052) (xy 371.633452 -225.329913) (xy 371.609874 -225.376187)
			(xy 371.579348 -225.418203) (xy 371.542625 -225.454926) (xy 371.500609 -225.485452) (xy 371.454335 -225.50903)
			(xy 371.404942 -225.525078) (xy 371.353647 -225.533203) (xy 371.301713 -225.533203) (xy 371.250418 -225.525078)
			(xy 371.201025 -225.50903) (xy 371.154751 -225.485452) (xy 371.112735 -225.454926) (xy 371.076012 -225.418203)
			(xy 371.045486 -225.376187) (xy 371.021908 -225.329913) (xy 371.00586 -225.28052) (xy 370.997735 -225.229225)
			(xy 370.997226 -225.203258) (xy 370.997767 -225.175272) (xy 371.007225 -225.120104) (xy 371.016022 -225.09353)
			(xy 371.023642 -225.071432) (xy 370.819934 -224.718626) (xy 370.797074 -224.714308) (xy 370.772149 -224.709155)
			(xy 370.724163 -224.69219) (xy 370.679344 -224.668072) (xy 370.63875 -224.63737) (xy 370.60334 -224.60081)
			(xy 370.573952 -224.559256) (xy 370.55128 -224.513688) (xy 370.535858 -224.465184) (xy 370.528052 -224.41489)
			(xy 370.52758 -224.389442) (xy 370.248688 -224.389442) (xy 370.248179 -224.415409) (xy 370.240054 -224.466704)
			(xy 370.224006 -224.516097) (xy 370.200428 -224.562371) (xy 370.169902 -224.604387) (xy 370.133179 -224.64111)
			(xy 370.091163 -224.671636) (xy 370.044889 -224.695214) (xy 369.995496 -224.711262) (xy 369.944201 -224.719387)
			(xy 369.892267 -224.719387) (xy 369.840972 -224.711262) (xy 369.791579 -224.695214) (xy 369.745305 -224.671636)
			(xy 369.703289 -224.64111) (xy 369.666566 -224.604387) (xy 369.63604 -224.562371) (xy 369.612462 -224.516097)
			(xy 369.596414 -224.466704) (xy 369.588289 -224.415409) (xy 369.58778 -224.389442) (xy 369.308888 -224.389442)
			(xy 369.308346 -224.417428) (xy 369.298889 -224.472596) (xy 369.290092 -224.49917) (xy 369.282472 -224.521268)
			(xy 369.48618 -224.874074) (xy 369.50904 -224.878392) (xy 369.533967 -224.883535) (xy 369.581953 -224.900502)
			(xy 369.626772 -224.924622) (xy 369.667366 -224.955325) (xy 369.702775 -224.991886) (xy 369.732162 -225.033442)
			(xy 369.754835 -225.07901) (xy 369.770256 -225.127515) (xy 369.778062 -225.17781) (xy 369.778534 -225.203258)
			(xy 369.778025 -225.229225) (xy 369.7699 -225.28052) (xy 369.753852 -225.329913) (xy 369.730274 -225.376187)
			(xy 369.699748 -225.418203) (xy 369.663025 -225.454926) (xy 369.621009 -225.485452) (xy 369.574735 -225.50903)
			(xy 369.525342 -225.525078) (xy 369.474047 -225.533203) (xy 369.422113 -225.533203) (xy 369.370818 -225.525078)
			(xy 369.321425 -225.50903) (xy 369.275151 -225.485452) (xy 369.233135 -225.454926) (xy 369.196412 -225.418203)
			(xy 369.165886 -225.376187) (xy 369.142308 -225.329913) (xy 369.12626 -225.28052) (xy 369.118135 -225.229225)
			(xy 369.117626 -225.203258) (xy 369.118167 -225.175272) (xy 369.127625 -225.120104) (xy 369.136422 -225.09353)
			(xy 369.144042 -225.071432) (xy 368.940334 -224.718626) (xy 368.917474 -224.714308) (xy 368.892549 -224.709155)
			(xy 368.844563 -224.69219) (xy 368.799744 -224.668072) (xy 368.75915 -224.63737) (xy 368.72374 -224.60081)
			(xy 368.694352 -224.559256) (xy 368.67168 -224.513688) (xy 368.656258 -224.465184) (xy 368.648452 -224.41489)
			(xy 368.64798 -224.389442) (xy 368.369088 -224.389442) (xy 368.368579 -224.415409) (xy 368.360454 -224.466704)
			(xy 368.344406 -224.516097) (xy 368.320828 -224.562371) (xy 368.290302 -224.604387) (xy 368.253579 -224.64111)
			(xy 368.211563 -224.671636) (xy 368.165289 -224.695214) (xy 368.115896 -224.711262) (xy 368.064601 -224.719387)
			(xy 368.012667 -224.719387) (xy 367.961372 -224.711262) (xy 367.911979 -224.695214) (xy 367.865705 -224.671636)
			(xy 367.823689 -224.64111) (xy 367.786966 -224.604387) (xy 367.75644 -224.562371) (xy 367.732862 -224.516097)
			(xy 367.716814 -224.466704) (xy 367.708689 -224.415409) (xy 367.70818 -224.389442) (xy 367.429288 -224.389442)
			(xy 367.428746 -224.417428) (xy 367.419289 -224.472596) (xy 367.410492 -224.49917) (xy 367.402872 -224.521268)
			(xy 367.60658 -224.874074) (xy 367.62944 -224.878392) (xy 367.654367 -224.883535) (xy 367.702353 -224.900502)
			(xy 367.747172 -224.924622) (xy 367.787766 -224.955325) (xy 367.823175 -224.991886) (xy 367.852562 -225.033442)
			(xy 367.875235 -225.07901) (xy 367.890656 -225.127515) (xy 367.898462 -225.17781) (xy 367.898934 -225.203258)
			(xy 367.898425 -225.229225) (xy 367.8903 -225.28052) (xy 367.874252 -225.329913) (xy 367.850674 -225.376187)
			(xy 367.820148 -225.418203) (xy 367.783425 -225.454926) (xy 367.741409 -225.485452) (xy 367.695135 -225.50903)
			(xy 367.645742 -225.525078) (xy 367.594447 -225.533203) (xy 367.542513 -225.533203) (xy 367.491218 -225.525078)
			(xy 367.441825 -225.50903) (xy 367.395551 -225.485452) (xy 367.353535 -225.454926) (xy 367.316812 -225.418203)
			(xy 367.286286 -225.376187) (xy 367.262708 -225.329913) (xy 367.24666 -225.28052) (xy 367.238535 -225.229225)
			(xy 367.238026 -225.203258) (xy 367.238567 -225.175272) (xy 367.248025 -225.120104) (xy 367.256822 -225.09353)
			(xy 367.264442 -225.071432) (xy 367.060734 -224.718626) (xy 367.037874 -224.714308) (xy 367.012949 -224.709155)
			(xy 366.964963 -224.69219) (xy 366.920144 -224.668072) (xy 366.87955 -224.63737) (xy 366.84414 -224.60081)
			(xy 366.814752 -224.559256) (xy 366.79208 -224.513688) (xy 366.776658 -224.465184) (xy 366.768852 -224.41489)
			(xy 366.76838 -224.389442) (xy 366.489488 -224.389442) (xy 366.488979 -224.415409) (xy 366.480854 -224.466704)
			(xy 366.464806 -224.516097) (xy 366.441228 -224.562371) (xy 366.410702 -224.604387) (xy 366.373979 -224.64111)
			(xy 366.331963 -224.671636) (xy 366.285689 -224.695214) (xy 366.236296 -224.711262) (xy 366.185001 -224.719387)
			(xy 366.133067 -224.719387) (xy 366.081772 -224.711262) (xy 366.032379 -224.695214) (xy 365.986105 -224.671636)
			(xy 365.944089 -224.64111) (xy 365.907366 -224.604387) (xy 365.87684 -224.562371) (xy 365.853262 -224.516097)
			(xy 365.837214 -224.466704) (xy 365.829089 -224.415409) (xy 365.82858 -224.389442) (xy 365.549688 -224.389442)
			(xy 365.549146 -224.417428) (xy 365.539689 -224.472596) (xy 365.530892 -224.49917) (xy 365.523272 -224.521268)
			(xy 365.72698 -224.874074) (xy 365.74984 -224.878392) (xy 365.774767 -224.883535) (xy 365.822753 -224.900502)
			(xy 365.867572 -224.924622) (xy 365.908166 -224.955325) (xy 365.943575 -224.991886) (xy 365.972962 -225.033442)
			(xy 365.995635 -225.07901) (xy 366.011056 -225.127515) (xy 366.018862 -225.17781) (xy 366.019334 -225.203258)
			(xy 366.018825 -225.229225) (xy 366.0107 -225.28052) (xy 365.994652 -225.329913) (xy 365.971074 -225.376187)
			(xy 365.940548 -225.418203) (xy 365.903825 -225.454926) (xy 365.861809 -225.485452) (xy 365.815535 -225.50903)
			(xy 365.766142 -225.525078) (xy 365.714847 -225.533203) (xy 365.662913 -225.533203) (xy 365.611618 -225.525078)
			(xy 365.562225 -225.50903) (xy 365.515951 -225.485452) (xy 365.473935 -225.454926) (xy 365.437212 -225.418203)
			(xy 365.406686 -225.376187) (xy 365.383108 -225.329913) (xy 365.36706 -225.28052) (xy 365.358935 -225.229225)
			(xy 365.358426 -225.203258) (xy 365.358967 -225.175272) (xy 365.368425 -225.120104) (xy 365.377222 -225.09353)
			(xy 365.384842 -225.071432) (xy 365.181134 -224.718626) (xy 365.158274 -224.714308) (xy 365.133349 -224.709155)
			(xy 365.085363 -224.69219) (xy 365.040544 -224.668072) (xy 364.99995 -224.63737) (xy 364.96454 -224.60081)
			(xy 364.935152 -224.559256) (xy 364.91248 -224.513688) (xy 364.897058 -224.465184) (xy 364.889252 -224.41489)
			(xy 364.88878 -224.389442) (xy 364.609888 -224.389442) (xy 364.609379 -224.415409) (xy 364.601254 -224.466704)
			(xy 364.585206 -224.516097) (xy 364.561628 -224.562371) (xy 364.531102 -224.604387) (xy 364.494379 -224.64111)
			(xy 364.452363 -224.671636) (xy 364.406089 -224.695214) (xy 364.356696 -224.711262) (xy 364.305401 -224.719387)
			(xy 364.253467 -224.719387) (xy 364.202172 -224.711262) (xy 364.152779 -224.695214) (xy 364.106505 -224.671636)
			(xy 364.064489 -224.64111) (xy 364.027766 -224.604387) (xy 363.99724 -224.562371) (xy 363.973662 -224.516097)
			(xy 363.957614 -224.466704) (xy 363.949489 -224.415409) (xy 363.94898 -224.389442) (xy 363.670088 -224.389442)
			(xy 363.669546 -224.417428) (xy 363.660089 -224.472596) (xy 363.651292 -224.49917) (xy 363.643672 -224.521268)
			(xy 363.84738 -224.874074) (xy 363.87024 -224.878392) (xy 363.895167 -224.883535) (xy 363.943153 -224.900502)
			(xy 363.987972 -224.924622) (xy 364.028566 -224.955325) (xy 364.063975 -224.991886) (xy 364.093362 -225.033442)
			(xy 364.116035 -225.07901) (xy 364.131456 -225.127515) (xy 364.139262 -225.17781) (xy 364.139734 -225.203258)
			(xy 364.139225 -225.229225) (xy 364.1311 -225.28052) (xy 364.115052 -225.329913) (xy 364.091474 -225.376187)
			(xy 364.060948 -225.418203) (xy 364.024225 -225.454926) (xy 363.982209 -225.485452) (xy 363.935935 -225.50903)
			(xy 363.886542 -225.525078) (xy 363.835247 -225.533203) (xy 363.783313 -225.533203) (xy 363.732018 -225.525078)
			(xy 363.682625 -225.50903) (xy 363.636351 -225.485452) (xy 363.594335 -225.454926) (xy 363.557612 -225.418203)
			(xy 363.527086 -225.376187) (xy 363.503508 -225.329913) (xy 363.48746 -225.28052) (xy 363.479335 -225.229225)
			(xy 363.478826 -225.203258) (xy 363.479367 -225.175272) (xy 363.488825 -225.120104) (xy 363.497622 -225.09353)
			(xy 363.505242 -225.071432) (xy 363.301534 -224.718626) (xy 363.278674 -224.714308) (xy 363.253749 -224.709155)
			(xy 363.205763 -224.69219) (xy 363.160944 -224.668072) (xy 363.12035 -224.63737) (xy 363.08494 -224.60081)
			(xy 363.055552 -224.559256) (xy 363.03288 -224.513688) (xy 363.017458 -224.465184) (xy 363.009652 -224.41489)
			(xy 363.00918 -224.389442) (xy 362.730288 -224.389442) (xy 362.729779 -224.415409) (xy 362.721654 -224.466704)
			(xy 362.705606 -224.516097) (xy 362.682028 -224.562371) (xy 362.651502 -224.604387) (xy 362.614779 -224.64111)
			(xy 362.572763 -224.671636) (xy 362.526489 -224.695214) (xy 362.477096 -224.711262) (xy 362.425801 -224.719387)
			(xy 362.373867 -224.719387) (xy 362.322572 -224.711262) (xy 362.273179 -224.695214) (xy 362.226905 -224.671636)
			(xy 362.184889 -224.64111) (xy 362.148166 -224.604387) (xy 362.11764 -224.562371) (xy 362.094062 -224.516097)
			(xy 362.078014 -224.466704) (xy 362.069889 -224.415409) (xy 362.06938 -224.389442) (xy 361.790488 -224.389442)
			(xy 361.789946 -224.417428) (xy 361.780489 -224.472596) (xy 361.771692 -224.49917) (xy 361.764072 -224.521268)
			(xy 361.96778 -224.874074) (xy 361.99064 -224.878392) (xy 362.015567 -224.883535) (xy 362.063553 -224.900502)
			(xy 362.108372 -224.924622) (xy 362.148966 -224.955325) (xy 362.184375 -224.991886) (xy 362.213762 -225.033442)
			(xy 362.236435 -225.07901) (xy 362.251856 -225.127515) (xy 362.259662 -225.17781) (xy 362.260134 -225.203258)
			(xy 362.259625 -225.229225) (xy 362.2515 -225.28052) (xy 362.235452 -225.329913) (xy 362.211874 -225.376187)
			(xy 362.181348 -225.418203) (xy 362.144625 -225.454926) (xy 362.102609 -225.485452) (xy 362.056335 -225.50903)
			(xy 362.006942 -225.525078) (xy 361.955647 -225.533203) (xy 361.903713 -225.533203) (xy 361.852418 -225.525078)
			(xy 361.803025 -225.50903) (xy 361.756751 -225.485452) (xy 361.714735 -225.454926) (xy 361.678012 -225.418203)
			(xy 361.647486 -225.376187) (xy 361.623908 -225.329913) (xy 361.60786 -225.28052) (xy 361.599735 -225.229225)
			(xy 361.599226 -225.203258) (xy 361.599767 -225.175272) (xy 361.609225 -225.120104) (xy 361.618022 -225.09353)
			(xy 361.625642 -225.071432) (xy 361.421934 -224.718626) (xy 361.399074 -224.714308) (xy 361.374149 -224.709155)
			(xy 361.326163 -224.69219) (xy 361.281344 -224.668072) (xy 361.24075 -224.63737) (xy 361.20534 -224.60081)
			(xy 361.175952 -224.559256) (xy 361.15328 -224.513688) (xy 361.137858 -224.465184) (xy 361.130052 -224.41489)
			(xy 361.12958 -224.389442) (xy 360.850688 -224.389442) (xy 360.850179 -224.415409) (xy 360.842054 -224.466704)
			(xy 360.826006 -224.516097) (xy 360.802428 -224.562371) (xy 360.771902 -224.604387) (xy 360.735179 -224.64111)
			(xy 360.693163 -224.671636) (xy 360.646889 -224.695214) (xy 360.597496 -224.711262) (xy 360.546201 -224.719387)
			(xy 360.494267 -224.719387) (xy 360.442972 -224.711262) (xy 360.393579 -224.695214) (xy 360.347305 -224.671636)
			(xy 360.305289 -224.64111) (xy 360.268566 -224.604387) (xy 360.23804 -224.562371) (xy 360.214462 -224.516097)
			(xy 360.198414 -224.466704) (xy 360.190289 -224.415409) (xy 360.18978 -224.389442) (xy 359.910888 -224.389442)
			(xy 359.910346 -224.417428) (xy 359.900889 -224.472596) (xy 359.892092 -224.49917) (xy 359.884472 -224.521268)
			(xy 360.08818 -224.874074) (xy 360.11104 -224.878392) (xy 360.135967 -224.883535) (xy 360.183953 -224.900502)
			(xy 360.228772 -224.924622) (xy 360.269366 -224.955325) (xy 360.304775 -224.991886) (xy 360.334162 -225.033442)
			(xy 360.356835 -225.07901) (xy 360.372256 -225.127515) (xy 360.380062 -225.17781) (xy 360.380534 -225.203258)
			(xy 360.380025 -225.229225) (xy 360.3719 -225.28052) (xy 360.355852 -225.329913) (xy 360.332274 -225.376187)
			(xy 360.301748 -225.418203) (xy 360.265025 -225.454926) (xy 360.223009 -225.485452) (xy 360.176735 -225.50903)
			(xy 360.127342 -225.525078) (xy 360.076047 -225.533203) (xy 360.024113 -225.533203) (xy 359.972818 -225.525078)
			(xy 359.923425 -225.50903) (xy 359.877151 -225.485452) (xy 359.835135 -225.454926) (xy 359.798412 -225.418203)
			(xy 359.767886 -225.376187) (xy 359.744308 -225.329913) (xy 359.72826 -225.28052) (xy 359.720135 -225.229225)
			(xy 359.719626 -225.203258) (xy 359.720167 -225.175272) (xy 359.729625 -225.120104) (xy 359.738422 -225.09353)
			(xy 359.746042 -225.071432) (xy 359.542334 -224.718626) (xy 359.519474 -224.714308) (xy 359.494549 -224.709155)
			(xy 359.446563 -224.69219) (xy 359.401744 -224.668072) (xy 359.36115 -224.63737) (xy 359.32574 -224.60081)
			(xy 359.296352 -224.559256) (xy 359.27368 -224.513688) (xy 359.258258 -224.465184) (xy 359.250452 -224.41489)
			(xy 359.24998 -224.389442) (xy 358.971088 -224.389442) (xy 358.970579 -224.415409) (xy 358.962454 -224.466704)
			(xy 358.946406 -224.516097) (xy 358.922828 -224.562371) (xy 358.892302 -224.604387) (xy 358.855579 -224.64111)
			(xy 358.813563 -224.671636) (xy 358.767289 -224.695214) (xy 358.717896 -224.711262) (xy 358.666601 -224.719387)
			(xy 358.614667 -224.719387) (xy 358.563372 -224.711262) (xy 358.513979 -224.695214) (xy 358.467705 -224.671636)
			(xy 358.425689 -224.64111) (xy 358.388966 -224.604387) (xy 358.35844 -224.562371) (xy 358.334862 -224.516097)
			(xy 358.318814 -224.466704) (xy 358.310689 -224.415409) (xy 358.31018 -224.389442) (xy 358.031288 -224.389442)
			(xy 358.030746 -224.417428) (xy 358.021289 -224.472596) (xy 358.012492 -224.49917) (xy 358.004872 -224.521268)
			(xy 358.20858 -224.874074) (xy 358.23144 -224.878392) (xy 358.256367 -224.883535) (xy 358.304353 -224.900502)
			(xy 358.349172 -224.924622) (xy 358.389766 -224.955325) (xy 358.425175 -224.991886) (xy 358.454562 -225.033442)
			(xy 358.477235 -225.07901) (xy 358.492656 -225.127515) (xy 358.500462 -225.17781) (xy 358.500934 -225.203258)
			(xy 358.500425 -225.229225) (xy 358.780335 -225.229225) (xy 358.780335 -225.177291) (xy 358.78846 -225.125996)
			(xy 358.804508 -225.076603) (xy 358.828086 -225.030329) (xy 358.858612 -224.988313) (xy 358.895335 -224.95159)
			(xy 358.937351 -224.921064) (xy 358.983625 -224.897486) (xy 359.033018 -224.881438) (xy 359.084313 -224.873313)
			(xy 359.136247 -224.873313) (xy 359.187542 -224.881438) (xy 359.236935 -224.897486) (xy 359.283209 -224.921064)
			(xy 359.325225 -224.95159) (xy 359.361948 -224.988313) (xy 359.392474 -225.030329) (xy 359.416052 -225.076603)
			(xy 359.4321 -225.125996) (xy 359.440225 -225.177291) (xy 359.440734 -225.203258) (xy 359.440225 -225.229225)
			(xy 359.4321 -225.28052) (xy 359.416052 -225.329913) (xy 359.392474 -225.376187) (xy 359.361948 -225.418203)
			(xy 359.325225 -225.454926) (xy 359.283209 -225.485452) (xy 359.236935 -225.50903) (xy 359.187542 -225.525078)
			(xy 359.136247 -225.533203) (xy 359.084313 -225.533203) (xy 359.033018 -225.525078) (xy 358.983625 -225.50903)
			(xy 358.937351 -225.485452) (xy 358.895335 -225.454926) (xy 358.858612 -225.418203) (xy 358.828086 -225.376187)
			(xy 358.804508 -225.329913) (xy 358.78846 -225.28052) (xy 358.780335 -225.229225) (xy 358.500425 -225.229225)
			(xy 358.4923 -225.28052) (xy 358.476252 -225.329913) (xy 358.452674 -225.376187) (xy 358.422148 -225.418203)
			(xy 358.385425 -225.454926) (xy 358.343409 -225.485452) (xy 358.297135 -225.50903) (xy 358.247742 -225.525078)
			(xy 358.196447 -225.533203) (xy 358.144513 -225.533203) (xy 358.093218 -225.525078) (xy 358.043825 -225.50903)
			(xy 357.997551 -225.485452) (xy 357.955535 -225.454926) (xy 357.918812 -225.418203) (xy 357.888286 -225.376187)
			(xy 357.864708 -225.329913) (xy 357.84866 -225.28052) (xy 357.840535 -225.229225) (xy 357.840026 -225.203258)
			(xy 357.840567 -225.175272) (xy 357.850025 -225.120104) (xy 357.858822 -225.09353) (xy 357.866442 -225.071432)
			(xy 357.662734 -224.718626) (xy 357.639874 -224.714308) (xy 357.614949 -224.709155) (xy 357.566963 -224.69219)
			(xy 357.522144 -224.668072) (xy 357.48155 -224.63737) (xy 357.44614 -224.60081) (xy 357.416752 -224.559256)
			(xy 357.39408 -224.513688) (xy 357.378658 -224.465184) (xy 357.370852 -224.41489) (xy 357.37038 -224.389442)
			(xy 357.091488 -224.389442) (xy 357.09098 -224.415699) (xy 357.082674 -224.467552) (xy 357.066277 -224.51744)
			(xy 357.042202 -224.56411) (xy 357.011054 -224.606388) (xy 356.992682 -224.625154) (xy 356.986425 -224.631782)
			(xy 356.978673 -224.648263) (xy 356.977201 -224.666417) (xy 356.982196 -224.683932) (xy 356.987348 -224.691448)
			(xy 357.012764 -224.72698) (xy 357.057112 -224.802252) (xy 357.093641 -224.881614) (xy 357.121977 -224.964257)
			(xy 357.141831 -225.049336) (xy 357.153001 -225.135984) (xy 357.154734 -225.179636) (xy 357.154988 -225.187764)
			(xy 357.154988 -225.203258) (xy 357.155471 -225.215672) (xy 357.163415 -225.239194) (xy 357.178479 -225.25893)
			(xy 357.188516 -225.26625) (xy 357.191818 -225.268282) (xy 357.192834 -225.26879) (xy 357.226541 -225.288742)
			(xy 357.290572 -225.333865) (xy 357.350258 -225.384597) (xy 357.405108 -225.440521) (xy 357.454673 -225.501179)
			(xy 357.498547 -225.566073) (xy 357.536368 -225.63467) (xy 357.552498 -225.670364) (xy 357.556502 -225.678509)
			(xy 357.569153 -225.691507) (xy 357.585537 -225.699288) (xy 357.603605 -225.700879) (xy 357.612442 -225.698812)
			(xy 357.634107 -225.693202) (xy 357.678457 -225.687216) (xy 357.700834 -225.686874) (xy 357.726799 -225.687386)
			(xy 357.778088 -225.695515) (xy 357.827474 -225.711567) (xy 357.873741 -225.735147) (xy 357.91575 -225.765674)
			(xy 357.952466 -225.802397) (xy 357.982986 -225.844412) (xy 358.006557 -225.890683) (xy 358.0226 -225.940072)
			(xy 358.030719 -225.991363) (xy 358.031288 -226.017328) (xy 358.030787 -226.043295) (xy 358.310689 -226.043295)
			(xy 358.310689 -225.991361) (xy 358.318814 -225.940066) (xy 358.334862 -225.890673) (xy 358.35844 -225.844399)
			(xy 358.388966 -225.802383) (xy 358.425689 -225.76566) (xy 358.467705 -225.735134) (xy 358.513979 -225.711556)
			(xy 358.563372 -225.695508) (xy 358.614667 -225.687383) (xy 358.666601 -225.687383) (xy 358.717896 -225.695508)
			(xy 358.767289 -225.711556) (xy 358.813563 -225.735134) (xy 358.855579 -225.76566) (xy 358.892302 -225.802383)
			(xy 358.922828 -225.844399) (xy 358.946406 -225.890673) (xy 358.962454 -225.940066) (xy 358.970579 -225.991361)
			(xy 358.971088 -226.017328) (xy 358.970579 -226.043295) (xy 359.250489 -226.043295) (xy 359.250489 -225.991361)
			(xy 359.258614 -225.940066) (xy 359.274662 -225.890673) (xy 359.29824 -225.844399) (xy 359.328766 -225.802383)
			(xy 359.365489 -225.76566) (xy 359.407505 -225.735134) (xy 359.453779 -225.711556) (xy 359.503172 -225.695508)
			(xy 359.554467 -225.687383) (xy 359.606401 -225.687383) (xy 359.657696 -225.695508) (xy 359.707089 -225.711556)
			(xy 359.753363 -225.735134) (xy 359.795379 -225.76566) (xy 359.832102 -225.802383) (xy 359.862628 -225.844399)
			(xy 359.886206 -225.890673) (xy 359.902254 -225.940066) (xy 359.910379 -225.991361) (xy 359.910888 -226.017328)
			(xy 359.910379 -226.043295) (xy 360.190289 -226.043295) (xy 360.190289 -225.991361) (xy 360.198414 -225.940066)
			(xy 360.214462 -225.890673) (xy 360.23804 -225.844399) (xy 360.268566 -225.802383) (xy 360.305289 -225.76566)
			(xy 360.347305 -225.735134) (xy 360.393579 -225.711556) (xy 360.442972 -225.695508) (xy 360.494267 -225.687383)
			(xy 360.546201 -225.687383) (xy 360.597496 -225.695508) (xy 360.646889 -225.711556) (xy 360.693163 -225.735134)
			(xy 360.735179 -225.76566) (xy 360.771902 -225.802383) (xy 360.802428 -225.844399) (xy 360.826006 -225.890673)
			(xy 360.842054 -225.940066) (xy 360.850179 -225.991361) (xy 360.850688 -226.017328) (xy 360.850179 -226.043295)
			(xy 361.130089 -226.043295) (xy 361.130089 -225.991361) (xy 361.138214 -225.940066) (xy 361.154262 -225.890673)
			(xy 361.17784 -225.844399) (xy 361.208366 -225.802383) (xy 361.245089 -225.76566) (xy 361.287105 -225.735134)
			(xy 361.333379 -225.711556) (xy 361.382772 -225.695508) (xy 361.434067 -225.687383) (xy 361.486001 -225.687383)
			(xy 361.537296 -225.695508) (xy 361.586689 -225.711556) (xy 361.632963 -225.735134) (xy 361.674979 -225.76566)
			(xy 361.711702 -225.802383) (xy 361.742228 -225.844399) (xy 361.765806 -225.890673) (xy 361.781854 -225.940066)
			(xy 361.789979 -225.991361) (xy 361.790488 -226.017328) (xy 361.789979 -226.043295) (xy 362.069889 -226.043295)
			(xy 362.069889 -225.991361) (xy 362.078014 -225.940066) (xy 362.094062 -225.890673) (xy 362.11764 -225.844399)
			(xy 362.148166 -225.802383) (xy 362.184889 -225.76566) (xy 362.226905 -225.735134) (xy 362.273179 -225.711556)
			(xy 362.322572 -225.695508) (xy 362.373867 -225.687383) (xy 362.425801 -225.687383) (xy 362.477096 -225.695508)
			(xy 362.526489 -225.711556) (xy 362.572763 -225.735134) (xy 362.614779 -225.76566) (xy 362.651502 -225.802383)
			(xy 362.682028 -225.844399) (xy 362.705606 -225.890673) (xy 362.721654 -225.940066) (xy 362.729779 -225.991361)
			(xy 362.730288 -226.017328) (xy 362.729779 -226.043295) (xy 363.009689 -226.043295) (xy 363.009689 -225.991361)
			(xy 363.017814 -225.940066) (xy 363.033862 -225.890673) (xy 363.05744 -225.844399) (xy 363.087966 -225.802383)
			(xy 363.124689 -225.76566) (xy 363.166705 -225.735134) (xy 363.212979 -225.711556) (xy 363.262372 -225.695508)
			(xy 363.313667 -225.687383) (xy 363.365601 -225.687383) (xy 363.416896 -225.695508) (xy 363.466289 -225.711556)
			(xy 363.512563 -225.735134) (xy 363.554579 -225.76566) (xy 363.591302 -225.802383) (xy 363.621828 -225.844399)
			(xy 363.645406 -225.890673) (xy 363.661454 -225.940066) (xy 363.669579 -225.991361) (xy 363.670088 -226.017328)
			(xy 363.669579 -226.043295) (xy 363.949489 -226.043295) (xy 363.949489 -225.991361) (xy 363.957614 -225.940066)
			(xy 363.973662 -225.890673) (xy 363.99724 -225.844399) (xy 364.027766 -225.802383) (xy 364.064489 -225.76566)
			(xy 364.106505 -225.735134) (xy 364.152779 -225.711556) (xy 364.202172 -225.695508) (xy 364.253467 -225.687383)
			(xy 364.305401 -225.687383) (xy 364.356696 -225.695508) (xy 364.406089 -225.711556) (xy 364.452363 -225.735134)
			(xy 364.494379 -225.76566) (xy 364.531102 -225.802383) (xy 364.561628 -225.844399) (xy 364.585206 -225.890673)
			(xy 364.601254 -225.940066) (xy 364.609379 -225.991361) (xy 364.609888 -226.017328) (xy 364.609379 -226.043295)
			(xy 364.889289 -226.043295) (xy 364.889289 -225.991361) (xy 364.897414 -225.940066) (xy 364.913462 -225.890673)
			(xy 364.93704 -225.844399) (xy 364.967566 -225.802383) (xy 365.004289 -225.76566) (xy 365.046305 -225.735134)
			(xy 365.092579 -225.711556) (xy 365.141972 -225.695508) (xy 365.193267 -225.687383) (xy 365.245201 -225.687383)
			(xy 365.296496 -225.695508) (xy 365.345889 -225.711556) (xy 365.392163 -225.735134) (xy 365.434179 -225.76566)
			(xy 365.470902 -225.802383) (xy 365.501428 -225.844399) (xy 365.525006 -225.890673) (xy 365.541054 -225.940066)
			(xy 365.549179 -225.991361) (xy 365.549688 -226.017328) (xy 365.549179 -226.043295) (xy 365.829089 -226.043295)
			(xy 365.829089 -225.991361) (xy 365.837214 -225.940066) (xy 365.853262 -225.890673) (xy 365.87684 -225.844399)
			(xy 365.907366 -225.802383) (xy 365.944089 -225.76566) (xy 365.986105 -225.735134) (xy 366.032379 -225.711556)
			(xy 366.081772 -225.695508) (xy 366.133067 -225.687383) (xy 366.185001 -225.687383) (xy 366.236296 -225.695508)
			(xy 366.285689 -225.711556) (xy 366.331963 -225.735134) (xy 366.373979 -225.76566) (xy 366.410702 -225.802383)
			(xy 366.441228 -225.844399) (xy 366.464806 -225.890673) (xy 366.480854 -225.940066) (xy 366.488979 -225.991361)
			(xy 366.489488 -226.017328) (xy 366.488979 -226.043295) (xy 366.768889 -226.043295) (xy 366.768889 -225.991361)
			(xy 366.777014 -225.940066) (xy 366.793062 -225.890673) (xy 366.81664 -225.844399) (xy 366.847166 -225.802383)
			(xy 366.883889 -225.76566) (xy 366.925905 -225.735134) (xy 366.972179 -225.711556) (xy 367.021572 -225.695508)
			(xy 367.072867 -225.687383) (xy 367.124801 -225.687383) (xy 367.176096 -225.695508) (xy 367.225489 -225.711556)
			(xy 367.271763 -225.735134) (xy 367.313779 -225.76566) (xy 367.350502 -225.802383) (xy 367.381028 -225.844399)
			(xy 367.404606 -225.890673) (xy 367.420654 -225.940066) (xy 367.428779 -225.991361) (xy 367.429288 -226.017328)
			(xy 367.428779 -226.043295) (xy 367.708689 -226.043295) (xy 367.708689 -225.991361) (xy 367.716814 -225.940066)
			(xy 367.732862 -225.890673) (xy 367.75644 -225.844399) (xy 367.786966 -225.802383) (xy 367.823689 -225.76566)
			(xy 367.865705 -225.735134) (xy 367.911979 -225.711556) (xy 367.961372 -225.695508) (xy 368.012667 -225.687383)
			(xy 368.064601 -225.687383) (xy 368.115896 -225.695508) (xy 368.165289 -225.711556) (xy 368.211563 -225.735134)
			(xy 368.253579 -225.76566) (xy 368.290302 -225.802383) (xy 368.320828 -225.844399) (xy 368.344406 -225.890673)
			(xy 368.360454 -225.940066) (xy 368.368579 -225.991361) (xy 368.369088 -226.017328) (xy 368.368579 -226.043295)
			(xy 368.648489 -226.043295) (xy 368.648489 -225.991361) (xy 368.656614 -225.940066) (xy 368.672662 -225.890673)
			(xy 368.69624 -225.844399) (xy 368.726766 -225.802383) (xy 368.763489 -225.76566) (xy 368.805505 -225.735134)
			(xy 368.851779 -225.711556) (xy 368.901172 -225.695508) (xy 368.952467 -225.687383) (xy 369.004401 -225.687383)
			(xy 369.055696 -225.695508) (xy 369.105089 -225.711556) (xy 369.151363 -225.735134) (xy 369.193379 -225.76566)
			(xy 369.230102 -225.802383) (xy 369.260628 -225.844399) (xy 369.284206 -225.890673) (xy 369.300254 -225.940066)
			(xy 369.308379 -225.991361) (xy 369.308888 -226.017328) (xy 369.308379 -226.043295) (xy 369.588289 -226.043295)
			(xy 369.588289 -225.991361) (xy 369.596414 -225.940066) (xy 369.612462 -225.890673) (xy 369.63604 -225.844399)
			(xy 369.666566 -225.802383) (xy 369.703289 -225.76566) (xy 369.745305 -225.735134) (xy 369.791579 -225.711556)
			(xy 369.840972 -225.695508) (xy 369.892267 -225.687383) (xy 369.944201 -225.687383) (xy 369.995496 -225.695508)
			(xy 370.044889 -225.711556) (xy 370.091163 -225.735134) (xy 370.133179 -225.76566) (xy 370.169902 -225.802383)
			(xy 370.200428 -225.844399) (xy 370.224006 -225.890673) (xy 370.240054 -225.940066) (xy 370.248179 -225.991361)
			(xy 370.248688 -226.017328) (xy 370.248179 -226.043295) (xy 370.528089 -226.043295) (xy 370.528089 -225.991361)
			(xy 370.536214 -225.940066) (xy 370.552262 -225.890673) (xy 370.57584 -225.844399) (xy 370.606366 -225.802383)
			(xy 370.643089 -225.76566) (xy 370.685105 -225.735134) (xy 370.731379 -225.711556) (xy 370.780772 -225.695508)
			(xy 370.832067 -225.687383) (xy 370.884001 -225.687383) (xy 370.935296 -225.695508) (xy 370.984689 -225.711556)
			(xy 371.030963 -225.735134) (xy 371.072979 -225.76566) (xy 371.109702 -225.802383) (xy 371.140228 -225.844399)
			(xy 371.163806 -225.890673) (xy 371.179854 -225.940066) (xy 371.187979 -225.991361) (xy 371.188488 -226.017328)
			(xy 371.187979 -226.043295) (xy 371.467889 -226.043295) (xy 371.467889 -225.991361) (xy 371.476014 -225.940066)
			(xy 371.492062 -225.890673) (xy 371.51564 -225.844399) (xy 371.546166 -225.802383) (xy 371.582889 -225.76566)
			(xy 371.624905 -225.735134) (xy 371.671179 -225.711556) (xy 371.720572 -225.695508) (xy 371.771867 -225.687383)
			(xy 371.823801 -225.687383) (xy 371.875096 -225.695508) (xy 371.924489 -225.711556) (xy 371.970763 -225.735134)
			(xy 372.012779 -225.76566) (xy 372.049502 -225.802383) (xy 372.080028 -225.844399) (xy 372.103606 -225.890673)
			(xy 372.119654 -225.940066) (xy 372.127779 -225.991361) (xy 372.128288 -226.017328) (xy 372.127779 -226.043295)
			(xy 372.407689 -226.043295) (xy 372.407689 -225.991361) (xy 372.415814 -225.940066) (xy 372.431862 -225.890673)
			(xy 372.45544 -225.844399) (xy 372.485966 -225.802383) (xy 372.522689 -225.76566) (xy 372.564705 -225.735134)
			(xy 372.610979 -225.711556) (xy 372.660372 -225.695508) (xy 372.711667 -225.687383) (xy 372.763601 -225.687383)
			(xy 372.814896 -225.695508) (xy 372.864289 -225.711556) (xy 372.910563 -225.735134) (xy 372.952579 -225.76566)
			(xy 372.989302 -225.802383) (xy 373.019828 -225.844399) (xy 373.043406 -225.890673) (xy 373.059454 -225.940066)
			(xy 373.067579 -225.991361) (xy 373.068088 -226.017328) (xy 373.067579 -226.043295) (xy 373.347489 -226.043295)
			(xy 373.347489 -225.991361) (xy 373.355614 -225.940066) (xy 373.371662 -225.890673) (xy 373.39524 -225.844399)
			(xy 373.425766 -225.802383) (xy 373.462489 -225.76566) (xy 373.504505 -225.735134) (xy 373.550779 -225.711556)
			(xy 373.600172 -225.695508) (xy 373.651467 -225.687383) (xy 373.703401 -225.687383) (xy 373.754696 -225.695508)
			(xy 373.804089 -225.711556) (xy 373.850363 -225.735134) (xy 373.892379 -225.76566) (xy 373.929102 -225.802383)
			(xy 373.959628 -225.844399) (xy 373.983206 -225.890673) (xy 373.999254 -225.940066) (xy 374.007379 -225.991361)
			(xy 374.007888 -226.017328) (xy 374.007379 -226.043295) (xy 374.287289 -226.043295) (xy 374.287289 -225.991361)
			(xy 374.295414 -225.940066) (xy 374.311462 -225.890673) (xy 374.33504 -225.844399) (xy 374.365566 -225.802383)
			(xy 374.402289 -225.76566) (xy 374.444305 -225.735134) (xy 374.490579 -225.711556) (xy 374.539972 -225.695508)
			(xy 374.591267 -225.687383) (xy 374.643201 -225.687383) (xy 374.694496 -225.695508) (xy 374.743889 -225.711556)
			(xy 374.790163 -225.735134) (xy 374.832179 -225.76566) (xy 374.868902 -225.802383) (xy 374.899428 -225.844399)
			(xy 374.923006 -225.890673) (xy 374.939054 -225.940066) (xy 374.947179 -225.991361) (xy 374.947688 -226.017328)
			(xy 374.947179 -226.043295) (xy 375.227089 -226.043295) (xy 375.227089 -225.991361) (xy 375.235214 -225.940066)
			(xy 375.251262 -225.890673) (xy 375.27484 -225.844399) (xy 375.305366 -225.802383) (xy 375.342089 -225.76566)
			(xy 375.384105 -225.735134) (xy 375.430379 -225.711556) (xy 375.479772 -225.695508) (xy 375.531067 -225.687383)
			(xy 375.583001 -225.687383) (xy 375.634296 -225.695508) (xy 375.683689 -225.711556) (xy 375.729963 -225.735134)
			(xy 375.771979 -225.76566) (xy 375.808702 -225.802383) (xy 375.839228 -225.844399) (xy 375.862806 -225.890673)
			(xy 375.878854 -225.940066) (xy 375.886979 -225.991361) (xy 375.887488 -226.017328) (xy 375.886979 -226.043295)
			(xy 375.878854 -226.09459) (xy 375.862806 -226.143983) (xy 375.839228 -226.190257) (xy 375.808702 -226.232273)
			(xy 375.771979 -226.268996) (xy 375.729963 -226.299522) (xy 375.683689 -226.3231) (xy 375.634296 -226.339148)
			(xy 375.583001 -226.347273) (xy 375.531067 -226.347273) (xy 375.479772 -226.339148) (xy 375.430379 -226.3231)
			(xy 375.384105 -226.299522) (xy 375.342089 -226.268996) (xy 375.305366 -226.232273) (xy 375.27484 -226.190257)
			(xy 375.251262 -226.143983) (xy 375.235214 -226.09459) (xy 375.227089 -226.043295) (xy 374.947179 -226.043295)
			(xy 374.939054 -226.09459) (xy 374.923006 -226.143983) (xy 374.899428 -226.190257) (xy 374.868902 -226.232273)
			(xy 374.832179 -226.268996) (xy 374.790163 -226.299522) (xy 374.743889 -226.3231) (xy 374.694496 -226.339148)
			(xy 374.643201 -226.347273) (xy 374.591267 -226.347273) (xy 374.539972 -226.339148) (xy 374.490579 -226.3231)
			(xy 374.444305 -226.299522) (xy 374.402289 -226.268996) (xy 374.365566 -226.232273) (xy 374.33504 -226.190257)
			(xy 374.311462 -226.143983) (xy 374.295414 -226.09459) (xy 374.287289 -226.043295) (xy 374.007379 -226.043295)
			(xy 373.999254 -226.09459) (xy 373.983206 -226.143983) (xy 373.959628 -226.190257) (xy 373.929102 -226.232273)
			(xy 373.892379 -226.268996) (xy 373.850363 -226.299522) (xy 373.804089 -226.3231) (xy 373.754696 -226.339148)
			(xy 373.703401 -226.347273) (xy 373.651467 -226.347273) (xy 373.600172 -226.339148) (xy 373.550779 -226.3231)
			(xy 373.504505 -226.299522) (xy 373.462489 -226.268996) (xy 373.425766 -226.232273) (xy 373.39524 -226.190257)
			(xy 373.371662 -226.143983) (xy 373.355614 -226.09459) (xy 373.347489 -226.043295) (xy 373.067579 -226.043295)
			(xy 373.059454 -226.09459) (xy 373.043406 -226.143983) (xy 373.019828 -226.190257) (xy 372.989302 -226.232273)
			(xy 372.952579 -226.268996) (xy 372.910563 -226.299522) (xy 372.864289 -226.3231) (xy 372.814896 -226.339148)
			(xy 372.763601 -226.347273) (xy 372.711667 -226.347273) (xy 372.660372 -226.339148) (xy 372.610979 -226.3231)
			(xy 372.564705 -226.299522) (xy 372.522689 -226.268996) (xy 372.485966 -226.232273) (xy 372.45544 -226.190257)
			(xy 372.431862 -226.143983) (xy 372.415814 -226.09459) (xy 372.407689 -226.043295) (xy 372.127779 -226.043295)
			(xy 372.119654 -226.09459) (xy 372.103606 -226.143983) (xy 372.080028 -226.190257) (xy 372.049502 -226.232273)
			(xy 372.012779 -226.268996) (xy 371.970763 -226.299522) (xy 371.924489 -226.3231) (xy 371.875096 -226.339148)
			(xy 371.823801 -226.347273) (xy 371.771867 -226.347273) (xy 371.720572 -226.339148) (xy 371.671179 -226.3231)
			(xy 371.624905 -226.299522) (xy 371.582889 -226.268996) (xy 371.546166 -226.232273) (xy 371.51564 -226.190257)
			(xy 371.492062 -226.143983) (xy 371.476014 -226.09459) (xy 371.467889 -226.043295) (xy 371.187979 -226.043295)
			(xy 371.179854 -226.09459) (xy 371.163806 -226.143983) (xy 371.140228 -226.190257) (xy 371.109702 -226.232273)
			(xy 371.072979 -226.268996) (xy 371.030963 -226.299522) (xy 370.984689 -226.3231) (xy 370.935296 -226.339148)
			(xy 370.884001 -226.347273) (xy 370.832067 -226.347273) (xy 370.780772 -226.339148) (xy 370.731379 -226.3231)
			(xy 370.685105 -226.299522) (xy 370.643089 -226.268996) (xy 370.606366 -226.232273) (xy 370.57584 -226.190257)
			(xy 370.552262 -226.143983) (xy 370.536214 -226.09459) (xy 370.528089 -226.043295) (xy 370.248179 -226.043295)
			(xy 370.240054 -226.09459) (xy 370.224006 -226.143983) (xy 370.200428 -226.190257) (xy 370.169902 -226.232273)
			(xy 370.133179 -226.268996) (xy 370.091163 -226.299522) (xy 370.044889 -226.3231) (xy 369.995496 -226.339148)
			(xy 369.944201 -226.347273) (xy 369.892267 -226.347273) (xy 369.840972 -226.339148) (xy 369.791579 -226.3231)
			(xy 369.745305 -226.299522) (xy 369.703289 -226.268996) (xy 369.666566 -226.232273) (xy 369.63604 -226.190257)
			(xy 369.612462 -226.143983) (xy 369.596414 -226.09459) (xy 369.588289 -226.043295) (xy 369.308379 -226.043295)
			(xy 369.300254 -226.09459) (xy 369.284206 -226.143983) (xy 369.260628 -226.190257) (xy 369.230102 -226.232273)
			(xy 369.193379 -226.268996) (xy 369.151363 -226.299522) (xy 369.105089 -226.3231) (xy 369.055696 -226.339148)
			(xy 369.004401 -226.347273) (xy 368.952467 -226.347273) (xy 368.901172 -226.339148) (xy 368.851779 -226.3231)
			(xy 368.805505 -226.299522) (xy 368.763489 -226.268996) (xy 368.726766 -226.232273) (xy 368.69624 -226.190257)
			(xy 368.672662 -226.143983) (xy 368.656614 -226.09459) (xy 368.648489 -226.043295) (xy 368.368579 -226.043295)
			(xy 368.360454 -226.09459) (xy 368.344406 -226.143983) (xy 368.320828 -226.190257) (xy 368.290302 -226.232273)
			(xy 368.253579 -226.268996) (xy 368.211563 -226.299522) (xy 368.165289 -226.3231) (xy 368.115896 -226.339148)
			(xy 368.064601 -226.347273) (xy 368.012667 -226.347273) (xy 367.961372 -226.339148) (xy 367.911979 -226.3231)
			(xy 367.865705 -226.299522) (xy 367.823689 -226.268996) (xy 367.786966 -226.232273) (xy 367.75644 -226.190257)
			(xy 367.732862 -226.143983) (xy 367.716814 -226.09459) (xy 367.708689 -226.043295) (xy 367.428779 -226.043295)
			(xy 367.420654 -226.09459) (xy 367.404606 -226.143983) (xy 367.381028 -226.190257) (xy 367.350502 -226.232273)
			(xy 367.313779 -226.268996) (xy 367.271763 -226.299522) (xy 367.225489 -226.3231) (xy 367.176096 -226.339148)
			(xy 367.124801 -226.347273) (xy 367.072867 -226.347273) (xy 367.021572 -226.339148) (xy 366.972179 -226.3231)
			(xy 366.925905 -226.299522) (xy 366.883889 -226.268996) (xy 366.847166 -226.232273) (xy 366.81664 -226.190257)
			(xy 366.793062 -226.143983) (xy 366.777014 -226.09459) (xy 366.768889 -226.043295) (xy 366.488979 -226.043295)
			(xy 366.480854 -226.09459) (xy 366.464806 -226.143983) (xy 366.441228 -226.190257) (xy 366.410702 -226.232273)
			(xy 366.373979 -226.268996) (xy 366.331963 -226.299522) (xy 366.285689 -226.3231) (xy 366.236296 -226.339148)
			(xy 366.185001 -226.347273) (xy 366.133067 -226.347273) (xy 366.081772 -226.339148) (xy 366.032379 -226.3231)
			(xy 365.986105 -226.299522) (xy 365.944089 -226.268996) (xy 365.907366 -226.232273) (xy 365.87684 -226.190257)
			(xy 365.853262 -226.143983) (xy 365.837214 -226.09459) (xy 365.829089 -226.043295) (xy 365.549179 -226.043295)
			(xy 365.541054 -226.09459) (xy 365.525006 -226.143983) (xy 365.501428 -226.190257) (xy 365.470902 -226.232273)
			(xy 365.434179 -226.268996) (xy 365.392163 -226.299522) (xy 365.345889 -226.3231) (xy 365.296496 -226.339148)
			(xy 365.245201 -226.347273) (xy 365.193267 -226.347273) (xy 365.141972 -226.339148) (xy 365.092579 -226.3231)
			(xy 365.046305 -226.299522) (xy 365.004289 -226.268996) (xy 364.967566 -226.232273) (xy 364.93704 -226.190257)
			(xy 364.913462 -226.143983) (xy 364.897414 -226.09459) (xy 364.889289 -226.043295) (xy 364.609379 -226.043295)
			(xy 364.601254 -226.09459) (xy 364.585206 -226.143983) (xy 364.561628 -226.190257) (xy 364.531102 -226.232273)
			(xy 364.494379 -226.268996) (xy 364.452363 -226.299522) (xy 364.406089 -226.3231) (xy 364.356696 -226.339148)
			(xy 364.305401 -226.347273) (xy 364.253467 -226.347273) (xy 364.202172 -226.339148) (xy 364.152779 -226.3231)
			(xy 364.106505 -226.299522) (xy 364.064489 -226.268996) (xy 364.027766 -226.232273) (xy 363.99724 -226.190257)
			(xy 363.973662 -226.143983) (xy 363.957614 -226.09459) (xy 363.949489 -226.043295) (xy 363.669579 -226.043295)
			(xy 363.661454 -226.09459) (xy 363.645406 -226.143983) (xy 363.621828 -226.190257) (xy 363.591302 -226.232273)
			(xy 363.554579 -226.268996) (xy 363.512563 -226.299522) (xy 363.466289 -226.3231) (xy 363.416896 -226.339148)
			(xy 363.365601 -226.347273) (xy 363.313667 -226.347273) (xy 363.262372 -226.339148) (xy 363.212979 -226.3231)
			(xy 363.166705 -226.299522) (xy 363.124689 -226.268996) (xy 363.087966 -226.232273) (xy 363.05744 -226.190257)
			(xy 363.033862 -226.143983) (xy 363.017814 -226.09459) (xy 363.009689 -226.043295) (xy 362.729779 -226.043295)
			(xy 362.721654 -226.09459) (xy 362.705606 -226.143983) (xy 362.682028 -226.190257) (xy 362.651502 -226.232273)
			(xy 362.614779 -226.268996) (xy 362.572763 -226.299522) (xy 362.526489 -226.3231) (xy 362.477096 -226.339148)
			(xy 362.425801 -226.347273) (xy 362.373867 -226.347273) (xy 362.322572 -226.339148) (xy 362.273179 -226.3231)
			(xy 362.226905 -226.299522) (xy 362.184889 -226.268996) (xy 362.148166 -226.232273) (xy 362.11764 -226.190257)
			(xy 362.094062 -226.143983) (xy 362.078014 -226.09459) (xy 362.069889 -226.043295) (xy 361.789979 -226.043295)
			(xy 361.781854 -226.09459) (xy 361.765806 -226.143983) (xy 361.742228 -226.190257) (xy 361.711702 -226.232273)
			(xy 361.674979 -226.268996) (xy 361.632963 -226.299522) (xy 361.586689 -226.3231) (xy 361.537296 -226.339148)
			(xy 361.486001 -226.347273) (xy 361.434067 -226.347273) (xy 361.382772 -226.339148) (xy 361.333379 -226.3231)
			(xy 361.287105 -226.299522) (xy 361.245089 -226.268996) (xy 361.208366 -226.232273) (xy 361.17784 -226.190257)
			(xy 361.154262 -226.143983) (xy 361.138214 -226.09459) (xy 361.130089 -226.043295) (xy 360.850179 -226.043295)
			(xy 360.842054 -226.09459) (xy 360.826006 -226.143983) (xy 360.802428 -226.190257) (xy 360.771902 -226.232273)
			(xy 360.735179 -226.268996) (xy 360.693163 -226.299522) (xy 360.646889 -226.3231) (xy 360.597496 -226.339148)
			(xy 360.546201 -226.347273) (xy 360.494267 -226.347273) (xy 360.442972 -226.339148) (xy 360.393579 -226.3231)
			(xy 360.347305 -226.299522) (xy 360.305289 -226.268996) (xy 360.268566 -226.232273) (xy 360.23804 -226.190257)
			(xy 360.214462 -226.143983) (xy 360.198414 -226.09459) (xy 360.190289 -226.043295) (xy 359.910379 -226.043295)
			(xy 359.902254 -226.09459) (xy 359.886206 -226.143983) (xy 359.862628 -226.190257) (xy 359.832102 -226.232273)
			(xy 359.795379 -226.268996) (xy 359.753363 -226.299522) (xy 359.707089 -226.3231) (xy 359.657696 -226.339148)
			(xy 359.606401 -226.347273) (xy 359.554467 -226.347273) (xy 359.503172 -226.339148) (xy 359.453779 -226.3231)
			(xy 359.407505 -226.299522) (xy 359.365489 -226.268996) (xy 359.328766 -226.232273) (xy 359.29824 -226.190257)
			(xy 359.274662 -226.143983) (xy 359.258614 -226.09459) (xy 359.250489 -226.043295) (xy 358.970579 -226.043295)
			(xy 358.962454 -226.09459) (xy 358.946406 -226.143983) (xy 358.922828 -226.190257) (xy 358.892302 -226.232273)
			(xy 358.855579 -226.268996) (xy 358.813563 -226.299522) (xy 358.767289 -226.3231) (xy 358.717896 -226.339148)
			(xy 358.666601 -226.347273) (xy 358.614667 -226.347273) (xy 358.563372 -226.339148) (xy 358.513979 -226.3231)
			(xy 358.467705 -226.299522) (xy 358.425689 -226.268996) (xy 358.388966 -226.232273) (xy 358.35844 -226.190257)
			(xy 358.334862 -226.143983) (xy 358.318814 -226.09459) (xy 358.310689 -226.043295) (xy 358.030787 -226.043295)
			(xy 358.030781 -226.043585) (xy 358.022477 -226.095439) (xy 358.006082 -226.145329) (xy 357.982008 -226.192)
			(xy 357.95086 -226.23428) (xy 357.932482 -226.25304) (xy 357.92624 -226.259668) (xy 357.918517 -226.276141)
			(xy 357.917069 -226.294277) (xy 357.922082 -226.311766) (xy 357.927148 -226.319334) (xy 357.954844 -226.358144)
			(xy 358.002453 -226.440757) (xy 358.022144 -226.48418) (xy 358.026133 -226.492384) (xy 358.038822 -226.505471)
			(xy 358.055303 -226.513259) (xy 358.073471 -226.514753) (xy 358.082342 -226.512628) (xy 358.104007 -226.507018)
			(xy 358.148357 -226.501032) (xy 358.170734 -226.50069) (xy 358.196696 -226.501202) (xy 358.24798 -226.509329)
			(xy 358.297362 -226.525379) (xy 358.343625 -226.548955) (xy 358.38563 -226.579478) (xy 358.422344 -226.616196)
			(xy 358.452863 -226.658204) (xy 358.476434 -226.70447) (xy 358.492479 -226.753853) (xy 358.500601 -226.805138)
			(xy 358.500601 -226.857062) (xy 358.500593 -226.857111) (xy 358.780335 -226.857111) (xy 358.780335 -226.805177)
			(xy 358.78846 -226.753882) (xy 358.804508 -226.704489) (xy 358.828086 -226.658215) (xy 358.858612 -226.616199)
			(xy 358.895335 -226.579476) (xy 358.937351 -226.54895) (xy 358.983625 -226.525372) (xy 359.033018 -226.509324)
			(xy 359.084313 -226.501199) (xy 359.136247 -226.501199) (xy 359.187542 -226.509324) (xy 359.236935 -226.525372)
			(xy 359.283209 -226.54895) (xy 359.325225 -226.579476) (xy 359.361948 -226.616199) (xy 359.392474 -226.658215)
			(xy 359.416052 -226.704489) (xy 359.4321 -226.753882) (xy 359.440225 -226.805177) (xy 359.440734 -226.831144)
			(xy 359.440225 -226.857111) (xy 359.720389 -226.857111) (xy 359.720389 -226.805177) (xy 359.728514 -226.753882)
			(xy 359.744562 -226.704489) (xy 359.76814 -226.658215) (xy 359.798666 -226.616199) (xy 359.835389 -226.579476)
			(xy 359.877405 -226.54895) (xy 359.923679 -226.525372) (xy 359.973072 -226.509324) (xy 360.024367 -226.501199)
			(xy 360.076301 -226.501199) (xy 360.127596 -226.509324) (xy 360.176989 -226.525372) (xy 360.223263 -226.54895)
			(xy 360.265279 -226.579476) (xy 360.302002 -226.616199) (xy 360.332528 -226.658215) (xy 360.356106 -226.704489)
			(xy 360.372154 -226.753882) (xy 360.380279 -226.805177) (xy 360.380788 -226.831144) (xy 360.380279 -226.857111)
			(xy 360.659935 -226.857111) (xy 360.659935 -226.805177) (xy 360.66806 -226.753882) (xy 360.684108 -226.704489)
			(xy 360.707686 -226.658215) (xy 360.738212 -226.616199) (xy 360.774935 -226.579476) (xy 360.816951 -226.54895)
			(xy 360.863225 -226.525372) (xy 360.912618 -226.509324) (xy 360.963913 -226.501199) (xy 361.015847 -226.501199)
			(xy 361.067142 -226.509324) (xy 361.116535 -226.525372) (xy 361.162809 -226.54895) (xy 361.204825 -226.579476)
			(xy 361.241548 -226.616199) (xy 361.272074 -226.658215) (xy 361.295652 -226.704489) (xy 361.3117 -226.753882)
			(xy 361.319825 -226.805177) (xy 361.320334 -226.831144) (xy 361.319825 -226.857111) (xy 361.599989 -226.857111)
			(xy 361.599989 -226.805177) (xy 361.608114 -226.753882) (xy 361.624162 -226.704489) (xy 361.64774 -226.658215)
			(xy 361.678266 -226.616199) (xy 361.714989 -226.579476) (xy 361.757005 -226.54895) (xy 361.803279 -226.525372)
			(xy 361.852672 -226.509324) (xy 361.903967 -226.501199) (xy 361.955901 -226.501199) (xy 362.007196 -226.509324)
			(xy 362.056589 -226.525372) (xy 362.102863 -226.54895) (xy 362.144879 -226.579476) (xy 362.181602 -226.616199)
			(xy 362.212128 -226.658215) (xy 362.235706 -226.704489) (xy 362.251754 -226.753882) (xy 362.259879 -226.805177)
			(xy 362.260388 -226.831144) (xy 362.259879 -226.857111) (xy 362.539789 -226.857111) (xy 362.539789 -226.805177)
			(xy 362.547914 -226.753882) (xy 362.563962 -226.704489) (xy 362.58754 -226.658215) (xy 362.618066 -226.616199)
			(xy 362.654789 -226.579476) (xy 362.696805 -226.54895) (xy 362.743079 -226.525372) (xy 362.792472 -226.509324)
			(xy 362.843767 -226.501199) (xy 362.895701 -226.501199) (xy 362.946996 -226.509324) (xy 362.996389 -226.525372)
			(xy 363.042663 -226.54895) (xy 363.084679 -226.579476) (xy 363.121402 -226.616199) (xy 363.151928 -226.658215)
			(xy 363.175506 -226.704489) (xy 363.191554 -226.753882) (xy 363.199679 -226.805177) (xy 363.200188 -226.831144)
			(xy 363.199679 -226.857111) (xy 363.479589 -226.857111) (xy 363.479589 -226.805177) (xy 363.487714 -226.753882)
			(xy 363.503762 -226.704489) (xy 363.52734 -226.658215) (xy 363.557866 -226.616199) (xy 363.594589 -226.579476)
			(xy 363.636605 -226.54895) (xy 363.682879 -226.525372) (xy 363.732272 -226.509324) (xy 363.783567 -226.501199)
			(xy 363.835501 -226.501199) (xy 363.886796 -226.509324) (xy 363.936189 -226.525372) (xy 363.982463 -226.54895)
			(xy 364.024479 -226.579476) (xy 364.061202 -226.616199) (xy 364.091728 -226.658215) (xy 364.115306 -226.704489)
			(xy 364.131354 -226.753882) (xy 364.139479 -226.805177) (xy 364.139988 -226.831144) (xy 364.139479 -226.857111)
			(xy 364.419135 -226.857111) (xy 364.419135 -226.805177) (xy 364.42726 -226.753882) (xy 364.443308 -226.704489)
			(xy 364.466886 -226.658215) (xy 364.497412 -226.616199) (xy 364.534135 -226.579476) (xy 364.576151 -226.54895)
			(xy 364.622425 -226.525372) (xy 364.671818 -226.509324) (xy 364.723113 -226.501199) (xy 364.775047 -226.501199)
			(xy 364.826342 -226.509324) (xy 364.875735 -226.525372) (xy 364.922009 -226.54895) (xy 364.964025 -226.579476)
			(xy 365.000748 -226.616199) (xy 365.031274 -226.658215) (xy 365.054852 -226.704489) (xy 365.0709 -226.753882)
			(xy 365.079025 -226.805177) (xy 365.079534 -226.831144) (xy 365.079025 -226.857111) (xy 365.359189 -226.857111)
			(xy 365.359189 -226.805177) (xy 365.367314 -226.753882) (xy 365.383362 -226.704489) (xy 365.40694 -226.658215)
			(xy 365.437466 -226.616199) (xy 365.474189 -226.579476) (xy 365.516205 -226.54895) (xy 365.562479 -226.525372)
			(xy 365.611872 -226.509324) (xy 365.663167 -226.501199) (xy 365.715101 -226.501199) (xy 365.766396 -226.509324)
			(xy 365.815789 -226.525372) (xy 365.862063 -226.54895) (xy 365.904079 -226.579476) (xy 365.940802 -226.616199)
			(xy 365.971328 -226.658215) (xy 365.994906 -226.704489) (xy 366.010954 -226.753882) (xy 366.019079 -226.805177)
			(xy 366.019588 -226.831144) (xy 366.019079 -226.857111) (xy 366.298735 -226.857111) (xy 366.298735 -226.805177)
			(xy 366.30686 -226.753882) (xy 366.322908 -226.704489) (xy 366.346486 -226.658215) (xy 366.377012 -226.616199)
			(xy 366.413735 -226.579476) (xy 366.455751 -226.54895) (xy 366.502025 -226.525372) (xy 366.551418 -226.509324)
			(xy 366.602713 -226.501199) (xy 366.654647 -226.501199) (xy 366.705942 -226.509324) (xy 366.755335 -226.525372)
			(xy 366.801609 -226.54895) (xy 366.843625 -226.579476) (xy 366.880348 -226.616199) (xy 366.910874 -226.658215)
			(xy 366.934452 -226.704489) (xy 366.9505 -226.753882) (xy 366.958625 -226.805177) (xy 366.959134 -226.831144)
			(xy 366.958625 -226.857111) (xy 367.238789 -226.857111) (xy 367.238789 -226.805177) (xy 367.246914 -226.753882)
			(xy 367.262962 -226.704489) (xy 367.28654 -226.658215) (xy 367.317066 -226.616199) (xy 367.353789 -226.579476)
			(xy 367.395805 -226.54895) (xy 367.442079 -226.525372) (xy 367.491472 -226.509324) (xy 367.542767 -226.501199)
			(xy 367.594701 -226.501199) (xy 367.645996 -226.509324) (xy 367.695389 -226.525372) (xy 367.741663 -226.54895)
			(xy 367.783679 -226.579476) (xy 367.820402 -226.616199) (xy 367.850928 -226.658215) (xy 367.874506 -226.704489)
			(xy 367.890554 -226.753882) (xy 367.898679 -226.805177) (xy 367.899188 -226.831144) (xy 367.898679 -226.857111)
			(xy 368.178335 -226.857111) (xy 368.178335 -226.805177) (xy 368.18646 -226.753882) (xy 368.202508 -226.704489)
			(xy 368.226086 -226.658215) (xy 368.256612 -226.616199) (xy 368.293335 -226.579476) (xy 368.335351 -226.54895)
			(xy 368.381625 -226.525372) (xy 368.431018 -226.509324) (xy 368.482313 -226.501199) (xy 368.534247 -226.501199)
			(xy 368.585542 -226.509324) (xy 368.634935 -226.525372) (xy 368.681209 -226.54895) (xy 368.723225 -226.579476)
			(xy 368.759948 -226.616199) (xy 368.790474 -226.658215) (xy 368.814052 -226.704489) (xy 368.8301 -226.753882)
			(xy 368.838225 -226.805177) (xy 368.838734 -226.831144) (xy 368.838225 -226.857111) (xy 369.118389 -226.857111)
			(xy 369.118389 -226.805177) (xy 369.126514 -226.753882) (xy 369.142562 -226.704489) (xy 369.16614 -226.658215)
			(xy 369.196666 -226.616199) (xy 369.233389 -226.579476) (xy 369.275405 -226.54895) (xy 369.321679 -226.525372)
			(xy 369.371072 -226.509324) (xy 369.422367 -226.501199) (xy 369.474301 -226.501199) (xy 369.525596 -226.509324)
			(xy 369.574989 -226.525372) (xy 369.621263 -226.54895) (xy 369.663279 -226.579476) (xy 369.700002 -226.616199)
			(xy 369.730528 -226.658215) (xy 369.754106 -226.704489) (xy 369.770154 -226.753882) (xy 369.778279 -226.805177)
			(xy 369.778788 -226.831144) (xy 369.778279 -226.857111) (xy 370.057935 -226.857111) (xy 370.057935 -226.805177)
			(xy 370.06606 -226.753882) (xy 370.082108 -226.704489) (xy 370.105686 -226.658215) (xy 370.136212 -226.616199)
			(xy 370.172935 -226.579476) (xy 370.214951 -226.54895) (xy 370.261225 -226.525372) (xy 370.310618 -226.509324)
			(xy 370.361913 -226.501199) (xy 370.413847 -226.501199) (xy 370.465142 -226.509324) (xy 370.514535 -226.525372)
			(xy 370.560809 -226.54895) (xy 370.602825 -226.579476) (xy 370.639548 -226.616199) (xy 370.670074 -226.658215)
			(xy 370.693652 -226.704489) (xy 370.7097 -226.753882) (xy 370.717825 -226.805177) (xy 370.718334 -226.831144)
			(xy 370.717825 -226.857111) (xy 370.997735 -226.857111) (xy 370.997735 -226.805177) (xy 371.00586 -226.753882)
			(xy 371.021908 -226.704489) (xy 371.045486 -226.658215) (xy 371.076012 -226.616199) (xy 371.112735 -226.579476)
			(xy 371.154751 -226.54895) (xy 371.201025 -226.525372) (xy 371.250418 -226.509324) (xy 371.301713 -226.501199)
			(xy 371.353647 -226.501199) (xy 371.404942 -226.509324) (xy 371.454335 -226.525372) (xy 371.500609 -226.54895)
			(xy 371.542625 -226.579476) (xy 371.579348 -226.616199) (xy 371.609874 -226.658215) (xy 371.633452 -226.704489)
			(xy 371.6495 -226.753882) (xy 371.657625 -226.805177) (xy 371.658134 -226.831144) (xy 371.657625 -226.857111)
			(xy 371.937789 -226.857111) (xy 371.937789 -226.805177) (xy 371.945914 -226.753882) (xy 371.961962 -226.704489)
			(xy 371.98554 -226.658215) (xy 372.016066 -226.616199) (xy 372.052789 -226.579476) (xy 372.094805 -226.54895)
			(xy 372.141079 -226.525372) (xy 372.190472 -226.509324) (xy 372.241767 -226.501199) (xy 372.293701 -226.501199)
			(xy 372.344996 -226.509324) (xy 372.394389 -226.525372) (xy 372.440663 -226.54895) (xy 372.482679 -226.579476)
			(xy 372.519402 -226.616199) (xy 372.549928 -226.658215) (xy 372.573506 -226.704489) (xy 372.589554 -226.753882)
			(xy 372.597679 -226.805177) (xy 372.598188 -226.831144) (xy 372.597679 -226.857111) (xy 372.877335 -226.857111)
			(xy 372.877335 -226.805177) (xy 372.88546 -226.753882) (xy 372.901508 -226.704489) (xy 372.925086 -226.658215)
			(xy 372.955612 -226.616199) (xy 372.992335 -226.579476) (xy 373.034351 -226.54895) (xy 373.080625 -226.525372)
			(xy 373.130018 -226.509324) (xy 373.181313 -226.501199) (xy 373.233247 -226.501199) (xy 373.284542 -226.509324)
			(xy 373.333935 -226.525372) (xy 373.380209 -226.54895) (xy 373.422225 -226.579476) (xy 373.458948 -226.616199)
			(xy 373.489474 -226.658215) (xy 373.513052 -226.704489) (xy 373.5291 -226.753882) (xy 373.537225 -226.805177)
			(xy 373.537734 -226.831144) (xy 373.537225 -226.857111) (xy 373.817135 -226.857111) (xy 373.817135 -226.805177)
			(xy 373.82526 -226.753882) (xy 373.841308 -226.704489) (xy 373.864886 -226.658215) (xy 373.895412 -226.616199)
			(xy 373.932135 -226.579476) (xy 373.974151 -226.54895) (xy 374.020425 -226.525372) (xy 374.069818 -226.509324)
			(xy 374.121113 -226.501199) (xy 374.173047 -226.501199) (xy 374.224342 -226.509324) (xy 374.273735 -226.525372)
			(xy 374.320009 -226.54895) (xy 374.362025 -226.579476) (xy 374.398748 -226.616199) (xy 374.429274 -226.658215)
			(xy 374.452852 -226.704489) (xy 374.4689 -226.753882) (xy 374.477025 -226.805177) (xy 374.477534 -226.831144)
			(xy 374.477025 -226.857111) (xy 374.757189 -226.857111) (xy 374.757189 -226.805177) (xy 374.765314 -226.753882)
			(xy 374.781362 -226.704489) (xy 374.80494 -226.658215) (xy 374.835466 -226.616199) (xy 374.872189 -226.579476)
			(xy 374.914205 -226.54895) (xy 374.960479 -226.525372) (xy 375.009872 -226.509324) (xy 375.061167 -226.501199)
			(xy 375.113101 -226.501199) (xy 375.164396 -226.509324) (xy 375.213789 -226.525372) (xy 375.260063 -226.54895)
			(xy 375.302079 -226.579476) (xy 375.338802 -226.616199) (xy 375.369328 -226.658215) (xy 375.392906 -226.704489)
			(xy 375.408954 -226.753882) (xy 375.417079 -226.805177) (xy 375.417588 -226.831144) (xy 375.417079 -226.857111)
			(xy 375.408954 -226.908406) (xy 375.392906 -226.957799) (xy 375.369328 -227.004073) (xy 375.338802 -227.046089)
			(xy 375.302079 -227.082812) (xy 375.260063 -227.113338) (xy 375.213789 -227.136916) (xy 375.164396 -227.152964)
			(xy 375.113101 -227.161089) (xy 375.061167 -227.161089) (xy 375.009872 -227.152964) (xy 374.960479 -227.136916)
			(xy 374.914205 -227.113338) (xy 374.872189 -227.082812) (xy 374.835466 -227.046089) (xy 374.80494 -227.004073)
			(xy 374.781362 -226.957799) (xy 374.765314 -226.908406) (xy 374.757189 -226.857111) (xy 374.477025 -226.857111)
			(xy 374.4689 -226.908406) (xy 374.452852 -226.957799) (xy 374.429274 -227.004073) (xy 374.398748 -227.046089)
			(xy 374.362025 -227.082812) (xy 374.320009 -227.113338) (xy 374.273735 -227.136916) (xy 374.224342 -227.152964)
			(xy 374.173047 -227.161089) (xy 374.121113 -227.161089) (xy 374.069818 -227.152964) (xy 374.020425 -227.136916)
			(xy 373.974151 -227.113338) (xy 373.932135 -227.082812) (xy 373.895412 -227.046089) (xy 373.864886 -227.004073)
			(xy 373.841308 -226.957799) (xy 373.82526 -226.908406) (xy 373.817135 -226.857111) (xy 373.537225 -226.857111)
			(xy 373.5291 -226.908406) (xy 373.513052 -226.957799) (xy 373.489474 -227.004073) (xy 373.458948 -227.046089)
			(xy 373.422225 -227.082812) (xy 373.380209 -227.113338) (xy 373.333935 -227.136916) (xy 373.284542 -227.152964)
			(xy 373.233247 -227.161089) (xy 373.181313 -227.161089) (xy 373.130018 -227.152964) (xy 373.080625 -227.136916)
			(xy 373.034351 -227.113338) (xy 372.992335 -227.082812) (xy 372.955612 -227.046089) (xy 372.925086 -227.004073)
			(xy 372.901508 -226.957799) (xy 372.88546 -226.908406) (xy 372.877335 -226.857111) (xy 372.597679 -226.857111)
			(xy 372.589554 -226.908406) (xy 372.573506 -226.957799) (xy 372.549928 -227.004073) (xy 372.519402 -227.046089)
			(xy 372.482679 -227.082812) (xy 372.440663 -227.113338) (xy 372.394389 -227.136916) (xy 372.344996 -227.152964)
			(xy 372.293701 -227.161089) (xy 372.241767 -227.161089) (xy 372.190472 -227.152964) (xy 372.141079 -227.136916)
			(xy 372.094805 -227.113338) (xy 372.052789 -227.082812) (xy 372.016066 -227.046089) (xy 371.98554 -227.004073)
			(xy 371.961962 -226.957799) (xy 371.945914 -226.908406) (xy 371.937789 -226.857111) (xy 371.657625 -226.857111)
			(xy 371.6495 -226.908406) (xy 371.633452 -226.957799) (xy 371.609874 -227.004073) (xy 371.579348 -227.046089)
			(xy 371.542625 -227.082812) (xy 371.500609 -227.113338) (xy 371.454335 -227.136916) (xy 371.404942 -227.152964)
			(xy 371.353647 -227.161089) (xy 371.301713 -227.161089) (xy 371.250418 -227.152964) (xy 371.201025 -227.136916)
			(xy 371.154751 -227.113338) (xy 371.112735 -227.082812) (xy 371.076012 -227.046089) (xy 371.045486 -227.004073)
			(xy 371.021908 -226.957799) (xy 371.00586 -226.908406) (xy 370.997735 -226.857111) (xy 370.717825 -226.857111)
			(xy 370.7097 -226.908406) (xy 370.693652 -226.957799) (xy 370.670074 -227.004073) (xy 370.639548 -227.046089)
			(xy 370.602825 -227.082812) (xy 370.560809 -227.113338) (xy 370.514535 -227.136916) (xy 370.465142 -227.152964)
			(xy 370.413847 -227.161089) (xy 370.361913 -227.161089) (xy 370.310618 -227.152964) (xy 370.261225 -227.136916)
			(xy 370.214951 -227.113338) (xy 370.172935 -227.082812) (xy 370.136212 -227.046089) (xy 370.105686 -227.004073)
			(xy 370.082108 -226.957799) (xy 370.06606 -226.908406) (xy 370.057935 -226.857111) (xy 369.778279 -226.857111)
			(xy 369.770154 -226.908406) (xy 369.754106 -226.957799) (xy 369.730528 -227.004073) (xy 369.700002 -227.046089)
			(xy 369.663279 -227.082812) (xy 369.621263 -227.113338) (xy 369.574989 -227.136916) (xy 369.525596 -227.152964)
			(xy 369.474301 -227.161089) (xy 369.422367 -227.161089) (xy 369.371072 -227.152964) (xy 369.321679 -227.136916)
			(xy 369.275405 -227.113338) (xy 369.233389 -227.082812) (xy 369.196666 -227.046089) (xy 369.16614 -227.004073)
			(xy 369.142562 -226.957799) (xy 369.126514 -226.908406) (xy 369.118389 -226.857111) (xy 368.838225 -226.857111)
			(xy 368.8301 -226.908406) (xy 368.814052 -226.957799) (xy 368.790474 -227.004073) (xy 368.759948 -227.046089)
			(xy 368.723225 -227.082812) (xy 368.681209 -227.113338) (xy 368.634935 -227.136916) (xy 368.585542 -227.152964)
			(xy 368.534247 -227.161089) (xy 368.482313 -227.161089) (xy 368.431018 -227.152964) (xy 368.381625 -227.136916)
			(xy 368.335351 -227.113338) (xy 368.293335 -227.082812) (xy 368.256612 -227.046089) (xy 368.226086 -227.004073)
			(xy 368.202508 -226.957799) (xy 368.18646 -226.908406) (xy 368.178335 -226.857111) (xy 367.898679 -226.857111)
			(xy 367.890554 -226.908406) (xy 367.874506 -226.957799) (xy 367.850928 -227.004073) (xy 367.820402 -227.046089)
			(xy 367.783679 -227.082812) (xy 367.741663 -227.113338) (xy 367.695389 -227.136916) (xy 367.645996 -227.152964)
			(xy 367.594701 -227.161089) (xy 367.542767 -227.161089) (xy 367.491472 -227.152964) (xy 367.442079 -227.136916)
			(xy 367.395805 -227.113338) (xy 367.353789 -227.082812) (xy 367.317066 -227.046089) (xy 367.28654 -227.004073)
			(xy 367.262962 -226.957799) (xy 367.246914 -226.908406) (xy 367.238789 -226.857111) (xy 366.958625 -226.857111)
			(xy 366.9505 -226.908406) (xy 366.934452 -226.957799) (xy 366.910874 -227.004073) (xy 366.880348 -227.046089)
			(xy 366.843625 -227.082812) (xy 366.801609 -227.113338) (xy 366.755335 -227.136916) (xy 366.705942 -227.152964)
			(xy 366.654647 -227.161089) (xy 366.602713 -227.161089) (xy 366.551418 -227.152964) (xy 366.502025 -227.136916)
			(xy 366.455751 -227.113338) (xy 366.413735 -227.082812) (xy 366.377012 -227.046089) (xy 366.346486 -227.004073)
			(xy 366.322908 -226.957799) (xy 366.30686 -226.908406) (xy 366.298735 -226.857111) (xy 366.019079 -226.857111)
			(xy 366.010954 -226.908406) (xy 365.994906 -226.957799) (xy 365.971328 -227.004073) (xy 365.940802 -227.046089)
			(xy 365.904079 -227.082812) (xy 365.862063 -227.113338) (xy 365.815789 -227.136916) (xy 365.766396 -227.152964)
			(xy 365.715101 -227.161089) (xy 365.663167 -227.161089) (xy 365.611872 -227.152964) (xy 365.562479 -227.136916)
			(xy 365.516205 -227.113338) (xy 365.474189 -227.082812) (xy 365.437466 -227.046089) (xy 365.40694 -227.004073)
			(xy 365.383362 -226.957799) (xy 365.367314 -226.908406) (xy 365.359189 -226.857111) (xy 365.079025 -226.857111)
			(xy 365.0709 -226.908406) (xy 365.054852 -226.957799) (xy 365.031274 -227.004073) (xy 365.000748 -227.046089)
			(xy 364.964025 -227.082812) (xy 364.922009 -227.113338) (xy 364.875735 -227.136916) (xy 364.826342 -227.152964)
			(xy 364.775047 -227.161089) (xy 364.723113 -227.161089) (xy 364.671818 -227.152964) (xy 364.622425 -227.136916)
			(xy 364.576151 -227.113338) (xy 364.534135 -227.082812) (xy 364.497412 -227.046089) (xy 364.466886 -227.004073)
			(xy 364.443308 -226.957799) (xy 364.42726 -226.908406) (xy 364.419135 -226.857111) (xy 364.139479 -226.857111)
			(xy 364.131354 -226.908406) (xy 364.115306 -226.957799) (xy 364.091728 -227.004073) (xy 364.061202 -227.046089)
			(xy 364.024479 -227.082812) (xy 363.982463 -227.113338) (xy 363.936189 -227.136916) (xy 363.886796 -227.152964)
			(xy 363.835501 -227.161089) (xy 363.783567 -227.161089) (xy 363.732272 -227.152964) (xy 363.682879 -227.136916)
			(xy 363.636605 -227.113338) (xy 363.594589 -227.082812) (xy 363.557866 -227.046089) (xy 363.52734 -227.004073)
			(xy 363.503762 -226.957799) (xy 363.487714 -226.908406) (xy 363.479589 -226.857111) (xy 363.199679 -226.857111)
			(xy 363.191554 -226.908406) (xy 363.175506 -226.957799) (xy 363.151928 -227.004073) (xy 363.121402 -227.046089)
			(xy 363.084679 -227.082812) (xy 363.042663 -227.113338) (xy 362.996389 -227.136916) (xy 362.946996 -227.152964)
			(xy 362.895701 -227.161089) (xy 362.843767 -227.161089) (xy 362.792472 -227.152964) (xy 362.743079 -227.136916)
			(xy 362.696805 -227.113338) (xy 362.654789 -227.082812) (xy 362.618066 -227.046089) (xy 362.58754 -227.004073)
			(xy 362.563962 -226.957799) (xy 362.547914 -226.908406) (xy 362.539789 -226.857111) (xy 362.259879 -226.857111)
			(xy 362.251754 -226.908406) (xy 362.235706 -226.957799) (xy 362.212128 -227.004073) (xy 362.181602 -227.046089)
			(xy 362.144879 -227.082812) (xy 362.102863 -227.113338) (xy 362.056589 -227.136916) (xy 362.007196 -227.152964)
			(xy 361.955901 -227.161089) (xy 361.903967 -227.161089) (xy 361.852672 -227.152964) (xy 361.803279 -227.136916)
			(xy 361.757005 -227.113338) (xy 361.714989 -227.082812) (xy 361.678266 -227.046089) (xy 361.64774 -227.004073)
			(xy 361.624162 -226.957799) (xy 361.608114 -226.908406) (xy 361.599989 -226.857111) (xy 361.319825 -226.857111)
			(xy 361.3117 -226.908406) (xy 361.295652 -226.957799) (xy 361.272074 -227.004073) (xy 361.241548 -227.046089)
			(xy 361.204825 -227.082812) (xy 361.162809 -227.113338) (xy 361.116535 -227.136916) (xy 361.067142 -227.152964)
			(xy 361.015847 -227.161089) (xy 360.963913 -227.161089) (xy 360.912618 -227.152964) (xy 360.863225 -227.136916)
			(xy 360.816951 -227.113338) (xy 360.774935 -227.082812) (xy 360.738212 -227.046089) (xy 360.707686 -227.004073)
			(xy 360.684108 -226.957799) (xy 360.66806 -226.908406) (xy 360.659935 -226.857111) (xy 360.380279 -226.857111)
			(xy 360.372154 -226.908406) (xy 360.356106 -226.957799) (xy 360.332528 -227.004073) (xy 360.302002 -227.046089)
			(xy 360.265279 -227.082812) (xy 360.223263 -227.113338) (xy 360.176989 -227.136916) (xy 360.127596 -227.152964)
			(xy 360.076301 -227.161089) (xy 360.024367 -227.161089) (xy 359.973072 -227.152964) (xy 359.923679 -227.136916)
			(xy 359.877405 -227.113338) (xy 359.835389 -227.082812) (xy 359.798666 -227.046089) (xy 359.76814 -227.004073)
			(xy 359.744562 -226.957799) (xy 359.728514 -226.908406) (xy 359.720389 -226.857111) (xy 359.440225 -226.857111)
			(xy 359.4321 -226.908406) (xy 359.416052 -226.957799) (xy 359.392474 -227.004073) (xy 359.361948 -227.046089)
			(xy 359.325225 -227.082812) (xy 359.283209 -227.113338) (xy 359.236935 -227.136916) (xy 359.187542 -227.152964)
			(xy 359.136247 -227.161089) (xy 359.084313 -227.161089) (xy 359.033018 -227.152964) (xy 358.983625 -227.136916)
			(xy 358.937351 -227.113338) (xy 358.895335 -227.082812) (xy 358.858612 -227.046089) (xy 358.828086 -227.004073)
			(xy 358.804508 -226.957799) (xy 358.78846 -226.908406) (xy 358.780335 -226.857111) (xy 358.500593 -226.857111)
			(xy 358.492479 -226.908347) (xy 358.476434 -226.95773) (xy 358.452863 -227.003996) (xy 358.422344 -227.046004)
			(xy 358.38563 -227.082722) (xy 358.343625 -227.113245) (xy 358.297362 -227.136821) (xy 358.24798 -227.152871)
			(xy 358.196696 -227.160998) (xy 358.170734 -227.161598) (xy 358.148359 -227.161242) (xy 358.10401 -227.155252)
			(xy 358.082342 -227.14966) (xy 358.073469 -227.147558) (xy 358.055311 -227.149079) (xy 358.038831 -227.156853)
			(xy 358.026111 -227.1699) (xy 358.022144 -227.178108) (xy 358.002449 -227.221529) (xy 357.954838 -227.30414)
			(xy 357.927148 -227.342954) (xy 357.922087 -227.350511) (xy 357.917149 -227.368002) (xy 357.918608 -227.386119)
			(xy 357.926281 -227.402594) (xy 357.932482 -227.409248) (xy 357.950858 -227.428015) (xy 357.982025 -227.470289)
			(xy 358.006114 -227.516959) (xy 358.022521 -227.566852) (xy 358.03083 -227.618712) (xy 358.030835 -227.670927)
			(xy 358.310689 -227.670927) (xy 358.310689 -227.618993) (xy 358.318814 -227.567698) (xy 358.334862 -227.518305)
			(xy 358.35844 -227.472031) (xy 358.388966 -227.430015) (xy 358.425689 -227.393292) (xy 358.467705 -227.362766)
			(xy 358.513979 -227.339188) (xy 358.563372 -227.32314) (xy 358.614667 -227.315015) (xy 358.666601 -227.315015)
			(xy 358.717896 -227.32314) (xy 358.767289 -227.339188) (xy 358.813563 -227.362766) (xy 358.855579 -227.393292)
			(xy 358.892302 -227.430015) (xy 358.922828 -227.472031) (xy 358.946406 -227.518305) (xy 358.962454 -227.567698)
			(xy 358.970579 -227.618993) (xy 358.971088 -227.64496) (xy 358.970579 -227.670927) (xy 359.250489 -227.670927)
			(xy 359.250489 -227.618993) (xy 359.258614 -227.567698) (xy 359.274662 -227.518305) (xy 359.29824 -227.472031)
			(xy 359.328766 -227.430015) (xy 359.365489 -227.393292) (xy 359.407505 -227.362766) (xy 359.453779 -227.339188)
			(xy 359.503172 -227.32314) (xy 359.554467 -227.315015) (xy 359.606401 -227.315015) (xy 359.657696 -227.32314)
			(xy 359.707089 -227.339188) (xy 359.753363 -227.362766) (xy 359.795379 -227.393292) (xy 359.832102 -227.430015)
			(xy 359.862628 -227.472031) (xy 359.886206 -227.518305) (xy 359.902254 -227.567698) (xy 359.910379 -227.618993)
			(xy 359.910888 -227.64496) (xy 359.910379 -227.670927) (xy 360.190289 -227.670927) (xy 360.190289 -227.618993)
			(xy 360.198414 -227.567698) (xy 360.214462 -227.518305) (xy 360.23804 -227.472031) (xy 360.268566 -227.430015)
			(xy 360.305289 -227.393292) (xy 360.347305 -227.362766) (xy 360.393579 -227.339188) (xy 360.442972 -227.32314)
			(xy 360.494267 -227.315015) (xy 360.546201 -227.315015) (xy 360.597496 -227.32314) (xy 360.646889 -227.339188)
			(xy 360.693163 -227.362766) (xy 360.735179 -227.393292) (xy 360.771902 -227.430015) (xy 360.802428 -227.472031)
			(xy 360.826006 -227.518305) (xy 360.842054 -227.567698) (xy 360.850179 -227.618993) (xy 360.850688 -227.64496)
			(xy 360.850179 -227.670927) (xy 361.130089 -227.670927) (xy 361.130089 -227.618993) (xy 361.138214 -227.567698)
			(xy 361.154262 -227.518305) (xy 361.17784 -227.472031) (xy 361.208366 -227.430015) (xy 361.245089 -227.393292)
			(xy 361.287105 -227.362766) (xy 361.333379 -227.339188) (xy 361.382772 -227.32314) (xy 361.434067 -227.315015)
			(xy 361.486001 -227.315015) (xy 361.537296 -227.32314) (xy 361.586689 -227.339188) (xy 361.632963 -227.362766)
			(xy 361.674979 -227.393292) (xy 361.711702 -227.430015) (xy 361.742228 -227.472031) (xy 361.765806 -227.518305)
			(xy 361.781854 -227.567698) (xy 361.789979 -227.618993) (xy 361.790488 -227.64496) (xy 361.789979 -227.670927)
			(xy 362.070143 -227.670927) (xy 362.070143 -227.618993) (xy 362.078268 -227.567698) (xy 362.094316 -227.518305)
			(xy 362.117894 -227.472031) (xy 362.14842 -227.430015) (xy 362.185143 -227.393292) (xy 362.227159 -227.362766)
			(xy 362.273433 -227.339188) (xy 362.322826 -227.32314) (xy 362.374121 -227.315015) (xy 362.426055 -227.315015)
			(xy 362.47735 -227.32314) (xy 362.526743 -227.339188) (xy 362.573017 -227.362766) (xy 362.615033 -227.393292)
			(xy 362.651756 -227.430015) (xy 362.682282 -227.472031) (xy 362.70586 -227.518305) (xy 362.721908 -227.567698)
			(xy 362.730033 -227.618993) (xy 362.730542 -227.64496) (xy 362.730033 -227.670927) (xy 363.009689 -227.670927)
			(xy 363.009689 -227.618993) (xy 363.017814 -227.567698) (xy 363.033862 -227.518305) (xy 363.05744 -227.472031)
			(xy 363.087966 -227.430015) (xy 363.124689 -227.393292) (xy 363.166705 -227.362766) (xy 363.212979 -227.339188)
			(xy 363.262372 -227.32314) (xy 363.313667 -227.315015) (xy 363.365601 -227.315015) (xy 363.416896 -227.32314)
			(xy 363.466289 -227.339188) (xy 363.512563 -227.362766) (xy 363.554579 -227.393292) (xy 363.591302 -227.430015)
			(xy 363.621828 -227.472031) (xy 363.645406 -227.518305) (xy 363.661454 -227.567698) (xy 363.669579 -227.618993)
			(xy 363.670088 -227.64496) (xy 363.669579 -227.670927) (xy 363.949489 -227.670927) (xy 363.949489 -227.618993)
			(xy 363.957614 -227.567698) (xy 363.973662 -227.518305) (xy 363.99724 -227.472031) (xy 364.027766 -227.430015)
			(xy 364.064489 -227.393292) (xy 364.106505 -227.362766) (xy 364.152779 -227.339188) (xy 364.202172 -227.32314)
			(xy 364.253467 -227.315015) (xy 364.305401 -227.315015) (xy 364.356696 -227.32314) (xy 364.406089 -227.339188)
			(xy 364.452363 -227.362766) (xy 364.494379 -227.393292) (xy 364.531102 -227.430015) (xy 364.561628 -227.472031)
			(xy 364.585206 -227.518305) (xy 364.601254 -227.567698) (xy 364.609379 -227.618993) (xy 364.609888 -227.64496)
			(xy 364.609379 -227.670927) (xy 364.889289 -227.670927) (xy 364.889289 -227.618993) (xy 364.897414 -227.567698)
			(xy 364.913462 -227.518305) (xy 364.93704 -227.472031) (xy 364.967566 -227.430015) (xy 365.004289 -227.393292)
			(xy 365.046305 -227.362766) (xy 365.092579 -227.339188) (xy 365.141972 -227.32314) (xy 365.193267 -227.315015)
			(xy 365.245201 -227.315015) (xy 365.296496 -227.32314) (xy 365.345889 -227.339188) (xy 365.392163 -227.362766)
			(xy 365.434179 -227.393292) (xy 365.470902 -227.430015) (xy 365.501428 -227.472031) (xy 365.525006 -227.518305)
			(xy 365.541054 -227.567698) (xy 365.549179 -227.618993) (xy 365.549688 -227.64496) (xy 365.549179 -227.670927)
			(xy 365.829089 -227.670927) (xy 365.829089 -227.618993) (xy 365.837214 -227.567698) (xy 365.853262 -227.518305)
			(xy 365.87684 -227.472031) (xy 365.907366 -227.430015) (xy 365.944089 -227.393292) (xy 365.986105 -227.362766)
			(xy 366.032379 -227.339188) (xy 366.081772 -227.32314) (xy 366.133067 -227.315015) (xy 366.185001 -227.315015)
			(xy 366.236296 -227.32314) (xy 366.285689 -227.339188) (xy 366.331963 -227.362766) (xy 366.373979 -227.393292)
			(xy 366.410702 -227.430015) (xy 366.441228 -227.472031) (xy 366.464806 -227.518305) (xy 366.480854 -227.567698)
			(xy 366.488979 -227.618993) (xy 366.489488 -227.64496) (xy 366.488979 -227.670927) (xy 366.768889 -227.670927)
			(xy 366.768889 -227.618993) (xy 366.777014 -227.567698) (xy 366.793062 -227.518305) (xy 366.81664 -227.472031)
			(xy 366.847166 -227.430015) (xy 366.883889 -227.393292) (xy 366.925905 -227.362766) (xy 366.972179 -227.339188)
			(xy 367.021572 -227.32314) (xy 367.072867 -227.315015) (xy 367.124801 -227.315015) (xy 367.176096 -227.32314)
			(xy 367.225489 -227.339188) (xy 367.271763 -227.362766) (xy 367.313779 -227.393292) (xy 367.350502 -227.430015)
			(xy 367.381028 -227.472031) (xy 367.404606 -227.518305) (xy 367.420654 -227.567698) (xy 367.428779 -227.618993)
			(xy 367.429288 -227.64496) (xy 367.428779 -227.670927) (xy 367.708689 -227.670927) (xy 367.708689 -227.618993)
			(xy 367.716814 -227.567698) (xy 367.732862 -227.518305) (xy 367.75644 -227.472031) (xy 367.786966 -227.430015)
			(xy 367.823689 -227.393292) (xy 367.865705 -227.362766) (xy 367.911979 -227.339188) (xy 367.961372 -227.32314)
			(xy 368.012667 -227.315015) (xy 368.064601 -227.315015) (xy 368.115896 -227.32314) (xy 368.165289 -227.339188)
			(xy 368.211563 -227.362766) (xy 368.253579 -227.393292) (xy 368.290302 -227.430015) (xy 368.320828 -227.472031)
			(xy 368.344406 -227.518305) (xy 368.360454 -227.567698) (xy 368.368579 -227.618993) (xy 368.369088 -227.64496)
			(xy 368.368579 -227.670927) (xy 368.648489 -227.670927) (xy 368.648489 -227.618993) (xy 368.656614 -227.567698)
			(xy 368.672662 -227.518305) (xy 368.69624 -227.472031) (xy 368.726766 -227.430015) (xy 368.763489 -227.393292)
			(xy 368.805505 -227.362766) (xy 368.851779 -227.339188) (xy 368.901172 -227.32314) (xy 368.952467 -227.315015)
			(xy 369.004401 -227.315015) (xy 369.055696 -227.32314) (xy 369.105089 -227.339188) (xy 369.151363 -227.362766)
			(xy 369.193379 -227.393292) (xy 369.230102 -227.430015) (xy 369.260628 -227.472031) (xy 369.284206 -227.518305)
			(xy 369.300254 -227.567698) (xy 369.308379 -227.618993) (xy 369.308888 -227.64496) (xy 369.308379 -227.670927)
			(xy 369.588035 -227.670927) (xy 369.588035 -227.618993) (xy 369.59616 -227.567698) (xy 369.612208 -227.518305)
			(xy 369.635786 -227.472031) (xy 369.666312 -227.430015) (xy 369.703035 -227.393292) (xy 369.745051 -227.362766)
			(xy 369.791325 -227.339188) (xy 369.840718 -227.32314) (xy 369.892013 -227.315015) (xy 369.943947 -227.315015)
			(xy 369.995242 -227.32314) (xy 370.044635 -227.339188) (xy 370.090909 -227.362766) (xy 370.132925 -227.393292)
			(xy 370.169648 -227.430015) (xy 370.200174 -227.472031) (xy 370.223752 -227.518305) (xy 370.2398 -227.567698)
			(xy 370.247925 -227.618993) (xy 370.248434 -227.64496) (xy 370.247925 -227.670927) (xy 370.528089 -227.670927)
			(xy 370.528089 -227.618993) (xy 370.536214 -227.567698) (xy 370.552262 -227.518305) (xy 370.57584 -227.472031)
			(xy 370.606366 -227.430015) (xy 370.643089 -227.393292) (xy 370.685105 -227.362766) (xy 370.731379 -227.339188)
			(xy 370.780772 -227.32314) (xy 370.832067 -227.315015) (xy 370.884001 -227.315015) (xy 370.935296 -227.32314)
			(xy 370.984689 -227.339188) (xy 371.030963 -227.362766) (xy 371.072979 -227.393292) (xy 371.109702 -227.430015)
			(xy 371.140228 -227.472031) (xy 371.163806 -227.518305) (xy 371.179854 -227.567698) (xy 371.187979 -227.618993)
			(xy 371.188488 -227.64496) (xy 371.187979 -227.670927) (xy 371.467889 -227.670927) (xy 371.467889 -227.618993)
			(xy 371.476014 -227.567698) (xy 371.492062 -227.518305) (xy 371.51564 -227.472031) (xy 371.546166 -227.430015)
			(xy 371.582889 -227.393292) (xy 371.624905 -227.362766) (xy 371.671179 -227.339188) (xy 371.720572 -227.32314)
			(xy 371.771867 -227.315015) (xy 371.823801 -227.315015) (xy 371.875096 -227.32314) (xy 371.924489 -227.339188)
			(xy 371.970763 -227.362766) (xy 372.012779 -227.393292) (xy 372.049502 -227.430015) (xy 372.080028 -227.472031)
			(xy 372.103606 -227.518305) (xy 372.119654 -227.567698) (xy 372.127779 -227.618993) (xy 372.128288 -227.64496)
			(xy 372.127779 -227.670927) (xy 372.407689 -227.670927) (xy 372.407689 -227.618993) (xy 372.415814 -227.567698)
			(xy 372.431862 -227.518305) (xy 372.45544 -227.472031) (xy 372.485966 -227.430015) (xy 372.522689 -227.393292)
			(xy 372.564705 -227.362766) (xy 372.610979 -227.339188) (xy 372.660372 -227.32314) (xy 372.711667 -227.315015)
			(xy 372.763601 -227.315015) (xy 372.814896 -227.32314) (xy 372.864289 -227.339188) (xy 372.910563 -227.362766)
			(xy 372.952579 -227.393292) (xy 372.989302 -227.430015) (xy 373.019828 -227.472031) (xy 373.043406 -227.518305)
			(xy 373.059454 -227.567698) (xy 373.067579 -227.618993) (xy 373.068088 -227.64496) (xy 373.067579 -227.670927)
			(xy 373.347489 -227.670927) (xy 373.347489 -227.618993) (xy 373.355614 -227.567698) (xy 373.371662 -227.518305)
			(xy 373.39524 -227.472031) (xy 373.425766 -227.430015) (xy 373.462489 -227.393292) (xy 373.504505 -227.362766)
			(xy 373.550779 -227.339188) (xy 373.600172 -227.32314) (xy 373.651467 -227.315015) (xy 373.703401 -227.315015)
			(xy 373.754696 -227.32314) (xy 373.804089 -227.339188) (xy 373.850363 -227.362766) (xy 373.892379 -227.393292)
			(xy 373.929102 -227.430015) (xy 373.959628 -227.472031) (xy 373.983206 -227.518305) (xy 373.999254 -227.567698)
			(xy 374.007379 -227.618993) (xy 374.007888 -227.64496) (xy 374.007379 -227.670927) (xy 374.287289 -227.670927)
			(xy 374.287289 -227.618993) (xy 374.295414 -227.567698) (xy 374.311462 -227.518305) (xy 374.33504 -227.472031)
			(xy 374.365566 -227.430015) (xy 374.402289 -227.393292) (xy 374.444305 -227.362766) (xy 374.490579 -227.339188)
			(xy 374.539972 -227.32314) (xy 374.591267 -227.315015) (xy 374.643201 -227.315015) (xy 374.694496 -227.32314)
			(xy 374.743889 -227.339188) (xy 374.790163 -227.362766) (xy 374.832179 -227.393292) (xy 374.868902 -227.430015)
			(xy 374.899428 -227.472031) (xy 374.923006 -227.518305) (xy 374.939054 -227.567698) (xy 374.947179 -227.618993)
			(xy 374.947688 -227.64496) (xy 374.947179 -227.670927) (xy 375.226835 -227.670927) (xy 375.226835 -227.618993)
			(xy 375.23496 -227.567698) (xy 375.251008 -227.518305) (xy 375.274586 -227.472031) (xy 375.305112 -227.430015)
			(xy 375.341835 -227.393292) (xy 375.383851 -227.362766) (xy 375.430125 -227.339188) (xy 375.479518 -227.32314)
			(xy 375.530813 -227.315015) (xy 375.582747 -227.315015) (xy 375.634042 -227.32314) (xy 375.683435 -227.339188)
			(xy 375.729709 -227.362766) (xy 375.771725 -227.393292) (xy 375.808448 -227.430015) (xy 375.838974 -227.472031)
			(xy 375.862552 -227.518305) (xy 375.8786 -227.567698) (xy 375.886725 -227.618993) (xy 375.887234 -227.64496)
			(xy 375.886725 -227.670927) (xy 375.8786 -227.722222) (xy 375.862552 -227.771615) (xy 375.838974 -227.817889)
			(xy 375.808448 -227.859905) (xy 375.771725 -227.896628) (xy 375.729709 -227.927154) (xy 375.683435 -227.950732)
			(xy 375.634042 -227.96678) (xy 375.582747 -227.974905) (xy 375.530813 -227.974905) (xy 375.479518 -227.96678)
			(xy 375.430125 -227.950732) (xy 375.383851 -227.927154) (xy 375.341835 -227.896628) (xy 375.305112 -227.859905)
			(xy 375.274586 -227.817889) (xy 375.251008 -227.771615) (xy 375.23496 -227.722222) (xy 375.226835 -227.670927)
			(xy 374.947179 -227.670927) (xy 374.939054 -227.722222) (xy 374.923006 -227.771615) (xy 374.899428 -227.817889)
			(xy 374.868902 -227.859905) (xy 374.832179 -227.896628) (xy 374.790163 -227.927154) (xy 374.743889 -227.950732)
			(xy 374.694496 -227.96678) (xy 374.643201 -227.974905) (xy 374.591267 -227.974905) (xy 374.539972 -227.96678)
			(xy 374.490579 -227.950732) (xy 374.444305 -227.927154) (xy 374.402289 -227.896628) (xy 374.365566 -227.859905)
			(xy 374.33504 -227.817889) (xy 374.311462 -227.771615) (xy 374.295414 -227.722222) (xy 374.287289 -227.670927)
			(xy 374.007379 -227.670927) (xy 373.999254 -227.722222) (xy 373.983206 -227.771615) (xy 373.959628 -227.817889)
			(xy 373.929102 -227.859905) (xy 373.892379 -227.896628) (xy 373.850363 -227.927154) (xy 373.804089 -227.950732)
			(xy 373.754696 -227.96678) (xy 373.703401 -227.974905) (xy 373.651467 -227.974905) (xy 373.600172 -227.96678)
			(xy 373.550779 -227.950732) (xy 373.504505 -227.927154) (xy 373.462489 -227.896628) (xy 373.425766 -227.859905)
			(xy 373.39524 -227.817889) (xy 373.371662 -227.771615) (xy 373.355614 -227.722222) (xy 373.347489 -227.670927)
			(xy 373.067579 -227.670927) (xy 373.059454 -227.722222) (xy 373.043406 -227.771615) (xy 373.019828 -227.817889)
			(xy 372.989302 -227.859905) (xy 372.952579 -227.896628) (xy 372.910563 -227.927154) (xy 372.864289 -227.950732)
			(xy 372.814896 -227.96678) (xy 372.763601 -227.974905) (xy 372.711667 -227.974905) (xy 372.660372 -227.96678)
			(xy 372.610979 -227.950732) (xy 372.564705 -227.927154) (xy 372.522689 -227.896628) (xy 372.485966 -227.859905)
			(xy 372.45544 -227.817889) (xy 372.431862 -227.771615) (xy 372.415814 -227.722222) (xy 372.407689 -227.670927)
			(xy 372.127779 -227.670927) (xy 372.119654 -227.722222) (xy 372.103606 -227.771615) (xy 372.080028 -227.817889)
			(xy 372.049502 -227.859905) (xy 372.012779 -227.896628) (xy 371.970763 -227.927154) (xy 371.924489 -227.950732)
			(xy 371.875096 -227.96678) (xy 371.823801 -227.974905) (xy 371.771867 -227.974905) (xy 371.720572 -227.96678)
			(xy 371.671179 -227.950732) (xy 371.624905 -227.927154) (xy 371.582889 -227.896628) (xy 371.546166 -227.859905)
			(xy 371.51564 -227.817889) (xy 371.492062 -227.771615) (xy 371.476014 -227.722222) (xy 371.467889 -227.670927)
			(xy 371.187979 -227.670927) (xy 371.179854 -227.722222) (xy 371.163806 -227.771615) (xy 371.140228 -227.817889)
			(xy 371.109702 -227.859905) (xy 371.072979 -227.896628) (xy 371.030963 -227.927154) (xy 370.984689 -227.950732)
			(xy 370.935296 -227.96678) (xy 370.884001 -227.974905) (xy 370.832067 -227.974905) (xy 370.780772 -227.96678)
			(xy 370.731379 -227.950732) (xy 370.685105 -227.927154) (xy 370.643089 -227.896628) (xy 370.606366 -227.859905)
			(xy 370.57584 -227.817889) (xy 370.552262 -227.771615) (xy 370.536214 -227.722222) (xy 370.528089 -227.670927)
			(xy 370.247925 -227.670927) (xy 370.2398 -227.722222) (xy 370.223752 -227.771615) (xy 370.200174 -227.817889)
			(xy 370.169648 -227.859905) (xy 370.132925 -227.896628) (xy 370.090909 -227.927154) (xy 370.044635 -227.950732)
			(xy 369.995242 -227.96678) (xy 369.943947 -227.974905) (xy 369.892013 -227.974905) (xy 369.840718 -227.96678)
			(xy 369.791325 -227.950732) (xy 369.745051 -227.927154) (xy 369.703035 -227.896628) (xy 369.666312 -227.859905)
			(xy 369.635786 -227.817889) (xy 369.612208 -227.771615) (xy 369.59616 -227.722222) (xy 369.588035 -227.670927)
			(xy 369.308379 -227.670927) (xy 369.300254 -227.722222) (xy 369.284206 -227.771615) (xy 369.260628 -227.817889)
			(xy 369.230102 -227.859905) (xy 369.193379 -227.896628) (xy 369.151363 -227.927154) (xy 369.105089 -227.950732)
			(xy 369.055696 -227.96678) (xy 369.004401 -227.974905) (xy 368.952467 -227.974905) (xy 368.901172 -227.96678)
			(xy 368.851779 -227.950732) (xy 368.805505 -227.927154) (xy 368.763489 -227.896628) (xy 368.726766 -227.859905)
			(xy 368.69624 -227.817889) (xy 368.672662 -227.771615) (xy 368.656614 -227.722222) (xy 368.648489 -227.670927)
			(xy 368.368579 -227.670927) (xy 368.360454 -227.722222) (xy 368.344406 -227.771615) (xy 368.320828 -227.817889)
			(xy 368.290302 -227.859905) (xy 368.253579 -227.896628) (xy 368.211563 -227.927154) (xy 368.165289 -227.950732)
			(xy 368.115896 -227.96678) (xy 368.064601 -227.974905) (xy 368.012667 -227.974905) (xy 367.961372 -227.96678)
			(xy 367.911979 -227.950732) (xy 367.865705 -227.927154) (xy 367.823689 -227.896628) (xy 367.786966 -227.859905)
			(xy 367.75644 -227.817889) (xy 367.732862 -227.771615) (xy 367.716814 -227.722222) (xy 367.708689 -227.670927)
			(xy 367.428779 -227.670927) (xy 367.420654 -227.722222) (xy 367.404606 -227.771615) (xy 367.381028 -227.817889)
			(xy 367.350502 -227.859905) (xy 367.313779 -227.896628) (xy 367.271763 -227.927154) (xy 367.225489 -227.950732)
			(xy 367.176096 -227.96678) (xy 367.124801 -227.974905) (xy 367.072867 -227.974905) (xy 367.021572 -227.96678)
			(xy 366.972179 -227.950732) (xy 366.925905 -227.927154) (xy 366.883889 -227.896628) (xy 366.847166 -227.859905)
			(xy 366.81664 -227.817889) (xy 366.793062 -227.771615) (xy 366.777014 -227.722222) (xy 366.768889 -227.670927)
			(xy 366.488979 -227.670927) (xy 366.480854 -227.722222) (xy 366.464806 -227.771615) (xy 366.441228 -227.817889)
			(xy 366.410702 -227.859905) (xy 366.373979 -227.896628) (xy 366.331963 -227.927154) (xy 366.285689 -227.950732)
			(xy 366.236296 -227.96678) (xy 366.185001 -227.974905) (xy 366.133067 -227.974905) (xy 366.081772 -227.96678)
			(xy 366.032379 -227.950732) (xy 365.986105 -227.927154) (xy 365.944089 -227.896628) (xy 365.907366 -227.859905)
			(xy 365.87684 -227.817889) (xy 365.853262 -227.771615) (xy 365.837214 -227.722222) (xy 365.829089 -227.670927)
			(xy 365.549179 -227.670927) (xy 365.541054 -227.722222) (xy 365.525006 -227.771615) (xy 365.501428 -227.817889)
			(xy 365.470902 -227.859905) (xy 365.434179 -227.896628) (xy 365.392163 -227.927154) (xy 365.345889 -227.950732)
			(xy 365.296496 -227.96678) (xy 365.245201 -227.974905) (xy 365.193267 -227.974905) (xy 365.141972 -227.96678)
			(xy 365.092579 -227.950732) (xy 365.046305 -227.927154) (xy 365.004289 -227.896628) (xy 364.967566 -227.859905)
			(xy 364.93704 -227.817889) (xy 364.913462 -227.771615) (xy 364.897414 -227.722222) (xy 364.889289 -227.670927)
			(xy 364.609379 -227.670927) (xy 364.601254 -227.722222) (xy 364.585206 -227.771615) (xy 364.561628 -227.817889)
			(xy 364.531102 -227.859905) (xy 364.494379 -227.896628) (xy 364.452363 -227.927154) (xy 364.406089 -227.950732)
			(xy 364.356696 -227.96678) (xy 364.305401 -227.974905) (xy 364.253467 -227.974905) (xy 364.202172 -227.96678)
			(xy 364.152779 -227.950732) (xy 364.106505 -227.927154) (xy 364.064489 -227.896628) (xy 364.027766 -227.859905)
			(xy 363.99724 -227.817889) (xy 363.973662 -227.771615) (xy 363.957614 -227.722222) (xy 363.949489 -227.670927)
			(xy 363.669579 -227.670927) (xy 363.661454 -227.722222) (xy 363.645406 -227.771615) (xy 363.621828 -227.817889)
			(xy 363.591302 -227.859905) (xy 363.554579 -227.896628) (xy 363.512563 -227.927154) (xy 363.466289 -227.950732)
			(xy 363.416896 -227.96678) (xy 363.365601 -227.974905) (xy 363.313667 -227.974905) (xy 363.262372 -227.96678)
			(xy 363.212979 -227.950732) (xy 363.166705 -227.927154) (xy 363.124689 -227.896628) (xy 363.087966 -227.859905)
			(xy 363.05744 -227.817889) (xy 363.033862 -227.771615) (xy 363.017814 -227.722222) (xy 363.009689 -227.670927)
			(xy 362.730033 -227.670927) (xy 362.721908 -227.722222) (xy 362.70586 -227.771615) (xy 362.682282 -227.817889)
			(xy 362.651756 -227.859905) (xy 362.615033 -227.896628) (xy 362.573017 -227.927154) (xy 362.526743 -227.950732)
			(xy 362.47735 -227.96678) (xy 362.426055 -227.974905) (xy 362.374121 -227.974905) (xy 362.322826 -227.96678)
			(xy 362.273433 -227.950732) (xy 362.227159 -227.927154) (xy 362.185143 -227.896628) (xy 362.14842 -227.859905)
			(xy 362.117894 -227.817889) (xy 362.094316 -227.771615) (xy 362.078268 -227.722222) (xy 362.070143 -227.670927)
			(xy 361.789979 -227.670927) (xy 361.781854 -227.722222) (xy 361.765806 -227.771615) (xy 361.742228 -227.817889)
			(xy 361.711702 -227.859905) (xy 361.674979 -227.896628) (xy 361.632963 -227.927154) (xy 361.586689 -227.950732)
			(xy 361.537296 -227.96678) (xy 361.486001 -227.974905) (xy 361.434067 -227.974905) (xy 361.382772 -227.96678)
			(xy 361.333379 -227.950732) (xy 361.287105 -227.927154) (xy 361.245089 -227.896628) (xy 361.208366 -227.859905)
			(xy 361.17784 -227.817889) (xy 361.154262 -227.771615) (xy 361.138214 -227.722222) (xy 361.130089 -227.670927)
			(xy 360.850179 -227.670927) (xy 360.842054 -227.722222) (xy 360.826006 -227.771615) (xy 360.802428 -227.817889)
			(xy 360.771902 -227.859905) (xy 360.735179 -227.896628) (xy 360.693163 -227.927154) (xy 360.646889 -227.950732)
			(xy 360.597496 -227.96678) (xy 360.546201 -227.974905) (xy 360.494267 -227.974905) (xy 360.442972 -227.96678)
			(xy 360.393579 -227.950732) (xy 360.347305 -227.927154) (xy 360.305289 -227.896628) (xy 360.268566 -227.859905)
			(xy 360.23804 -227.817889) (xy 360.214462 -227.771615) (xy 360.198414 -227.722222) (xy 360.190289 -227.670927)
			(xy 359.910379 -227.670927) (xy 359.902254 -227.722222) (xy 359.886206 -227.771615) (xy 359.862628 -227.817889)
			(xy 359.832102 -227.859905) (xy 359.795379 -227.896628) (xy 359.753363 -227.927154) (xy 359.707089 -227.950732)
			(xy 359.657696 -227.96678) (xy 359.606401 -227.974905) (xy 359.554467 -227.974905) (xy 359.503172 -227.96678)
			(xy 359.453779 -227.950732) (xy 359.407505 -227.927154) (xy 359.365489 -227.896628) (xy 359.328766 -227.859905)
			(xy 359.29824 -227.817889) (xy 359.274662 -227.771615) (xy 359.258614 -227.722222) (xy 359.250489 -227.670927)
			(xy 358.970579 -227.670927) (xy 358.962454 -227.722222) (xy 358.946406 -227.771615) (xy 358.922828 -227.817889)
			(xy 358.892302 -227.859905) (xy 358.855579 -227.896628) (xy 358.813563 -227.927154) (xy 358.767289 -227.950732)
			(xy 358.717896 -227.96678) (xy 358.666601 -227.974905) (xy 358.614667 -227.974905) (xy 358.563372 -227.96678)
			(xy 358.513979 -227.950732) (xy 358.467705 -227.927154) (xy 358.425689 -227.896628) (xy 358.388966 -227.859905)
			(xy 358.35844 -227.817889) (xy 358.334862 -227.771615) (xy 358.318814 -227.722222) (xy 358.310689 -227.670927)
			(xy 358.030835 -227.670927) (xy 358.030835 -227.671232) (xy 358.022534 -227.723093) (xy 358.006136 -227.772989)
			(xy 357.982054 -227.819663) (xy 357.950894 -227.861942) (xy 357.932482 -227.880672) (xy 357.926229 -227.8873)
			(xy 357.918483 -227.903779) (xy 357.917016 -227.921929) (xy 357.922014 -227.939439) (xy 357.927148 -227.946966)
			(xy 357.954917 -227.985831) (xy 358.002656 -228.06857) (xy 358.022398 -228.112066) (xy 358.026402 -228.120211)
			(xy 358.039053 -228.133208) (xy 358.055437 -228.140989) (xy 358.073505 -228.14258) (xy 358.082342 -228.140514)
			(xy 358.103945 -228.134917) (xy 358.148167 -228.128931) (xy 358.17048 -228.128576) (xy 358.196448 -228.129057)
			(xy 358.247745 -228.137179) (xy 358.29714 -228.153226) (xy 358.343416 -228.176802) (xy 358.385434 -228.207328)
			(xy 358.422159 -228.244051) (xy 358.452687 -228.286067) (xy 358.476267 -228.332342) (xy 358.492316 -228.381736)
			(xy 358.500441 -228.433032) (xy 358.500441 -228.484968) (xy 358.500436 -228.484997) (xy 358.780589 -228.484997)
			(xy 358.780589 -228.433063) (xy 358.788714 -228.381768) (xy 358.804762 -228.332375) (xy 358.82834 -228.286101)
			(xy 358.858866 -228.244085) (xy 358.895589 -228.207362) (xy 358.937605 -228.176836) (xy 358.983879 -228.153258)
			(xy 359.033272 -228.13721) (xy 359.084567 -228.129085) (xy 359.136501 -228.129085) (xy 359.187796 -228.13721)
			(xy 359.237189 -228.153258) (xy 359.283463 -228.176836) (xy 359.325479 -228.207362) (xy 359.362202 -228.244085)
			(xy 359.392728 -228.286101) (xy 359.416306 -228.332375) (xy 359.432354 -228.381768) (xy 359.440479 -228.433063)
			(xy 359.440988 -228.45903) (xy 359.440479 -228.484997) (xy 359.720135 -228.484997) (xy 359.720135 -228.433063)
			(xy 359.72826 -228.381768) (xy 359.744308 -228.332375) (xy 359.767886 -228.286101) (xy 359.798412 -228.244085)
			(xy 359.835135 -228.207362) (xy 359.877151 -228.176836) (xy 359.923425 -228.153258) (xy 359.972818 -228.13721)
			(xy 360.024113 -228.129085) (xy 360.076047 -228.129085) (xy 360.127342 -228.13721) (xy 360.176735 -228.153258)
			(xy 360.223009 -228.176836) (xy 360.265025 -228.207362) (xy 360.301748 -228.244085) (xy 360.332274 -228.286101)
			(xy 360.355852 -228.332375) (xy 360.3719 -228.381768) (xy 360.380025 -228.433063) (xy 360.380534 -228.45903)
			(xy 360.380025 -228.484997) (xy 360.659935 -228.484997) (xy 360.659935 -228.433063) (xy 360.66806 -228.381768)
			(xy 360.684108 -228.332375) (xy 360.707686 -228.286101) (xy 360.738212 -228.244085) (xy 360.774935 -228.207362)
			(xy 360.816951 -228.176836) (xy 360.863225 -228.153258) (xy 360.912618 -228.13721) (xy 360.963913 -228.129085)
			(xy 361.015847 -228.129085) (xy 361.067142 -228.13721) (xy 361.116535 -228.153258) (xy 361.162809 -228.176836)
			(xy 361.204825 -228.207362) (xy 361.241548 -228.244085) (xy 361.272074 -228.286101) (xy 361.295652 -228.332375)
			(xy 361.3117 -228.381768) (xy 361.319825 -228.433063) (xy 361.320334 -228.45903) (xy 361.319825 -228.484997)
			(xy 361.599735 -228.484997) (xy 361.599735 -228.433063) (xy 361.60786 -228.381768) (xy 361.623908 -228.332375)
			(xy 361.647486 -228.286101) (xy 361.678012 -228.244085) (xy 361.714735 -228.207362) (xy 361.756751 -228.176836)
			(xy 361.803025 -228.153258) (xy 361.852418 -228.13721) (xy 361.903713 -228.129085) (xy 361.955647 -228.129085)
			(xy 362.006942 -228.13721) (xy 362.056335 -228.153258) (xy 362.102609 -228.176836) (xy 362.144625 -228.207362)
			(xy 362.181348 -228.244085) (xy 362.211874 -228.286101) (xy 362.235452 -228.332375) (xy 362.2515 -228.381768)
			(xy 362.259625 -228.433063) (xy 362.260134 -228.45903) (xy 362.259625 -228.484997) (xy 363.479335 -228.484997)
			(xy 363.479335 -228.433063) (xy 363.48746 -228.381768) (xy 363.503508 -228.332375) (xy 363.527086 -228.286101)
			(xy 363.557612 -228.244085) (xy 363.594335 -228.207362) (xy 363.636351 -228.176836) (xy 363.682625 -228.153258)
			(xy 363.732018 -228.13721) (xy 363.783313 -228.129085) (xy 363.835247 -228.129085) (xy 363.886542 -228.13721)
			(xy 363.935935 -228.153258) (xy 363.982209 -228.176836) (xy 364.024225 -228.207362) (xy 364.060948 -228.244085)
			(xy 364.091474 -228.286101) (xy 364.115052 -228.332375) (xy 364.1311 -228.381768) (xy 364.139225 -228.433063)
			(xy 364.139734 -228.45903) (xy 364.139225 -228.484997) (xy 365.358935 -228.484997) (xy 365.358935 -228.433063)
			(xy 365.36706 -228.381768) (xy 365.383108 -228.332375) (xy 365.406686 -228.286101) (xy 365.437212 -228.244085)
			(xy 365.473935 -228.207362) (xy 365.515951 -228.176836) (xy 365.562225 -228.153258) (xy 365.611618 -228.13721)
			(xy 365.662913 -228.129085) (xy 365.714847 -228.129085) (xy 365.766142 -228.13721) (xy 365.815535 -228.153258)
			(xy 365.861809 -228.176836) (xy 365.903825 -228.207362) (xy 365.940548 -228.244085) (xy 365.971074 -228.286101)
			(xy 365.994652 -228.332375) (xy 366.0107 -228.381768) (xy 366.018825 -228.433063) (xy 366.019334 -228.45903)
			(xy 366.018825 -228.484997) (xy 367.238535 -228.484997) (xy 367.238535 -228.433063) (xy 367.24666 -228.381768)
			(xy 367.262708 -228.332375) (xy 367.286286 -228.286101) (xy 367.316812 -228.244085) (xy 367.353535 -228.207362)
			(xy 367.395551 -228.176836) (xy 367.441825 -228.153258) (xy 367.491218 -228.13721) (xy 367.542513 -228.129085)
			(xy 367.594447 -228.129085) (xy 367.645742 -228.13721) (xy 367.695135 -228.153258) (xy 367.741409 -228.176836)
			(xy 367.783425 -228.207362) (xy 367.820148 -228.244085) (xy 367.850674 -228.286101) (xy 367.874252 -228.332375)
			(xy 367.8903 -228.381768) (xy 367.898425 -228.433063) (xy 367.898934 -228.45903) (xy 367.898425 -228.484997)
			(xy 368.178335 -228.484997) (xy 368.178335 -228.433063) (xy 368.18646 -228.381768) (xy 368.202508 -228.332375)
			(xy 368.226086 -228.286101) (xy 368.256612 -228.244085) (xy 368.293335 -228.207362) (xy 368.335351 -228.176836)
			(xy 368.381625 -228.153258) (xy 368.431018 -228.13721) (xy 368.482313 -228.129085) (xy 368.534247 -228.129085)
			(xy 368.585542 -228.13721) (xy 368.634935 -228.153258) (xy 368.681209 -228.176836) (xy 368.723225 -228.207362)
			(xy 368.759948 -228.244085) (xy 368.790474 -228.286101) (xy 368.814052 -228.332375) (xy 368.8301 -228.381768)
			(xy 368.838225 -228.433063) (xy 368.838734 -228.45903) (xy 368.838225 -228.484997) (xy 369.118135 -228.484997)
			(xy 369.118135 -228.433063) (xy 369.12626 -228.381768) (xy 369.142308 -228.332375) (xy 369.165886 -228.286101)
			(xy 369.196412 -228.244085) (xy 369.233135 -228.207362) (xy 369.275151 -228.176836) (xy 369.321425 -228.153258)
			(xy 369.370818 -228.13721) (xy 369.422113 -228.129085) (xy 369.474047 -228.129085) (xy 369.525342 -228.13721)
			(xy 369.574735 -228.153258) (xy 369.621009 -228.176836) (xy 369.663025 -228.207362) (xy 369.699748 -228.244085)
			(xy 369.730274 -228.286101) (xy 369.753852 -228.332375) (xy 369.7699 -228.381768) (xy 369.778025 -228.433063)
			(xy 369.778534 -228.45903) (xy 369.778025 -228.484997) (xy 370.057935 -228.484997) (xy 370.057935 -228.433063)
			(xy 370.06606 -228.381768) (xy 370.082108 -228.332375) (xy 370.105686 -228.286101) (xy 370.136212 -228.244085)
			(xy 370.172935 -228.207362) (xy 370.214951 -228.176836) (xy 370.261225 -228.153258) (xy 370.310618 -228.13721)
			(xy 370.361913 -228.129085) (xy 370.413847 -228.129085) (xy 370.465142 -228.13721) (xy 370.514535 -228.153258)
			(xy 370.560809 -228.176836) (xy 370.602825 -228.207362) (xy 370.639548 -228.244085) (xy 370.670074 -228.286101)
			(xy 370.693652 -228.332375) (xy 370.7097 -228.381768) (xy 370.717825 -228.433063) (xy 370.718334 -228.45903)
			(xy 370.717825 -228.484997) (xy 370.997735 -228.484997) (xy 370.997735 -228.433063) (xy 371.00586 -228.381768)
			(xy 371.021908 -228.332375) (xy 371.045486 -228.286101) (xy 371.076012 -228.244085) (xy 371.112735 -228.207362)
			(xy 371.154751 -228.176836) (xy 371.201025 -228.153258) (xy 371.250418 -228.13721) (xy 371.301713 -228.129085)
			(xy 371.353647 -228.129085) (xy 371.404942 -228.13721) (xy 371.454335 -228.153258) (xy 371.500609 -228.176836)
			(xy 371.542625 -228.207362) (xy 371.579348 -228.244085) (xy 371.609874 -228.286101) (xy 371.633452 -228.332375)
			(xy 371.6495 -228.381768) (xy 371.657625 -228.433063) (xy 371.658134 -228.45903) (xy 371.657625 -228.484997)
			(xy 371.937535 -228.484997) (xy 371.937535 -228.433063) (xy 371.94566 -228.381768) (xy 371.961708 -228.332375)
			(xy 371.985286 -228.286101) (xy 372.015812 -228.244085) (xy 372.052535 -228.207362) (xy 372.094551 -228.176836)
			(xy 372.140825 -228.153258) (xy 372.190218 -228.13721) (xy 372.241513 -228.129085) (xy 372.293447 -228.129085)
			(xy 372.344742 -228.13721) (xy 372.394135 -228.153258) (xy 372.440409 -228.176836) (xy 372.482425 -228.207362)
			(xy 372.519148 -228.244085) (xy 372.549674 -228.286101) (xy 372.573252 -228.332375) (xy 372.5893 -228.381768)
			(xy 372.597425 -228.433063) (xy 372.597934 -228.45903) (xy 372.597425 -228.484997) (xy 372.877335 -228.484997)
			(xy 372.877335 -228.433063) (xy 372.88546 -228.381768) (xy 372.901508 -228.332375) (xy 372.925086 -228.286101)
			(xy 372.955612 -228.244085) (xy 372.992335 -228.207362) (xy 373.034351 -228.176836) (xy 373.080625 -228.153258)
			(xy 373.130018 -228.13721) (xy 373.181313 -228.129085) (xy 373.233247 -228.129085) (xy 373.284542 -228.13721)
			(xy 373.333935 -228.153258) (xy 373.380209 -228.176836) (xy 373.422225 -228.207362) (xy 373.458948 -228.244085)
			(xy 373.489474 -228.286101) (xy 373.513052 -228.332375) (xy 373.5291 -228.381768) (xy 373.537225 -228.433063)
			(xy 373.537734 -228.45903) (xy 373.537225 -228.484997) (xy 373.817389 -228.484997) (xy 373.817389 -228.433063)
			(xy 373.825514 -228.381768) (xy 373.841562 -228.332375) (xy 373.86514 -228.286101) (xy 373.895666 -228.244085)
			(xy 373.932389 -228.207362) (xy 373.974405 -228.176836) (xy 374.020679 -228.153258) (xy 374.070072 -228.13721)
			(xy 374.121367 -228.129085) (xy 374.173301 -228.129085) (xy 374.224596 -228.13721) (xy 374.273989 -228.153258)
			(xy 374.320263 -228.176836) (xy 374.362279 -228.207362) (xy 374.399002 -228.244085) (xy 374.429528 -228.286101)
			(xy 374.453106 -228.332375) (xy 374.469154 -228.381768) (xy 374.477279 -228.433063) (xy 374.477788 -228.45903)
			(xy 374.477279 -228.484997) (xy 374.756935 -228.484997) (xy 374.756935 -228.433063) (xy 374.76506 -228.381768)
			(xy 374.781108 -228.332375) (xy 374.804686 -228.286101) (xy 374.835212 -228.244085) (xy 374.871935 -228.207362)
			(xy 374.913951 -228.176836) (xy 374.960225 -228.153258) (xy 375.009618 -228.13721) (xy 375.060913 -228.129085)
			(xy 375.112847 -228.129085) (xy 375.164142 -228.13721) (xy 375.213535 -228.153258) (xy 375.259809 -228.176836)
			(xy 375.301825 -228.207362) (xy 375.338548 -228.244085) (xy 375.369074 -228.286101) (xy 375.392652 -228.332375)
			(xy 375.4087 -228.381768) (xy 375.416825 -228.433063) (xy 375.417334 -228.45903) (xy 375.416825 -228.484997)
			(xy 375.4087 -228.536292) (xy 375.392652 -228.585685) (xy 375.369074 -228.631959) (xy 375.338548 -228.673975)
			(xy 375.301825 -228.710698) (xy 375.259809 -228.741224) (xy 375.213535 -228.764802) (xy 375.164142 -228.78085)
			(xy 375.112847 -228.788975) (xy 375.060913 -228.788975) (xy 375.009618 -228.78085) (xy 374.960225 -228.764802)
			(xy 374.913951 -228.741224) (xy 374.871935 -228.710698) (xy 374.835212 -228.673975) (xy 374.804686 -228.631959)
			(xy 374.781108 -228.585685) (xy 374.76506 -228.536292) (xy 374.756935 -228.484997) (xy 374.477279 -228.484997)
			(xy 374.469154 -228.536292) (xy 374.453106 -228.585685) (xy 374.429528 -228.631959) (xy 374.399002 -228.673975)
			(xy 374.362279 -228.710698) (xy 374.320263 -228.741224) (xy 374.273989 -228.764802) (xy 374.224596 -228.78085)
			(xy 374.173301 -228.788975) (xy 374.121367 -228.788975) (xy 374.070072 -228.78085) (xy 374.020679 -228.764802)
			(xy 373.974405 -228.741224) (xy 373.932389 -228.710698) (xy 373.895666 -228.673975) (xy 373.86514 -228.631959)
			(xy 373.841562 -228.585685) (xy 373.825514 -228.536292) (xy 373.817389 -228.484997) (xy 373.537225 -228.484997)
			(xy 373.5291 -228.536292) (xy 373.513052 -228.585685) (xy 373.489474 -228.631959) (xy 373.458948 -228.673975)
			(xy 373.422225 -228.710698) (xy 373.380209 -228.741224) (xy 373.333935 -228.764802) (xy 373.284542 -228.78085)
			(xy 373.233247 -228.788975) (xy 373.181313 -228.788975) (xy 373.130018 -228.78085) (xy 373.080625 -228.764802)
			(xy 373.034351 -228.741224) (xy 372.992335 -228.710698) (xy 372.955612 -228.673975) (xy 372.925086 -228.631959)
			(xy 372.901508 -228.585685) (xy 372.88546 -228.536292) (xy 372.877335 -228.484997) (xy 372.597425 -228.484997)
			(xy 372.5893 -228.536292) (xy 372.573252 -228.585685) (xy 372.549674 -228.631959) (xy 372.519148 -228.673975)
			(xy 372.482425 -228.710698) (xy 372.440409 -228.741224) (xy 372.394135 -228.764802) (xy 372.344742 -228.78085)
			(xy 372.293447 -228.788975) (xy 372.241513 -228.788975) (xy 372.190218 -228.78085) (xy 372.140825 -228.764802)
			(xy 372.094551 -228.741224) (xy 372.052535 -228.710698) (xy 372.015812 -228.673975) (xy 371.985286 -228.631959)
			(xy 371.961708 -228.585685) (xy 371.94566 -228.536292) (xy 371.937535 -228.484997) (xy 371.657625 -228.484997)
			(xy 371.6495 -228.536292) (xy 371.633452 -228.585685) (xy 371.609874 -228.631959) (xy 371.579348 -228.673975)
			(xy 371.542625 -228.710698) (xy 371.500609 -228.741224) (xy 371.454335 -228.764802) (xy 371.404942 -228.78085)
			(xy 371.353647 -228.788975) (xy 371.301713 -228.788975) (xy 371.250418 -228.78085) (xy 371.201025 -228.764802)
			(xy 371.154751 -228.741224) (xy 371.112735 -228.710698) (xy 371.076012 -228.673975) (xy 371.045486 -228.631959)
			(xy 371.021908 -228.585685) (xy 371.00586 -228.536292) (xy 370.997735 -228.484997) (xy 370.717825 -228.484997)
			(xy 370.7097 -228.536292) (xy 370.693652 -228.585685) (xy 370.670074 -228.631959) (xy 370.639548 -228.673975)
			(xy 370.602825 -228.710698) (xy 370.560809 -228.741224) (xy 370.514535 -228.764802) (xy 370.465142 -228.78085)
			(xy 370.413847 -228.788975) (xy 370.361913 -228.788975) (xy 370.310618 -228.78085) (xy 370.261225 -228.764802)
			(xy 370.214951 -228.741224) (xy 370.172935 -228.710698) (xy 370.136212 -228.673975) (xy 370.105686 -228.631959)
			(xy 370.082108 -228.585685) (xy 370.06606 -228.536292) (xy 370.057935 -228.484997) (xy 369.778025 -228.484997)
			(xy 369.7699 -228.536292) (xy 369.753852 -228.585685) (xy 369.730274 -228.631959) (xy 369.699748 -228.673975)
			(xy 369.663025 -228.710698) (xy 369.621009 -228.741224) (xy 369.574735 -228.764802) (xy 369.525342 -228.78085)
			(xy 369.474047 -228.788975) (xy 369.422113 -228.788975) (xy 369.370818 -228.78085) (xy 369.321425 -228.764802)
			(xy 369.275151 -228.741224) (xy 369.233135 -228.710698) (xy 369.196412 -228.673975) (xy 369.165886 -228.631959)
			(xy 369.142308 -228.585685) (xy 369.12626 -228.536292) (xy 369.118135 -228.484997) (xy 368.838225 -228.484997)
			(xy 368.8301 -228.536292) (xy 368.814052 -228.585685) (xy 368.790474 -228.631959) (xy 368.759948 -228.673975)
			(xy 368.723225 -228.710698) (xy 368.681209 -228.741224) (xy 368.634935 -228.764802) (xy 368.585542 -228.78085)
			(xy 368.534247 -228.788975) (xy 368.482313 -228.788975) (xy 368.431018 -228.78085) (xy 368.381625 -228.764802)
			(xy 368.335351 -228.741224) (xy 368.293335 -228.710698) (xy 368.256612 -228.673975) (xy 368.226086 -228.631959)
			(xy 368.202508 -228.585685) (xy 368.18646 -228.536292) (xy 368.178335 -228.484997) (xy 367.898425 -228.484997)
			(xy 367.8903 -228.536292) (xy 367.874252 -228.585685) (xy 367.850674 -228.631959) (xy 367.820148 -228.673975)
			(xy 367.783425 -228.710698) (xy 367.741409 -228.741224) (xy 367.695135 -228.764802) (xy 367.645742 -228.78085)
			(xy 367.594447 -228.788975) (xy 367.542513 -228.788975) (xy 367.491218 -228.78085) (xy 367.441825 -228.764802)
			(xy 367.395551 -228.741224) (xy 367.353535 -228.710698) (xy 367.316812 -228.673975) (xy 367.286286 -228.631959)
			(xy 367.262708 -228.585685) (xy 367.24666 -228.536292) (xy 367.238535 -228.484997) (xy 366.018825 -228.484997)
			(xy 366.0107 -228.536292) (xy 365.994652 -228.585685) (xy 365.971074 -228.631959) (xy 365.940548 -228.673975)
			(xy 365.903825 -228.710698) (xy 365.861809 -228.741224) (xy 365.815535 -228.764802) (xy 365.766142 -228.78085)
			(xy 365.714847 -228.788975) (xy 365.662913 -228.788975) (xy 365.611618 -228.78085) (xy 365.562225 -228.764802)
			(xy 365.515951 -228.741224) (xy 365.473935 -228.710698) (xy 365.437212 -228.673975) (xy 365.406686 -228.631959)
			(xy 365.383108 -228.585685) (xy 365.36706 -228.536292) (xy 365.358935 -228.484997) (xy 364.139225 -228.484997)
			(xy 364.1311 -228.536292) (xy 364.115052 -228.585685) (xy 364.091474 -228.631959) (xy 364.060948 -228.673975)
			(xy 364.024225 -228.710698) (xy 363.982209 -228.741224) (xy 363.935935 -228.764802) (xy 363.886542 -228.78085)
			(xy 363.835247 -228.788975) (xy 363.783313 -228.788975) (xy 363.732018 -228.78085) (xy 363.682625 -228.764802)
			(xy 363.636351 -228.741224) (xy 363.594335 -228.710698) (xy 363.557612 -228.673975) (xy 363.527086 -228.631959)
			(xy 363.503508 -228.585685) (xy 363.48746 -228.536292) (xy 363.479335 -228.484997) (xy 362.259625 -228.484997)
			(xy 362.2515 -228.536292) (xy 362.235452 -228.585685) (xy 362.211874 -228.631959) (xy 362.181348 -228.673975)
			(xy 362.144625 -228.710698) (xy 362.102609 -228.741224) (xy 362.056335 -228.764802) (xy 362.006942 -228.78085)
			(xy 361.955647 -228.788975) (xy 361.903713 -228.788975) (xy 361.852418 -228.78085) (xy 361.803025 -228.764802)
			(xy 361.756751 -228.741224) (xy 361.714735 -228.710698) (xy 361.678012 -228.673975) (xy 361.647486 -228.631959)
			(xy 361.623908 -228.585685) (xy 361.60786 -228.536292) (xy 361.599735 -228.484997) (xy 361.319825 -228.484997)
			(xy 361.3117 -228.536292) (xy 361.295652 -228.585685) (xy 361.272074 -228.631959) (xy 361.241548 -228.673975)
			(xy 361.204825 -228.710698) (xy 361.162809 -228.741224) (xy 361.116535 -228.764802) (xy 361.067142 -228.78085)
			(xy 361.015847 -228.788975) (xy 360.963913 -228.788975) (xy 360.912618 -228.78085) (xy 360.863225 -228.764802)
			(xy 360.816951 -228.741224) (xy 360.774935 -228.710698) (xy 360.738212 -228.673975) (xy 360.707686 -228.631959)
			(xy 360.684108 -228.585685) (xy 360.66806 -228.536292) (xy 360.659935 -228.484997) (xy 360.380025 -228.484997)
			(xy 360.3719 -228.536292) (xy 360.355852 -228.585685) (xy 360.332274 -228.631959) (xy 360.301748 -228.673975)
			(xy 360.265025 -228.710698) (xy 360.223009 -228.741224) (xy 360.176735 -228.764802) (xy 360.127342 -228.78085)
			(xy 360.076047 -228.788975) (xy 360.024113 -228.788975) (xy 359.972818 -228.78085) (xy 359.923425 -228.764802)
			(xy 359.877151 -228.741224) (xy 359.835135 -228.710698) (xy 359.798412 -228.673975) (xy 359.767886 -228.631959)
			(xy 359.744308 -228.585685) (xy 359.72826 -228.536292) (xy 359.720135 -228.484997) (xy 359.440479 -228.484997)
			(xy 359.432354 -228.536292) (xy 359.416306 -228.585685) (xy 359.392728 -228.631959) (xy 359.362202 -228.673975)
			(xy 359.325479 -228.710698) (xy 359.283463 -228.741224) (xy 359.237189 -228.764802) (xy 359.187796 -228.78085)
			(xy 359.136501 -228.788975) (xy 359.084567 -228.788975) (xy 359.033272 -228.78085) (xy 358.983879 -228.764802)
			(xy 358.937605 -228.741224) (xy 358.895589 -228.710698) (xy 358.858866 -228.673975) (xy 358.82834 -228.631959)
			(xy 358.804762 -228.585685) (xy 358.788714 -228.536292) (xy 358.780589 -228.484997) (xy 358.500436 -228.484997)
			(xy 358.492316 -228.536264) (xy 358.476267 -228.585658) (xy 358.452687 -228.631933) (xy 358.422159 -228.673949)
			(xy 358.385434 -228.710672) (xy 358.343416 -228.741198) (xy 358.29714 -228.764774) (xy 358.247745 -228.780821)
			(xy 358.196448 -228.788943) (xy 358.17048 -228.789484) (xy 358.148168 -228.789115) (xy 358.103948 -228.783125)
			(xy 358.082342 -228.777546) (xy 358.073472 -228.775443) (xy 358.055318 -228.776964) (xy 358.038847 -228.784745)
			(xy 358.026144 -228.797802) (xy 358.022144 -228.805994) (xy 358.00245 -228.849415) (xy 357.954839 -228.932027)
			(xy 357.927148 -228.97084) (xy 357.922084 -228.978397) (xy 357.917142 -228.99589) (xy 357.918597 -229.014011)
			(xy 357.926268 -229.030491) (xy 357.932482 -229.037134) (xy 357.950855 -229.055899) (xy 357.982015 -229.09817)
			(xy 358.006093 -229.14484) (xy 358.022483 -229.194732) (xy 358.03077 -229.246588) (xy 358.031288 -229.272846)
			(xy 358.030807 -229.298498) (xy 358.030758 -229.298813) (xy 358.310689 -229.298813) (xy 358.310689 -229.246879)
			(xy 358.318814 -229.195584) (xy 358.334862 -229.146191) (xy 358.35844 -229.099917) (xy 358.388966 -229.057901)
			(xy 358.425689 -229.021178) (xy 358.467705 -228.990652) (xy 358.513979 -228.967074) (xy 358.563372 -228.951026)
			(xy 358.614667 -228.942901) (xy 358.666601 -228.942901) (xy 358.717896 -228.951026) (xy 358.767289 -228.967074)
			(xy 358.813563 -228.990652) (xy 358.855579 -229.021178) (xy 358.892302 -229.057901) (xy 358.922828 -229.099917)
			(xy 358.946406 -229.146191) (xy 358.962454 -229.195584) (xy 358.970579 -229.246879) (xy 358.971088 -229.272846)
			(xy 358.970579 -229.298813) (xy 359.250235 -229.298813) (xy 359.250235 -229.246879) (xy 359.25836 -229.195584)
			(xy 359.274408 -229.146191) (xy 359.297986 -229.099917) (xy 359.328512 -229.057901) (xy 359.365235 -229.021178)
			(xy 359.407251 -228.990652) (xy 359.453525 -228.967074) (xy 359.502918 -228.951026) (xy 359.554213 -228.942901)
			(xy 359.606147 -228.942901) (xy 359.657442 -228.951026) (xy 359.706835 -228.967074) (xy 359.753109 -228.990652)
			(xy 359.795125 -229.021178) (xy 359.831848 -229.057901) (xy 359.862374 -229.099917) (xy 359.885952 -229.146191)
			(xy 359.902 -229.195584) (xy 359.910125 -229.246879) (xy 359.910634 -229.272846) (xy 359.910125 -229.298813)
			(xy 360.190289 -229.298813) (xy 360.190289 -229.246879) (xy 360.198414 -229.195584) (xy 360.214462 -229.146191)
			(xy 360.23804 -229.099917) (xy 360.268566 -229.057901) (xy 360.305289 -229.021178) (xy 360.347305 -228.990652)
			(xy 360.393579 -228.967074) (xy 360.442972 -228.951026) (xy 360.494267 -228.942901) (xy 360.546201 -228.942901)
			(xy 360.597496 -228.951026) (xy 360.646889 -228.967074) (xy 360.693163 -228.990652) (xy 360.735179 -229.021178)
			(xy 360.771902 -229.057901) (xy 360.802428 -229.099917) (xy 360.826006 -229.146191) (xy 360.842054 -229.195584)
			(xy 360.850179 -229.246879) (xy 360.850688 -229.272846) (xy 360.850179 -229.298813) (xy 361.130089 -229.298813)
			(xy 361.130089 -229.246879) (xy 361.138214 -229.195584) (xy 361.154262 -229.146191) (xy 361.17784 -229.099917)
			(xy 361.208366 -229.057901) (xy 361.245089 -229.021178) (xy 361.287105 -228.990652) (xy 361.333379 -228.967074)
			(xy 361.382772 -228.951026) (xy 361.434067 -228.942901) (xy 361.486001 -228.942901) (xy 361.537296 -228.951026)
			(xy 361.586689 -228.967074) (xy 361.632963 -228.990652) (xy 361.674979 -229.021178) (xy 361.711702 -229.057901)
			(xy 361.742228 -229.099917) (xy 361.765806 -229.146191) (xy 361.781854 -229.195584) (xy 361.789979 -229.246879)
			(xy 361.790488 -229.272846) (xy 361.789979 -229.298813) (xy 362.069889 -229.298813) (xy 362.069889 -229.246879)
			(xy 362.078014 -229.195584) (xy 362.094062 -229.146191) (xy 362.11764 -229.099917) (xy 362.148166 -229.057901)
			(xy 362.184889 -229.021178) (xy 362.226905 -228.990652) (xy 362.273179 -228.967074) (xy 362.322572 -228.951026)
			(xy 362.373867 -228.942901) (xy 362.425801 -228.942901) (xy 362.477096 -228.951026) (xy 362.526489 -228.967074)
			(xy 362.572763 -228.990652) (xy 362.614779 -229.021178) (xy 362.651502 -229.057901) (xy 362.682028 -229.099917)
			(xy 362.705606 -229.146191) (xy 362.721654 -229.195584) (xy 362.729779 -229.246879) (xy 362.730288 -229.272846)
			(xy 362.729779 -229.298813) (xy 363.009689 -229.298813) (xy 363.009689 -229.246879) (xy 363.017814 -229.195584)
			(xy 363.033862 -229.146191) (xy 363.05744 -229.099917) (xy 363.087966 -229.057901) (xy 363.124689 -229.021178)
			(xy 363.166705 -228.990652) (xy 363.212979 -228.967074) (xy 363.262372 -228.951026) (xy 363.313667 -228.942901)
			(xy 363.365601 -228.942901) (xy 363.416896 -228.951026) (xy 363.466289 -228.967074) (xy 363.512563 -228.990652)
			(xy 363.554579 -229.021178) (xy 363.591302 -229.057901) (xy 363.621828 -229.099917) (xy 363.645406 -229.146191)
			(xy 363.661454 -229.195584) (xy 363.669579 -229.246879) (xy 363.670088 -229.272846) (xy 363.669579 -229.298813)
			(xy 363.949489 -229.298813) (xy 363.949489 -229.246879) (xy 363.957614 -229.195584) (xy 363.973662 -229.146191)
			(xy 363.99724 -229.099917) (xy 364.027766 -229.057901) (xy 364.064489 -229.021178) (xy 364.106505 -228.990652)
			(xy 364.152779 -228.967074) (xy 364.202172 -228.951026) (xy 364.253467 -228.942901) (xy 364.305401 -228.942901)
			(xy 364.356696 -228.951026) (xy 364.406089 -228.967074) (xy 364.452363 -228.990652) (xy 364.494379 -229.021178)
			(xy 364.531102 -229.057901) (xy 364.561628 -229.099917) (xy 364.585206 -229.146191) (xy 364.601254 -229.195584)
			(xy 364.609379 -229.246879) (xy 364.609888 -229.272846) (xy 364.609379 -229.298813) (xy 364.889289 -229.298813)
			(xy 364.889289 -229.246879) (xy 364.897414 -229.195584) (xy 364.913462 -229.146191) (xy 364.93704 -229.099917)
			(xy 364.967566 -229.057901) (xy 365.004289 -229.021178) (xy 365.046305 -228.990652) (xy 365.092579 -228.967074)
			(xy 365.141972 -228.951026) (xy 365.193267 -228.942901) (xy 365.245201 -228.942901) (xy 365.296496 -228.951026)
			(xy 365.345889 -228.967074) (xy 365.392163 -228.990652) (xy 365.434179 -229.021178) (xy 365.470902 -229.057901)
			(xy 365.501428 -229.099917) (xy 365.525006 -229.146191) (xy 365.541054 -229.195584) (xy 365.549179 -229.246879)
			(xy 365.549688 -229.272846) (xy 365.549179 -229.298813) (xy 365.829089 -229.298813) (xy 365.829089 -229.246879)
			(xy 365.837214 -229.195584) (xy 365.853262 -229.146191) (xy 365.87684 -229.099917) (xy 365.907366 -229.057901)
			(xy 365.944089 -229.021178) (xy 365.986105 -228.990652) (xy 366.032379 -228.967074) (xy 366.081772 -228.951026)
			(xy 366.133067 -228.942901) (xy 366.185001 -228.942901) (xy 366.236296 -228.951026) (xy 366.285689 -228.967074)
			(xy 366.331963 -228.990652) (xy 366.373979 -229.021178) (xy 366.410702 -229.057901) (xy 366.441228 -229.099917)
			(xy 366.464806 -229.146191) (xy 366.480854 -229.195584) (xy 366.488979 -229.246879) (xy 366.489488 -229.272846)
			(xy 366.488979 -229.298813) (xy 366.768889 -229.298813) (xy 366.768889 -229.246879) (xy 366.777014 -229.195584)
			(xy 366.793062 -229.146191) (xy 366.81664 -229.099917) (xy 366.847166 -229.057901) (xy 366.883889 -229.021178)
			(xy 366.925905 -228.990652) (xy 366.972179 -228.967074) (xy 367.021572 -228.951026) (xy 367.072867 -228.942901)
			(xy 367.124801 -228.942901) (xy 367.176096 -228.951026) (xy 367.225489 -228.967074) (xy 367.271763 -228.990652)
			(xy 367.313779 -229.021178) (xy 367.350502 -229.057901) (xy 367.381028 -229.099917) (xy 367.404606 -229.146191)
			(xy 367.420654 -229.195584) (xy 367.428779 -229.246879) (xy 367.429288 -229.272846) (xy 367.428779 -229.298813)
			(xy 367.708689 -229.298813) (xy 367.708689 -229.246879) (xy 367.716814 -229.195584) (xy 367.732862 -229.146191)
			(xy 367.75644 -229.099917) (xy 367.786966 -229.057901) (xy 367.823689 -229.021178) (xy 367.865705 -228.990652)
			(xy 367.911979 -228.967074) (xy 367.961372 -228.951026) (xy 368.012667 -228.942901) (xy 368.064601 -228.942901)
			(xy 368.115896 -228.951026) (xy 368.165289 -228.967074) (xy 368.211563 -228.990652) (xy 368.253579 -229.021178)
			(xy 368.290302 -229.057901) (xy 368.320828 -229.099917) (xy 368.344406 -229.146191) (xy 368.360454 -229.195584)
			(xy 368.368579 -229.246879) (xy 368.369088 -229.272846) (xy 368.368579 -229.298813) (xy 368.648489 -229.298813)
			(xy 368.648489 -229.246879) (xy 368.656614 -229.195584) (xy 368.672662 -229.146191) (xy 368.69624 -229.099917)
			(xy 368.726766 -229.057901) (xy 368.763489 -229.021178) (xy 368.805505 -228.990652) (xy 368.851779 -228.967074)
			(xy 368.901172 -228.951026) (xy 368.952467 -228.942901) (xy 369.004401 -228.942901) (xy 369.055696 -228.951026)
			(xy 369.105089 -228.967074) (xy 369.151363 -228.990652) (xy 369.193379 -229.021178) (xy 369.230102 -229.057901)
			(xy 369.260628 -229.099917) (xy 369.284206 -229.146191) (xy 369.300254 -229.195584) (xy 369.308379 -229.246879)
			(xy 369.308888 -229.272846) (xy 369.308379 -229.298813) (xy 369.588289 -229.298813) (xy 369.588289 -229.246879)
			(xy 369.596414 -229.195584) (xy 369.612462 -229.146191) (xy 369.63604 -229.099917) (xy 369.666566 -229.057901)
			(xy 369.703289 -229.021178) (xy 369.745305 -228.990652) (xy 369.791579 -228.967074) (xy 369.840972 -228.951026)
			(xy 369.892267 -228.942901) (xy 369.944201 -228.942901) (xy 369.995496 -228.951026) (xy 370.044889 -228.967074)
			(xy 370.091163 -228.990652) (xy 370.133179 -229.021178) (xy 370.169902 -229.057901) (xy 370.200428 -229.099917)
			(xy 370.224006 -229.146191) (xy 370.240054 -229.195584) (xy 370.248179 -229.246879) (xy 370.248688 -229.272846)
			(xy 370.248179 -229.298813) (xy 370.527835 -229.298813) (xy 370.527835 -229.246879) (xy 370.53596 -229.195584)
			(xy 370.552008 -229.146191) (xy 370.575586 -229.099917) (xy 370.606112 -229.057901) (xy 370.642835 -229.021178)
			(xy 370.684851 -228.990652) (xy 370.731125 -228.967074) (xy 370.780518 -228.951026) (xy 370.831813 -228.942901)
			(xy 370.883747 -228.942901) (xy 370.935042 -228.951026) (xy 370.984435 -228.967074) (xy 371.030709 -228.990652)
			(xy 371.072725 -229.021178) (xy 371.109448 -229.057901) (xy 371.139974 -229.099917) (xy 371.163552 -229.146191)
			(xy 371.1796 -229.195584) (xy 371.187725 -229.246879) (xy 371.188234 -229.272846) (xy 371.187725 -229.298813)
			(xy 371.467889 -229.298813) (xy 371.467889 -229.246879) (xy 371.476014 -229.195584) (xy 371.492062 -229.146191)
			(xy 371.51564 -229.099917) (xy 371.546166 -229.057901) (xy 371.582889 -229.021178) (xy 371.624905 -228.990652)
			(xy 371.671179 -228.967074) (xy 371.720572 -228.951026) (xy 371.771867 -228.942901) (xy 371.823801 -228.942901)
			(xy 371.875096 -228.951026) (xy 371.924489 -228.967074) (xy 371.970763 -228.990652) (xy 372.012779 -229.021178)
			(xy 372.049502 -229.057901) (xy 372.080028 -229.099917) (xy 372.103606 -229.146191) (xy 372.119654 -229.195584)
			(xy 372.127779 -229.246879) (xy 372.128288 -229.272846) (xy 372.127779 -229.298813) (xy 372.407689 -229.298813)
			(xy 372.407689 -229.246879) (xy 372.415814 -229.195584) (xy 372.431862 -229.146191) (xy 372.45544 -229.099917)
			(xy 372.485966 -229.057901) (xy 372.522689 -229.021178) (xy 372.564705 -228.990652) (xy 372.610979 -228.967074)
			(xy 372.660372 -228.951026) (xy 372.711667 -228.942901) (xy 372.763601 -228.942901) (xy 372.814896 -228.951026)
			(xy 372.864289 -228.967074) (xy 372.910563 -228.990652) (xy 372.952579 -229.021178) (xy 372.989302 -229.057901)
			(xy 373.019828 -229.099917) (xy 373.043406 -229.146191) (xy 373.059454 -229.195584) (xy 373.067579 -229.246879)
			(xy 373.068088 -229.272846) (xy 373.067579 -229.298813) (xy 373.347489 -229.298813) (xy 373.347489 -229.246879)
			(xy 373.355614 -229.195584) (xy 373.371662 -229.146191) (xy 373.39524 -229.099917) (xy 373.425766 -229.057901)
			(xy 373.462489 -229.021178) (xy 373.504505 -228.990652) (xy 373.550779 -228.967074) (xy 373.600172 -228.951026)
			(xy 373.651467 -228.942901) (xy 373.703401 -228.942901) (xy 373.754696 -228.951026) (xy 373.804089 -228.967074)
			(xy 373.850363 -228.990652) (xy 373.892379 -229.021178) (xy 373.929102 -229.057901) (xy 373.959628 -229.099917)
			(xy 373.983206 -229.146191) (xy 373.999254 -229.195584) (xy 374.007379 -229.246879) (xy 374.007888 -229.272846)
			(xy 374.007379 -229.298813) (xy 374.287289 -229.298813) (xy 374.287289 -229.246879) (xy 374.295414 -229.195584)
			(xy 374.311462 -229.146191) (xy 374.33504 -229.099917) (xy 374.365566 -229.057901) (xy 374.402289 -229.021178)
			(xy 374.444305 -228.990652) (xy 374.490579 -228.967074) (xy 374.539972 -228.951026) (xy 374.591267 -228.942901)
			(xy 374.643201 -228.942901) (xy 374.694496 -228.951026) (xy 374.743889 -228.967074) (xy 374.790163 -228.990652)
			(xy 374.832179 -229.021178) (xy 374.868902 -229.057901) (xy 374.899428 -229.099917) (xy 374.923006 -229.146191)
			(xy 374.939054 -229.195584) (xy 374.947179 -229.246879) (xy 374.947688 -229.272846) (xy 374.947179 -229.298813)
			(xy 375.227089 -229.298813) (xy 375.227089 -229.246879) (xy 375.235214 -229.195584) (xy 375.251262 -229.146191)
			(xy 375.27484 -229.099917) (xy 375.305366 -229.057901) (xy 375.342089 -229.021178) (xy 375.384105 -228.990652)
			(xy 375.430379 -228.967074) (xy 375.479772 -228.951026) (xy 375.531067 -228.942901) (xy 375.583001 -228.942901)
			(xy 375.634296 -228.951026) (xy 375.683689 -228.967074) (xy 375.729963 -228.990652) (xy 375.771979 -229.021178)
			(xy 375.808702 -229.057901) (xy 375.839228 -229.099917) (xy 375.862806 -229.146191) (xy 375.878854 -229.195584)
			(xy 375.886979 -229.246879) (xy 375.887488 -229.272846) (xy 375.886979 -229.298813) (xy 375.878854 -229.350108)
			(xy 375.862806 -229.399501) (xy 375.839228 -229.445775) (xy 375.808702 -229.487791) (xy 375.771979 -229.524514)
			(xy 375.729963 -229.55504) (xy 375.683689 -229.578618) (xy 375.634296 -229.594666) (xy 375.583001 -229.602791)
			(xy 375.531067 -229.602791) (xy 375.479772 -229.594666) (xy 375.430379 -229.578618) (xy 375.384105 -229.55504)
			(xy 375.342089 -229.524514) (xy 375.305366 -229.487791) (xy 375.27484 -229.445775) (xy 375.251262 -229.399501)
			(xy 375.235214 -229.350108) (xy 375.227089 -229.298813) (xy 374.947179 -229.298813) (xy 374.939054 -229.350108)
			(xy 374.923006 -229.399501) (xy 374.899428 -229.445775) (xy 374.868902 -229.487791) (xy 374.832179 -229.524514)
			(xy 374.790163 -229.55504) (xy 374.743889 -229.578618) (xy 374.694496 -229.594666) (xy 374.643201 -229.602791)
			(xy 374.591267 -229.602791) (xy 374.539972 -229.594666) (xy 374.490579 -229.578618) (xy 374.444305 -229.55504)
			(xy 374.402289 -229.524514) (xy 374.365566 -229.487791) (xy 374.33504 -229.445775) (xy 374.311462 -229.399501)
			(xy 374.295414 -229.350108) (xy 374.287289 -229.298813) (xy 374.007379 -229.298813) (xy 373.999254 -229.350108)
			(xy 373.983206 -229.399501) (xy 373.959628 -229.445775) (xy 373.929102 -229.487791) (xy 373.892379 -229.524514)
			(xy 373.850363 -229.55504) (xy 373.804089 -229.578618) (xy 373.754696 -229.594666) (xy 373.703401 -229.602791)
			(xy 373.651467 -229.602791) (xy 373.600172 -229.594666) (xy 373.550779 -229.578618) (xy 373.504505 -229.55504)
			(xy 373.462489 -229.524514) (xy 373.425766 -229.487791) (xy 373.39524 -229.445775) (xy 373.371662 -229.399501)
			(xy 373.355614 -229.350108) (xy 373.347489 -229.298813) (xy 373.067579 -229.298813) (xy 373.059454 -229.350108)
			(xy 373.043406 -229.399501) (xy 373.019828 -229.445775) (xy 372.989302 -229.487791) (xy 372.952579 -229.524514)
			(xy 372.910563 -229.55504) (xy 372.864289 -229.578618) (xy 372.814896 -229.594666) (xy 372.763601 -229.602791)
			(xy 372.711667 -229.602791) (xy 372.660372 -229.594666) (xy 372.610979 -229.578618) (xy 372.564705 -229.55504)
			(xy 372.522689 -229.524514) (xy 372.485966 -229.487791) (xy 372.45544 -229.445775) (xy 372.431862 -229.399501)
			(xy 372.415814 -229.350108) (xy 372.407689 -229.298813) (xy 372.127779 -229.298813) (xy 372.119654 -229.350108)
			(xy 372.103606 -229.399501) (xy 372.080028 -229.445775) (xy 372.049502 -229.487791) (xy 372.012779 -229.524514)
			(xy 371.970763 -229.55504) (xy 371.924489 -229.578618) (xy 371.875096 -229.594666) (xy 371.823801 -229.602791)
			(xy 371.771867 -229.602791) (xy 371.720572 -229.594666) (xy 371.671179 -229.578618) (xy 371.624905 -229.55504)
			(xy 371.582889 -229.524514) (xy 371.546166 -229.487791) (xy 371.51564 -229.445775) (xy 371.492062 -229.399501)
			(xy 371.476014 -229.350108) (xy 371.467889 -229.298813) (xy 371.187725 -229.298813) (xy 371.1796 -229.350108)
			(xy 371.163552 -229.399501) (xy 371.139974 -229.445775) (xy 371.109448 -229.487791) (xy 371.072725 -229.524514)
			(xy 371.030709 -229.55504) (xy 370.984435 -229.578618) (xy 370.935042 -229.594666) (xy 370.883747 -229.602791)
			(xy 370.831813 -229.602791) (xy 370.780518 -229.594666) (xy 370.731125 -229.578618) (xy 370.684851 -229.55504)
			(xy 370.642835 -229.524514) (xy 370.606112 -229.487791) (xy 370.575586 -229.445775) (xy 370.552008 -229.399501)
			(xy 370.53596 -229.350108) (xy 370.527835 -229.298813) (xy 370.248179 -229.298813) (xy 370.240054 -229.350108)
			(xy 370.224006 -229.399501) (xy 370.200428 -229.445775) (xy 370.169902 -229.487791) (xy 370.133179 -229.524514)
			(xy 370.091163 -229.55504) (xy 370.044889 -229.578618) (xy 369.995496 -229.594666) (xy 369.944201 -229.602791)
			(xy 369.892267 -229.602791) (xy 369.840972 -229.594666) (xy 369.791579 -229.578618) (xy 369.745305 -229.55504)
			(xy 369.703289 -229.524514) (xy 369.666566 -229.487791) (xy 369.63604 -229.445775) (xy 369.612462 -229.399501)
			(xy 369.596414 -229.350108) (xy 369.588289 -229.298813) (xy 369.308379 -229.298813) (xy 369.300254 -229.350108)
			(xy 369.284206 -229.399501) (xy 369.260628 -229.445775) (xy 369.230102 -229.487791) (xy 369.193379 -229.524514)
			(xy 369.151363 -229.55504) (xy 369.105089 -229.578618) (xy 369.055696 -229.594666) (xy 369.004401 -229.602791)
			(xy 368.952467 -229.602791) (xy 368.901172 -229.594666) (xy 368.851779 -229.578618) (xy 368.805505 -229.55504)
			(xy 368.763489 -229.524514) (xy 368.726766 -229.487791) (xy 368.69624 -229.445775) (xy 368.672662 -229.399501)
			(xy 368.656614 -229.350108) (xy 368.648489 -229.298813) (xy 368.368579 -229.298813) (xy 368.360454 -229.350108)
			(xy 368.344406 -229.399501) (xy 368.320828 -229.445775) (xy 368.290302 -229.487791) (xy 368.253579 -229.524514)
			(xy 368.211563 -229.55504) (xy 368.165289 -229.578618) (xy 368.115896 -229.594666) (xy 368.064601 -229.602791)
			(xy 368.012667 -229.602791) (xy 367.961372 -229.594666) (xy 367.911979 -229.578618) (xy 367.865705 -229.55504)
			(xy 367.823689 -229.524514) (xy 367.786966 -229.487791) (xy 367.75644 -229.445775) (xy 367.732862 -229.399501)
			(xy 367.716814 -229.350108) (xy 367.708689 -229.298813) (xy 367.428779 -229.298813) (xy 367.420654 -229.350108)
			(xy 367.404606 -229.399501) (xy 367.381028 -229.445775) (xy 367.350502 -229.487791) (xy 367.313779 -229.524514)
			(xy 367.271763 -229.55504) (xy 367.225489 -229.578618) (xy 367.176096 -229.594666) (xy 367.124801 -229.602791)
			(xy 367.072867 -229.602791) (xy 367.021572 -229.594666) (xy 366.972179 -229.578618) (xy 366.925905 -229.55504)
			(xy 366.883889 -229.524514) (xy 366.847166 -229.487791) (xy 366.81664 -229.445775) (xy 366.793062 -229.399501)
			(xy 366.777014 -229.350108) (xy 366.768889 -229.298813) (xy 366.488979 -229.298813) (xy 366.480854 -229.350108)
			(xy 366.464806 -229.399501) (xy 366.441228 -229.445775) (xy 366.410702 -229.487791) (xy 366.373979 -229.524514)
			(xy 366.331963 -229.55504) (xy 366.285689 -229.578618) (xy 366.236296 -229.594666) (xy 366.185001 -229.602791)
			(xy 366.133067 -229.602791) (xy 366.081772 -229.594666) (xy 366.032379 -229.578618) (xy 365.986105 -229.55504)
			(xy 365.944089 -229.524514) (xy 365.907366 -229.487791) (xy 365.87684 -229.445775) (xy 365.853262 -229.399501)
			(xy 365.837214 -229.350108) (xy 365.829089 -229.298813) (xy 365.549179 -229.298813) (xy 365.541054 -229.350108)
			(xy 365.525006 -229.399501) (xy 365.501428 -229.445775) (xy 365.470902 -229.487791) (xy 365.434179 -229.524514)
			(xy 365.392163 -229.55504) (xy 365.345889 -229.578618) (xy 365.296496 -229.594666) (xy 365.245201 -229.602791)
			(xy 365.193267 -229.602791) (xy 365.141972 -229.594666) (xy 365.092579 -229.578618) (xy 365.046305 -229.55504)
			(xy 365.004289 -229.524514) (xy 364.967566 -229.487791) (xy 364.93704 -229.445775) (xy 364.913462 -229.399501)
			(xy 364.897414 -229.350108) (xy 364.889289 -229.298813) (xy 364.609379 -229.298813) (xy 364.601254 -229.350108)
			(xy 364.585206 -229.399501) (xy 364.561628 -229.445775) (xy 364.531102 -229.487791) (xy 364.494379 -229.524514)
			(xy 364.452363 -229.55504) (xy 364.406089 -229.578618) (xy 364.356696 -229.594666) (xy 364.305401 -229.602791)
			(xy 364.253467 -229.602791) (xy 364.202172 -229.594666) (xy 364.152779 -229.578618) (xy 364.106505 -229.55504)
			(xy 364.064489 -229.524514) (xy 364.027766 -229.487791) (xy 363.99724 -229.445775) (xy 363.973662 -229.399501)
			(xy 363.957614 -229.350108) (xy 363.949489 -229.298813) (xy 363.669579 -229.298813) (xy 363.661454 -229.350108)
			(xy 363.645406 -229.399501) (xy 363.621828 -229.445775) (xy 363.591302 -229.487791) (xy 363.554579 -229.524514)
			(xy 363.512563 -229.55504) (xy 363.466289 -229.578618) (xy 363.416896 -229.594666) (xy 363.365601 -229.602791)
			(xy 363.313667 -229.602791) (xy 363.262372 -229.594666) (xy 363.212979 -229.578618) (xy 363.166705 -229.55504)
			(xy 363.124689 -229.524514) (xy 363.087966 -229.487791) (xy 363.05744 -229.445775) (xy 363.033862 -229.399501)
			(xy 363.017814 -229.350108) (xy 363.009689 -229.298813) (xy 362.729779 -229.298813) (xy 362.721654 -229.350108)
			(xy 362.705606 -229.399501) (xy 362.682028 -229.445775) (xy 362.651502 -229.487791) (xy 362.614779 -229.524514)
			(xy 362.572763 -229.55504) (xy 362.526489 -229.578618) (xy 362.477096 -229.594666) (xy 362.425801 -229.602791)
			(xy 362.373867 -229.602791) (xy 362.322572 -229.594666) (xy 362.273179 -229.578618) (xy 362.226905 -229.55504)
			(xy 362.184889 -229.524514) (xy 362.148166 -229.487791) (xy 362.11764 -229.445775) (xy 362.094062 -229.399501)
			(xy 362.078014 -229.350108) (xy 362.069889 -229.298813) (xy 361.789979 -229.298813) (xy 361.781854 -229.350108)
			(xy 361.765806 -229.399501) (xy 361.742228 -229.445775) (xy 361.711702 -229.487791) (xy 361.674979 -229.524514)
			(xy 361.632963 -229.55504) (xy 361.586689 -229.578618) (xy 361.537296 -229.594666) (xy 361.486001 -229.602791)
			(xy 361.434067 -229.602791) (xy 361.382772 -229.594666) (xy 361.333379 -229.578618) (xy 361.287105 -229.55504)
			(xy 361.245089 -229.524514) (xy 361.208366 -229.487791) (xy 361.17784 -229.445775) (xy 361.154262 -229.399501)
			(xy 361.138214 -229.350108) (xy 361.130089 -229.298813) (xy 360.850179 -229.298813) (xy 360.842054 -229.350108)
			(xy 360.826006 -229.399501) (xy 360.802428 -229.445775) (xy 360.771902 -229.487791) (xy 360.735179 -229.524514)
			(xy 360.693163 -229.55504) (xy 360.646889 -229.578618) (xy 360.597496 -229.594666) (xy 360.546201 -229.602791)
			(xy 360.494267 -229.602791) (xy 360.442972 -229.594666) (xy 360.393579 -229.578618) (xy 360.347305 -229.55504)
			(xy 360.305289 -229.524514) (xy 360.268566 -229.487791) (xy 360.23804 -229.445775) (xy 360.214462 -229.399501)
			(xy 360.198414 -229.350108) (xy 360.190289 -229.298813) (xy 359.910125 -229.298813) (xy 359.902 -229.350108)
			(xy 359.885952 -229.399501) (xy 359.862374 -229.445775) (xy 359.831848 -229.487791) (xy 359.795125 -229.524514)
			(xy 359.753109 -229.55504) (xy 359.706835 -229.578618) (xy 359.657442 -229.594666) (xy 359.606147 -229.602791)
			(xy 359.554213 -229.602791) (xy 359.502918 -229.594666) (xy 359.453525 -229.578618) (xy 359.407251 -229.55504)
			(xy 359.365235 -229.524514) (xy 359.328512 -229.487791) (xy 359.297986 -229.445775) (xy 359.274408 -229.399501)
			(xy 359.25836 -229.350108) (xy 359.250235 -229.298813) (xy 358.970579 -229.298813) (xy 358.962454 -229.350108)
			(xy 358.946406 -229.399501) (xy 358.922828 -229.445775) (xy 358.892302 -229.487791) (xy 358.855579 -229.524514)
			(xy 358.813563 -229.55504) (xy 358.767289 -229.578618) (xy 358.717896 -229.594666) (xy 358.666601 -229.602791)
			(xy 358.614667 -229.602791) (xy 358.563372 -229.594666) (xy 358.513979 -229.578618) (xy 358.467705 -229.55504)
			(xy 358.425689 -229.524514) (xy 358.388966 -229.487791) (xy 358.35844 -229.445775) (xy 358.334862 -229.399501)
			(xy 358.318814 -229.350108) (xy 358.310689 -229.298813) (xy 358.030758 -229.298813) (xy 358.022882 -229.349185)
			(xy 358.007216 -229.398037) (xy 357.984185 -229.44388) (xy 357.954342 -229.48561) (xy 357.918406 -229.522224)
			(xy 357.877241 -229.552841) (xy 357.854758 -229.5652) (xy 357.854758 -229.705154) (xy 357.875586 -229.725982)
			(xy 357.8907 -229.741395) (xy 357.918921 -229.774067) (xy 357.931974 -229.79126) (xy 357.937951 -229.798517)
			(xy 357.953872 -229.808482) (xy 357.972312 -229.812056) (xy 357.990804 -229.808761) (xy 357.99903 -229.804214)
			(xy 358.018496 -229.792838) (xy 358.059855 -229.774891) (xy 358.103271 -229.762737) (xy 358.147937 -229.756601)
			(xy 358.17048 -229.756208) (xy 358.196453 -229.756689) (xy 358.247761 -229.764813) (xy 358.297166 -229.780863)
			(xy 358.343451 -229.804444) (xy 358.385478 -229.834976) (xy 358.422211 -229.871707) (xy 358.452745 -229.913732)
			(xy 358.476329 -229.960016) (xy 358.492382 -230.00942) (xy 358.500509 -230.060727) (xy 358.500509 -230.112629)
			(xy 358.780589 -230.112629) (xy 358.780589 -230.060695) (xy 358.788714 -230.0094) (xy 358.804762 -229.960007)
			(xy 358.82834 -229.913733) (xy 358.858866 -229.871717) (xy 358.895589 -229.834994) (xy 358.937605 -229.804468)
			(xy 358.983879 -229.78089) (xy 359.033272 -229.764842) (xy 359.084567 -229.756717) (xy 359.136501 -229.756717)
			(xy 359.187796 -229.764842) (xy 359.237189 -229.78089) (xy 359.283463 -229.804468) (xy 359.325479 -229.834994)
			(xy 359.362202 -229.871717) (xy 359.392728 -229.913733) (xy 359.416306 -229.960007) (xy 359.432354 -230.0094)
			(xy 359.440479 -230.060695) (xy 359.440988 -230.086662) (xy 359.440479 -230.112629) (xy 359.720389 -230.112629)
			(xy 359.720389 -230.060695) (xy 359.728514 -230.0094) (xy 359.744562 -229.960007) (xy 359.76814 -229.913733)
			(xy 359.798666 -229.871717) (xy 359.835389 -229.834994) (xy 359.877405 -229.804468) (xy 359.923679 -229.78089)
			(xy 359.973072 -229.764842) (xy 360.024367 -229.756717) (xy 360.076301 -229.756717) (xy 360.127596 -229.764842)
			(xy 360.176989 -229.78089) (xy 360.223263 -229.804468) (xy 360.265279 -229.834994) (xy 360.302002 -229.871717)
			(xy 360.332528 -229.913733) (xy 360.356106 -229.960007) (xy 360.372154 -230.0094) (xy 360.380279 -230.060695)
			(xy 360.380788 -230.086662) (xy 360.380279 -230.112629) (xy 360.660189 -230.112629) (xy 360.660189 -230.060695)
			(xy 360.668314 -230.0094) (xy 360.684362 -229.960007) (xy 360.70794 -229.913733) (xy 360.738466 -229.871717)
			(xy 360.775189 -229.834994) (xy 360.817205 -229.804468) (xy 360.863479 -229.78089) (xy 360.912872 -229.764842)
			(xy 360.964167 -229.756717) (xy 361.016101 -229.756717) (xy 361.067396 -229.764842) (xy 361.116789 -229.78089)
			(xy 361.163063 -229.804468) (xy 361.205079 -229.834994) (xy 361.241802 -229.871717) (xy 361.272328 -229.913733)
			(xy 361.295906 -229.960007) (xy 361.311954 -230.0094) (xy 361.320079 -230.060695) (xy 361.320588 -230.086662)
			(xy 361.320079 -230.112629) (xy 361.599989 -230.112629) (xy 361.599989 -230.060695) (xy 361.608114 -230.0094)
			(xy 361.624162 -229.960007) (xy 361.64774 -229.913733) (xy 361.678266 -229.871717) (xy 361.714989 -229.834994)
			(xy 361.757005 -229.804468) (xy 361.803279 -229.78089) (xy 361.852672 -229.764842) (xy 361.903967 -229.756717)
			(xy 361.955901 -229.756717) (xy 362.007196 -229.764842) (xy 362.056589 -229.78089) (xy 362.102863 -229.804468)
			(xy 362.144879 -229.834994) (xy 362.181602 -229.871717) (xy 362.212128 -229.913733) (xy 362.235706 -229.960007)
			(xy 362.251754 -230.0094) (xy 362.259879 -230.060695) (xy 362.260388 -230.086662) (xy 362.259879 -230.112629)
			(xy 362.539789 -230.112629) (xy 362.539789 -230.060695) (xy 362.547914 -230.0094) (xy 362.563962 -229.960007)
			(xy 362.58754 -229.913733) (xy 362.618066 -229.871717) (xy 362.654789 -229.834994) (xy 362.696805 -229.804468)
			(xy 362.743079 -229.78089) (xy 362.792472 -229.764842) (xy 362.843767 -229.756717) (xy 362.895701 -229.756717)
			(xy 362.946996 -229.764842) (xy 362.996389 -229.78089) (xy 363.042663 -229.804468) (xy 363.084679 -229.834994)
			(xy 363.121402 -229.871717) (xy 363.151928 -229.913733) (xy 363.175506 -229.960007) (xy 363.191554 -230.0094)
			(xy 363.199679 -230.060695) (xy 363.200188 -230.086662) (xy 363.199679 -230.112629) (xy 363.479335 -230.112629)
			(xy 363.479335 -230.060695) (xy 363.48746 -230.0094) (xy 363.503508 -229.960007) (xy 363.527086 -229.913733)
			(xy 363.557612 -229.871717) (xy 363.594335 -229.834994) (xy 363.636351 -229.804468) (xy 363.682625 -229.78089)
			(xy 363.732018 -229.764842) (xy 363.783313 -229.756717) (xy 363.835247 -229.756717) (xy 363.886542 -229.764842)
			(xy 363.935935 -229.78089) (xy 363.982209 -229.804468) (xy 364.024225 -229.834994) (xy 364.060948 -229.871717)
			(xy 364.091474 -229.913733) (xy 364.115052 -229.960007) (xy 364.1311 -230.0094) (xy 364.139225 -230.060695)
			(xy 364.139734 -230.086662) (xy 364.139225 -230.112629) (xy 364.419135 -230.112629) (xy 364.419135 -230.060695)
			(xy 364.42726 -230.0094) (xy 364.443308 -229.960007) (xy 364.466886 -229.913733) (xy 364.497412 -229.871717)
			(xy 364.534135 -229.834994) (xy 364.576151 -229.804468) (xy 364.622425 -229.78089) (xy 364.671818 -229.764842)
			(xy 364.723113 -229.756717) (xy 364.775047 -229.756717) (xy 364.826342 -229.764842) (xy 364.875735 -229.78089)
			(xy 364.922009 -229.804468) (xy 364.964025 -229.834994) (xy 365.000748 -229.871717) (xy 365.031274 -229.913733)
			(xy 365.054852 -229.960007) (xy 365.0709 -230.0094) (xy 365.079025 -230.060695) (xy 365.079534 -230.086662)
			(xy 365.079025 -230.112629) (xy 365.358935 -230.112629) (xy 365.358935 -230.060695) (xy 365.36706 -230.0094)
			(xy 365.383108 -229.960007) (xy 365.406686 -229.913733) (xy 365.437212 -229.871717) (xy 365.473935 -229.834994)
			(xy 365.515951 -229.804468) (xy 365.562225 -229.78089) (xy 365.611618 -229.764842) (xy 365.662913 -229.756717)
			(xy 365.714847 -229.756717) (xy 365.766142 -229.764842) (xy 365.815535 -229.78089) (xy 365.861809 -229.804468)
			(xy 365.903825 -229.834994) (xy 365.940548 -229.871717) (xy 365.971074 -229.913733) (xy 365.994652 -229.960007)
			(xy 366.0107 -230.0094) (xy 366.018825 -230.060695) (xy 366.019334 -230.086662) (xy 366.018825 -230.112629)
			(xy 366.298735 -230.112629) (xy 366.298735 -230.060695) (xy 366.30686 -230.0094) (xy 366.322908 -229.960007)
			(xy 366.346486 -229.913733) (xy 366.377012 -229.871717) (xy 366.413735 -229.834994) (xy 366.455751 -229.804468)
			(xy 366.502025 -229.78089) (xy 366.551418 -229.764842) (xy 366.602713 -229.756717) (xy 366.654647 -229.756717)
			(xy 366.705942 -229.764842) (xy 366.755335 -229.78089) (xy 366.801609 -229.804468) (xy 366.843625 -229.834994)
			(xy 366.880348 -229.871717) (xy 366.910874 -229.913733) (xy 366.934452 -229.960007) (xy 366.9505 -230.0094)
			(xy 366.958625 -230.060695) (xy 366.959134 -230.086662) (xy 366.958625 -230.112629) (xy 367.238535 -230.112629)
			(xy 367.238535 -230.060695) (xy 367.24666 -230.0094) (xy 367.262708 -229.960007) (xy 367.286286 -229.913733)
			(xy 367.316812 -229.871717) (xy 367.353535 -229.834994) (xy 367.395551 -229.804468) (xy 367.441825 -229.78089)
			(xy 367.491218 -229.764842) (xy 367.542513 -229.756717) (xy 367.594447 -229.756717) (xy 367.645742 -229.764842)
			(xy 367.695135 -229.78089) (xy 367.741409 -229.804468) (xy 367.783425 -229.834994) (xy 367.820148 -229.871717)
			(xy 367.850674 -229.913733) (xy 367.874252 -229.960007) (xy 367.8903 -230.0094) (xy 367.898425 -230.060695)
			(xy 367.898934 -230.086662) (xy 367.898425 -230.112629) (xy 368.178335 -230.112629) (xy 368.178335 -230.060695)
			(xy 368.18646 -230.0094) (xy 368.202508 -229.960007) (xy 368.226086 -229.913733) (xy 368.256612 -229.871717)
			(xy 368.293335 -229.834994) (xy 368.335351 -229.804468) (xy 368.381625 -229.78089) (xy 368.431018 -229.764842)
			(xy 368.482313 -229.756717) (xy 368.534247 -229.756717) (xy 368.585542 -229.764842) (xy 368.634935 -229.78089)
			(xy 368.681209 -229.804468) (xy 368.723225 -229.834994) (xy 368.759948 -229.871717) (xy 368.790474 -229.913733)
			(xy 368.814052 -229.960007) (xy 368.8301 -230.0094) (xy 368.838225 -230.060695) (xy 368.838734 -230.086662)
			(xy 368.838225 -230.112629) (xy 369.118135 -230.112629) (xy 369.118135 -230.060695) (xy 369.12626 -230.0094)
			(xy 369.142308 -229.960007) (xy 369.165886 -229.913733) (xy 369.196412 -229.871717) (xy 369.233135 -229.834994)
			(xy 369.275151 -229.804468) (xy 369.321425 -229.78089) (xy 369.370818 -229.764842) (xy 369.422113 -229.756717)
			(xy 369.474047 -229.756717) (xy 369.525342 -229.764842) (xy 369.574735 -229.78089) (xy 369.621009 -229.804468)
			(xy 369.663025 -229.834994) (xy 369.699748 -229.871717) (xy 369.730274 -229.913733) (xy 369.753852 -229.960007)
			(xy 369.7699 -230.0094) (xy 369.778025 -230.060695) (xy 369.778534 -230.086662) (xy 369.778025 -230.112629)
			(xy 370.997735 -230.112629) (xy 370.997735 -230.060695) (xy 371.00586 -230.0094) (xy 371.021908 -229.960007)
			(xy 371.045486 -229.913733) (xy 371.076012 -229.871717) (xy 371.112735 -229.834994) (xy 371.154751 -229.804468)
			(xy 371.201025 -229.78089) (xy 371.250418 -229.764842) (xy 371.301713 -229.756717) (xy 371.353647 -229.756717)
			(xy 371.404942 -229.764842) (xy 371.454335 -229.78089) (xy 371.500609 -229.804468) (xy 371.542625 -229.834994)
			(xy 371.579348 -229.871717) (xy 371.609874 -229.913733) (xy 371.633452 -229.960007) (xy 371.6495 -230.0094)
			(xy 371.657625 -230.060695) (xy 371.658134 -230.086662) (xy 371.657625 -230.112629) (xy 371.937535 -230.112629)
			(xy 371.937535 -230.060695) (xy 371.94566 -230.0094) (xy 371.961708 -229.960007) (xy 371.985286 -229.913733)
			(xy 372.015812 -229.871717) (xy 372.052535 -229.834994) (xy 372.094551 -229.804468) (xy 372.140825 -229.78089)
			(xy 372.190218 -229.764842) (xy 372.241513 -229.756717) (xy 372.293447 -229.756717) (xy 372.344742 -229.764842)
			(xy 372.394135 -229.78089) (xy 372.440409 -229.804468) (xy 372.482425 -229.834994) (xy 372.519148 -229.871717)
			(xy 372.549674 -229.913733) (xy 372.573252 -229.960007) (xy 372.5893 -230.0094) (xy 372.597425 -230.060695)
			(xy 372.597934 -230.086662) (xy 372.597425 -230.112629) (xy 372.877589 -230.112629) (xy 372.877589 -230.060695)
			(xy 372.885714 -230.0094) (xy 372.901762 -229.960007) (xy 372.92534 -229.913733) (xy 372.955866 -229.871717)
			(xy 372.992589 -229.834994) (xy 373.034605 -229.804468) (xy 373.080879 -229.78089) (xy 373.130272 -229.764842)
			(xy 373.181567 -229.756717) (xy 373.233501 -229.756717) (xy 373.284796 -229.764842) (xy 373.334189 -229.78089)
			(xy 373.380463 -229.804468) (xy 373.422479 -229.834994) (xy 373.459202 -229.871717) (xy 373.489728 -229.913733)
			(xy 373.513306 -229.960007) (xy 373.529354 -230.0094) (xy 373.537479 -230.060695) (xy 373.537988 -230.086662)
			(xy 373.537479 -230.112629) (xy 373.817135 -230.112629) (xy 373.817135 -230.060695) (xy 373.82526 -230.0094)
			(xy 373.841308 -229.960007) (xy 373.864886 -229.913733) (xy 373.895412 -229.871717) (xy 373.932135 -229.834994)
			(xy 373.974151 -229.804468) (xy 374.020425 -229.78089) (xy 374.069818 -229.764842) (xy 374.121113 -229.756717)
			(xy 374.173047 -229.756717) (xy 374.224342 -229.764842) (xy 374.273735 -229.78089) (xy 374.320009 -229.804468)
			(xy 374.362025 -229.834994) (xy 374.398748 -229.871717) (xy 374.429274 -229.913733) (xy 374.452852 -229.960007)
			(xy 374.4689 -230.0094) (xy 374.477025 -230.060695) (xy 374.477534 -230.086662) (xy 374.477025 -230.112629)
			(xy 374.756935 -230.112629) (xy 374.756935 -230.060695) (xy 374.76506 -230.0094) (xy 374.781108 -229.960007)
			(xy 374.804686 -229.913733) (xy 374.835212 -229.871717) (xy 374.871935 -229.834994) (xy 374.913951 -229.804468)
			(xy 374.960225 -229.78089) (xy 375.009618 -229.764842) (xy 375.060913 -229.756717) (xy 375.112847 -229.756717)
			(xy 375.164142 -229.764842) (xy 375.213535 -229.78089) (xy 375.259809 -229.804468) (xy 375.301825 -229.834994)
			(xy 375.338548 -229.871717) (xy 375.369074 -229.913733) (xy 375.392652 -229.960007) (xy 375.4087 -230.0094)
			(xy 375.416825 -230.060695) (xy 375.417334 -230.086662) (xy 375.416825 -230.112629) (xy 375.4087 -230.163924)
			(xy 375.392652 -230.213317) (xy 375.369074 -230.259591) (xy 375.338548 -230.301607) (xy 375.301825 -230.33833)
			(xy 375.259809 -230.368856) (xy 375.213535 -230.392434) (xy 375.164142 -230.408482) (xy 375.112847 -230.416607)
			(xy 375.060913 -230.416607) (xy 375.009618 -230.408482) (xy 374.960225 -230.392434) (xy 374.913951 -230.368856)
			(xy 374.871935 -230.33833) (xy 374.835212 -230.301607) (xy 374.804686 -230.259591) (xy 374.781108 -230.213317)
			(xy 374.76506 -230.163924) (xy 374.756935 -230.112629) (xy 374.477025 -230.112629) (xy 374.4689 -230.163924)
			(xy 374.452852 -230.213317) (xy 374.429274 -230.259591) (xy 374.398748 -230.301607) (xy 374.362025 -230.33833)
			(xy 374.320009 -230.368856) (xy 374.273735 -230.392434) (xy 374.224342 -230.408482) (xy 374.173047 -230.416607)
			(xy 374.121113 -230.416607) (xy 374.069818 -230.408482) (xy 374.020425 -230.392434) (xy 373.974151 -230.368856)
			(xy 373.932135 -230.33833) (xy 373.895412 -230.301607) (xy 373.864886 -230.259591) (xy 373.841308 -230.213317)
			(xy 373.82526 -230.163924) (xy 373.817135 -230.112629) (xy 373.537479 -230.112629) (xy 373.529354 -230.163924)
			(xy 373.513306 -230.213317) (xy 373.489728 -230.259591) (xy 373.459202 -230.301607) (xy 373.422479 -230.33833)
			(xy 373.380463 -230.368856) (xy 373.334189 -230.392434) (xy 373.284796 -230.408482) (xy 373.233501 -230.416607)
			(xy 373.181567 -230.416607) (xy 373.130272 -230.408482) (xy 373.080879 -230.392434) (xy 373.034605 -230.368856)
			(xy 372.992589 -230.33833) (xy 372.955866 -230.301607) (xy 372.92534 -230.259591) (xy 372.901762 -230.213317)
			(xy 372.885714 -230.163924) (xy 372.877589 -230.112629) (xy 372.597425 -230.112629) (xy 372.5893 -230.163924)
			(xy 372.573252 -230.213317) (xy 372.549674 -230.259591) (xy 372.519148 -230.301607) (xy 372.482425 -230.33833)
			(xy 372.440409 -230.368856) (xy 372.394135 -230.392434) (xy 372.344742 -230.408482) (xy 372.293447 -230.416607)
			(xy 372.241513 -230.416607) (xy 372.190218 -230.408482) (xy 372.140825 -230.392434) (xy 372.094551 -230.368856)
			(xy 372.052535 -230.33833) (xy 372.015812 -230.301607) (xy 371.985286 -230.259591) (xy 371.961708 -230.213317)
			(xy 371.94566 -230.163924) (xy 371.937535 -230.112629) (xy 371.657625 -230.112629) (xy 371.6495 -230.163924)
			(xy 371.633452 -230.213317) (xy 371.609874 -230.259591) (xy 371.579348 -230.301607) (xy 371.542625 -230.33833)
			(xy 371.500609 -230.368856) (xy 371.454335 -230.392434) (xy 371.404942 -230.408482) (xy 371.353647 -230.416607)
			(xy 371.301713 -230.416607) (xy 371.250418 -230.408482) (xy 371.201025 -230.392434) (xy 371.154751 -230.368856)
			(xy 371.112735 -230.33833) (xy 371.076012 -230.301607) (xy 371.045486 -230.259591) (xy 371.021908 -230.213317)
			(xy 371.00586 -230.163924) (xy 370.997735 -230.112629) (xy 369.778025 -230.112629) (xy 369.7699 -230.163924)
			(xy 369.753852 -230.213317) (xy 369.730274 -230.259591) (xy 369.699748 -230.301607) (xy 369.663025 -230.33833)
			(xy 369.621009 -230.368856) (xy 369.574735 -230.392434) (xy 369.525342 -230.408482) (xy 369.474047 -230.416607)
			(xy 369.422113 -230.416607) (xy 369.370818 -230.408482) (xy 369.321425 -230.392434) (xy 369.275151 -230.368856)
			(xy 369.233135 -230.33833) (xy 369.196412 -230.301607) (xy 369.165886 -230.259591) (xy 369.142308 -230.213317)
			(xy 369.12626 -230.163924) (xy 369.118135 -230.112629) (xy 368.838225 -230.112629) (xy 368.8301 -230.163924)
			(xy 368.814052 -230.213317) (xy 368.790474 -230.259591) (xy 368.759948 -230.301607) (xy 368.723225 -230.33833)
			(xy 368.681209 -230.368856) (xy 368.634935 -230.392434) (xy 368.585542 -230.408482) (xy 368.534247 -230.416607)
			(xy 368.482313 -230.416607) (xy 368.431018 -230.408482) (xy 368.381625 -230.392434) (xy 368.335351 -230.368856)
			(xy 368.293335 -230.33833) (xy 368.256612 -230.301607) (xy 368.226086 -230.259591) (xy 368.202508 -230.213317)
			(xy 368.18646 -230.163924) (xy 368.178335 -230.112629) (xy 367.898425 -230.112629) (xy 367.8903 -230.163924)
			(xy 367.874252 -230.213317) (xy 367.850674 -230.259591) (xy 367.820148 -230.301607) (xy 367.783425 -230.33833)
			(xy 367.741409 -230.368856) (xy 367.695135 -230.392434) (xy 367.645742 -230.408482) (xy 367.594447 -230.416607)
			(xy 367.542513 -230.416607) (xy 367.491218 -230.408482) (xy 367.441825 -230.392434) (xy 367.395551 -230.368856)
			(xy 367.353535 -230.33833) (xy 367.316812 -230.301607) (xy 367.286286 -230.259591) (xy 367.262708 -230.213317)
			(xy 367.24666 -230.163924) (xy 367.238535 -230.112629) (xy 366.958625 -230.112629) (xy 366.9505 -230.163924)
			(xy 366.934452 -230.213317) (xy 366.910874 -230.259591) (xy 366.880348 -230.301607) (xy 366.843625 -230.33833)
			(xy 366.801609 -230.368856) (xy 366.755335 -230.392434) (xy 366.705942 -230.408482) (xy 366.654647 -230.416607)
			(xy 366.602713 -230.416607) (xy 366.551418 -230.408482) (xy 366.502025 -230.392434) (xy 366.455751 -230.368856)
			(xy 366.413735 -230.33833) (xy 366.377012 -230.301607) (xy 366.346486 -230.259591) (xy 366.322908 -230.213317)
			(xy 366.30686 -230.163924) (xy 366.298735 -230.112629) (xy 366.018825 -230.112629) (xy 366.0107 -230.163924)
			(xy 365.994652 -230.213317) (xy 365.971074 -230.259591) (xy 365.940548 -230.301607) (xy 365.903825 -230.33833)
			(xy 365.861809 -230.368856) (xy 365.815535 -230.392434) (xy 365.766142 -230.408482) (xy 365.714847 -230.416607)
			(xy 365.662913 -230.416607) (xy 365.611618 -230.408482) (xy 365.562225 -230.392434) (xy 365.515951 -230.368856)
			(xy 365.473935 -230.33833) (xy 365.437212 -230.301607) (xy 365.406686 -230.259591) (xy 365.383108 -230.213317)
			(xy 365.36706 -230.163924) (xy 365.358935 -230.112629) (xy 365.079025 -230.112629) (xy 365.0709 -230.163924)
			(xy 365.054852 -230.213317) (xy 365.031274 -230.259591) (xy 365.000748 -230.301607) (xy 364.964025 -230.33833)
			(xy 364.922009 -230.368856) (xy 364.875735 -230.392434) (xy 364.826342 -230.408482) (xy 364.775047 -230.416607)
			(xy 364.723113 -230.416607) (xy 364.671818 -230.408482) (xy 364.622425 -230.392434) (xy 364.576151 -230.368856)
			(xy 364.534135 -230.33833) (xy 364.497412 -230.301607) (xy 364.466886 -230.259591) (xy 364.443308 -230.213317)
			(xy 364.42726 -230.163924) (xy 364.419135 -230.112629) (xy 364.139225 -230.112629) (xy 364.1311 -230.163924)
			(xy 364.115052 -230.213317) (xy 364.091474 -230.259591) (xy 364.060948 -230.301607) (xy 364.024225 -230.33833)
			(xy 363.982209 -230.368856) (xy 363.935935 -230.392434) (xy 363.886542 -230.408482) (xy 363.835247 -230.416607)
			(xy 363.783313 -230.416607) (xy 363.732018 -230.408482) (xy 363.682625 -230.392434) (xy 363.636351 -230.368856)
			(xy 363.594335 -230.33833) (xy 363.557612 -230.301607) (xy 363.527086 -230.259591) (xy 363.503508 -230.213317)
			(xy 363.48746 -230.163924) (xy 363.479335 -230.112629) (xy 363.199679 -230.112629) (xy 363.191554 -230.163924)
			(xy 363.175506 -230.213317) (xy 363.151928 -230.259591) (xy 363.121402 -230.301607) (xy 363.084679 -230.33833)
			(xy 363.042663 -230.368856) (xy 362.996389 -230.392434) (xy 362.946996 -230.408482) (xy 362.895701 -230.416607)
			(xy 362.843767 -230.416607) (xy 362.792472 -230.408482) (xy 362.743079 -230.392434) (xy 362.696805 -230.368856)
			(xy 362.654789 -230.33833) (xy 362.618066 -230.301607) (xy 362.58754 -230.259591) (xy 362.563962 -230.213317)
			(xy 362.547914 -230.163924) (xy 362.539789 -230.112629) (xy 362.259879 -230.112629) (xy 362.251754 -230.163924)
			(xy 362.235706 -230.213317) (xy 362.212128 -230.259591) (xy 362.181602 -230.301607) (xy 362.144879 -230.33833)
			(xy 362.102863 -230.368856) (xy 362.056589 -230.392434) (xy 362.007196 -230.408482) (xy 361.955901 -230.416607)
			(xy 361.903967 -230.416607) (xy 361.852672 -230.408482) (xy 361.803279 -230.392434) (xy 361.757005 -230.368856)
			(xy 361.714989 -230.33833) (xy 361.678266 -230.301607) (xy 361.64774 -230.259591) (xy 361.624162 -230.213317)
			(xy 361.608114 -230.163924) (xy 361.599989 -230.112629) (xy 361.320079 -230.112629) (xy 361.311954 -230.163924)
			(xy 361.295906 -230.213317) (xy 361.272328 -230.259591) (xy 361.241802 -230.301607) (xy 361.205079 -230.33833)
			(xy 361.163063 -230.368856) (xy 361.116789 -230.392434) (xy 361.067396 -230.408482) (xy 361.016101 -230.416607)
			(xy 360.964167 -230.416607) (xy 360.912872 -230.408482) (xy 360.863479 -230.392434) (xy 360.817205 -230.368856)
			(xy 360.775189 -230.33833) (xy 360.738466 -230.301607) (xy 360.70794 -230.259591) (xy 360.684362 -230.213317)
			(xy 360.668314 -230.163924) (xy 360.660189 -230.112629) (xy 360.380279 -230.112629) (xy 360.372154 -230.163924)
			(xy 360.356106 -230.213317) (xy 360.332528 -230.259591) (xy 360.302002 -230.301607) (xy 360.265279 -230.33833)
			(xy 360.223263 -230.368856) (xy 360.176989 -230.392434) (xy 360.127596 -230.408482) (xy 360.076301 -230.416607)
			(xy 360.024367 -230.416607) (xy 359.973072 -230.408482) (xy 359.923679 -230.392434) (xy 359.877405 -230.368856)
			(xy 359.835389 -230.33833) (xy 359.798666 -230.301607) (xy 359.76814 -230.259591) (xy 359.744562 -230.213317)
			(xy 359.728514 -230.163924) (xy 359.720389 -230.112629) (xy 359.440479 -230.112629) (xy 359.432354 -230.163924)
			(xy 359.416306 -230.213317) (xy 359.392728 -230.259591) (xy 359.362202 -230.301607) (xy 359.325479 -230.33833)
			(xy 359.283463 -230.368856) (xy 359.237189 -230.392434) (xy 359.187796 -230.408482) (xy 359.136501 -230.416607)
			(xy 359.084567 -230.416607) (xy 359.033272 -230.408482) (xy 358.983879 -230.392434) (xy 358.937605 -230.368856)
			(xy 358.895589 -230.33833) (xy 358.858866 -230.301607) (xy 358.82834 -230.259591) (xy 358.804762 -230.213317)
			(xy 358.788714 -230.163924) (xy 358.780589 -230.112629) (xy 358.500509 -230.112629) (xy 358.500509 -230.112673)
			(xy 358.492382 -230.16398) (xy 358.476329 -230.213384) (xy 358.452745 -230.259668) (xy 358.422211 -230.301693)
			(xy 358.385478 -230.338424) (xy 358.343451 -230.368956) (xy 358.297166 -230.392537) (xy 358.247761 -230.408587)
			(xy 358.196453 -230.416711) (xy 358.17048 -230.417116) (xy 358.139238 -230.41636) (xy 358.077871 -230.40459)
			(xy 358.04856 -230.393748) (xy 358.03967 -230.390616) (xy 358.020833 -230.390447) (xy 358.003209 -230.397096)
			(xy 357.989177 -230.409664) (xy 357.984552 -230.417878) (xy 357.970128 -230.445272) (xy 357.936403 -230.497193)
			(xy 357.917242 -230.52151) (xy 357.908036 -230.533672) (xy 357.896681 -230.561968) (xy 357.894192 -230.592355)
			(xy 357.900791 -230.622122) (xy 357.915889 -230.64861) (xy 357.92664 -230.659432) (xy 357.945984 -230.678317)
			(xy 357.978864 -230.721226) (xy 358.004319 -230.768914) (xy 358.021673 -230.820111) (xy 358.03046 -230.873449)
			(xy 358.031034 -230.900478) (xy 358.030529 -230.926445) (xy 358.310689 -230.926445) (xy 358.310689 -230.874511)
			(xy 358.318814 -230.823216) (xy 358.334862 -230.773823) (xy 358.35844 -230.727549) (xy 358.388966 -230.685533)
			(xy 358.425689 -230.64881) (xy 358.467705 -230.618284) (xy 358.513979 -230.594706) (xy 358.563372 -230.578658)
			(xy 358.614667 -230.570533) (xy 358.666601 -230.570533) (xy 358.717896 -230.578658) (xy 358.767289 -230.594706)
			(xy 358.813563 -230.618284) (xy 358.855579 -230.64881) (xy 358.892302 -230.685533) (xy 358.922828 -230.727549)
			(xy 358.946406 -230.773823) (xy 358.962454 -230.823216) (xy 358.970579 -230.874511) (xy 358.971088 -230.900478)
			(xy 358.970579 -230.926445) (xy 359.250489 -230.926445) (xy 359.250489 -230.874511) (xy 359.258614 -230.823216)
			(xy 359.274662 -230.773823) (xy 359.29824 -230.727549) (xy 359.328766 -230.685533) (xy 359.365489 -230.64881)
			(xy 359.407505 -230.618284) (xy 359.453779 -230.594706) (xy 359.503172 -230.578658) (xy 359.554467 -230.570533)
			(xy 359.606401 -230.570533) (xy 359.657696 -230.578658) (xy 359.707089 -230.594706) (xy 359.753363 -230.618284)
			(xy 359.795379 -230.64881) (xy 359.832102 -230.685533) (xy 359.862628 -230.727549) (xy 359.886206 -230.773823)
			(xy 359.902254 -230.823216) (xy 359.910379 -230.874511) (xy 359.910888 -230.900478) (xy 359.910379 -230.926445)
			(xy 360.190289 -230.926445) (xy 360.190289 -230.874511) (xy 360.198414 -230.823216) (xy 360.214462 -230.773823)
			(xy 360.23804 -230.727549) (xy 360.268566 -230.685533) (xy 360.305289 -230.64881) (xy 360.347305 -230.618284)
			(xy 360.393579 -230.594706) (xy 360.442972 -230.578658) (xy 360.494267 -230.570533) (xy 360.546201 -230.570533)
			(xy 360.597496 -230.578658) (xy 360.646889 -230.594706) (xy 360.693163 -230.618284) (xy 360.735179 -230.64881)
			(xy 360.771902 -230.685533) (xy 360.802428 -230.727549) (xy 360.826006 -230.773823) (xy 360.842054 -230.823216)
			(xy 360.850179 -230.874511) (xy 360.850688 -230.900478) (xy 360.850179 -230.926445) (xy 361.130089 -230.926445)
			(xy 361.130089 -230.874511) (xy 361.138214 -230.823216) (xy 361.154262 -230.773823) (xy 361.17784 -230.727549)
			(xy 361.208366 -230.685533) (xy 361.245089 -230.64881) (xy 361.287105 -230.618284) (xy 361.333379 -230.594706)
			(xy 361.382772 -230.578658) (xy 361.434067 -230.570533) (xy 361.486001 -230.570533) (xy 361.537296 -230.578658)
			(xy 361.586689 -230.594706) (xy 361.632963 -230.618284) (xy 361.674979 -230.64881) (xy 361.711702 -230.685533)
			(xy 361.742228 -230.727549) (xy 361.765806 -230.773823) (xy 361.781854 -230.823216) (xy 361.789979 -230.874511)
			(xy 361.790488 -230.900478) (xy 361.789979 -230.926445) (xy 362.070143 -230.926445) (xy 362.070143 -230.874511)
			(xy 362.078268 -230.823216) (xy 362.094316 -230.773823) (xy 362.117894 -230.727549) (xy 362.14842 -230.685533)
			(xy 362.185143 -230.64881) (xy 362.227159 -230.618284) (xy 362.273433 -230.594706) (xy 362.322826 -230.578658)
			(xy 362.374121 -230.570533) (xy 362.426055 -230.570533) (xy 362.47735 -230.578658) (xy 362.526743 -230.594706)
			(xy 362.573017 -230.618284) (xy 362.615033 -230.64881) (xy 362.651756 -230.685533) (xy 362.682282 -230.727549)
			(xy 362.70586 -230.773823) (xy 362.721908 -230.823216) (xy 362.730033 -230.874511) (xy 362.730542 -230.900478)
			(xy 362.730033 -230.926445) (xy 363.009689 -230.926445) (xy 363.009689 -230.874511) (xy 363.017814 -230.823216)
			(xy 363.033862 -230.773823) (xy 363.05744 -230.727549) (xy 363.087966 -230.685533) (xy 363.124689 -230.64881)
			(xy 363.166705 -230.618284) (xy 363.212979 -230.594706) (xy 363.262372 -230.578658) (xy 363.313667 -230.570533)
			(xy 363.365601 -230.570533) (xy 363.416896 -230.578658) (xy 363.466289 -230.594706) (xy 363.512563 -230.618284)
			(xy 363.554579 -230.64881) (xy 363.591302 -230.685533) (xy 363.621828 -230.727549) (xy 363.645406 -230.773823)
			(xy 363.661454 -230.823216) (xy 363.669579 -230.874511) (xy 363.670088 -230.900478) (xy 363.669579 -230.926445)
			(xy 363.949489 -230.926445) (xy 363.949489 -230.874511) (xy 363.957614 -230.823216) (xy 363.973662 -230.773823)
			(xy 363.99724 -230.727549) (xy 364.027766 -230.685533) (xy 364.064489 -230.64881) (xy 364.106505 -230.618284)
			(xy 364.152779 -230.594706) (xy 364.202172 -230.578658) (xy 364.253467 -230.570533) (xy 364.305401 -230.570533)
			(xy 364.356696 -230.578658) (xy 364.406089 -230.594706) (xy 364.452363 -230.618284) (xy 364.494379 -230.64881)
			(xy 364.531102 -230.685533) (xy 364.561628 -230.727549) (xy 364.585206 -230.773823) (xy 364.601254 -230.823216)
			(xy 364.609379 -230.874511) (xy 364.609888 -230.900478) (xy 364.609379 -230.926445) (xy 364.889289 -230.926445)
			(xy 364.889289 -230.874511) (xy 364.897414 -230.823216) (xy 364.913462 -230.773823) (xy 364.93704 -230.727549)
			(xy 364.967566 -230.685533) (xy 365.004289 -230.64881) (xy 365.046305 -230.618284) (xy 365.092579 -230.594706)
			(xy 365.141972 -230.578658) (xy 365.193267 -230.570533) (xy 365.245201 -230.570533) (xy 365.296496 -230.578658)
			(xy 365.345889 -230.594706) (xy 365.392163 -230.618284) (xy 365.434179 -230.64881) (xy 365.470902 -230.685533)
			(xy 365.501428 -230.727549) (xy 365.525006 -230.773823) (xy 365.541054 -230.823216) (xy 365.549179 -230.874511)
			(xy 365.549688 -230.900478) (xy 365.549179 -230.926445) (xy 365.829089 -230.926445) (xy 365.829089 -230.874511)
			(xy 365.837214 -230.823216) (xy 365.853262 -230.773823) (xy 365.87684 -230.727549) (xy 365.907366 -230.685533)
			(xy 365.944089 -230.64881) (xy 365.986105 -230.618284) (xy 366.032379 -230.594706) (xy 366.081772 -230.578658)
			(xy 366.133067 -230.570533) (xy 366.185001 -230.570533) (xy 366.236296 -230.578658) (xy 366.285689 -230.594706)
			(xy 366.331963 -230.618284) (xy 366.373979 -230.64881) (xy 366.410702 -230.685533) (xy 366.441228 -230.727549)
			(xy 366.464806 -230.773823) (xy 366.480854 -230.823216) (xy 366.488979 -230.874511) (xy 366.489488 -230.900478)
			(xy 366.488979 -230.926445) (xy 366.768889 -230.926445) (xy 366.768889 -230.874511) (xy 366.777014 -230.823216)
			(xy 366.793062 -230.773823) (xy 366.81664 -230.727549) (xy 366.847166 -230.685533) (xy 366.883889 -230.64881)
			(xy 366.925905 -230.618284) (xy 366.972179 -230.594706) (xy 367.021572 -230.578658) (xy 367.072867 -230.570533)
			(xy 367.124801 -230.570533) (xy 367.176096 -230.578658) (xy 367.225489 -230.594706) (xy 367.271763 -230.618284)
			(xy 367.313779 -230.64881) (xy 367.350502 -230.685533) (xy 367.381028 -230.727549) (xy 367.404606 -230.773823)
			(xy 367.420654 -230.823216) (xy 367.428779 -230.874511) (xy 367.429288 -230.900478) (xy 367.428779 -230.926445)
			(xy 367.708689 -230.926445) (xy 367.708689 -230.874511) (xy 367.716814 -230.823216) (xy 367.732862 -230.773823)
			(xy 367.75644 -230.727549) (xy 367.786966 -230.685533) (xy 367.823689 -230.64881) (xy 367.865705 -230.618284)
			(xy 367.911979 -230.594706) (xy 367.961372 -230.578658) (xy 368.012667 -230.570533) (xy 368.064601 -230.570533)
			(xy 368.115896 -230.578658) (xy 368.165289 -230.594706) (xy 368.211563 -230.618284) (xy 368.253579 -230.64881)
			(xy 368.290302 -230.685533) (xy 368.320828 -230.727549) (xy 368.344406 -230.773823) (xy 368.360454 -230.823216)
			(xy 368.368579 -230.874511) (xy 368.369088 -230.900478) (xy 368.368579 -230.926445) (xy 368.648489 -230.926445)
			(xy 368.648489 -230.874511) (xy 368.656614 -230.823216) (xy 368.672662 -230.773823) (xy 368.69624 -230.727549)
			(xy 368.726766 -230.685533) (xy 368.763489 -230.64881) (xy 368.805505 -230.618284) (xy 368.851779 -230.594706)
			(xy 368.901172 -230.578658) (xy 368.952467 -230.570533) (xy 369.004401 -230.570533) (xy 369.055696 -230.578658)
			(xy 369.105089 -230.594706) (xy 369.151363 -230.618284) (xy 369.193379 -230.64881) (xy 369.230102 -230.685533)
			(xy 369.260628 -230.727549) (xy 369.284206 -230.773823) (xy 369.300254 -230.823216) (xy 369.308379 -230.874511)
			(xy 369.308888 -230.900478) (xy 369.308379 -230.926445) (xy 369.588035 -230.926445) (xy 369.588035 -230.874511)
			(xy 369.59616 -230.823216) (xy 369.612208 -230.773823) (xy 369.635786 -230.727549) (xy 369.666312 -230.685533)
			(xy 369.703035 -230.64881) (xy 369.745051 -230.618284) (xy 369.791325 -230.594706) (xy 369.840718 -230.578658)
			(xy 369.892013 -230.570533) (xy 369.943947 -230.570533) (xy 369.995242 -230.578658) (xy 370.044635 -230.594706)
			(xy 370.090909 -230.618284) (xy 370.132925 -230.64881) (xy 370.169648 -230.685533) (xy 370.200174 -230.727549)
			(xy 370.223752 -230.773823) (xy 370.2398 -230.823216) (xy 370.247925 -230.874511) (xy 370.248434 -230.900478)
			(xy 370.247925 -230.926445) (xy 370.528089 -230.926445) (xy 370.528089 -230.874511) (xy 370.536214 -230.823216)
			(xy 370.552262 -230.773823) (xy 370.57584 -230.727549) (xy 370.606366 -230.685533) (xy 370.643089 -230.64881)
			(xy 370.685105 -230.618284) (xy 370.731379 -230.594706) (xy 370.780772 -230.578658) (xy 370.832067 -230.570533)
			(xy 370.884001 -230.570533) (xy 370.935296 -230.578658) (xy 370.984689 -230.594706) (xy 371.030963 -230.618284)
			(xy 371.072979 -230.64881) (xy 371.109702 -230.685533) (xy 371.140228 -230.727549) (xy 371.163806 -230.773823)
			(xy 371.179854 -230.823216) (xy 371.187979 -230.874511) (xy 371.188488 -230.900478) (xy 371.187979 -230.926445)
			(xy 371.467889 -230.926445) (xy 371.467889 -230.874511) (xy 371.476014 -230.823216) (xy 371.492062 -230.773823)
			(xy 371.51564 -230.727549) (xy 371.546166 -230.685533) (xy 371.582889 -230.64881) (xy 371.624905 -230.618284)
			(xy 371.671179 -230.594706) (xy 371.720572 -230.578658) (xy 371.771867 -230.570533) (xy 371.823801 -230.570533)
			(xy 371.875096 -230.578658) (xy 371.924489 -230.594706) (xy 371.970763 -230.618284) (xy 372.012779 -230.64881)
			(xy 372.049502 -230.685533) (xy 372.080028 -230.727549) (xy 372.103606 -230.773823) (xy 372.119654 -230.823216)
			(xy 372.127779 -230.874511) (xy 372.128288 -230.900478) (xy 372.127779 -230.926445) (xy 372.407689 -230.926445)
			(xy 372.407689 -230.874511) (xy 372.415814 -230.823216) (xy 372.431862 -230.773823) (xy 372.45544 -230.727549)
			(xy 372.485966 -230.685533) (xy 372.522689 -230.64881) (xy 372.564705 -230.618284) (xy 372.610979 -230.594706)
			(xy 372.660372 -230.578658) (xy 372.711667 -230.570533) (xy 372.763601 -230.570533) (xy 372.814896 -230.578658)
			(xy 372.864289 -230.594706) (xy 372.910563 -230.618284) (xy 372.952579 -230.64881) (xy 372.989302 -230.685533)
			(xy 373.019828 -230.727549) (xy 373.043406 -230.773823) (xy 373.059454 -230.823216) (xy 373.067579 -230.874511)
			(xy 373.068088 -230.900478) (xy 373.067579 -230.926445) (xy 373.347489 -230.926445) (xy 373.347489 -230.874511)
			(xy 373.355614 -230.823216) (xy 373.371662 -230.773823) (xy 373.39524 -230.727549) (xy 373.425766 -230.685533)
			(xy 373.462489 -230.64881) (xy 373.504505 -230.618284) (xy 373.550779 -230.594706) (xy 373.600172 -230.578658)
			(xy 373.651467 -230.570533) (xy 373.703401 -230.570533) (xy 373.754696 -230.578658) (xy 373.804089 -230.594706)
			(xy 373.850363 -230.618284) (xy 373.892379 -230.64881) (xy 373.929102 -230.685533) (xy 373.959628 -230.727549)
			(xy 373.983206 -230.773823) (xy 373.999254 -230.823216) (xy 374.007379 -230.874511) (xy 374.007888 -230.900478)
			(xy 374.007379 -230.926445) (xy 374.287289 -230.926445) (xy 374.287289 -230.874511) (xy 374.295414 -230.823216)
			(xy 374.311462 -230.773823) (xy 374.33504 -230.727549) (xy 374.365566 -230.685533) (xy 374.402289 -230.64881)
			(xy 374.444305 -230.618284) (xy 374.490579 -230.594706) (xy 374.539972 -230.578658) (xy 374.591267 -230.570533)
			(xy 374.643201 -230.570533) (xy 374.694496 -230.578658) (xy 374.743889 -230.594706) (xy 374.790163 -230.618284)
			(xy 374.832179 -230.64881) (xy 374.868902 -230.685533) (xy 374.899428 -230.727549) (xy 374.923006 -230.773823)
			(xy 374.939054 -230.823216) (xy 374.947179 -230.874511) (xy 374.947688 -230.900478) (xy 374.947179 -230.926445)
			(xy 375.227089 -230.926445) (xy 375.227089 -230.874511) (xy 375.235214 -230.823216) (xy 375.251262 -230.773823)
			(xy 375.27484 -230.727549) (xy 375.305366 -230.685533) (xy 375.342089 -230.64881) (xy 375.384105 -230.618284)
			(xy 375.430379 -230.594706) (xy 375.479772 -230.578658) (xy 375.531067 -230.570533) (xy 375.583001 -230.570533)
			(xy 375.634296 -230.578658) (xy 375.683689 -230.594706) (xy 375.729963 -230.618284) (xy 375.771979 -230.64881)
			(xy 375.808702 -230.685533) (xy 375.839228 -230.727549) (xy 375.862806 -230.773823) (xy 375.878854 -230.823216)
			(xy 375.886979 -230.874511) (xy 375.887488 -230.900478) (xy 375.886979 -230.926445) (xy 375.878854 -230.97774)
			(xy 375.862806 -231.027133) (xy 375.839228 -231.073407) (xy 375.808702 -231.115423) (xy 375.771979 -231.152146)
			(xy 375.729963 -231.182672) (xy 375.683689 -231.20625) (xy 375.634296 -231.222298) (xy 375.583001 -231.230423)
			(xy 375.531067 -231.230423) (xy 375.479772 -231.222298) (xy 375.430379 -231.20625) (xy 375.384105 -231.182672)
			(xy 375.342089 -231.152146) (xy 375.305366 -231.115423) (xy 375.27484 -231.073407) (xy 375.251262 -231.027133)
			(xy 375.235214 -230.97774) (xy 375.227089 -230.926445) (xy 374.947179 -230.926445) (xy 374.939054 -230.97774)
			(xy 374.923006 -231.027133) (xy 374.899428 -231.073407) (xy 374.868902 -231.115423) (xy 374.832179 -231.152146)
			(xy 374.790163 -231.182672) (xy 374.743889 -231.20625) (xy 374.694496 -231.222298) (xy 374.643201 -231.230423)
			(xy 374.591267 -231.230423) (xy 374.539972 -231.222298) (xy 374.490579 -231.20625) (xy 374.444305 -231.182672)
			(xy 374.402289 -231.152146) (xy 374.365566 -231.115423) (xy 374.33504 -231.073407) (xy 374.311462 -231.027133)
			(xy 374.295414 -230.97774) (xy 374.287289 -230.926445) (xy 374.007379 -230.926445) (xy 373.999254 -230.97774)
			(xy 373.983206 -231.027133) (xy 373.959628 -231.073407) (xy 373.929102 -231.115423) (xy 373.892379 -231.152146)
			(xy 373.850363 -231.182672) (xy 373.804089 -231.20625) (xy 373.754696 -231.222298) (xy 373.703401 -231.230423)
			(xy 373.651467 -231.230423) (xy 373.600172 -231.222298) (xy 373.550779 -231.20625) (xy 373.504505 -231.182672)
			(xy 373.462489 -231.152146) (xy 373.425766 -231.115423) (xy 373.39524 -231.073407) (xy 373.371662 -231.027133)
			(xy 373.355614 -230.97774) (xy 373.347489 -230.926445) (xy 373.067579 -230.926445) (xy 373.059454 -230.97774)
			(xy 373.043406 -231.027133) (xy 373.019828 -231.073407) (xy 372.989302 -231.115423) (xy 372.952579 -231.152146)
			(xy 372.910563 -231.182672) (xy 372.864289 -231.20625) (xy 372.814896 -231.222298) (xy 372.763601 -231.230423)
			(xy 372.711667 -231.230423) (xy 372.660372 -231.222298) (xy 372.610979 -231.20625) (xy 372.564705 -231.182672)
			(xy 372.522689 -231.152146) (xy 372.485966 -231.115423) (xy 372.45544 -231.073407) (xy 372.431862 -231.027133)
			(xy 372.415814 -230.97774) (xy 372.407689 -230.926445) (xy 372.127779 -230.926445) (xy 372.119654 -230.97774)
			(xy 372.103606 -231.027133) (xy 372.080028 -231.073407) (xy 372.049502 -231.115423) (xy 372.012779 -231.152146)
			(xy 371.970763 -231.182672) (xy 371.924489 -231.20625) (xy 371.875096 -231.222298) (xy 371.823801 -231.230423)
			(xy 371.771867 -231.230423) (xy 371.720572 -231.222298) (xy 371.671179 -231.20625) (xy 371.624905 -231.182672)
			(xy 371.582889 -231.152146) (xy 371.546166 -231.115423) (xy 371.51564 -231.073407) (xy 371.492062 -231.027133)
			(xy 371.476014 -230.97774) (xy 371.467889 -230.926445) (xy 371.187979 -230.926445) (xy 371.179854 -230.97774)
			(xy 371.163806 -231.027133) (xy 371.140228 -231.073407) (xy 371.109702 -231.115423) (xy 371.072979 -231.152146)
			(xy 371.030963 -231.182672) (xy 370.984689 -231.20625) (xy 370.935296 -231.222298) (xy 370.884001 -231.230423)
			(xy 370.832067 -231.230423) (xy 370.780772 -231.222298) (xy 370.731379 -231.20625) (xy 370.685105 -231.182672)
			(xy 370.643089 -231.152146) (xy 370.606366 -231.115423) (xy 370.57584 -231.073407) (xy 370.552262 -231.027133)
			(xy 370.536214 -230.97774) (xy 370.528089 -230.926445) (xy 370.247925 -230.926445) (xy 370.2398 -230.97774)
			(xy 370.223752 -231.027133) (xy 370.200174 -231.073407) (xy 370.169648 -231.115423) (xy 370.132925 -231.152146)
			(xy 370.090909 -231.182672) (xy 370.044635 -231.20625) (xy 369.995242 -231.222298) (xy 369.943947 -231.230423)
			(xy 369.892013 -231.230423) (xy 369.840718 -231.222298) (xy 369.791325 -231.20625) (xy 369.745051 -231.182672)
			(xy 369.703035 -231.152146) (xy 369.666312 -231.115423) (xy 369.635786 -231.073407) (xy 369.612208 -231.027133)
			(xy 369.59616 -230.97774) (xy 369.588035 -230.926445) (xy 369.308379 -230.926445) (xy 369.300254 -230.97774)
			(xy 369.284206 -231.027133) (xy 369.260628 -231.073407) (xy 369.230102 -231.115423) (xy 369.193379 -231.152146)
			(xy 369.151363 -231.182672) (xy 369.105089 -231.20625) (xy 369.055696 -231.222298) (xy 369.004401 -231.230423)
			(xy 368.952467 -231.230423) (xy 368.901172 -231.222298) (xy 368.851779 -231.20625) (xy 368.805505 -231.182672)
			(xy 368.763489 -231.152146) (xy 368.726766 -231.115423) (xy 368.69624 -231.073407) (xy 368.672662 -231.027133)
			(xy 368.656614 -230.97774) (xy 368.648489 -230.926445) (xy 368.368579 -230.926445) (xy 368.360454 -230.97774)
			(xy 368.344406 -231.027133) (xy 368.320828 -231.073407) (xy 368.290302 -231.115423) (xy 368.253579 -231.152146)
			(xy 368.211563 -231.182672) (xy 368.165289 -231.20625) (xy 368.115896 -231.222298) (xy 368.064601 -231.230423)
			(xy 368.012667 -231.230423) (xy 367.961372 -231.222298) (xy 367.911979 -231.20625) (xy 367.865705 -231.182672)
			(xy 367.823689 -231.152146) (xy 367.786966 -231.115423) (xy 367.75644 -231.073407) (xy 367.732862 -231.027133)
			(xy 367.716814 -230.97774) (xy 367.708689 -230.926445) (xy 367.428779 -230.926445) (xy 367.420654 -230.97774)
			(xy 367.404606 -231.027133) (xy 367.381028 -231.073407) (xy 367.350502 -231.115423) (xy 367.313779 -231.152146)
			(xy 367.271763 -231.182672) (xy 367.225489 -231.20625) (xy 367.176096 -231.222298) (xy 367.124801 -231.230423)
			(xy 367.072867 -231.230423) (xy 367.021572 -231.222298) (xy 366.972179 -231.20625) (xy 366.925905 -231.182672)
			(xy 366.883889 -231.152146) (xy 366.847166 -231.115423) (xy 366.81664 -231.073407) (xy 366.793062 -231.027133)
			(xy 366.777014 -230.97774) (xy 366.768889 -230.926445) (xy 366.488979 -230.926445) (xy 366.480854 -230.97774)
			(xy 366.464806 -231.027133) (xy 366.441228 -231.073407) (xy 366.410702 -231.115423) (xy 366.373979 -231.152146)
			(xy 366.331963 -231.182672) (xy 366.285689 -231.20625) (xy 366.236296 -231.222298) (xy 366.185001 -231.230423)
			(xy 366.133067 -231.230423) (xy 366.081772 -231.222298) (xy 366.032379 -231.20625) (xy 365.986105 -231.182672)
			(xy 365.944089 -231.152146) (xy 365.907366 -231.115423) (xy 365.87684 -231.073407) (xy 365.853262 -231.027133)
			(xy 365.837214 -230.97774) (xy 365.829089 -230.926445) (xy 365.549179 -230.926445) (xy 365.541054 -230.97774)
			(xy 365.525006 -231.027133) (xy 365.501428 -231.073407) (xy 365.470902 -231.115423) (xy 365.434179 -231.152146)
			(xy 365.392163 -231.182672) (xy 365.345889 -231.20625) (xy 365.296496 -231.222298) (xy 365.245201 -231.230423)
			(xy 365.193267 -231.230423) (xy 365.141972 -231.222298) (xy 365.092579 -231.20625) (xy 365.046305 -231.182672)
			(xy 365.004289 -231.152146) (xy 364.967566 -231.115423) (xy 364.93704 -231.073407) (xy 364.913462 -231.027133)
			(xy 364.897414 -230.97774) (xy 364.889289 -230.926445) (xy 364.609379 -230.926445) (xy 364.601254 -230.97774)
			(xy 364.585206 -231.027133) (xy 364.561628 -231.073407) (xy 364.531102 -231.115423) (xy 364.494379 -231.152146)
			(xy 364.452363 -231.182672) (xy 364.406089 -231.20625) (xy 364.356696 -231.222298) (xy 364.305401 -231.230423)
			(xy 364.253467 -231.230423) (xy 364.202172 -231.222298) (xy 364.152779 -231.20625) (xy 364.106505 -231.182672)
			(xy 364.064489 -231.152146) (xy 364.027766 -231.115423) (xy 363.99724 -231.073407) (xy 363.973662 -231.027133)
			(xy 363.957614 -230.97774) (xy 363.949489 -230.926445) (xy 363.669579 -230.926445) (xy 363.661454 -230.97774)
			(xy 363.645406 -231.027133) (xy 363.621828 -231.073407) (xy 363.591302 -231.115423) (xy 363.554579 -231.152146)
			(xy 363.512563 -231.182672) (xy 363.466289 -231.20625) (xy 363.416896 -231.222298) (xy 363.365601 -231.230423)
			(xy 363.313667 -231.230423) (xy 363.262372 -231.222298) (xy 363.212979 -231.20625) (xy 363.166705 -231.182672)
			(xy 363.124689 -231.152146) (xy 363.087966 -231.115423) (xy 363.05744 -231.073407) (xy 363.033862 -231.027133)
			(xy 363.017814 -230.97774) (xy 363.009689 -230.926445) (xy 362.730033 -230.926445) (xy 362.721908 -230.97774)
			(xy 362.70586 -231.027133) (xy 362.682282 -231.073407) (xy 362.651756 -231.115423) (xy 362.615033 -231.152146)
			(xy 362.573017 -231.182672) (xy 362.526743 -231.20625) (xy 362.47735 -231.222298) (xy 362.426055 -231.230423)
			(xy 362.374121 -231.230423) (xy 362.322826 -231.222298) (xy 362.273433 -231.20625) (xy 362.227159 -231.182672)
			(xy 362.185143 -231.152146) (xy 362.14842 -231.115423) (xy 362.117894 -231.073407) (xy 362.094316 -231.027133)
			(xy 362.078268 -230.97774) (xy 362.070143 -230.926445) (xy 361.789979 -230.926445) (xy 361.781854 -230.97774)
			(xy 361.765806 -231.027133) (xy 361.742228 -231.073407) (xy 361.711702 -231.115423) (xy 361.674979 -231.152146)
			(xy 361.632963 -231.182672) (xy 361.586689 -231.20625) (xy 361.537296 -231.222298) (xy 361.486001 -231.230423)
			(xy 361.434067 -231.230423) (xy 361.382772 -231.222298) (xy 361.333379 -231.20625) (xy 361.287105 -231.182672)
			(xy 361.245089 -231.152146) (xy 361.208366 -231.115423) (xy 361.17784 -231.073407) (xy 361.154262 -231.027133)
			(xy 361.138214 -230.97774) (xy 361.130089 -230.926445) (xy 360.850179 -230.926445) (xy 360.842054 -230.97774)
			(xy 360.826006 -231.027133) (xy 360.802428 -231.073407) (xy 360.771902 -231.115423) (xy 360.735179 -231.152146)
			(xy 360.693163 -231.182672) (xy 360.646889 -231.20625) (xy 360.597496 -231.222298) (xy 360.546201 -231.230423)
			(xy 360.494267 -231.230423) (xy 360.442972 -231.222298) (xy 360.393579 -231.20625) (xy 360.347305 -231.182672)
			(xy 360.305289 -231.152146) (xy 360.268566 -231.115423) (xy 360.23804 -231.073407) (xy 360.214462 -231.027133)
			(xy 360.198414 -230.97774) (xy 360.190289 -230.926445) (xy 359.910379 -230.926445) (xy 359.902254 -230.97774)
			(xy 359.886206 -231.027133) (xy 359.862628 -231.073407) (xy 359.832102 -231.115423) (xy 359.795379 -231.152146)
			(xy 359.753363 -231.182672) (xy 359.707089 -231.20625) (xy 359.657696 -231.222298) (xy 359.606401 -231.230423)
			(xy 359.554467 -231.230423) (xy 359.503172 -231.222298) (xy 359.453779 -231.20625) (xy 359.407505 -231.182672)
			(xy 359.365489 -231.152146) (xy 359.328766 -231.115423) (xy 359.29824 -231.073407) (xy 359.274662 -231.027133)
			(xy 359.258614 -230.97774) (xy 359.250489 -230.926445) (xy 358.970579 -230.926445) (xy 358.962454 -230.97774)
			(xy 358.946406 -231.027133) (xy 358.922828 -231.073407) (xy 358.892302 -231.115423) (xy 358.855579 -231.152146)
			(xy 358.813563 -231.182672) (xy 358.767289 -231.20625) (xy 358.717896 -231.222298) (xy 358.666601 -231.230423)
			(xy 358.614667 -231.230423) (xy 358.563372 -231.222298) (xy 358.513979 -231.20625) (xy 358.467705 -231.182672)
			(xy 358.425689 -231.152146) (xy 358.388966 -231.115423) (xy 358.35844 -231.073407) (xy 358.334862 -231.027133)
			(xy 358.318814 -230.97774) (xy 358.310689 -230.926445) (xy 358.030529 -230.926445) (xy 358.030523 -230.926733)
			(xy 358.022211 -230.978582) (xy 358.005808 -231.028465) (xy 357.981727 -231.075128) (xy 357.950573 -231.117399)
			(xy 357.932228 -231.13619) (xy 357.925973 -231.142816) (xy 357.918225 -231.159294) (xy 357.916762 -231.177443)
			(xy 357.92177 -231.19495) (xy 357.926894 -231.202484) (xy 357.954662 -231.24135) (xy 358.002396 -231.324091)
			(xy 358.022144 -231.367584) (xy 358.026175 -231.375746) (xy 358.03889 -231.388755) (xy 358.055341 -231.396518)
			(xy 358.073467 -231.398063) (xy 358.082342 -231.396032) (xy 358.104007 -231.390422) (xy 358.148357 -231.384435)
			(xy 358.170734 -231.384094) (xy 358.196696 -231.384606) (xy 358.247979 -231.392733) (xy 358.29736 -231.408782)
			(xy 358.343623 -231.432358) (xy 358.385628 -231.462881) (xy 358.422341 -231.499598) (xy 358.452859 -231.541607)
			(xy 358.476431 -231.587871) (xy 358.492475 -231.637254) (xy 358.500597 -231.688538) (xy 358.500597 -231.740462)
			(xy 358.500589 -231.740515) (xy 358.780335 -231.740515) (xy 358.780335 -231.688581) (xy 358.78846 -231.637286)
			(xy 358.804508 -231.587893) (xy 358.828086 -231.541619) (xy 358.858612 -231.499603) (xy 358.895335 -231.46288)
			(xy 358.937351 -231.432354) (xy 358.983625 -231.408776) (xy 359.033018 -231.392728) (xy 359.084313 -231.384603)
			(xy 359.136247 -231.384603) (xy 359.187542 -231.392728) (xy 359.236935 -231.408776) (xy 359.283209 -231.432354)
			(xy 359.325225 -231.46288) (xy 359.361948 -231.499603) (xy 359.392474 -231.541619) (xy 359.416052 -231.587893)
			(xy 359.4321 -231.637286) (xy 359.440225 -231.688581) (xy 359.440734 -231.714548) (xy 359.440225 -231.740515)
			(xy 359.720643 -231.740515) (xy 359.720643 -231.688581) (xy 359.728768 -231.637286) (xy 359.744816 -231.587893)
			(xy 359.768394 -231.541619) (xy 359.79892 -231.499603) (xy 359.835643 -231.46288) (xy 359.877659 -231.432354)
			(xy 359.923933 -231.408776) (xy 359.973326 -231.392728) (xy 360.024621 -231.384603) (xy 360.076555 -231.384603)
			(xy 360.12785 -231.392728) (xy 360.177243 -231.408776) (xy 360.223517 -231.432354) (xy 360.265533 -231.46288)
			(xy 360.302256 -231.499603) (xy 360.332782 -231.541619) (xy 360.35636 -231.587893) (xy 360.372408 -231.637286)
			(xy 360.380533 -231.688581) (xy 360.381042 -231.714548) (xy 360.380533 -231.740515) (xy 360.660443 -231.740515)
			(xy 360.660443 -231.688581) (xy 360.668568 -231.637286) (xy 360.684616 -231.587893) (xy 360.708194 -231.541619)
			(xy 360.73872 -231.499603) (xy 360.775443 -231.46288) (xy 360.817459 -231.432354) (xy 360.863733 -231.408776)
			(xy 360.913126 -231.392728) (xy 360.964421 -231.384603) (xy 361.016355 -231.384603) (xy 361.06765 -231.392728)
			(xy 361.117043 -231.408776) (xy 361.163317 -231.432354) (xy 361.205333 -231.46288) (xy 361.242056 -231.499603)
			(xy 361.272582 -231.541619) (xy 361.29616 -231.587893) (xy 361.312208 -231.637286) (xy 361.320333 -231.688581)
			(xy 361.320842 -231.714548) (xy 361.320333 -231.740515) (xy 361.600243 -231.740515) (xy 361.600243 -231.688581)
			(xy 361.608368 -231.637286) (xy 361.624416 -231.587893) (xy 361.647994 -231.541619) (xy 361.67852 -231.499603)
			(xy 361.715243 -231.46288) (xy 361.757259 -231.432354) (xy 361.803533 -231.408776) (xy 361.852926 -231.392728)
			(xy 361.904221 -231.384603) (xy 361.956155 -231.384603) (xy 362.00745 -231.392728) (xy 362.056843 -231.408776)
			(xy 362.103117 -231.432354) (xy 362.145133 -231.46288) (xy 362.181856 -231.499603) (xy 362.212382 -231.541619)
			(xy 362.23596 -231.587893) (xy 362.252008 -231.637286) (xy 362.260133 -231.688581) (xy 362.260642 -231.714548)
			(xy 362.260133 -231.740515) (xy 362.539535 -231.740515) (xy 362.539535 -231.688581) (xy 362.54766 -231.637286)
			(xy 362.563708 -231.587893) (xy 362.587286 -231.541619) (xy 362.617812 -231.499603) (xy 362.654535 -231.46288)
			(xy 362.696551 -231.432354) (xy 362.742825 -231.408776) (xy 362.792218 -231.392728) (xy 362.843513 -231.384603)
			(xy 362.895447 -231.384603) (xy 362.946742 -231.392728) (xy 362.996135 -231.408776) (xy 363.042409 -231.432354)
			(xy 363.084425 -231.46288) (xy 363.121148 -231.499603) (xy 363.151674 -231.541619) (xy 363.175252 -231.587893)
			(xy 363.1913 -231.637286) (xy 363.199425 -231.688581) (xy 363.199934 -231.714548) (xy 363.199425 -231.740515)
			(xy 363.479335 -231.740515) (xy 363.479335 -231.688581) (xy 363.48746 -231.637286) (xy 363.503508 -231.587893)
			(xy 363.527086 -231.541619) (xy 363.557612 -231.499603) (xy 363.594335 -231.46288) (xy 363.636351 -231.432354)
			(xy 363.682625 -231.408776) (xy 363.732018 -231.392728) (xy 363.783313 -231.384603) (xy 363.835247 -231.384603)
			(xy 363.886542 -231.392728) (xy 363.935935 -231.408776) (xy 363.982209 -231.432354) (xy 364.024225 -231.46288)
			(xy 364.060948 -231.499603) (xy 364.091474 -231.541619) (xy 364.115052 -231.587893) (xy 364.1311 -231.637286)
			(xy 364.139225 -231.688581) (xy 364.139734 -231.714548) (xy 364.139225 -231.740515) (xy 364.419135 -231.740515)
			(xy 364.419135 -231.688581) (xy 364.42726 -231.637286) (xy 364.443308 -231.587893) (xy 364.466886 -231.541619)
			(xy 364.497412 -231.499603) (xy 364.534135 -231.46288) (xy 364.576151 -231.432354) (xy 364.622425 -231.408776)
			(xy 364.671818 -231.392728) (xy 364.723113 -231.384603) (xy 364.775047 -231.384603) (xy 364.826342 -231.392728)
			(xy 364.875735 -231.408776) (xy 364.922009 -231.432354) (xy 364.964025 -231.46288) (xy 365.000748 -231.499603)
			(xy 365.031274 -231.541619) (xy 365.054852 -231.587893) (xy 365.0709 -231.637286) (xy 365.079025 -231.688581)
			(xy 365.079534 -231.714548) (xy 365.079025 -231.740515) (xy 365.358935 -231.740515) (xy 365.358935 -231.688581)
			(xy 365.36706 -231.637286) (xy 365.383108 -231.587893) (xy 365.406686 -231.541619) (xy 365.437212 -231.499603)
			(xy 365.473935 -231.46288) (xy 365.515951 -231.432354) (xy 365.562225 -231.408776) (xy 365.611618 -231.392728)
			(xy 365.662913 -231.384603) (xy 365.714847 -231.384603) (xy 365.766142 -231.392728) (xy 365.815535 -231.408776)
			(xy 365.861809 -231.432354) (xy 365.903825 -231.46288) (xy 365.940548 -231.499603) (xy 365.971074 -231.541619)
			(xy 365.994652 -231.587893) (xy 366.0107 -231.637286) (xy 366.018825 -231.688581) (xy 366.019334 -231.714548)
			(xy 366.018825 -231.740515) (xy 366.298735 -231.740515) (xy 366.298735 -231.688581) (xy 366.30686 -231.637286)
			(xy 366.322908 -231.587893) (xy 366.346486 -231.541619) (xy 366.377012 -231.499603) (xy 366.413735 -231.46288)
			(xy 366.455751 -231.432354) (xy 366.502025 -231.408776) (xy 366.551418 -231.392728) (xy 366.602713 -231.384603)
			(xy 366.654647 -231.384603) (xy 366.705942 -231.392728) (xy 366.755335 -231.408776) (xy 366.801609 -231.432354)
			(xy 366.843625 -231.46288) (xy 366.880348 -231.499603) (xy 366.910874 -231.541619) (xy 366.934452 -231.587893)
			(xy 366.9505 -231.637286) (xy 366.958625 -231.688581) (xy 366.959134 -231.714548) (xy 366.958625 -231.740515)
			(xy 367.239043 -231.740515) (xy 367.239043 -231.688581) (xy 367.247168 -231.637286) (xy 367.263216 -231.587893)
			(xy 367.286794 -231.541619) (xy 367.31732 -231.499603) (xy 367.354043 -231.46288) (xy 367.396059 -231.432354)
			(xy 367.442333 -231.408776) (xy 367.491726 -231.392728) (xy 367.543021 -231.384603) (xy 367.594955 -231.384603)
			(xy 367.64625 -231.392728) (xy 367.695643 -231.408776) (xy 367.741917 -231.432354) (xy 367.783933 -231.46288)
			(xy 367.820656 -231.499603) (xy 367.851182 -231.541619) (xy 367.87476 -231.587893) (xy 367.890808 -231.637286)
			(xy 367.898933 -231.688581) (xy 367.899442 -231.714548) (xy 367.898933 -231.740515) (xy 368.178335 -231.740515)
			(xy 368.178335 -231.688581) (xy 368.18646 -231.637286) (xy 368.202508 -231.587893) (xy 368.226086 -231.541619)
			(xy 368.256612 -231.499603) (xy 368.293335 -231.46288) (xy 368.335351 -231.432354) (xy 368.381625 -231.408776)
			(xy 368.431018 -231.392728) (xy 368.482313 -231.384603) (xy 368.534247 -231.384603) (xy 368.585542 -231.392728)
			(xy 368.634935 -231.408776) (xy 368.681209 -231.432354) (xy 368.723225 -231.46288) (xy 368.759948 -231.499603)
			(xy 368.790474 -231.541619) (xy 368.814052 -231.587893) (xy 368.8301 -231.637286) (xy 368.838225 -231.688581)
			(xy 368.838734 -231.714548) (xy 368.838225 -231.740515) (xy 369.118643 -231.740515) (xy 369.118643 -231.688581)
			(xy 369.126768 -231.637286) (xy 369.142816 -231.587893) (xy 369.166394 -231.541619) (xy 369.19692 -231.499603)
			(xy 369.233643 -231.46288) (xy 369.275659 -231.432354) (xy 369.321933 -231.408776) (xy 369.371326 -231.392728)
			(xy 369.422621 -231.384603) (xy 369.474555 -231.384603) (xy 369.52585 -231.392728) (xy 369.575243 -231.408776)
			(xy 369.621517 -231.432354) (xy 369.663533 -231.46288) (xy 369.700256 -231.499603) (xy 369.730782 -231.541619)
			(xy 369.75436 -231.587893) (xy 369.770408 -231.637286) (xy 369.778533 -231.688581) (xy 369.779042 -231.714548)
			(xy 369.778533 -231.740515) (xy 370.058189 -231.740515) (xy 370.058189 -231.688581) (xy 370.066314 -231.637286)
			(xy 370.082362 -231.587893) (xy 370.10594 -231.541619) (xy 370.136466 -231.499603) (xy 370.173189 -231.46288)
			(xy 370.215205 -231.432354) (xy 370.261479 -231.408776) (xy 370.310872 -231.392728) (xy 370.362167 -231.384603)
			(xy 370.414101 -231.384603) (xy 370.465396 -231.392728) (xy 370.514789 -231.408776) (xy 370.561063 -231.432354)
			(xy 370.603079 -231.46288) (xy 370.639802 -231.499603) (xy 370.670328 -231.541619) (xy 370.693906 -231.587893)
			(xy 370.709954 -231.637286) (xy 370.718079 -231.688581) (xy 370.718588 -231.714548) (xy 370.718079 -231.740515)
			(xy 370.997735 -231.740515) (xy 370.997735 -231.688581) (xy 371.00586 -231.637286) (xy 371.021908 -231.587893)
			(xy 371.045486 -231.541619) (xy 371.076012 -231.499603) (xy 371.112735 -231.46288) (xy 371.154751 -231.432354)
			(xy 371.201025 -231.408776) (xy 371.250418 -231.392728) (xy 371.301713 -231.384603) (xy 371.353647 -231.384603)
			(xy 371.404942 -231.392728) (xy 371.454335 -231.408776) (xy 371.500609 -231.432354) (xy 371.542625 -231.46288)
			(xy 371.579348 -231.499603) (xy 371.609874 -231.541619) (xy 371.633452 -231.587893) (xy 371.6495 -231.637286)
			(xy 371.657625 -231.688581) (xy 371.658134 -231.714548) (xy 371.657625 -231.740515) (xy 371.937535 -231.740515)
			(xy 371.937535 -231.688581) (xy 371.94566 -231.637286) (xy 371.961708 -231.587893) (xy 371.985286 -231.541619)
			(xy 372.015812 -231.499603) (xy 372.052535 -231.46288) (xy 372.094551 -231.432354) (xy 372.140825 -231.408776)
			(xy 372.190218 -231.392728) (xy 372.241513 -231.384603) (xy 372.293447 -231.384603) (xy 372.344742 -231.392728)
			(xy 372.394135 -231.408776) (xy 372.440409 -231.432354) (xy 372.482425 -231.46288) (xy 372.519148 -231.499603)
			(xy 372.549674 -231.541619) (xy 372.573252 -231.587893) (xy 372.5893 -231.637286) (xy 372.597425 -231.688581)
			(xy 372.597934 -231.714548) (xy 372.597425 -231.740515) (xy 372.877335 -231.740515) (xy 372.877335 -231.688581)
			(xy 372.88546 -231.637286) (xy 372.901508 -231.587893) (xy 372.925086 -231.541619) (xy 372.955612 -231.499603)
			(xy 372.992335 -231.46288) (xy 373.034351 -231.432354) (xy 373.080625 -231.408776) (xy 373.130018 -231.392728)
			(xy 373.181313 -231.384603) (xy 373.233247 -231.384603) (xy 373.284542 -231.392728) (xy 373.333935 -231.408776)
			(xy 373.380209 -231.432354) (xy 373.422225 -231.46288) (xy 373.458948 -231.499603) (xy 373.489474 -231.541619)
			(xy 373.513052 -231.587893) (xy 373.5291 -231.637286) (xy 373.537225 -231.688581) (xy 373.537734 -231.714548)
			(xy 373.537225 -231.740515) (xy 373.817135 -231.740515) (xy 373.817135 -231.688581) (xy 373.82526 -231.637286)
			(xy 373.841308 -231.587893) (xy 373.864886 -231.541619) (xy 373.895412 -231.499603) (xy 373.932135 -231.46288)
			(xy 373.974151 -231.432354) (xy 374.020425 -231.408776) (xy 374.069818 -231.392728) (xy 374.121113 -231.384603)
			(xy 374.173047 -231.384603) (xy 374.224342 -231.392728) (xy 374.273735 -231.408776) (xy 374.320009 -231.432354)
			(xy 374.362025 -231.46288) (xy 374.398748 -231.499603) (xy 374.429274 -231.541619) (xy 374.452852 -231.587893)
			(xy 374.4689 -231.637286) (xy 374.477025 -231.688581) (xy 374.477534 -231.714548) (xy 374.477025 -231.740515)
			(xy 374.756935 -231.740515) (xy 374.756935 -231.688581) (xy 374.76506 -231.637286) (xy 374.781108 -231.587893)
			(xy 374.804686 -231.541619) (xy 374.835212 -231.499603) (xy 374.871935 -231.46288) (xy 374.913951 -231.432354)
			(xy 374.960225 -231.408776) (xy 375.009618 -231.392728) (xy 375.060913 -231.384603) (xy 375.112847 -231.384603)
			(xy 375.164142 -231.392728) (xy 375.213535 -231.408776) (xy 375.259809 -231.432354) (xy 375.301825 -231.46288)
			(xy 375.338548 -231.499603) (xy 375.369074 -231.541619) (xy 375.392652 -231.587893) (xy 375.4087 -231.637286)
			(xy 375.416825 -231.688581) (xy 375.417334 -231.714548) (xy 375.416825 -231.740515) (xy 375.4087 -231.79181)
			(xy 375.392652 -231.841203) (xy 375.369074 -231.887477) (xy 375.338548 -231.929493) (xy 375.301825 -231.966216)
			(xy 375.259809 -231.996742) (xy 375.213535 -232.02032) (xy 375.164142 -232.036368) (xy 375.112847 -232.044493)
			(xy 375.060913 -232.044493) (xy 375.009618 -232.036368) (xy 374.960225 -232.02032) (xy 374.913951 -231.996742)
			(xy 374.871935 -231.966216) (xy 374.835212 -231.929493) (xy 374.804686 -231.887477) (xy 374.781108 -231.841203)
			(xy 374.76506 -231.79181) (xy 374.756935 -231.740515) (xy 374.477025 -231.740515) (xy 374.4689 -231.79181)
			(xy 374.452852 -231.841203) (xy 374.429274 -231.887477) (xy 374.398748 -231.929493) (xy 374.362025 -231.966216)
			(xy 374.320009 -231.996742) (xy 374.273735 -232.02032) (xy 374.224342 -232.036368) (xy 374.173047 -232.044493)
			(xy 374.121113 -232.044493) (xy 374.069818 -232.036368) (xy 374.020425 -232.02032) (xy 373.974151 -231.996742)
			(xy 373.932135 -231.966216) (xy 373.895412 -231.929493) (xy 373.864886 -231.887477) (xy 373.841308 -231.841203)
			(xy 373.82526 -231.79181) (xy 373.817135 -231.740515) (xy 373.537225 -231.740515) (xy 373.5291 -231.79181)
			(xy 373.513052 -231.841203) (xy 373.489474 -231.887477) (xy 373.458948 -231.929493) (xy 373.422225 -231.966216)
			(xy 373.380209 -231.996742) (xy 373.333935 -232.02032) (xy 373.284542 -232.036368) (xy 373.233247 -232.044493)
			(xy 373.181313 -232.044493) (xy 373.130018 -232.036368) (xy 373.080625 -232.02032) (xy 373.034351 -231.996742)
			(xy 372.992335 -231.966216) (xy 372.955612 -231.929493) (xy 372.925086 -231.887477) (xy 372.901508 -231.841203)
			(xy 372.88546 -231.79181) (xy 372.877335 -231.740515) (xy 372.597425 -231.740515) (xy 372.5893 -231.79181)
			(xy 372.573252 -231.841203) (xy 372.549674 -231.887477) (xy 372.519148 -231.929493) (xy 372.482425 -231.966216)
			(xy 372.440409 -231.996742) (xy 372.394135 -232.02032) (xy 372.344742 -232.036368) (xy 372.293447 -232.044493)
			(xy 372.241513 -232.044493) (xy 372.190218 -232.036368) (xy 372.140825 -232.02032) (xy 372.094551 -231.996742)
			(xy 372.052535 -231.966216) (xy 372.015812 -231.929493) (xy 371.985286 -231.887477) (xy 371.961708 -231.841203)
			(xy 371.94566 -231.79181) (xy 371.937535 -231.740515) (xy 371.657625 -231.740515) (xy 371.6495 -231.79181)
			(xy 371.633452 -231.841203) (xy 371.609874 -231.887477) (xy 371.579348 -231.929493) (xy 371.542625 -231.966216)
			(xy 371.500609 -231.996742) (xy 371.454335 -232.02032) (xy 371.404942 -232.036368) (xy 371.353647 -232.044493)
			(xy 371.301713 -232.044493) (xy 371.250418 -232.036368) (xy 371.201025 -232.02032) (xy 371.154751 -231.996742)
			(xy 371.112735 -231.966216) (xy 371.076012 -231.929493) (xy 371.045486 -231.887477) (xy 371.021908 -231.841203)
			(xy 371.00586 -231.79181) (xy 370.997735 -231.740515) (xy 370.718079 -231.740515) (xy 370.709954 -231.79181)
			(xy 370.693906 -231.841203) (xy 370.670328 -231.887477) (xy 370.639802 -231.929493) (xy 370.603079 -231.966216)
			(xy 370.561063 -231.996742) (xy 370.514789 -232.02032) (xy 370.465396 -232.036368) (xy 370.414101 -232.044493)
			(xy 370.362167 -232.044493) (xy 370.310872 -232.036368) (xy 370.261479 -232.02032) (xy 370.215205 -231.996742)
			(xy 370.173189 -231.966216) (xy 370.136466 -231.929493) (xy 370.10594 -231.887477) (xy 370.082362 -231.841203)
			(xy 370.066314 -231.79181) (xy 370.058189 -231.740515) (xy 369.778533 -231.740515) (xy 369.770408 -231.79181)
			(xy 369.75436 -231.841203) (xy 369.730782 -231.887477) (xy 369.700256 -231.929493) (xy 369.663533 -231.966216)
			(xy 369.621517 -231.996742) (xy 369.575243 -232.02032) (xy 369.52585 -232.036368) (xy 369.474555 -232.044493)
			(xy 369.422621 -232.044493) (xy 369.371326 -232.036368) (xy 369.321933 -232.02032) (xy 369.275659 -231.996742)
			(xy 369.233643 -231.966216) (xy 369.19692 -231.929493) (xy 369.166394 -231.887477) (xy 369.142816 -231.841203)
			(xy 369.126768 -231.79181) (xy 369.118643 -231.740515) (xy 368.838225 -231.740515) (xy 368.8301 -231.79181)
			(xy 368.814052 -231.841203) (xy 368.790474 -231.887477) (xy 368.759948 -231.929493) (xy 368.723225 -231.966216)
			(xy 368.681209 -231.996742) (xy 368.634935 -232.02032) (xy 368.585542 -232.036368) (xy 368.534247 -232.044493)
			(xy 368.482313 -232.044493) (xy 368.431018 -232.036368) (xy 368.381625 -232.02032) (xy 368.335351 -231.996742)
			(xy 368.293335 -231.966216) (xy 368.256612 -231.929493) (xy 368.226086 -231.887477) (xy 368.202508 -231.841203)
			(xy 368.18646 -231.79181) (xy 368.178335 -231.740515) (xy 367.898933 -231.740515) (xy 367.890808 -231.79181)
			(xy 367.87476 -231.841203) (xy 367.851182 -231.887477) (xy 367.820656 -231.929493) (xy 367.783933 -231.966216)
			(xy 367.741917 -231.996742) (xy 367.695643 -232.02032) (xy 367.64625 -232.036368) (xy 367.594955 -232.044493)
			(xy 367.543021 -232.044493) (xy 367.491726 -232.036368) (xy 367.442333 -232.02032) (xy 367.396059 -231.996742)
			(xy 367.354043 -231.966216) (xy 367.31732 -231.929493) (xy 367.286794 -231.887477) (xy 367.263216 -231.841203)
			(xy 367.247168 -231.79181) (xy 367.239043 -231.740515) (xy 366.958625 -231.740515) (xy 366.9505 -231.79181)
			(xy 366.934452 -231.841203) (xy 366.910874 -231.887477) (xy 366.880348 -231.929493) (xy 366.843625 -231.966216)
			(xy 366.801609 -231.996742) (xy 366.755335 -232.02032) (xy 366.705942 -232.036368) (xy 366.654647 -232.044493)
			(xy 366.602713 -232.044493) (xy 366.551418 -232.036368) (xy 366.502025 -232.02032) (xy 366.455751 -231.996742)
			(xy 366.413735 -231.966216) (xy 366.377012 -231.929493) (xy 366.346486 -231.887477) (xy 366.322908 -231.841203)
			(xy 366.30686 -231.79181) (xy 366.298735 -231.740515) (xy 366.018825 -231.740515) (xy 366.0107 -231.79181)
			(xy 365.994652 -231.841203) (xy 365.971074 -231.887477) (xy 365.940548 -231.929493) (xy 365.903825 -231.966216)
			(xy 365.861809 -231.996742) (xy 365.815535 -232.02032) (xy 365.766142 -232.036368) (xy 365.714847 -232.044493)
			(xy 365.662913 -232.044493) (xy 365.611618 -232.036368) (xy 365.562225 -232.02032) (xy 365.515951 -231.996742)
			(xy 365.473935 -231.966216) (xy 365.437212 -231.929493) (xy 365.406686 -231.887477) (xy 365.383108 -231.841203)
			(xy 365.36706 -231.79181) (xy 365.358935 -231.740515) (xy 365.079025 -231.740515) (xy 365.0709 -231.79181)
			(xy 365.054852 -231.841203) (xy 365.031274 -231.887477) (xy 365.000748 -231.929493) (xy 364.964025 -231.966216)
			(xy 364.922009 -231.996742) (xy 364.875735 -232.02032) (xy 364.826342 -232.036368) (xy 364.775047 -232.044493)
			(xy 364.723113 -232.044493) (xy 364.671818 -232.036368) (xy 364.622425 -232.02032) (xy 364.576151 -231.996742)
			(xy 364.534135 -231.966216) (xy 364.497412 -231.929493) (xy 364.466886 -231.887477) (xy 364.443308 -231.841203)
			(xy 364.42726 -231.79181) (xy 364.419135 -231.740515) (xy 364.139225 -231.740515) (xy 364.1311 -231.79181)
			(xy 364.115052 -231.841203) (xy 364.091474 -231.887477) (xy 364.060948 -231.929493) (xy 364.024225 -231.966216)
			(xy 363.982209 -231.996742) (xy 363.935935 -232.02032) (xy 363.886542 -232.036368) (xy 363.835247 -232.044493)
			(xy 363.783313 -232.044493) (xy 363.732018 -232.036368) (xy 363.682625 -232.02032) (xy 363.636351 -231.996742)
			(xy 363.594335 -231.966216) (xy 363.557612 -231.929493) (xy 363.527086 -231.887477) (xy 363.503508 -231.841203)
			(xy 363.48746 -231.79181) (xy 363.479335 -231.740515) (xy 363.199425 -231.740515) (xy 363.1913 -231.79181)
			(xy 363.175252 -231.841203) (xy 363.151674 -231.887477) (xy 363.121148 -231.929493) (xy 363.084425 -231.966216)
			(xy 363.042409 -231.996742) (xy 362.996135 -232.02032) (xy 362.946742 -232.036368) (xy 362.895447 -232.044493)
			(xy 362.843513 -232.044493) (xy 362.792218 -232.036368) (xy 362.742825 -232.02032) (xy 362.696551 -231.996742)
			(xy 362.654535 -231.966216) (xy 362.617812 -231.929493) (xy 362.587286 -231.887477) (xy 362.563708 -231.841203)
			(xy 362.54766 -231.79181) (xy 362.539535 -231.740515) (xy 362.260133 -231.740515) (xy 362.252008 -231.79181)
			(xy 362.23596 -231.841203) (xy 362.212382 -231.887477) (xy 362.181856 -231.929493) (xy 362.145133 -231.966216)
			(xy 362.103117 -231.996742) (xy 362.056843 -232.02032) (xy 362.00745 -232.036368) (xy 361.956155 -232.044493)
			(xy 361.904221 -232.044493) (xy 361.852926 -232.036368) (xy 361.803533 -232.02032) (xy 361.757259 -231.996742)
			(xy 361.715243 -231.966216) (xy 361.67852 -231.929493) (xy 361.647994 -231.887477) (xy 361.624416 -231.841203)
			(xy 361.608368 -231.79181) (xy 361.600243 -231.740515) (xy 361.320333 -231.740515) (xy 361.312208 -231.79181)
			(xy 361.29616 -231.841203) (xy 361.272582 -231.887477) (xy 361.242056 -231.929493) (xy 361.205333 -231.966216)
			(xy 361.163317 -231.996742) (xy 361.117043 -232.02032) (xy 361.06765 -232.036368) (xy 361.016355 -232.044493)
			(xy 360.964421 -232.044493) (xy 360.913126 -232.036368) (xy 360.863733 -232.02032) (xy 360.817459 -231.996742)
			(xy 360.775443 -231.966216) (xy 360.73872 -231.929493) (xy 360.708194 -231.887477) (xy 360.684616 -231.841203)
			(xy 360.668568 -231.79181) (xy 360.660443 -231.740515) (xy 360.380533 -231.740515) (xy 360.372408 -231.79181)
			(xy 360.35636 -231.841203) (xy 360.332782 -231.887477) (xy 360.302256 -231.929493) (xy 360.265533 -231.966216)
			(xy 360.223517 -231.996742) (xy 360.177243 -232.02032) (xy 360.12785 -232.036368) (xy 360.076555 -232.044493)
			(xy 360.024621 -232.044493) (xy 359.973326 -232.036368) (xy 359.923933 -232.02032) (xy 359.877659 -231.996742)
			(xy 359.835643 -231.966216) (xy 359.79892 -231.929493) (xy 359.768394 -231.887477) (xy 359.744816 -231.841203)
			(xy 359.728768 -231.79181) (xy 359.720643 -231.740515) (xy 359.440225 -231.740515) (xy 359.4321 -231.79181)
			(xy 359.416052 -231.841203) (xy 359.392474 -231.887477) (xy 359.361948 -231.929493) (xy 359.325225 -231.966216)
			(xy 359.283209 -231.996742) (xy 359.236935 -232.02032) (xy 359.187542 -232.036368) (xy 359.136247 -232.044493)
			(xy 359.084313 -232.044493) (xy 359.033018 -232.036368) (xy 358.983625 -232.02032) (xy 358.937351 -231.996742)
			(xy 358.895335 -231.966216) (xy 358.858612 -231.929493) (xy 358.828086 -231.887477) (xy 358.804508 -231.841203)
			(xy 358.78846 -231.79181) (xy 358.780335 -231.740515) (xy 358.500589 -231.740515) (xy 358.492475 -231.791746)
			(xy 358.476431 -231.841129) (xy 358.452859 -231.887394) (xy 358.422341 -231.929402) (xy 358.385628 -231.966119)
			(xy 358.343623 -231.996642) (xy 358.29736 -232.020218) (xy 358.247979 -232.036267) (xy 358.196696 -232.044394)
			(xy 358.170734 -232.045002) (xy 358.148359 -232.044646) (xy 358.10401 -232.038656) (xy 358.082342 -232.033064)
			(xy 358.073469 -232.030963) (xy 358.055312 -232.032483) (xy 358.038832 -232.040258) (xy 358.026113 -232.053305)
			(xy 358.022144 -232.061512) (xy 358.002449 -232.104933) (xy 357.954837 -232.187543) (xy 357.927148 -232.226358)
			(xy 357.922087 -232.233915) (xy 357.917151 -232.251405) (xy 357.918611 -232.269521) (xy 357.926284 -232.285995)
			(xy 357.932482 -232.292652) (xy 357.950854 -232.311418) (xy 357.982012 -232.353689) (xy 358.006088 -232.400359)
			(xy 358.022474 -232.450251) (xy 358.030759 -232.502107) (xy 358.031288 -232.528364) (xy 358.0308 -232.554093)
			(xy 358.030763 -232.554331) (xy 358.310689 -232.554331) (xy 358.310689 -232.502397) (xy 358.318814 -232.451102)
			(xy 358.334862 -232.401709) (xy 358.35844 -232.355435) (xy 358.388966 -232.313419) (xy 358.425689 -232.276696)
			(xy 358.467705 -232.24617) (xy 358.513979 -232.222592) (xy 358.563372 -232.206544) (xy 358.614667 -232.198419)
			(xy 358.666601 -232.198419) (xy 358.717896 -232.206544) (xy 358.767289 -232.222592) (xy 358.813563 -232.24617)
			(xy 358.855579 -232.276696) (xy 358.892302 -232.313419) (xy 358.922828 -232.355435) (xy 358.946406 -232.401709)
			(xy 358.962454 -232.451102) (xy 358.970579 -232.502397) (xy 358.971088 -232.528364) (xy 358.970579 -232.554331)
			(xy 359.250489 -232.554331) (xy 359.250489 -232.502397) (xy 359.258614 -232.451102) (xy 359.274662 -232.401709)
			(xy 359.29824 -232.355435) (xy 359.328766 -232.313419) (xy 359.365489 -232.276696) (xy 359.407505 -232.24617)
			(xy 359.453779 -232.222592) (xy 359.503172 -232.206544) (xy 359.554467 -232.198419) (xy 359.606401 -232.198419)
			(xy 359.657696 -232.206544) (xy 359.707089 -232.222592) (xy 359.753363 -232.24617) (xy 359.795379 -232.276696)
			(xy 359.832102 -232.313419) (xy 359.862628 -232.355435) (xy 359.886206 -232.401709) (xy 359.902254 -232.451102)
			(xy 359.910379 -232.502397) (xy 359.910888 -232.528364) (xy 359.910379 -232.554331) (xy 360.190289 -232.554331)
			(xy 360.190289 -232.502397) (xy 360.198414 -232.451102) (xy 360.214462 -232.401709) (xy 360.23804 -232.355435)
			(xy 360.268566 -232.313419) (xy 360.305289 -232.276696) (xy 360.347305 -232.24617) (xy 360.393579 -232.222592)
			(xy 360.442972 -232.206544) (xy 360.494267 -232.198419) (xy 360.546201 -232.198419) (xy 360.597496 -232.206544)
			(xy 360.646889 -232.222592) (xy 360.693163 -232.24617) (xy 360.735179 -232.276696) (xy 360.771902 -232.313419)
			(xy 360.802428 -232.355435) (xy 360.826006 -232.401709) (xy 360.842054 -232.451102) (xy 360.850179 -232.502397)
			(xy 360.850688 -232.528364) (xy 360.850179 -232.554331) (xy 361.130089 -232.554331) (xy 361.130089 -232.502397)
			(xy 361.138214 -232.451102) (xy 361.154262 -232.401709) (xy 361.17784 -232.355435) (xy 361.208366 -232.313419)
			(xy 361.245089 -232.276696) (xy 361.287105 -232.24617) (xy 361.333379 -232.222592) (xy 361.382772 -232.206544)
			(xy 361.434067 -232.198419) (xy 361.486001 -232.198419) (xy 361.537296 -232.206544) (xy 361.586689 -232.222592)
			(xy 361.632963 -232.24617) (xy 361.674979 -232.276696) (xy 361.711702 -232.313419) (xy 361.742228 -232.355435)
			(xy 361.765806 -232.401709) (xy 361.781854 -232.451102) (xy 361.789979 -232.502397) (xy 361.790488 -232.528364)
			(xy 361.789979 -232.554331) (xy 362.069889 -232.554331) (xy 362.069889 -232.502397) (xy 362.078014 -232.451102)
			(xy 362.094062 -232.401709) (xy 362.11764 -232.355435) (xy 362.148166 -232.313419) (xy 362.184889 -232.276696)
			(xy 362.226905 -232.24617) (xy 362.273179 -232.222592) (xy 362.322572 -232.206544) (xy 362.373867 -232.198419)
			(xy 362.425801 -232.198419) (xy 362.477096 -232.206544) (xy 362.526489 -232.222592) (xy 362.572763 -232.24617)
			(xy 362.614779 -232.276696) (xy 362.651502 -232.313419) (xy 362.682028 -232.355435) (xy 362.705606 -232.401709)
			(xy 362.721654 -232.451102) (xy 362.729779 -232.502397) (xy 362.730288 -232.528364) (xy 362.729779 -232.554331)
			(xy 363.009689 -232.554331) (xy 363.009689 -232.502397) (xy 363.017814 -232.451102) (xy 363.033862 -232.401709)
			(xy 363.05744 -232.355435) (xy 363.087966 -232.313419) (xy 363.124689 -232.276696) (xy 363.166705 -232.24617)
			(xy 363.212979 -232.222592) (xy 363.262372 -232.206544) (xy 363.313667 -232.198419) (xy 363.365601 -232.198419)
			(xy 363.416896 -232.206544) (xy 363.466289 -232.222592) (xy 363.512563 -232.24617) (xy 363.554579 -232.276696)
			(xy 363.591302 -232.313419) (xy 363.621828 -232.355435) (xy 363.645406 -232.401709) (xy 363.661454 -232.451102)
			(xy 363.669579 -232.502397) (xy 363.670088 -232.528364) (xy 363.669579 -232.554331) (xy 363.949489 -232.554331)
			(xy 363.949489 -232.502397) (xy 363.957614 -232.451102) (xy 363.973662 -232.401709) (xy 363.99724 -232.355435)
			(xy 364.027766 -232.313419) (xy 364.064489 -232.276696) (xy 364.106505 -232.24617) (xy 364.152779 -232.222592)
			(xy 364.202172 -232.206544) (xy 364.253467 -232.198419) (xy 364.305401 -232.198419) (xy 364.356696 -232.206544)
			(xy 364.406089 -232.222592) (xy 364.452363 -232.24617) (xy 364.494379 -232.276696) (xy 364.531102 -232.313419)
			(xy 364.561628 -232.355435) (xy 364.585206 -232.401709) (xy 364.601254 -232.451102) (xy 364.609379 -232.502397)
			(xy 364.609888 -232.528364) (xy 364.609379 -232.554331) (xy 364.889289 -232.554331) (xy 364.889289 -232.502397)
			(xy 364.897414 -232.451102) (xy 364.913462 -232.401709) (xy 364.93704 -232.355435) (xy 364.967566 -232.313419)
			(xy 365.004289 -232.276696) (xy 365.046305 -232.24617) (xy 365.092579 -232.222592) (xy 365.141972 -232.206544)
			(xy 365.193267 -232.198419) (xy 365.245201 -232.198419) (xy 365.296496 -232.206544) (xy 365.345889 -232.222592)
			(xy 365.392163 -232.24617) (xy 365.434179 -232.276696) (xy 365.470902 -232.313419) (xy 365.501428 -232.355435)
			(xy 365.525006 -232.401709) (xy 365.541054 -232.451102) (xy 365.549179 -232.502397) (xy 365.549688 -232.528364)
			(xy 365.549179 -232.554331) (xy 365.829089 -232.554331) (xy 365.829089 -232.502397) (xy 365.837214 -232.451102)
			(xy 365.853262 -232.401709) (xy 365.87684 -232.355435) (xy 365.907366 -232.313419) (xy 365.944089 -232.276696)
			(xy 365.986105 -232.24617) (xy 366.032379 -232.222592) (xy 366.081772 -232.206544) (xy 366.133067 -232.198419)
			(xy 366.185001 -232.198419) (xy 366.236296 -232.206544) (xy 366.285689 -232.222592) (xy 366.331963 -232.24617)
			(xy 366.373979 -232.276696) (xy 366.410702 -232.313419) (xy 366.441228 -232.355435) (xy 366.464806 -232.401709)
			(xy 366.480854 -232.451102) (xy 366.488979 -232.502397) (xy 366.489488 -232.528364) (xy 366.488979 -232.554331)
			(xy 366.768889 -232.554331) (xy 366.768889 -232.502397) (xy 366.777014 -232.451102) (xy 366.793062 -232.401709)
			(xy 366.81664 -232.355435) (xy 366.847166 -232.313419) (xy 366.883889 -232.276696) (xy 366.925905 -232.24617)
			(xy 366.972179 -232.222592) (xy 367.021572 -232.206544) (xy 367.072867 -232.198419) (xy 367.124801 -232.198419)
			(xy 367.176096 -232.206544) (xy 367.225489 -232.222592) (xy 367.271763 -232.24617) (xy 367.313779 -232.276696)
			(xy 367.350502 -232.313419) (xy 367.381028 -232.355435) (xy 367.404606 -232.401709) (xy 367.420654 -232.451102)
			(xy 367.428779 -232.502397) (xy 367.429288 -232.528364) (xy 367.428779 -232.554331) (xy 367.708435 -232.554331)
			(xy 367.708435 -232.502397) (xy 367.71656 -232.451102) (xy 367.732608 -232.401709) (xy 367.756186 -232.355435)
			(xy 367.786712 -232.313419) (xy 367.823435 -232.276696) (xy 367.865451 -232.24617) (xy 367.911725 -232.222592)
			(xy 367.961118 -232.206544) (xy 368.012413 -232.198419) (xy 368.064347 -232.198419) (xy 368.115642 -232.206544)
			(xy 368.165035 -232.222592) (xy 368.211309 -232.24617) (xy 368.253325 -232.276696) (xy 368.290048 -232.313419)
			(xy 368.320574 -232.355435) (xy 368.344152 -232.401709) (xy 368.3602 -232.451102) (xy 368.368325 -232.502397)
			(xy 368.368834 -232.528364) (xy 368.368325 -232.554331) (xy 368.648489 -232.554331) (xy 368.648489 -232.502397)
			(xy 368.656614 -232.451102) (xy 368.672662 -232.401709) (xy 368.69624 -232.355435) (xy 368.726766 -232.313419)
			(xy 368.763489 -232.276696) (xy 368.805505 -232.24617) (xy 368.851779 -232.222592) (xy 368.901172 -232.206544)
			(xy 368.952467 -232.198419) (xy 369.004401 -232.198419) (xy 369.055696 -232.206544) (xy 369.105089 -232.222592)
			(xy 369.151363 -232.24617) (xy 369.193379 -232.276696) (xy 369.230102 -232.313419) (xy 369.260628 -232.355435)
			(xy 369.284206 -232.401709) (xy 369.300254 -232.451102) (xy 369.308379 -232.502397) (xy 369.308888 -232.528364)
			(xy 369.308379 -232.554331) (xy 369.588289 -232.554331) (xy 369.588289 -232.502397) (xy 369.596414 -232.451102)
			(xy 369.612462 -232.401709) (xy 369.63604 -232.355435) (xy 369.666566 -232.313419) (xy 369.703289 -232.276696)
			(xy 369.745305 -232.24617) (xy 369.791579 -232.222592) (xy 369.840972 -232.206544) (xy 369.892267 -232.198419)
			(xy 369.944201 -232.198419) (xy 369.995496 -232.206544) (xy 370.044889 -232.222592) (xy 370.091163 -232.24617)
			(xy 370.133179 -232.276696) (xy 370.169902 -232.313419) (xy 370.200428 -232.355435) (xy 370.224006 -232.401709)
			(xy 370.240054 -232.451102) (xy 370.248179 -232.502397) (xy 370.248688 -232.528364) (xy 370.248179 -232.554331)
			(xy 370.528089 -232.554331) (xy 370.528089 -232.502397) (xy 370.536214 -232.451102) (xy 370.552262 -232.401709)
			(xy 370.57584 -232.355435) (xy 370.606366 -232.313419) (xy 370.643089 -232.276696) (xy 370.685105 -232.24617)
			(xy 370.731379 -232.222592) (xy 370.780772 -232.206544) (xy 370.832067 -232.198419) (xy 370.884001 -232.198419)
			(xy 370.935296 -232.206544) (xy 370.984689 -232.222592) (xy 371.030963 -232.24617) (xy 371.072979 -232.276696)
			(xy 371.109702 -232.313419) (xy 371.140228 -232.355435) (xy 371.163806 -232.401709) (xy 371.179854 -232.451102)
			(xy 371.187979 -232.502397) (xy 371.188488 -232.528364) (xy 371.187979 -232.554331) (xy 371.467889 -232.554331)
			(xy 371.467889 -232.502397) (xy 371.476014 -232.451102) (xy 371.492062 -232.401709) (xy 371.51564 -232.355435)
			(xy 371.546166 -232.313419) (xy 371.582889 -232.276696) (xy 371.624905 -232.24617) (xy 371.671179 -232.222592)
			(xy 371.720572 -232.206544) (xy 371.771867 -232.198419) (xy 371.823801 -232.198419) (xy 371.875096 -232.206544)
			(xy 371.924489 -232.222592) (xy 371.970763 -232.24617) (xy 372.012779 -232.276696) (xy 372.049502 -232.313419)
			(xy 372.080028 -232.355435) (xy 372.103606 -232.401709) (xy 372.119654 -232.451102) (xy 372.127779 -232.502397)
			(xy 372.128288 -232.528364) (xy 372.127779 -232.554331) (xy 372.407689 -232.554331) (xy 372.407689 -232.502397)
			(xy 372.415814 -232.451102) (xy 372.431862 -232.401709) (xy 372.45544 -232.355435) (xy 372.485966 -232.313419)
			(xy 372.522689 -232.276696) (xy 372.564705 -232.24617) (xy 372.610979 -232.222592) (xy 372.660372 -232.206544)
			(xy 372.711667 -232.198419) (xy 372.763601 -232.198419) (xy 372.814896 -232.206544) (xy 372.864289 -232.222592)
			(xy 372.910563 -232.24617) (xy 372.952579 -232.276696) (xy 372.989302 -232.313419) (xy 373.019828 -232.355435)
			(xy 373.043406 -232.401709) (xy 373.059454 -232.451102) (xy 373.067579 -232.502397) (xy 373.068088 -232.528364)
			(xy 373.067579 -232.554331) (xy 373.347489 -232.554331) (xy 373.347489 -232.502397) (xy 373.355614 -232.451102)
			(xy 373.371662 -232.401709) (xy 373.39524 -232.355435) (xy 373.425766 -232.313419) (xy 373.462489 -232.276696)
			(xy 373.504505 -232.24617) (xy 373.550779 -232.222592) (xy 373.600172 -232.206544) (xy 373.651467 -232.198419)
			(xy 373.703401 -232.198419) (xy 373.754696 -232.206544) (xy 373.804089 -232.222592) (xy 373.850363 -232.24617)
			(xy 373.892379 -232.276696) (xy 373.929102 -232.313419) (xy 373.959628 -232.355435) (xy 373.983206 -232.401709)
			(xy 373.999254 -232.451102) (xy 374.007379 -232.502397) (xy 374.007888 -232.528364) (xy 374.007379 -232.554331)
			(xy 374.287035 -232.554331) (xy 374.287035 -232.502397) (xy 374.29516 -232.451102) (xy 374.311208 -232.401709)
			(xy 374.334786 -232.355435) (xy 374.365312 -232.313419) (xy 374.402035 -232.276696) (xy 374.444051 -232.24617)
			(xy 374.490325 -232.222592) (xy 374.539718 -232.206544) (xy 374.591013 -232.198419) (xy 374.642947 -232.198419)
			(xy 374.694242 -232.206544) (xy 374.743635 -232.222592) (xy 374.789909 -232.24617) (xy 374.831925 -232.276696)
			(xy 374.868648 -232.313419) (xy 374.899174 -232.355435) (xy 374.922752 -232.401709) (xy 374.9388 -232.451102)
			(xy 374.946925 -232.502397) (xy 374.947434 -232.528364) (xy 374.946925 -232.554331) (xy 375.227089 -232.554331)
			(xy 375.227089 -232.502397) (xy 375.235214 -232.451102) (xy 375.251262 -232.401709) (xy 375.27484 -232.355435)
			(xy 375.305366 -232.313419) (xy 375.342089 -232.276696) (xy 375.384105 -232.24617) (xy 375.430379 -232.222592)
			(xy 375.479772 -232.206544) (xy 375.531067 -232.198419) (xy 375.583001 -232.198419) (xy 375.634296 -232.206544)
			(xy 375.683689 -232.222592) (xy 375.729963 -232.24617) (xy 375.771979 -232.276696) (xy 375.808702 -232.313419)
			(xy 375.839228 -232.355435) (xy 375.862806 -232.401709) (xy 375.878854 -232.451102) (xy 375.886979 -232.502397)
			(xy 375.887488 -232.528364) (xy 375.886979 -232.554331) (xy 375.878854 -232.605626) (xy 375.862806 -232.655019)
			(xy 375.839228 -232.701293) (xy 375.808702 -232.743309) (xy 375.771979 -232.780032) (xy 375.729963 -232.810558)
			(xy 375.683689 -232.834136) (xy 375.634296 -232.850184) (xy 375.583001 -232.858309) (xy 375.531067 -232.858309)
			(xy 375.479772 -232.850184) (xy 375.430379 -232.834136) (xy 375.384105 -232.810558) (xy 375.342089 -232.780032)
			(xy 375.305366 -232.743309) (xy 375.27484 -232.701293) (xy 375.251262 -232.655019) (xy 375.235214 -232.605626)
			(xy 375.227089 -232.554331) (xy 374.946925 -232.554331) (xy 374.9388 -232.605626) (xy 374.922752 -232.655019)
			(xy 374.899174 -232.701293) (xy 374.868648 -232.743309) (xy 374.831925 -232.780032) (xy 374.789909 -232.810558)
			(xy 374.743635 -232.834136) (xy 374.694242 -232.850184) (xy 374.642947 -232.858309) (xy 374.591013 -232.858309)
			(xy 374.539718 -232.850184) (xy 374.490325 -232.834136) (xy 374.444051 -232.810558) (xy 374.402035 -232.780032)
			(xy 374.365312 -232.743309) (xy 374.334786 -232.701293) (xy 374.311208 -232.655019) (xy 374.29516 -232.605626)
			(xy 374.287035 -232.554331) (xy 374.007379 -232.554331) (xy 373.999254 -232.605626) (xy 373.983206 -232.655019)
			(xy 373.959628 -232.701293) (xy 373.929102 -232.743309) (xy 373.892379 -232.780032) (xy 373.850363 -232.810558)
			(xy 373.804089 -232.834136) (xy 373.754696 -232.850184) (xy 373.703401 -232.858309) (xy 373.651467 -232.858309)
			(xy 373.600172 -232.850184) (xy 373.550779 -232.834136) (xy 373.504505 -232.810558) (xy 373.462489 -232.780032)
			(xy 373.425766 -232.743309) (xy 373.39524 -232.701293) (xy 373.371662 -232.655019) (xy 373.355614 -232.605626)
			(xy 373.347489 -232.554331) (xy 373.067579 -232.554331) (xy 373.059454 -232.605626) (xy 373.043406 -232.655019)
			(xy 373.019828 -232.701293) (xy 372.989302 -232.743309) (xy 372.952579 -232.780032) (xy 372.910563 -232.810558)
			(xy 372.864289 -232.834136) (xy 372.814896 -232.850184) (xy 372.763601 -232.858309) (xy 372.711667 -232.858309)
			(xy 372.660372 -232.850184) (xy 372.610979 -232.834136) (xy 372.564705 -232.810558) (xy 372.522689 -232.780032)
			(xy 372.485966 -232.743309) (xy 372.45544 -232.701293) (xy 372.431862 -232.655019) (xy 372.415814 -232.605626)
			(xy 372.407689 -232.554331) (xy 372.127779 -232.554331) (xy 372.119654 -232.605626) (xy 372.103606 -232.655019)
			(xy 372.080028 -232.701293) (xy 372.049502 -232.743309) (xy 372.012779 -232.780032) (xy 371.970763 -232.810558)
			(xy 371.924489 -232.834136) (xy 371.875096 -232.850184) (xy 371.823801 -232.858309) (xy 371.771867 -232.858309)
			(xy 371.720572 -232.850184) (xy 371.671179 -232.834136) (xy 371.624905 -232.810558) (xy 371.582889 -232.780032)
			(xy 371.546166 -232.743309) (xy 371.51564 -232.701293) (xy 371.492062 -232.655019) (xy 371.476014 -232.605626)
			(xy 371.467889 -232.554331) (xy 371.187979 -232.554331) (xy 371.179854 -232.605626) (xy 371.163806 -232.655019)
			(xy 371.140228 -232.701293) (xy 371.109702 -232.743309) (xy 371.072979 -232.780032) (xy 371.030963 -232.810558)
			(xy 370.984689 -232.834136) (xy 370.935296 -232.850184) (xy 370.884001 -232.858309) (xy 370.832067 -232.858309)
			(xy 370.780772 -232.850184) (xy 370.731379 -232.834136) (xy 370.685105 -232.810558) (xy 370.643089 -232.780032)
			(xy 370.606366 -232.743309) (xy 370.57584 -232.701293) (xy 370.552262 -232.655019) (xy 370.536214 -232.605626)
			(xy 370.528089 -232.554331) (xy 370.248179 -232.554331) (xy 370.240054 -232.605626) (xy 370.224006 -232.655019)
			(xy 370.200428 -232.701293) (xy 370.169902 -232.743309) (xy 370.133179 -232.780032) (xy 370.091163 -232.810558)
			(xy 370.044889 -232.834136) (xy 369.995496 -232.850184) (xy 369.944201 -232.858309) (xy 369.892267 -232.858309)
			(xy 369.840972 -232.850184) (xy 369.791579 -232.834136) (xy 369.745305 -232.810558) (xy 369.703289 -232.780032)
			(xy 369.666566 -232.743309) (xy 369.63604 -232.701293) (xy 369.612462 -232.655019) (xy 369.596414 -232.605626)
			(xy 369.588289 -232.554331) (xy 369.308379 -232.554331) (xy 369.300254 -232.605626) (xy 369.284206 -232.655019)
			(xy 369.260628 -232.701293) (xy 369.230102 -232.743309) (xy 369.193379 -232.780032) (xy 369.151363 -232.810558)
			(xy 369.105089 -232.834136) (xy 369.055696 -232.850184) (xy 369.004401 -232.858309) (xy 368.952467 -232.858309)
			(xy 368.901172 -232.850184) (xy 368.851779 -232.834136) (xy 368.805505 -232.810558) (xy 368.763489 -232.780032)
			(xy 368.726766 -232.743309) (xy 368.69624 -232.701293) (xy 368.672662 -232.655019) (xy 368.656614 -232.605626)
			(xy 368.648489 -232.554331) (xy 368.368325 -232.554331) (xy 368.3602 -232.605626) (xy 368.344152 -232.655019)
			(xy 368.320574 -232.701293) (xy 368.290048 -232.743309) (xy 368.253325 -232.780032) (xy 368.211309 -232.810558)
			(xy 368.165035 -232.834136) (xy 368.115642 -232.850184) (xy 368.064347 -232.858309) (xy 368.012413 -232.858309)
			(xy 367.961118 -232.850184) (xy 367.911725 -232.834136) (xy 367.865451 -232.810558) (xy 367.823435 -232.780032)
			(xy 367.786712 -232.743309) (xy 367.756186 -232.701293) (xy 367.732608 -232.655019) (xy 367.71656 -232.605626)
			(xy 367.708435 -232.554331) (xy 367.428779 -232.554331) (xy 367.420654 -232.605626) (xy 367.404606 -232.655019)
			(xy 367.381028 -232.701293) (xy 367.350502 -232.743309) (xy 367.313779 -232.780032) (xy 367.271763 -232.810558)
			(xy 367.225489 -232.834136) (xy 367.176096 -232.850184) (xy 367.124801 -232.858309) (xy 367.072867 -232.858309)
			(xy 367.021572 -232.850184) (xy 366.972179 -232.834136) (xy 366.925905 -232.810558) (xy 366.883889 -232.780032)
			(xy 366.847166 -232.743309) (xy 366.81664 -232.701293) (xy 366.793062 -232.655019) (xy 366.777014 -232.605626)
			(xy 366.768889 -232.554331) (xy 366.488979 -232.554331) (xy 366.480854 -232.605626) (xy 366.464806 -232.655019)
			(xy 366.441228 -232.701293) (xy 366.410702 -232.743309) (xy 366.373979 -232.780032) (xy 366.331963 -232.810558)
			(xy 366.285689 -232.834136) (xy 366.236296 -232.850184) (xy 366.185001 -232.858309) (xy 366.133067 -232.858309)
			(xy 366.081772 -232.850184) (xy 366.032379 -232.834136) (xy 365.986105 -232.810558) (xy 365.944089 -232.780032)
			(xy 365.907366 -232.743309) (xy 365.87684 -232.701293) (xy 365.853262 -232.655019) (xy 365.837214 -232.605626)
			(xy 365.829089 -232.554331) (xy 365.549179 -232.554331) (xy 365.541054 -232.605626) (xy 365.525006 -232.655019)
			(xy 365.501428 -232.701293) (xy 365.470902 -232.743309) (xy 365.434179 -232.780032) (xy 365.392163 -232.810558)
			(xy 365.345889 -232.834136) (xy 365.296496 -232.850184) (xy 365.245201 -232.858309) (xy 365.193267 -232.858309)
			(xy 365.141972 -232.850184) (xy 365.092579 -232.834136) (xy 365.046305 -232.810558) (xy 365.004289 -232.780032)
			(xy 364.967566 -232.743309) (xy 364.93704 -232.701293) (xy 364.913462 -232.655019) (xy 364.897414 -232.605626)
			(xy 364.889289 -232.554331) (xy 364.609379 -232.554331) (xy 364.601254 -232.605626) (xy 364.585206 -232.655019)
			(xy 364.561628 -232.701293) (xy 364.531102 -232.743309) (xy 364.494379 -232.780032) (xy 364.452363 -232.810558)
			(xy 364.406089 -232.834136) (xy 364.356696 -232.850184) (xy 364.305401 -232.858309) (xy 364.253467 -232.858309)
			(xy 364.202172 -232.850184) (xy 364.152779 -232.834136) (xy 364.106505 -232.810558) (xy 364.064489 -232.780032)
			(xy 364.027766 -232.743309) (xy 363.99724 -232.701293) (xy 363.973662 -232.655019) (xy 363.957614 -232.605626)
			(xy 363.949489 -232.554331) (xy 363.669579 -232.554331) (xy 363.661454 -232.605626) (xy 363.645406 -232.655019)
			(xy 363.621828 -232.701293) (xy 363.591302 -232.743309) (xy 363.554579 -232.780032) (xy 363.512563 -232.810558)
			(xy 363.466289 -232.834136) (xy 363.416896 -232.850184) (xy 363.365601 -232.858309) (xy 363.313667 -232.858309)
			(xy 363.262372 -232.850184) (xy 363.212979 -232.834136) (xy 363.166705 -232.810558) (xy 363.124689 -232.780032)
			(xy 363.087966 -232.743309) (xy 363.05744 -232.701293) (xy 363.033862 -232.655019) (xy 363.017814 -232.605626)
			(xy 363.009689 -232.554331) (xy 362.729779 -232.554331) (xy 362.721654 -232.605626) (xy 362.705606 -232.655019)
			(xy 362.682028 -232.701293) (xy 362.651502 -232.743309) (xy 362.614779 -232.780032) (xy 362.572763 -232.810558)
			(xy 362.526489 -232.834136) (xy 362.477096 -232.850184) (xy 362.425801 -232.858309) (xy 362.373867 -232.858309)
			(xy 362.322572 -232.850184) (xy 362.273179 -232.834136) (xy 362.226905 -232.810558) (xy 362.184889 -232.780032)
			(xy 362.148166 -232.743309) (xy 362.11764 -232.701293) (xy 362.094062 -232.655019) (xy 362.078014 -232.605626)
			(xy 362.069889 -232.554331) (xy 361.789979 -232.554331) (xy 361.781854 -232.605626) (xy 361.765806 -232.655019)
			(xy 361.742228 -232.701293) (xy 361.711702 -232.743309) (xy 361.674979 -232.780032) (xy 361.632963 -232.810558)
			(xy 361.586689 -232.834136) (xy 361.537296 -232.850184) (xy 361.486001 -232.858309) (xy 361.434067 -232.858309)
			(xy 361.382772 -232.850184) (xy 361.333379 -232.834136) (xy 361.287105 -232.810558) (xy 361.245089 -232.780032)
			(xy 361.208366 -232.743309) (xy 361.17784 -232.701293) (xy 361.154262 -232.655019) (xy 361.138214 -232.605626)
			(xy 361.130089 -232.554331) (xy 360.850179 -232.554331) (xy 360.842054 -232.605626) (xy 360.826006 -232.655019)
			(xy 360.802428 -232.701293) (xy 360.771902 -232.743309) (xy 360.735179 -232.780032) (xy 360.693163 -232.810558)
			(xy 360.646889 -232.834136) (xy 360.597496 -232.850184) (xy 360.546201 -232.858309) (xy 360.494267 -232.858309)
			(xy 360.442972 -232.850184) (xy 360.393579 -232.834136) (xy 360.347305 -232.810558) (xy 360.305289 -232.780032)
			(xy 360.268566 -232.743309) (xy 360.23804 -232.701293) (xy 360.214462 -232.655019) (xy 360.198414 -232.605626)
			(xy 360.190289 -232.554331) (xy 359.910379 -232.554331) (xy 359.902254 -232.605626) (xy 359.886206 -232.655019)
			(xy 359.862628 -232.701293) (xy 359.832102 -232.743309) (xy 359.795379 -232.780032) (xy 359.753363 -232.810558)
			(xy 359.707089 -232.834136) (xy 359.657696 -232.850184) (xy 359.606401 -232.858309) (xy 359.554467 -232.858309)
			(xy 359.503172 -232.850184) (xy 359.453779 -232.834136) (xy 359.407505 -232.810558) (xy 359.365489 -232.780032)
			(xy 359.328766 -232.743309) (xy 359.29824 -232.701293) (xy 359.274662 -232.655019) (xy 359.258614 -232.605626)
			(xy 359.250489 -232.554331) (xy 358.970579 -232.554331) (xy 358.962454 -232.605626) (xy 358.946406 -232.655019)
			(xy 358.922828 -232.701293) (xy 358.892302 -232.743309) (xy 358.855579 -232.780032) (xy 358.813563 -232.810558)
			(xy 358.767289 -232.834136) (xy 358.717896 -232.850184) (xy 358.666601 -232.858309) (xy 358.614667 -232.858309)
			(xy 358.563372 -232.850184) (xy 358.513979 -232.834136) (xy 358.467705 -232.810558) (xy 358.425689 -232.780032)
			(xy 358.388966 -232.743309) (xy 358.35844 -232.701293) (xy 358.334862 -232.655019) (xy 358.318814 -232.605626)
			(xy 358.310689 -232.554331) (xy 358.030763 -232.554331) (xy 358.02283 -232.60493) (xy 358.007077 -232.653917)
			(xy 357.983922 -232.69987) (xy 357.953925 -232.74168) (xy 357.917809 -232.778335) (xy 357.89743 -232.794048)
			(xy 357.888794 -232.800398) (xy 357.854758 -232.859326) (xy 357.854758 -232.967022) (xy 357.85531 -232.982208)
			(xy 357.864229 -233.011241) (xy 357.881301 -233.036362) (xy 357.905011 -233.055343) (xy 357.933259 -233.066502)
			(xy 357.96354 -233.068851) (xy 357.99317 -233.06218) (xy 358.00665 -233.05516) (xy 358.031814 -233.041493)
			(xy 358.08569 -233.022101) (xy 358.142104 -233.012295) (xy 358.170734 -233.011726) (xy 358.196701 -233.012238)
			(xy 358.247995 -233.020367) (xy 358.297386 -233.03642) (xy 358.343658 -233.06) (xy 358.385672 -233.090529)
			(xy 358.422393 -233.127254) (xy 358.452917 -233.169271) (xy 358.476494 -233.215545) (xy 358.492541 -233.264938)
			(xy 358.500665 -233.316233) (xy 358.500665 -233.368147) (xy 358.780335 -233.368147) (xy 358.780335 -233.316213)
			(xy 358.78846 -233.264918) (xy 358.804508 -233.215525) (xy 358.828086 -233.169251) (xy 358.858612 -233.127235)
			(xy 358.895335 -233.090512) (xy 358.937351 -233.059986) (xy 358.983625 -233.036408) (xy 359.033018 -233.02036)
			(xy 359.084313 -233.012235) (xy 359.136247 -233.012235) (xy 359.187542 -233.02036) (xy 359.236935 -233.036408)
			(xy 359.283209 -233.059986) (xy 359.325225 -233.090512) (xy 359.361948 -233.127235) (xy 359.392474 -233.169251)
			(xy 359.416052 -233.215525) (xy 359.4321 -233.264918) (xy 359.440225 -233.316213) (xy 359.440734 -233.34218)
			(xy 359.440225 -233.368147) (xy 359.720135 -233.368147) (xy 359.720135 -233.316213) (xy 359.72826 -233.264918)
			(xy 359.744308 -233.215525) (xy 359.767886 -233.169251) (xy 359.798412 -233.127235) (xy 359.835135 -233.090512)
			(xy 359.877151 -233.059986) (xy 359.923425 -233.036408) (xy 359.972818 -233.02036) (xy 360.024113 -233.012235)
			(xy 360.076047 -233.012235) (xy 360.127342 -233.02036) (xy 360.176735 -233.036408) (xy 360.223009 -233.059986)
			(xy 360.265025 -233.090512) (xy 360.301748 -233.127235) (xy 360.332274 -233.169251) (xy 360.355852 -233.215525)
			(xy 360.3719 -233.264918) (xy 360.380025 -233.316213) (xy 360.380534 -233.34218) (xy 360.380025 -233.368147)
			(xy 360.659935 -233.368147) (xy 360.659935 -233.316213) (xy 360.66806 -233.264918) (xy 360.684108 -233.215525)
			(xy 360.707686 -233.169251) (xy 360.738212 -233.127235) (xy 360.774935 -233.090512) (xy 360.816951 -233.059986)
			(xy 360.863225 -233.036408) (xy 360.912618 -233.02036) (xy 360.963913 -233.012235) (xy 361.015847 -233.012235)
			(xy 361.067142 -233.02036) (xy 361.116535 -233.036408) (xy 361.162809 -233.059986) (xy 361.204825 -233.090512)
			(xy 361.241548 -233.127235) (xy 361.272074 -233.169251) (xy 361.295652 -233.215525) (xy 361.3117 -233.264918)
			(xy 361.319825 -233.316213) (xy 361.320334 -233.34218) (xy 361.319825 -233.368147) (xy 361.599989 -233.368147)
			(xy 361.599989 -233.316213) (xy 361.608114 -233.264918) (xy 361.624162 -233.215525) (xy 361.64774 -233.169251)
			(xy 361.678266 -233.127235) (xy 361.714989 -233.090512) (xy 361.757005 -233.059986) (xy 361.803279 -233.036408)
			(xy 361.852672 -233.02036) (xy 361.903967 -233.012235) (xy 361.955901 -233.012235) (xy 362.007196 -233.02036)
			(xy 362.056589 -233.036408) (xy 362.102863 -233.059986) (xy 362.144879 -233.090512) (xy 362.181602 -233.127235)
			(xy 362.212128 -233.169251) (xy 362.235706 -233.215525) (xy 362.251754 -233.264918) (xy 362.259879 -233.316213)
			(xy 362.260388 -233.34218) (xy 362.259879 -233.368147) (xy 362.539535 -233.368147) (xy 362.539535 -233.316213)
			(xy 362.54766 -233.264918) (xy 362.563708 -233.215525) (xy 362.587286 -233.169251) (xy 362.617812 -233.127235)
			(xy 362.654535 -233.090512) (xy 362.696551 -233.059986) (xy 362.742825 -233.036408) (xy 362.792218 -233.02036)
			(xy 362.843513 -233.012235) (xy 362.895447 -233.012235) (xy 362.946742 -233.02036) (xy 362.996135 -233.036408)
			(xy 363.042409 -233.059986) (xy 363.084425 -233.090512) (xy 363.121148 -233.127235) (xy 363.151674 -233.169251)
			(xy 363.175252 -233.215525) (xy 363.1913 -233.264918) (xy 363.199425 -233.316213) (xy 363.199934 -233.34218)
			(xy 363.199425 -233.368147) (xy 363.479335 -233.368147) (xy 363.479335 -233.316213) (xy 363.48746 -233.264918)
			(xy 363.503508 -233.215525) (xy 363.527086 -233.169251) (xy 363.557612 -233.127235) (xy 363.594335 -233.090512)
			(xy 363.636351 -233.059986) (xy 363.682625 -233.036408) (xy 363.732018 -233.02036) (xy 363.783313 -233.012235)
			(xy 363.835247 -233.012235) (xy 363.886542 -233.02036) (xy 363.935935 -233.036408) (xy 363.982209 -233.059986)
			(xy 364.024225 -233.090512) (xy 364.060948 -233.127235) (xy 364.091474 -233.169251) (xy 364.115052 -233.215525)
			(xy 364.1311 -233.264918) (xy 364.139225 -233.316213) (xy 364.139734 -233.34218) (xy 364.139225 -233.368147)
			(xy 364.419135 -233.368147) (xy 364.419135 -233.316213) (xy 364.42726 -233.264918) (xy 364.443308 -233.215525)
			(xy 364.466886 -233.169251) (xy 364.497412 -233.127235) (xy 364.534135 -233.090512) (xy 364.576151 -233.059986)
			(xy 364.622425 -233.036408) (xy 364.671818 -233.02036) (xy 364.723113 -233.012235) (xy 364.775047 -233.012235)
			(xy 364.826342 -233.02036) (xy 364.875735 -233.036408) (xy 364.922009 -233.059986) (xy 364.964025 -233.090512)
			(xy 365.000748 -233.127235) (xy 365.031274 -233.169251) (xy 365.054852 -233.215525) (xy 365.0709 -233.264918)
			(xy 365.079025 -233.316213) (xy 365.079534 -233.34218) (xy 365.079025 -233.368147) (xy 365.358935 -233.368147)
			(xy 365.358935 -233.316213) (xy 365.36706 -233.264918) (xy 365.383108 -233.215525) (xy 365.406686 -233.169251)
			(xy 365.437212 -233.127235) (xy 365.473935 -233.090512) (xy 365.515951 -233.059986) (xy 365.562225 -233.036408)
			(xy 365.611618 -233.02036) (xy 365.662913 -233.012235) (xy 365.714847 -233.012235) (xy 365.766142 -233.02036)
			(xy 365.815535 -233.036408) (xy 365.861809 -233.059986) (xy 365.903825 -233.090512) (xy 365.940548 -233.127235)
			(xy 365.971074 -233.169251) (xy 365.994652 -233.215525) (xy 366.0107 -233.264918) (xy 366.018825 -233.316213)
			(xy 366.019334 -233.34218) (xy 366.018825 -233.368147) (xy 366.298735 -233.368147) (xy 366.298735 -233.316213)
			(xy 366.30686 -233.264918) (xy 366.322908 -233.215525) (xy 366.346486 -233.169251) (xy 366.377012 -233.127235)
			(xy 366.413735 -233.090512) (xy 366.455751 -233.059986) (xy 366.502025 -233.036408) (xy 366.551418 -233.02036)
			(xy 366.602713 -233.012235) (xy 366.654647 -233.012235) (xy 366.705942 -233.02036) (xy 366.755335 -233.036408)
			(xy 366.801609 -233.059986) (xy 366.843625 -233.090512) (xy 366.880348 -233.127235) (xy 366.910874 -233.169251)
			(xy 366.934452 -233.215525) (xy 366.9505 -233.264918) (xy 366.958625 -233.316213) (xy 366.959134 -233.34218)
			(xy 366.958625 -233.368147) (xy 367.238535 -233.368147) (xy 367.238535 -233.316213) (xy 367.24666 -233.264918)
			(xy 367.262708 -233.215525) (xy 367.286286 -233.169251) (xy 367.316812 -233.127235) (xy 367.353535 -233.090512)
			(xy 367.395551 -233.059986) (xy 367.441825 -233.036408) (xy 367.491218 -233.02036) (xy 367.542513 -233.012235)
			(xy 367.594447 -233.012235) (xy 367.645742 -233.02036) (xy 367.695135 -233.036408) (xy 367.741409 -233.059986)
			(xy 367.783425 -233.090512) (xy 367.820148 -233.127235) (xy 367.850674 -233.169251) (xy 367.874252 -233.215525)
			(xy 367.8903 -233.264918) (xy 367.898425 -233.316213) (xy 367.898934 -233.34218) (xy 367.898425 -233.368147)
			(xy 368.178335 -233.368147) (xy 368.178335 -233.316213) (xy 368.18646 -233.264918) (xy 368.202508 -233.215525)
			(xy 368.226086 -233.169251) (xy 368.256612 -233.127235) (xy 368.293335 -233.090512) (xy 368.335351 -233.059986)
			(xy 368.381625 -233.036408) (xy 368.431018 -233.02036) (xy 368.482313 -233.012235) (xy 368.534247 -233.012235)
			(xy 368.585542 -233.02036) (xy 368.634935 -233.036408) (xy 368.681209 -233.059986) (xy 368.723225 -233.090512)
			(xy 368.759948 -233.127235) (xy 368.790474 -233.169251) (xy 368.814052 -233.215525) (xy 368.8301 -233.264918)
			(xy 368.838225 -233.316213) (xy 368.838734 -233.34218) (xy 368.838225 -233.368147) (xy 369.118389 -233.368147)
			(xy 369.118389 -233.316213) (xy 369.126514 -233.264918) (xy 369.142562 -233.215525) (xy 369.16614 -233.169251)
			(xy 369.196666 -233.127235) (xy 369.233389 -233.090512) (xy 369.275405 -233.059986) (xy 369.321679 -233.036408)
			(xy 369.371072 -233.02036) (xy 369.422367 -233.012235) (xy 369.474301 -233.012235) (xy 369.525596 -233.02036)
			(xy 369.574989 -233.036408) (xy 369.621263 -233.059986) (xy 369.663279 -233.090512) (xy 369.700002 -233.127235)
			(xy 369.730528 -233.169251) (xy 369.754106 -233.215525) (xy 369.770154 -233.264918) (xy 369.778279 -233.316213)
			(xy 369.778788 -233.34218) (xy 369.778279 -233.368147) (xy 370.057935 -233.368147) (xy 370.057935 -233.316213)
			(xy 370.06606 -233.264918) (xy 370.082108 -233.215525) (xy 370.105686 -233.169251) (xy 370.136212 -233.127235)
			(xy 370.172935 -233.090512) (xy 370.214951 -233.059986) (xy 370.261225 -233.036408) (xy 370.310618 -233.02036)
			(xy 370.361913 -233.012235) (xy 370.413847 -233.012235) (xy 370.465142 -233.02036) (xy 370.514535 -233.036408)
			(xy 370.560809 -233.059986) (xy 370.602825 -233.090512) (xy 370.639548 -233.127235) (xy 370.670074 -233.169251)
			(xy 370.693652 -233.215525) (xy 370.7097 -233.264918) (xy 370.717825 -233.316213) (xy 370.718334 -233.34218)
			(xy 370.717825 -233.368147) (xy 370.997735 -233.368147) (xy 370.997735 -233.316213) (xy 371.00586 -233.264918)
			(xy 371.021908 -233.215525) (xy 371.045486 -233.169251) (xy 371.076012 -233.127235) (xy 371.112735 -233.090512)
			(xy 371.154751 -233.059986) (xy 371.201025 -233.036408) (xy 371.250418 -233.02036) (xy 371.301713 -233.012235)
			(xy 371.353647 -233.012235) (xy 371.404942 -233.02036) (xy 371.454335 -233.036408) (xy 371.500609 -233.059986)
			(xy 371.542625 -233.090512) (xy 371.579348 -233.127235) (xy 371.609874 -233.169251) (xy 371.633452 -233.215525)
			(xy 371.6495 -233.264918) (xy 371.657625 -233.316213) (xy 371.658134 -233.34218) (xy 371.657625 -233.368147)
			(xy 371.937535 -233.368147) (xy 371.937535 -233.316213) (xy 371.94566 -233.264918) (xy 371.961708 -233.215525)
			(xy 371.985286 -233.169251) (xy 372.015812 -233.127235) (xy 372.052535 -233.090512) (xy 372.094551 -233.059986)
			(xy 372.140825 -233.036408) (xy 372.190218 -233.02036) (xy 372.241513 -233.012235) (xy 372.293447 -233.012235)
			(xy 372.344742 -233.02036) (xy 372.394135 -233.036408) (xy 372.440409 -233.059986) (xy 372.482425 -233.090512)
			(xy 372.519148 -233.127235) (xy 372.549674 -233.169251) (xy 372.573252 -233.215525) (xy 372.5893 -233.264918)
			(xy 372.597425 -233.316213) (xy 372.597934 -233.34218) (xy 372.597425 -233.368147) (xy 372.877335 -233.368147)
			(xy 372.877335 -233.316213) (xy 372.88546 -233.264918) (xy 372.901508 -233.215525) (xy 372.925086 -233.169251)
			(xy 372.955612 -233.127235) (xy 372.992335 -233.090512) (xy 373.034351 -233.059986) (xy 373.080625 -233.036408)
			(xy 373.130018 -233.02036) (xy 373.181313 -233.012235) (xy 373.233247 -233.012235) (xy 373.284542 -233.02036)
			(xy 373.333935 -233.036408) (xy 373.380209 -233.059986) (xy 373.422225 -233.090512) (xy 373.458948 -233.127235)
			(xy 373.489474 -233.169251) (xy 373.513052 -233.215525) (xy 373.5291 -233.264918) (xy 373.537225 -233.316213)
			(xy 373.537734 -233.34218) (xy 373.537225 -233.368147) (xy 373.817389 -233.368147) (xy 373.817389 -233.316213)
			(xy 373.825514 -233.264918) (xy 373.841562 -233.215525) (xy 373.86514 -233.169251) (xy 373.895666 -233.127235)
			(xy 373.932389 -233.090512) (xy 373.974405 -233.059986) (xy 374.020679 -233.036408) (xy 374.070072 -233.02036)
			(xy 374.121367 -233.012235) (xy 374.173301 -233.012235) (xy 374.224596 -233.02036) (xy 374.273989 -233.036408)
			(xy 374.320263 -233.059986) (xy 374.362279 -233.090512) (xy 374.399002 -233.127235) (xy 374.429528 -233.169251)
			(xy 374.453106 -233.215525) (xy 374.469154 -233.264918) (xy 374.477279 -233.316213) (xy 374.477788 -233.34218)
			(xy 374.477279 -233.368147) (xy 374.756935 -233.368147) (xy 374.756935 -233.316213) (xy 374.76506 -233.264918)
			(xy 374.781108 -233.215525) (xy 374.804686 -233.169251) (xy 374.835212 -233.127235) (xy 374.871935 -233.090512)
			(xy 374.913951 -233.059986) (xy 374.960225 -233.036408) (xy 375.009618 -233.02036) (xy 375.060913 -233.012235)
			(xy 375.112847 -233.012235) (xy 375.164142 -233.02036) (xy 375.213535 -233.036408) (xy 375.259809 -233.059986)
			(xy 375.301825 -233.090512) (xy 375.338548 -233.127235) (xy 375.369074 -233.169251) (xy 375.392652 -233.215525)
			(xy 375.4087 -233.264918) (xy 375.416825 -233.316213) (xy 375.417334 -233.34218) (xy 375.416825 -233.368147)
			(xy 375.4087 -233.419442) (xy 375.392652 -233.468835) (xy 375.369074 -233.515109) (xy 375.338548 -233.557125)
			(xy 375.301825 -233.593848) (xy 375.259809 -233.624374) (xy 375.213535 -233.647952) (xy 375.164142 -233.664)
			(xy 375.112847 -233.672125) (xy 375.060913 -233.672125) (xy 375.009618 -233.664) (xy 374.960225 -233.647952)
			(xy 374.913951 -233.624374) (xy 374.871935 -233.593848) (xy 374.835212 -233.557125) (xy 374.804686 -233.515109)
			(xy 374.781108 -233.468835) (xy 374.76506 -233.419442) (xy 374.756935 -233.368147) (xy 374.477279 -233.368147)
			(xy 374.469154 -233.419442) (xy 374.453106 -233.468835) (xy 374.429528 -233.515109) (xy 374.399002 -233.557125)
			(xy 374.362279 -233.593848) (xy 374.320263 -233.624374) (xy 374.273989 -233.647952) (xy 374.224596 -233.664)
			(xy 374.173301 -233.672125) (xy 374.121367 -233.672125) (xy 374.070072 -233.664) (xy 374.020679 -233.647952)
			(xy 373.974405 -233.624374) (xy 373.932389 -233.593848) (xy 373.895666 -233.557125) (xy 373.86514 -233.515109)
			(xy 373.841562 -233.468835) (xy 373.825514 -233.419442) (xy 373.817389 -233.368147) (xy 373.537225 -233.368147)
			(xy 373.5291 -233.419442) (xy 373.513052 -233.468835) (xy 373.489474 -233.515109) (xy 373.458948 -233.557125)
			(xy 373.422225 -233.593848) (xy 373.380209 -233.624374) (xy 373.333935 -233.647952) (xy 373.284542 -233.664)
			(xy 373.233247 -233.672125) (xy 373.181313 -233.672125) (xy 373.130018 -233.664) (xy 373.080625 -233.647952)
			(xy 373.034351 -233.624374) (xy 372.992335 -233.593848) (xy 372.955612 -233.557125) (xy 372.925086 -233.515109)
			(xy 372.901508 -233.468835) (xy 372.88546 -233.419442) (xy 372.877335 -233.368147) (xy 372.597425 -233.368147)
			(xy 372.5893 -233.419442) (xy 372.573252 -233.468835) (xy 372.549674 -233.515109) (xy 372.519148 -233.557125)
			(xy 372.482425 -233.593848) (xy 372.440409 -233.624374) (xy 372.394135 -233.647952) (xy 372.344742 -233.664)
			(xy 372.293447 -233.672125) (xy 372.241513 -233.672125) (xy 372.190218 -233.664) (xy 372.140825 -233.647952)
			(xy 372.094551 -233.624374) (xy 372.052535 -233.593848) (xy 372.015812 -233.557125) (xy 371.985286 -233.515109)
			(xy 371.961708 -233.468835) (xy 371.94566 -233.419442) (xy 371.937535 -233.368147) (xy 371.657625 -233.368147)
			(xy 371.6495 -233.419442) (xy 371.633452 -233.468835) (xy 371.609874 -233.515109) (xy 371.579348 -233.557125)
			(xy 371.542625 -233.593848) (xy 371.500609 -233.624374) (xy 371.454335 -233.647952) (xy 371.404942 -233.664)
			(xy 371.353647 -233.672125) (xy 371.301713 -233.672125) (xy 371.250418 -233.664) (xy 371.201025 -233.647952)
			(xy 371.154751 -233.624374) (xy 371.112735 -233.593848) (xy 371.076012 -233.557125) (xy 371.045486 -233.515109)
			(xy 371.021908 -233.468835) (xy 371.00586 -233.419442) (xy 370.997735 -233.368147) (xy 370.717825 -233.368147)
			(xy 370.7097 -233.419442) (xy 370.693652 -233.468835) (xy 370.670074 -233.515109) (xy 370.639548 -233.557125)
			(xy 370.602825 -233.593848) (xy 370.560809 -233.624374) (xy 370.514535 -233.647952) (xy 370.465142 -233.664)
			(xy 370.413847 -233.672125) (xy 370.361913 -233.672125) (xy 370.310618 -233.664) (xy 370.261225 -233.647952)
			(xy 370.214951 -233.624374) (xy 370.172935 -233.593848) (xy 370.136212 -233.557125) (xy 370.105686 -233.515109)
			(xy 370.082108 -233.468835) (xy 370.06606 -233.419442) (xy 370.057935 -233.368147) (xy 369.778279 -233.368147)
			(xy 369.770154 -233.419442) (xy 369.754106 -233.468835) (xy 369.730528 -233.515109) (xy 369.700002 -233.557125)
			(xy 369.663279 -233.593848) (xy 369.621263 -233.624374) (xy 369.574989 -233.647952) (xy 369.525596 -233.664)
			(xy 369.474301 -233.672125) (xy 369.422367 -233.672125) (xy 369.371072 -233.664) (xy 369.321679 -233.647952)
			(xy 369.275405 -233.624374) (xy 369.233389 -233.593848) (xy 369.196666 -233.557125) (xy 369.16614 -233.515109)
			(xy 369.142562 -233.468835) (xy 369.126514 -233.419442) (xy 369.118389 -233.368147) (xy 368.838225 -233.368147)
			(xy 368.8301 -233.419442) (xy 368.814052 -233.468835) (xy 368.790474 -233.515109) (xy 368.759948 -233.557125)
			(xy 368.723225 -233.593848) (xy 368.681209 -233.624374) (xy 368.634935 -233.647952) (xy 368.585542 -233.664)
			(xy 368.534247 -233.672125) (xy 368.482313 -233.672125) (xy 368.431018 -233.664) (xy 368.381625 -233.647952)
			(xy 368.335351 -233.624374) (xy 368.293335 -233.593848) (xy 368.256612 -233.557125) (xy 368.226086 -233.515109)
			(xy 368.202508 -233.468835) (xy 368.18646 -233.419442) (xy 368.178335 -233.368147) (xy 367.898425 -233.368147)
			(xy 367.8903 -233.419442) (xy 367.874252 -233.468835) (xy 367.850674 -233.515109) (xy 367.820148 -233.557125)
			(xy 367.783425 -233.593848) (xy 367.741409 -233.624374) (xy 367.695135 -233.647952) (xy 367.645742 -233.664)
			(xy 367.594447 -233.672125) (xy 367.542513 -233.672125) (xy 367.491218 -233.664) (xy 367.441825 -233.647952)
			(xy 367.395551 -233.624374) (xy 367.353535 -233.593848) (xy 367.316812 -233.557125) (xy 367.286286 -233.515109)
			(xy 367.262708 -233.468835) (xy 367.24666 -233.419442) (xy 367.238535 -233.368147) (xy 366.958625 -233.368147)
			(xy 366.9505 -233.419442) (xy 366.934452 -233.468835) (xy 366.910874 -233.515109) (xy 366.880348 -233.557125)
			(xy 366.843625 -233.593848) (xy 366.801609 -233.624374) (xy 366.755335 -233.647952) (xy 366.705942 -233.664)
			(xy 366.654647 -233.672125) (xy 366.602713 -233.672125) (xy 366.551418 -233.664) (xy 366.502025 -233.647952)
			(xy 366.455751 -233.624374) (xy 366.413735 -233.593848) (xy 366.377012 -233.557125) (xy 366.346486 -233.515109)
			(xy 366.322908 -233.468835) (xy 366.30686 -233.419442) (xy 366.298735 -233.368147) (xy 366.018825 -233.368147)
			(xy 366.0107 -233.419442) (xy 365.994652 -233.468835) (xy 365.971074 -233.515109) (xy 365.940548 -233.557125)
			(xy 365.903825 -233.593848) (xy 365.861809 -233.624374) (xy 365.815535 -233.647952) (xy 365.766142 -233.664)
			(xy 365.714847 -233.672125) (xy 365.662913 -233.672125) (xy 365.611618 -233.664) (xy 365.562225 -233.647952)
			(xy 365.515951 -233.624374) (xy 365.473935 -233.593848) (xy 365.437212 -233.557125) (xy 365.406686 -233.515109)
			(xy 365.383108 -233.468835) (xy 365.36706 -233.419442) (xy 365.358935 -233.368147) (xy 365.079025 -233.368147)
			(xy 365.0709 -233.419442) (xy 365.054852 -233.468835) (xy 365.031274 -233.515109) (xy 365.000748 -233.557125)
			(xy 364.964025 -233.593848) (xy 364.922009 -233.624374) (xy 364.875735 -233.647952) (xy 364.826342 -233.664)
			(xy 364.775047 -233.672125) (xy 364.723113 -233.672125) (xy 364.671818 -233.664) (xy 364.622425 -233.647952)
			(xy 364.576151 -233.624374) (xy 364.534135 -233.593848) (xy 364.497412 -233.557125) (xy 364.466886 -233.515109)
			(xy 364.443308 -233.468835) (xy 364.42726 -233.419442) (xy 364.419135 -233.368147) (xy 364.139225 -233.368147)
			(xy 364.1311 -233.419442) (xy 364.115052 -233.468835) (xy 364.091474 -233.515109) (xy 364.060948 -233.557125)
			(xy 364.024225 -233.593848) (xy 363.982209 -233.624374) (xy 363.935935 -233.647952) (xy 363.886542 -233.664)
			(xy 363.835247 -233.672125) (xy 363.783313 -233.672125) (xy 363.732018 -233.664) (xy 363.682625 -233.647952)
			(xy 363.636351 -233.624374) (xy 363.594335 -233.593848) (xy 363.557612 -233.557125) (xy 363.527086 -233.515109)
			(xy 363.503508 -233.468835) (xy 363.48746 -233.419442) (xy 363.479335 -233.368147) (xy 363.199425 -233.368147)
			(xy 363.1913 -233.419442) (xy 363.175252 -233.468835) (xy 363.151674 -233.515109) (xy 363.121148 -233.557125)
			(xy 363.084425 -233.593848) (xy 363.042409 -233.624374) (xy 362.996135 -233.647952) (xy 362.946742 -233.664)
			(xy 362.895447 -233.672125) (xy 362.843513 -233.672125) (xy 362.792218 -233.664) (xy 362.742825 -233.647952)
			(xy 362.696551 -233.624374) (xy 362.654535 -233.593848) (xy 362.617812 -233.557125) (xy 362.587286 -233.515109)
			(xy 362.563708 -233.468835) (xy 362.54766 -233.419442) (xy 362.539535 -233.368147) (xy 362.259879 -233.368147)
			(xy 362.251754 -233.419442) (xy 362.235706 -233.468835) (xy 362.212128 -233.515109) (xy 362.181602 -233.557125)
			(xy 362.144879 -233.593848) (xy 362.102863 -233.624374) (xy 362.056589 -233.647952) (xy 362.007196 -233.664)
			(xy 361.955901 -233.672125) (xy 361.903967 -233.672125) (xy 361.852672 -233.664) (xy 361.803279 -233.647952)
			(xy 361.757005 -233.624374) (xy 361.714989 -233.593848) (xy 361.678266 -233.557125) (xy 361.64774 -233.515109)
			(xy 361.624162 -233.468835) (xy 361.608114 -233.419442) (xy 361.599989 -233.368147) (xy 361.319825 -233.368147)
			(xy 361.3117 -233.419442) (xy 361.295652 -233.468835) (xy 361.272074 -233.515109) (xy 361.241548 -233.557125)
			(xy 361.204825 -233.593848) (xy 361.162809 -233.624374) (xy 361.116535 -233.647952) (xy 361.067142 -233.664)
			(xy 361.015847 -233.672125) (xy 360.963913 -233.672125) (xy 360.912618 -233.664) (xy 360.863225 -233.647952)
			(xy 360.816951 -233.624374) (xy 360.774935 -233.593848) (xy 360.738212 -233.557125) (xy 360.707686 -233.515109)
			(xy 360.684108 -233.468835) (xy 360.66806 -233.419442) (xy 360.659935 -233.368147) (xy 360.380025 -233.368147)
			(xy 360.3719 -233.419442) (xy 360.355852 -233.468835) (xy 360.332274 -233.515109) (xy 360.301748 -233.557125)
			(xy 360.265025 -233.593848) (xy 360.223009 -233.624374) (xy 360.176735 -233.647952) (xy 360.127342 -233.664)
			(xy 360.076047 -233.672125) (xy 360.024113 -233.672125) (xy 359.972818 -233.664) (xy 359.923425 -233.647952)
			(xy 359.877151 -233.624374) (xy 359.835135 -233.593848) (xy 359.798412 -233.557125) (xy 359.767886 -233.515109)
			(xy 359.744308 -233.468835) (xy 359.72826 -233.419442) (xy 359.720135 -233.368147) (xy 359.440225 -233.368147)
			(xy 359.4321 -233.419442) (xy 359.416052 -233.468835) (xy 359.392474 -233.515109) (xy 359.361948 -233.557125)
			(xy 359.325225 -233.593848) (xy 359.283209 -233.624374) (xy 359.236935 -233.647952) (xy 359.187542 -233.664)
			(xy 359.136247 -233.672125) (xy 359.084313 -233.672125) (xy 359.033018 -233.664) (xy 358.983625 -233.647952)
			(xy 358.937351 -233.624374) (xy 358.895335 -233.593848) (xy 358.858612 -233.557125) (xy 358.828086 -233.515109)
			(xy 358.804508 -233.468835) (xy 358.78846 -233.419442) (xy 358.780335 -233.368147) (xy 358.500665 -233.368147)
			(xy 358.500665 -233.368167) (xy 358.492541 -233.419462) (xy 358.476494 -233.468855) (xy 358.452917 -233.515129)
			(xy 358.422393 -233.557146) (xy 358.385672 -233.593871) (xy 358.343658 -233.6244) (xy 358.297386 -233.64798)
			(xy 358.247995 -233.664033) (xy 358.196701 -233.672162) (xy 358.170734 -233.672634) (xy 358.142105 -233.672048)
			(xy 358.085694 -233.662237) (xy 358.031812 -233.642867) (xy 358.00665 -233.6292) (xy 357.993188 -233.622182)
			(xy 357.963572 -233.615581) (xy 357.933323 -233.617969) (xy 357.90511 -233.629136) (xy 357.88142 -233.648096)
			(xy 357.864344 -233.673177) (xy 357.855386 -233.702168) (xy 357.854758 -233.717338) (xy 357.854758 -233.863896)
			(xy 357.877229 -233.876275) (xy 357.918382 -233.906903) (xy 357.954309 -233.943522) (xy 357.984145 -233.985254)
			(xy 358.007174 -234.031094) (xy 358.022842 -234.079943) (xy 358.030773 -234.130627) (xy 358.030776 -234.181927)
			(xy 358.030731 -234.182217) (xy 358.310689 -234.182217) (xy 358.310689 -234.130283) (xy 358.318814 -234.078988)
			(xy 358.334862 -234.029595) (xy 358.35844 -233.983321) (xy 358.388966 -233.941305) (xy 358.425689 -233.904582)
			(xy 358.467705 -233.874056) (xy 358.513979 -233.850478) (xy 358.563372 -233.83443) (xy 358.614667 -233.826305)
			(xy 358.666601 -233.826305) (xy 358.717896 -233.83443) (xy 358.767289 -233.850478) (xy 358.813563 -233.874056)
			(xy 358.855579 -233.904582) (xy 358.892302 -233.941305) (xy 358.922828 -233.983321) (xy 358.946406 -234.029595)
			(xy 358.962454 -234.078988) (xy 358.970579 -234.130283) (xy 358.971088 -234.15625) (xy 358.970579 -234.182217)
			(xy 359.250489 -234.182217) (xy 359.250489 -234.130283) (xy 359.258614 -234.078988) (xy 359.274662 -234.029595)
			(xy 359.29824 -233.983321) (xy 359.328766 -233.941305) (xy 359.365489 -233.904582) (xy 359.407505 -233.874056)
			(xy 359.453779 -233.850478) (xy 359.503172 -233.83443) (xy 359.554467 -233.826305) (xy 359.606401 -233.826305)
			(xy 359.657696 -233.83443) (xy 359.707089 -233.850478) (xy 359.753363 -233.874056) (xy 359.795379 -233.904582)
			(xy 359.832102 -233.941305) (xy 359.862628 -233.983321) (xy 359.886206 -234.029595) (xy 359.902254 -234.078988)
			(xy 359.910379 -234.130283) (xy 359.910888 -234.15625) (xy 359.910379 -234.182217) (xy 360.190289 -234.182217)
			(xy 360.190289 -234.130283) (xy 360.198414 -234.078988) (xy 360.214462 -234.029595) (xy 360.23804 -233.983321)
			(xy 360.268566 -233.941305) (xy 360.305289 -233.904582) (xy 360.347305 -233.874056) (xy 360.393579 -233.850478)
			(xy 360.442972 -233.83443) (xy 360.494267 -233.826305) (xy 360.546201 -233.826305) (xy 360.597496 -233.83443)
			(xy 360.646889 -233.850478) (xy 360.693163 -233.874056) (xy 360.735179 -233.904582) (xy 360.771902 -233.941305)
			(xy 360.802428 -233.983321) (xy 360.826006 -234.029595) (xy 360.842054 -234.078988) (xy 360.850179 -234.130283)
			(xy 360.850688 -234.15625) (xy 360.850179 -234.182217) (xy 361.130089 -234.182217) (xy 361.130089 -234.130283)
			(xy 361.138214 -234.078988) (xy 361.154262 -234.029595) (xy 361.17784 -233.983321) (xy 361.208366 -233.941305)
			(xy 361.245089 -233.904582) (xy 361.287105 -233.874056) (xy 361.333379 -233.850478) (xy 361.382772 -233.83443)
			(xy 361.434067 -233.826305) (xy 361.486001 -233.826305) (xy 361.537296 -233.83443) (xy 361.586689 -233.850478)
			(xy 361.632963 -233.874056) (xy 361.674979 -233.904582) (xy 361.711702 -233.941305) (xy 361.742228 -233.983321)
			(xy 361.765806 -234.029595) (xy 361.781854 -234.078988) (xy 361.789979 -234.130283) (xy 361.790488 -234.15625)
			(xy 361.789979 -234.182217) (xy 362.069889 -234.182217) (xy 362.069889 -234.130283) (xy 362.078014 -234.078988)
			(xy 362.094062 -234.029595) (xy 362.11764 -233.983321) (xy 362.148166 -233.941305) (xy 362.184889 -233.904582)
			(xy 362.226905 -233.874056) (xy 362.273179 -233.850478) (xy 362.322572 -233.83443) (xy 362.373867 -233.826305)
			(xy 362.425801 -233.826305) (xy 362.477096 -233.83443) (xy 362.526489 -233.850478) (xy 362.572763 -233.874056)
			(xy 362.614779 -233.904582) (xy 362.651502 -233.941305) (xy 362.682028 -233.983321) (xy 362.705606 -234.029595)
			(xy 362.721654 -234.078988) (xy 362.729779 -234.130283) (xy 362.730288 -234.15625) (xy 362.729779 -234.182217)
			(xy 363.009689 -234.182217) (xy 363.009689 -234.130283) (xy 363.017814 -234.078988) (xy 363.033862 -234.029595)
			(xy 363.05744 -233.983321) (xy 363.087966 -233.941305) (xy 363.124689 -233.904582) (xy 363.166705 -233.874056)
			(xy 363.212979 -233.850478) (xy 363.262372 -233.83443) (xy 363.313667 -233.826305) (xy 363.365601 -233.826305)
			(xy 363.416896 -233.83443) (xy 363.466289 -233.850478) (xy 363.512563 -233.874056) (xy 363.554579 -233.904582)
			(xy 363.591302 -233.941305) (xy 363.621828 -233.983321) (xy 363.645406 -234.029595) (xy 363.661454 -234.078988)
			(xy 363.669579 -234.130283) (xy 363.670088 -234.15625) (xy 363.669579 -234.182217) (xy 363.949489 -234.182217)
			(xy 363.949489 -234.130283) (xy 363.957614 -234.078988) (xy 363.973662 -234.029595) (xy 363.99724 -233.983321)
			(xy 364.027766 -233.941305) (xy 364.064489 -233.904582) (xy 364.106505 -233.874056) (xy 364.152779 -233.850478)
			(xy 364.202172 -233.83443) (xy 364.253467 -233.826305) (xy 364.305401 -233.826305) (xy 364.356696 -233.83443)
			(xy 364.406089 -233.850478) (xy 364.452363 -233.874056) (xy 364.494379 -233.904582) (xy 364.531102 -233.941305)
			(xy 364.561628 -233.983321) (xy 364.585206 -234.029595) (xy 364.601254 -234.078988) (xy 364.609379 -234.130283)
			(xy 364.609888 -234.15625) (xy 364.609379 -234.182217) (xy 364.889289 -234.182217) (xy 364.889289 -234.130283)
			(xy 364.897414 -234.078988) (xy 364.913462 -234.029595) (xy 364.93704 -233.983321) (xy 364.967566 -233.941305)
			(xy 365.004289 -233.904582) (xy 365.046305 -233.874056) (xy 365.092579 -233.850478) (xy 365.141972 -233.83443)
			(xy 365.193267 -233.826305) (xy 365.245201 -233.826305) (xy 365.296496 -233.83443) (xy 365.345889 -233.850478)
			(xy 365.392163 -233.874056) (xy 365.434179 -233.904582) (xy 365.470902 -233.941305) (xy 365.501428 -233.983321)
			(xy 365.525006 -234.029595) (xy 365.541054 -234.078988) (xy 365.549179 -234.130283) (xy 365.549688 -234.15625)
			(xy 365.549179 -234.182217) (xy 365.829089 -234.182217) (xy 365.829089 -234.130283) (xy 365.837214 -234.078988)
			(xy 365.853262 -234.029595) (xy 365.87684 -233.983321) (xy 365.907366 -233.941305) (xy 365.944089 -233.904582)
			(xy 365.986105 -233.874056) (xy 366.032379 -233.850478) (xy 366.081772 -233.83443) (xy 366.133067 -233.826305)
			(xy 366.185001 -233.826305) (xy 366.236296 -233.83443) (xy 366.285689 -233.850478) (xy 366.331963 -233.874056)
			(xy 366.373979 -233.904582) (xy 366.410702 -233.941305) (xy 366.441228 -233.983321) (xy 366.464806 -234.029595)
			(xy 366.480854 -234.078988) (xy 366.488979 -234.130283) (xy 366.489488 -234.15625) (xy 366.488979 -234.182217)
			(xy 366.768889 -234.182217) (xy 366.768889 -234.130283) (xy 366.777014 -234.078988) (xy 366.793062 -234.029595)
			(xy 366.81664 -233.983321) (xy 366.847166 -233.941305) (xy 366.883889 -233.904582) (xy 366.925905 -233.874056)
			(xy 366.972179 -233.850478) (xy 367.021572 -233.83443) (xy 367.072867 -233.826305) (xy 367.124801 -233.826305)
			(xy 367.176096 -233.83443) (xy 367.225489 -233.850478) (xy 367.271763 -233.874056) (xy 367.313779 -233.904582)
			(xy 367.350502 -233.941305) (xy 367.381028 -233.983321) (xy 367.404606 -234.029595) (xy 367.420654 -234.078988)
			(xy 367.428779 -234.130283) (xy 367.429288 -234.15625) (xy 367.428779 -234.182217) (xy 367.708689 -234.182217)
			(xy 367.708689 -234.130283) (xy 367.716814 -234.078988) (xy 367.732862 -234.029595) (xy 367.75644 -233.983321)
			(xy 367.786966 -233.941305) (xy 367.823689 -233.904582) (xy 367.865705 -233.874056) (xy 367.911979 -233.850478)
			(xy 367.961372 -233.83443) (xy 368.012667 -233.826305) (xy 368.064601 -233.826305) (xy 368.115896 -233.83443)
			(xy 368.165289 -233.850478) (xy 368.211563 -233.874056) (xy 368.253579 -233.904582) (xy 368.290302 -233.941305)
			(xy 368.320828 -233.983321) (xy 368.344406 -234.029595) (xy 368.360454 -234.078988) (xy 368.368579 -234.130283)
			(xy 368.369088 -234.15625) (xy 368.368579 -234.182217) (xy 368.648235 -234.182217) (xy 368.648235 -234.130283)
			(xy 368.65636 -234.078988) (xy 368.672408 -234.029595) (xy 368.695986 -233.983321) (xy 368.726512 -233.941305)
			(xy 368.763235 -233.904582) (xy 368.805251 -233.874056) (xy 368.851525 -233.850478) (xy 368.900918 -233.83443)
			(xy 368.952213 -233.826305) (xy 369.004147 -233.826305) (xy 369.055442 -233.83443) (xy 369.104835 -233.850478)
			(xy 369.151109 -233.874056) (xy 369.193125 -233.904582) (xy 369.229848 -233.941305) (xy 369.260374 -233.983321)
			(xy 369.283952 -234.029595) (xy 369.3 -234.078988) (xy 369.308125 -234.130283) (xy 369.308634 -234.15625)
			(xy 369.308125 -234.182217) (xy 369.588289 -234.182217) (xy 369.588289 -234.130283) (xy 369.596414 -234.078988)
			(xy 369.612462 -234.029595) (xy 369.63604 -233.983321) (xy 369.666566 -233.941305) (xy 369.703289 -233.904582)
			(xy 369.745305 -233.874056) (xy 369.791579 -233.850478) (xy 369.840972 -233.83443) (xy 369.892267 -233.826305)
			(xy 369.944201 -233.826305) (xy 369.995496 -233.83443) (xy 370.044889 -233.850478) (xy 370.091163 -233.874056)
			(xy 370.133179 -233.904582) (xy 370.169902 -233.941305) (xy 370.200428 -233.983321) (xy 370.224006 -234.029595)
			(xy 370.240054 -234.078988) (xy 370.248179 -234.130283) (xy 370.248688 -234.15625) (xy 370.248179 -234.182217)
			(xy 370.527835 -234.182217) (xy 370.527835 -234.130283) (xy 370.53596 -234.078988) (xy 370.552008 -234.029595)
			(xy 370.575586 -233.983321) (xy 370.606112 -233.941305) (xy 370.642835 -233.904582) (xy 370.684851 -233.874056)
			(xy 370.731125 -233.850478) (xy 370.780518 -233.83443) (xy 370.831813 -233.826305) (xy 370.883747 -233.826305)
			(xy 370.935042 -233.83443) (xy 370.984435 -233.850478) (xy 371.030709 -233.874056) (xy 371.072725 -233.904582)
			(xy 371.109448 -233.941305) (xy 371.139974 -233.983321) (xy 371.163552 -234.029595) (xy 371.1796 -234.078988)
			(xy 371.187725 -234.130283) (xy 371.188234 -234.15625) (xy 371.187725 -234.182217) (xy 371.467889 -234.182217)
			(xy 371.467889 -234.130283) (xy 371.476014 -234.078988) (xy 371.492062 -234.029595) (xy 371.51564 -233.983321)
			(xy 371.546166 -233.941305) (xy 371.582889 -233.904582) (xy 371.624905 -233.874056) (xy 371.671179 -233.850478)
			(xy 371.720572 -233.83443) (xy 371.771867 -233.826305) (xy 371.823801 -233.826305) (xy 371.875096 -233.83443)
			(xy 371.924489 -233.850478) (xy 371.970763 -233.874056) (xy 372.012779 -233.904582) (xy 372.049502 -233.941305)
			(xy 372.080028 -233.983321) (xy 372.103606 -234.029595) (xy 372.119654 -234.078988) (xy 372.127779 -234.130283)
			(xy 372.128288 -234.15625) (xy 372.127779 -234.182217) (xy 372.407689 -234.182217) (xy 372.407689 -234.130283)
			(xy 372.415814 -234.078988) (xy 372.431862 -234.029595) (xy 372.45544 -233.983321) (xy 372.485966 -233.941305)
			(xy 372.522689 -233.904582) (xy 372.564705 -233.874056) (xy 372.610979 -233.850478) (xy 372.660372 -233.83443)
			(xy 372.711667 -233.826305) (xy 372.763601 -233.826305) (xy 372.814896 -233.83443) (xy 372.864289 -233.850478)
			(xy 372.910563 -233.874056) (xy 372.952579 -233.904582) (xy 372.989302 -233.941305) (xy 373.019828 -233.983321)
			(xy 373.043406 -234.029595) (xy 373.059454 -234.078988) (xy 373.067579 -234.130283) (xy 373.068088 -234.15625)
			(xy 373.067579 -234.182217) (xy 373.347489 -234.182217) (xy 373.347489 -234.130283) (xy 373.355614 -234.078988)
			(xy 373.371662 -234.029595) (xy 373.39524 -233.983321) (xy 373.425766 -233.941305) (xy 373.462489 -233.904582)
			(xy 373.504505 -233.874056) (xy 373.550779 -233.850478) (xy 373.600172 -233.83443) (xy 373.651467 -233.826305)
			(xy 373.703401 -233.826305) (xy 373.754696 -233.83443) (xy 373.804089 -233.850478) (xy 373.850363 -233.874056)
			(xy 373.892379 -233.904582) (xy 373.929102 -233.941305) (xy 373.959628 -233.983321) (xy 373.983206 -234.029595)
			(xy 373.999254 -234.078988) (xy 374.007379 -234.130283) (xy 374.007888 -234.15625) (xy 374.007379 -234.182217)
			(xy 374.287289 -234.182217) (xy 374.287289 -234.130283) (xy 374.295414 -234.078988) (xy 374.311462 -234.029595)
			(xy 374.33504 -233.983321) (xy 374.365566 -233.941305) (xy 374.402289 -233.904582) (xy 374.444305 -233.874056)
			(xy 374.490579 -233.850478) (xy 374.539972 -233.83443) (xy 374.591267 -233.826305) (xy 374.643201 -233.826305)
			(xy 374.694496 -233.83443) (xy 374.743889 -233.850478) (xy 374.790163 -233.874056) (xy 374.832179 -233.904582)
			(xy 374.868902 -233.941305) (xy 374.899428 -233.983321) (xy 374.923006 -234.029595) (xy 374.939054 -234.078988)
			(xy 374.947179 -234.130283) (xy 374.947688 -234.15625) (xy 374.947179 -234.182217) (xy 375.227089 -234.182217)
			(xy 375.227089 -234.130283) (xy 375.235214 -234.078988) (xy 375.251262 -234.029595) (xy 375.27484 -233.983321)
			(xy 375.305366 -233.941305) (xy 375.342089 -233.904582) (xy 375.384105 -233.874056) (xy 375.430379 -233.850478)
			(xy 375.479772 -233.83443) (xy 375.531067 -233.826305) (xy 375.583001 -233.826305) (xy 375.634296 -233.83443)
			(xy 375.683689 -233.850478) (xy 375.729963 -233.874056) (xy 375.771979 -233.904582) (xy 375.808702 -233.941305)
			(xy 375.839228 -233.983321) (xy 375.862806 -234.029595) (xy 375.878854 -234.078988) (xy 375.886979 -234.130283)
			(xy 375.887488 -234.15625) (xy 375.886979 -234.182217) (xy 375.878854 -234.233512) (xy 375.862806 -234.282905)
			(xy 375.839228 -234.329179) (xy 375.808702 -234.371195) (xy 375.771979 -234.407918) (xy 375.729963 -234.438444)
			(xy 375.683689 -234.462022) (xy 375.634296 -234.47807) (xy 375.583001 -234.486195) (xy 375.531067 -234.486195)
			(xy 375.479772 -234.47807) (xy 375.430379 -234.462022) (xy 375.384105 -234.438444) (xy 375.342089 -234.407918)
			(xy 375.305366 -234.371195) (xy 375.27484 -234.329179) (xy 375.251262 -234.282905) (xy 375.235214 -234.233512)
			(xy 375.227089 -234.182217) (xy 374.947179 -234.182217) (xy 374.939054 -234.233512) (xy 374.923006 -234.282905)
			(xy 374.899428 -234.329179) (xy 374.868902 -234.371195) (xy 374.832179 -234.407918) (xy 374.790163 -234.438444)
			(xy 374.743889 -234.462022) (xy 374.694496 -234.47807) (xy 374.643201 -234.486195) (xy 374.591267 -234.486195)
			(xy 374.539972 -234.47807) (xy 374.490579 -234.462022) (xy 374.444305 -234.438444) (xy 374.402289 -234.407918)
			(xy 374.365566 -234.371195) (xy 374.33504 -234.329179) (xy 374.311462 -234.282905) (xy 374.295414 -234.233512)
			(xy 374.287289 -234.182217) (xy 374.007379 -234.182217) (xy 373.999254 -234.233512) (xy 373.983206 -234.282905)
			(xy 373.959628 -234.329179) (xy 373.929102 -234.371195) (xy 373.892379 -234.407918) (xy 373.850363 -234.438444)
			(xy 373.804089 -234.462022) (xy 373.754696 -234.47807) (xy 373.703401 -234.486195) (xy 373.651467 -234.486195)
			(xy 373.600172 -234.47807) (xy 373.550779 -234.462022) (xy 373.504505 -234.438444) (xy 373.462489 -234.407918)
			(xy 373.425766 -234.371195) (xy 373.39524 -234.329179) (xy 373.371662 -234.282905) (xy 373.355614 -234.233512)
			(xy 373.347489 -234.182217) (xy 373.067579 -234.182217) (xy 373.059454 -234.233512) (xy 373.043406 -234.282905)
			(xy 373.019828 -234.329179) (xy 372.989302 -234.371195) (xy 372.952579 -234.407918) (xy 372.910563 -234.438444)
			(xy 372.864289 -234.462022) (xy 372.814896 -234.47807) (xy 372.763601 -234.486195) (xy 372.711667 -234.486195)
			(xy 372.660372 -234.47807) (xy 372.610979 -234.462022) (xy 372.564705 -234.438444) (xy 372.522689 -234.407918)
			(xy 372.485966 -234.371195) (xy 372.45544 -234.329179) (xy 372.431862 -234.282905) (xy 372.415814 -234.233512)
			(xy 372.407689 -234.182217) (xy 372.127779 -234.182217) (xy 372.119654 -234.233512) (xy 372.103606 -234.282905)
			(xy 372.080028 -234.329179) (xy 372.049502 -234.371195) (xy 372.012779 -234.407918) (xy 371.970763 -234.438444)
			(xy 371.924489 -234.462022) (xy 371.875096 -234.47807) (xy 371.823801 -234.486195) (xy 371.771867 -234.486195)
			(xy 371.720572 -234.47807) (xy 371.671179 -234.462022) (xy 371.624905 -234.438444) (xy 371.582889 -234.407918)
			(xy 371.546166 -234.371195) (xy 371.51564 -234.329179) (xy 371.492062 -234.282905) (xy 371.476014 -234.233512)
			(xy 371.467889 -234.182217) (xy 371.187725 -234.182217) (xy 371.1796 -234.233512) (xy 371.163552 -234.282905)
			(xy 371.139974 -234.329179) (xy 371.109448 -234.371195) (xy 371.072725 -234.407918) (xy 371.030709 -234.438444)
			(xy 370.984435 -234.462022) (xy 370.935042 -234.47807) (xy 370.883747 -234.486195) (xy 370.831813 -234.486195)
			(xy 370.780518 -234.47807) (xy 370.731125 -234.462022) (xy 370.684851 -234.438444) (xy 370.642835 -234.407918)
			(xy 370.606112 -234.371195) (xy 370.575586 -234.329179) (xy 370.552008 -234.282905) (xy 370.53596 -234.233512)
			(xy 370.527835 -234.182217) (xy 370.248179 -234.182217) (xy 370.240054 -234.233512) (xy 370.224006 -234.282905)
			(xy 370.200428 -234.329179) (xy 370.169902 -234.371195) (xy 370.133179 -234.407918) (xy 370.091163 -234.438444)
			(xy 370.044889 -234.462022) (xy 369.995496 -234.47807) (xy 369.944201 -234.486195) (xy 369.892267 -234.486195)
			(xy 369.840972 -234.47807) (xy 369.791579 -234.462022) (xy 369.745305 -234.438444) (xy 369.703289 -234.407918)
			(xy 369.666566 -234.371195) (xy 369.63604 -234.329179) (xy 369.612462 -234.282905) (xy 369.596414 -234.233512)
			(xy 369.588289 -234.182217) (xy 369.308125 -234.182217) (xy 369.3 -234.233512) (xy 369.283952 -234.282905)
			(xy 369.260374 -234.329179) (xy 369.229848 -234.371195) (xy 369.193125 -234.407918) (xy 369.151109 -234.438444)
			(xy 369.104835 -234.462022) (xy 369.055442 -234.47807) (xy 369.004147 -234.486195) (xy 368.952213 -234.486195)
			(xy 368.900918 -234.47807) (xy 368.851525 -234.462022) (xy 368.805251 -234.438444) (xy 368.763235 -234.407918)
			(xy 368.726512 -234.371195) (xy 368.695986 -234.329179) (xy 368.672408 -234.282905) (xy 368.65636 -234.233512)
			(xy 368.648235 -234.182217) (xy 368.368579 -234.182217) (xy 368.360454 -234.233512) (xy 368.344406 -234.282905)
			(xy 368.320828 -234.329179) (xy 368.290302 -234.371195) (xy 368.253579 -234.407918) (xy 368.211563 -234.438444)
			(xy 368.165289 -234.462022) (xy 368.115896 -234.47807) (xy 368.064601 -234.486195) (xy 368.012667 -234.486195)
			(xy 367.961372 -234.47807) (xy 367.911979 -234.462022) (xy 367.865705 -234.438444) (xy 367.823689 -234.407918)
			(xy 367.786966 -234.371195) (xy 367.75644 -234.329179) (xy 367.732862 -234.282905) (xy 367.716814 -234.233512)
			(xy 367.708689 -234.182217) (xy 367.428779 -234.182217) (xy 367.420654 -234.233512) (xy 367.404606 -234.282905)
			(xy 367.381028 -234.329179) (xy 367.350502 -234.371195) (xy 367.313779 -234.407918) (xy 367.271763 -234.438444)
			(xy 367.225489 -234.462022) (xy 367.176096 -234.47807) (xy 367.124801 -234.486195) (xy 367.072867 -234.486195)
			(xy 367.021572 -234.47807) (xy 366.972179 -234.462022) (xy 366.925905 -234.438444) (xy 366.883889 -234.407918)
			(xy 366.847166 -234.371195) (xy 366.81664 -234.329179) (xy 366.793062 -234.282905) (xy 366.777014 -234.233512)
			(xy 366.768889 -234.182217) (xy 366.488979 -234.182217) (xy 366.480854 -234.233512) (xy 366.464806 -234.282905)
			(xy 366.441228 -234.329179) (xy 366.410702 -234.371195) (xy 366.373979 -234.407918) (xy 366.331963 -234.438444)
			(xy 366.285689 -234.462022) (xy 366.236296 -234.47807) (xy 366.185001 -234.486195) (xy 366.133067 -234.486195)
			(xy 366.081772 -234.47807) (xy 366.032379 -234.462022) (xy 365.986105 -234.438444) (xy 365.944089 -234.407918)
			(xy 365.907366 -234.371195) (xy 365.87684 -234.329179) (xy 365.853262 -234.282905) (xy 365.837214 -234.233512)
			(xy 365.829089 -234.182217) (xy 365.549179 -234.182217) (xy 365.541054 -234.233512) (xy 365.525006 -234.282905)
			(xy 365.501428 -234.329179) (xy 365.470902 -234.371195) (xy 365.434179 -234.407918) (xy 365.392163 -234.438444)
			(xy 365.345889 -234.462022) (xy 365.296496 -234.47807) (xy 365.245201 -234.486195) (xy 365.193267 -234.486195)
			(xy 365.141972 -234.47807) (xy 365.092579 -234.462022) (xy 365.046305 -234.438444) (xy 365.004289 -234.407918)
			(xy 364.967566 -234.371195) (xy 364.93704 -234.329179) (xy 364.913462 -234.282905) (xy 364.897414 -234.233512)
			(xy 364.889289 -234.182217) (xy 364.609379 -234.182217) (xy 364.601254 -234.233512) (xy 364.585206 -234.282905)
			(xy 364.561628 -234.329179) (xy 364.531102 -234.371195) (xy 364.494379 -234.407918) (xy 364.452363 -234.438444)
			(xy 364.406089 -234.462022) (xy 364.356696 -234.47807) (xy 364.305401 -234.486195) (xy 364.253467 -234.486195)
			(xy 364.202172 -234.47807) (xy 364.152779 -234.462022) (xy 364.106505 -234.438444) (xy 364.064489 -234.407918)
			(xy 364.027766 -234.371195) (xy 363.99724 -234.329179) (xy 363.973662 -234.282905) (xy 363.957614 -234.233512)
			(xy 363.949489 -234.182217) (xy 363.669579 -234.182217) (xy 363.661454 -234.233512) (xy 363.645406 -234.282905)
			(xy 363.621828 -234.329179) (xy 363.591302 -234.371195) (xy 363.554579 -234.407918) (xy 363.512563 -234.438444)
			(xy 363.466289 -234.462022) (xy 363.416896 -234.47807) (xy 363.365601 -234.486195) (xy 363.313667 -234.486195)
			(xy 363.262372 -234.47807) (xy 363.212979 -234.462022) (xy 363.166705 -234.438444) (xy 363.124689 -234.407918)
			(xy 363.087966 -234.371195) (xy 363.05744 -234.329179) (xy 363.033862 -234.282905) (xy 363.017814 -234.233512)
			(xy 363.009689 -234.182217) (xy 362.729779 -234.182217) (xy 362.721654 -234.233512) (xy 362.705606 -234.282905)
			(xy 362.682028 -234.329179) (xy 362.651502 -234.371195) (xy 362.614779 -234.407918) (xy 362.572763 -234.438444)
			(xy 362.526489 -234.462022) (xy 362.477096 -234.47807) (xy 362.425801 -234.486195) (xy 362.373867 -234.486195)
			(xy 362.322572 -234.47807) (xy 362.273179 -234.462022) (xy 362.226905 -234.438444) (xy 362.184889 -234.407918)
			(xy 362.148166 -234.371195) (xy 362.11764 -234.329179) (xy 362.094062 -234.282905) (xy 362.078014 -234.233512)
			(xy 362.069889 -234.182217) (xy 361.789979 -234.182217) (xy 361.781854 -234.233512) (xy 361.765806 -234.282905)
			(xy 361.742228 -234.329179) (xy 361.711702 -234.371195) (xy 361.674979 -234.407918) (xy 361.632963 -234.438444)
			(xy 361.586689 -234.462022) (xy 361.537296 -234.47807) (xy 361.486001 -234.486195) (xy 361.434067 -234.486195)
			(xy 361.382772 -234.47807) (xy 361.333379 -234.462022) (xy 361.287105 -234.438444) (xy 361.245089 -234.407918)
			(xy 361.208366 -234.371195) (xy 361.17784 -234.329179) (xy 361.154262 -234.282905) (xy 361.138214 -234.233512)
			(xy 361.130089 -234.182217) (xy 360.850179 -234.182217) (xy 360.842054 -234.233512) (xy 360.826006 -234.282905)
			(xy 360.802428 -234.329179) (xy 360.771902 -234.371195) (xy 360.735179 -234.407918) (xy 360.693163 -234.438444)
			(xy 360.646889 -234.462022) (xy 360.597496 -234.47807) (xy 360.546201 -234.486195) (xy 360.494267 -234.486195)
			(xy 360.442972 -234.47807) (xy 360.393579 -234.462022) (xy 360.347305 -234.438444) (xy 360.305289 -234.407918)
			(xy 360.268566 -234.371195) (xy 360.23804 -234.329179) (xy 360.214462 -234.282905) (xy 360.198414 -234.233512)
			(xy 360.190289 -234.182217) (xy 359.910379 -234.182217) (xy 359.902254 -234.233512) (xy 359.886206 -234.282905)
			(xy 359.862628 -234.329179) (xy 359.832102 -234.371195) (xy 359.795379 -234.407918) (xy 359.753363 -234.438444)
			(xy 359.707089 -234.462022) (xy 359.657696 -234.47807) (xy 359.606401 -234.486195) (xy 359.554467 -234.486195)
			(xy 359.503172 -234.47807) (xy 359.453779 -234.462022) (xy 359.407505 -234.438444) (xy 359.365489 -234.407918)
			(xy 359.328766 -234.371195) (xy 359.29824 -234.329179) (xy 359.274662 -234.282905) (xy 359.258614 -234.233512)
			(xy 359.250489 -234.182217) (xy 358.970579 -234.182217) (xy 358.962454 -234.233512) (xy 358.946406 -234.282905)
			(xy 358.922828 -234.329179) (xy 358.892302 -234.371195) (xy 358.855579 -234.407918) (xy 358.813563 -234.438444)
			(xy 358.767289 -234.462022) (xy 358.717896 -234.47807) (xy 358.666601 -234.486195) (xy 358.614667 -234.486195)
			(xy 358.563372 -234.47807) (xy 358.513979 -234.462022) (xy 358.467705 -234.438444) (xy 358.425689 -234.407918)
			(xy 358.388966 -234.371195) (xy 358.35844 -234.329179) (xy 358.334862 -234.282905) (xy 358.318814 -234.233512)
			(xy 358.310689 -234.182217) (xy 358.030731 -234.182217) (xy 358.022852 -234.232611) (xy 358.007191 -234.281462)
			(xy 357.984169 -234.327306) (xy 357.954339 -234.369042) (xy 357.918418 -234.405667) (xy 357.877268 -234.4363)
			(xy 357.854758 -234.448604) (xy 357.854758 -234.594908) (xy 357.855308 -234.610096) (xy 357.864225 -234.639133)
			(xy 357.881296 -234.664257) (xy 357.905008 -234.683241) (xy 357.933258 -234.694402) (xy 357.963542 -234.69675)
			(xy 357.993175 -234.690078) (xy 358.00665 -234.683046) (xy 358.031814 -234.669379) (xy 358.08569 -234.649987)
			(xy 358.142104 -234.640182) (xy 358.170734 -234.639612) (xy 358.196702 -234.640124) (xy 358.247998 -234.648253)
			(xy 358.297391 -234.664307) (xy 358.343665 -234.687889) (xy 358.385681 -234.718419) (xy 358.422404 -234.755145)
			(xy 358.452929 -234.797164) (xy 358.476506 -234.84344) (xy 358.492555 -234.892835) (xy 358.500679 -234.944132)
			(xy 358.500679 -234.996033) (xy 358.780335 -234.996033) (xy 358.780335 -234.944099) (xy 358.78846 -234.892804)
			(xy 358.804508 -234.843411) (xy 358.828086 -234.797137) (xy 358.858612 -234.755121) (xy 358.895335 -234.718398)
			(xy 358.937351 -234.687872) (xy 358.983625 -234.664294) (xy 359.033018 -234.648246) (xy 359.084313 -234.640121)
			(xy 359.136247 -234.640121) (xy 359.187542 -234.648246) (xy 359.236935 -234.664294) (xy 359.283209 -234.687872)
			(xy 359.325225 -234.718398) (xy 359.361948 -234.755121) (xy 359.392474 -234.797137) (xy 359.416052 -234.843411)
			(xy 359.4321 -234.892804) (xy 359.440225 -234.944099) (xy 359.440734 -234.970066) (xy 359.440225 -234.996033)
			(xy 359.720135 -234.996033) (xy 359.720135 -234.944099) (xy 359.72826 -234.892804) (xy 359.744308 -234.843411)
			(xy 359.767886 -234.797137) (xy 359.798412 -234.755121) (xy 359.835135 -234.718398) (xy 359.877151 -234.687872)
			(xy 359.923425 -234.664294) (xy 359.972818 -234.648246) (xy 360.024113 -234.640121) (xy 360.076047 -234.640121)
			(xy 360.127342 -234.648246) (xy 360.176735 -234.664294) (xy 360.223009 -234.687872) (xy 360.265025 -234.718398)
			(xy 360.301748 -234.755121) (xy 360.332274 -234.797137) (xy 360.355852 -234.843411) (xy 360.3719 -234.892804)
			(xy 360.380025 -234.944099) (xy 360.380534 -234.970066) (xy 360.380025 -234.996033) (xy 360.659935 -234.996033)
			(xy 360.659935 -234.944099) (xy 360.66806 -234.892804) (xy 360.684108 -234.843411) (xy 360.707686 -234.797137)
			(xy 360.738212 -234.755121) (xy 360.774935 -234.718398) (xy 360.816951 -234.687872) (xy 360.863225 -234.664294)
			(xy 360.912618 -234.648246) (xy 360.963913 -234.640121) (xy 361.015847 -234.640121) (xy 361.067142 -234.648246)
			(xy 361.116535 -234.664294) (xy 361.162809 -234.687872) (xy 361.204825 -234.718398) (xy 361.241548 -234.755121)
			(xy 361.272074 -234.797137) (xy 361.295652 -234.843411) (xy 361.3117 -234.892804) (xy 361.319825 -234.944099)
			(xy 361.320334 -234.970066) (xy 361.319825 -234.996033) (xy 361.599989 -234.996033) (xy 361.599989 -234.944099)
			(xy 361.608114 -234.892804) (xy 361.624162 -234.843411) (xy 361.64774 -234.797137) (xy 361.678266 -234.755121)
			(xy 361.714989 -234.718398) (xy 361.757005 -234.687872) (xy 361.803279 -234.664294) (xy 361.852672 -234.648246)
			(xy 361.903967 -234.640121) (xy 361.955901 -234.640121) (xy 362.007196 -234.648246) (xy 362.056589 -234.664294)
			(xy 362.102863 -234.687872) (xy 362.144879 -234.718398) (xy 362.181602 -234.755121) (xy 362.212128 -234.797137)
			(xy 362.235706 -234.843411) (xy 362.251754 -234.892804) (xy 362.259879 -234.944099) (xy 362.260388 -234.970066)
			(xy 362.259879 -234.996033) (xy 369.118135 -234.996033) (xy 369.118135 -234.944099) (xy 369.12626 -234.892804)
			(xy 369.142308 -234.843411) (xy 369.165886 -234.797137) (xy 369.196412 -234.755121) (xy 369.233135 -234.718398)
			(xy 369.275151 -234.687872) (xy 369.321425 -234.664294) (xy 369.370818 -234.648246) (xy 369.422113 -234.640121)
			(xy 369.474047 -234.640121) (xy 369.525342 -234.648246) (xy 369.574735 -234.664294) (xy 369.621009 -234.687872)
			(xy 369.663025 -234.718398) (xy 369.699748 -234.755121) (xy 369.730274 -234.797137) (xy 369.753852 -234.843411)
			(xy 369.7699 -234.892804) (xy 369.778025 -234.944099) (xy 369.778534 -234.970066) (xy 369.778025 -234.996033)
			(xy 370.057935 -234.996033) (xy 370.057935 -234.944099) (xy 370.06606 -234.892804) (xy 370.082108 -234.843411)
			(xy 370.105686 -234.797137) (xy 370.136212 -234.755121) (xy 370.172935 -234.718398) (xy 370.214951 -234.687872)
			(xy 370.261225 -234.664294) (xy 370.310618 -234.648246) (xy 370.361913 -234.640121) (xy 370.413847 -234.640121)
			(xy 370.465142 -234.648246) (xy 370.514535 -234.664294) (xy 370.560809 -234.687872) (xy 370.602825 -234.718398)
			(xy 370.639548 -234.755121) (xy 370.670074 -234.797137) (xy 370.693652 -234.843411) (xy 370.7097 -234.892804)
			(xy 370.717825 -234.944099) (xy 370.718334 -234.970066) (xy 370.717825 -234.996033) (xy 370.997735 -234.996033)
			(xy 370.997735 -234.944099) (xy 371.00586 -234.892804) (xy 371.021908 -234.843411) (xy 371.045486 -234.797137)
			(xy 371.076012 -234.755121) (xy 371.112735 -234.718398) (xy 371.154751 -234.687872) (xy 371.201025 -234.664294)
			(xy 371.250418 -234.648246) (xy 371.301713 -234.640121) (xy 371.353647 -234.640121) (xy 371.404942 -234.648246)
			(xy 371.454335 -234.664294) (xy 371.500609 -234.687872) (xy 371.542625 -234.718398) (xy 371.579348 -234.755121)
			(xy 371.609874 -234.797137) (xy 371.633452 -234.843411) (xy 371.6495 -234.892804) (xy 371.657625 -234.944099)
			(xy 371.658134 -234.970066) (xy 371.657625 -234.996033) (xy 371.937535 -234.996033) (xy 371.937535 -234.944099)
			(xy 371.94566 -234.892804) (xy 371.961708 -234.843411) (xy 371.985286 -234.797137) (xy 372.015812 -234.755121)
			(xy 372.052535 -234.718398) (xy 372.094551 -234.687872) (xy 372.140825 -234.664294) (xy 372.190218 -234.648246)
			(xy 372.241513 -234.640121) (xy 372.293447 -234.640121) (xy 372.344742 -234.648246) (xy 372.394135 -234.664294)
			(xy 372.440409 -234.687872) (xy 372.482425 -234.718398) (xy 372.519148 -234.755121) (xy 372.549674 -234.797137)
			(xy 372.573252 -234.843411) (xy 372.5893 -234.892804) (xy 372.597425 -234.944099) (xy 372.597934 -234.970066)
			(xy 372.597425 -234.996033) (xy 372.877589 -234.996033) (xy 372.877589 -234.944099) (xy 372.885714 -234.892804)
			(xy 372.901762 -234.843411) (xy 372.92534 -234.797137) (xy 372.955866 -234.755121) (xy 372.992589 -234.718398)
			(xy 373.034605 -234.687872) (xy 373.080879 -234.664294) (xy 373.130272 -234.648246) (xy 373.181567 -234.640121)
			(xy 373.233501 -234.640121) (xy 373.284796 -234.648246) (xy 373.334189 -234.664294) (xy 373.380463 -234.687872)
			(xy 373.422479 -234.718398) (xy 373.459202 -234.755121) (xy 373.489728 -234.797137) (xy 373.513306 -234.843411)
			(xy 373.529354 -234.892804) (xy 373.537479 -234.944099) (xy 373.537988 -234.970066) (xy 373.537479 -234.996033)
			(xy 373.817135 -234.996033) (xy 373.817135 -234.944099) (xy 373.82526 -234.892804) (xy 373.841308 -234.843411)
			(xy 373.864886 -234.797137) (xy 373.895412 -234.755121) (xy 373.932135 -234.718398) (xy 373.974151 -234.687872)
			(xy 374.020425 -234.664294) (xy 374.069818 -234.648246) (xy 374.121113 -234.640121) (xy 374.173047 -234.640121)
			(xy 374.224342 -234.648246) (xy 374.273735 -234.664294) (xy 374.320009 -234.687872) (xy 374.362025 -234.718398)
			(xy 374.398748 -234.755121) (xy 374.429274 -234.797137) (xy 374.452852 -234.843411) (xy 374.4689 -234.892804)
			(xy 374.477025 -234.944099) (xy 374.477534 -234.970066) (xy 374.477025 -234.996033) (xy 374.756935 -234.996033)
			(xy 374.756935 -234.944099) (xy 374.76506 -234.892804) (xy 374.781108 -234.843411) (xy 374.804686 -234.797137)
			(xy 374.835212 -234.755121) (xy 374.871935 -234.718398) (xy 374.913951 -234.687872) (xy 374.960225 -234.664294)
			(xy 375.009618 -234.648246) (xy 375.060913 -234.640121) (xy 375.112847 -234.640121) (xy 375.164142 -234.648246)
			(xy 375.213535 -234.664294) (xy 375.259809 -234.687872) (xy 375.301825 -234.718398) (xy 375.338548 -234.755121)
			(xy 375.369074 -234.797137) (xy 375.392652 -234.843411) (xy 375.4087 -234.892804) (xy 375.416825 -234.944099)
			(xy 375.417334 -234.970066) (xy 375.416825 -234.996033) (xy 375.4087 -235.047328) (xy 375.392652 -235.096721)
			(xy 375.369074 -235.142995) (xy 375.338548 -235.185011) (xy 375.301825 -235.221734) (xy 375.259809 -235.25226)
			(xy 375.213535 -235.275838) (xy 375.164142 -235.291886) (xy 375.112847 -235.300011) (xy 375.060913 -235.300011)
			(xy 375.009618 -235.291886) (xy 374.960225 -235.275838) (xy 374.913951 -235.25226) (xy 374.871935 -235.221734)
			(xy 374.835212 -235.185011) (xy 374.804686 -235.142995) (xy 374.781108 -235.096721) (xy 374.76506 -235.047328)
			(xy 374.756935 -234.996033) (xy 374.477025 -234.996033) (xy 374.4689 -235.047328) (xy 374.452852 -235.096721)
			(xy 374.429274 -235.142995) (xy 374.398748 -235.185011) (xy 374.362025 -235.221734) (xy 374.320009 -235.25226)
			(xy 374.273735 -235.275838) (xy 374.224342 -235.291886) (xy 374.173047 -235.300011) (xy 374.121113 -235.300011)
			(xy 374.069818 -235.291886) (xy 374.020425 -235.275838) (xy 373.974151 -235.25226) (xy 373.932135 -235.221734)
			(xy 373.895412 -235.185011) (xy 373.864886 -235.142995) (xy 373.841308 -235.096721) (xy 373.82526 -235.047328)
			(xy 373.817135 -234.996033) (xy 373.537479 -234.996033) (xy 373.529354 -235.047328) (xy 373.513306 -235.096721)
			(xy 373.489728 -235.142995) (xy 373.459202 -235.185011) (xy 373.422479 -235.221734) (xy 373.380463 -235.25226)
			(xy 373.334189 -235.275838) (xy 373.284796 -235.291886) (xy 373.233501 -235.300011) (xy 373.181567 -235.300011)
			(xy 373.130272 -235.291886) (xy 373.080879 -235.275838) (xy 373.034605 -235.25226) (xy 372.992589 -235.221734)
			(xy 372.955866 -235.185011) (xy 372.92534 -235.142995) (xy 372.901762 -235.096721) (xy 372.885714 -235.047328)
			(xy 372.877589 -234.996033) (xy 372.597425 -234.996033) (xy 372.5893 -235.047328) (xy 372.573252 -235.096721)
			(xy 372.549674 -235.142995) (xy 372.519148 -235.185011) (xy 372.482425 -235.221734) (xy 372.440409 -235.25226)
			(xy 372.394135 -235.275838) (xy 372.344742 -235.291886) (xy 372.293447 -235.300011) (xy 372.241513 -235.300011)
			(xy 372.190218 -235.291886) (xy 372.140825 -235.275838) (xy 372.094551 -235.25226) (xy 372.052535 -235.221734)
			(xy 372.015812 -235.185011) (xy 371.985286 -235.142995) (xy 371.961708 -235.096721) (xy 371.94566 -235.047328)
			(xy 371.937535 -234.996033) (xy 371.657625 -234.996033) (xy 371.6495 -235.047328) (xy 371.633452 -235.096721)
			(xy 371.609874 -235.142995) (xy 371.579348 -235.185011) (xy 371.542625 -235.221734) (xy 371.500609 -235.25226)
			(xy 371.454335 -235.275838) (xy 371.404942 -235.291886) (xy 371.353647 -235.300011) (xy 371.301713 -235.300011)
			(xy 371.250418 -235.291886) (xy 371.201025 -235.275838) (xy 371.154751 -235.25226) (xy 371.112735 -235.221734)
			(xy 371.076012 -235.185011) (xy 371.045486 -235.142995) (xy 371.021908 -235.096721) (xy 371.00586 -235.047328)
			(xy 370.997735 -234.996033) (xy 370.717825 -234.996033) (xy 370.7097 -235.047328) (xy 370.693652 -235.096721)
			(xy 370.670074 -235.142995) (xy 370.639548 -235.185011) (xy 370.602825 -235.221734) (xy 370.560809 -235.25226)
			(xy 370.514535 -235.275838) (xy 370.465142 -235.291886) (xy 370.413847 -235.300011) (xy 370.361913 -235.300011)
			(xy 370.310618 -235.291886) (xy 370.261225 -235.275838) (xy 370.214951 -235.25226) (xy 370.172935 -235.221734)
			(xy 370.136212 -235.185011) (xy 370.105686 -235.142995) (xy 370.082108 -235.096721) (xy 370.06606 -235.047328)
			(xy 370.057935 -234.996033) (xy 369.778025 -234.996033) (xy 369.7699 -235.047328) (xy 369.753852 -235.096721)
			(xy 369.730274 -235.142995) (xy 369.699748 -235.185011) (xy 369.663025 -235.221734) (xy 369.621009 -235.25226)
			(xy 369.574735 -235.275838) (xy 369.525342 -235.291886) (xy 369.474047 -235.300011) (xy 369.422113 -235.300011)
			(xy 369.370818 -235.291886) (xy 369.321425 -235.275838) (xy 369.275151 -235.25226) (xy 369.233135 -235.221734)
			(xy 369.196412 -235.185011) (xy 369.165886 -235.142995) (xy 369.142308 -235.096721) (xy 369.12626 -235.047328)
			(xy 369.118135 -234.996033) (xy 362.259879 -234.996033) (xy 362.251754 -235.047328) (xy 362.235706 -235.096721)
			(xy 362.212128 -235.142995) (xy 362.181602 -235.185011) (xy 362.144879 -235.221734) (xy 362.102863 -235.25226)
			(xy 362.056589 -235.275838) (xy 362.007196 -235.291886) (xy 361.955901 -235.300011) (xy 361.903967 -235.300011)
			(xy 361.852672 -235.291886) (xy 361.803279 -235.275838) (xy 361.757005 -235.25226) (xy 361.714989 -235.221734)
			(xy 361.678266 -235.185011) (xy 361.64774 -235.142995) (xy 361.624162 -235.096721) (xy 361.608114 -235.047328)
			(xy 361.599989 -234.996033) (xy 361.319825 -234.996033) (xy 361.3117 -235.047328) (xy 361.295652 -235.096721)
			(xy 361.272074 -235.142995) (xy 361.241548 -235.185011) (xy 361.204825 -235.221734) (xy 361.162809 -235.25226)
			(xy 361.116535 -235.275838) (xy 361.067142 -235.291886) (xy 361.015847 -235.300011) (xy 360.963913 -235.300011)
			(xy 360.912618 -235.291886) (xy 360.863225 -235.275838) (xy 360.816951 -235.25226) (xy 360.774935 -235.221734)
			(xy 360.738212 -235.185011) (xy 360.707686 -235.142995) (xy 360.684108 -235.096721) (xy 360.66806 -235.047328)
			(xy 360.659935 -234.996033) (xy 360.380025 -234.996033) (xy 360.3719 -235.047328) (xy 360.355852 -235.096721)
			(xy 360.332274 -235.142995) (xy 360.301748 -235.185011) (xy 360.265025 -235.221734) (xy 360.223009 -235.25226)
			(xy 360.176735 -235.275838) (xy 360.127342 -235.291886) (xy 360.076047 -235.300011) (xy 360.024113 -235.300011)
			(xy 359.972818 -235.291886) (xy 359.923425 -235.275838) (xy 359.877151 -235.25226) (xy 359.835135 -235.221734)
			(xy 359.798412 -235.185011) (xy 359.767886 -235.142995) (xy 359.744308 -235.096721) (xy 359.72826 -235.047328)
			(xy 359.720135 -234.996033) (xy 359.440225 -234.996033) (xy 359.4321 -235.047328) (xy 359.416052 -235.096721)
			(xy 359.392474 -235.142995) (xy 359.361948 -235.185011) (xy 359.325225 -235.221734) (xy 359.283209 -235.25226)
			(xy 359.236935 -235.275838) (xy 359.187542 -235.291886) (xy 359.136247 -235.300011) (xy 359.084313 -235.300011)
			(xy 359.033018 -235.291886) (xy 358.983625 -235.275838) (xy 358.937351 -235.25226) (xy 358.895335 -235.221734)
			(xy 358.858612 -235.185011) (xy 358.828086 -235.142995) (xy 358.804508 -235.096721) (xy 358.78846 -235.047328)
			(xy 358.780335 -234.996033) (xy 358.500679 -234.996033) (xy 358.500679 -234.996068) (xy 358.492555 -235.047365)
			(xy 358.476506 -235.09676) (xy 358.452929 -235.143036) (xy 358.422404 -235.185055) (xy 358.385681 -235.221781)
			(xy 358.343665 -235.252311) (xy 358.297391 -235.275893) (xy 358.247998 -235.291947) (xy 358.196702 -235.300076)
			(xy 358.170734 -235.30052) (xy 358.142105 -235.299934) (xy 358.085694 -235.290123) (xy 358.031813 -235.270752)
			(xy 358.00665 -235.257086) (xy 357.993187 -235.250068) (xy 357.96357 -235.243469) (xy 357.933321 -235.245857)
			(xy 357.905107 -235.257023) (xy 357.881416 -235.275983) (xy 357.864337 -235.301063) (xy 357.855376 -235.330053)
			(xy 357.854758 -235.345224) (xy 357.854758 -235.491528) (xy 357.877226 -235.503907) (xy 357.918375 -235.534534)
			(xy 357.954297 -235.571152) (xy 357.984128 -235.612881) (xy 358.007153 -235.658719) (xy 358.022818 -235.707564)
			(xy 358.030746 -235.758244) (xy 358.030747 -235.809539) (xy 358.030699 -235.809849) (xy 358.310689 -235.809849)
			(xy 358.310689 -235.757915) (xy 358.318814 -235.70662) (xy 358.334862 -235.657227) (xy 358.35844 -235.610953)
			(xy 358.388966 -235.568937) (xy 358.425689 -235.532214) (xy 358.467705 -235.501688) (xy 358.513979 -235.47811)
			(xy 358.563372 -235.462062) (xy 358.614667 -235.453937) (xy 358.666601 -235.453937) (xy 358.717896 -235.462062)
			(xy 358.767289 -235.47811) (xy 358.813563 -235.501688) (xy 358.855579 -235.532214) (xy 358.892302 -235.568937)
			(xy 358.922828 -235.610953) (xy 358.946406 -235.657227) (xy 358.962454 -235.70662) (xy 358.970579 -235.757915)
			(xy 358.971088 -235.783882) (xy 358.970579 -235.809849) (xy 359.250489 -235.809849) (xy 359.250489 -235.757915)
			(xy 359.258614 -235.70662) (xy 359.274662 -235.657227) (xy 359.29824 -235.610953) (xy 359.328766 -235.568937)
			(xy 359.365489 -235.532214) (xy 359.407505 -235.501688) (xy 359.453779 -235.47811) (xy 359.503172 -235.462062)
			(xy 359.554467 -235.453937) (xy 359.606401 -235.453937) (xy 359.657696 -235.462062) (xy 359.707089 -235.47811)
			(xy 359.753363 -235.501688) (xy 359.795379 -235.532214) (xy 359.832102 -235.568937) (xy 359.862628 -235.610953)
			(xy 359.886206 -235.657227) (xy 359.902254 -235.70662) (xy 359.910379 -235.757915) (xy 359.910888 -235.783882)
			(xy 359.910379 -235.809849) (xy 360.190289 -235.809849) (xy 360.190289 -235.757915) (xy 360.198414 -235.70662)
			(xy 360.214462 -235.657227) (xy 360.23804 -235.610953) (xy 360.268566 -235.568937) (xy 360.305289 -235.532214)
			(xy 360.347305 -235.501688) (xy 360.393579 -235.47811) (xy 360.442972 -235.462062) (xy 360.494267 -235.453937)
			(xy 360.546201 -235.453937) (xy 360.597496 -235.462062) (xy 360.646889 -235.47811) (xy 360.693163 -235.501688)
			(xy 360.735179 -235.532214) (xy 360.771902 -235.568937) (xy 360.802428 -235.610953) (xy 360.826006 -235.657227)
			(xy 360.842054 -235.70662) (xy 360.850179 -235.757915) (xy 360.850688 -235.783882) (xy 360.850179 -235.809849)
			(xy 361.130089 -235.809849) (xy 361.130089 -235.757915) (xy 361.138214 -235.70662) (xy 361.154262 -235.657227)
			(xy 361.17784 -235.610953) (xy 361.208366 -235.568937) (xy 361.245089 -235.532214) (xy 361.287105 -235.501688)
			(xy 361.333379 -235.47811) (xy 361.382772 -235.462062) (xy 361.434067 -235.453937) (xy 361.486001 -235.453937)
			(xy 361.537296 -235.462062) (xy 361.586689 -235.47811) (xy 361.632963 -235.501688) (xy 361.674979 -235.532214)
			(xy 361.711702 -235.568937) (xy 361.742228 -235.610953) (xy 361.765806 -235.657227) (xy 361.781854 -235.70662)
			(xy 361.789979 -235.757915) (xy 361.790488 -235.783882) (xy 361.789979 -235.809849) (xy 362.069889 -235.809849)
			(xy 362.069889 -235.757915) (xy 362.078014 -235.70662) (xy 362.094062 -235.657227) (xy 362.11764 -235.610953)
			(xy 362.148166 -235.568937) (xy 362.184889 -235.532214) (xy 362.226905 -235.501688) (xy 362.273179 -235.47811)
			(xy 362.322572 -235.462062) (xy 362.373867 -235.453937) (xy 362.425801 -235.453937) (xy 362.477096 -235.462062)
			(xy 362.526489 -235.47811) (xy 362.572763 -235.501688) (xy 362.614779 -235.532214) (xy 362.651502 -235.568937)
			(xy 362.682028 -235.610953) (xy 362.705606 -235.657227) (xy 362.721654 -235.70662) (xy 362.729779 -235.757915)
			(xy 362.730288 -235.783882) (xy 362.729779 -235.809849) (xy 369.588289 -235.809849) (xy 369.588289 -235.757915)
			(xy 369.596414 -235.70662) (xy 369.612462 -235.657227) (xy 369.63604 -235.610953) (xy 369.666566 -235.568937)
			(xy 369.703289 -235.532214) (xy 369.745305 -235.501688) (xy 369.791579 -235.47811) (xy 369.840972 -235.462062)
			(xy 369.892267 -235.453937) (xy 369.944201 -235.453937) (xy 369.995496 -235.462062) (xy 370.044889 -235.47811)
			(xy 370.091163 -235.501688) (xy 370.133179 -235.532214) (xy 370.169902 -235.568937) (xy 370.200428 -235.610953)
			(xy 370.224006 -235.657227) (xy 370.240054 -235.70662) (xy 370.248179 -235.757915) (xy 370.248688 -235.783882)
			(xy 370.248179 -235.809849) (xy 370.528089 -235.809849) (xy 370.528089 -235.757915) (xy 370.536214 -235.70662)
			(xy 370.552262 -235.657227) (xy 370.57584 -235.610953) (xy 370.606366 -235.568937) (xy 370.643089 -235.532214)
			(xy 370.685105 -235.501688) (xy 370.731379 -235.47811) (xy 370.780772 -235.462062) (xy 370.832067 -235.453937)
			(xy 370.884001 -235.453937) (xy 370.935296 -235.462062) (xy 370.984689 -235.47811) (xy 371.030963 -235.501688)
			(xy 371.072979 -235.532214) (xy 371.109702 -235.568937) (xy 371.140228 -235.610953) (xy 371.163806 -235.657227)
			(xy 371.179854 -235.70662) (xy 371.187979 -235.757915) (xy 371.188488 -235.783882) (xy 371.187979 -235.809849)
			(xy 371.467889 -235.809849) (xy 371.467889 -235.757915) (xy 371.476014 -235.70662) (xy 371.492062 -235.657227)
			(xy 371.51564 -235.610953) (xy 371.546166 -235.568937) (xy 371.582889 -235.532214) (xy 371.624905 -235.501688)
			(xy 371.671179 -235.47811) (xy 371.720572 -235.462062) (xy 371.771867 -235.453937) (xy 371.823801 -235.453937)
			(xy 371.875096 -235.462062) (xy 371.924489 -235.47811) (xy 371.970763 -235.501688) (xy 372.012779 -235.532214)
			(xy 372.049502 -235.568937) (xy 372.080028 -235.610953) (xy 372.103606 -235.657227) (xy 372.119654 -235.70662)
			(xy 372.127779 -235.757915) (xy 372.128288 -235.783882) (xy 372.127779 -235.809849) (xy 372.407689 -235.809849)
			(xy 372.407689 -235.757915) (xy 372.415814 -235.70662) (xy 372.431862 -235.657227) (xy 372.45544 -235.610953)
			(xy 372.485966 -235.568937) (xy 372.522689 -235.532214) (xy 372.564705 -235.501688) (xy 372.610979 -235.47811)
			(xy 372.660372 -235.462062) (xy 372.711667 -235.453937) (xy 372.763601 -235.453937) (xy 372.814896 -235.462062)
			(xy 372.864289 -235.47811) (xy 372.910563 -235.501688) (xy 372.952579 -235.532214) (xy 372.989302 -235.568937)
			(xy 373.019828 -235.610953) (xy 373.043406 -235.657227) (xy 373.059454 -235.70662) (xy 373.067579 -235.757915)
			(xy 373.068088 -235.783882) (xy 373.067579 -235.809849) (xy 373.347235 -235.809849) (xy 373.347235 -235.757915)
			(xy 373.35536 -235.70662) (xy 373.371408 -235.657227) (xy 373.394986 -235.610953) (xy 373.425512 -235.568937)
			(xy 373.462235 -235.532214) (xy 373.504251 -235.501688) (xy 373.550525 -235.47811) (xy 373.599918 -235.462062)
			(xy 373.651213 -235.453937) (xy 373.703147 -235.453937) (xy 373.754442 -235.462062) (xy 373.803835 -235.47811)
			(xy 373.850109 -235.501688) (xy 373.892125 -235.532214) (xy 373.928848 -235.568937) (xy 373.959374 -235.610953)
			(xy 373.982952 -235.657227) (xy 373.999 -235.70662) (xy 374.007125 -235.757915) (xy 374.007634 -235.783882)
			(xy 374.007125 -235.809849) (xy 374.287289 -235.809849) (xy 374.287289 -235.757915) (xy 374.295414 -235.70662)
			(xy 374.311462 -235.657227) (xy 374.33504 -235.610953) (xy 374.365566 -235.568937) (xy 374.402289 -235.532214)
			(xy 374.444305 -235.501688) (xy 374.490579 -235.47811) (xy 374.539972 -235.462062) (xy 374.591267 -235.453937)
			(xy 374.643201 -235.453937) (xy 374.694496 -235.462062) (xy 374.743889 -235.47811) (xy 374.790163 -235.501688)
			(xy 374.832179 -235.532214) (xy 374.868902 -235.568937) (xy 374.899428 -235.610953) (xy 374.923006 -235.657227)
			(xy 374.939054 -235.70662) (xy 374.947179 -235.757915) (xy 374.947688 -235.783882) (xy 374.947179 -235.809849)
			(xy 375.227089 -235.809849) (xy 375.227089 -235.757915) (xy 375.235214 -235.70662) (xy 375.251262 -235.657227)
			(xy 375.27484 -235.610953) (xy 375.305366 -235.568937) (xy 375.342089 -235.532214) (xy 375.384105 -235.501688)
			(xy 375.430379 -235.47811) (xy 375.479772 -235.462062) (xy 375.531067 -235.453937) (xy 375.583001 -235.453937)
			(xy 375.634296 -235.462062) (xy 375.683689 -235.47811) (xy 375.729963 -235.501688) (xy 375.771979 -235.532214)
			(xy 375.808702 -235.568937) (xy 375.839228 -235.610953) (xy 375.862806 -235.657227) (xy 375.878854 -235.70662)
			(xy 375.886979 -235.757915) (xy 375.887488 -235.783882) (xy 375.886979 -235.809849) (xy 375.878854 -235.861144)
			(xy 375.862806 -235.910537) (xy 375.839228 -235.956811) (xy 375.808702 -235.998827) (xy 375.771979 -236.03555)
			(xy 375.729963 -236.066076) (xy 375.683689 -236.089654) (xy 375.634296 -236.105702) (xy 375.583001 -236.113827)
			(xy 375.531067 -236.113827) (xy 375.479772 -236.105702) (xy 375.430379 -236.089654) (xy 375.384105 -236.066076)
			(xy 375.342089 -236.03555) (xy 375.305366 -235.998827) (xy 375.27484 -235.956811) (xy 375.251262 -235.910537)
			(xy 375.235214 -235.861144) (xy 375.227089 -235.809849) (xy 374.947179 -235.809849) (xy 374.939054 -235.861144)
			(xy 374.923006 -235.910537) (xy 374.899428 -235.956811) (xy 374.868902 -235.998827) (xy 374.832179 -236.03555)
			(xy 374.790163 -236.066076) (xy 374.743889 -236.089654) (xy 374.694496 -236.105702) (xy 374.643201 -236.113827)
			(xy 374.591267 -236.113827) (xy 374.539972 -236.105702) (xy 374.490579 -236.089654) (xy 374.444305 -236.066076)
			(xy 374.402289 -236.03555) (xy 374.365566 -235.998827) (xy 374.33504 -235.956811) (xy 374.311462 -235.910537)
			(xy 374.295414 -235.861144) (xy 374.287289 -235.809849) (xy 374.007125 -235.809849) (xy 373.999 -235.861144)
			(xy 373.982952 -235.910537) (xy 373.959374 -235.956811) (xy 373.928848 -235.998827) (xy 373.892125 -236.03555)
			(xy 373.850109 -236.066076) (xy 373.803835 -236.089654) (xy 373.754442 -236.105702) (xy 373.703147 -236.113827)
			(xy 373.651213 -236.113827) (xy 373.599918 -236.105702) (xy 373.550525 -236.089654) (xy 373.504251 -236.066076)
			(xy 373.462235 -236.03555) (xy 373.425512 -235.998827) (xy 373.394986 -235.956811) (xy 373.371408 -235.910537)
			(xy 373.35536 -235.861144) (xy 373.347235 -235.809849) (xy 373.067579 -235.809849) (xy 373.059454 -235.861144)
			(xy 373.043406 -235.910537) (xy 373.019828 -235.956811) (xy 372.989302 -235.998827) (xy 372.952579 -236.03555)
			(xy 372.910563 -236.066076) (xy 372.864289 -236.089654) (xy 372.814896 -236.105702) (xy 372.763601 -236.113827)
			(xy 372.711667 -236.113827) (xy 372.660372 -236.105702) (xy 372.610979 -236.089654) (xy 372.564705 -236.066076)
			(xy 372.522689 -236.03555) (xy 372.485966 -235.998827) (xy 372.45544 -235.956811) (xy 372.431862 -235.910537)
			(xy 372.415814 -235.861144) (xy 372.407689 -235.809849) (xy 372.127779 -235.809849) (xy 372.119654 -235.861144)
			(xy 372.103606 -235.910537) (xy 372.080028 -235.956811) (xy 372.049502 -235.998827) (xy 372.012779 -236.03555)
			(xy 371.970763 -236.066076) (xy 371.924489 -236.089654) (xy 371.875096 -236.105702) (xy 371.823801 -236.113827)
			(xy 371.771867 -236.113827) (xy 371.720572 -236.105702) (xy 371.671179 -236.089654) (xy 371.624905 -236.066076)
			(xy 371.582889 -236.03555) (xy 371.546166 -235.998827) (xy 371.51564 -235.956811) (xy 371.492062 -235.910537)
			(xy 371.476014 -235.861144) (xy 371.467889 -235.809849) (xy 371.187979 -235.809849) (xy 371.179854 -235.861144)
			(xy 371.163806 -235.910537) (xy 371.140228 -235.956811) (xy 371.109702 -235.998827) (xy 371.072979 -236.03555)
			(xy 371.030963 -236.066076) (xy 370.984689 -236.089654) (xy 370.935296 -236.105702) (xy 370.884001 -236.113827)
			(xy 370.832067 -236.113827) (xy 370.780772 -236.105702) (xy 370.731379 -236.089654) (xy 370.685105 -236.066076)
			(xy 370.643089 -236.03555) (xy 370.606366 -235.998827) (xy 370.57584 -235.956811) (xy 370.552262 -235.910537)
			(xy 370.536214 -235.861144) (xy 370.528089 -235.809849) (xy 370.248179 -235.809849) (xy 370.240054 -235.861144)
			(xy 370.224006 -235.910537) (xy 370.200428 -235.956811) (xy 370.169902 -235.998827) (xy 370.133179 -236.03555)
			(xy 370.091163 -236.066076) (xy 370.044889 -236.089654) (xy 369.995496 -236.105702) (xy 369.944201 -236.113827)
			(xy 369.892267 -236.113827) (xy 369.840972 -236.105702) (xy 369.791579 -236.089654) (xy 369.745305 -236.066076)
			(xy 369.703289 -236.03555) (xy 369.666566 -235.998827) (xy 369.63604 -235.956811) (xy 369.612462 -235.910537)
			(xy 369.596414 -235.861144) (xy 369.588289 -235.809849) (xy 362.729779 -235.809849) (xy 362.721654 -235.861144)
			(xy 362.705606 -235.910537) (xy 362.682028 -235.956811) (xy 362.651502 -235.998827) (xy 362.614779 -236.03555)
			(xy 362.572763 -236.066076) (xy 362.526489 -236.089654) (xy 362.477096 -236.105702) (xy 362.425801 -236.113827)
			(xy 362.373867 -236.113827) (xy 362.322572 -236.105702) (xy 362.273179 -236.089654) (xy 362.226905 -236.066076)
			(xy 362.184889 -236.03555) (xy 362.148166 -235.998827) (xy 362.11764 -235.956811) (xy 362.094062 -235.910537)
			(xy 362.078014 -235.861144) (xy 362.069889 -235.809849) (xy 361.789979 -235.809849) (xy 361.781854 -235.861144)
			(xy 361.765806 -235.910537) (xy 361.742228 -235.956811) (xy 361.711702 -235.998827) (xy 361.674979 -236.03555)
			(xy 361.632963 -236.066076) (xy 361.586689 -236.089654) (xy 361.537296 -236.105702) (xy 361.486001 -236.113827)
			(xy 361.434067 -236.113827) (xy 361.382772 -236.105702) (xy 361.333379 -236.089654) (xy 361.287105 -236.066076)
			(xy 361.245089 -236.03555) (xy 361.208366 -235.998827) (xy 361.17784 -235.956811) (xy 361.154262 -235.910537)
			(xy 361.138214 -235.861144) (xy 361.130089 -235.809849) (xy 360.850179 -235.809849) (xy 360.842054 -235.861144)
			(xy 360.826006 -235.910537) (xy 360.802428 -235.956811) (xy 360.771902 -235.998827) (xy 360.735179 -236.03555)
			(xy 360.693163 -236.066076) (xy 360.646889 -236.089654) (xy 360.597496 -236.105702) (xy 360.546201 -236.113827)
			(xy 360.494267 -236.113827) (xy 360.442972 -236.105702) (xy 360.393579 -236.089654) (xy 360.347305 -236.066076)
			(xy 360.305289 -236.03555) (xy 360.268566 -235.998827) (xy 360.23804 -235.956811) (xy 360.214462 -235.910537)
			(xy 360.198414 -235.861144) (xy 360.190289 -235.809849) (xy 359.910379 -235.809849) (xy 359.902254 -235.861144)
			(xy 359.886206 -235.910537) (xy 359.862628 -235.956811) (xy 359.832102 -235.998827) (xy 359.795379 -236.03555)
			(xy 359.753363 -236.066076) (xy 359.707089 -236.089654) (xy 359.657696 -236.105702) (xy 359.606401 -236.113827)
			(xy 359.554467 -236.113827) (xy 359.503172 -236.105702) (xy 359.453779 -236.089654) (xy 359.407505 -236.066076)
			(xy 359.365489 -236.03555) (xy 359.328766 -235.998827) (xy 359.29824 -235.956811) (xy 359.274662 -235.910537)
			(xy 359.258614 -235.861144) (xy 359.250489 -235.809849) (xy 358.970579 -235.809849) (xy 358.962454 -235.861144)
			(xy 358.946406 -235.910537) (xy 358.922828 -235.956811) (xy 358.892302 -235.998827) (xy 358.855579 -236.03555)
			(xy 358.813563 -236.066076) (xy 358.767289 -236.089654) (xy 358.717896 -236.105702) (xy 358.666601 -236.113827)
			(xy 358.614667 -236.113827) (xy 358.563372 -236.105702) (xy 358.513979 -236.089654) (xy 358.467705 -236.066076)
			(xy 358.425689 -236.03555) (xy 358.388966 -235.998827) (xy 358.35844 -235.956811) (xy 358.334862 -235.910537)
			(xy 358.318814 -235.861144) (xy 358.310689 -235.809849) (xy 358.030699 -235.809849) (xy 358.022821 -235.860219)
			(xy 358.007159 -235.909065) (xy 357.984137 -235.954905) (xy 357.954308 -235.996635) (xy 357.918388 -236.033255)
			(xy 357.87724 -236.063884) (xy 357.854758 -236.076236) (xy 357.854758 -236.222794) (xy 357.855306 -236.237984)
			(xy 357.864221 -236.267024) (xy 357.881292 -236.292152) (xy 357.905005 -236.311139) (xy 357.933258 -236.322302)
			(xy 357.963545 -236.32465) (xy 357.993181 -236.317976) (xy 358.00665 -236.310932) (xy 358.031814 -236.297265)
			(xy 358.08569 -236.277875) (xy 358.142104 -236.26807) (xy 358.170734 -236.267498) (xy 358.196701 -236.26801)
			(xy 358.247995 -236.276138) (xy 358.297386 -236.292189) (xy 358.343658 -236.315768) (xy 358.385674 -236.346294)
			(xy 358.422397 -236.383016) (xy 358.452925 -236.42503) (xy 358.476506 -236.471301) (xy 358.492559 -236.520692)
			(xy 358.500689 -236.571985) (xy 358.501188 -236.597952) (xy 358.50067 -236.623919) (xy 358.780335 -236.623919)
			(xy 358.780335 -236.571985) (xy 358.78846 -236.52069) (xy 358.804508 -236.471297) (xy 358.828086 -236.425023)
			(xy 358.858612 -236.383007) (xy 358.895335 -236.346284) (xy 358.937351 -236.315758) (xy 358.983625 -236.29218)
			(xy 359.033018 -236.276132) (xy 359.084313 -236.268007) (xy 359.136247 -236.268007) (xy 359.187542 -236.276132)
			(xy 359.236935 -236.29218) (xy 359.283209 -236.315758) (xy 359.325225 -236.346284) (xy 359.361948 -236.383007)
			(xy 359.392474 -236.425023) (xy 359.416052 -236.471297) (xy 359.4321 -236.52069) (xy 359.440225 -236.571985)
			(xy 359.440734 -236.597952) (xy 359.440225 -236.623919) (xy 359.720135 -236.623919) (xy 359.720135 -236.571985)
			(xy 359.72826 -236.52069) (xy 359.744308 -236.471297) (xy 359.767886 -236.425023) (xy 359.798412 -236.383007)
			(xy 359.835135 -236.346284) (xy 359.877151 -236.315758) (xy 359.923425 -236.29218) (xy 359.972818 -236.276132)
			(xy 360.024113 -236.268007) (xy 360.076047 -236.268007) (xy 360.127342 -236.276132) (xy 360.176735 -236.29218)
			(xy 360.223009 -236.315758) (xy 360.265025 -236.346284) (xy 360.301748 -236.383007) (xy 360.332274 -236.425023)
			(xy 360.355852 -236.471297) (xy 360.3719 -236.52069) (xy 360.380025 -236.571985) (xy 360.380534 -236.597952)
			(xy 360.380025 -236.623919) (xy 360.659935 -236.623919) (xy 360.659935 -236.571985) (xy 360.66806 -236.52069)
			(xy 360.684108 -236.471297) (xy 360.707686 -236.425023) (xy 360.738212 -236.383007) (xy 360.774935 -236.346284)
			(xy 360.816951 -236.315758) (xy 360.863225 -236.29218) (xy 360.912618 -236.276132) (xy 360.963913 -236.268007)
			(xy 361.015847 -236.268007) (xy 361.067142 -236.276132) (xy 361.116535 -236.29218) (xy 361.162809 -236.315758)
			(xy 361.204825 -236.346284) (xy 361.241548 -236.383007) (xy 361.272074 -236.425023) (xy 361.295652 -236.471297)
			(xy 361.3117 -236.52069) (xy 361.319825 -236.571985) (xy 361.320334 -236.597952) (xy 361.319825 -236.623919)
			(xy 361.599989 -236.623919) (xy 361.599989 -236.571985) (xy 361.608114 -236.52069) (xy 361.624162 -236.471297)
			(xy 361.64774 -236.425023) (xy 361.678266 -236.383007) (xy 361.714989 -236.346284) (xy 361.757005 -236.315758)
			(xy 361.803279 -236.29218) (xy 361.852672 -236.276132) (xy 361.903967 -236.268007) (xy 361.955901 -236.268007)
			(xy 362.007196 -236.276132) (xy 362.056589 -236.29218) (xy 362.102863 -236.315758) (xy 362.144879 -236.346284)
			(xy 362.181602 -236.383007) (xy 362.212128 -236.425023) (xy 362.235706 -236.471297) (xy 362.251754 -236.52069)
			(xy 362.259879 -236.571985) (xy 362.260388 -236.597952) (xy 362.259879 -236.623919) (xy 362.251754 -236.675214)
			(xy 362.235706 -236.724607) (xy 362.212128 -236.770881) (xy 362.181602 -236.812897) (xy 362.144879 -236.84962)
			(xy 362.102863 -236.880146) (xy 362.056589 -236.903724) (xy 362.007196 -236.919772) (xy 361.955901 -236.927897)
			(xy 361.903967 -236.927897) (xy 361.852672 -236.919772) (xy 361.803279 -236.903724) (xy 361.757005 -236.880146)
			(xy 361.714989 -236.84962) (xy 361.678266 -236.812897) (xy 361.64774 -236.770881) (xy 361.624162 -236.724607)
			(xy 361.608114 -236.675214) (xy 361.599989 -236.623919) (xy 361.319825 -236.623919) (xy 361.3117 -236.675214)
			(xy 361.295652 -236.724607) (xy 361.272074 -236.770881) (xy 361.241548 -236.812897) (xy 361.204825 -236.84962)
			(xy 361.162809 -236.880146) (xy 361.116535 -236.903724) (xy 361.067142 -236.919772) (xy 361.015847 -236.927897)
			(xy 360.963913 -236.927897) (xy 360.912618 -236.919772) (xy 360.863225 -236.903724) (xy 360.816951 -236.880146)
			(xy 360.774935 -236.84962) (xy 360.738212 -236.812897) (xy 360.707686 -236.770881) (xy 360.684108 -236.724607)
			(xy 360.66806 -236.675214) (xy 360.659935 -236.623919) (xy 360.380025 -236.623919) (xy 360.3719 -236.675214)
			(xy 360.355852 -236.724607) (xy 360.332274 -236.770881) (xy 360.301748 -236.812897) (xy 360.265025 -236.84962)
			(xy 360.223009 -236.880146) (xy 360.176735 -236.903724) (xy 360.127342 -236.919772) (xy 360.076047 -236.927897)
			(xy 360.024113 -236.927897) (xy 359.972818 -236.919772) (xy 359.923425 -236.903724) (xy 359.877151 -236.880146)
			(xy 359.835135 -236.84962) (xy 359.798412 -236.812897) (xy 359.767886 -236.770881) (xy 359.744308 -236.724607)
			(xy 359.72826 -236.675214) (xy 359.720135 -236.623919) (xy 359.440225 -236.623919) (xy 359.4321 -236.675214)
			(xy 359.416052 -236.724607) (xy 359.392474 -236.770881) (xy 359.361948 -236.812897) (xy 359.325225 -236.84962)
			(xy 359.283209 -236.880146) (xy 359.236935 -236.903724) (xy 359.187542 -236.919772) (xy 359.136247 -236.927897)
			(xy 359.084313 -236.927897) (xy 359.033018 -236.919772) (xy 358.983625 -236.903724) (xy 358.937351 -236.880146)
			(xy 358.895335 -236.84962) (xy 358.858612 -236.812897) (xy 358.828086 -236.770881) (xy 358.804508 -236.724607)
			(xy 358.78846 -236.675214) (xy 358.780335 -236.623919) (xy 358.50067 -236.623919) (xy 358.500649 -236.624959)
			(xy 358.491867 -236.678256) (xy 358.474546 -236.729418) (xy 358.449144 -236.777088) (xy 358.416338 -236.819999)
			(xy 358.376997 -236.857011) (xy 358.354884 -236.872526) (xy 358.342724 -236.881298) (xy 358.323722 -236.904474)
			(xy 358.312271 -236.932169) (xy 358.309357 -236.961997) (xy 358.315231 -236.991385) (xy 358.329388 -237.0178)
			(xy 358.339644 -237.028736) (xy 358.44988 -237.138972) (xy 358.483154 -237.120938) (xy 358.507475 -237.108363)
			(xy 358.559253 -237.090573) (xy 358.613259 -237.081582) (xy 358.640634 -237.08106) (xy 358.666483 -237.081563)
			(xy 358.71755 -237.089619) (xy 358.766738 -237.10553) (xy 358.812849 -237.128907) (xy 358.854757 -237.15918)
			(xy 358.891439 -237.19561) (xy 358.921999 -237.237308) (xy 358.945694 -237.283256) (xy 358.954324 -237.307628)
			(xy 358.965754 -237.342426) (xy 359.255314 -237.342426) (xy 359.266744 -237.307628) (xy 359.275346 -237.283246)
			(xy 359.299044 -237.237297) (xy 359.32961 -237.1956) (xy 359.366296 -237.159172) (xy 359.408208 -237.128902)
			(xy 359.454322 -237.105528) (xy 359.503515 -237.089621) (xy 359.554584 -237.081569) (xy 359.606284 -237.081569)
			(xy 359.657353 -237.089621) (xy 359.706546 -237.105528) (xy 359.75266 -237.128902) (xy 359.794572 -237.159172)
			(xy 359.831258 -237.1956) (xy 359.861824 -237.237297) (xy 359.885522 -237.283246) (xy 359.894124 -237.307628)
			(xy 359.905554 -237.342426) (xy 360.195114 -237.342426) (xy 360.206544 -237.307628) (xy 360.215146 -237.283246)
			(xy 360.238844 -237.237297) (xy 360.26941 -237.1956) (xy 360.306096 -237.159172) (xy 360.348008 -237.128902)
			(xy 360.394122 -237.105528) (xy 360.443315 -237.089621) (xy 360.494384 -237.081569) (xy 360.546084 -237.081569)
			(xy 360.597153 -237.089621) (xy 360.646346 -237.105528) (xy 360.69246 -237.128902) (xy 360.734372 -237.159172)
			(xy 360.771058 -237.1956) (xy 360.801624 -237.237297) (xy 360.825322 -237.283246) (xy 360.833924 -237.307628)
			(xy 360.845354 -237.342426) (xy 361.134914 -237.342426) (xy 361.146344 -237.307628) (xy 361.154946 -237.283246)
			(xy 361.178644 -237.237297) (xy 361.20921 -237.1956) (xy 361.245896 -237.159172) (xy 361.287808 -237.128902)
			(xy 361.333922 -237.105528) (xy 361.383115 -237.089621) (xy 361.434184 -237.081569) (xy 361.485884 -237.081569)
			(xy 361.536953 -237.089621) (xy 361.586146 -237.105528) (xy 361.63226 -237.128902) (xy 361.674172 -237.159172)
			(xy 361.710858 -237.1956) (xy 361.741424 -237.237297) (xy 361.765122 -237.283246) (xy 361.773724 -237.307628)
			(xy 361.785154 -237.342426) (xy 362.859828 -237.342426) (xy 362.874968 -237.341868) (xy 362.903917 -237.332988)
			(xy 362.928993 -237.316014) (xy 362.947995 -237.292439) (xy 362.959254 -237.26433) (xy 362.961784 -237.234155)
			(xy 362.959142 -237.219236) (xy 362.955591 -237.201927) (xy 362.951775 -237.166799) (xy 362.951522 -237.149132)
			(xy 362.951947 -237.124577) (xy 362.95917 -237.076002) (xy 362.973506 -237.029032) (xy 362.994638 -236.984703)
			(xy 363.022102 -236.943991) (xy 363.03839 -236.925612) (xy 363.048197 -236.914122) (xy 363.061218 -236.886882)
			(xy 363.065694 -236.857024) (xy 363.061232 -236.827163) (xy 363.048224 -236.799917) (xy 363.03839 -236.788452)
			(xy 363.022136 -236.770047) (xy 362.994688 -236.729334) (xy 362.973561 -236.68501) (xy 362.959222 -236.638048)
			(xy 362.951985 -236.589483) (xy 362.951522 -236.564932) (xy 362.952031 -236.538965) (xy 362.960156 -236.48767)
			(xy 362.976204 -236.438277) (xy 362.999782 -236.392003) (xy 363.030308 -236.349987) (xy 363.067031 -236.313264)
			(xy 363.109047 -236.282738) (xy 363.155321 -236.25916) (xy 363.204714 -236.243112) (xy 363.256009 -236.234987)
			(xy 363.307943 -236.234987) (xy 363.359238 -236.243112) (xy 363.408631 -236.25916) (xy 363.444951 -236.277666)
			(xy 368.586279 -236.277666) (xy 368.586279 -236.225734) (xy 368.594403 -236.174443) (xy 368.61045 -236.125053)
			(xy 368.634027 -236.078782) (xy 368.664551 -236.036769) (xy 368.701272 -236.000049) (xy 368.743286 -235.969525)
			(xy 368.789557 -235.945949) (xy 368.838947 -235.929902) (xy 368.890238 -235.921778) (xy 368.916204 -235.921296)
			(xy 368.941974 -235.921745) (xy 368.992892 -235.929719) (xy 369.041953 -235.945504) (xy 369.087968 -235.968717)
			(xy 369.12982 -235.998795) (xy 369.166492 -236.035008) (xy 369.197096 -236.076477) (xy 369.220888 -236.122195)
			(xy 369.23729 -236.171054) (xy 369.242086 -236.196378) (xy 369.244862 -236.210088) (xy 369.256877 -236.235337)
			(xy 369.275298 -236.256375) (xy 369.29874 -236.27162) (xy 369.325441 -236.279926) (xy 369.353393 -236.280668)
			(xy 369.367054 -236.277658) (xy 369.387099 -236.272893) (xy 369.427986 -236.267797) (xy 369.448588 -236.267498)
			(xy 369.474554 -236.268076) (xy 369.525847 -236.276198) (xy 369.575238 -236.292245) (xy 369.621511 -236.31582)
			(xy 369.663526 -236.346344) (xy 369.700248 -236.383065) (xy 369.730774 -236.425079) (xy 369.754351 -236.471351)
			(xy 369.770399 -236.520741) (xy 369.778523 -236.572034) (xy 369.778523 -236.623919) (xy 370.057935 -236.623919)
			(xy 370.057935 -236.571985) (xy 370.06606 -236.52069) (xy 370.082108 -236.471297) (xy 370.105686 -236.425023)
			(xy 370.136212 -236.383007) (xy 370.172935 -236.346284) (xy 370.214951 -236.315758) (xy 370.261225 -236.29218)
			(xy 370.310618 -236.276132) (xy 370.361913 -236.268007) (xy 370.413847 -236.268007) (xy 370.465142 -236.276132)
			(xy 370.514535 -236.29218) (xy 370.560809 -236.315758) (xy 370.602825 -236.346284) (xy 370.639548 -236.383007)
			(xy 370.670074 -236.425023) (xy 370.693652 -236.471297) (xy 370.7097 -236.52069) (xy 370.717825 -236.571985)
			(xy 370.718334 -236.597952) (xy 370.717825 -236.623919) (xy 370.997735 -236.623919) (xy 370.997735 -236.571985)
			(xy 371.00586 -236.52069) (xy 371.021908 -236.471297) (xy 371.045486 -236.425023) (xy 371.076012 -236.383007)
			(xy 371.112735 -236.346284) (xy 371.154751 -236.315758) (xy 371.201025 -236.29218) (xy 371.250418 -236.276132)
			(xy 371.301713 -236.268007) (xy 371.353647 -236.268007) (xy 371.404942 -236.276132) (xy 371.454335 -236.29218)
			(xy 371.500609 -236.315758) (xy 371.542625 -236.346284) (xy 371.579348 -236.383007) (xy 371.609874 -236.425023)
			(xy 371.633452 -236.471297) (xy 371.6495 -236.52069) (xy 371.657625 -236.571985) (xy 371.658134 -236.597952)
			(xy 371.657625 -236.623919) (xy 371.937535 -236.623919) (xy 371.937535 -236.571985) (xy 371.94566 -236.52069)
			(xy 371.961708 -236.471297) (xy 371.985286 -236.425023) (xy 372.015812 -236.383007) (xy 372.052535 -236.346284)
			(xy 372.094551 -236.315758) (xy 372.140825 -236.29218) (xy 372.190218 -236.276132) (xy 372.241513 -236.268007)
			(xy 372.293447 -236.268007) (xy 372.344742 -236.276132) (xy 372.394135 -236.29218) (xy 372.440409 -236.315758)
			(xy 372.482425 -236.346284) (xy 372.519148 -236.383007) (xy 372.549674 -236.425023) (xy 372.573252 -236.471297)
			(xy 372.5893 -236.52069) (xy 372.597425 -236.571985) (xy 372.597934 -236.597952) (xy 372.597425 -236.623919)
			(xy 372.877335 -236.623919) (xy 372.877335 -236.571985) (xy 372.88546 -236.52069) (xy 372.901508 -236.471297)
			(xy 372.925086 -236.425023) (xy 372.955612 -236.383007) (xy 372.992335 -236.346284) (xy 373.034351 -236.315758)
			(xy 373.080625 -236.29218) (xy 373.130018 -236.276132) (xy 373.181313 -236.268007) (xy 373.233247 -236.268007)
			(xy 373.284542 -236.276132) (xy 373.333935 -236.29218) (xy 373.380209 -236.315758) (xy 373.422225 -236.346284)
			(xy 373.458948 -236.383007) (xy 373.489474 -236.425023) (xy 373.513052 -236.471297) (xy 373.5291 -236.52069)
			(xy 373.537225 -236.571985) (xy 373.537734 -236.597952) (xy 373.537225 -236.623919) (xy 373.817135 -236.623919)
			(xy 373.817135 -236.571985) (xy 373.82526 -236.52069) (xy 373.841308 -236.471297) (xy 373.864886 -236.425023)
			(xy 373.895412 -236.383007) (xy 373.932135 -236.346284) (xy 373.974151 -236.315758) (xy 374.020425 -236.29218)
			(xy 374.069818 -236.276132) (xy 374.121113 -236.268007) (xy 374.173047 -236.268007) (xy 374.224342 -236.276132)
			(xy 374.273735 -236.29218) (xy 374.320009 -236.315758) (xy 374.362025 -236.346284) (xy 374.398748 -236.383007)
			(xy 374.429274 -236.425023) (xy 374.452852 -236.471297) (xy 374.4689 -236.52069) (xy 374.477025 -236.571985)
			(xy 374.477534 -236.597952) (xy 374.477025 -236.623919) (xy 374.756935 -236.623919) (xy 374.756935 -236.571985)
			(xy 374.76506 -236.52069) (xy 374.781108 -236.471297) (xy 374.804686 -236.425023) (xy 374.835212 -236.383007)
			(xy 374.871935 -236.346284) (xy 374.913951 -236.315758) (xy 374.960225 -236.29218) (xy 375.009618 -236.276132)
			(xy 375.060913 -236.268007) (xy 375.112847 -236.268007) (xy 375.164142 -236.276132) (xy 375.213535 -236.29218)
			(xy 375.259809 -236.315758) (xy 375.301825 -236.346284) (xy 375.338548 -236.383007) (xy 375.369074 -236.425023)
			(xy 375.392652 -236.471297) (xy 375.4087 -236.52069) (xy 375.416825 -236.571985) (xy 375.417334 -236.597952)
			(xy 375.416825 -236.623919) (xy 375.4087 -236.675214) (xy 375.392652 -236.724607) (xy 375.369074 -236.770881)
			(xy 375.338548 -236.812897) (xy 375.301825 -236.84962) (xy 375.259809 -236.880146) (xy 375.213535 -236.903724)
			(xy 375.164142 -236.919772) (xy 375.112847 -236.927897) (xy 375.060913 -236.927897) (xy 375.009618 -236.919772)
			(xy 374.960225 -236.903724) (xy 374.913951 -236.880146) (xy 374.871935 -236.84962) (xy 374.835212 -236.812897)
			(xy 374.804686 -236.770881) (xy 374.781108 -236.724607) (xy 374.76506 -236.675214) (xy 374.756935 -236.623919)
			(xy 374.477025 -236.623919) (xy 374.4689 -236.675214) (xy 374.452852 -236.724607) (xy 374.429274 -236.770881)
			(xy 374.398748 -236.812897) (xy 374.362025 -236.84962) (xy 374.320009 -236.880146) (xy 374.273735 -236.903724)
			(xy 374.224342 -236.919772) (xy 374.173047 -236.927897) (xy 374.121113 -236.927897) (xy 374.069818 -236.919772)
			(xy 374.020425 -236.903724) (xy 373.974151 -236.880146) (xy 373.932135 -236.84962) (xy 373.895412 -236.812897)
			(xy 373.864886 -236.770881) (xy 373.841308 -236.724607) (xy 373.82526 -236.675214) (xy 373.817135 -236.623919)
			(xy 373.537225 -236.623919) (xy 373.5291 -236.675214) (xy 373.513052 -236.724607) (xy 373.489474 -236.770881)
			(xy 373.458948 -236.812897) (xy 373.422225 -236.84962) (xy 373.380209 -236.880146) (xy 373.333935 -236.903724)
			(xy 373.284542 -236.919772) (xy 373.233247 -236.927897) (xy 373.181313 -236.927897) (xy 373.130018 -236.919772)
			(xy 373.080625 -236.903724) (xy 373.034351 -236.880146) (xy 372.992335 -236.84962) (xy 372.955612 -236.812897)
			(xy 372.925086 -236.770881) (xy 372.901508 -236.724607) (xy 372.88546 -236.675214) (xy 372.877335 -236.623919)
			(xy 372.597425 -236.623919) (xy 372.5893 -236.675214) (xy 372.573252 -236.724607) (xy 372.549674 -236.770881)
			(xy 372.519148 -236.812897) (xy 372.482425 -236.84962) (xy 372.440409 -236.880146) (xy 372.394135 -236.903724)
			(xy 372.344742 -236.919772) (xy 372.293447 -236.927897) (xy 372.241513 -236.927897) (xy 372.190218 -236.919772)
			(xy 372.140825 -236.903724) (xy 372.094551 -236.880146) (xy 372.052535 -236.84962) (xy 372.015812 -236.812897)
			(xy 371.985286 -236.770881) (xy 371.961708 -236.724607) (xy 371.94566 -236.675214) (xy 371.937535 -236.623919)
			(xy 371.657625 -236.623919) (xy 371.6495 -236.675214) (xy 371.633452 -236.724607) (xy 371.609874 -236.770881)
			(xy 371.579348 -236.812897) (xy 371.542625 -236.84962) (xy 371.500609 -236.880146) (xy 371.454335 -236.903724)
			(xy 371.404942 -236.919772) (xy 371.353647 -236.927897) (xy 371.301713 -236.927897) (xy 371.250418 -236.919772)
			(xy 371.201025 -236.903724) (xy 371.154751 -236.880146) (xy 371.112735 -236.84962) (xy 371.076012 -236.812897)
			(xy 371.045486 -236.770881) (xy 371.021908 -236.724607) (xy 371.00586 -236.675214) (xy 370.997735 -236.623919)
			(xy 370.717825 -236.623919) (xy 370.7097 -236.675214) (xy 370.693652 -236.724607) (xy 370.670074 -236.770881)
			(xy 370.639548 -236.812897) (xy 370.602825 -236.84962) (xy 370.560809 -236.880146) (xy 370.514535 -236.903724)
			(xy 370.465142 -236.919772) (xy 370.413847 -236.927897) (xy 370.361913 -236.927897) (xy 370.310618 -236.919772)
			(xy 370.261225 -236.903724) (xy 370.214951 -236.880146) (xy 370.172935 -236.84962) (xy 370.136212 -236.812897)
			(xy 370.105686 -236.770881) (xy 370.082108 -236.724607) (xy 370.06606 -236.675214) (xy 370.057935 -236.623919)
			(xy 369.778523 -236.623919) (xy 369.778523 -236.623966) (xy 369.770399 -236.675259) (xy 369.754351 -236.724649)
			(xy 369.730774 -236.770921) (xy 369.700248 -236.812935) (xy 369.663526 -236.849656) (xy 369.621511 -236.88018)
			(xy 369.575238 -236.903755) (xy 369.525847 -236.919802) (xy 369.474554 -236.927924) (xy 369.448588 -236.928406)
			(xy 369.422818 -236.927963) (xy 369.3719 -236.919988) (xy 369.322838 -236.904201) (xy 369.276823 -236.880987)
			(xy 369.234972 -236.850909) (xy 369.1983 -236.814695) (xy 369.167696 -236.773226) (xy 369.143904 -236.727507)
			(xy 369.127502 -236.678648) (xy 369.122706 -236.653324) (xy 369.119938 -236.639612) (xy 369.107922 -236.614361)
			(xy 369.0895 -236.593323) (xy 369.066056 -236.578078) (xy 369.039353 -236.569773) (xy 369.011399 -236.569032)
			(xy 368.997738 -236.572044) (xy 368.977693 -236.576811) (xy 368.936806 -236.581905) (xy 368.916204 -236.582204)
			(xy 368.890238 -236.581622) (xy 368.838947 -236.573498) (xy 368.789557 -236.557451) (xy 368.743286 -236.533875)
			(xy 368.701272 -236.503351) (xy 368.664551 -236.466631) (xy 368.634027 -236.424618) (xy 368.61045 -236.378347)
			(xy 368.594403 -236.328957) (xy 368.586279 -236.277666) (xy 363.444951 -236.277666) (xy 363.454905 -236.282738)
			(xy 363.496921 -236.313264) (xy 363.533644 -236.349987) (xy 363.56417 -236.392003) (xy 363.587748 -236.438277)
			(xy 363.603796 -236.48767) (xy 363.611921 -236.538965) (xy 363.61243 -236.564932) (xy 363.612 -236.589485)
			(xy 363.604768 -236.638054) (xy 363.590424 -236.685017) (xy 363.569283 -236.729338) (xy 363.541812 -236.77004)
			(xy 363.525562 -236.788452) (xy 363.51576 -236.799939) (xy 363.502751 -236.827174) (xy 363.498288 -236.857024)
			(xy 363.502764 -236.886872) (xy 363.515787 -236.9141) (xy 363.525562 -236.925612) (xy 363.54182 -236.944016)
			(xy 363.569277 -236.984726) (xy 363.590411 -237.02905) (xy 363.604758 -237.076012) (xy 363.612001 -237.12458)
			(xy 363.61243 -237.149132) (xy 363.612174 -237.166799) (xy 363.608359 -237.201927) (xy 363.60481 -237.219236)
			(xy 363.602138 -237.234151) (xy 363.604667 -237.264329) (xy 363.615931 -237.292441) (xy 363.634941 -237.316016)
			(xy 363.660025 -237.332984) (xy 363.688982 -237.341854) (xy 363.704124 -237.342426) (xy 368.593116 -237.342426)
			(xy 368.605054 -237.308644) (xy 368.614038 -237.284931) (xy 368.638229 -237.240366) (xy 368.668948 -237.200022)
			(xy 368.705472 -237.164847) (xy 368.746942 -237.135668) (xy 368.792386 -237.11317) (xy 368.840733 -237.097882)
			(xy 368.89085 -237.090163) (xy 368.916204 -237.089696) (xy 368.942172 -237.090206) (xy 368.99347 -237.09833)
			(xy 369.042865 -237.114378) (xy 369.089142 -237.137956) (xy 369.131162 -237.168481) (xy 369.167889 -237.205203)
			(xy 369.19842 -237.247219) (xy 369.222004 -237.293492) (xy 369.238059 -237.342885) (xy 369.246191 -237.394182)
			(xy 369.246658 -237.42015) (xy 369.246385 -237.437481) (xy 369.588289 -237.437481) (xy 369.588289 -237.385547)
			(xy 369.596414 -237.334252) (xy 369.612462 -237.284859) (xy 369.63604 -237.238585) (xy 369.666566 -237.196569)
			(xy 369.703289 -237.159846) (xy 369.745305 -237.12932) (xy 369.791579 -237.105742) (xy 369.840972 -237.089694)
			(xy 369.892267 -237.081569) (xy 369.944201 -237.081569) (xy 369.995496 -237.089694) (xy 370.044889 -237.105742)
			(xy 370.091163 -237.12932) (xy 370.133179 -237.159846) (xy 370.169902 -237.196569) (xy 370.200428 -237.238585)
			(xy 370.224006 -237.284859) (xy 370.240054 -237.334252) (xy 370.248179 -237.385547) (xy 370.248688 -237.411514)
			(xy 370.248179 -237.437481) (xy 370.528089 -237.437481) (xy 370.528089 -237.385547) (xy 370.536214 -237.334252)
			(xy 370.552262 -237.284859) (xy 370.57584 -237.238585) (xy 370.606366 -237.196569) (xy 370.643089 -237.159846)
			(xy 370.685105 -237.12932) (xy 370.731379 -237.105742) (xy 370.780772 -237.089694) (xy 370.832067 -237.081569)
			(xy 370.884001 -237.081569) (xy 370.935296 -237.089694) (xy 370.984689 -237.105742) (xy 371.030963 -237.12932)
			(xy 371.072979 -237.159846) (xy 371.109702 -237.196569) (xy 371.140228 -237.238585) (xy 371.163806 -237.284859)
			(xy 371.179854 -237.334252) (xy 371.187979 -237.385547) (xy 371.188488 -237.411514) (xy 371.187979 -237.437481)
			(xy 371.467889 -237.437481) (xy 371.467889 -237.385547) (xy 371.476014 -237.334252) (xy 371.492062 -237.284859)
			(xy 371.51564 -237.238585) (xy 371.546166 -237.196569) (xy 371.582889 -237.159846) (xy 371.624905 -237.12932)
			(xy 371.671179 -237.105742) (xy 371.720572 -237.089694) (xy 371.771867 -237.081569) (xy 371.823801 -237.081569)
			(xy 371.875096 -237.089694) (xy 371.924489 -237.105742) (xy 371.970763 -237.12932) (xy 372.012779 -237.159846)
			(xy 372.049502 -237.196569) (xy 372.080028 -237.238585) (xy 372.103606 -237.284859) (xy 372.119654 -237.334252)
			(xy 372.127779 -237.385547) (xy 372.128288 -237.411514) (xy 372.127779 -237.437481) (xy 372.407689 -237.437481)
			(xy 372.407689 -237.385547) (xy 372.415814 -237.334252) (xy 372.431862 -237.284859) (xy 372.45544 -237.238585)
			(xy 372.485966 -237.196569) (xy 372.522689 -237.159846) (xy 372.564705 -237.12932) (xy 372.610979 -237.105742)
			(xy 372.660372 -237.089694) (xy 372.711667 -237.081569) (xy 372.763601 -237.081569) (xy 372.814896 -237.089694)
			(xy 372.864289 -237.105742) (xy 372.910563 -237.12932) (xy 372.952579 -237.159846) (xy 372.989302 -237.196569)
			(xy 373.019828 -237.238585) (xy 373.043406 -237.284859) (xy 373.059454 -237.334252) (xy 373.067579 -237.385547)
			(xy 373.068088 -237.411514) (xy 373.067579 -237.437481) (xy 373.347489 -237.437481) (xy 373.347489 -237.385547)
			(xy 373.355614 -237.334252) (xy 373.371662 -237.284859) (xy 373.39524 -237.238585) (xy 373.425766 -237.196569)
			(xy 373.462489 -237.159846) (xy 373.504505 -237.12932) (xy 373.550779 -237.105742) (xy 373.600172 -237.089694)
			(xy 373.651467 -237.081569) (xy 373.703401 -237.081569) (xy 373.754696 -237.089694) (xy 373.804089 -237.105742)
			(xy 373.850363 -237.12932) (xy 373.892379 -237.159846) (xy 373.929102 -237.196569) (xy 373.959628 -237.238585)
			(xy 373.983206 -237.284859) (xy 373.999254 -237.334252) (xy 374.007379 -237.385547) (xy 374.007888 -237.411514)
			(xy 374.007379 -237.437481) (xy 374.287289 -237.437481) (xy 374.287289 -237.385547) (xy 374.295414 -237.334252)
			(xy 374.311462 -237.284859) (xy 374.33504 -237.238585) (xy 374.365566 -237.196569) (xy 374.402289 -237.159846)
			(xy 374.444305 -237.12932) (xy 374.490579 -237.105742) (xy 374.539972 -237.089694) (xy 374.591267 -237.081569)
			(xy 374.643201 -237.081569) (xy 374.694496 -237.089694) (xy 374.743889 -237.105742) (xy 374.790163 -237.12932)
			(xy 374.832179 -237.159846) (xy 374.868902 -237.196569) (xy 374.899428 -237.238585) (xy 374.923006 -237.284859)
			(xy 374.939054 -237.334252) (xy 374.947179 -237.385547) (xy 374.947688 -237.411514) (xy 374.947179 -237.437481)
			(xy 375.227089 -237.437481) (xy 375.227089 -237.385547) (xy 375.235214 -237.334252) (xy 375.251262 -237.284859)
			(xy 375.27484 -237.238585) (xy 375.305366 -237.196569) (xy 375.342089 -237.159846) (xy 375.384105 -237.12932)
			(xy 375.430379 -237.105742) (xy 375.479772 -237.089694) (xy 375.531067 -237.081569) (xy 375.583001 -237.081569)
			(xy 375.634296 -237.089694) (xy 375.683689 -237.105742) (xy 375.729963 -237.12932) (xy 375.771979 -237.159846)
			(xy 375.808702 -237.196569) (xy 375.839228 -237.238585) (xy 375.862806 -237.284859) (xy 375.878854 -237.334252)
			(xy 375.886979 -237.385547) (xy 375.887488 -237.411514) (xy 375.886979 -237.437481) (xy 375.878854 -237.488776)
			(xy 375.862806 -237.538169) (xy 375.839228 -237.584443) (xy 375.808702 -237.626459) (xy 375.771979 -237.663182)
			(xy 375.729963 -237.693708) (xy 375.683689 -237.717286) (xy 375.634296 -237.733334) (xy 375.583001 -237.741459)
			(xy 375.531067 -237.741459) (xy 375.479772 -237.733334) (xy 375.430379 -237.717286) (xy 375.384105 -237.693708)
			(xy 375.342089 -237.663182) (xy 375.305366 -237.626459) (xy 375.27484 -237.584443) (xy 375.251262 -237.538169)
			(xy 375.235214 -237.488776) (xy 375.227089 -237.437481) (xy 374.947179 -237.437481) (xy 374.939054 -237.488776)
			(xy 374.923006 -237.538169) (xy 374.899428 -237.584443) (xy 374.868902 -237.626459) (xy 374.832179 -237.663182)
			(xy 374.790163 -237.693708) (xy 374.743889 -237.717286) (xy 374.694496 -237.733334) (xy 374.643201 -237.741459)
			(xy 374.591267 -237.741459) (xy 374.539972 -237.733334) (xy 374.490579 -237.717286) (xy 374.444305 -237.693708)
			(xy 374.402289 -237.663182) (xy 374.365566 -237.626459) (xy 374.33504 -237.584443) (xy 374.311462 -237.538169)
			(xy 374.295414 -237.488776) (xy 374.287289 -237.437481) (xy 374.007379 -237.437481) (xy 373.999254 -237.488776)
			(xy 373.983206 -237.538169) (xy 373.959628 -237.584443) (xy 373.929102 -237.626459) (xy 373.892379 -237.663182)
			(xy 373.850363 -237.693708) (xy 373.804089 -237.717286) (xy 373.754696 -237.733334) (xy 373.703401 -237.741459)
			(xy 373.651467 -237.741459) (xy 373.600172 -237.733334) (xy 373.550779 -237.717286) (xy 373.504505 -237.693708)
			(xy 373.462489 -237.663182) (xy 373.425766 -237.626459) (xy 373.39524 -237.584443) (xy 373.371662 -237.538169)
			(xy 373.355614 -237.488776) (xy 373.347489 -237.437481) (xy 373.067579 -237.437481) (xy 373.059454 -237.488776)
			(xy 373.043406 -237.538169) (xy 373.019828 -237.584443) (xy 372.989302 -237.626459) (xy 372.952579 -237.663182)
			(xy 372.910563 -237.693708) (xy 372.864289 -237.717286) (xy 372.814896 -237.733334) (xy 372.763601 -237.741459)
			(xy 372.711667 -237.741459) (xy 372.660372 -237.733334) (xy 372.610979 -237.717286) (xy 372.564705 -237.693708)
			(xy 372.522689 -237.663182) (xy 372.485966 -237.626459) (xy 372.45544 -237.584443) (xy 372.431862 -237.538169)
			(xy 372.415814 -237.488776) (xy 372.407689 -237.437481) (xy 372.127779 -237.437481) (xy 372.119654 -237.488776)
			(xy 372.103606 -237.538169) (xy 372.080028 -237.584443) (xy 372.049502 -237.626459) (xy 372.012779 -237.663182)
			(xy 371.970763 -237.693708) (xy 371.924489 -237.717286) (xy 371.875096 -237.733334) (xy 371.823801 -237.741459)
			(xy 371.771867 -237.741459) (xy 371.720572 -237.733334) (xy 371.671179 -237.717286) (xy 371.624905 -237.693708)
			(xy 371.582889 -237.663182) (xy 371.546166 -237.626459) (xy 371.51564 -237.584443) (xy 371.492062 -237.538169)
			(xy 371.476014 -237.488776) (xy 371.467889 -237.437481) (xy 371.187979 -237.437481) (xy 371.179854 -237.488776)
			(xy 371.163806 -237.538169) (xy 371.140228 -237.584443) (xy 371.109702 -237.626459) (xy 371.072979 -237.663182)
			(xy 371.030963 -237.693708) (xy 370.984689 -237.717286) (xy 370.935296 -237.733334) (xy 370.884001 -237.741459)
			(xy 370.832067 -237.741459) (xy 370.780772 -237.733334) (xy 370.731379 -237.717286) (xy 370.685105 -237.693708)
			(xy 370.643089 -237.663182) (xy 370.606366 -237.626459) (xy 370.57584 -237.584443) (xy 370.552262 -237.538169)
			(xy 370.536214 -237.488776) (xy 370.528089 -237.437481) (xy 370.248179 -237.437481) (xy 370.240054 -237.488776)
			(xy 370.224006 -237.538169) (xy 370.200428 -237.584443) (xy 370.169902 -237.626459) (xy 370.133179 -237.663182)
			(xy 370.091163 -237.693708) (xy 370.044889 -237.717286) (xy 369.995496 -237.733334) (xy 369.944201 -237.741459)
			(xy 369.892267 -237.741459) (xy 369.840972 -237.733334) (xy 369.791579 -237.717286) (xy 369.745305 -237.693708)
			(xy 369.703289 -237.663182) (xy 369.666566 -237.626459) (xy 369.63604 -237.584443) (xy 369.612462 -237.538169)
			(xy 369.596414 -237.488776) (xy 369.588289 -237.437481) (xy 369.246385 -237.437481) (xy 369.246315 -237.441886)
			(xy 369.240617 -237.484983) (xy 369.229312 -237.526958) (xy 369.221258 -237.54715) (xy 369.208304 -237.578646)
			(xy 369.386104 -237.756446) (xy 369.386104 -237.795308) (xy 369.386633 -237.810359) (xy 369.395387 -237.839159)
			(xy 369.412161 -237.864153) (xy 369.435496 -237.883168) (xy 369.463362 -237.894549) (xy 369.478306 -237.8964)
			(xy 369.503905 -237.899243) (xy 369.553844 -237.911846) (xy 369.601223 -237.932042) (xy 369.644898 -237.959341)
			(xy 369.68381 -237.993083) (xy 369.717018 -238.032452) (xy 369.743719 -238.076494) (xy 369.763267 -238.124145)
			(xy 369.775188 -238.17425) (xy 369.779194 -238.225599) (xy 369.777169 -238.251551) (xy 370.057935 -238.251551)
			(xy 370.057935 -238.199617) (xy 370.06606 -238.148322) (xy 370.082108 -238.098929) (xy 370.105686 -238.052655)
			(xy 370.136212 -238.010639) (xy 370.172935 -237.973916) (xy 370.214951 -237.94339) (xy 370.261225 -237.919812)
			(xy 370.310618 -237.903764) (xy 370.361913 -237.895639) (xy 370.413847 -237.895639) (xy 370.465142 -237.903764)
			(xy 370.514535 -237.919812) (xy 370.560809 -237.94339) (xy 370.602825 -237.973916) (xy 370.639548 -238.010639)
			(xy 370.670074 -238.052655) (xy 370.693652 -238.098929) (xy 370.7097 -238.148322) (xy 370.717825 -238.199617)
			(xy 370.718334 -238.225584) (xy 370.717825 -238.251551) (xy 370.997735 -238.251551) (xy 370.997735 -238.199617)
			(xy 371.00586 -238.148322) (xy 371.021908 -238.098929) (xy 371.045486 -238.052655) (xy 371.076012 -238.010639)
			(xy 371.112735 -237.973916) (xy 371.154751 -237.94339) (xy 371.201025 -237.919812) (xy 371.250418 -237.903764)
			(xy 371.301713 -237.895639) (xy 371.353647 -237.895639) (xy 371.404942 -237.903764) (xy 371.454335 -237.919812)
			(xy 371.500609 -237.94339) (xy 371.542625 -237.973916) (xy 371.579348 -238.010639) (xy 371.609874 -238.052655)
			(xy 371.633452 -238.098929) (xy 371.6495 -238.148322) (xy 371.657625 -238.199617) (xy 371.658134 -238.225584)
			(xy 371.657625 -238.251551) (xy 371.937535 -238.251551) (xy 371.937535 -238.199617) (xy 371.94566 -238.148322)
			(xy 371.961708 -238.098929) (xy 371.985286 -238.052655) (xy 372.015812 -238.010639) (xy 372.052535 -237.973916)
			(xy 372.094551 -237.94339) (xy 372.140825 -237.919812) (xy 372.190218 -237.903764) (xy 372.241513 -237.895639)
			(xy 372.293447 -237.895639) (xy 372.344742 -237.903764) (xy 372.394135 -237.919812) (xy 372.440409 -237.94339)
			(xy 372.482425 -237.973916) (xy 372.519148 -238.010639) (xy 372.549674 -238.052655) (xy 372.573252 -238.098929)
			(xy 372.5893 -238.148322) (xy 372.597425 -238.199617) (xy 372.597934 -238.225584) (xy 372.597425 -238.251551)
			(xy 372.877335 -238.251551) (xy 372.877335 -238.199617) (xy 372.88546 -238.148322) (xy 372.901508 -238.098929)
			(xy 372.925086 -238.052655) (xy 372.955612 -238.010639) (xy 372.992335 -237.973916) (xy 373.034351 -237.94339)
			(xy 373.080625 -237.919812) (xy 373.130018 -237.903764) (xy 373.181313 -237.895639) (xy 373.233247 -237.895639)
			(xy 373.284542 -237.903764) (xy 373.333935 -237.919812) (xy 373.380209 -237.94339) (xy 373.422225 -237.973916)
			(xy 373.458948 -238.010639) (xy 373.489474 -238.052655) (xy 373.513052 -238.098929) (xy 373.5291 -238.148322)
			(xy 373.537225 -238.199617) (xy 373.537734 -238.225584) (xy 373.537225 -238.251551) (xy 373.817389 -238.251551)
			(xy 373.817389 -238.199617) (xy 373.825514 -238.148322) (xy 373.841562 -238.098929) (xy 373.86514 -238.052655)
			(xy 373.895666 -238.010639) (xy 373.932389 -237.973916) (xy 373.974405 -237.94339) (xy 374.020679 -237.919812)
			(xy 374.070072 -237.903764) (xy 374.121367 -237.895639) (xy 374.173301 -237.895639) (xy 374.224596 -237.903764)
			(xy 374.273989 -237.919812) (xy 374.320263 -237.94339) (xy 374.362279 -237.973916) (xy 374.399002 -238.010639)
			(xy 374.429528 -238.052655) (xy 374.453106 -238.098929) (xy 374.469154 -238.148322) (xy 374.477279 -238.199617)
			(xy 374.477788 -238.225584) (xy 374.477279 -238.251551) (xy 374.756935 -238.251551) (xy 374.756935 -238.199617)
			(xy 374.76506 -238.148322) (xy 374.781108 -238.098929) (xy 374.804686 -238.052655) (xy 374.835212 -238.010639)
			(xy 374.871935 -237.973916) (xy 374.913951 -237.94339) (xy 374.960225 -237.919812) (xy 375.009618 -237.903764)
			(xy 375.060913 -237.895639) (xy 375.112847 -237.895639) (xy 375.164142 -237.903764) (xy 375.213535 -237.919812)
			(xy 375.259809 -237.94339) (xy 375.301825 -237.973916) (xy 375.338548 -238.010639) (xy 375.369074 -238.052655)
			(xy 375.392652 -238.098929) (xy 375.4087 -238.148322) (xy 375.416825 -238.199617) (xy 375.417334 -238.225584)
			(xy 375.416825 -238.251551) (xy 375.4087 -238.302846) (xy 375.392652 -238.352239) (xy 375.369074 -238.398513)
			(xy 375.338548 -238.440529) (xy 375.301825 -238.477252) (xy 375.259809 -238.507778) (xy 375.213535 -238.531356)
			(xy 375.164142 -238.547404) (xy 375.112847 -238.555529) (xy 375.060913 -238.555529) (xy 375.009618 -238.547404)
			(xy 374.960225 -238.531356) (xy 374.913951 -238.507778) (xy 374.871935 -238.477252) (xy 374.835212 -238.440529)
			(xy 374.804686 -238.398513) (xy 374.781108 -238.352239) (xy 374.76506 -238.302846) (xy 374.756935 -238.251551)
			(xy 374.477279 -238.251551) (xy 374.469154 -238.302846) (xy 374.453106 -238.352239) (xy 374.429528 -238.398513)
			(xy 374.399002 -238.440529) (xy 374.362279 -238.477252) (xy 374.320263 -238.507778) (xy 374.273989 -238.531356)
			(xy 374.224596 -238.547404) (xy 374.173301 -238.555529) (xy 374.121367 -238.555529) (xy 374.070072 -238.547404)
			(xy 374.020679 -238.531356) (xy 373.974405 -238.507778) (xy 373.932389 -238.477252) (xy 373.895666 -238.440529)
			(xy 373.86514 -238.398513) (xy 373.841562 -238.352239) (xy 373.825514 -238.302846) (xy 373.817389 -238.251551)
			(xy 373.537225 -238.251551) (xy 373.5291 -238.302846) (xy 373.513052 -238.352239) (xy 373.489474 -238.398513)
			(xy 373.458948 -238.440529) (xy 373.422225 -238.477252) (xy 373.380209 -238.507778) (xy 373.333935 -238.531356)
			(xy 373.284542 -238.547404) (xy 373.233247 -238.555529) (xy 373.181313 -238.555529) (xy 373.130018 -238.547404)
			(xy 373.080625 -238.531356) (xy 373.034351 -238.507778) (xy 372.992335 -238.477252) (xy 372.955612 -238.440529)
			(xy 372.925086 -238.398513) (xy 372.901508 -238.352239) (xy 372.88546 -238.302846) (xy 372.877335 -238.251551)
			(xy 372.597425 -238.251551) (xy 372.5893 -238.302846) (xy 372.573252 -238.352239) (xy 372.549674 -238.398513)
			(xy 372.519148 -238.440529) (xy 372.482425 -238.477252) (xy 372.440409 -238.507778) (xy 372.394135 -238.531356)
			(xy 372.344742 -238.547404) (xy 372.293447 -238.555529) (xy 372.241513 -238.555529) (xy 372.190218 -238.547404)
			(xy 372.140825 -238.531356) (xy 372.094551 -238.507778) (xy 372.052535 -238.477252) (xy 372.015812 -238.440529)
			(xy 371.985286 -238.398513) (xy 371.961708 -238.352239) (xy 371.94566 -238.302846) (xy 371.937535 -238.251551)
			(xy 371.657625 -238.251551) (xy 371.6495 -238.302846) (xy 371.633452 -238.352239) (xy 371.609874 -238.398513)
			(xy 371.579348 -238.440529) (xy 371.542625 -238.477252) (xy 371.500609 -238.507778) (xy 371.454335 -238.531356)
			(xy 371.404942 -238.547404) (xy 371.353647 -238.555529) (xy 371.301713 -238.555529) (xy 371.250418 -238.547404)
			(xy 371.201025 -238.531356) (xy 371.154751 -238.507778) (xy 371.112735 -238.477252) (xy 371.076012 -238.440529)
			(xy 371.045486 -238.398513) (xy 371.021908 -238.352239) (xy 371.00586 -238.302846) (xy 370.997735 -238.251551)
			(xy 370.717825 -238.251551) (xy 370.7097 -238.302846) (xy 370.693652 -238.352239) (xy 370.670074 -238.398513)
			(xy 370.639548 -238.440529) (xy 370.602825 -238.477252) (xy 370.560809 -238.507778) (xy 370.514535 -238.531356)
			(xy 370.465142 -238.547404) (xy 370.413847 -238.555529) (xy 370.361913 -238.555529) (xy 370.310618 -238.547404)
			(xy 370.261225 -238.531356) (xy 370.214951 -238.507778) (xy 370.172935 -238.477252) (xy 370.136212 -238.440529)
			(xy 370.105686 -238.398513) (xy 370.082108 -238.352239) (xy 370.06606 -238.302846) (xy 370.057935 -238.251551)
			(xy 369.777169 -238.251551) (xy 369.775188 -238.276947) (xy 369.763268 -238.327052) (xy 369.74372 -238.374703)
			(xy 369.71702 -238.418746) (xy 369.683812 -238.458115) (xy 369.6449 -238.491857) (xy 369.601226 -238.519157)
			(xy 369.553847 -238.539353) (xy 369.503908 -238.551957) (xy 369.478306 -238.554768) (xy 369.463385 -238.556707)
			(xy 369.435556 -238.568104) (xy 369.412245 -238.587104) (xy 369.39547 -238.612064) (xy 369.386682 -238.640824)
			(xy 369.386104 -238.65586) (xy 369.386104 -239.065367) (xy 369.588289 -239.065367) (xy 369.588289 -239.013433)
			(xy 369.596414 -238.962138) (xy 369.612462 -238.912745) (xy 369.63604 -238.866471) (xy 369.666566 -238.824455)
			(xy 369.703289 -238.787732) (xy 369.745305 -238.757206) (xy 369.791579 -238.733628) (xy 369.840972 -238.71758)
			(xy 369.892267 -238.709455) (xy 369.944201 -238.709455) (xy 369.995496 -238.71758) (xy 370.044889 -238.733628)
			(xy 370.091163 -238.757206) (xy 370.133179 -238.787732) (xy 370.169902 -238.824455) (xy 370.200428 -238.866471)
			(xy 370.224006 -238.912745) (xy 370.240054 -238.962138) (xy 370.248179 -239.013433) (xy 370.248688 -239.0394)
			(xy 370.248179 -239.065367) (xy 370.527835 -239.065367) (xy 370.527835 -239.013433) (xy 370.53596 -238.962138)
			(xy 370.552008 -238.912745) (xy 370.575586 -238.866471) (xy 370.606112 -238.824455) (xy 370.642835 -238.787732)
			(xy 370.684851 -238.757206) (xy 370.731125 -238.733628) (xy 370.780518 -238.71758) (xy 370.831813 -238.709455)
			(xy 370.883747 -238.709455) (xy 370.935042 -238.71758) (xy 370.984435 -238.733628) (xy 371.030709 -238.757206)
			(xy 371.072725 -238.787732) (xy 371.109448 -238.824455) (xy 371.139974 -238.866471) (xy 371.163552 -238.912745)
			(xy 371.1796 -238.962138) (xy 371.187725 -239.013433) (xy 371.188234 -239.0394) (xy 371.187725 -239.065367)
			(xy 371.467889 -239.065367) (xy 371.467889 -239.013433) (xy 371.476014 -238.962138) (xy 371.492062 -238.912745)
			(xy 371.51564 -238.866471) (xy 371.546166 -238.824455) (xy 371.582889 -238.787732) (xy 371.624905 -238.757206)
			(xy 371.671179 -238.733628) (xy 371.720572 -238.71758) (xy 371.771867 -238.709455) (xy 371.823801 -238.709455)
			(xy 371.875096 -238.71758) (xy 371.924489 -238.733628) (xy 371.970763 -238.757206) (xy 372.012779 -238.787732)
			(xy 372.049502 -238.824455) (xy 372.080028 -238.866471) (xy 372.103606 -238.912745) (xy 372.119654 -238.962138)
			(xy 372.127779 -239.013433) (xy 372.128288 -239.0394) (xy 372.127779 -239.065367) (xy 372.407689 -239.065367)
			(xy 372.407689 -239.013433) (xy 372.415814 -238.962138) (xy 372.431862 -238.912745) (xy 372.45544 -238.866471)
			(xy 372.485966 -238.824455) (xy 372.522689 -238.787732) (xy 372.564705 -238.757206) (xy 372.610979 -238.733628)
			(xy 372.660372 -238.71758) (xy 372.711667 -238.709455) (xy 372.763601 -238.709455) (xy 372.814896 -238.71758)
			(xy 372.864289 -238.733628) (xy 372.910563 -238.757206) (xy 372.952579 -238.787732) (xy 372.989302 -238.824455)
			(xy 373.019828 -238.866471) (xy 373.043406 -238.912745) (xy 373.059454 -238.962138) (xy 373.067579 -239.013433)
			(xy 373.068088 -239.0394) (xy 373.067579 -239.065367) (xy 373.347489 -239.065367) (xy 373.347489 -239.013433)
			(xy 373.355614 -238.962138) (xy 373.371662 -238.912745) (xy 373.39524 -238.866471) (xy 373.425766 -238.824455)
			(xy 373.462489 -238.787732) (xy 373.504505 -238.757206) (xy 373.550779 -238.733628) (xy 373.600172 -238.71758)
			(xy 373.651467 -238.709455) (xy 373.703401 -238.709455) (xy 373.754696 -238.71758) (xy 373.804089 -238.733628)
			(xy 373.850363 -238.757206) (xy 373.892379 -238.787732) (xy 373.929102 -238.824455) (xy 373.959628 -238.866471)
			(xy 373.983206 -238.912745) (xy 373.999254 -238.962138) (xy 374.007379 -239.013433) (xy 374.007888 -239.0394)
			(xy 374.007379 -239.065367) (xy 374.287289 -239.065367) (xy 374.287289 -239.013433) (xy 374.295414 -238.962138)
			(xy 374.311462 -238.912745) (xy 374.33504 -238.866471) (xy 374.365566 -238.824455) (xy 374.402289 -238.787732)
			(xy 374.444305 -238.757206) (xy 374.490579 -238.733628) (xy 374.539972 -238.71758) (xy 374.591267 -238.709455)
			(xy 374.643201 -238.709455) (xy 374.694496 -238.71758) (xy 374.743889 -238.733628) (xy 374.790163 -238.757206)
			(xy 374.832179 -238.787732) (xy 374.868902 -238.824455) (xy 374.899428 -238.866471) (xy 374.923006 -238.912745)
			(xy 374.939054 -238.962138) (xy 374.947179 -239.013433) (xy 374.947688 -239.0394) (xy 374.947179 -239.065367)
			(xy 375.227089 -239.065367) (xy 375.227089 -239.013433) (xy 375.235214 -238.962138) (xy 375.251262 -238.912745)
			(xy 375.27484 -238.866471) (xy 375.305366 -238.824455) (xy 375.342089 -238.787732) (xy 375.384105 -238.757206)
			(xy 375.430379 -238.733628) (xy 375.479772 -238.71758) (xy 375.531067 -238.709455) (xy 375.583001 -238.709455)
			(xy 375.634296 -238.71758) (xy 375.683689 -238.733628) (xy 375.729963 -238.757206) (xy 375.771979 -238.787732)
			(xy 375.808702 -238.824455) (xy 375.839228 -238.866471) (xy 375.862806 -238.912745) (xy 375.878854 -238.962138)
			(xy 375.886979 -239.013433) (xy 375.887488 -239.0394) (xy 375.886979 -239.065367) (xy 375.878854 -239.116662)
			(xy 375.862806 -239.166055) (xy 375.839228 -239.212329) (xy 375.808702 -239.254345) (xy 375.771979 -239.291068)
			(xy 375.729963 -239.321594) (xy 375.683689 -239.345172) (xy 375.634296 -239.36122) (xy 375.583001 -239.369345)
			(xy 375.531067 -239.369345) (xy 375.479772 -239.36122) (xy 375.430379 -239.345172) (xy 375.384105 -239.321594)
			(xy 375.342089 -239.291068) (xy 375.305366 -239.254345) (xy 375.27484 -239.212329) (xy 375.251262 -239.166055)
			(xy 375.235214 -239.116662) (xy 375.227089 -239.065367) (xy 374.947179 -239.065367) (xy 374.939054 -239.116662)
			(xy 374.923006 -239.166055) (xy 374.899428 -239.212329) (xy 374.868902 -239.254345) (xy 374.832179 -239.291068)
			(xy 374.790163 -239.321594) (xy 374.743889 -239.345172) (xy 374.694496 -239.36122) (xy 374.643201 -239.369345)
			(xy 374.591267 -239.369345) (xy 374.539972 -239.36122) (xy 374.490579 -239.345172) (xy 374.444305 -239.321594)
			(xy 374.402289 -239.291068) (xy 374.365566 -239.254345) (xy 374.33504 -239.212329) (xy 374.311462 -239.166055)
			(xy 374.295414 -239.116662) (xy 374.287289 -239.065367) (xy 374.007379 -239.065367) (xy 373.999254 -239.116662)
			(xy 373.983206 -239.166055) (xy 373.959628 -239.212329) (xy 373.929102 -239.254345) (xy 373.892379 -239.291068)
			(xy 373.850363 -239.321594) (xy 373.804089 -239.345172) (xy 373.754696 -239.36122) (xy 373.703401 -239.369345)
			(xy 373.651467 -239.369345) (xy 373.600172 -239.36122) (xy 373.550779 -239.345172) (xy 373.504505 -239.321594)
			(xy 373.462489 -239.291068) (xy 373.425766 -239.254345) (xy 373.39524 -239.212329) (xy 373.371662 -239.166055)
			(xy 373.355614 -239.116662) (xy 373.347489 -239.065367) (xy 373.067579 -239.065367) (xy 373.059454 -239.116662)
			(xy 373.043406 -239.166055) (xy 373.019828 -239.212329) (xy 372.989302 -239.254345) (xy 372.952579 -239.291068)
			(xy 372.910563 -239.321594) (xy 372.864289 -239.345172) (xy 372.814896 -239.36122) (xy 372.763601 -239.369345)
			(xy 372.711667 -239.369345) (xy 372.660372 -239.36122) (xy 372.610979 -239.345172) (xy 372.564705 -239.321594)
			(xy 372.522689 -239.291068) (xy 372.485966 -239.254345) (xy 372.45544 -239.212329) (xy 372.431862 -239.166055)
			(xy 372.415814 -239.116662) (xy 372.407689 -239.065367) (xy 372.127779 -239.065367) (xy 372.119654 -239.116662)
			(xy 372.103606 -239.166055) (xy 372.080028 -239.212329) (xy 372.049502 -239.254345) (xy 372.012779 -239.291068)
			(xy 371.970763 -239.321594) (xy 371.924489 -239.345172) (xy 371.875096 -239.36122) (xy 371.823801 -239.369345)
			(xy 371.771867 -239.369345) (xy 371.720572 -239.36122) (xy 371.671179 -239.345172) (xy 371.624905 -239.321594)
			(xy 371.582889 -239.291068) (xy 371.546166 -239.254345) (xy 371.51564 -239.212329) (xy 371.492062 -239.166055)
			(xy 371.476014 -239.116662) (xy 371.467889 -239.065367) (xy 371.187725 -239.065367) (xy 371.1796 -239.116662)
			(xy 371.163552 -239.166055) (xy 371.139974 -239.212329) (xy 371.109448 -239.254345) (xy 371.072725 -239.291068)
			(xy 371.030709 -239.321594) (xy 370.984435 -239.345172) (xy 370.935042 -239.36122) (xy 370.883747 -239.369345)
			(xy 370.831813 -239.369345) (xy 370.780518 -239.36122) (xy 370.731125 -239.345172) (xy 370.684851 -239.321594)
			(xy 370.642835 -239.291068) (xy 370.606112 -239.254345) (xy 370.575586 -239.212329) (xy 370.552008 -239.166055)
			(xy 370.53596 -239.116662) (xy 370.527835 -239.065367) (xy 370.248179 -239.065367) (xy 370.240054 -239.116662)
			(xy 370.224006 -239.166055) (xy 370.200428 -239.212329) (xy 370.169902 -239.254345) (xy 370.133179 -239.291068)
			(xy 370.091163 -239.321594) (xy 370.044889 -239.345172) (xy 369.995496 -239.36122) (xy 369.944201 -239.369345)
			(xy 369.892267 -239.369345) (xy 369.840972 -239.36122) (xy 369.791579 -239.345172) (xy 369.745305 -239.321594)
			(xy 369.703289 -239.291068) (xy 369.666566 -239.254345) (xy 369.63604 -239.212329) (xy 369.612462 -239.166055)
			(xy 369.596414 -239.116662) (xy 369.588289 -239.065367) (xy 369.386104 -239.065367) (xy 369.386104 -239.42294)
			(xy 369.386637 -239.437988) (xy 369.395397 -239.46678) (xy 369.412173 -239.491766) (xy 369.435506 -239.510774)
			(xy 369.463368 -239.522151) (xy 369.478306 -239.524032) (xy 369.503903 -239.526875) (xy 369.553836 -239.539477)
			(xy 369.601211 -239.559671) (xy 369.644881 -239.586968) (xy 369.683789 -239.620708) (xy 369.716994 -239.660073)
			(xy 369.743692 -239.704111) (xy 369.763237 -239.751757) (xy 369.775157 -239.801858) (xy 369.779162 -239.853201)
			(xy 369.777135 -239.879183) (xy 370.058189 -239.879183) (xy 370.058189 -239.827249) (xy 370.066314 -239.775954)
			(xy 370.082362 -239.726561) (xy 370.10594 -239.680287) (xy 370.136466 -239.638271) (xy 370.173189 -239.601548)
			(xy 370.215205 -239.571022) (xy 370.261479 -239.547444) (xy 370.310872 -239.531396) (xy 370.362167 -239.523271)
			(xy 370.414101 -239.523271) (xy 370.465396 -239.531396) (xy 370.514789 -239.547444) (xy 370.561063 -239.571022)
			(xy 370.603079 -239.601548) (xy 370.639802 -239.638271) (xy 370.670328 -239.680287) (xy 370.693906 -239.726561)
			(xy 370.709954 -239.775954) (xy 370.718079 -239.827249) (xy 370.718588 -239.853216) (xy 370.718079 -239.879183)
			(xy 370.997735 -239.879183) (xy 370.997735 -239.827249) (xy 371.00586 -239.775954) (xy 371.021908 -239.726561)
			(xy 371.045486 -239.680287) (xy 371.076012 -239.638271) (xy 371.112735 -239.601548) (xy 371.154751 -239.571022)
			(xy 371.201025 -239.547444) (xy 371.250418 -239.531396) (xy 371.301713 -239.523271) (xy 371.353647 -239.523271)
			(xy 371.404942 -239.531396) (xy 371.454335 -239.547444) (xy 371.500609 -239.571022) (xy 371.542625 -239.601548)
			(xy 371.579348 -239.638271) (xy 371.609874 -239.680287) (xy 371.633452 -239.726561) (xy 371.6495 -239.775954)
			(xy 371.657625 -239.827249) (xy 371.658134 -239.853216) (xy 371.657625 -239.879183) (xy 371.937535 -239.879183)
			(xy 371.937535 -239.827249) (xy 371.94566 -239.775954) (xy 371.961708 -239.726561) (xy 371.985286 -239.680287)
			(xy 372.015812 -239.638271) (xy 372.052535 -239.601548) (xy 372.094551 -239.571022) (xy 372.140825 -239.547444)
			(xy 372.190218 -239.531396) (xy 372.241513 -239.523271) (xy 372.293447 -239.523271) (xy 372.344742 -239.531396)
			(xy 372.394135 -239.547444) (xy 372.440409 -239.571022) (xy 372.482425 -239.601548) (xy 372.519148 -239.638271)
			(xy 372.549674 -239.680287) (xy 372.573252 -239.726561) (xy 372.5893 -239.775954) (xy 372.597425 -239.827249)
			(xy 372.597934 -239.853216) (xy 372.597425 -239.879183) (xy 372.877589 -239.879183) (xy 372.877589 -239.827249)
			(xy 372.885714 -239.775954) (xy 372.901762 -239.726561) (xy 372.92534 -239.680287) (xy 372.955866 -239.638271)
			(xy 372.992589 -239.601548) (xy 373.034605 -239.571022) (xy 373.080879 -239.547444) (xy 373.130272 -239.531396)
			(xy 373.181567 -239.523271) (xy 373.233501 -239.523271) (xy 373.284796 -239.531396) (xy 373.334189 -239.547444)
			(xy 373.380463 -239.571022) (xy 373.422479 -239.601548) (xy 373.459202 -239.638271) (xy 373.489728 -239.680287)
			(xy 373.513306 -239.726561) (xy 373.529354 -239.775954) (xy 373.537479 -239.827249) (xy 373.537988 -239.853216)
			(xy 373.537479 -239.879183) (xy 373.817135 -239.879183) (xy 373.817135 -239.827249) (xy 373.82526 -239.775954)
			(xy 373.841308 -239.726561) (xy 373.864886 -239.680287) (xy 373.895412 -239.638271) (xy 373.932135 -239.601548)
			(xy 373.974151 -239.571022) (xy 374.020425 -239.547444) (xy 374.069818 -239.531396) (xy 374.121113 -239.523271)
			(xy 374.173047 -239.523271) (xy 374.224342 -239.531396) (xy 374.273735 -239.547444) (xy 374.320009 -239.571022)
			(xy 374.362025 -239.601548) (xy 374.398748 -239.638271) (xy 374.429274 -239.680287) (xy 374.452852 -239.726561)
			(xy 374.4689 -239.775954) (xy 374.477025 -239.827249) (xy 374.477534 -239.853216) (xy 374.477025 -239.879183)
			(xy 374.756935 -239.879183) (xy 374.756935 -239.827249) (xy 374.76506 -239.775954) (xy 374.781108 -239.726561)
			(xy 374.804686 -239.680287) (xy 374.835212 -239.638271) (xy 374.871935 -239.601548) (xy 374.913951 -239.571022)
			(xy 374.960225 -239.547444) (xy 375.009618 -239.531396) (xy 375.060913 -239.523271) (xy 375.112847 -239.523271)
			(xy 375.164142 -239.531396) (xy 375.213535 -239.547444) (xy 375.259809 -239.571022) (xy 375.301825 -239.601548)
			(xy 375.338548 -239.638271) (xy 375.369074 -239.680287) (xy 375.392652 -239.726561) (xy 375.4087 -239.775954)
			(xy 375.416825 -239.827249) (xy 375.417334 -239.853216) (xy 375.416825 -239.879183) (xy 375.4087 -239.930478)
			(xy 375.392652 -239.979871) (xy 375.369074 -240.026145) (xy 375.338548 -240.068161) (xy 375.301825 -240.104884)
			(xy 375.259809 -240.13541) (xy 375.213535 -240.158988) (xy 375.164142 -240.175036) (xy 375.112847 -240.183161)
			(xy 375.060913 -240.183161) (xy 375.009618 -240.175036) (xy 374.960225 -240.158988) (xy 374.913951 -240.13541)
			(xy 374.871935 -240.104884) (xy 374.835212 -240.068161) (xy 374.804686 -240.026145) (xy 374.781108 -239.979871)
			(xy 374.76506 -239.930478) (xy 374.756935 -239.879183) (xy 374.477025 -239.879183) (xy 374.4689 -239.930478)
			(xy 374.452852 -239.979871) (xy 374.429274 -240.026145) (xy 374.398748 -240.068161) (xy 374.362025 -240.104884)
			(xy 374.320009 -240.13541) (xy 374.273735 -240.158988) (xy 374.224342 -240.175036) (xy 374.173047 -240.183161)
			(xy 374.121113 -240.183161) (xy 374.069818 -240.175036) (xy 374.020425 -240.158988) (xy 373.974151 -240.13541)
			(xy 373.932135 -240.104884) (xy 373.895412 -240.068161) (xy 373.864886 -240.026145) (xy 373.841308 -239.979871)
			(xy 373.82526 -239.930478) (xy 373.817135 -239.879183) (xy 373.537479 -239.879183) (xy 373.529354 -239.930478)
			(xy 373.513306 -239.979871) (xy 373.489728 -240.026145) (xy 373.459202 -240.068161) (xy 373.422479 -240.104884)
			(xy 373.380463 -240.13541) (xy 373.334189 -240.158988) (xy 373.284796 -240.175036) (xy 373.233501 -240.183161)
			(xy 373.181567 -240.183161) (xy 373.130272 -240.175036) (xy 373.080879 -240.158988) (xy 373.034605 -240.13541)
			(xy 372.992589 -240.104884) (xy 372.955866 -240.068161) (xy 372.92534 -240.026145) (xy 372.901762 -239.979871)
			(xy 372.885714 -239.930478) (xy 372.877589 -239.879183) (xy 372.597425 -239.879183) (xy 372.5893 -239.930478)
			(xy 372.573252 -239.979871) (xy 372.549674 -240.026145) (xy 372.519148 -240.068161) (xy 372.482425 -240.104884)
			(xy 372.440409 -240.13541) (xy 372.394135 -240.158988) (xy 372.344742 -240.175036) (xy 372.293447 -240.183161)
			(xy 372.241513 -240.183161) (xy 372.190218 -240.175036) (xy 372.140825 -240.158988) (xy 372.094551 -240.13541)
			(xy 372.052535 -240.104884) (xy 372.015812 -240.068161) (xy 371.985286 -240.026145) (xy 371.961708 -239.979871)
			(xy 371.94566 -239.930478) (xy 371.937535 -239.879183) (xy 371.657625 -239.879183) (xy 371.6495 -239.930478)
			(xy 371.633452 -239.979871) (xy 371.609874 -240.026145) (xy 371.579348 -240.068161) (xy 371.542625 -240.104884)
			(xy 371.500609 -240.13541) (xy 371.454335 -240.158988) (xy 371.404942 -240.175036) (xy 371.353647 -240.183161)
			(xy 371.301713 -240.183161) (xy 371.250418 -240.175036) (xy 371.201025 -240.158988) (xy 371.154751 -240.13541)
			(xy 371.112735 -240.104884) (xy 371.076012 -240.068161) (xy 371.045486 -240.026145) (xy 371.021908 -239.979871)
			(xy 371.00586 -239.930478) (xy 370.997735 -239.879183) (xy 370.718079 -239.879183) (xy 370.709954 -239.930478)
			(xy 370.693906 -239.979871) (xy 370.670328 -240.026145) (xy 370.639802 -240.068161) (xy 370.603079 -240.104884)
			(xy 370.561063 -240.13541) (xy 370.514789 -240.158988) (xy 370.465396 -240.175036) (xy 370.414101 -240.183161)
			(xy 370.362167 -240.183161) (xy 370.310872 -240.175036) (xy 370.261479 -240.158988) (xy 370.215205 -240.13541)
			(xy 370.173189 -240.104884) (xy 370.136466 -240.068161) (xy 370.10594 -240.026145) (xy 370.082362 -239.979871)
			(xy 370.066314 -239.930478) (xy 370.058189 -239.879183) (xy 369.777135 -239.879183) (xy 369.775156 -239.904545)
			(xy 369.763236 -239.954645) (xy 369.743691 -240.002291) (xy 369.716992 -240.04633) (xy 369.683787 -240.085695)
			(xy 369.644879 -240.119433) (xy 369.601209 -240.14673) (xy 369.553834 -240.166924) (xy 369.5039 -240.179526)
			(xy 369.478306 -240.1824) (xy 369.463387 -240.18434) (xy 369.435562 -240.195738) (xy 369.412257 -240.214739)
			(xy 369.395489 -240.239699) (xy 369.386709 -240.268458) (xy 369.386104 -240.283492) (xy 369.386104 -240.693253)
			(xy 369.588289 -240.693253) (xy 369.588289 -240.641319) (xy 369.596414 -240.590024) (xy 369.612462 -240.540631)
			(xy 369.63604 -240.494357) (xy 369.666566 -240.452341) (xy 369.703289 -240.415618) (xy 369.745305 -240.385092)
			(xy 369.791579 -240.361514) (xy 369.840972 -240.345466) (xy 369.892267 -240.337341) (xy 369.944201 -240.337341)
			(xy 369.995496 -240.345466) (xy 370.044889 -240.361514) (xy 370.091163 -240.385092) (xy 370.133179 -240.415618)
			(xy 370.169902 -240.452341) (xy 370.200428 -240.494357) (xy 370.224006 -240.540631) (xy 370.240054 -240.590024)
			(xy 370.248179 -240.641319) (xy 370.248688 -240.667286) (xy 370.248179 -240.693253) (xy 370.527835 -240.693253)
			(xy 370.527835 -240.641319) (xy 370.53596 -240.590024) (xy 370.552008 -240.540631) (xy 370.575586 -240.494357)
			(xy 370.606112 -240.452341) (xy 370.642835 -240.415618) (xy 370.684851 -240.385092) (xy 370.731125 -240.361514)
			(xy 370.780518 -240.345466) (xy 370.831813 -240.337341) (xy 370.883747 -240.337341) (xy 370.935042 -240.345466)
			(xy 370.984435 -240.361514) (xy 371.030709 -240.385092) (xy 371.072725 -240.415618) (xy 371.109448 -240.452341)
			(xy 371.139974 -240.494357) (xy 371.163552 -240.540631) (xy 371.1796 -240.590024) (xy 371.187725 -240.641319)
			(xy 371.188234 -240.667286) (xy 371.187725 -240.693253) (xy 371.467889 -240.693253) (xy 371.467889 -240.641319)
			(xy 371.476014 -240.590024) (xy 371.492062 -240.540631) (xy 371.51564 -240.494357) (xy 371.546166 -240.452341)
			(xy 371.582889 -240.415618) (xy 371.624905 -240.385092) (xy 371.671179 -240.361514) (xy 371.720572 -240.345466)
			(xy 371.771867 -240.337341) (xy 371.823801 -240.337341) (xy 371.875096 -240.345466) (xy 371.924489 -240.361514)
			(xy 371.970763 -240.385092) (xy 372.012779 -240.415618) (xy 372.049502 -240.452341) (xy 372.080028 -240.494357)
			(xy 372.103606 -240.540631) (xy 372.119654 -240.590024) (xy 372.127779 -240.641319) (xy 372.128288 -240.667286)
			(xy 372.127779 -240.693253) (xy 372.407689 -240.693253) (xy 372.407689 -240.641319) (xy 372.415814 -240.590024)
			(xy 372.431862 -240.540631) (xy 372.45544 -240.494357) (xy 372.485966 -240.452341) (xy 372.522689 -240.415618)
			(xy 372.564705 -240.385092) (xy 372.610979 -240.361514) (xy 372.660372 -240.345466) (xy 372.711667 -240.337341)
			(xy 372.763601 -240.337341) (xy 372.814896 -240.345466) (xy 372.864289 -240.361514) (xy 372.910563 -240.385092)
			(xy 372.952579 -240.415618) (xy 372.989302 -240.452341) (xy 373.019828 -240.494357) (xy 373.043406 -240.540631)
			(xy 373.059454 -240.590024) (xy 373.067579 -240.641319) (xy 373.068088 -240.667286) (xy 373.067579 -240.693253)
			(xy 373.347235 -240.693253) (xy 373.347235 -240.641319) (xy 373.35536 -240.590024) (xy 373.371408 -240.540631)
			(xy 373.394986 -240.494357) (xy 373.425512 -240.452341) (xy 373.462235 -240.415618) (xy 373.504251 -240.385092)
			(xy 373.550525 -240.361514) (xy 373.599918 -240.345466) (xy 373.651213 -240.337341) (xy 373.703147 -240.337341)
			(xy 373.754442 -240.345466) (xy 373.803835 -240.361514) (xy 373.850109 -240.385092) (xy 373.892125 -240.415618)
			(xy 373.928848 -240.452341) (xy 373.959374 -240.494357) (xy 373.982952 -240.540631) (xy 373.999 -240.590024)
			(xy 374.007125 -240.641319) (xy 374.007634 -240.667286) (xy 374.007125 -240.693253) (xy 374.287289 -240.693253)
			(xy 374.287289 -240.641319) (xy 374.295414 -240.590024) (xy 374.311462 -240.540631) (xy 374.33504 -240.494357)
			(xy 374.365566 -240.452341) (xy 374.402289 -240.415618) (xy 374.444305 -240.385092) (xy 374.490579 -240.361514)
			(xy 374.539972 -240.345466) (xy 374.591267 -240.337341) (xy 374.643201 -240.337341) (xy 374.694496 -240.345466)
			(xy 374.743889 -240.361514) (xy 374.790163 -240.385092) (xy 374.832179 -240.415618) (xy 374.868902 -240.452341)
			(xy 374.899428 -240.494357) (xy 374.923006 -240.540631) (xy 374.939054 -240.590024) (xy 374.947179 -240.641319)
			(xy 374.947688 -240.667286) (xy 374.947179 -240.693253) (xy 375.227089 -240.693253) (xy 375.227089 -240.641319)
			(xy 375.235214 -240.590024) (xy 375.251262 -240.540631) (xy 375.27484 -240.494357) (xy 375.305366 -240.452341)
			(xy 375.342089 -240.415618) (xy 375.384105 -240.385092) (xy 375.430379 -240.361514) (xy 375.479772 -240.345466)
			(xy 375.531067 -240.337341) (xy 375.583001 -240.337341) (xy 375.634296 -240.345466) (xy 375.683689 -240.361514)
			(xy 375.729963 -240.385092) (xy 375.771979 -240.415618) (xy 375.808702 -240.452341) (xy 375.839228 -240.494357)
			(xy 375.862806 -240.540631) (xy 375.878854 -240.590024) (xy 375.886979 -240.641319) (xy 375.887488 -240.667286)
			(xy 375.886979 -240.693253) (xy 375.878854 -240.744548) (xy 375.862806 -240.793941) (xy 375.839228 -240.840215)
			(xy 375.808702 -240.882231) (xy 375.771979 -240.918954) (xy 375.729963 -240.94948) (xy 375.683689 -240.973058)
			(xy 375.634296 -240.989106) (xy 375.583001 -240.997231) (xy 375.531067 -240.997231) (xy 375.479772 -240.989106)
			(xy 375.430379 -240.973058) (xy 375.384105 -240.94948) (xy 375.342089 -240.918954) (xy 375.305366 -240.882231)
			(xy 375.27484 -240.840215) (xy 375.251262 -240.793941) (xy 375.235214 -240.744548) (xy 375.227089 -240.693253)
			(xy 374.947179 -240.693253) (xy 374.939054 -240.744548) (xy 374.923006 -240.793941) (xy 374.899428 -240.840215)
			(xy 374.868902 -240.882231) (xy 374.832179 -240.918954) (xy 374.790163 -240.94948) (xy 374.743889 -240.973058)
			(xy 374.694496 -240.989106) (xy 374.643201 -240.997231) (xy 374.591267 -240.997231) (xy 374.539972 -240.989106)
			(xy 374.490579 -240.973058) (xy 374.444305 -240.94948) (xy 374.402289 -240.918954) (xy 374.365566 -240.882231)
			(xy 374.33504 -240.840215) (xy 374.311462 -240.793941) (xy 374.295414 -240.744548) (xy 374.287289 -240.693253)
			(xy 374.007125 -240.693253) (xy 373.999 -240.744548) (xy 373.982952 -240.793941) (xy 373.959374 -240.840215)
			(xy 373.928848 -240.882231) (xy 373.892125 -240.918954) (xy 373.850109 -240.94948) (xy 373.803835 -240.973058)
			(xy 373.754442 -240.989106) (xy 373.703147 -240.997231) (xy 373.651213 -240.997231) (xy 373.599918 -240.989106)
			(xy 373.550525 -240.973058) (xy 373.504251 -240.94948) (xy 373.462235 -240.918954) (xy 373.425512 -240.882231)
			(xy 373.394986 -240.840215) (xy 373.371408 -240.793941) (xy 373.35536 -240.744548) (xy 373.347235 -240.693253)
			(xy 373.067579 -240.693253) (xy 373.059454 -240.744548) (xy 373.043406 -240.793941) (xy 373.019828 -240.840215)
			(xy 372.989302 -240.882231) (xy 372.952579 -240.918954) (xy 372.910563 -240.94948) (xy 372.864289 -240.973058)
			(xy 372.814896 -240.989106) (xy 372.763601 -240.997231) (xy 372.711667 -240.997231) (xy 372.660372 -240.989106)
			(xy 372.610979 -240.973058) (xy 372.564705 -240.94948) (xy 372.522689 -240.918954) (xy 372.485966 -240.882231)
			(xy 372.45544 -240.840215) (xy 372.431862 -240.793941) (xy 372.415814 -240.744548) (xy 372.407689 -240.693253)
			(xy 372.127779 -240.693253) (xy 372.119654 -240.744548) (xy 372.103606 -240.793941) (xy 372.080028 -240.840215)
			(xy 372.049502 -240.882231) (xy 372.012779 -240.918954) (xy 371.970763 -240.94948) (xy 371.924489 -240.973058)
			(xy 371.875096 -240.989106) (xy 371.823801 -240.997231) (xy 371.771867 -240.997231) (xy 371.720572 -240.989106)
			(xy 371.671179 -240.973058) (xy 371.624905 -240.94948) (xy 371.582889 -240.918954) (xy 371.546166 -240.882231)
			(xy 371.51564 -240.840215) (xy 371.492062 -240.793941) (xy 371.476014 -240.744548) (xy 371.467889 -240.693253)
			(xy 371.187725 -240.693253) (xy 371.1796 -240.744548) (xy 371.163552 -240.793941) (xy 371.139974 -240.840215)
			(xy 371.109448 -240.882231) (xy 371.072725 -240.918954) (xy 371.030709 -240.94948) (xy 370.984435 -240.973058)
			(xy 370.935042 -240.989106) (xy 370.883747 -240.997231) (xy 370.831813 -240.997231) (xy 370.780518 -240.989106)
			(xy 370.731125 -240.973058) (xy 370.684851 -240.94948) (xy 370.642835 -240.918954) (xy 370.606112 -240.882231)
			(xy 370.575586 -240.840215) (xy 370.552008 -240.793941) (xy 370.53596 -240.744548) (xy 370.527835 -240.693253)
			(xy 370.248179 -240.693253) (xy 370.240054 -240.744548) (xy 370.224006 -240.793941) (xy 370.200428 -240.840215)
			(xy 370.169902 -240.882231) (xy 370.133179 -240.918954) (xy 370.091163 -240.94948) (xy 370.044889 -240.973058)
			(xy 369.995496 -240.989106) (xy 369.944201 -240.997231) (xy 369.892267 -240.997231) (xy 369.840972 -240.989106)
			(xy 369.791579 -240.973058) (xy 369.745305 -240.94948) (xy 369.703289 -240.918954) (xy 369.666566 -240.882231)
			(xy 369.63604 -240.840215) (xy 369.612462 -240.793941) (xy 369.596414 -240.744548) (xy 369.588289 -240.693253)
			(xy 369.386104 -240.693253) (xy 369.386104 -241.050826) (xy 369.386636 -241.065875) (xy 369.395393 -241.094671)
			(xy 369.412168 -241.119661) (xy 369.435501 -241.138671) (xy 369.463365 -241.15005) (xy 369.478306 -241.151918)
			(xy 369.503904 -241.154761) (xy 369.55384 -241.167364) (xy 369.601217 -241.187558) (xy 369.644888 -241.214856)
			(xy 369.683798 -241.248597) (xy 369.717004 -241.287964) (xy 369.743704 -241.332004) (xy 369.76325 -241.379652)
			(xy 369.77517 -241.429755) (xy 369.779176 -241.4811) (xy 369.77715 -241.507069) (xy 370.058189 -241.507069)
			(xy 370.058189 -241.455135) (xy 370.066314 -241.40384) (xy 370.082362 -241.354447) (xy 370.10594 -241.308173)
			(xy 370.136466 -241.266157) (xy 370.173189 -241.229434) (xy 370.215205 -241.198908) (xy 370.261479 -241.17533)
			(xy 370.310872 -241.159282) (xy 370.362167 -241.151157) (xy 370.414101 -241.151157) (xy 370.465396 -241.159282)
			(xy 370.514789 -241.17533) (xy 370.561063 -241.198908) (xy 370.603079 -241.229434) (xy 370.639802 -241.266157)
			(xy 370.670328 -241.308173) (xy 370.693906 -241.354447) (xy 370.709954 -241.40384) (xy 370.718079 -241.455135)
			(xy 370.718588 -241.481102) (xy 370.718079 -241.507069) (xy 370.997735 -241.507069) (xy 370.997735 -241.455135)
			(xy 371.00586 -241.40384) (xy 371.021908 -241.354447) (xy 371.045486 -241.308173) (xy 371.076012 -241.266157)
			(xy 371.112735 -241.229434) (xy 371.154751 -241.198908) (xy 371.201025 -241.17533) (xy 371.250418 -241.159282)
			(xy 371.301713 -241.151157) (xy 371.353647 -241.151157) (xy 371.404942 -241.159282) (xy 371.454335 -241.17533)
			(xy 371.500609 -241.198908) (xy 371.542625 -241.229434) (xy 371.579348 -241.266157) (xy 371.609874 -241.308173)
			(xy 371.633452 -241.354447) (xy 371.6495 -241.40384) (xy 371.657625 -241.455135) (xy 371.658134 -241.481102)
			(xy 371.657625 -241.507069) (xy 371.937535 -241.507069) (xy 371.937535 -241.455135) (xy 371.94566 -241.40384)
			(xy 371.961708 -241.354447) (xy 371.985286 -241.308173) (xy 372.015812 -241.266157) (xy 372.052535 -241.229434)
			(xy 372.094551 -241.198908) (xy 372.140825 -241.17533) (xy 372.190218 -241.159282) (xy 372.241513 -241.151157)
			(xy 372.293447 -241.151157) (xy 372.344742 -241.159282) (xy 372.394135 -241.17533) (xy 372.440409 -241.198908)
			(xy 372.482425 -241.229434) (xy 372.519148 -241.266157) (xy 372.549674 -241.308173) (xy 372.573252 -241.354447)
			(xy 372.5893 -241.40384) (xy 372.597425 -241.455135) (xy 372.597934 -241.481102) (xy 372.597425 -241.507069)
			(xy 372.877335 -241.507069) (xy 372.877335 -241.455135) (xy 372.88546 -241.40384) (xy 372.901508 -241.354447)
			(xy 372.925086 -241.308173) (xy 372.955612 -241.266157) (xy 372.992335 -241.229434) (xy 373.034351 -241.198908)
			(xy 373.080625 -241.17533) (xy 373.130018 -241.159282) (xy 373.181313 -241.151157) (xy 373.233247 -241.151157)
			(xy 373.284542 -241.159282) (xy 373.333935 -241.17533) (xy 373.380209 -241.198908) (xy 373.422225 -241.229434)
			(xy 373.458948 -241.266157) (xy 373.489474 -241.308173) (xy 373.513052 -241.354447) (xy 373.5291 -241.40384)
			(xy 373.537225 -241.455135) (xy 373.537734 -241.481102) (xy 373.537225 -241.507069) (xy 373.817135 -241.507069)
			(xy 373.817135 -241.455135) (xy 373.82526 -241.40384) (xy 373.841308 -241.354447) (xy 373.864886 -241.308173)
			(xy 373.895412 -241.266157) (xy 373.932135 -241.229434) (xy 373.974151 -241.198908) (xy 374.020425 -241.17533)
			(xy 374.069818 -241.159282) (xy 374.121113 -241.151157) (xy 374.173047 -241.151157) (xy 374.224342 -241.159282)
			(xy 374.273735 -241.17533) (xy 374.320009 -241.198908) (xy 374.362025 -241.229434) (xy 374.398748 -241.266157)
			(xy 374.429274 -241.308173) (xy 374.452852 -241.354447) (xy 374.4689 -241.40384) (xy 374.477025 -241.455135)
			(xy 374.477534 -241.481102) (xy 374.477025 -241.507069) (xy 374.756935 -241.507069) (xy 374.756935 -241.455135)
			(xy 374.76506 -241.40384) (xy 374.781108 -241.354447) (xy 374.804686 -241.308173) (xy 374.835212 -241.266157)
			(xy 374.871935 -241.229434) (xy 374.913951 -241.198908) (xy 374.960225 -241.17533) (xy 375.009618 -241.159282)
			(xy 375.060913 -241.151157) (xy 375.112847 -241.151157) (xy 375.164142 -241.159282) (xy 375.213535 -241.17533)
			(xy 375.259809 -241.198908) (xy 375.301825 -241.229434) (xy 375.338548 -241.266157) (xy 375.369074 -241.308173)
			(xy 375.392652 -241.354447) (xy 375.4087 -241.40384) (xy 375.416825 -241.455135) (xy 375.417334 -241.481102)
			(xy 375.416825 -241.507069) (xy 375.4087 -241.558364) (xy 375.392652 -241.607757) (xy 375.369074 -241.654031)
			(xy 375.338548 -241.696047) (xy 375.301825 -241.73277) (xy 375.259809 -241.763296) (xy 375.213535 -241.786874)
			(xy 375.164142 -241.802922) (xy 375.112847 -241.811047) (xy 375.060913 -241.811047) (xy 375.009618 -241.802922)
			(xy 374.960225 -241.786874) (xy 374.913951 -241.763296) (xy 374.871935 -241.73277) (xy 374.835212 -241.696047)
			(xy 374.804686 -241.654031) (xy 374.781108 -241.607757) (xy 374.76506 -241.558364) (xy 374.756935 -241.507069)
			(xy 374.477025 -241.507069) (xy 374.4689 -241.558364) (xy 374.452852 -241.607757) (xy 374.429274 -241.654031)
			(xy 374.398748 -241.696047) (xy 374.362025 -241.73277) (xy 374.320009 -241.763296) (xy 374.273735 -241.786874)
			(xy 374.224342 -241.802922) (xy 374.173047 -241.811047) (xy 374.121113 -241.811047) (xy 374.069818 -241.802922)
			(xy 374.020425 -241.786874) (xy 373.974151 -241.763296) (xy 373.932135 -241.73277) (xy 373.895412 -241.696047)
			(xy 373.864886 -241.654031) (xy 373.841308 -241.607757) (xy 373.82526 -241.558364) (xy 373.817135 -241.507069)
			(xy 373.537225 -241.507069) (xy 373.5291 -241.558364) (xy 373.513052 -241.607757) (xy 373.489474 -241.654031)
			(xy 373.458948 -241.696047) (xy 373.422225 -241.73277) (xy 373.380209 -241.763296) (xy 373.333935 -241.786874)
			(xy 373.284542 -241.802922) (xy 373.233247 -241.811047) (xy 373.181313 -241.811047) (xy 373.130018 -241.802922)
			(xy 373.080625 -241.786874) (xy 373.034351 -241.763296) (xy 372.992335 -241.73277) (xy 372.955612 -241.696047)
			(xy 372.925086 -241.654031) (xy 372.901508 -241.607757) (xy 372.88546 -241.558364) (xy 372.877335 -241.507069)
			(xy 372.597425 -241.507069) (xy 372.5893 -241.558364) (xy 372.573252 -241.607757) (xy 372.549674 -241.654031)
			(xy 372.519148 -241.696047) (xy 372.482425 -241.73277) (xy 372.440409 -241.763296) (xy 372.394135 -241.786874)
			(xy 372.344742 -241.802922) (xy 372.293447 -241.811047) (xy 372.241513 -241.811047) (xy 372.190218 -241.802922)
			(xy 372.140825 -241.786874) (xy 372.094551 -241.763296) (xy 372.052535 -241.73277) (xy 372.015812 -241.696047)
			(xy 371.985286 -241.654031) (xy 371.961708 -241.607757) (xy 371.94566 -241.558364) (xy 371.937535 -241.507069)
			(xy 371.657625 -241.507069) (xy 371.6495 -241.558364) (xy 371.633452 -241.607757) (xy 371.609874 -241.654031)
			(xy 371.579348 -241.696047) (xy 371.542625 -241.73277) (xy 371.500609 -241.763296) (xy 371.454335 -241.786874)
			(xy 371.404942 -241.802922) (xy 371.353647 -241.811047) (xy 371.301713 -241.811047) (xy 371.250418 -241.802922)
			(xy 371.201025 -241.786874) (xy 371.154751 -241.763296) (xy 371.112735 -241.73277) (xy 371.076012 -241.696047)
			(xy 371.045486 -241.654031) (xy 371.021908 -241.607757) (xy 371.00586 -241.558364) (xy 370.997735 -241.507069)
			(xy 370.718079 -241.507069) (xy 370.709954 -241.558364) (xy 370.693906 -241.607757) (xy 370.670328 -241.654031)
			(xy 370.639802 -241.696047) (xy 370.603079 -241.73277) (xy 370.561063 -241.763296) (xy 370.514789 -241.786874)
			(xy 370.465396 -241.802922) (xy 370.414101 -241.811047) (xy 370.362167 -241.811047) (xy 370.310872 -241.802922)
			(xy 370.261479 -241.786874) (xy 370.215205 -241.763296) (xy 370.173189 -241.73277) (xy 370.136466 -241.696047)
			(xy 370.10594 -241.654031) (xy 370.082362 -241.607757) (xy 370.066314 -241.558364) (xy 370.058189 -241.507069)
			(xy 369.77715 -241.507069) (xy 369.77517 -241.532446) (xy 369.76325 -241.582549) (xy 369.743704 -241.630197)
			(xy 369.717004 -241.674237) (xy 369.683798 -241.713603) (xy 369.644888 -241.747344) (xy 369.601216 -241.774642)
			(xy 369.553839 -241.794836) (xy 369.503904 -241.807439) (xy 369.478306 -241.810286) (xy 369.463386 -241.812226)
			(xy 369.435559 -241.823623) (xy 369.412252 -241.842624) (xy 369.395481 -241.867584) (xy 369.386697 -241.896343)
			(xy 369.386104 -241.911378) (xy 369.386104 -242.320885) (xy 369.588289 -242.320885) (xy 369.588289 -242.268951)
			(xy 369.596414 -242.217656) (xy 369.612462 -242.168263) (xy 369.63604 -242.121989) (xy 369.666566 -242.079973)
			(xy 369.703289 -242.04325) (xy 369.745305 -242.012724) (xy 369.791579 -241.989146) (xy 369.840972 -241.973098)
			(xy 369.892267 -241.964973) (xy 369.944201 -241.964973) (xy 369.995496 -241.973098) (xy 370.044889 -241.989146)
			(xy 370.091163 -242.012724) (xy 370.133179 -242.04325) (xy 370.169902 -242.079973) (xy 370.200428 -242.121989)
			(xy 370.224006 -242.168263) (xy 370.240054 -242.217656) (xy 370.248179 -242.268951) (xy 370.248688 -242.294918)
			(xy 370.248179 -242.320885) (xy 370.528089 -242.320885) (xy 370.528089 -242.268951) (xy 370.536214 -242.217656)
			(xy 370.552262 -242.168263) (xy 370.57584 -242.121989) (xy 370.606366 -242.079973) (xy 370.643089 -242.04325)
			(xy 370.685105 -242.012724) (xy 370.731379 -241.989146) (xy 370.780772 -241.973098) (xy 370.832067 -241.964973)
			(xy 370.884001 -241.964973) (xy 370.935296 -241.973098) (xy 370.984689 -241.989146) (xy 371.030963 -242.012724)
			(xy 371.072979 -242.04325) (xy 371.109702 -242.079973) (xy 371.140228 -242.121989) (xy 371.163806 -242.168263)
			(xy 371.179854 -242.217656) (xy 371.187979 -242.268951) (xy 371.188488 -242.294918) (xy 371.187979 -242.320885)
			(xy 371.467889 -242.320885) (xy 371.467889 -242.268951) (xy 371.476014 -242.217656) (xy 371.492062 -242.168263)
			(xy 371.51564 -242.121989) (xy 371.546166 -242.079973) (xy 371.582889 -242.04325) (xy 371.624905 -242.012724)
			(xy 371.671179 -241.989146) (xy 371.720572 -241.973098) (xy 371.771867 -241.964973) (xy 371.823801 -241.964973)
			(xy 371.875096 -241.973098) (xy 371.924489 -241.989146) (xy 371.970763 -242.012724) (xy 372.012779 -242.04325)
			(xy 372.049502 -242.079973) (xy 372.080028 -242.121989) (xy 372.103606 -242.168263) (xy 372.119654 -242.217656)
			(xy 372.127779 -242.268951) (xy 372.128288 -242.294918) (xy 372.127779 -242.320885) (xy 372.407689 -242.320885)
			(xy 372.407689 -242.268951) (xy 372.415814 -242.217656) (xy 372.431862 -242.168263) (xy 372.45544 -242.121989)
			(xy 372.485966 -242.079973) (xy 372.522689 -242.04325) (xy 372.564705 -242.012724) (xy 372.610979 -241.989146)
			(xy 372.660372 -241.973098) (xy 372.711667 -241.964973) (xy 372.763601 -241.964973) (xy 372.814896 -241.973098)
			(xy 372.864289 -241.989146) (xy 372.910563 -242.012724) (xy 372.952579 -242.04325) (xy 372.989302 -242.079973)
			(xy 373.019828 -242.121989) (xy 373.043406 -242.168263) (xy 373.059454 -242.217656) (xy 373.067579 -242.268951)
			(xy 373.068088 -242.294918) (xy 373.067579 -242.320885) (xy 373.347489 -242.320885) (xy 373.347489 -242.268951)
			(xy 373.355614 -242.217656) (xy 373.371662 -242.168263) (xy 373.39524 -242.121989) (xy 373.425766 -242.079973)
			(xy 373.462489 -242.04325) (xy 373.504505 -242.012724) (xy 373.550779 -241.989146) (xy 373.600172 -241.973098)
			(xy 373.651467 -241.964973) (xy 373.703401 -241.964973) (xy 373.754696 -241.973098) (xy 373.804089 -241.989146)
			(xy 373.850363 -242.012724) (xy 373.892379 -242.04325) (xy 373.929102 -242.079973) (xy 373.959628 -242.121989)
			(xy 373.983206 -242.168263) (xy 373.999254 -242.217656) (xy 374.007379 -242.268951) (xy 374.007888 -242.294918)
			(xy 374.007379 -242.320885) (xy 374.287289 -242.320885) (xy 374.287289 -242.268951) (xy 374.295414 -242.217656)
			(xy 374.311462 -242.168263) (xy 374.33504 -242.121989) (xy 374.365566 -242.079973) (xy 374.402289 -242.04325)
			(xy 374.444305 -242.012724) (xy 374.490579 -241.989146) (xy 374.539972 -241.973098) (xy 374.591267 -241.964973)
			(xy 374.643201 -241.964973) (xy 374.694496 -241.973098) (xy 374.743889 -241.989146) (xy 374.790163 -242.012724)
			(xy 374.832179 -242.04325) (xy 374.868902 -242.079973) (xy 374.899428 -242.121989) (xy 374.923006 -242.168263)
			(xy 374.939054 -242.217656) (xy 374.947179 -242.268951) (xy 374.947688 -242.294918) (xy 374.947179 -242.320885)
			(xy 375.227089 -242.320885) (xy 375.227089 -242.268951) (xy 375.235214 -242.217656) (xy 375.251262 -242.168263)
			(xy 375.27484 -242.121989) (xy 375.305366 -242.079973) (xy 375.342089 -242.04325) (xy 375.384105 -242.012724)
			(xy 375.430379 -241.989146) (xy 375.479772 -241.973098) (xy 375.531067 -241.964973) (xy 375.583001 -241.964973)
			(xy 375.634296 -241.973098) (xy 375.683689 -241.989146) (xy 375.729963 -242.012724) (xy 375.771979 -242.04325)
			(xy 375.808702 -242.079973) (xy 375.839228 -242.121989) (xy 375.862806 -242.168263) (xy 375.878854 -242.217656)
			(xy 375.886979 -242.268951) (xy 375.887488 -242.294918) (xy 375.886979 -242.320885) (xy 375.878854 -242.37218)
			(xy 375.862806 -242.421573) (xy 375.839228 -242.467847) (xy 375.808702 -242.509863) (xy 375.771979 -242.546586)
			(xy 375.729963 -242.577112) (xy 375.683689 -242.60069) (xy 375.634296 -242.616738) (xy 375.583001 -242.624863)
			(xy 375.531067 -242.624863) (xy 375.479772 -242.616738) (xy 375.430379 -242.60069) (xy 375.384105 -242.577112)
			(xy 375.342089 -242.546586) (xy 375.305366 -242.509863) (xy 375.27484 -242.467847) (xy 375.251262 -242.421573)
			(xy 375.235214 -242.37218) (xy 375.227089 -242.320885) (xy 374.947179 -242.320885) (xy 374.939054 -242.37218)
			(xy 374.923006 -242.421573) (xy 374.899428 -242.467847) (xy 374.868902 -242.509863) (xy 374.832179 -242.546586)
			(xy 374.790163 -242.577112) (xy 374.743889 -242.60069) (xy 374.694496 -242.616738) (xy 374.643201 -242.624863)
			(xy 374.591267 -242.624863) (xy 374.539972 -242.616738) (xy 374.490579 -242.60069) (xy 374.444305 -242.577112)
			(xy 374.402289 -242.546586) (xy 374.365566 -242.509863) (xy 374.33504 -242.467847) (xy 374.311462 -242.421573)
			(xy 374.295414 -242.37218) (xy 374.287289 -242.320885) (xy 374.007379 -242.320885) (xy 373.999254 -242.37218)
			(xy 373.983206 -242.421573) (xy 373.959628 -242.467847) (xy 373.929102 -242.509863) (xy 373.892379 -242.546586)
			(xy 373.850363 -242.577112) (xy 373.804089 -242.60069) (xy 373.754696 -242.616738) (xy 373.703401 -242.624863)
			(xy 373.651467 -242.624863) (xy 373.600172 -242.616738) (xy 373.550779 -242.60069) (xy 373.504505 -242.577112)
			(xy 373.462489 -242.546586) (xy 373.425766 -242.509863) (xy 373.39524 -242.467847) (xy 373.371662 -242.421573)
			(xy 373.355614 -242.37218) (xy 373.347489 -242.320885) (xy 373.067579 -242.320885) (xy 373.059454 -242.37218)
			(xy 373.043406 -242.421573) (xy 373.019828 -242.467847) (xy 372.989302 -242.509863) (xy 372.952579 -242.546586)
			(xy 372.910563 -242.577112) (xy 372.864289 -242.60069) (xy 372.814896 -242.616738) (xy 372.763601 -242.624863)
			(xy 372.711667 -242.624863) (xy 372.660372 -242.616738) (xy 372.610979 -242.60069) (xy 372.564705 -242.577112)
			(xy 372.522689 -242.546586) (xy 372.485966 -242.509863) (xy 372.45544 -242.467847) (xy 372.431862 -242.421573)
			(xy 372.415814 -242.37218) (xy 372.407689 -242.320885) (xy 372.127779 -242.320885) (xy 372.119654 -242.37218)
			(xy 372.103606 -242.421573) (xy 372.080028 -242.467847) (xy 372.049502 -242.509863) (xy 372.012779 -242.546586)
			(xy 371.970763 -242.577112) (xy 371.924489 -242.60069) (xy 371.875096 -242.616738) (xy 371.823801 -242.624863)
			(xy 371.771867 -242.624863) (xy 371.720572 -242.616738) (xy 371.671179 -242.60069) (xy 371.624905 -242.577112)
			(xy 371.582889 -242.546586) (xy 371.546166 -242.509863) (xy 371.51564 -242.467847) (xy 371.492062 -242.421573)
			(xy 371.476014 -242.37218) (xy 371.467889 -242.320885) (xy 371.187979 -242.320885) (xy 371.179854 -242.37218)
			(xy 371.163806 -242.421573) (xy 371.140228 -242.467847) (xy 371.109702 -242.509863) (xy 371.072979 -242.546586)
			(xy 371.030963 -242.577112) (xy 370.984689 -242.60069) (xy 370.935296 -242.616738) (xy 370.884001 -242.624863)
			(xy 370.832067 -242.624863) (xy 370.780772 -242.616738) (xy 370.731379 -242.60069) (xy 370.685105 -242.577112)
			(xy 370.643089 -242.546586) (xy 370.606366 -242.509863) (xy 370.57584 -242.467847) (xy 370.552262 -242.421573)
			(xy 370.536214 -242.37218) (xy 370.528089 -242.320885) (xy 370.248179 -242.320885) (xy 370.240054 -242.37218)
			(xy 370.224006 -242.421573) (xy 370.200428 -242.467847) (xy 370.169902 -242.509863) (xy 370.133179 -242.546586)
			(xy 370.091163 -242.577112) (xy 370.044889 -242.60069) (xy 369.995496 -242.616738) (xy 369.944201 -242.624863)
			(xy 369.892267 -242.624863) (xy 369.840972 -242.616738) (xy 369.791579 -242.60069) (xy 369.745305 -242.577112)
			(xy 369.703289 -242.546586) (xy 369.666566 -242.509863) (xy 369.63604 -242.467847) (xy 369.612462 -242.421573)
			(xy 369.596414 -242.37218) (xy 369.588289 -242.320885) (xy 369.386104 -242.320885) (xy 369.386104 -242.678712)
			(xy 369.386634 -242.693763) (xy 369.395388 -242.722562) (xy 369.412162 -242.747555) (xy 369.435497 -242.766569)
			(xy 369.463363 -242.77795) (xy 369.478306 -242.779804) (xy 369.503905 -242.782647) (xy 369.553843 -242.79525)
			(xy 369.601222 -242.815446) (xy 369.644896 -242.842744) (xy 369.683807 -242.876486) (xy 369.717015 -242.915854)
			(xy 369.743716 -242.959896) (xy 369.763263 -243.007546) (xy 369.775184 -243.057651) (xy 369.77919 -243.108999)
			(xy 369.777165 -243.134955) (xy 370.057935 -243.134955) (xy 370.057935 -243.083021) (xy 370.06606 -243.031726)
			(xy 370.082108 -242.982333) (xy 370.105686 -242.936059) (xy 370.136212 -242.894043) (xy 370.172935 -242.85732)
			(xy 370.214951 -242.826794) (xy 370.261225 -242.803216) (xy 370.310618 -242.787168) (xy 370.361913 -242.779043)
			(xy 370.413847 -242.779043) (xy 370.465142 -242.787168) (xy 370.514535 -242.803216) (xy 370.560809 -242.826794)
			(xy 370.602825 -242.85732) (xy 370.639548 -242.894043) (xy 370.670074 -242.936059) (xy 370.693652 -242.982333)
			(xy 370.7097 -243.031726) (xy 370.717825 -243.083021) (xy 370.718334 -243.108988) (xy 370.717825 -243.134955)
			(xy 370.997735 -243.134955) (xy 370.997735 -243.083021) (xy 371.00586 -243.031726) (xy 371.021908 -242.982333)
			(xy 371.045486 -242.936059) (xy 371.076012 -242.894043) (xy 371.112735 -242.85732) (xy 371.154751 -242.826794)
			(xy 371.201025 -242.803216) (xy 371.250418 -242.787168) (xy 371.301713 -242.779043) (xy 371.353647 -242.779043)
			(xy 371.404942 -242.787168) (xy 371.454335 -242.803216) (xy 371.500609 -242.826794) (xy 371.542625 -242.85732)
			(xy 371.579348 -242.894043) (xy 371.609874 -242.936059) (xy 371.633452 -242.982333) (xy 371.6495 -243.031726)
			(xy 371.657625 -243.083021) (xy 371.658134 -243.108988) (xy 371.657625 -243.134955) (xy 371.937535 -243.134955)
			(xy 371.937535 -243.083021) (xy 371.94566 -243.031726) (xy 371.961708 -242.982333) (xy 371.985286 -242.936059)
			(xy 372.015812 -242.894043) (xy 372.052535 -242.85732) (xy 372.094551 -242.826794) (xy 372.140825 -242.803216)
			(xy 372.190218 -242.787168) (xy 372.241513 -242.779043) (xy 372.293447 -242.779043) (xy 372.344742 -242.787168)
			(xy 372.394135 -242.803216) (xy 372.440409 -242.826794) (xy 372.482425 -242.85732) (xy 372.519148 -242.894043)
			(xy 372.549674 -242.936059) (xy 372.573252 -242.982333) (xy 372.5893 -243.031726) (xy 372.597425 -243.083021)
			(xy 372.597934 -243.108988) (xy 372.597425 -243.134955) (xy 372.877335 -243.134955) (xy 372.877335 -243.083021)
			(xy 372.88546 -243.031726) (xy 372.901508 -242.982333) (xy 372.925086 -242.936059) (xy 372.955612 -242.894043)
			(xy 372.992335 -242.85732) (xy 373.034351 -242.826794) (xy 373.080625 -242.803216) (xy 373.130018 -242.787168)
			(xy 373.181313 -242.779043) (xy 373.233247 -242.779043) (xy 373.284542 -242.787168) (xy 373.333935 -242.803216)
			(xy 373.380209 -242.826794) (xy 373.422225 -242.85732) (xy 373.458948 -242.894043) (xy 373.489474 -242.936059)
			(xy 373.513052 -242.982333) (xy 373.5291 -243.031726) (xy 373.537225 -243.083021) (xy 373.537734 -243.108988)
			(xy 373.537225 -243.134955) (xy 373.817389 -243.134955) (xy 373.817389 -243.083021) (xy 373.825514 -243.031726)
			(xy 373.841562 -242.982333) (xy 373.86514 -242.936059) (xy 373.895666 -242.894043) (xy 373.932389 -242.85732)
			(xy 373.974405 -242.826794) (xy 374.020679 -242.803216) (xy 374.070072 -242.787168) (xy 374.121367 -242.779043)
			(xy 374.173301 -242.779043) (xy 374.224596 -242.787168) (xy 374.273989 -242.803216) (xy 374.320263 -242.826794)
			(xy 374.362279 -242.85732) (xy 374.399002 -242.894043) (xy 374.429528 -242.936059) (xy 374.453106 -242.982333)
			(xy 374.469154 -243.031726) (xy 374.477279 -243.083021) (xy 374.477788 -243.108988) (xy 374.477279 -243.134955)
			(xy 374.756935 -243.134955) (xy 374.756935 -243.083021) (xy 374.76506 -243.031726) (xy 374.781108 -242.982333)
			(xy 374.804686 -242.936059) (xy 374.835212 -242.894043) (xy 374.871935 -242.85732) (xy 374.913951 -242.826794)
			(xy 374.960225 -242.803216) (xy 375.009618 -242.787168) (xy 375.060913 -242.779043) (xy 375.112847 -242.779043)
			(xy 375.164142 -242.787168) (xy 375.213535 -242.803216) (xy 375.259809 -242.826794) (xy 375.301825 -242.85732)
			(xy 375.338548 -242.894043) (xy 375.369074 -242.936059) (xy 375.392652 -242.982333) (xy 375.4087 -243.031726)
			(xy 375.416825 -243.083021) (xy 375.417334 -243.108988) (xy 375.416825 -243.134955) (xy 375.4087 -243.18625)
			(xy 375.392652 -243.235643) (xy 375.369074 -243.281917) (xy 375.338548 -243.323933) (xy 375.301825 -243.360656)
			(xy 375.259809 -243.391182) (xy 375.213535 -243.41476) (xy 375.164142 -243.430808) (xy 375.112847 -243.438933)
			(xy 375.060913 -243.438933) (xy 375.009618 -243.430808) (xy 374.960225 -243.41476) (xy 374.913951 -243.391182)
			(xy 374.871935 -243.360656) (xy 374.835212 -243.323933) (xy 374.804686 -243.281917) (xy 374.781108 -243.235643)
			(xy 374.76506 -243.18625) (xy 374.756935 -243.134955) (xy 374.477279 -243.134955) (xy 374.469154 -243.18625)
			(xy 374.453106 -243.235643) (xy 374.429528 -243.281917) (xy 374.399002 -243.323933) (xy 374.362279 -243.360656)
			(xy 374.320263 -243.391182) (xy 374.273989 -243.41476) (xy 374.224596 -243.430808) (xy 374.173301 -243.438933)
			(xy 374.121367 -243.438933) (xy 374.070072 -243.430808) (xy 374.020679 -243.41476) (xy 373.974405 -243.391182)
			(xy 373.932389 -243.360656) (xy 373.895666 -243.323933) (xy 373.86514 -243.281917) (xy 373.841562 -243.235643)
			(xy 373.825514 -243.18625) (xy 373.817389 -243.134955) (xy 373.537225 -243.134955) (xy 373.5291 -243.18625)
			(xy 373.513052 -243.235643) (xy 373.489474 -243.281917) (xy 373.458948 -243.323933) (xy 373.422225 -243.360656)
			(xy 373.380209 -243.391182) (xy 373.333935 -243.41476) (xy 373.284542 -243.430808) (xy 373.233247 -243.438933)
			(xy 373.181313 -243.438933) (xy 373.130018 -243.430808) (xy 373.080625 -243.41476) (xy 373.034351 -243.391182)
			(xy 372.992335 -243.360656) (xy 372.955612 -243.323933) (xy 372.925086 -243.281917) (xy 372.901508 -243.235643)
			(xy 372.88546 -243.18625) (xy 372.877335 -243.134955) (xy 372.597425 -243.134955) (xy 372.5893 -243.18625)
			(xy 372.573252 -243.235643) (xy 372.549674 -243.281917) (xy 372.519148 -243.323933) (xy 372.482425 -243.360656)
			(xy 372.440409 -243.391182) (xy 372.394135 -243.41476) (xy 372.344742 -243.430808) (xy 372.293447 -243.438933)
			(xy 372.241513 -243.438933) (xy 372.190218 -243.430808) (xy 372.140825 -243.41476) (xy 372.094551 -243.391182)
			(xy 372.052535 -243.360656) (xy 372.015812 -243.323933) (xy 371.985286 -243.281917) (xy 371.961708 -243.235643)
			(xy 371.94566 -243.18625) (xy 371.937535 -243.134955) (xy 371.657625 -243.134955) (xy 371.6495 -243.18625)
			(xy 371.633452 -243.235643) (xy 371.609874 -243.281917) (xy 371.579348 -243.323933) (xy 371.542625 -243.360656)
			(xy 371.500609 -243.391182) (xy 371.454335 -243.41476) (xy 371.404942 -243.430808) (xy 371.353647 -243.438933)
			(xy 371.301713 -243.438933) (xy 371.250418 -243.430808) (xy 371.201025 -243.41476) (xy 371.154751 -243.391182)
			(xy 371.112735 -243.360656) (xy 371.076012 -243.323933) (xy 371.045486 -243.281917) (xy 371.021908 -243.235643)
			(xy 371.00586 -243.18625) (xy 370.997735 -243.134955) (xy 370.717825 -243.134955) (xy 370.7097 -243.18625)
			(xy 370.693652 -243.235643) (xy 370.670074 -243.281917) (xy 370.639548 -243.323933) (xy 370.602825 -243.360656)
			(xy 370.560809 -243.391182) (xy 370.514535 -243.41476) (xy 370.465142 -243.430808) (xy 370.413847 -243.438933)
			(xy 370.361913 -243.438933) (xy 370.310618 -243.430808) (xy 370.261225 -243.41476) (xy 370.214951 -243.391182)
			(xy 370.172935 -243.360656) (xy 370.136212 -243.323933) (xy 370.105686 -243.281917) (xy 370.082108 -243.235643)
			(xy 370.06606 -243.18625) (xy 370.057935 -243.134955) (xy 369.777165 -243.134955) (xy 369.775184 -243.160346)
			(xy 369.763264 -243.210452) (xy 369.743717 -243.258102) (xy 369.717016 -243.302144) (xy 369.683809 -243.341512)
			(xy 369.644897 -243.375254) (xy 369.601224 -243.402553) (xy 369.553845 -243.422749) (xy 369.503907 -243.435353)
			(xy 369.478306 -243.438172) (xy 369.463386 -243.440111) (xy 369.435557 -243.451509) (xy 369.412247 -243.470509)
			(xy 369.395473 -243.495468) (xy 369.386686 -243.524229) (xy 369.386104 -243.539264) (xy 369.386104 -243.948771)
			(xy 369.588035 -243.948771) (xy 369.588035 -243.896837) (xy 369.59616 -243.845542) (xy 369.612208 -243.796149)
			(xy 369.635786 -243.749875) (xy 369.666312 -243.707859) (xy 369.703035 -243.671136) (xy 369.745051 -243.64061)
			(xy 369.791325 -243.617032) (xy 369.840718 -243.600984) (xy 369.892013 -243.592859) (xy 369.943947 -243.592859)
			(xy 369.995242 -243.600984) (xy 370.044635 -243.617032) (xy 370.090909 -243.64061) (xy 370.132925 -243.671136)
			(xy 370.169648 -243.707859) (xy 370.200174 -243.749875) (xy 370.223752 -243.796149) (xy 370.2398 -243.845542)
			(xy 370.247925 -243.896837) (xy 370.248434 -243.922804) (xy 370.247925 -243.948771) (xy 370.527835 -243.948771)
			(xy 370.527835 -243.896837) (xy 370.53596 -243.845542) (xy 370.552008 -243.796149) (xy 370.575586 -243.749875)
			(xy 370.606112 -243.707859) (xy 370.642835 -243.671136) (xy 370.684851 -243.64061) (xy 370.731125 -243.617032)
			(xy 370.780518 -243.600984) (xy 370.831813 -243.592859) (xy 370.883747 -243.592859) (xy 370.935042 -243.600984)
			(xy 370.984435 -243.617032) (xy 371.030709 -243.64061) (xy 371.072725 -243.671136) (xy 371.109448 -243.707859)
			(xy 371.139974 -243.749875) (xy 371.163552 -243.796149) (xy 371.1796 -243.845542) (xy 371.187725 -243.896837)
			(xy 371.188234 -243.922804) (xy 371.187725 -243.948771) (xy 371.467889 -243.948771) (xy 371.467889 -243.896837)
			(xy 371.476014 -243.845542) (xy 371.492062 -243.796149) (xy 371.51564 -243.749875) (xy 371.546166 -243.707859)
			(xy 371.582889 -243.671136) (xy 371.624905 -243.64061) (xy 371.671179 -243.617032) (xy 371.720572 -243.600984)
			(xy 371.771867 -243.592859) (xy 371.823801 -243.592859) (xy 371.875096 -243.600984) (xy 371.924489 -243.617032)
			(xy 371.970763 -243.64061) (xy 372.012779 -243.671136) (xy 372.049502 -243.707859) (xy 372.080028 -243.749875)
			(xy 372.103606 -243.796149) (xy 372.119654 -243.845542) (xy 372.127779 -243.896837) (xy 372.128288 -243.922804)
			(xy 372.127779 -243.948771) (xy 372.407689 -243.948771) (xy 372.407689 -243.896837) (xy 372.415814 -243.845542)
			(xy 372.431862 -243.796149) (xy 372.45544 -243.749875) (xy 372.485966 -243.707859) (xy 372.522689 -243.671136)
			(xy 372.564705 -243.64061) (xy 372.610979 -243.617032) (xy 372.660372 -243.600984) (xy 372.711667 -243.592859)
			(xy 372.763601 -243.592859) (xy 372.814896 -243.600984) (xy 372.864289 -243.617032) (xy 372.910563 -243.64061)
			(xy 372.952579 -243.671136) (xy 372.989302 -243.707859) (xy 373.019828 -243.749875) (xy 373.043406 -243.796149)
			(xy 373.059454 -243.845542) (xy 373.067579 -243.896837) (xy 373.068088 -243.922804) (xy 373.067579 -243.948771)
			(xy 373.347489 -243.948771) (xy 373.347489 -243.896837) (xy 373.355614 -243.845542) (xy 373.371662 -243.796149)
			(xy 373.39524 -243.749875) (xy 373.425766 -243.707859) (xy 373.462489 -243.671136) (xy 373.504505 -243.64061)
			(xy 373.550779 -243.617032) (xy 373.600172 -243.600984) (xy 373.651467 -243.592859) (xy 373.703401 -243.592859)
			(xy 373.754696 -243.600984) (xy 373.804089 -243.617032) (xy 373.850363 -243.64061) (xy 373.892379 -243.671136)
			(xy 373.929102 -243.707859) (xy 373.959628 -243.749875) (xy 373.983206 -243.796149) (xy 373.999254 -243.845542)
			(xy 374.007379 -243.896837) (xy 374.007888 -243.922804) (xy 374.007379 -243.948771) (xy 374.287289 -243.948771)
			(xy 374.287289 -243.896837) (xy 374.295414 -243.845542) (xy 374.311462 -243.796149) (xy 374.33504 -243.749875)
			(xy 374.365566 -243.707859) (xy 374.402289 -243.671136) (xy 374.444305 -243.64061) (xy 374.490579 -243.617032)
			(xy 374.539972 -243.600984) (xy 374.591267 -243.592859) (xy 374.643201 -243.592859) (xy 374.694496 -243.600984)
			(xy 374.743889 -243.617032) (xy 374.790163 -243.64061) (xy 374.832179 -243.671136) (xy 374.868902 -243.707859)
			(xy 374.899428 -243.749875) (xy 374.923006 -243.796149) (xy 374.939054 -243.845542) (xy 374.947179 -243.896837)
			(xy 374.947688 -243.922804) (xy 374.947179 -243.948771) (xy 375.227089 -243.948771) (xy 375.227089 -243.896837)
			(xy 375.235214 -243.845542) (xy 375.251262 -243.796149) (xy 375.27484 -243.749875) (xy 375.305366 -243.707859)
			(xy 375.342089 -243.671136) (xy 375.384105 -243.64061) (xy 375.430379 -243.617032) (xy 375.479772 -243.600984)
			(xy 375.531067 -243.592859) (xy 375.583001 -243.592859) (xy 375.634296 -243.600984) (xy 375.683689 -243.617032)
			(xy 375.729963 -243.64061) (xy 375.771979 -243.671136) (xy 375.808702 -243.707859) (xy 375.839228 -243.749875)
			(xy 375.862806 -243.796149) (xy 375.878854 -243.845542) (xy 375.886979 -243.896837) (xy 375.887488 -243.922804)
			(xy 375.886979 -243.948771) (xy 375.878854 -244.000066) (xy 375.862806 -244.049459) (xy 375.839228 -244.095733)
			(xy 375.808702 -244.137749) (xy 375.771979 -244.174472) (xy 375.729963 -244.204998) (xy 375.683689 -244.228576)
			(xy 375.634296 -244.244624) (xy 375.583001 -244.252749) (xy 375.531067 -244.252749) (xy 375.479772 -244.244624)
			(xy 375.430379 -244.228576) (xy 375.384105 -244.204998) (xy 375.342089 -244.174472) (xy 375.305366 -244.137749)
			(xy 375.27484 -244.095733) (xy 375.251262 -244.049459) (xy 375.235214 -244.000066) (xy 375.227089 -243.948771)
			(xy 374.947179 -243.948771) (xy 374.939054 -244.000066) (xy 374.923006 -244.049459) (xy 374.899428 -244.095733)
			(xy 374.868902 -244.137749) (xy 374.832179 -244.174472) (xy 374.790163 -244.204998) (xy 374.743889 -244.228576)
			(xy 374.694496 -244.244624) (xy 374.643201 -244.252749) (xy 374.591267 -244.252749) (xy 374.539972 -244.244624)
			(xy 374.490579 -244.228576) (xy 374.444305 -244.204998) (xy 374.402289 -244.174472) (xy 374.365566 -244.137749)
			(xy 374.33504 -244.095733) (xy 374.311462 -244.049459) (xy 374.295414 -244.000066) (xy 374.287289 -243.948771)
			(xy 374.007379 -243.948771) (xy 373.999254 -244.000066) (xy 373.983206 -244.049459) (xy 373.959628 -244.095733)
			(xy 373.929102 -244.137749) (xy 373.892379 -244.174472) (xy 373.850363 -244.204998) (xy 373.804089 -244.228576)
			(xy 373.754696 -244.244624) (xy 373.703401 -244.252749) (xy 373.651467 -244.252749) (xy 373.600172 -244.244624)
			(xy 373.550779 -244.228576) (xy 373.504505 -244.204998) (xy 373.462489 -244.174472) (xy 373.425766 -244.137749)
			(xy 373.39524 -244.095733) (xy 373.371662 -244.049459) (xy 373.355614 -244.000066) (xy 373.347489 -243.948771)
			(xy 373.067579 -243.948771) (xy 373.059454 -244.000066) (xy 373.043406 -244.049459) (xy 373.019828 -244.095733)
			(xy 372.989302 -244.137749) (xy 372.952579 -244.174472) (xy 372.910563 -244.204998) (xy 372.864289 -244.228576)
			(xy 372.814896 -244.244624) (xy 372.763601 -244.252749) (xy 372.711667 -244.252749) (xy 372.660372 -244.244624)
			(xy 372.610979 -244.228576) (xy 372.564705 -244.204998) (xy 372.522689 -244.174472) (xy 372.485966 -244.137749)
			(xy 372.45544 -244.095733) (xy 372.431862 -244.049459) (xy 372.415814 -244.000066) (xy 372.407689 -243.948771)
			(xy 372.127779 -243.948771) (xy 372.119654 -244.000066) (xy 372.103606 -244.049459) (xy 372.080028 -244.095733)
			(xy 372.049502 -244.137749) (xy 372.012779 -244.174472) (xy 371.970763 -244.204998) (xy 371.924489 -244.228576)
			(xy 371.875096 -244.244624) (xy 371.823801 -244.252749) (xy 371.771867 -244.252749) (xy 371.720572 -244.244624)
			(xy 371.671179 -244.228576) (xy 371.624905 -244.204998) (xy 371.582889 -244.174472) (xy 371.546166 -244.137749)
			(xy 371.51564 -244.095733) (xy 371.492062 -244.049459) (xy 371.476014 -244.000066) (xy 371.467889 -243.948771)
			(xy 371.187725 -243.948771) (xy 371.1796 -244.000066) (xy 371.163552 -244.049459) (xy 371.139974 -244.095733)
			(xy 371.109448 -244.137749) (xy 371.072725 -244.174472) (xy 371.030709 -244.204998) (xy 370.984435 -244.228576)
			(xy 370.935042 -244.244624) (xy 370.883747 -244.252749) (xy 370.831813 -244.252749) (xy 370.780518 -244.244624)
			(xy 370.731125 -244.228576) (xy 370.684851 -244.204998) (xy 370.642835 -244.174472) (xy 370.606112 -244.137749)
			(xy 370.575586 -244.095733) (xy 370.552008 -244.049459) (xy 370.53596 -244.000066) (xy 370.527835 -243.948771)
			(xy 370.247925 -243.948771) (xy 370.2398 -244.000066) (xy 370.223752 -244.049459) (xy 370.200174 -244.095733)
			(xy 370.169648 -244.137749) (xy 370.132925 -244.174472) (xy 370.090909 -244.204998) (xy 370.044635 -244.228576)
			(xy 369.995242 -244.244624) (xy 369.943947 -244.252749) (xy 369.892013 -244.252749) (xy 369.840718 -244.244624)
			(xy 369.791325 -244.228576) (xy 369.745051 -244.204998) (xy 369.703035 -244.174472) (xy 369.666312 -244.137749)
			(xy 369.635786 -244.095733) (xy 369.612208 -244.049459) (xy 369.59616 -244.000066) (xy 369.588035 -243.948771)
			(xy 369.386104 -243.948771) (xy 369.386104 -244.306344) (xy 369.386638 -244.321392) (xy 369.395398 -244.350183)
			(xy 369.412174 -244.375168) (xy 369.435507 -244.394175) (xy 369.463369 -244.405551) (xy 369.478306 -244.407436)
			(xy 369.503903 -244.410279) (xy 369.553835 -244.422881) (xy 369.60121 -244.443075) (xy 369.644879 -244.470372)
			(xy 369.683786 -244.504111) (xy 369.716991 -244.543475) (xy 369.743689 -244.587513) (xy 369.763234 -244.635159)
			(xy 369.775153 -244.685259) (xy 369.779158 -244.736602) (xy 369.77715 -244.762333) (xy 370.057935 -244.762333)
			(xy 370.057935 -244.710399) (xy 370.06606 -244.659104) (xy 370.082108 -244.609711) (xy 370.105686 -244.563437)
			(xy 370.136212 -244.521421) (xy 370.172935 -244.484698) (xy 370.214951 -244.454172) (xy 370.261225 -244.430594)
			(xy 370.310618 -244.414546) (xy 370.361913 -244.406421) (xy 370.413847 -244.406421) (xy 370.465142 -244.414546)
			(xy 370.514535 -244.430594) (xy 370.560809 -244.454172) (xy 370.602825 -244.484698) (xy 370.639548 -244.521421)
			(xy 370.670074 -244.563437) (xy 370.693652 -244.609711) (xy 370.7097 -244.659104) (xy 370.717825 -244.710399)
			(xy 370.718334 -244.736366) (xy 370.717825 -244.762333) (xy 370.717785 -244.762587) (xy 370.997735 -244.762587)
			(xy 370.997735 -244.710653) (xy 371.00586 -244.659358) (xy 371.021908 -244.609965) (xy 371.045486 -244.563691)
			(xy 371.076012 -244.521675) (xy 371.112735 -244.484952) (xy 371.154751 -244.454426) (xy 371.201025 -244.430848)
			(xy 371.250418 -244.4148) (xy 371.301713 -244.406675) (xy 371.353647 -244.406675) (xy 371.404942 -244.4148)
			(xy 371.454335 -244.430848) (xy 371.500609 -244.454426) (xy 371.542625 -244.484952) (xy 371.579348 -244.521675)
			(xy 371.609874 -244.563691) (xy 371.633452 -244.609965) (xy 371.6495 -244.659358) (xy 371.657625 -244.710653)
			(xy 371.658134 -244.73662) (xy 371.657625 -244.762587) (xy 371.937535 -244.762587) (xy 371.937535 -244.710653)
			(xy 371.94566 -244.659358) (xy 371.961708 -244.609965) (xy 371.985286 -244.563691) (xy 372.015812 -244.521675)
			(xy 372.052535 -244.484952) (xy 372.094551 -244.454426) (xy 372.140825 -244.430848) (xy 372.190218 -244.4148)
			(xy 372.241513 -244.406675) (xy 372.293447 -244.406675) (xy 372.344742 -244.4148) (xy 372.394135 -244.430848)
			(xy 372.440409 -244.454426) (xy 372.482425 -244.484952) (xy 372.519148 -244.521675) (xy 372.549674 -244.563691)
			(xy 372.573252 -244.609965) (xy 372.5893 -244.659358) (xy 372.597425 -244.710653) (xy 372.597934 -244.73662)
			(xy 372.597425 -244.762587) (xy 372.877589 -244.762587) (xy 372.877589 -244.710653) (xy 372.885714 -244.659358)
			(xy 372.901762 -244.609965) (xy 372.92534 -244.563691) (xy 372.955866 -244.521675) (xy 372.992589 -244.484952)
			(xy 373.034605 -244.454426) (xy 373.080879 -244.430848) (xy 373.130272 -244.4148) (xy 373.181567 -244.406675)
			(xy 373.233501 -244.406675) (xy 373.284796 -244.4148) (xy 373.334189 -244.430848) (xy 373.380463 -244.454426)
			(xy 373.422479 -244.484952) (xy 373.459202 -244.521675) (xy 373.489728 -244.563691) (xy 373.513306 -244.609965)
			(xy 373.529354 -244.659358) (xy 373.537479 -244.710653) (xy 373.537988 -244.73662) (xy 373.537479 -244.762587)
			(xy 373.817135 -244.762587) (xy 373.817135 -244.710653) (xy 373.82526 -244.659358) (xy 373.841308 -244.609965)
			(xy 373.864886 -244.563691) (xy 373.895412 -244.521675) (xy 373.932135 -244.484952) (xy 373.974151 -244.454426)
			(xy 374.020425 -244.430848) (xy 374.069818 -244.4148) (xy 374.121113 -244.406675) (xy 374.173047 -244.406675)
			(xy 374.224342 -244.4148) (xy 374.273735 -244.430848) (xy 374.320009 -244.454426) (xy 374.362025 -244.484952)
			(xy 374.398748 -244.521675) (xy 374.429274 -244.563691) (xy 374.452852 -244.609965) (xy 374.4689 -244.659358)
			(xy 374.477025 -244.710653) (xy 374.477534 -244.73662) (xy 374.477025 -244.762587) (xy 374.757189 -244.762587)
			(xy 374.757189 -244.710653) (xy 374.765314 -244.659358) (xy 374.781362 -244.609965) (xy 374.80494 -244.563691)
			(xy 374.835466 -244.521675) (xy 374.872189 -244.484952) (xy 374.914205 -244.454426) (xy 374.960479 -244.430848)
			(xy 375.009872 -244.4148) (xy 375.061167 -244.406675) (xy 375.113101 -244.406675) (xy 375.164396 -244.4148)
			(xy 375.213789 -244.430848) (xy 375.260063 -244.454426) (xy 375.302079 -244.484952) (xy 375.338802 -244.521675)
			(xy 375.369328 -244.563691) (xy 375.392906 -244.609965) (xy 375.408954 -244.659358) (xy 375.417079 -244.710653)
			(xy 375.417588 -244.73662) (xy 375.417079 -244.762587) (xy 375.408954 -244.813882) (xy 375.392906 -244.863275)
			(xy 375.369328 -244.909549) (xy 375.338802 -244.951565) (xy 375.302079 -244.988288) (xy 375.260063 -245.018814)
			(xy 375.213789 -245.042392) (xy 375.164396 -245.05844) (xy 375.113101 -245.066565) (xy 375.061167 -245.066565)
			(xy 375.009872 -245.05844) (xy 374.960479 -245.042392) (xy 374.914205 -245.018814) (xy 374.872189 -244.988288)
			(xy 374.835466 -244.951565) (xy 374.80494 -244.909549) (xy 374.781362 -244.863275) (xy 374.765314 -244.813882)
			(xy 374.757189 -244.762587) (xy 374.477025 -244.762587) (xy 374.4689 -244.813882) (xy 374.452852 -244.863275)
			(xy 374.429274 -244.909549) (xy 374.398748 -244.951565) (xy 374.362025 -244.988288) (xy 374.320009 -245.018814)
			(xy 374.273735 -245.042392) (xy 374.224342 -245.05844) (xy 374.173047 -245.066565) (xy 374.121113 -245.066565)
			(xy 374.069818 -245.05844) (xy 374.020425 -245.042392) (xy 373.974151 -245.018814) (xy 373.932135 -244.988288)
			(xy 373.895412 -244.951565) (xy 373.864886 -244.909549) (xy 373.841308 -244.863275) (xy 373.82526 -244.813882)
			(xy 373.817135 -244.762587) (xy 373.537479 -244.762587) (xy 373.529354 -244.813882) (xy 373.513306 -244.863275)
			(xy 373.489728 -244.909549) (xy 373.459202 -244.951565) (xy 373.422479 -244.988288) (xy 373.380463 -245.018814)
			(xy 373.334189 -245.042392) (xy 373.284796 -245.05844) (xy 373.233501 -245.066565) (xy 373.181567 -245.066565)
			(xy 373.130272 -245.05844) (xy 373.080879 -245.042392) (xy 373.034605 -245.018814) (xy 372.992589 -244.988288)
			(xy 372.955866 -244.951565) (xy 372.92534 -244.909549) (xy 372.901762 -244.863275) (xy 372.885714 -244.813882)
			(xy 372.877589 -244.762587) (xy 372.597425 -244.762587) (xy 372.5893 -244.813882) (xy 372.573252 -244.863275)
			(xy 372.549674 -244.909549) (xy 372.519148 -244.951565) (xy 372.482425 -244.988288) (xy 372.440409 -245.018814)
			(xy 372.394135 -245.042392) (xy 372.344742 -245.05844) (xy 372.293447 -245.066565) (xy 372.241513 -245.066565)
			(xy 372.190218 -245.05844) (xy 372.140825 -245.042392) (xy 372.094551 -245.018814) (xy 372.052535 -244.988288)
			(xy 372.015812 -244.951565) (xy 371.985286 -244.909549) (xy 371.961708 -244.863275) (xy 371.94566 -244.813882)
			(xy 371.937535 -244.762587) (xy 371.657625 -244.762587) (xy 371.6495 -244.813882) (xy 371.633452 -244.863275)
			(xy 371.609874 -244.909549) (xy 371.579348 -244.951565) (xy 371.542625 -244.988288) (xy 371.500609 -245.018814)
			(xy 371.454335 -245.042392) (xy 371.404942 -245.05844) (xy 371.353647 -245.066565) (xy 371.301713 -245.066565)
			(xy 371.250418 -245.05844) (xy 371.201025 -245.042392) (xy 371.154751 -245.018814) (xy 371.112735 -244.988288)
			(xy 371.076012 -244.951565) (xy 371.045486 -244.909549) (xy 371.021908 -244.863275) (xy 371.00586 -244.813882)
			(xy 370.997735 -244.762587) (xy 370.717785 -244.762587) (xy 370.7097 -244.813628) (xy 370.693652 -244.863021)
			(xy 370.670074 -244.909295) (xy 370.639548 -244.951311) (xy 370.602825 -244.988034) (xy 370.560809 -245.01856)
			(xy 370.514535 -245.042138) (xy 370.465142 -245.058186) (xy 370.413847 -245.066311) (xy 370.361913 -245.066311)
			(xy 370.310618 -245.058186) (xy 370.261225 -245.042138) (xy 370.214951 -245.01856) (xy 370.172935 -244.988034)
			(xy 370.136212 -244.951311) (xy 370.105686 -244.909295) (xy 370.082108 -244.863021) (xy 370.06606 -244.813628)
			(xy 370.057935 -244.762333) (xy 369.77715 -244.762333) (xy 369.775152 -244.787944) (xy 369.763232 -244.838045)
			(xy 369.743687 -244.88569) (xy 369.716989 -244.929728) (xy 369.683784 -244.969092) (xy 369.644876 -245.00283)
			(xy 369.601206 -245.030127) (xy 369.553832 -245.05032) (xy 369.503899 -245.062922) (xy 369.478306 -245.065804)
			(xy 369.463388 -245.067744) (xy 369.435563 -245.079142) (xy 369.412258 -245.098143) (xy 369.395491 -245.123103)
			(xy 369.386713 -245.151862) (xy 369.386104 -245.166896) (xy 369.386104 -245.576657) (xy 369.588289 -245.576657)
			(xy 369.588289 -245.524723) (xy 369.596414 -245.473428) (xy 369.612462 -245.424035) (xy 369.63604 -245.377761)
			(xy 369.666566 -245.335745) (xy 369.703289 -245.299022) (xy 369.745305 -245.268496) (xy 369.791579 -245.244918)
			(xy 369.840972 -245.22887) (xy 369.892267 -245.220745) (xy 369.944201 -245.220745) (xy 369.995496 -245.22887)
			(xy 370.044889 -245.244918) (xy 370.091163 -245.268496) (xy 370.133179 -245.299022) (xy 370.169902 -245.335745)
			(xy 370.200428 -245.377761) (xy 370.224006 -245.424035) (xy 370.240054 -245.473428) (xy 370.248179 -245.524723)
			(xy 370.248688 -245.55069) (xy 370.248179 -245.576657) (xy 370.528089 -245.576657) (xy 370.528089 -245.524723)
			(xy 370.536214 -245.473428) (xy 370.552262 -245.424035) (xy 370.57584 -245.377761) (xy 370.606366 -245.335745)
			(xy 370.643089 -245.299022) (xy 370.685105 -245.268496) (xy 370.731379 -245.244918) (xy 370.780772 -245.22887)
			(xy 370.832067 -245.220745) (xy 370.884001 -245.220745) (xy 370.935296 -245.22887) (xy 370.984689 -245.244918)
			(xy 371.030963 -245.268496) (xy 371.072979 -245.299022) (xy 371.109702 -245.335745) (xy 371.140228 -245.377761)
			(xy 371.163806 -245.424035) (xy 371.179854 -245.473428) (xy 371.187979 -245.524723) (xy 371.188488 -245.55069)
			(xy 371.187979 -245.576657) (xy 371.467889 -245.576657) (xy 371.467889 -245.524723) (xy 371.476014 -245.473428)
			(xy 371.492062 -245.424035) (xy 371.51564 -245.377761) (xy 371.546166 -245.335745) (xy 371.582889 -245.299022)
			(xy 371.624905 -245.268496) (xy 371.671179 -245.244918) (xy 371.720572 -245.22887) (xy 371.771867 -245.220745)
			(xy 371.823801 -245.220745) (xy 371.875096 -245.22887) (xy 371.924489 -245.244918) (xy 371.970763 -245.268496)
			(xy 372.012779 -245.299022) (xy 372.049502 -245.335745) (xy 372.080028 -245.377761) (xy 372.103606 -245.424035)
			(xy 372.119654 -245.473428) (xy 372.127779 -245.524723) (xy 372.128288 -245.55069) (xy 372.127779 -245.576657)
			(xy 372.407689 -245.576657) (xy 372.407689 -245.524723) (xy 372.415814 -245.473428) (xy 372.431862 -245.424035)
			(xy 372.45544 -245.377761) (xy 372.485966 -245.335745) (xy 372.522689 -245.299022) (xy 372.564705 -245.268496)
			(xy 372.610979 -245.244918) (xy 372.660372 -245.22887) (xy 372.711667 -245.220745) (xy 372.763601 -245.220745)
			(xy 372.814896 -245.22887) (xy 372.864289 -245.244918) (xy 372.910563 -245.268496) (xy 372.952579 -245.299022)
			(xy 372.989302 -245.335745) (xy 373.019828 -245.377761) (xy 373.043406 -245.424035) (xy 373.059454 -245.473428)
			(xy 373.067579 -245.524723) (xy 373.068088 -245.55069) (xy 373.067579 -245.576657) (xy 373.347235 -245.576657)
			(xy 373.347235 -245.524723) (xy 373.35536 -245.473428) (xy 373.371408 -245.424035) (xy 373.394986 -245.377761)
			(xy 373.425512 -245.335745) (xy 373.462235 -245.299022) (xy 373.504251 -245.268496) (xy 373.550525 -245.244918)
			(xy 373.599918 -245.22887) (xy 373.651213 -245.220745) (xy 373.703147 -245.220745) (xy 373.754442 -245.22887)
			(xy 373.803835 -245.244918) (xy 373.850109 -245.268496) (xy 373.892125 -245.299022) (xy 373.928848 -245.335745)
			(xy 373.959374 -245.377761) (xy 373.982952 -245.424035) (xy 373.999 -245.473428) (xy 374.007125 -245.524723)
			(xy 374.007634 -245.55069) (xy 374.007125 -245.576657) (xy 374.287289 -245.576657) (xy 374.287289 -245.524723)
			(xy 374.295414 -245.473428) (xy 374.311462 -245.424035) (xy 374.33504 -245.377761) (xy 374.365566 -245.335745)
			(xy 374.402289 -245.299022) (xy 374.444305 -245.268496) (xy 374.490579 -245.244918) (xy 374.539972 -245.22887)
			(xy 374.591267 -245.220745) (xy 374.643201 -245.220745) (xy 374.694496 -245.22887) (xy 374.743889 -245.244918)
			(xy 374.790163 -245.268496) (xy 374.832179 -245.299022) (xy 374.868902 -245.335745) (xy 374.899428 -245.377761)
			(xy 374.923006 -245.424035) (xy 374.939054 -245.473428) (xy 374.947179 -245.524723) (xy 374.947688 -245.55069)
			(xy 374.947179 -245.576657) (xy 374.939054 -245.627952) (xy 374.923006 -245.677345) (xy 374.899428 -245.723619)
			(xy 374.868902 -245.765635) (xy 374.832179 -245.802358) (xy 374.790163 -245.832884) (xy 374.743889 -245.856462)
			(xy 374.694496 -245.87251) (xy 374.643201 -245.880635) (xy 374.591267 -245.880635) (xy 374.539972 -245.87251)
			(xy 374.490579 -245.856462) (xy 374.444305 -245.832884) (xy 374.402289 -245.802358) (xy 374.365566 -245.765635)
			(xy 374.33504 -245.723619) (xy 374.311462 -245.677345) (xy 374.295414 -245.627952) (xy 374.287289 -245.576657)
			(xy 374.007125 -245.576657) (xy 373.999 -245.627952) (xy 373.982952 -245.677345) (xy 373.959374 -245.723619)
			(xy 373.928848 -245.765635) (xy 373.892125 -245.802358) (xy 373.850109 -245.832884) (xy 373.803835 -245.856462)
			(xy 373.754442 -245.87251) (xy 373.703147 -245.880635) (xy 373.651213 -245.880635) (xy 373.599918 -245.87251)
			(xy 373.550525 -245.856462) (xy 373.504251 -245.832884) (xy 373.462235 -245.802358) (xy 373.425512 -245.765635)
			(xy 373.394986 -245.723619) (xy 373.371408 -245.677345) (xy 373.35536 -245.627952) (xy 373.347235 -245.576657)
			(xy 373.067579 -245.576657) (xy 373.059454 -245.627952) (xy 373.043406 -245.677345) (xy 373.019828 -245.723619)
			(xy 372.989302 -245.765635) (xy 372.952579 -245.802358) (xy 372.910563 -245.832884) (xy 372.864289 -245.856462)
			(xy 372.814896 -245.87251) (xy 372.763601 -245.880635) (xy 372.711667 -245.880635) (xy 372.660372 -245.87251)
			(xy 372.610979 -245.856462) (xy 372.564705 -245.832884) (xy 372.522689 -245.802358) (xy 372.485966 -245.765635)
			(xy 372.45544 -245.723619) (xy 372.431862 -245.677345) (xy 372.415814 -245.627952) (xy 372.407689 -245.576657)
			(xy 372.127779 -245.576657) (xy 372.119654 -245.627952) (xy 372.103606 -245.677345) (xy 372.080028 -245.723619)
			(xy 372.049502 -245.765635) (xy 372.012779 -245.802358) (xy 371.970763 -245.832884) (xy 371.924489 -245.856462)
			(xy 371.875096 -245.87251) (xy 371.823801 -245.880635) (xy 371.771867 -245.880635) (xy 371.720572 -245.87251)
			(xy 371.671179 -245.856462) (xy 371.624905 -245.832884) (xy 371.582889 -245.802358) (xy 371.546166 -245.765635)
			(xy 371.51564 -245.723619) (xy 371.492062 -245.677345) (xy 371.476014 -245.627952) (xy 371.467889 -245.576657)
			(xy 371.187979 -245.576657) (xy 371.179854 -245.627952) (xy 371.163806 -245.677345) (xy 371.140228 -245.723619)
			(xy 371.109702 -245.765635) (xy 371.072979 -245.802358) (xy 371.030963 -245.832884) (xy 370.984689 -245.856462)
			(xy 370.935296 -245.87251) (xy 370.884001 -245.880635) (xy 370.832067 -245.880635) (xy 370.780772 -245.87251)
			(xy 370.731379 -245.856462) (xy 370.685105 -245.832884) (xy 370.643089 -245.802358) (xy 370.606366 -245.765635)
			(xy 370.57584 -245.723619) (xy 370.552262 -245.677345) (xy 370.536214 -245.627952) (xy 370.528089 -245.576657)
			(xy 370.248179 -245.576657) (xy 370.240054 -245.627952) (xy 370.224006 -245.677345) (xy 370.200428 -245.723619)
			(xy 370.169902 -245.765635) (xy 370.133179 -245.802358) (xy 370.091163 -245.832884) (xy 370.044889 -245.856462)
			(xy 369.995496 -245.87251) (xy 369.944201 -245.880635) (xy 369.892267 -245.880635) (xy 369.840972 -245.87251)
			(xy 369.791579 -245.856462) (xy 369.745305 -245.832884) (xy 369.703289 -245.802358) (xy 369.666566 -245.765635)
			(xy 369.63604 -245.723619) (xy 369.612462 -245.677345) (xy 369.596414 -245.627952) (xy 369.588289 -245.576657)
			(xy 369.386104 -245.576657) (xy 369.386104 -245.93423) (xy 369.386641 -245.949299) (xy 369.39543 -245.978127)
			(xy 369.412263 -246.003125) (xy 369.435667 -246.022112) (xy 369.4636 -246.033428) (xy 369.47856 -246.035322)
			(xy 369.504155 -246.038169) (xy 369.554083 -246.050777) (xy 369.601452 -246.070976) (xy 369.645116 -246.098276)
			(xy 369.684019 -246.132017) (xy 369.717219 -246.171382) (xy 369.743912 -246.215419) (xy 369.763455 -246.263063)
			(xy 369.775372 -246.313161) (xy 369.779377 -246.364501) (xy 369.777351 -246.390473) (xy 370.058189 -246.390473)
			(xy 370.058189 -246.338539) (xy 370.066314 -246.287244) (xy 370.082362 -246.237851) (xy 370.10594 -246.191577)
			(xy 370.136466 -246.149561) (xy 370.173189 -246.112838) (xy 370.215205 -246.082312) (xy 370.261479 -246.058734)
			(xy 370.310872 -246.042686) (xy 370.362167 -246.034561) (xy 370.414101 -246.034561) (xy 370.465396 -246.042686)
			(xy 370.514789 -246.058734) (xy 370.561063 -246.082312) (xy 370.603079 -246.112838) (xy 370.639802 -246.149561)
			(xy 370.670328 -246.191577) (xy 370.693906 -246.237851) (xy 370.709954 -246.287244) (xy 370.718079 -246.338539)
			(xy 370.718588 -246.364506) (xy 370.718079 -246.390473) (xy 370.997735 -246.390473) (xy 370.997735 -246.338539)
			(xy 371.00586 -246.287244) (xy 371.021908 -246.237851) (xy 371.045486 -246.191577) (xy 371.076012 -246.149561)
			(xy 371.112735 -246.112838) (xy 371.154751 -246.082312) (xy 371.201025 -246.058734) (xy 371.250418 -246.042686)
			(xy 371.301713 -246.034561) (xy 371.353647 -246.034561) (xy 371.404942 -246.042686) (xy 371.454335 -246.058734)
			(xy 371.500609 -246.082312) (xy 371.542625 -246.112838) (xy 371.579348 -246.149561) (xy 371.609874 -246.191577)
			(xy 371.633452 -246.237851) (xy 371.6495 -246.287244) (xy 371.657625 -246.338539) (xy 371.658134 -246.364506)
			(xy 371.657625 -246.390473) (xy 371.937535 -246.390473) (xy 371.937535 -246.338539) (xy 371.94566 -246.287244)
			(xy 371.961708 -246.237851) (xy 371.985286 -246.191577) (xy 372.015812 -246.149561) (xy 372.052535 -246.112838)
			(xy 372.094551 -246.082312) (xy 372.140825 -246.058734) (xy 372.190218 -246.042686) (xy 372.241513 -246.034561)
			(xy 372.293447 -246.034561) (xy 372.344742 -246.042686) (xy 372.394135 -246.058734) (xy 372.440409 -246.082312)
			(xy 372.482425 -246.112838) (xy 372.519148 -246.149561) (xy 372.549674 -246.191577) (xy 372.573252 -246.237851)
			(xy 372.5893 -246.287244) (xy 372.597425 -246.338539) (xy 372.597934 -246.364506) (xy 372.597425 -246.390473)
			(xy 372.877335 -246.390473) (xy 372.877335 -246.338539) (xy 372.88546 -246.287244) (xy 372.901508 -246.237851)
			(xy 372.925086 -246.191577) (xy 372.955612 -246.149561) (xy 372.992335 -246.112838) (xy 373.034351 -246.082312)
			(xy 373.080625 -246.058734) (xy 373.130018 -246.042686) (xy 373.181313 -246.034561) (xy 373.233247 -246.034561)
			(xy 373.284542 -246.042686) (xy 373.333935 -246.058734) (xy 373.380209 -246.082312) (xy 373.422225 -246.112838)
			(xy 373.458948 -246.149561) (xy 373.489474 -246.191577) (xy 373.513052 -246.237851) (xy 373.5291 -246.287244)
			(xy 373.537225 -246.338539) (xy 373.537734 -246.364506) (xy 373.537225 -246.390473) (xy 373.5291 -246.441768)
			(xy 373.513052 -246.491161) (xy 373.489474 -246.537435) (xy 373.458948 -246.579451) (xy 373.422225 -246.616174)
			(xy 373.380209 -246.6467) (xy 373.333935 -246.670278) (xy 373.284542 -246.686326) (xy 373.233247 -246.694451)
			(xy 373.181313 -246.694451) (xy 373.130018 -246.686326) (xy 373.080625 -246.670278) (xy 373.034351 -246.6467)
			(xy 372.992335 -246.616174) (xy 372.955612 -246.579451) (xy 372.925086 -246.537435) (xy 372.901508 -246.491161)
			(xy 372.88546 -246.441768) (xy 372.877335 -246.390473) (xy 372.597425 -246.390473) (xy 372.5893 -246.441768)
			(xy 372.573252 -246.491161) (xy 372.549674 -246.537435) (xy 372.519148 -246.579451) (xy 372.482425 -246.616174)
			(xy 372.440409 -246.6467) (xy 372.394135 -246.670278) (xy 372.344742 -246.686326) (xy 372.293447 -246.694451)
			(xy 372.241513 -246.694451) (xy 372.190218 -246.686326) (xy 372.140825 -246.670278) (xy 372.094551 -246.6467)
			(xy 372.052535 -246.616174) (xy 372.015812 -246.579451) (xy 371.985286 -246.537435) (xy 371.961708 -246.491161)
			(xy 371.94566 -246.441768) (xy 371.937535 -246.390473) (xy 371.657625 -246.390473) (xy 371.6495 -246.441768)
			(xy 371.633452 -246.491161) (xy 371.609874 -246.537435) (xy 371.579348 -246.579451) (xy 371.542625 -246.616174)
			(xy 371.500609 -246.6467) (xy 371.454335 -246.670278) (xy 371.404942 -246.686326) (xy 371.353647 -246.694451)
			(xy 371.301713 -246.694451) (xy 371.250418 -246.686326) (xy 371.201025 -246.670278) (xy 371.154751 -246.6467)
			(xy 371.112735 -246.616174) (xy 371.076012 -246.579451) (xy 371.045486 -246.537435) (xy 371.021908 -246.491161)
			(xy 371.00586 -246.441768) (xy 370.997735 -246.390473) (xy 370.718079 -246.390473) (xy 370.709954 -246.441768)
			(xy 370.693906 -246.491161) (xy 370.670328 -246.537435) (xy 370.639802 -246.579451) (xy 370.603079 -246.616174)
			(xy 370.561063 -246.6467) (xy 370.514789 -246.670278) (xy 370.465396 -246.686326) (xy 370.414101 -246.694451)
			(xy 370.362167 -246.694451) (xy 370.310872 -246.686326) (xy 370.261479 -246.670278) (xy 370.215205 -246.6467)
			(xy 370.173189 -246.616174) (xy 370.136466 -246.579451) (xy 370.10594 -246.537435) (xy 370.082362 -246.491161)
			(xy 370.066314 -246.441768) (xy 370.058189 -246.390473) (xy 369.777351 -246.390473) (xy 369.775372 -246.41584)
			(xy 369.763454 -246.465938) (xy 369.743912 -246.513582) (xy 369.717218 -246.557619) (xy 369.684018 -246.596984)
			(xy 369.645116 -246.630725) (xy 369.601451 -246.658024) (xy 369.554082 -246.678223) (xy 369.504154 -246.690832)
			(xy 369.47856 -246.69369) (xy 369.463609 -246.695596) (xy 369.435706 -246.706952) (xy 369.41232 -246.725942)
			(xy 369.395478 -246.75092) (xy 369.386642 -246.77972) (xy 369.386104 -246.794782) (xy 369.386104 -247.204289)
			(xy 369.588289 -247.204289) (xy 369.588289 -247.152355) (xy 369.596414 -247.10106) (xy 369.612462 -247.051667)
			(xy 369.63604 -247.005393) (xy 369.666566 -246.963377) (xy 369.703289 -246.926654) (xy 369.745305 -246.896128)
			(xy 369.791579 -246.87255) (xy 369.840972 -246.856502) (xy 369.892267 -246.848377) (xy 369.944201 -246.848377)
			(xy 369.995496 -246.856502) (xy 370.044889 -246.87255) (xy 370.091163 -246.896128) (xy 370.133179 -246.926654)
			(xy 370.169902 -246.963377) (xy 370.200428 -247.005393) (xy 370.224006 -247.051667) (xy 370.240054 -247.10106)
			(xy 370.248179 -247.152355) (xy 370.248688 -247.178322) (xy 370.248179 -247.204289) (xy 370.528089 -247.204289)
			(xy 370.528089 -247.152355) (xy 370.536214 -247.10106) (xy 370.552262 -247.051667) (xy 370.57584 -247.005393)
			(xy 370.606366 -246.963377) (xy 370.643089 -246.926654) (xy 370.685105 -246.896128) (xy 370.731379 -246.87255)
			(xy 370.780772 -246.856502) (xy 370.832067 -246.848377) (xy 370.884001 -246.848377) (xy 370.935296 -246.856502)
			(xy 370.984689 -246.87255) (xy 371.030963 -246.896128) (xy 371.072979 -246.926654) (xy 371.109702 -246.963377)
			(xy 371.140228 -247.005393) (xy 371.163806 -247.051667) (xy 371.179854 -247.10106) (xy 371.187979 -247.152355)
			(xy 371.188488 -247.178322) (xy 371.187979 -247.204289) (xy 371.467889 -247.204289) (xy 371.467889 -247.152355)
			(xy 371.476014 -247.10106) (xy 371.492062 -247.051667) (xy 371.51564 -247.005393) (xy 371.546166 -246.963377)
			(xy 371.582889 -246.926654) (xy 371.624905 -246.896128) (xy 371.671179 -246.87255) (xy 371.720572 -246.856502)
			(xy 371.771867 -246.848377) (xy 371.823801 -246.848377) (xy 371.875096 -246.856502) (xy 371.924489 -246.87255)
			(xy 371.970763 -246.896128) (xy 372.012779 -246.926654) (xy 372.049502 -246.963377) (xy 372.080028 -247.005393)
			(xy 372.103606 -247.051667) (xy 372.119654 -247.10106) (xy 372.127779 -247.152355) (xy 372.128288 -247.178322)
			(xy 372.127779 -247.204289) (xy 372.407689 -247.204289) (xy 372.407689 -247.152355) (xy 372.415814 -247.10106)
			(xy 372.431862 -247.051667) (xy 372.45544 -247.005393) (xy 372.485966 -246.963377) (xy 372.522689 -246.926654)
			(xy 372.564705 -246.896128) (xy 372.610979 -246.87255) (xy 372.660372 -246.856502) (xy 372.711667 -246.848377)
			(xy 372.763601 -246.848377) (xy 372.814896 -246.856502) (xy 372.864289 -246.87255) (xy 372.910563 -246.896128)
			(xy 372.952579 -246.926654) (xy 372.989302 -246.963377) (xy 373.019828 -247.005393) (xy 373.043406 -247.051667)
			(xy 373.059454 -247.10106) (xy 373.067579 -247.152355) (xy 373.068088 -247.178322) (xy 373.067579 -247.204289)
			(xy 373.059454 -247.255584) (xy 373.043406 -247.304977) (xy 373.019828 -247.351251) (xy 372.989302 -247.393267)
			(xy 372.952579 -247.42999) (xy 372.910563 -247.460516) (xy 372.864289 -247.484094) (xy 372.814896 -247.500142)
			(xy 372.763601 -247.508267) (xy 372.711667 -247.508267) (xy 372.660372 -247.500142) (xy 372.610979 -247.484094)
			(xy 372.564705 -247.460516) (xy 372.522689 -247.42999) (xy 372.485966 -247.393267) (xy 372.45544 -247.351251)
			(xy 372.431862 -247.304977) (xy 372.415814 -247.255584) (xy 372.407689 -247.204289) (xy 372.127779 -247.204289)
			(xy 372.119654 -247.255584) (xy 372.103606 -247.304977) (xy 372.080028 -247.351251) (xy 372.049502 -247.393267)
			(xy 372.012779 -247.42999) (xy 371.970763 -247.460516) (xy 371.924489 -247.484094) (xy 371.875096 -247.500142)
			(xy 371.823801 -247.508267) (xy 371.771867 -247.508267) (xy 371.720572 -247.500142) (xy 371.671179 -247.484094)
			(xy 371.624905 -247.460516) (xy 371.582889 -247.42999) (xy 371.546166 -247.393267) (xy 371.51564 -247.351251)
			(xy 371.492062 -247.304977) (xy 371.476014 -247.255584) (xy 371.467889 -247.204289) (xy 371.187979 -247.204289)
			(xy 371.179854 -247.255584) (xy 371.163806 -247.304977) (xy 371.140228 -247.351251) (xy 371.109702 -247.393267)
			(xy 371.072979 -247.42999) (xy 371.030963 -247.460516) (xy 370.984689 -247.484094) (xy 370.935296 -247.500142)
			(xy 370.884001 -247.508267) (xy 370.832067 -247.508267) (xy 370.780772 -247.500142) (xy 370.731379 -247.484094)
			(xy 370.685105 -247.460516) (xy 370.643089 -247.42999) (xy 370.606366 -247.393267) (xy 370.57584 -247.351251)
			(xy 370.552262 -247.304977) (xy 370.536214 -247.255584) (xy 370.528089 -247.204289) (xy 370.248179 -247.204289)
			(xy 370.240054 -247.255584) (xy 370.224006 -247.304977) (xy 370.200428 -247.351251) (xy 370.169902 -247.393267)
			(xy 370.133179 -247.42999) (xy 370.091163 -247.460516) (xy 370.044889 -247.484094) (xy 369.995496 -247.500142)
			(xy 369.944201 -247.508267) (xy 369.892267 -247.508267) (xy 369.840972 -247.500142) (xy 369.791579 -247.484094)
			(xy 369.745305 -247.460516) (xy 369.703289 -247.42999) (xy 369.666566 -247.393267) (xy 369.63604 -247.351251)
			(xy 369.612462 -247.304977) (xy 369.596414 -247.255584) (xy 369.588289 -247.204289) (xy 369.386104 -247.204289)
			(xy 369.386104 -247.561862) (xy 369.38664 -247.576908) (xy 369.395404 -247.605695) (xy 369.412181 -247.630675)
			(xy 369.435513 -247.649678) (xy 369.463372 -247.661052) (xy 369.478306 -247.662954) (xy 369.503901 -247.665797)
			(xy 369.553831 -247.678399) (xy 369.601203 -247.698592) (xy 369.64487 -247.725887) (xy 369.683775 -247.759624)
			(xy 369.716977 -247.798987) (xy 369.743673 -247.843023) (xy 369.763217 -247.890666) (xy 369.775135 -247.940764)
			(xy 369.77914 -247.992103) (xy 369.777111 -248.018105) (xy 370.057935 -248.018105) (xy 370.057935 -247.966171)
			(xy 370.06606 -247.914876) (xy 370.082108 -247.865483) (xy 370.105686 -247.819209) (xy 370.136212 -247.777193)
			(xy 370.172935 -247.74047) (xy 370.214951 -247.709944) (xy 370.261225 -247.686366) (xy 370.310618 -247.670318)
			(xy 370.361913 -247.662193) (xy 370.413847 -247.662193) (xy 370.465142 -247.670318) (xy 370.514535 -247.686366)
			(xy 370.560809 -247.709944) (xy 370.602825 -247.74047) (xy 370.639548 -247.777193) (xy 370.670074 -247.819209)
			(xy 370.693652 -247.865483) (xy 370.7097 -247.914876) (xy 370.717825 -247.966171) (xy 370.718334 -247.992138)
			(xy 370.717825 -248.018105) (xy 370.997735 -248.018105) (xy 370.997735 -247.966171) (xy 371.00586 -247.914876)
			(xy 371.021908 -247.865483) (xy 371.045486 -247.819209) (xy 371.076012 -247.777193) (xy 371.112735 -247.74047)
			(xy 371.154751 -247.709944) (xy 371.201025 -247.686366) (xy 371.250418 -247.670318) (xy 371.301713 -247.662193)
			(xy 371.353647 -247.662193) (xy 371.404942 -247.670318) (xy 371.454335 -247.686366) (xy 371.500609 -247.709944)
			(xy 371.542625 -247.74047) (xy 371.579348 -247.777193) (xy 371.609874 -247.819209) (xy 371.633452 -247.865483)
			(xy 371.6495 -247.914876) (xy 371.657625 -247.966171) (xy 371.658134 -247.992138) (xy 371.657625 -248.018105)
			(xy 371.937535 -248.018105) (xy 371.937535 -247.966171) (xy 371.94566 -247.914876) (xy 371.961708 -247.865483)
			(xy 371.985286 -247.819209) (xy 372.015812 -247.777193) (xy 372.052535 -247.74047) (xy 372.094551 -247.709944)
			(xy 372.140825 -247.686366) (xy 372.190218 -247.670318) (xy 372.241513 -247.662193) (xy 372.293447 -247.662193)
			(xy 372.344742 -247.670318) (xy 372.394135 -247.686366) (xy 372.440409 -247.709944) (xy 372.482425 -247.74047)
			(xy 372.519148 -247.777193) (xy 372.549674 -247.819209) (xy 372.573252 -247.865483) (xy 372.5893 -247.914876)
			(xy 372.597425 -247.966171) (xy 372.597934 -247.992138) (xy 372.597425 -248.018105) (xy 372.5893 -248.0694)
			(xy 372.573252 -248.118793) (xy 372.549674 -248.165067) (xy 372.519148 -248.207083) (xy 372.482425 -248.243806)
			(xy 372.440409 -248.274332) (xy 372.394135 -248.29791) (xy 372.344742 -248.313958) (xy 372.293447 -248.322083)
			(xy 372.241513 -248.322083) (xy 372.190218 -248.313958) (xy 372.140825 -248.29791) (xy 372.094551 -248.274332)
			(xy 372.052535 -248.243806) (xy 372.015812 -248.207083) (xy 371.985286 -248.165067) (xy 371.961708 -248.118793)
			(xy 371.94566 -248.0694) (xy 371.937535 -248.018105) (xy 371.657625 -248.018105) (xy 371.6495 -248.0694)
			(xy 371.633452 -248.118793) (xy 371.609874 -248.165067) (xy 371.579348 -248.207083) (xy 371.542625 -248.243806)
			(xy 371.500609 -248.274332) (xy 371.454335 -248.29791) (xy 371.404942 -248.313958) (xy 371.353647 -248.322083)
			(xy 371.301713 -248.322083) (xy 371.250418 -248.313958) (xy 371.201025 -248.29791) (xy 371.154751 -248.274332)
			(xy 371.112735 -248.243806) (xy 371.076012 -248.207083) (xy 371.045486 -248.165067) (xy 371.021908 -248.118793)
			(xy 371.00586 -248.0694) (xy 370.997735 -248.018105) (xy 370.717825 -248.018105) (xy 370.7097 -248.0694)
			(xy 370.693652 -248.118793) (xy 370.670074 -248.165067) (xy 370.639548 -248.207083) (xy 370.602825 -248.243806)
			(xy 370.560809 -248.274332) (xy 370.514535 -248.29791) (xy 370.465142 -248.313958) (xy 370.413847 -248.322083)
			(xy 370.361913 -248.322083) (xy 370.310618 -248.313958) (xy 370.261225 -248.29791) (xy 370.214951 -248.274332)
			(xy 370.172935 -248.243806) (xy 370.136212 -248.207083) (xy 370.105686 -248.165067) (xy 370.082108 -248.118793)
			(xy 370.06606 -248.0694) (xy 370.057935 -248.018105) (xy 369.777111 -248.018105) (xy 369.775134 -248.043443)
			(xy 369.763215 -248.093541) (xy 369.74367 -248.141183) (xy 369.716973 -248.185219) (xy 369.68377 -248.224581)
			(xy 369.644864 -248.258317) (xy 369.601197 -248.285611) (xy 369.553825 -248.305803) (xy 369.503894 -248.318404)
			(xy 369.478306 -248.321322) (xy 369.463389 -248.323262) (xy 369.435566 -248.334661) (xy 369.412265 -248.353663)
			(xy 369.395502 -248.378623) (xy 369.386728 -248.407381) (xy 369.386104 -248.422414) (xy 369.386104 -248.832175)
			(xy 369.588289 -248.832175) (xy 369.588289 -248.780241) (xy 369.596414 -248.728946) (xy 369.612462 -248.679553)
			(xy 369.63604 -248.633279) (xy 369.666566 -248.591263) (xy 369.703289 -248.55454) (xy 369.745305 -248.524014)
			(xy 369.791579 -248.500436) (xy 369.840972 -248.484388) (xy 369.892267 -248.476263) (xy 369.944201 -248.476263)
			(xy 369.995496 -248.484388) (xy 370.044889 -248.500436) (xy 370.091163 -248.524014) (xy 370.133179 -248.55454)
			(xy 370.169902 -248.591263) (xy 370.200428 -248.633279) (xy 370.224006 -248.679553) (xy 370.240054 -248.728946)
			(xy 370.248179 -248.780241) (xy 370.248688 -248.806208) (xy 370.248179 -248.832175) (xy 370.527835 -248.832175)
			(xy 370.527835 -248.780241) (xy 370.53596 -248.728946) (xy 370.552008 -248.679553) (xy 370.575586 -248.633279)
			(xy 370.606112 -248.591263) (xy 370.642835 -248.55454) (xy 370.684851 -248.524014) (xy 370.731125 -248.500436)
			(xy 370.780518 -248.484388) (xy 370.831813 -248.476263) (xy 370.883747 -248.476263) (xy 370.935042 -248.484388)
			(xy 370.984435 -248.500436) (xy 371.030709 -248.524014) (xy 371.072725 -248.55454) (xy 371.109448 -248.591263)
			(xy 371.139974 -248.633279) (xy 371.163552 -248.679553) (xy 371.1796 -248.728946) (xy 371.187725 -248.780241)
			(xy 371.188234 -248.806208) (xy 371.187725 -248.832175) (xy 371.1796 -248.88347) (xy 371.163552 -248.932863)
			(xy 371.139974 -248.979137) (xy 371.109448 -249.021153) (xy 371.072725 -249.057876) (xy 371.030709 -249.088402)
			(xy 370.984435 -249.11198) (xy 370.935042 -249.128028) (xy 370.883747 -249.136153) (xy 370.831813 -249.136153)
			(xy 370.780518 -249.128028) (xy 370.731125 -249.11198) (xy 370.684851 -249.088402) (xy 370.642835 -249.057876)
			(xy 370.606112 -249.021153) (xy 370.575586 -248.979137) (xy 370.552008 -248.932863) (xy 370.53596 -248.88347)
			(xy 370.527835 -248.832175) (xy 370.248179 -248.832175) (xy 370.240054 -248.88347) (xy 370.224006 -248.932863)
			(xy 370.200428 -248.979137) (xy 370.169902 -249.021153) (xy 370.133179 -249.057876) (xy 370.091163 -249.088402)
			(xy 370.044889 -249.11198) (xy 369.995496 -249.128028) (xy 369.944201 -249.136153) (xy 369.892267 -249.136153)
			(xy 369.840972 -249.128028) (xy 369.791579 -249.11198) (xy 369.745305 -249.088402) (xy 369.703289 -249.057876)
			(xy 369.666566 -249.021153) (xy 369.63604 -248.979137) (xy 369.612462 -248.932863) (xy 369.596414 -248.88347)
			(xy 369.588289 -248.832175) (xy 369.386104 -248.832175) (xy 369.386104 -249.189748) (xy 369.386638 -249.204795)
			(xy 369.3954 -249.233586) (xy 369.412176 -249.25857) (xy 369.435508 -249.277576) (xy 369.463369 -249.288951)
			(xy 369.478306 -249.29084) (xy 369.503902 -249.293683) (xy 369.553835 -249.306285) (xy 369.601208 -249.326479)
			(xy 369.644877 -249.353775) (xy 369.683784 -249.387514) (xy 369.716988 -249.426878) (xy 369.743685 -249.470915)
			(xy 369.76323 -249.51856) (xy 369.775149 -249.56866) (xy 369.779154 -249.620002) (xy 369.777126 -249.645991)
			(xy 370.057935 -249.645991) (xy 370.057935 -249.594057) (xy 370.06606 -249.542762) (xy 370.082108 -249.493369)
			(xy 370.105686 -249.447095) (xy 370.136212 -249.405079) (xy 370.172935 -249.368356) (xy 370.214951 -249.33783)
			(xy 370.261225 -249.314252) (xy 370.310618 -249.298204) (xy 370.361913 -249.290079) (xy 370.413847 -249.290079)
			(xy 370.465142 -249.298204) (xy 370.514535 -249.314252) (xy 370.560809 -249.33783) (xy 370.602825 -249.368356)
			(xy 370.639548 -249.405079) (xy 370.670074 -249.447095) (xy 370.693652 -249.493369) (xy 370.7097 -249.542762)
			(xy 370.717825 -249.594057) (xy 370.718334 -249.620024) (xy 370.717825 -249.645991) (xy 370.997735 -249.645991)
			(xy 370.997735 -249.594057) (xy 371.00586 -249.542762) (xy 371.021908 -249.493369) (xy 371.045486 -249.447095)
			(xy 371.076012 -249.405079) (xy 371.112735 -249.368356) (xy 371.154751 -249.33783) (xy 371.201025 -249.314252)
			(xy 371.250418 -249.298204) (xy 371.301713 -249.290079) (xy 371.353647 -249.290079) (xy 371.404942 -249.298204)
			(xy 371.454335 -249.314252) (xy 371.500609 -249.33783) (xy 371.542625 -249.368356) (xy 371.579348 -249.405079)
			(xy 371.609874 -249.447095) (xy 371.633452 -249.493369) (xy 371.6495 -249.542762) (xy 371.657625 -249.594057)
			(xy 371.658134 -249.620024) (xy 371.657625 -249.645991) (xy 371.6495 -249.697286) (xy 371.633452 -249.746679)
			(xy 371.609874 -249.792953) (xy 371.579348 -249.834969) (xy 371.542625 -249.871692) (xy 371.500609 -249.902218)
			(xy 371.454335 -249.925796) (xy 371.404942 -249.941844) (xy 371.353647 -249.949969) (xy 371.301713 -249.949969)
			(xy 371.250418 -249.941844) (xy 371.201025 -249.925796) (xy 371.154751 -249.902218) (xy 371.112735 -249.871692)
			(xy 371.076012 -249.834969) (xy 371.045486 -249.792953) (xy 371.021908 -249.746679) (xy 371.00586 -249.697286)
			(xy 370.997735 -249.645991) (xy 370.717825 -249.645991) (xy 370.7097 -249.697286) (xy 370.693652 -249.746679)
			(xy 370.670074 -249.792953) (xy 370.639548 -249.834969) (xy 370.602825 -249.871692) (xy 370.560809 -249.902218)
			(xy 370.514535 -249.925796) (xy 370.465142 -249.941844) (xy 370.413847 -249.949969) (xy 370.361913 -249.949969)
			(xy 370.310618 -249.941844) (xy 370.261225 -249.925796) (xy 370.214951 -249.902218) (xy 370.172935 -249.871692)
			(xy 370.136212 -249.834969) (xy 370.105686 -249.792953) (xy 370.082108 -249.746679) (xy 370.06606 -249.697286)
			(xy 370.057935 -249.645991) (xy 369.777126 -249.645991) (xy 369.775148 -249.671344) (xy 369.763228 -249.721444)
			(xy 369.743683 -249.769089) (xy 369.716985 -249.813126) (xy 369.683781 -249.852489) (xy 369.644873 -249.886227)
			(xy 369.601204 -249.913523) (xy 369.55383 -249.933716) (xy 369.503898 -249.946318) (xy 369.478306 -249.949208)
			(xy 369.463388 -249.951148) (xy 369.435563 -249.962546) (xy 369.41226 -249.981548) (xy 369.395494 -250.006508)
			(xy 369.386716 -250.035266) (xy 369.386104 -250.0503) (xy 369.386104 -253.945703) (xy 369.698271 -253.945703)
			(xy 369.698271 -253.893769) (xy 369.706396 -253.842474) (xy 369.722444 -253.793081) (xy 369.746022 -253.746807)
			(xy 369.776548 -253.704791) (xy 369.813271 -253.668068) (xy 369.855287 -253.637542) (xy 369.901561 -253.613964)
			(xy 369.950954 -253.597916) (xy 370.002249 -253.589791) (xy 370.054183 -253.589791) (xy 370.105478 -253.597916)
			(xy 370.154871 -253.613964) (xy 370.201145 -253.637542) (xy 370.243161 -253.668068) (xy 370.279884 -253.704791)
			(xy 370.31041 -253.746807) (xy 370.333988 -253.793081) (xy 370.350036 -253.842474) (xy 370.358161 -253.893769)
			(xy 370.35867 -253.919736) (xy 370.358161 -253.945703) (xy 370.637817 -253.945703) (xy 370.637817 -253.893769)
			(xy 370.645942 -253.842474) (xy 370.66199 -253.793081) (xy 370.685568 -253.746807) (xy 370.716094 -253.704791)
			(xy 370.752817 -253.668068) (xy 370.794833 -253.637542) (xy 370.841107 -253.613964) (xy 370.8905 -253.597916)
			(xy 370.941795 -253.589791) (xy 370.993729 -253.589791) (xy 371.045024 -253.597916) (xy 371.094417 -253.613964)
			(xy 371.140691 -253.637542) (xy 371.182707 -253.668068) (xy 371.21943 -253.704791) (xy 371.249956 -253.746807)
			(xy 371.273534 -253.793081) (xy 371.289582 -253.842474) (xy 371.297707 -253.893769) (xy 371.298216 -253.919736)
			(xy 371.297707 -253.945703) (xy 371.577871 -253.945703) (xy 371.577871 -253.893769) (xy 371.585996 -253.842474)
			(xy 371.602044 -253.793081) (xy 371.625622 -253.746807) (xy 371.656148 -253.704791) (xy 371.692871 -253.668068)
			(xy 371.734887 -253.637542) (xy 371.781161 -253.613964) (xy 371.830554 -253.597916) (xy 371.881849 -253.589791)
			(xy 371.933783 -253.589791) (xy 371.985078 -253.597916) (xy 372.034471 -253.613964) (xy 372.080745 -253.637542)
			(xy 372.122761 -253.668068) (xy 372.159484 -253.704791) (xy 372.19001 -253.746807) (xy 372.213588 -253.793081)
			(xy 372.229636 -253.842474) (xy 372.237761 -253.893769) (xy 372.23827 -253.919736) (xy 372.237761 -253.945703)
			(xy 372.517671 -253.945703) (xy 372.517671 -253.893769) (xy 372.525796 -253.842474) (xy 372.541844 -253.793081)
			(xy 372.565422 -253.746807) (xy 372.595948 -253.704791) (xy 372.632671 -253.668068) (xy 372.674687 -253.637542)
			(xy 372.720961 -253.613964) (xy 372.770354 -253.597916) (xy 372.821649 -253.589791) (xy 372.873583 -253.589791)
			(xy 372.924878 -253.597916) (xy 372.974271 -253.613964) (xy 373.020545 -253.637542) (xy 373.062561 -253.668068)
			(xy 373.099284 -253.704791) (xy 373.12981 -253.746807) (xy 373.153388 -253.793081) (xy 373.169436 -253.842474)
			(xy 373.177561 -253.893769) (xy 373.17807 -253.919736) (xy 373.177561 -253.945703) (xy 373.169436 -253.996998)
			(xy 373.153388 -254.046391) (xy 373.12981 -254.092665) (xy 373.099284 -254.134681) (xy 373.062561 -254.171404)
			(xy 373.020545 -254.20193) (xy 372.974271 -254.225508) (xy 372.924878 -254.241556) (xy 372.873583 -254.249681)
			(xy 372.821649 -254.249681) (xy 372.770354 -254.241556) (xy 372.720961 -254.225508) (xy 372.674687 -254.20193)
			(xy 372.632671 -254.171404) (xy 372.595948 -254.134681) (xy 372.565422 -254.092665) (xy 372.541844 -254.046391)
			(xy 372.525796 -253.996998) (xy 372.517671 -253.945703) (xy 372.237761 -253.945703) (xy 372.229636 -253.996998)
			(xy 372.213588 -254.046391) (xy 372.19001 -254.092665) (xy 372.159484 -254.134681) (xy 372.122761 -254.171404)
			(xy 372.080745 -254.20193) (xy 372.034471 -254.225508) (xy 371.985078 -254.241556) (xy 371.933783 -254.249681)
			(xy 371.881849 -254.249681) (xy 371.830554 -254.241556) (xy 371.781161 -254.225508) (xy 371.734887 -254.20193)
			(xy 371.692871 -254.171404) (xy 371.656148 -254.134681) (xy 371.625622 -254.092665) (xy 371.602044 -254.046391)
			(xy 371.585996 -253.996998) (xy 371.577871 -253.945703) (xy 371.297707 -253.945703) (xy 371.289582 -253.996998)
			(xy 371.273534 -254.046391) (xy 371.249956 -254.092665) (xy 371.21943 -254.134681) (xy 371.182707 -254.171404)
			(xy 371.140691 -254.20193) (xy 371.094417 -254.225508) (xy 371.045024 -254.241556) (xy 370.993729 -254.249681)
			(xy 370.941795 -254.249681) (xy 370.8905 -254.241556) (xy 370.841107 -254.225508) (xy 370.794833 -254.20193)
			(xy 370.752817 -254.171404) (xy 370.716094 -254.134681) (xy 370.685568 -254.092665) (xy 370.66199 -254.046391)
			(xy 370.645942 -253.996998) (xy 370.637817 -253.945703) (xy 370.358161 -253.945703) (xy 370.350036 -253.996998)
			(xy 370.333988 -254.046391) (xy 370.31041 -254.092665) (xy 370.279884 -254.134681) (xy 370.243161 -254.171404)
			(xy 370.201145 -254.20193) (xy 370.154871 -254.225508) (xy 370.105478 -254.241556) (xy 370.054183 -254.249681)
			(xy 370.002249 -254.249681) (xy 369.950954 -254.241556) (xy 369.901561 -254.225508) (xy 369.855287 -254.20193)
			(xy 369.813271 -254.171404) (xy 369.776548 -254.134681) (xy 369.746022 -254.092665) (xy 369.722444 -254.046391)
			(xy 369.706396 -253.996998) (xy 369.698271 -253.945703) (xy 369.386104 -253.945703) (xy 369.386104 -254.30734)
			(xy 369.386576 -254.322059) (xy 369.39494 -254.350281) (xy 369.411017 -254.374939) (xy 369.433468 -254.393976)
			(xy 369.460421 -254.405807) (xy 369.489631 -254.409446) (xy 369.504214 -254.407416) (xy 369.517581 -254.405364)
			(xy 369.544539 -254.403201) (xy 369.558062 -254.403098) (xy 369.584037 -254.403578) (xy 369.635348 -254.4117)
			(xy 369.684757 -254.427748) (xy 369.731047 -254.451329) (xy 369.773077 -254.481862) (xy 369.809813 -254.518594)
			(xy 369.840351 -254.560621) (xy 369.863937 -254.606908) (xy 369.879992 -254.656315) (xy 369.888119 -254.707625)
			(xy 369.888119 -254.759519) (xy 370.167917 -254.759519) (xy 370.167917 -254.707585) (xy 370.176042 -254.65629)
			(xy 370.19209 -254.606897) (xy 370.215668 -254.560623) (xy 370.246194 -254.518607) (xy 370.282917 -254.481884)
			(xy 370.324933 -254.451358) (xy 370.371207 -254.42778) (xy 370.4206 -254.411732) (xy 370.471895 -254.403607)
			(xy 370.523829 -254.403607) (xy 370.575124 -254.411732) (xy 370.624517 -254.42778) (xy 370.670791 -254.451358)
			(xy 370.712807 -254.481884) (xy 370.74953 -254.518607) (xy 370.780056 -254.560623) (xy 370.803634 -254.606897)
			(xy 370.819682 -254.65629) (xy 370.827807 -254.707585) (xy 370.828316 -254.733552) (xy 370.827807 -254.759519)
			(xy 371.107717 -254.759519) (xy 371.107717 -254.707585) (xy 371.115842 -254.65629) (xy 371.13189 -254.606897)
			(xy 371.155468 -254.560623) (xy 371.185994 -254.518607) (xy 371.222717 -254.481884) (xy 371.264733 -254.451358)
			(xy 371.311007 -254.42778) (xy 371.3604 -254.411732) (xy 371.411695 -254.403607) (xy 371.463629 -254.403607)
			(xy 371.514924 -254.411732) (xy 371.564317 -254.42778) (xy 371.610591 -254.451358) (xy 371.652607 -254.481884)
			(xy 371.68933 -254.518607) (xy 371.719856 -254.560623) (xy 371.743434 -254.606897) (xy 371.759482 -254.65629)
			(xy 371.767607 -254.707585) (xy 371.768116 -254.733552) (xy 371.767607 -254.759519) (xy 372.047771 -254.759519)
			(xy 372.047771 -254.707585) (xy 372.055896 -254.65629) (xy 372.071944 -254.606897) (xy 372.095522 -254.560623)
			(xy 372.126048 -254.518607) (xy 372.162771 -254.481884) (xy 372.204787 -254.451358) (xy 372.251061 -254.42778)
			(xy 372.300454 -254.411732) (xy 372.351749 -254.403607) (xy 372.403683 -254.403607) (xy 372.454978 -254.411732)
			(xy 372.504371 -254.42778) (xy 372.550645 -254.451358) (xy 372.592661 -254.481884) (xy 372.629384 -254.518607)
			(xy 372.65991 -254.560623) (xy 372.683488 -254.606897) (xy 372.699536 -254.65629) (xy 372.707661 -254.707585)
			(xy 372.70817 -254.733552) (xy 372.707661 -254.759519) (xy 372.699536 -254.810814) (xy 372.683488 -254.860207)
			(xy 372.65991 -254.906481) (xy 372.629384 -254.948497) (xy 372.592661 -254.98522) (xy 372.550645 -255.015746)
			(xy 372.504371 -255.039324) (xy 372.454978 -255.055372) (xy 372.403683 -255.063497) (xy 372.351749 -255.063497)
			(xy 372.300454 -255.055372) (xy 372.251061 -255.039324) (xy 372.204787 -255.015746) (xy 372.162771 -254.98522)
			(xy 372.126048 -254.948497) (xy 372.095522 -254.906481) (xy 372.071944 -254.860207) (xy 372.055896 -254.810814)
			(xy 372.047771 -254.759519) (xy 371.767607 -254.759519) (xy 371.759482 -254.810814) (xy 371.743434 -254.860207)
			(xy 371.719856 -254.906481) (xy 371.68933 -254.948497) (xy 371.652607 -254.98522) (xy 371.610591 -255.015746)
			(xy 371.564317 -255.039324) (xy 371.514924 -255.055372) (xy 371.463629 -255.063497) (xy 371.411695 -255.063497)
			(xy 371.3604 -255.055372) (xy 371.311007 -255.039324) (xy 371.264733 -255.015746) (xy 371.222717 -254.98522)
			(xy 371.185994 -254.948497) (xy 371.155468 -254.906481) (xy 371.13189 -254.860207) (xy 371.115842 -254.810814)
			(xy 371.107717 -254.759519) (xy 370.827807 -254.759519) (xy 370.819682 -254.810814) (xy 370.803634 -254.860207)
			(xy 370.780056 -254.906481) (xy 370.74953 -254.948497) (xy 370.712807 -254.98522) (xy 370.670791 -255.015746)
			(xy 370.624517 -255.039324) (xy 370.575124 -255.055372) (xy 370.523829 -255.063497) (xy 370.471895 -255.063497)
			(xy 370.4206 -255.055372) (xy 370.371207 -255.039324) (xy 370.324933 -255.015746) (xy 370.282917 -254.98522)
			(xy 370.246194 -254.948497) (xy 370.215668 -254.906481) (xy 370.19209 -254.860207) (xy 370.176042 -254.810814)
			(xy 370.167917 -254.759519) (xy 369.888119 -254.759519) (xy 369.888119 -254.759575) (xy 369.879992 -254.810885)
			(xy 369.863937 -254.860292) (xy 369.840351 -254.906579) (xy 369.809813 -254.948606) (xy 369.773077 -254.985338)
			(xy 369.731047 -255.015871) (xy 369.684757 -255.039452) (xy 369.635348 -255.0555) (xy 369.584037 -255.063622)
			(xy 369.558062 -255.064006) (xy 369.54454 -255.063888) (xy 369.517582 -255.06173) (xy 369.504214 -255.059688)
			(xy 369.489637 -255.057796) (xy 369.460488 -255.061496) (xy 369.433596 -255.073335) (xy 369.411182 -255.092334)
			(xy 369.395099 -255.116925) (xy 369.386676 -255.145074) (xy 369.386104 -255.159764) (xy 369.386104 -255.573589)
			(xy 370.638071 -255.573589) (xy 370.638071 -255.521655) (xy 370.646196 -255.47036) (xy 370.662244 -255.420967)
			(xy 370.685822 -255.374693) (xy 370.716348 -255.332677) (xy 370.753071 -255.295954) (xy 370.795087 -255.265428)
			(xy 370.841361 -255.24185) (xy 370.890754 -255.225802) (xy 370.942049 -255.217677) (xy 370.993983 -255.217677)
			(xy 371.045278 -255.225802) (xy 371.094671 -255.24185) (xy 371.140945 -255.265428) (xy 371.182961 -255.295954)
			(xy 371.219684 -255.332677) (xy 371.25021 -255.374693) (xy 371.273788 -255.420967) (xy 371.289836 -255.47036)
			(xy 371.297961 -255.521655) (xy 371.29847 -255.547622) (xy 371.297961 -255.573589) (xy 371.577871 -255.573589)
			(xy 371.577871 -255.521655) (xy 371.585996 -255.47036) (xy 371.602044 -255.420967) (xy 371.625622 -255.374693)
			(xy 371.656148 -255.332677) (xy 371.692871 -255.295954) (xy 371.734887 -255.265428) (xy 371.781161 -255.24185)
			(xy 371.830554 -255.225802) (xy 371.881849 -255.217677) (xy 371.933783 -255.217677) (xy 371.985078 -255.225802)
			(xy 372.034471 -255.24185) (xy 372.080745 -255.265428) (xy 372.122761 -255.295954) (xy 372.159484 -255.332677)
			(xy 372.19001 -255.374693) (xy 372.213588 -255.420967) (xy 372.229636 -255.47036) (xy 372.237761 -255.521655)
			(xy 372.23827 -255.547622) (xy 372.237761 -255.573589) (xy 372.517417 -255.573589) (xy 372.517417 -255.521655)
			(xy 372.525542 -255.47036) (xy 372.54159 -255.420967) (xy 372.565168 -255.374693) (xy 372.595694 -255.332677)
			(xy 372.632417 -255.295954) (xy 372.674433 -255.265428) (xy 372.720707 -255.24185) (xy 372.7701 -255.225802)
			(xy 372.821395 -255.217677) (xy 372.873329 -255.217677) (xy 372.924624 -255.225802) (xy 372.974017 -255.24185)
			(xy 373.020291 -255.265428) (xy 373.062307 -255.295954) (xy 373.09903 -255.332677) (xy 373.129556 -255.374693)
			(xy 373.153134 -255.420967) (xy 373.169182 -255.47036) (xy 373.177307 -255.521655) (xy 373.177816 -255.547622)
			(xy 373.177307 -255.573589) (xy 373.169182 -255.624884) (xy 373.153134 -255.674277) (xy 373.129556 -255.720551)
			(xy 373.09903 -255.762567) (xy 373.062307 -255.79929) (xy 373.020291 -255.829816) (xy 372.974017 -255.853394)
			(xy 372.924624 -255.869442) (xy 372.873329 -255.877567) (xy 372.821395 -255.877567) (xy 372.7701 -255.869442)
			(xy 372.720707 -255.853394) (xy 372.674433 -255.829816) (xy 372.632417 -255.79929) (xy 372.595694 -255.762567)
			(xy 372.565168 -255.720551) (xy 372.54159 -255.674277) (xy 372.525542 -255.624884) (xy 372.517417 -255.573589)
			(xy 372.237761 -255.573589) (xy 372.229636 -255.624884) (xy 372.213588 -255.674277) (xy 372.19001 -255.720551)
			(xy 372.159484 -255.762567) (xy 372.122761 -255.79929) (xy 372.080745 -255.829816) (xy 372.034471 -255.853394)
			(xy 371.985078 -255.869442) (xy 371.933783 -255.877567) (xy 371.881849 -255.877567) (xy 371.830554 -255.869442)
			(xy 371.781161 -255.853394) (xy 371.734887 -255.829816) (xy 371.692871 -255.79929) (xy 371.656148 -255.762567)
			(xy 371.625622 -255.720551) (xy 371.602044 -255.674277) (xy 371.585996 -255.624884) (xy 371.577871 -255.573589)
			(xy 371.297961 -255.573589) (xy 371.289836 -255.624884) (xy 371.273788 -255.674277) (xy 371.25021 -255.720551)
			(xy 371.219684 -255.762567) (xy 371.182961 -255.79929) (xy 371.140945 -255.829816) (xy 371.094671 -255.853394)
			(xy 371.045278 -255.869442) (xy 370.993983 -255.877567) (xy 370.942049 -255.877567) (xy 370.890754 -255.869442)
			(xy 370.841361 -255.853394) (xy 370.795087 -255.829816) (xy 370.753071 -255.79929) (xy 370.716348 -255.762567)
			(xy 370.685822 -255.720551) (xy 370.662244 -255.674277) (xy 370.646196 -255.624884) (xy 370.638071 -255.573589)
			(xy 369.386104 -255.573589) (xy 369.386104 -255.935226) (xy 369.386587 -255.949936) (xy 369.394966 -255.978137)
			(xy 369.411047 -256.002772) (xy 369.433491 -256.021791) (xy 369.460432 -256.03361) (xy 369.489625 -256.037246)
			(xy 369.504214 -256.035302) (xy 369.517581 -256.033251) (xy 369.544539 -256.031087) (xy 369.558062 -256.030984)
			(xy 369.58403 -256.031464) (xy 369.635328 -256.039583) (xy 369.684724 -256.055628) (xy 369.731002 -256.079203)
			(xy 369.773021 -256.109727) (xy 369.809748 -256.14645) (xy 369.840277 -256.188466) (xy 369.863858 -256.234741)
			(xy 369.879908 -256.284135) (xy 369.888033 -256.335432) (xy 369.888033 -256.387368) (xy 369.888027 -256.387405)
			(xy 370.168171 -256.387405) (xy 370.168171 -256.335471) (xy 370.176296 -256.284176) (xy 370.192344 -256.234783)
			(xy 370.215922 -256.188509) (xy 370.246448 -256.146493) (xy 370.283171 -256.10977) (xy 370.325187 -256.079244)
			(xy 370.371461 -256.055666) (xy 370.420854 -256.039618) (xy 370.472149 -256.031493) (xy 370.524083 -256.031493)
			(xy 370.575378 -256.039618) (xy 370.624771 -256.055666) (xy 370.671045 -256.079244) (xy 370.713061 -256.10977)
			(xy 370.749784 -256.146493) (xy 370.78031 -256.188509) (xy 370.803888 -256.234783) (xy 370.819936 -256.284176)
			(xy 370.828061 -256.335471) (xy 370.82857 -256.361438) (xy 370.828061 -256.387405) (xy 371.107717 -256.387405)
			(xy 371.107717 -256.335471) (xy 371.115842 -256.284176) (xy 371.13189 -256.234783) (xy 371.155468 -256.188509)
			(xy 371.185994 -256.146493) (xy 371.222717 -256.10977) (xy 371.264733 -256.079244) (xy 371.311007 -256.055666)
			(xy 371.3604 -256.039618) (xy 371.411695 -256.031493) (xy 371.463629 -256.031493) (xy 371.514924 -256.039618)
			(xy 371.564317 -256.055666) (xy 371.610591 -256.079244) (xy 371.652607 -256.10977) (xy 371.68933 -256.146493)
			(xy 371.719856 -256.188509) (xy 371.743434 -256.234783) (xy 371.759482 -256.284176) (xy 371.767607 -256.335471)
			(xy 371.768116 -256.361438) (xy 371.767607 -256.387405) (xy 372.047517 -256.387405) (xy 372.047517 -256.335471)
			(xy 372.055642 -256.284176) (xy 372.07169 -256.234783) (xy 372.095268 -256.188509) (xy 372.125794 -256.146493)
			(xy 372.162517 -256.10977) (xy 372.204533 -256.079244) (xy 372.250807 -256.055666) (xy 372.3002 -256.039618)
			(xy 372.351495 -256.031493) (xy 372.403429 -256.031493) (xy 372.454724 -256.039618) (xy 372.504117 -256.055666)
			(xy 372.550391 -256.079244) (xy 372.592407 -256.10977) (xy 372.62913 -256.146493) (xy 372.659656 -256.188509)
			(xy 372.683234 -256.234783) (xy 372.699282 -256.284176) (xy 372.707407 -256.335471) (xy 372.707916 -256.361438)
			(xy 372.707407 -256.387405) (xy 372.699282 -256.4387) (xy 372.683234 -256.488093) (xy 372.659656 -256.534367)
			(xy 372.62913 -256.576383) (xy 372.592407 -256.613106) (xy 372.550391 -256.643632) (xy 372.504117 -256.66721)
			(xy 372.454724 -256.683258) (xy 372.403429 -256.691383) (xy 372.351495 -256.691383) (xy 372.3002 -256.683258)
			(xy 372.250807 -256.66721) (xy 372.204533 -256.643632) (xy 372.162517 -256.613106) (xy 372.125794 -256.576383)
			(xy 372.095268 -256.534367) (xy 372.07169 -256.488093) (xy 372.055642 -256.4387) (xy 372.047517 -256.387405)
			(xy 371.767607 -256.387405) (xy 371.759482 -256.4387) (xy 371.743434 -256.488093) (xy 371.719856 -256.534367)
			(xy 371.68933 -256.576383) (xy 371.652607 -256.613106) (xy 371.610591 -256.643632) (xy 371.564317 -256.66721)
			(xy 371.514924 -256.683258) (xy 371.463629 -256.691383) (xy 371.411695 -256.691383) (xy 371.3604 -256.683258)
			(xy 371.311007 -256.66721) (xy 371.264733 -256.643632) (xy 371.222717 -256.613106) (xy 371.185994 -256.576383)
			(xy 371.155468 -256.534367) (xy 371.13189 -256.488093) (xy 371.115842 -256.4387) (xy 371.107717 -256.387405)
			(xy 370.828061 -256.387405) (xy 370.819936 -256.4387) (xy 370.803888 -256.488093) (xy 370.78031 -256.534367)
			(xy 370.749784 -256.576383) (xy 370.713061 -256.613106) (xy 370.671045 -256.643632) (xy 370.624771 -256.66721)
			(xy 370.575378 -256.683258) (xy 370.524083 -256.691383) (xy 370.472149 -256.691383) (xy 370.420854 -256.683258)
			(xy 370.371461 -256.66721) (xy 370.325187 -256.643632) (xy 370.283171 -256.613106) (xy 370.246448 -256.576383)
			(xy 370.215922 -256.534367) (xy 370.192344 -256.488093) (xy 370.176296 -256.4387) (xy 370.168171 -256.387405)
			(xy 369.888027 -256.387405) (xy 369.879908 -256.438665) (xy 369.863858 -256.488059) (xy 369.840277 -256.534334)
			(xy 369.809748 -256.57635) (xy 369.773021 -256.613073) (xy 369.731002 -256.643597) (xy 369.684724 -256.667172)
			(xy 369.635328 -256.683217) (xy 369.58403 -256.691336) (xy 369.558062 -256.691892) (xy 369.54454 -256.691774)
			(xy 369.517582 -256.689616) (xy 369.504214 -256.687574) (xy 369.489636 -256.685683) (xy 369.460486 -256.689382)
			(xy 369.433592 -256.701221) (xy 369.411177 -256.72022) (xy 369.395091 -256.74481) (xy 369.386664 -256.772959)
			(xy 369.386104 -256.78765) (xy 369.386104 -257.201221) (xy 369.698271 -257.201221) (xy 369.698271 -257.149287)
			(xy 369.706396 -257.097992) (xy 369.722444 -257.048599) (xy 369.746022 -257.002325) (xy 369.776548 -256.960309)
			(xy 369.813271 -256.923586) (xy 369.855287 -256.89306) (xy 369.901561 -256.869482) (xy 369.950954 -256.853434)
			(xy 370.002249 -256.845309) (xy 370.054183 -256.845309) (xy 370.105478 -256.853434) (xy 370.154871 -256.869482)
			(xy 370.201145 -256.89306) (xy 370.243161 -256.923586) (xy 370.279884 -256.960309) (xy 370.31041 -257.002325)
			(xy 370.333988 -257.048599) (xy 370.350036 -257.097992) (xy 370.358161 -257.149287) (xy 370.35867 -257.175254)
			(xy 370.358161 -257.201221) (xy 370.638071 -257.201221) (xy 370.638071 -257.149287) (xy 370.646196 -257.097992)
			(xy 370.662244 -257.048599) (xy 370.685822 -257.002325) (xy 370.716348 -256.960309) (xy 370.753071 -256.923586)
			(xy 370.795087 -256.89306) (xy 370.841361 -256.869482) (xy 370.890754 -256.853434) (xy 370.942049 -256.845309)
			(xy 370.993983 -256.845309) (xy 371.045278 -256.853434) (xy 371.094671 -256.869482) (xy 371.140945 -256.89306)
			(xy 371.182961 -256.923586) (xy 371.219684 -256.960309) (xy 371.25021 -257.002325) (xy 371.273788 -257.048599)
			(xy 371.289836 -257.097992) (xy 371.297961 -257.149287) (xy 371.29847 -257.175254) (xy 371.297961 -257.201221)
			(xy 371.577871 -257.201221) (xy 371.577871 -257.149287) (xy 371.585996 -257.097992) (xy 371.602044 -257.048599)
			(xy 371.625622 -257.002325) (xy 371.656148 -256.960309) (xy 371.692871 -256.923586) (xy 371.734887 -256.89306)
			(xy 371.781161 -256.869482) (xy 371.830554 -256.853434) (xy 371.881849 -256.845309) (xy 371.933783 -256.845309)
			(xy 371.985078 -256.853434) (xy 372.034471 -256.869482) (xy 372.080745 -256.89306) (xy 372.122761 -256.923586)
			(xy 372.159484 -256.960309) (xy 372.19001 -257.002325) (xy 372.213588 -257.048599) (xy 372.229636 -257.097992)
			(xy 372.237761 -257.149287) (xy 372.23827 -257.175254) (xy 372.237761 -257.201221) (xy 372.517417 -257.201221)
			(xy 372.517417 -257.149287) (xy 372.525542 -257.097992) (xy 372.54159 -257.048599) (xy 372.565168 -257.002325)
			(xy 372.595694 -256.960309) (xy 372.632417 -256.923586) (xy 372.674433 -256.89306) (xy 372.720707 -256.869482)
			(xy 372.7701 -256.853434) (xy 372.821395 -256.845309) (xy 372.873329 -256.845309) (xy 372.924624 -256.853434)
			(xy 372.974017 -256.869482) (xy 373.020291 -256.89306) (xy 373.062307 -256.923586) (xy 373.09903 -256.960309)
			(xy 373.129556 -257.002325) (xy 373.153134 -257.048599) (xy 373.169182 -257.097992) (xy 373.177307 -257.149287)
			(xy 373.177816 -257.175254) (xy 373.177307 -257.201221) (xy 373.169182 -257.252516) (xy 373.153134 -257.301909)
			(xy 373.129556 -257.348183) (xy 373.09903 -257.390199) (xy 373.062307 -257.426922) (xy 373.020291 -257.457448)
			(xy 372.974017 -257.481026) (xy 372.924624 -257.497074) (xy 372.873329 -257.505199) (xy 372.821395 -257.505199)
			(xy 372.7701 -257.497074) (xy 372.720707 -257.481026) (xy 372.674433 -257.457448) (xy 372.632417 -257.426922)
			(xy 372.595694 -257.390199) (xy 372.565168 -257.348183) (xy 372.54159 -257.301909) (xy 372.525542 -257.252516)
			(xy 372.517417 -257.201221) (xy 372.237761 -257.201221) (xy 372.229636 -257.252516) (xy 372.213588 -257.301909)
			(xy 372.19001 -257.348183) (xy 372.159484 -257.390199) (xy 372.122761 -257.426922) (xy 372.080745 -257.457448)
			(xy 372.034471 -257.481026) (xy 371.985078 -257.497074) (xy 371.933783 -257.505199) (xy 371.881849 -257.505199)
			(xy 371.830554 -257.497074) (xy 371.781161 -257.481026) (xy 371.734887 -257.457448) (xy 371.692871 -257.426922)
			(xy 371.656148 -257.390199) (xy 371.625622 -257.348183) (xy 371.602044 -257.301909) (xy 371.585996 -257.252516)
			(xy 371.577871 -257.201221) (xy 371.297961 -257.201221) (xy 371.289836 -257.252516) (xy 371.273788 -257.301909)
			(xy 371.25021 -257.348183) (xy 371.219684 -257.390199) (xy 371.182961 -257.426922) (xy 371.140945 -257.457448)
			(xy 371.094671 -257.481026) (xy 371.045278 -257.497074) (xy 370.993983 -257.505199) (xy 370.942049 -257.505199)
			(xy 370.890754 -257.497074) (xy 370.841361 -257.481026) (xy 370.795087 -257.457448) (xy 370.753071 -257.426922)
			(xy 370.716348 -257.390199) (xy 370.685822 -257.348183) (xy 370.662244 -257.301909) (xy 370.646196 -257.252516)
			(xy 370.638071 -257.201221) (xy 370.358161 -257.201221) (xy 370.350036 -257.252516) (xy 370.333988 -257.301909)
			(xy 370.31041 -257.348183) (xy 370.279884 -257.390199) (xy 370.243161 -257.426922) (xy 370.201145 -257.457448)
			(xy 370.154871 -257.481026) (xy 370.105478 -257.497074) (xy 370.054183 -257.505199) (xy 370.002249 -257.505199)
			(xy 369.950954 -257.497074) (xy 369.901561 -257.481026) (xy 369.855287 -257.457448) (xy 369.813271 -257.426922)
			(xy 369.776548 -257.390199) (xy 369.746022 -257.348183) (xy 369.722444 -257.301909) (xy 369.706396 -257.252516)
			(xy 369.698271 -257.201221) (xy 369.386104 -257.201221) (xy 369.386104 -257.562858) (xy 369.386578 -257.577575)
			(xy 369.394945 -257.605793) (xy 369.411023 -257.630446) (xy 369.433473 -257.649479) (xy 369.460423 -257.661308)
			(xy 369.48963 -257.664946) (xy 369.504214 -257.662934) (xy 369.517581 -257.660883) (xy 369.544539 -257.65872)
			(xy 369.558062 -257.658616) (xy 369.584036 -257.659096) (xy 369.635344 -257.667217) (xy 369.68475 -257.683265)
			(xy 369.731037 -257.706845) (xy 369.773065 -257.737376) (xy 369.8098 -257.774106) (xy 369.840335 -257.81613)
			(xy 369.86392 -257.862415) (xy 369.879974 -257.911819) (xy 369.888101 -257.963126) (xy 369.888101 -258.015037)
			(xy 370.167917 -258.015037) (xy 370.167917 -257.963103) (xy 370.176042 -257.911808) (xy 370.19209 -257.862415)
			(xy 370.215668 -257.816141) (xy 370.246194 -257.774125) (xy 370.282917 -257.737402) (xy 370.324933 -257.706876)
			(xy 370.371207 -257.683298) (xy 370.4206 -257.66725) (xy 370.471895 -257.659125) (xy 370.523829 -257.659125)
			(xy 370.575124 -257.66725) (xy 370.624517 -257.683298) (xy 370.670791 -257.706876) (xy 370.712807 -257.737402)
			(xy 370.74953 -257.774125) (xy 370.780056 -257.816141) (xy 370.803634 -257.862415) (xy 370.819682 -257.911808)
			(xy 370.827807 -257.963103) (xy 370.828316 -257.98907) (xy 370.827807 -258.015037) (xy 371.107717 -258.015037)
			(xy 371.107717 -257.963103) (xy 371.115842 -257.911808) (xy 371.13189 -257.862415) (xy 371.155468 -257.816141)
			(xy 371.185994 -257.774125) (xy 371.222717 -257.737402) (xy 371.264733 -257.706876) (xy 371.311007 -257.683298)
			(xy 371.3604 -257.66725) (xy 371.411695 -257.659125) (xy 371.463629 -257.659125) (xy 371.514924 -257.66725)
			(xy 371.564317 -257.683298) (xy 371.610591 -257.706876) (xy 371.652607 -257.737402) (xy 371.68933 -257.774125)
			(xy 371.719856 -257.816141) (xy 371.743434 -257.862415) (xy 371.759482 -257.911808) (xy 371.767607 -257.963103)
			(xy 371.768116 -257.98907) (xy 371.767607 -258.015037) (xy 372.047517 -258.015037) (xy 372.047517 -257.963103)
			(xy 372.055642 -257.911808) (xy 372.07169 -257.862415) (xy 372.095268 -257.816141) (xy 372.125794 -257.774125)
			(xy 372.162517 -257.737402) (xy 372.204533 -257.706876) (xy 372.250807 -257.683298) (xy 372.3002 -257.66725)
			(xy 372.351495 -257.659125) (xy 372.403429 -257.659125) (xy 372.454724 -257.66725) (xy 372.504117 -257.683298)
			(xy 372.550391 -257.706876) (xy 372.592407 -257.737402) (xy 372.62913 -257.774125) (xy 372.659656 -257.816141)
			(xy 372.683234 -257.862415) (xy 372.699282 -257.911808) (xy 372.707407 -257.963103) (xy 372.707916 -257.98907)
			(xy 372.707407 -258.015037) (xy 372.699282 -258.066332) (xy 372.683234 -258.115725) (xy 372.659656 -258.161999)
			(xy 372.62913 -258.204015) (xy 372.592407 -258.240738) (xy 372.550391 -258.271264) (xy 372.504117 -258.294842)
			(xy 372.454724 -258.31089) (xy 372.403429 -258.319015) (xy 372.351495 -258.319015) (xy 372.3002 -258.31089)
			(xy 372.250807 -258.294842) (xy 372.204533 -258.271264) (xy 372.162517 -258.240738) (xy 372.125794 -258.204015)
			(xy 372.095268 -258.161999) (xy 372.07169 -258.115725) (xy 372.055642 -258.066332) (xy 372.047517 -258.015037)
			(xy 371.767607 -258.015037) (xy 371.759482 -258.066332) (xy 371.743434 -258.115725) (xy 371.719856 -258.161999)
			(xy 371.68933 -258.204015) (xy 371.652607 -258.240738) (xy 371.610591 -258.271264) (xy 371.564317 -258.294842)
			(xy 371.514924 -258.31089) (xy 371.463629 -258.319015) (xy 371.411695 -258.319015) (xy 371.3604 -258.31089)
			(xy 371.311007 -258.294842) (xy 371.264733 -258.271264) (xy 371.222717 -258.240738) (xy 371.185994 -258.204015)
			(xy 371.155468 -258.161999) (xy 371.13189 -258.115725) (xy 371.115842 -258.066332) (xy 371.107717 -258.015037)
			(xy 370.827807 -258.015037) (xy 370.819682 -258.066332) (xy 370.803634 -258.115725) (xy 370.780056 -258.161999)
			(xy 370.74953 -258.204015) (xy 370.712807 -258.240738) (xy 370.670791 -258.271264) (xy 370.624517 -258.294842)
			(xy 370.575124 -258.31089) (xy 370.523829 -258.319015) (xy 370.471895 -258.319015) (xy 370.4206 -258.31089)
			(xy 370.371207 -258.294842) (xy 370.324933 -258.271264) (xy 370.282917 -258.240738) (xy 370.246194 -258.204015)
			(xy 370.215668 -258.161999) (xy 370.19209 -258.115725) (xy 370.176042 -258.066332) (xy 370.167917 -258.015037)
			(xy 369.888101 -258.015037) (xy 369.888101 -258.015074) (xy 369.879974 -258.066381) (xy 369.86392 -258.115785)
			(xy 369.840335 -258.16207) (xy 369.8098 -258.204094) (xy 369.773065 -258.240824) (xy 369.731037 -258.271355)
			(xy 369.68475 -258.294935) (xy 369.635344 -258.310983) (xy 369.584036 -258.319104) (xy 369.558062 -258.319524)
			(xy 369.54454 -258.319406) (xy 369.517582 -258.317248) (xy 369.504214 -258.315206) (xy 369.489638 -258.313314)
			(xy 369.46049 -258.317014) (xy 369.4336 -258.328853) (xy 369.411189 -258.347853) (xy 369.39511 -258.372444)
			(xy 369.386691 -258.400593) (xy 369.386104 -258.415282) (xy 369.386104 -258.829107) (xy 369.698017 -258.829107)
			(xy 369.698017 -258.777173) (xy 369.706142 -258.725878) (xy 369.72219 -258.676485) (xy 369.745768 -258.630211)
			(xy 369.776294 -258.588195) (xy 369.813017 -258.551472) (xy 369.855033 -258.520946) (xy 369.901307 -258.497368)
			(xy 369.9507 -258.48132) (xy 370.001995 -258.473195) (xy 370.053929 -258.473195) (xy 370.105224 -258.48132)
			(xy 370.154617 -258.497368) (xy 370.200891 -258.520946) (xy 370.242907 -258.551472) (xy 370.27963 -258.588195)
			(xy 370.310156 -258.630211) (xy 370.333734 -258.676485) (xy 370.349782 -258.725878) (xy 370.357907 -258.777173)
			(xy 370.358416 -258.80314) (xy 370.357907 -258.829107) (xy 370.637817 -258.829107) (xy 370.637817 -258.777173)
			(xy 370.645942 -258.725878) (xy 370.66199 -258.676485) (xy 370.685568 -258.630211) (xy 370.716094 -258.588195)
			(xy 370.752817 -258.551472) (xy 370.794833 -258.520946) (xy 370.841107 -258.497368) (xy 370.8905 -258.48132)
			(xy 370.941795 -258.473195) (xy 370.993729 -258.473195) (xy 371.045024 -258.48132) (xy 371.094417 -258.497368)
			(xy 371.140691 -258.520946) (xy 371.182707 -258.551472) (xy 371.21943 -258.588195) (xy 371.249956 -258.630211)
			(xy 371.273534 -258.676485) (xy 371.289582 -258.725878) (xy 371.297707 -258.777173) (xy 371.298216 -258.80314)
			(xy 371.297707 -258.829107) (xy 371.577871 -258.829107) (xy 371.577871 -258.777173) (xy 371.585996 -258.725878)
			(xy 371.602044 -258.676485) (xy 371.625622 -258.630211) (xy 371.656148 -258.588195) (xy 371.692871 -258.551472)
			(xy 371.734887 -258.520946) (xy 371.781161 -258.497368) (xy 371.830554 -258.48132) (xy 371.881849 -258.473195)
			(xy 371.933783 -258.473195) (xy 371.985078 -258.48132) (xy 372.034471 -258.497368) (xy 372.080745 -258.520946)
			(xy 372.122761 -258.551472) (xy 372.159484 -258.588195) (xy 372.19001 -258.630211) (xy 372.213588 -258.676485)
			(xy 372.229636 -258.725878) (xy 372.237761 -258.777173) (xy 372.23827 -258.80314) (xy 372.237761 -258.829107)
			(xy 372.517671 -258.829107) (xy 372.517671 -258.777173) (xy 372.525796 -258.725878) (xy 372.541844 -258.676485)
			(xy 372.565422 -258.630211) (xy 372.595948 -258.588195) (xy 372.632671 -258.551472) (xy 372.674687 -258.520946)
			(xy 372.720961 -258.497368) (xy 372.770354 -258.48132) (xy 372.821649 -258.473195) (xy 372.873583 -258.473195)
			(xy 372.924878 -258.48132) (xy 372.974271 -258.497368) (xy 373.020545 -258.520946) (xy 373.062561 -258.551472)
			(xy 373.099284 -258.588195) (xy 373.12981 -258.630211) (xy 373.153388 -258.676485) (xy 373.169436 -258.725878)
			(xy 373.177561 -258.777173) (xy 373.17807 -258.80314) (xy 373.177561 -258.829107) (xy 373.169436 -258.880402)
			(xy 373.153388 -258.929795) (xy 373.12981 -258.976069) (xy 373.099284 -259.018085) (xy 373.062561 -259.054808)
			(xy 373.020545 -259.085334) (xy 372.974271 -259.108912) (xy 372.924878 -259.12496) (xy 372.873583 -259.133085)
			(xy 372.821649 -259.133085) (xy 372.770354 -259.12496) (xy 372.720961 -259.108912) (xy 372.674687 -259.085334)
			(xy 372.632671 -259.054808) (xy 372.595948 -259.018085) (xy 372.565422 -258.976069) (xy 372.541844 -258.929795)
			(xy 372.525796 -258.880402) (xy 372.517671 -258.829107) (xy 372.237761 -258.829107) (xy 372.229636 -258.880402)
			(xy 372.213588 -258.929795) (xy 372.19001 -258.976069) (xy 372.159484 -259.018085) (xy 372.122761 -259.054808)
			(xy 372.080745 -259.085334) (xy 372.034471 -259.108912) (xy 371.985078 -259.12496) (xy 371.933783 -259.133085)
			(xy 371.881849 -259.133085) (xy 371.830554 -259.12496) (xy 371.781161 -259.108912) (xy 371.734887 -259.085334)
			(xy 371.692871 -259.054808) (xy 371.656148 -259.018085) (xy 371.625622 -258.976069) (xy 371.602044 -258.929795)
			(xy 371.585996 -258.880402) (xy 371.577871 -258.829107) (xy 371.297707 -258.829107) (xy 371.289582 -258.880402)
			(xy 371.273534 -258.929795) (xy 371.249956 -258.976069) (xy 371.21943 -259.018085) (xy 371.182707 -259.054808)
			(xy 371.140691 -259.085334) (xy 371.094417 -259.108912) (xy 371.045024 -259.12496) (xy 370.993729 -259.133085)
			(xy 370.941795 -259.133085) (xy 370.8905 -259.12496) (xy 370.841107 -259.108912) (xy 370.794833 -259.085334)
			(xy 370.752817 -259.054808) (xy 370.716094 -259.018085) (xy 370.685568 -258.976069) (xy 370.66199 -258.929795)
			(xy 370.645942 -258.880402) (xy 370.637817 -258.829107) (xy 370.357907 -258.829107) (xy 370.349782 -258.880402)
			(xy 370.333734 -258.929795) (xy 370.310156 -258.976069) (xy 370.27963 -259.018085) (xy 370.242907 -259.054808)
			(xy 370.200891 -259.085334) (xy 370.154617 -259.108912) (xy 370.105224 -259.12496) (xy 370.053929 -259.133085)
			(xy 370.001995 -259.133085) (xy 369.9507 -259.12496) (xy 369.901307 -259.108912) (xy 369.855033 -259.085334)
			(xy 369.813017 -259.054808) (xy 369.776294 -259.018085) (xy 369.745768 -258.976069) (xy 369.72219 -258.929795)
			(xy 369.706142 -258.880402) (xy 369.698017 -258.829107) (xy 369.386104 -258.829107) (xy 369.386104 -259.190744)
			(xy 369.386577 -259.205462) (xy 369.394941 -259.233684) (xy 369.411018 -259.25834) (xy 369.433469 -259.277377)
			(xy 369.460422 -259.289208) (xy 369.489631 -259.292846) (xy 369.504214 -259.29082) (xy 369.517581 -259.288768)
			(xy 369.544539 -259.286605) (xy 369.558062 -259.286502) (xy 369.584037 -259.286982) (xy 369.635347 -259.295103)
			(xy 369.684755 -259.311152) (xy 369.731044 -259.334733) (xy 369.773074 -259.365265) (xy 369.80981 -259.401997)
			(xy 369.840347 -259.444023) (xy 369.863933 -259.490309) (xy 369.879988 -259.539716) (xy 369.888115 -259.591025)
			(xy 369.888115 -259.642923) (xy 370.167917 -259.642923) (xy 370.167917 -259.590989) (xy 370.176042 -259.539694)
			(xy 370.19209 -259.490301) (xy 370.215668 -259.444027) (xy 370.246194 -259.402011) (xy 370.282917 -259.365288)
			(xy 370.324933 -259.334762) (xy 370.371207 -259.311184) (xy 370.4206 -259.295136) (xy 370.471895 -259.287011)
			(xy 370.523829 -259.287011) (xy 370.575124 -259.295136) (xy 370.624517 -259.311184) (xy 370.670791 -259.334762)
			(xy 370.712807 -259.365288) (xy 370.74953 -259.402011) (xy 370.780056 -259.444027) (xy 370.803634 -259.490301)
			(xy 370.819682 -259.539694) (xy 370.827807 -259.590989) (xy 370.828316 -259.616956) (xy 370.827807 -259.642923)
			(xy 371.107717 -259.642923) (xy 371.107717 -259.590989) (xy 371.115842 -259.539694) (xy 371.13189 -259.490301)
			(xy 371.155468 -259.444027) (xy 371.185994 -259.402011) (xy 371.222717 -259.365288) (xy 371.264733 -259.334762)
			(xy 371.311007 -259.311184) (xy 371.3604 -259.295136) (xy 371.411695 -259.287011) (xy 371.463629 -259.287011)
			(xy 371.514924 -259.295136) (xy 371.564317 -259.311184) (xy 371.610591 -259.334762) (xy 371.652607 -259.365288)
			(xy 371.68933 -259.402011) (xy 371.719856 -259.444027) (xy 371.743434 -259.490301) (xy 371.759482 -259.539694)
			(xy 371.767607 -259.590989) (xy 371.768116 -259.616956) (xy 371.767607 -259.642923) (xy 372.047517 -259.642923)
			(xy 372.047517 -259.590989) (xy 372.055642 -259.539694) (xy 372.07169 -259.490301) (xy 372.095268 -259.444027)
			(xy 372.125794 -259.402011) (xy 372.162517 -259.365288) (xy 372.204533 -259.334762) (xy 372.250807 -259.311184)
			(xy 372.3002 -259.295136) (xy 372.351495 -259.287011) (xy 372.403429 -259.287011) (xy 372.454724 -259.295136)
			(xy 372.504117 -259.311184) (xy 372.550391 -259.334762) (xy 372.592407 -259.365288) (xy 372.62913 -259.402011)
			(xy 372.659656 -259.444027) (xy 372.683234 -259.490301) (xy 372.699282 -259.539694) (xy 372.707407 -259.590989)
			(xy 372.707916 -259.616956) (xy 372.707407 -259.642923) (xy 372.699282 -259.694218) (xy 372.683234 -259.743611)
			(xy 372.659656 -259.789885) (xy 372.62913 -259.831901) (xy 372.592407 -259.868624) (xy 372.550391 -259.89915)
			(xy 372.504117 -259.922728) (xy 372.454724 -259.938776) (xy 372.403429 -259.946901) (xy 372.351495 -259.946901)
			(xy 372.3002 -259.938776) (xy 372.250807 -259.922728) (xy 372.204533 -259.89915) (xy 372.162517 -259.868624)
			(xy 372.125794 -259.831901) (xy 372.095268 -259.789885) (xy 372.07169 -259.743611) (xy 372.055642 -259.694218)
			(xy 372.047517 -259.642923) (xy 371.767607 -259.642923) (xy 371.759482 -259.694218) (xy 371.743434 -259.743611)
			(xy 371.719856 -259.789885) (xy 371.68933 -259.831901) (xy 371.652607 -259.868624) (xy 371.610591 -259.89915)
			(xy 371.564317 -259.922728) (xy 371.514924 -259.938776) (xy 371.463629 -259.946901) (xy 371.411695 -259.946901)
			(xy 371.3604 -259.938776) (xy 371.311007 -259.922728) (xy 371.264733 -259.89915) (xy 371.222717 -259.868624)
			(xy 371.185994 -259.831901) (xy 371.155468 -259.789885) (xy 371.13189 -259.743611) (xy 371.115842 -259.694218)
			(xy 371.107717 -259.642923) (xy 370.827807 -259.642923) (xy 370.819682 -259.694218) (xy 370.803634 -259.743611)
			(xy 370.780056 -259.789885) (xy 370.74953 -259.831901) (xy 370.712807 -259.868624) (xy 370.670791 -259.89915)
			(xy 370.624517 -259.922728) (xy 370.575124 -259.938776) (xy 370.523829 -259.946901) (xy 370.471895 -259.946901)
			(xy 370.4206 -259.938776) (xy 370.371207 -259.922728) (xy 370.324933 -259.89915) (xy 370.282917 -259.868624)
			(xy 370.246194 -259.831901) (xy 370.215668 -259.789885) (xy 370.19209 -259.743611) (xy 370.176042 -259.694218)
			(xy 370.167917 -259.642923) (xy 369.888115 -259.642923) (xy 369.888115 -259.642975) (xy 369.879988 -259.694284)
			(xy 369.863933 -259.743691) (xy 369.840347 -259.789977) (xy 369.80981 -259.832003) (xy 369.773074 -259.868735)
			(xy 369.731044 -259.899267) (xy 369.684755 -259.922848) (xy 369.635347 -259.938897) (xy 369.584037 -259.947018)
			(xy 369.558062 -259.94741) (xy 369.532785 -259.946926) (xy 369.482822 -259.939217) (xy 369.434617 -259.923984)
			(xy 369.389297 -259.901584) (xy 369.368324 -259.887466) (xy 369.333526 -259.863082) (xy 368.981482 -260.215126)
			(xy 368.431064 -260.215126) (xy 368.189451 -260.456739) (xy 369.698271 -260.456739) (xy 369.698271 -260.404805)
			(xy 369.706396 -260.35351) (xy 369.722444 -260.304117) (xy 369.746022 -260.257843) (xy 369.776548 -260.215827)
			(xy 369.813271 -260.179104) (xy 369.855287 -260.148578) (xy 369.901561 -260.125) (xy 369.950954 -260.108952)
			(xy 370.002249 -260.100827) (xy 370.054183 -260.100827) (xy 370.105478 -260.108952) (xy 370.154871 -260.125)
			(xy 370.201145 -260.148578) (xy 370.243161 -260.179104) (xy 370.279884 -260.215827) (xy 370.31041 -260.257843)
			(xy 370.333988 -260.304117) (xy 370.350036 -260.35351) (xy 370.358161 -260.404805) (xy 370.35867 -260.430772)
			(xy 370.358161 -260.456739) (xy 370.638071 -260.456739) (xy 370.638071 -260.404805) (xy 370.646196 -260.35351)
			(xy 370.662244 -260.304117) (xy 370.685822 -260.257843) (xy 370.716348 -260.215827) (xy 370.753071 -260.179104)
			(xy 370.795087 -260.148578) (xy 370.841361 -260.125) (xy 370.890754 -260.108952) (xy 370.942049 -260.100827)
			(xy 370.993983 -260.100827) (xy 371.045278 -260.108952) (xy 371.094671 -260.125) (xy 371.140945 -260.148578)
			(xy 371.182961 -260.179104) (xy 371.219684 -260.215827) (xy 371.25021 -260.257843) (xy 371.273788 -260.304117)
			(xy 371.289836 -260.35351) (xy 371.297961 -260.404805) (xy 371.29847 -260.430772) (xy 371.297961 -260.456739)
			(xy 371.577871 -260.456739) (xy 371.577871 -260.404805) (xy 371.585996 -260.35351) (xy 371.602044 -260.304117)
			(xy 371.625622 -260.257843) (xy 371.656148 -260.215827) (xy 371.692871 -260.179104) (xy 371.734887 -260.148578)
			(xy 371.781161 -260.125) (xy 371.830554 -260.108952) (xy 371.881849 -260.100827) (xy 371.933783 -260.100827)
			(xy 371.985078 -260.108952) (xy 372.034471 -260.125) (xy 372.080745 -260.148578) (xy 372.122761 -260.179104)
			(xy 372.159484 -260.215827) (xy 372.19001 -260.257843) (xy 372.213588 -260.304117) (xy 372.229636 -260.35351)
			(xy 372.237761 -260.404805) (xy 372.23827 -260.430772) (xy 372.237761 -260.456739) (xy 372.517671 -260.456739)
			(xy 372.517671 -260.404805) (xy 372.525796 -260.35351) (xy 372.541844 -260.304117) (xy 372.565422 -260.257843)
			(xy 372.595948 -260.215827) (xy 372.632671 -260.179104) (xy 372.674687 -260.148578) (xy 372.720961 -260.125)
			(xy 372.770354 -260.108952) (xy 372.821649 -260.100827) (xy 372.873583 -260.100827) (xy 372.924878 -260.108952)
			(xy 372.974271 -260.125) (xy 373.020545 -260.148578) (xy 373.062561 -260.179104) (xy 373.099284 -260.215827)
			(xy 373.12981 -260.257843) (xy 373.153388 -260.304117) (xy 373.169436 -260.35351) (xy 373.177561 -260.404805)
			(xy 373.17807 -260.430772) (xy 373.177561 -260.456739) (xy 373.169436 -260.508034) (xy 373.153388 -260.557427)
			(xy 373.12981 -260.603701) (xy 373.099284 -260.645717) (xy 373.062561 -260.68244) (xy 373.020545 -260.712966)
			(xy 372.974271 -260.736544) (xy 372.924878 -260.752592) (xy 372.873583 -260.760717) (xy 372.821649 -260.760717)
			(xy 372.770354 -260.752592) (xy 372.720961 -260.736544) (xy 372.674687 -260.712966) (xy 372.632671 -260.68244)
			(xy 372.595948 -260.645717) (xy 372.565422 -260.603701) (xy 372.541844 -260.557427) (xy 372.525796 -260.508034)
			(xy 372.517671 -260.456739) (xy 372.237761 -260.456739) (xy 372.229636 -260.508034) (xy 372.213588 -260.557427)
			(xy 372.19001 -260.603701) (xy 372.159484 -260.645717) (xy 372.122761 -260.68244) (xy 372.080745 -260.712966)
			(xy 372.034471 -260.736544) (xy 371.985078 -260.752592) (xy 371.933783 -260.760717) (xy 371.881849 -260.760717)
			(xy 371.830554 -260.752592) (xy 371.781161 -260.736544) (xy 371.734887 -260.712966) (xy 371.692871 -260.68244)
			(xy 371.656148 -260.645717) (xy 371.625622 -260.603701) (xy 371.602044 -260.557427) (xy 371.585996 -260.508034)
			(xy 371.577871 -260.456739) (xy 371.297961 -260.456739) (xy 371.289836 -260.508034) (xy 371.273788 -260.557427)
			(xy 371.25021 -260.603701) (xy 371.219684 -260.645717) (xy 371.182961 -260.68244) (xy 371.140945 -260.712966)
			(xy 371.094671 -260.736544) (xy 371.045278 -260.752592) (xy 370.993983 -260.760717) (xy 370.942049 -260.760717)
			(xy 370.890754 -260.752592) (xy 370.841361 -260.736544) (xy 370.795087 -260.712966) (xy 370.753071 -260.68244)
			(xy 370.716348 -260.645717) (xy 370.685822 -260.603701) (xy 370.662244 -260.557427) (xy 370.646196 -260.508034)
			(xy 370.638071 -260.456739) (xy 370.358161 -260.456739) (xy 370.350036 -260.508034) (xy 370.333988 -260.557427)
			(xy 370.31041 -260.603701) (xy 370.279884 -260.645717) (xy 370.243161 -260.68244) (xy 370.201145 -260.712966)
			(xy 370.154871 -260.736544) (xy 370.105478 -260.752592) (xy 370.054183 -260.760717) (xy 370.002249 -260.760717)
			(xy 369.950954 -260.752592) (xy 369.901561 -260.736544) (xy 369.855287 -260.712966) (xy 369.813271 -260.68244)
			(xy 369.776548 -260.645717) (xy 369.746022 -260.603701) (xy 369.722444 -260.557427) (xy 369.706396 -260.508034)
			(xy 369.698271 -260.456739) (xy 368.189451 -260.456739) (xy 367.375381 -261.270809) (xy 369.228117 -261.270809)
			(xy 369.228117 -261.218875) (xy 369.236242 -261.16758) (xy 369.25229 -261.118187) (xy 369.275868 -261.071913)
			(xy 369.306394 -261.029897) (xy 369.343117 -260.993174) (xy 369.385133 -260.962648) (xy 369.431407 -260.93907)
			(xy 369.4808 -260.923022) (xy 369.532095 -260.914897) (xy 369.584029 -260.914897) (xy 369.635324 -260.923022)
			(xy 369.684717 -260.93907) (xy 369.730991 -260.962648) (xy 369.773007 -260.993174) (xy 369.80973 -261.029897)
			(xy 369.840256 -261.071913) (xy 369.863834 -261.118187) (xy 369.879882 -261.16758) (xy 369.888007 -261.218875)
			(xy 369.888516 -261.244842) (xy 369.888007 -261.270809) (xy 370.167917 -261.270809) (xy 370.167917 -261.218875)
			(xy 370.176042 -261.16758) (xy 370.19209 -261.118187) (xy 370.215668 -261.071913) (xy 370.246194 -261.029897)
			(xy 370.282917 -260.993174) (xy 370.324933 -260.962648) (xy 370.371207 -260.93907) (xy 370.4206 -260.923022)
			(xy 370.471895 -260.914897) (xy 370.523829 -260.914897) (xy 370.575124 -260.923022) (xy 370.624517 -260.93907)
			(xy 370.670791 -260.962648) (xy 370.712807 -260.993174) (xy 370.74953 -261.029897) (xy 370.780056 -261.071913)
			(xy 370.803634 -261.118187) (xy 370.819682 -261.16758) (xy 370.827807 -261.218875) (xy 370.828316 -261.244842)
			(xy 370.827807 -261.270809) (xy 371.107717 -261.270809) (xy 371.107717 -261.218875) (xy 371.115842 -261.16758)
			(xy 371.13189 -261.118187) (xy 371.155468 -261.071913) (xy 371.185994 -261.029897) (xy 371.222717 -260.993174)
			(xy 371.264733 -260.962648) (xy 371.311007 -260.93907) (xy 371.3604 -260.923022) (xy 371.411695 -260.914897)
			(xy 371.463629 -260.914897) (xy 371.514924 -260.923022) (xy 371.564317 -260.93907) (xy 371.610591 -260.962648)
			(xy 371.652607 -260.993174) (xy 371.68933 -261.029897) (xy 371.719856 -261.071913) (xy 371.743434 -261.118187)
			(xy 371.759482 -261.16758) (xy 371.767607 -261.218875) (xy 371.768116 -261.244842) (xy 371.767607 -261.270809)
			(xy 372.047517 -261.270809) (xy 372.047517 -261.218875) (xy 372.055642 -261.16758) (xy 372.07169 -261.118187)
			(xy 372.095268 -261.071913) (xy 372.125794 -261.029897) (xy 372.162517 -260.993174) (xy 372.204533 -260.962648)
			(xy 372.250807 -260.93907) (xy 372.3002 -260.923022) (xy 372.351495 -260.914897) (xy 372.403429 -260.914897)
			(xy 372.454724 -260.923022) (xy 372.504117 -260.93907) (xy 372.550391 -260.962648) (xy 372.592407 -260.993174)
			(xy 372.62913 -261.029897) (xy 372.659656 -261.071913) (xy 372.683234 -261.118187) (xy 372.699282 -261.16758)
			(xy 372.707407 -261.218875) (xy 372.707916 -261.244842) (xy 372.707407 -261.270809) (xy 372.699282 -261.322104)
			(xy 372.683234 -261.371497) (xy 372.659656 -261.417771) (xy 372.62913 -261.459787) (xy 372.592407 -261.49651)
			(xy 372.550391 -261.527036) (xy 372.504117 -261.550614) (xy 372.454724 -261.566662) (xy 372.403429 -261.574787)
			(xy 372.351495 -261.574787) (xy 372.3002 -261.566662) (xy 372.250807 -261.550614) (xy 372.204533 -261.527036)
			(xy 372.162517 -261.49651) (xy 372.125794 -261.459787) (xy 372.095268 -261.417771) (xy 372.07169 -261.371497)
			(xy 372.055642 -261.322104) (xy 372.047517 -261.270809) (xy 371.767607 -261.270809) (xy 371.759482 -261.322104)
			(xy 371.743434 -261.371497) (xy 371.719856 -261.417771) (xy 371.68933 -261.459787) (xy 371.652607 -261.49651)
			(xy 371.610591 -261.527036) (xy 371.564317 -261.550614) (xy 371.514924 -261.566662) (xy 371.463629 -261.574787)
			(xy 371.411695 -261.574787) (xy 371.3604 -261.566662) (xy 371.311007 -261.550614) (xy 371.264733 -261.527036)
			(xy 371.222717 -261.49651) (xy 371.185994 -261.459787) (xy 371.155468 -261.417771) (xy 371.13189 -261.371497)
			(xy 371.115842 -261.322104) (xy 371.107717 -261.270809) (xy 370.827807 -261.270809) (xy 370.819682 -261.322104)
			(xy 370.803634 -261.371497) (xy 370.780056 -261.417771) (xy 370.74953 -261.459787) (xy 370.712807 -261.49651)
			(xy 370.670791 -261.527036) (xy 370.624517 -261.550614) (xy 370.575124 -261.566662) (xy 370.523829 -261.574787)
			(xy 370.471895 -261.574787) (xy 370.4206 -261.566662) (xy 370.371207 -261.550614) (xy 370.324933 -261.527036)
			(xy 370.282917 -261.49651) (xy 370.246194 -261.459787) (xy 370.215668 -261.417771) (xy 370.19209 -261.371497)
			(xy 370.176042 -261.322104) (xy 370.167917 -261.270809) (xy 369.888007 -261.270809) (xy 369.879882 -261.322104)
			(xy 369.863834 -261.371497) (xy 369.840256 -261.417771) (xy 369.80973 -261.459787) (xy 369.773007 -261.49651)
			(xy 369.730991 -261.527036) (xy 369.684717 -261.550614) (xy 369.635324 -261.566662) (xy 369.584029 -261.574787)
			(xy 369.532095 -261.574787) (xy 369.4808 -261.566662) (xy 369.431407 -261.550614) (xy 369.385133 -261.527036)
			(xy 369.343117 -261.49651) (xy 369.306394 -261.459787) (xy 369.275868 -261.417771) (xy 369.25229 -261.371497)
			(xy 369.236242 -261.322104) (xy 369.228117 -261.270809) (xy 367.375381 -261.270809) (xy 366.561565 -262.084625)
			(xy 369.698271 -262.084625) (xy 369.698271 -262.032691) (xy 369.706396 -261.981396) (xy 369.722444 -261.932003)
			(xy 369.746022 -261.885729) (xy 369.776548 -261.843713) (xy 369.813271 -261.80699) (xy 369.855287 -261.776464)
			(xy 369.901561 -261.752886) (xy 369.950954 -261.736838) (xy 370.002249 -261.728713) (xy 370.054183 -261.728713)
			(xy 370.105478 -261.736838) (xy 370.154871 -261.752886) (xy 370.201145 -261.776464) (xy 370.243161 -261.80699)
			(xy 370.279884 -261.843713) (xy 370.31041 -261.885729) (xy 370.333988 -261.932003) (xy 370.350036 -261.981396)
			(xy 370.358161 -262.032691) (xy 370.35867 -262.058658) (xy 370.358161 -262.084625) (xy 370.637817 -262.084625)
			(xy 370.637817 -262.032691) (xy 370.645942 -261.981396) (xy 370.66199 -261.932003) (xy 370.685568 -261.885729)
			(xy 370.716094 -261.843713) (xy 370.752817 -261.80699) (xy 370.794833 -261.776464) (xy 370.841107 -261.752886)
			(xy 370.8905 -261.736838) (xy 370.941795 -261.728713) (xy 370.993729 -261.728713) (xy 371.045024 -261.736838)
			(xy 371.094417 -261.752886) (xy 371.140691 -261.776464) (xy 371.182707 -261.80699) (xy 371.21943 -261.843713)
			(xy 371.249956 -261.885729) (xy 371.273534 -261.932003) (xy 371.289582 -261.981396) (xy 371.297707 -262.032691)
			(xy 371.298216 -262.058658) (xy 371.297707 -262.084625) (xy 371.577871 -262.084625) (xy 371.577871 -262.032691)
			(xy 371.585996 -261.981396) (xy 371.602044 -261.932003) (xy 371.625622 -261.885729) (xy 371.656148 -261.843713)
			(xy 371.692871 -261.80699) (xy 371.734887 -261.776464) (xy 371.781161 -261.752886) (xy 371.830554 -261.736838)
			(xy 371.881849 -261.728713) (xy 371.933783 -261.728713) (xy 371.985078 -261.736838) (xy 372.034471 -261.752886)
			(xy 372.080745 -261.776464) (xy 372.122761 -261.80699) (xy 372.159484 -261.843713) (xy 372.19001 -261.885729)
			(xy 372.213588 -261.932003) (xy 372.229636 -261.981396) (xy 372.237761 -262.032691) (xy 372.23827 -262.058658)
			(xy 372.237761 -262.084625) (xy 372.517671 -262.084625) (xy 372.517671 -262.032691) (xy 372.525796 -261.981396)
			(xy 372.541844 -261.932003) (xy 372.565422 -261.885729) (xy 372.595948 -261.843713) (xy 372.632671 -261.80699)
			(xy 372.674687 -261.776464) (xy 372.720961 -261.752886) (xy 372.770354 -261.736838) (xy 372.821649 -261.728713)
			(xy 372.873583 -261.728713) (xy 372.924878 -261.736838) (xy 372.974271 -261.752886) (xy 373.020545 -261.776464)
			(xy 373.062561 -261.80699) (xy 373.099284 -261.843713) (xy 373.12981 -261.885729) (xy 373.153388 -261.932003)
			(xy 373.169436 -261.981396) (xy 373.177561 -262.032691) (xy 373.17807 -262.058658) (xy 373.177561 -262.084625)
			(xy 373.169436 -262.13592) (xy 373.153388 -262.185313) (xy 373.12981 -262.231587) (xy 373.099284 -262.273603)
			(xy 373.062561 -262.310326) (xy 373.020545 -262.340852) (xy 372.974271 -262.36443) (xy 372.924878 -262.380478)
			(xy 372.873583 -262.388603) (xy 372.821649 -262.388603) (xy 372.770354 -262.380478) (xy 372.720961 -262.36443)
			(xy 372.674687 -262.340852) (xy 372.632671 -262.310326) (xy 372.595948 -262.273603) (xy 372.565422 -262.231587)
			(xy 372.541844 -262.185313) (xy 372.525796 -262.13592) (xy 372.517671 -262.084625) (xy 372.237761 -262.084625)
			(xy 372.229636 -262.13592) (xy 372.213588 -262.185313) (xy 372.19001 -262.231587) (xy 372.159484 -262.273603)
			(xy 372.122761 -262.310326) (xy 372.080745 -262.340852) (xy 372.034471 -262.36443) (xy 371.985078 -262.380478)
			(xy 371.933783 -262.388603) (xy 371.881849 -262.388603) (xy 371.830554 -262.380478) (xy 371.781161 -262.36443)
			(xy 371.734887 -262.340852) (xy 371.692871 -262.310326) (xy 371.656148 -262.273603) (xy 371.625622 -262.231587)
			(xy 371.602044 -262.185313) (xy 371.585996 -262.13592) (xy 371.577871 -262.084625) (xy 371.297707 -262.084625)
			(xy 371.289582 -262.13592) (xy 371.273534 -262.185313) (xy 371.249956 -262.231587) (xy 371.21943 -262.273603)
			(xy 371.182707 -262.310326) (xy 371.140691 -262.340852) (xy 371.094417 -262.36443) (xy 371.045024 -262.380478)
			(xy 370.993729 -262.388603) (xy 370.941795 -262.388603) (xy 370.8905 -262.380478) (xy 370.841107 -262.36443)
			(xy 370.794833 -262.340852) (xy 370.752817 -262.310326) (xy 370.716094 -262.273603) (xy 370.685568 -262.231587)
			(xy 370.66199 -262.185313) (xy 370.645942 -262.13592) (xy 370.637817 -262.084625) (xy 370.358161 -262.084625)
			(xy 370.350036 -262.13592) (xy 370.333988 -262.185313) (xy 370.31041 -262.231587) (xy 370.279884 -262.273603)
			(xy 370.243161 -262.310326) (xy 370.201145 -262.340852) (xy 370.154871 -262.36443) (xy 370.105478 -262.380478)
			(xy 370.054183 -262.388603) (xy 370.002249 -262.388603) (xy 369.950954 -262.380478) (xy 369.901561 -262.36443)
			(xy 369.855287 -262.340852) (xy 369.813271 -262.310326) (xy 369.776548 -262.273603) (xy 369.746022 -262.231587)
			(xy 369.722444 -262.185313) (xy 369.706396 -262.13592) (xy 369.698271 -262.084625) (xy 366.561565 -262.084625)
			(xy 365.637064 -263.009126) (xy 365.637064 -263.083548) (xy 365.677704 -263.09193) (xy 365.702199 -263.097465)
			(xy 365.749275 -263.114944) (xy 365.793165 -263.139346) (xy 365.832856 -263.170108) (xy 365.867435 -263.206522)
			(xy 365.896105 -263.24775) (xy 365.918205 -263.292842) (xy 365.933228 -263.340759) (xy 365.940827 -263.390397)
			(xy 365.940827 -263.402123) (xy 366.329469 -263.402123) (xy 366.329469 -263.350189) (xy 366.337594 -263.298894)
			(xy 366.353642 -263.249501) (xy 366.37722 -263.203227) (xy 366.407746 -263.161211) (xy 366.444469 -263.124488)
			(xy 366.486485 -263.093962) (xy 366.532759 -263.070384) (xy 366.582152 -263.054336) (xy 366.633447 -263.046211)
			(xy 366.685381 -263.046211) (xy 366.736676 -263.054336) (xy 366.786069 -263.070384) (xy 366.832343 -263.093962)
			(xy 366.874359 -263.124488) (xy 366.911082 -263.161211) (xy 366.941608 -263.203227) (xy 366.965186 -263.249501)
			(xy 366.981234 -263.298894) (xy 366.981974 -263.303567) (xy 367.315759 -263.303567) (xy 367.315759 -263.251633)
			(xy 367.323883 -263.200339) (xy 367.339932 -263.150948) (xy 367.363509 -263.104675) (xy 367.394034 -263.062659)
			(xy 367.430756 -263.025937) (xy 367.472771 -262.995411) (xy 367.519044 -262.971833) (xy 367.568435 -262.955784)
			(xy 367.619729 -262.94766) (xy 367.645696 -262.94715) (xy 367.672209 -262.947689) (xy 367.724554 -262.956172)
			(xy 367.774866 -262.97292) (xy 367.798604 -262.984742) (xy 367.812288 -262.99133) (xy 367.842135 -262.996881)
			(xy 367.872296 -262.993424) (xy 367.900112 -262.981263) (xy 367.923131 -262.96147) (xy 367.9317 -262.948928)
			(xy 367.946989 -262.92579) (xy 367.984057 -262.884544) (xy 368.027492 -262.850066) (xy 368.076075 -262.823326)
			(xy 368.12844 -262.805073) (xy 368.183118 -262.795821) (xy 368.210846 -262.795258) (xy 368.236812 -262.795747)
			(xy 368.288103 -262.803877) (xy 368.337491 -262.81993) (xy 368.383761 -262.843511) (xy 368.425772 -262.87404)
			(xy 368.45017 -262.898441) (xy 369.228117 -262.898441) (xy 369.228117 -262.846507) (xy 369.236242 -262.795212)
			(xy 369.25229 -262.745819) (xy 369.275868 -262.699545) (xy 369.306394 -262.657529) (xy 369.343117 -262.620806)
			(xy 369.385133 -262.59028) (xy 369.431407 -262.566702) (xy 369.4808 -262.550654) (xy 369.532095 -262.542529)
			(xy 369.584029 -262.542529) (xy 369.635324 -262.550654) (xy 369.684717 -262.566702) (xy 369.730991 -262.59028)
			(xy 369.773007 -262.620806) (xy 369.80973 -262.657529) (xy 369.840256 -262.699545) (xy 369.863834 -262.745819)
			(xy 369.879882 -262.795212) (xy 369.888007 -262.846507) (xy 369.888516 -262.872474) (xy 369.888007 -262.898441)
			(xy 370.168171 -262.898441) (xy 370.168171 -262.846507) (xy 370.176296 -262.795212) (xy 370.192344 -262.745819)
			(xy 370.215922 -262.699545) (xy 370.246448 -262.657529) (xy 370.283171 -262.620806) (xy 370.325187 -262.59028)
			(xy 370.371461 -262.566702) (xy 370.420854 -262.550654) (xy 370.472149 -262.542529) (xy 370.524083 -262.542529)
			(xy 370.575378 -262.550654) (xy 370.624771 -262.566702) (xy 370.671045 -262.59028) (xy 370.713061 -262.620806)
			(xy 370.749784 -262.657529) (xy 370.78031 -262.699545) (xy 370.803888 -262.745819) (xy 370.819936 -262.795212)
			(xy 370.828061 -262.846507) (xy 370.82857 -262.872474) (xy 370.828061 -262.898441) (xy 371.107717 -262.898441)
			(xy 371.107717 -262.846507) (xy 371.115842 -262.795212) (xy 371.13189 -262.745819) (xy 371.155468 -262.699545)
			(xy 371.185994 -262.657529) (xy 371.222717 -262.620806) (xy 371.264733 -262.59028) (xy 371.311007 -262.566702)
			(xy 371.3604 -262.550654) (xy 371.411695 -262.542529) (xy 371.463629 -262.542529) (xy 371.514924 -262.550654)
			(xy 371.564317 -262.566702) (xy 371.610591 -262.59028) (xy 371.652607 -262.620806) (xy 371.68933 -262.657529)
			(xy 371.719856 -262.699545) (xy 371.743434 -262.745819) (xy 371.759482 -262.795212) (xy 371.767607 -262.846507)
			(xy 371.768116 -262.872474) (xy 371.767607 -262.898441) (xy 372.047517 -262.898441) (xy 372.047517 -262.846507)
			(xy 372.055642 -262.795212) (xy 372.07169 -262.745819) (xy 372.095268 -262.699545) (xy 372.125794 -262.657529)
			(xy 372.162517 -262.620806) (xy 372.204533 -262.59028) (xy 372.250807 -262.566702) (xy 372.3002 -262.550654)
			(xy 372.351495 -262.542529) (xy 372.403429 -262.542529) (xy 372.454724 -262.550654) (xy 372.504117 -262.566702)
			(xy 372.550391 -262.59028) (xy 372.592407 -262.620806) (xy 372.62913 -262.657529) (xy 372.659656 -262.699545)
			(xy 372.683234 -262.745819) (xy 372.699282 -262.795212) (xy 372.707407 -262.846507) (xy 372.707916 -262.872474)
			(xy 372.707407 -262.898441) (xy 372.699282 -262.949736) (xy 372.683234 -262.999129) (xy 372.659656 -263.045403)
			(xy 372.62913 -263.087419) (xy 372.592407 -263.124142) (xy 372.550391 -263.154668) (xy 372.504117 -263.178246)
			(xy 372.454724 -263.194294) (xy 372.403429 -263.202419) (xy 372.351495 -263.202419) (xy 372.3002 -263.194294)
			(xy 372.250807 -263.178246) (xy 372.204533 -263.154668) (xy 372.162517 -263.124142) (xy 372.125794 -263.087419)
			(xy 372.095268 -263.045403) (xy 372.07169 -262.999129) (xy 372.055642 -262.949736) (xy 372.047517 -262.898441)
			(xy 371.767607 -262.898441) (xy 371.759482 -262.949736) (xy 371.743434 -262.999129) (xy 371.719856 -263.045403)
			(xy 371.68933 -263.087419) (xy 371.652607 -263.124142) (xy 371.610591 -263.154668) (xy 371.564317 -263.178246)
			(xy 371.514924 -263.194294) (xy 371.463629 -263.202419) (xy 371.411695 -263.202419) (xy 371.3604 -263.194294)
			(xy 371.311007 -263.178246) (xy 371.264733 -263.154668) (xy 371.222717 -263.124142) (xy 371.185994 -263.087419)
			(xy 371.155468 -263.045403) (xy 371.13189 -262.999129) (xy 371.115842 -262.949736) (xy 371.107717 -262.898441)
			(xy 370.828061 -262.898441) (xy 370.819936 -262.949736) (xy 370.803888 -262.999129) (xy 370.78031 -263.045403)
			(xy 370.749784 -263.087419) (xy 370.713061 -263.124142) (xy 370.671045 -263.154668) (xy 370.624771 -263.178246)
			(xy 370.575378 -263.194294) (xy 370.524083 -263.202419) (xy 370.472149 -263.202419) (xy 370.420854 -263.194294)
			(xy 370.371461 -263.178246) (xy 370.325187 -263.154668) (xy 370.283171 -263.124142) (xy 370.246448 -263.087419)
			(xy 370.215922 -263.045403) (xy 370.192344 -262.999129) (xy 370.176296 -262.949736) (xy 370.168171 -262.898441)
			(xy 369.888007 -262.898441) (xy 369.879882 -262.949736) (xy 369.863834 -262.999129) (xy 369.840256 -263.045403)
			(xy 369.80973 -263.087419) (xy 369.773007 -263.124142) (xy 369.730991 -263.154668) (xy 369.684717 -263.178246)
			(xy 369.635324 -263.194294) (xy 369.584029 -263.202419) (xy 369.532095 -263.202419) (xy 369.4808 -263.194294)
			(xy 369.431407 -263.178246) (xy 369.385133 -263.154668) (xy 369.343117 -263.124142) (xy 369.306394 -263.087419)
			(xy 369.275868 -263.045403) (xy 369.25229 -262.999129) (xy 369.236242 -262.949736) (xy 369.228117 -262.898441)
			(xy 368.45017 -262.898441) (xy 368.46249 -262.910763) (xy 368.493013 -262.952779) (xy 368.516587 -262.999051)
			(xy 368.532634 -263.048442) (xy 368.540757 -263.099734) (xy 368.540757 -263.151666) (xy 368.532634 -263.202958)
			(xy 368.516587 -263.252349) (xy 368.493013 -263.298621) (xy 368.46249 -263.340637) (xy 368.425772 -263.37736)
			(xy 368.383761 -263.407889) (xy 368.337491 -263.43147) (xy 368.288103 -263.447523) (xy 368.236812 -263.455653)
			(xy 368.210846 -263.456166) (xy 368.184331 -263.455659) (xy 368.131986 -263.447164) (xy 368.081674 -263.430403)
			(xy 368.057938 -263.418574) (xy 368.044236 -263.412025) (xy 368.014398 -263.406464) (xy 367.984242 -263.409912)
			(xy 367.956428 -263.422064) (xy 367.933411 -263.44185) (xy 367.924842 -263.454388) (xy 367.909498 -263.477488)
			(xy 367.872444 -263.51874) (xy 367.829021 -263.553224) (xy 367.780449 -263.579972) (xy 367.728092 -263.598232)
			(xy 367.673421 -263.607492) (xy 367.645696 -263.608058) (xy 367.619729 -263.60754) (xy 367.568435 -263.599416)
			(xy 367.519044 -263.583367) (xy 367.472771 -263.559789) (xy 367.430756 -263.529263) (xy 367.394034 -263.492541)
			(xy 367.363509 -263.450525) (xy 367.339932 -263.404252) (xy 367.323883 -263.354861) (xy 367.315759 -263.303567)
			(xy 366.981974 -263.303567) (xy 366.989359 -263.350189) (xy 366.989868 -263.376156) (xy 366.989359 -263.402123)
			(xy 366.981234 -263.453418) (xy 366.965186 -263.502811) (xy 366.941608 -263.549085) (xy 366.911082 -263.591101)
			(xy 366.874359 -263.627824) (xy 366.832343 -263.65835) (xy 366.786069 -263.681928) (xy 366.736676 -263.697976)
			(xy 366.685381 -263.706101) (xy 366.633447 -263.706101) (xy 366.582152 -263.697976) (xy 366.532759 -263.681928)
			(xy 366.486485 -263.65835) (xy 366.444469 -263.627824) (xy 366.407746 -263.591101) (xy 366.37722 -263.549085)
			(xy 366.353642 -263.502811) (xy 366.337594 -263.453418) (xy 366.329469 -263.402123) (xy 365.940827 -263.402123)
			(xy 365.940826 -263.440614) (xy 365.933226 -263.490252) (xy 365.918202 -263.538168) (xy 365.896099 -263.583259)
			(xy 365.867428 -263.624486) (xy 365.832848 -263.660899) (xy 365.793156 -263.69166) (xy 365.75565 -263.712511)
			(xy 369.698271 -263.712511) (xy 369.698271 -263.660577) (xy 369.706396 -263.609282) (xy 369.722444 -263.559889)
			(xy 369.746022 -263.513615) (xy 369.776548 -263.471599) (xy 369.813271 -263.434876) (xy 369.855287 -263.40435)
			(xy 369.901561 -263.380772) (xy 369.950954 -263.364724) (xy 370.002249 -263.356599) (xy 370.054183 -263.356599)
			(xy 370.105478 -263.364724) (xy 370.154871 -263.380772) (xy 370.201145 -263.40435) (xy 370.243161 -263.434876)
			(xy 370.279884 -263.471599) (xy 370.31041 -263.513615) (xy 370.333988 -263.559889) (xy 370.350036 -263.609282)
			(xy 370.358161 -263.660577) (xy 370.35867 -263.686544) (xy 370.358161 -263.712511) (xy 370.637817 -263.712511)
			(xy 370.637817 -263.660577) (xy 370.645942 -263.609282) (xy 370.66199 -263.559889) (xy 370.685568 -263.513615)
			(xy 370.716094 -263.471599) (xy 370.752817 -263.434876) (xy 370.794833 -263.40435) (xy 370.841107 -263.380772)
			(xy 370.8905 -263.364724) (xy 370.941795 -263.356599) (xy 370.993729 -263.356599) (xy 371.045024 -263.364724)
			(xy 371.094417 -263.380772) (xy 371.140691 -263.40435) (xy 371.182707 -263.434876) (xy 371.21943 -263.471599)
			(xy 371.249956 -263.513615) (xy 371.273534 -263.559889) (xy 371.289582 -263.609282) (xy 371.297707 -263.660577)
			(xy 371.298216 -263.686544) (xy 371.297707 -263.712511) (xy 371.577871 -263.712511) (xy 371.577871 -263.660577)
			(xy 371.585996 -263.609282) (xy 371.602044 -263.559889) (xy 371.625622 -263.513615) (xy 371.656148 -263.471599)
			(xy 371.692871 -263.434876) (xy 371.734887 -263.40435) (xy 371.781161 -263.380772) (xy 371.830554 -263.364724)
			(xy 371.881849 -263.356599) (xy 371.933783 -263.356599) (xy 371.985078 -263.364724) (xy 372.034471 -263.380772)
			(xy 372.080745 -263.40435) (xy 372.122761 -263.434876) (xy 372.159484 -263.471599) (xy 372.19001 -263.513615)
			(xy 372.213588 -263.559889) (xy 372.229636 -263.609282) (xy 372.237761 -263.660577) (xy 372.23827 -263.686544)
			(xy 372.237761 -263.712511) (xy 372.517671 -263.712511) (xy 372.517671 -263.660577) (xy 372.525796 -263.609282)
			(xy 372.541844 -263.559889) (xy 372.565422 -263.513615) (xy 372.595948 -263.471599) (xy 372.632671 -263.434876)
			(xy 372.674687 -263.40435) (xy 372.720961 -263.380772) (xy 372.770354 -263.364724) (xy 372.821649 -263.356599)
			(xy 372.873583 -263.356599) (xy 372.924878 -263.364724) (xy 372.974271 -263.380772) (xy 373.020545 -263.40435)
			(xy 373.062561 -263.434876) (xy 373.099284 -263.471599) (xy 373.12981 -263.513615) (xy 373.153388 -263.559889)
			(xy 373.169436 -263.609282) (xy 373.177561 -263.660577) (xy 373.17807 -263.686544) (xy 373.177561 -263.712511)
			(xy 373.169436 -263.763806) (xy 373.153388 -263.813199) (xy 373.12981 -263.859473) (xy 373.099284 -263.901489)
			(xy 373.062561 -263.938212) (xy 373.020545 -263.968738) (xy 372.974271 -263.992316) (xy 372.924878 -264.008364)
			(xy 372.873583 -264.016489) (xy 372.821649 -264.016489) (xy 372.770354 -264.008364) (xy 372.720961 -263.992316)
			(xy 372.674687 -263.968738) (xy 372.632671 -263.938212) (xy 372.595948 -263.901489) (xy 372.565422 -263.859473)
			(xy 372.541844 -263.813199) (xy 372.525796 -263.763806) (xy 372.517671 -263.712511) (xy 372.237761 -263.712511)
			(xy 372.229636 -263.763806) (xy 372.213588 -263.813199) (xy 372.19001 -263.859473) (xy 372.159484 -263.901489)
			(xy 372.122761 -263.938212) (xy 372.080745 -263.968738) (xy 372.034471 -263.992316) (xy 371.985078 -264.008364)
			(xy 371.933783 -264.016489) (xy 371.881849 -264.016489) (xy 371.830554 -264.008364) (xy 371.781161 -263.992316)
			(xy 371.734887 -263.968738) (xy 371.692871 -263.938212) (xy 371.656148 -263.901489) (xy 371.625622 -263.859473)
			(xy 371.602044 -263.813199) (xy 371.585996 -263.763806) (xy 371.577871 -263.712511) (xy 371.297707 -263.712511)
			(xy 371.289582 -263.763806) (xy 371.273534 -263.813199) (xy 371.249956 -263.859473) (xy 371.21943 -263.901489)
			(xy 371.182707 -263.938212) (xy 371.140691 -263.968738) (xy 371.094417 -263.992316) (xy 371.045024 -264.008364)
			(xy 370.993729 -264.016489) (xy 370.941795 -264.016489) (xy 370.8905 -264.008364) (xy 370.841107 -263.992316)
			(xy 370.794833 -263.968738) (xy 370.752817 -263.938212) (xy 370.716094 -263.901489) (xy 370.685568 -263.859473)
			(xy 370.66199 -263.813199) (xy 370.645942 -263.763806) (xy 370.637817 -263.712511) (xy 370.358161 -263.712511)
			(xy 370.350036 -263.763806) (xy 370.333988 -263.813199) (xy 370.31041 -263.859473) (xy 370.279884 -263.901489)
			(xy 370.243161 -263.938212) (xy 370.201145 -263.968738) (xy 370.154871 -263.992316) (xy 370.105478 -264.008364)
			(xy 370.054183 -264.016489) (xy 370.002249 -264.016489) (xy 369.950954 -264.008364) (xy 369.901561 -263.992316)
			(xy 369.855287 -263.968738) (xy 369.813271 -263.938212) (xy 369.776548 -263.901489) (xy 369.746022 -263.859473)
			(xy 369.722444 -263.813199) (xy 369.706396 -263.763806) (xy 369.698271 -263.712511) (xy 365.75565 -263.712511)
			(xy 365.749266 -263.71606) (xy 365.702189 -263.733538) (xy 365.677704 -263.739122) (xy 365.637064 -263.747504)
			(xy 365.637064 -264.072624) (xy 365.637582 -264.087132) (xy 365.645754 -264.114973) (xy 365.661431 -264.139389)
			(xy 365.683345 -264.158406) (xy 365.709726 -264.170488) (xy 365.73844 -264.174658) (xy 365.752888 -264.173208)
			(xy 365.764321 -264.171688) (xy 365.787329 -264.170038) (xy 365.798862 -264.169906) (xy 365.824836 -264.170386)
			(xy 365.876146 -264.178507) (xy 365.925554 -264.194556) (xy 365.971842 -264.218136) (xy 366.013872 -264.248668)
			(xy 366.050607 -264.285399) (xy 366.081144 -264.327425) (xy 366.10473 -264.373711) (xy 366.120784 -264.423117)
			(xy 366.128911 -264.474426) (xy 366.128911 -264.526327) (xy 366.408717 -264.526327) (xy 366.408717 -264.474393)
			(xy 366.416842 -264.423098) (xy 366.43289 -264.373705) (xy 366.456468 -264.327431) (xy 366.486994 -264.285415)
			(xy 366.523717 -264.248692) (xy 366.565733 -264.218166) (xy 366.612007 -264.194588) (xy 366.6614 -264.17854)
			(xy 366.712695 -264.170415) (xy 366.764629 -264.170415) (xy 366.815924 -264.17854) (xy 366.865317 -264.194588)
			(xy 366.911591 -264.218166) (xy 366.953607 -264.248692) (xy 366.99033 -264.285415) (xy 367.020856 -264.327431)
			(xy 367.044434 -264.373705) (xy 367.060482 -264.423098) (xy 367.068607 -264.474393) (xy 367.069116 -264.50036)
			(xy 367.068607 -264.526327) (xy 367.348517 -264.526327) (xy 367.348517 -264.474393) (xy 367.356642 -264.423098)
			(xy 367.37269 -264.373705) (xy 367.396268 -264.327431) (xy 367.426794 -264.285415) (xy 367.463517 -264.248692)
			(xy 367.505533 -264.218166) (xy 367.551807 -264.194588) (xy 367.6012 -264.17854) (xy 367.652495 -264.170415)
			(xy 367.704429 -264.170415) (xy 367.755724 -264.17854) (xy 367.805117 -264.194588) (xy 367.851391 -264.218166)
			(xy 367.893407 -264.248692) (xy 367.93013 -264.285415) (xy 367.960656 -264.327431) (xy 367.984234 -264.373705)
			(xy 368.000282 -264.423098) (xy 368.008407 -264.474393) (xy 368.008916 -264.50036) (xy 368.008407 -264.526327)
			(xy 368.288317 -264.526327) (xy 368.288317 -264.474393) (xy 368.296442 -264.423098) (xy 368.31249 -264.373705)
			(xy 368.336068 -264.327431) (xy 368.366594 -264.285415) (xy 368.403317 -264.248692) (xy 368.445333 -264.218166)
			(xy 368.491607 -264.194588) (xy 368.541 -264.17854) (xy 368.592295 -264.170415) (xy 368.644229 -264.170415)
			(xy 368.695524 -264.17854) (xy 368.744917 -264.194588) (xy 368.791191 -264.218166) (xy 368.833207 -264.248692)
			(xy 368.86993 -264.285415) (xy 368.900456 -264.327431) (xy 368.924034 -264.373705) (xy 368.940082 -264.423098)
			(xy 368.948207 -264.474393) (xy 368.948716 -264.50036) (xy 368.948207 -264.526327) (xy 369.228117 -264.526327)
			(xy 369.228117 -264.474393) (xy 369.236242 -264.423098) (xy 369.25229 -264.373705) (xy 369.275868 -264.327431)
			(xy 369.306394 -264.285415) (xy 369.343117 -264.248692) (xy 369.385133 -264.218166) (xy 369.431407 -264.194588)
			(xy 369.4808 -264.17854) (xy 369.532095 -264.170415) (xy 369.584029 -264.170415) (xy 369.635324 -264.17854)
			(xy 369.684717 -264.194588) (xy 369.730991 -264.218166) (xy 369.773007 -264.248692) (xy 369.80973 -264.285415)
			(xy 369.840256 -264.327431) (xy 369.863834 -264.373705) (xy 369.879882 -264.423098) (xy 369.888007 -264.474393)
			(xy 369.888516 -264.50036) (xy 369.888007 -264.526327) (xy 370.167917 -264.526327) (xy 370.167917 -264.474393)
			(xy 370.176042 -264.423098) (xy 370.19209 -264.373705) (xy 370.215668 -264.327431) (xy 370.246194 -264.285415)
			(xy 370.282917 -264.248692) (xy 370.324933 -264.218166) (xy 370.371207 -264.194588) (xy 370.4206 -264.17854)
			(xy 370.471895 -264.170415) (xy 370.523829 -264.170415) (xy 370.575124 -264.17854) (xy 370.624517 -264.194588)
			(xy 370.670791 -264.218166) (xy 370.712807 -264.248692) (xy 370.74953 -264.285415) (xy 370.780056 -264.327431)
			(xy 370.803634 -264.373705) (xy 370.819682 -264.423098) (xy 370.827807 -264.474393) (xy 370.828316 -264.50036)
			(xy 370.827807 -264.526327) (xy 371.107717 -264.526327) (xy 371.107717 -264.474393) (xy 371.115842 -264.423098)
			(xy 371.13189 -264.373705) (xy 371.155468 -264.327431) (xy 371.185994 -264.285415) (xy 371.222717 -264.248692)
			(xy 371.264733 -264.218166) (xy 371.311007 -264.194588) (xy 371.3604 -264.17854) (xy 371.411695 -264.170415)
			(xy 371.463629 -264.170415) (xy 371.514924 -264.17854) (xy 371.564317 -264.194588) (xy 371.610591 -264.218166)
			(xy 371.652607 -264.248692) (xy 371.68933 -264.285415) (xy 371.719856 -264.327431) (xy 371.743434 -264.373705)
			(xy 371.759482 -264.423098) (xy 371.767607 -264.474393) (xy 371.768116 -264.50036) (xy 371.767607 -264.526327)
			(xy 372.047517 -264.526327) (xy 372.047517 -264.474393) (xy 372.055642 -264.423098) (xy 372.07169 -264.373705)
			(xy 372.095268 -264.327431) (xy 372.125794 -264.285415) (xy 372.162517 -264.248692) (xy 372.204533 -264.218166)
			(xy 372.250807 -264.194588) (xy 372.3002 -264.17854) (xy 372.351495 -264.170415) (xy 372.403429 -264.170415)
			(xy 372.454724 -264.17854) (xy 372.504117 -264.194588) (xy 372.550391 -264.218166) (xy 372.592407 -264.248692)
			(xy 372.62913 -264.285415) (xy 372.659656 -264.327431) (xy 372.683234 -264.373705) (xy 372.699282 -264.423098)
			(xy 372.707407 -264.474393) (xy 372.707916 -264.50036) (xy 372.707407 -264.526327) (xy 372.699282 -264.577622)
			(xy 372.683234 -264.627015) (xy 372.659656 -264.673289) (xy 372.62913 -264.715305) (xy 372.592407 -264.752028)
			(xy 372.550391 -264.782554) (xy 372.504117 -264.806132) (xy 372.454724 -264.82218) (xy 372.403429 -264.830305)
			(xy 372.351495 -264.830305) (xy 372.3002 -264.82218) (xy 372.250807 -264.806132) (xy 372.204533 -264.782554)
			(xy 372.162517 -264.752028) (xy 372.125794 -264.715305) (xy 372.095268 -264.673289) (xy 372.07169 -264.627015)
			(xy 372.055642 -264.577622) (xy 372.047517 -264.526327) (xy 371.767607 -264.526327) (xy 371.759482 -264.577622)
			(xy 371.743434 -264.627015) (xy 371.719856 -264.673289) (xy 371.68933 -264.715305) (xy 371.652607 -264.752028)
			(xy 371.610591 -264.782554) (xy 371.564317 -264.806132) (xy 371.514924 -264.82218) (xy 371.463629 -264.830305)
			(xy 371.411695 -264.830305) (xy 371.3604 -264.82218) (xy 371.311007 -264.806132) (xy 371.264733 -264.782554)
			(xy 371.222717 -264.752028) (xy 371.185994 -264.715305) (xy 371.155468 -264.673289) (xy 371.13189 -264.627015)
			(xy 371.115842 -264.577622) (xy 371.107717 -264.526327) (xy 370.827807 -264.526327) (xy 370.819682 -264.577622)
			(xy 370.803634 -264.627015) (xy 370.780056 -264.673289) (xy 370.74953 -264.715305) (xy 370.712807 -264.752028)
			(xy 370.670791 -264.782554) (xy 370.624517 -264.806132) (xy 370.575124 -264.82218) (xy 370.523829 -264.830305)
			(xy 370.471895 -264.830305) (xy 370.4206 -264.82218) (xy 370.371207 -264.806132) (xy 370.324933 -264.782554)
			(xy 370.282917 -264.752028) (xy 370.246194 -264.715305) (xy 370.215668 -264.673289) (xy 370.19209 -264.627015)
			(xy 370.176042 -264.577622) (xy 370.167917 -264.526327) (xy 369.888007 -264.526327) (xy 369.879882 -264.577622)
			(xy 369.863834 -264.627015) (xy 369.840256 -264.673289) (xy 369.80973 -264.715305) (xy 369.773007 -264.752028)
			(xy 369.730991 -264.782554) (xy 369.684717 -264.806132) (xy 369.635324 -264.82218) (xy 369.584029 -264.830305)
			(xy 369.532095 -264.830305) (xy 369.4808 -264.82218) (xy 369.431407 -264.806132) (xy 369.385133 -264.782554)
			(xy 369.343117 -264.752028) (xy 369.306394 -264.715305) (xy 369.275868 -264.673289) (xy 369.25229 -264.627015)
			(xy 369.236242 -264.577622) (xy 369.228117 -264.526327) (xy 368.948207 -264.526327) (xy 368.940082 -264.577622)
			(xy 368.924034 -264.627015) (xy 368.900456 -264.673289) (xy 368.86993 -264.715305) (xy 368.833207 -264.752028)
			(xy 368.791191 -264.782554) (xy 368.744917 -264.806132) (xy 368.695524 -264.82218) (xy 368.644229 -264.830305)
			(xy 368.592295 -264.830305) (xy 368.541 -264.82218) (xy 368.491607 -264.806132) (xy 368.445333 -264.782554)
			(xy 368.403317 -264.752028) (xy 368.366594 -264.715305) (xy 368.336068 -264.673289) (xy 368.31249 -264.627015)
			(xy 368.296442 -264.577622) (xy 368.288317 -264.526327) (xy 368.008407 -264.526327) (xy 368.000282 -264.577622)
			(xy 367.984234 -264.627015) (xy 367.960656 -264.673289) (xy 367.93013 -264.715305) (xy 367.893407 -264.752028)
			(xy 367.851391 -264.782554) (xy 367.805117 -264.806132) (xy 367.755724 -264.82218) (xy 367.704429 -264.830305)
			(xy 367.652495 -264.830305) (xy 367.6012 -264.82218) (xy 367.551807 -264.806132) (xy 367.505533 -264.782554)
			(xy 367.463517 -264.752028) (xy 367.426794 -264.715305) (xy 367.396268 -264.673289) (xy 367.37269 -264.627015)
			(xy 367.356642 -264.577622) (xy 367.348517 -264.526327) (xy 367.068607 -264.526327) (xy 367.060482 -264.577622)
			(xy 367.044434 -264.627015) (xy 367.020856 -264.673289) (xy 366.99033 -264.715305) (xy 366.953607 -264.752028)
			(xy 366.911591 -264.782554) (xy 366.865317 -264.806132) (xy 366.815924 -264.82218) (xy 366.764629 -264.830305)
			(xy 366.712695 -264.830305) (xy 366.6614 -264.82218) (xy 366.612007 -264.806132) (xy 366.565733 -264.782554)
			(xy 366.523717 -264.752028) (xy 366.486994 -264.715305) (xy 366.456468 -264.673289) (xy 366.43289 -264.627015)
			(xy 366.416842 -264.577622) (xy 366.408717 -264.526327) (xy 366.128911 -264.526327) (xy 366.128911 -264.526374)
			(xy 366.120784 -264.577683) (xy 366.10473 -264.627089) (xy 366.081144 -264.673375) (xy 366.050607 -264.715401)
			(xy 366.013872 -264.752132) (xy 365.971842 -264.782664) (xy 365.925554 -264.806244) (xy 365.876146 -264.822293)
			(xy 365.824836 -264.830414) (xy 365.798862 -264.830814) (xy 365.787328 -264.830701) (xy 365.764319 -264.829051)
			(xy 365.752888 -264.827512) (xy 365.73845 -264.825994) (xy 365.709738 -264.830187) (xy 365.683365 -264.842288)
			(xy 365.66146 -264.861319) (xy 365.645794 -264.885743) (xy 365.63763 -264.913588) (xy 365.637064 -264.928096)
			(xy 365.637064 -265.19378) (xy 365.640112 -265.202162) (xy 365.649234 -265.229263) (xy 365.659075 -265.285588)
			(xy 365.659079 -265.340143) (xy 365.938817 -265.340143) (xy 365.938817 -265.288209) (xy 365.946942 -265.236914)
			(xy 365.96299 -265.187521) (xy 365.986568 -265.141247) (xy 366.017094 -265.099231) (xy 366.053817 -265.062508)
			(xy 366.095833 -265.031982) (xy 366.142107 -265.008404) (xy 366.1915 -264.992356) (xy 366.242795 -264.984231)
			(xy 366.294729 -264.984231) (xy 366.346024 -264.992356) (xy 366.395417 -265.008404) (xy 366.441691 -265.031982)
			(xy 366.483707 -265.062508) (xy 366.52043 -265.099231) (xy 366.550956 -265.141247) (xy 366.574534 -265.187521)
			(xy 366.590582 -265.236914) (xy 366.598707 -265.288209) (xy 366.599216 -265.314176) (xy 366.598707 -265.340143)
			(xy 366.878871 -265.340143) (xy 366.878871 -265.288209) (xy 366.886996 -265.236914) (xy 366.903044 -265.187521)
			(xy 366.926622 -265.141247) (xy 366.957148 -265.099231) (xy 366.993871 -265.062508) (xy 367.035887 -265.031982)
			(xy 367.082161 -265.008404) (xy 367.131554 -264.992356) (xy 367.182849 -264.984231) (xy 367.234783 -264.984231)
			(xy 367.286078 -264.992356) (xy 367.335471 -265.008404) (xy 367.381745 -265.031982) (xy 367.423761 -265.062508)
			(xy 367.460484 -265.099231) (xy 367.49101 -265.141247) (xy 367.514588 -265.187521) (xy 367.530636 -265.236914)
			(xy 367.538761 -265.288209) (xy 367.53927 -265.314176) (xy 367.538761 -265.340143) (xy 367.818671 -265.340143)
			(xy 367.818671 -265.288209) (xy 367.826796 -265.236914) (xy 367.842844 -265.187521) (xy 367.866422 -265.141247)
			(xy 367.896948 -265.099231) (xy 367.933671 -265.062508) (xy 367.975687 -265.031982) (xy 368.021961 -265.008404)
			(xy 368.071354 -264.992356) (xy 368.122649 -264.984231) (xy 368.174583 -264.984231) (xy 368.225878 -264.992356)
			(xy 368.275271 -265.008404) (xy 368.321545 -265.031982) (xy 368.363561 -265.062508) (xy 368.400284 -265.099231)
			(xy 368.43081 -265.141247) (xy 368.454388 -265.187521) (xy 368.470436 -265.236914) (xy 368.478561 -265.288209)
			(xy 368.47907 -265.314176) (xy 368.478561 -265.340143) (xy 369.698271 -265.340143) (xy 369.698271 -265.288209)
			(xy 369.706396 -265.236914) (xy 369.722444 -265.187521) (xy 369.746022 -265.141247) (xy 369.776548 -265.099231)
			(xy 369.813271 -265.062508) (xy 369.855287 -265.031982) (xy 369.901561 -265.008404) (xy 369.950954 -264.992356)
			(xy 370.002249 -264.984231) (xy 370.054183 -264.984231) (xy 370.105478 -264.992356) (xy 370.154871 -265.008404)
			(xy 370.201145 -265.031982) (xy 370.243161 -265.062508) (xy 370.279884 -265.099231) (xy 370.31041 -265.141247)
			(xy 370.333988 -265.187521) (xy 370.350036 -265.236914) (xy 370.358161 -265.288209) (xy 370.35867 -265.314176)
			(xy 370.358161 -265.340143) (xy 370.638071 -265.340143) (xy 370.638071 -265.288209) (xy 370.646196 -265.236914)
			(xy 370.662244 -265.187521) (xy 370.685822 -265.141247) (xy 370.716348 -265.099231) (xy 370.753071 -265.062508)
			(xy 370.795087 -265.031982) (xy 370.841361 -265.008404) (xy 370.890754 -264.992356) (xy 370.942049 -264.984231)
			(xy 370.993983 -264.984231) (xy 371.045278 -264.992356) (xy 371.094671 -265.008404) (xy 371.140945 -265.031982)
			(xy 371.182961 -265.062508) (xy 371.219684 -265.099231) (xy 371.25021 -265.141247) (xy 371.273788 -265.187521)
			(xy 371.289836 -265.236914) (xy 371.297961 -265.288209) (xy 371.29847 -265.314176) (xy 371.297961 -265.340143)
			(xy 371.577871 -265.340143) (xy 371.577871 -265.288209) (xy 371.585996 -265.236914) (xy 371.602044 -265.187521)
			(xy 371.625622 -265.141247) (xy 371.656148 -265.099231) (xy 371.692871 -265.062508) (xy 371.734887 -265.031982)
			(xy 371.781161 -265.008404) (xy 371.830554 -264.992356) (xy 371.881849 -264.984231) (xy 371.933783 -264.984231)
			(xy 371.985078 -264.992356) (xy 372.034471 -265.008404) (xy 372.080745 -265.031982) (xy 372.122761 -265.062508)
			(xy 372.159484 -265.099231) (xy 372.19001 -265.141247) (xy 372.213588 -265.187521) (xy 372.229636 -265.236914)
			(xy 372.237761 -265.288209) (xy 372.23827 -265.314176) (xy 372.237761 -265.340143) (xy 372.517671 -265.340143)
			(xy 372.517671 -265.288209) (xy 372.525796 -265.236914) (xy 372.541844 -265.187521) (xy 372.565422 -265.141247)
			(xy 372.595948 -265.099231) (xy 372.632671 -265.062508) (xy 372.674687 -265.031982) (xy 372.720961 -265.008404)
			(xy 372.770354 -264.992356) (xy 372.821649 -264.984231) (xy 372.873583 -264.984231) (xy 372.924878 -264.992356)
			(xy 372.974271 -265.008404) (xy 373.020545 -265.031982) (xy 373.062561 -265.062508) (xy 373.099284 -265.099231)
			(xy 373.12981 -265.141247) (xy 373.153388 -265.187521) (xy 373.169436 -265.236914) (xy 373.177561 -265.288209)
			(xy 373.17807 -265.314176) (xy 373.177561 -265.340143) (xy 373.169436 -265.391438) (xy 373.153388 -265.440831)
			(xy 373.12981 -265.487105) (xy 373.099284 -265.529121) (xy 373.062561 -265.565844) (xy 373.020545 -265.59637)
			(xy 372.974271 -265.619948) (xy 372.924878 -265.635996) (xy 372.873583 -265.644121) (xy 372.821649 -265.644121)
			(xy 372.770354 -265.635996) (xy 372.720961 -265.619948) (xy 372.674687 -265.59637) (xy 372.632671 -265.565844)
			(xy 372.595948 -265.529121) (xy 372.565422 -265.487105) (xy 372.541844 -265.440831) (xy 372.525796 -265.391438)
			(xy 372.517671 -265.340143) (xy 372.237761 -265.340143) (xy 372.229636 -265.391438) (xy 372.213588 -265.440831)
			(xy 372.19001 -265.487105) (xy 372.159484 -265.529121) (xy 372.122761 -265.565844) (xy 372.080745 -265.59637)
			(xy 372.034471 -265.619948) (xy 371.985078 -265.635996) (xy 371.933783 -265.644121) (xy 371.881849 -265.644121)
			(xy 371.830554 -265.635996) (xy 371.781161 -265.619948) (xy 371.734887 -265.59637) (xy 371.692871 -265.565844)
			(xy 371.656148 -265.529121) (xy 371.625622 -265.487105) (xy 371.602044 -265.440831) (xy 371.585996 -265.391438)
			(xy 371.577871 -265.340143) (xy 371.297961 -265.340143) (xy 371.289836 -265.391438) (xy 371.273788 -265.440831)
			(xy 371.25021 -265.487105) (xy 371.219684 -265.529121) (xy 371.182961 -265.565844) (xy 371.140945 -265.59637)
			(xy 371.094671 -265.619948) (xy 371.045278 -265.635996) (xy 370.993983 -265.644121) (xy 370.942049 -265.644121)
			(xy 370.890754 -265.635996) (xy 370.841361 -265.619948) (xy 370.795087 -265.59637) (xy 370.753071 -265.565844)
			(xy 370.716348 -265.529121) (xy 370.685822 -265.487105) (xy 370.662244 -265.440831) (xy 370.646196 -265.391438)
			(xy 370.638071 -265.340143) (xy 370.358161 -265.340143) (xy 370.350036 -265.391438) (xy 370.333988 -265.440831)
			(xy 370.31041 -265.487105) (xy 370.279884 -265.529121) (xy 370.243161 -265.565844) (xy 370.201145 -265.59637)
			(xy 370.154871 -265.619948) (xy 370.105478 -265.635996) (xy 370.054183 -265.644121) (xy 370.002249 -265.644121)
			(xy 369.950954 -265.635996) (xy 369.901561 -265.619948) (xy 369.855287 -265.59637) (xy 369.813271 -265.565844)
			(xy 369.776548 -265.529121) (xy 369.746022 -265.487105) (xy 369.722444 -265.440831) (xy 369.706396 -265.391438)
			(xy 369.698271 -265.340143) (xy 368.478561 -265.340143) (xy 368.470436 -265.391438) (xy 368.454388 -265.440831)
			(xy 368.43081 -265.487105) (xy 368.400284 -265.529121) (xy 368.363561 -265.565844) (xy 368.321545 -265.59637)
			(xy 368.275271 -265.619948) (xy 368.225878 -265.635996) (xy 368.174583 -265.644121) (xy 368.122649 -265.644121)
			(xy 368.071354 -265.635996) (xy 368.021961 -265.619948) (xy 367.975687 -265.59637) (xy 367.933671 -265.565844)
			(xy 367.896948 -265.529121) (xy 367.866422 -265.487105) (xy 367.842844 -265.440831) (xy 367.826796 -265.391438)
			(xy 367.818671 -265.340143) (xy 367.538761 -265.340143) (xy 367.530636 -265.391438) (xy 367.514588 -265.440831)
			(xy 367.49101 -265.487105) (xy 367.460484 -265.529121) (xy 367.423761 -265.565844) (xy 367.381745 -265.59637)
			(xy 367.335471 -265.619948) (xy 367.286078 -265.635996) (xy 367.234783 -265.644121) (xy 367.182849 -265.644121)
			(xy 367.131554 -265.635996) (xy 367.082161 -265.619948) (xy 367.035887 -265.59637) (xy 366.993871 -265.565844)
			(xy 366.957148 -265.529121) (xy 366.926622 -265.487105) (xy 366.903044 -265.440831) (xy 366.886996 -265.391438)
			(xy 366.878871 -265.340143) (xy 366.598707 -265.340143) (xy 366.590582 -265.391438) (xy 366.574534 -265.440831)
			(xy 366.550956 -265.487105) (xy 366.52043 -265.529121) (xy 366.483707 -265.565844) (xy 366.441691 -265.59637)
			(xy 366.395417 -265.619948) (xy 366.346024 -265.635996) (xy 366.294729 -265.644121) (xy 366.242795 -265.644121)
			(xy 366.1915 -265.635996) (xy 366.142107 -265.619948) (xy 366.095833 -265.59637) (xy 366.053817 -265.565844)
			(xy 366.017094 -265.529121) (xy 365.986568 -265.487105) (xy 365.96299 -265.440831) (xy 365.946942 -265.391438)
			(xy 365.938817 -265.340143) (xy 365.659079 -265.340143) (xy 365.659079 -265.342767) (xy 365.649246 -265.399093)
			(xy 365.640112 -265.42619) (xy 365.637064 -265.434572) (xy 365.637064 -265.70051) (xy 365.63758 -265.715019)
			(xy 365.64575 -265.742864) (xy 365.661426 -265.767283) (xy 365.683341 -265.786304) (xy 365.709724 -265.798388)
			(xy 365.738441 -265.802558) (xy 365.752888 -265.801094) (xy 365.764321 -265.799574) (xy 365.787329 -265.797924)
			(xy 365.798862 -265.797792) (xy 365.82483 -265.798272) (xy 365.876126 -265.806391) (xy 365.925521 -265.822435)
			(xy 365.971797 -265.84601) (xy 366.013816 -265.876533) (xy 366.050542 -265.913255) (xy 366.08107 -265.95527)
			(xy 366.10465 -266.001544) (xy 366.1207 -266.050937) (xy 366.128825 -266.102232) (xy 366.128825 -266.154168)
			(xy 366.128778 -266.154467) (xy 366.408717 -266.154467) (xy 366.408717 -266.102533) (xy 366.416842 -266.051238)
			(xy 366.43289 -266.001845) (xy 366.456468 -265.955571) (xy 366.486994 -265.913555) (xy 366.523717 -265.876832)
			(xy 366.565733 -265.846306) (xy 366.612007 -265.822728) (xy 366.6614 -265.80668) (xy 366.712695 -265.798555)
			(xy 366.764629 -265.798555) (xy 366.815924 -265.80668) (xy 366.865317 -265.822728) (xy 366.911591 -265.846306)
			(xy 366.953607 -265.876832) (xy 366.99033 -265.913555) (xy 367.020856 -265.955571) (xy 367.044434 -266.001845)
			(xy 367.060482 -266.051238) (xy 367.068607 -266.102533) (xy 367.069116 -266.1285) (xy 367.068612 -266.154213)
			(xy 367.348517 -266.154213) (xy 367.348517 -266.102279) (xy 367.356642 -266.050984) (xy 367.37269 -266.001591)
			(xy 367.396268 -265.955317) (xy 367.426794 -265.913301) (xy 367.463517 -265.876578) (xy 367.505533 -265.846052)
			(xy 367.551807 -265.822474) (xy 367.6012 -265.806426) (xy 367.652495 -265.798301) (xy 367.704429 -265.798301)
			(xy 367.755724 -265.806426) (xy 367.805117 -265.822474) (xy 367.851391 -265.846052) (xy 367.893407 -265.876578)
			(xy 367.93013 -265.913301) (xy 367.960656 -265.955317) (xy 367.984234 -266.001591) (xy 368.000282 -266.050984)
			(xy 368.008407 -266.102279) (xy 368.008916 -266.128246) (xy 368.008407 -266.154213) (xy 368.288317 -266.154213)
			(xy 368.288317 -266.102279) (xy 368.296442 -266.050984) (xy 368.31249 -266.001591) (xy 368.336068 -265.955317)
			(xy 368.366594 -265.913301) (xy 368.403317 -265.876578) (xy 368.445333 -265.846052) (xy 368.491607 -265.822474)
			(xy 368.541 -265.806426) (xy 368.592295 -265.798301) (xy 368.644229 -265.798301) (xy 368.695524 -265.806426)
			(xy 368.744917 -265.822474) (xy 368.791191 -265.846052) (xy 368.833207 -265.876578) (xy 368.86993 -265.913301)
			(xy 368.900456 -265.955317) (xy 368.924034 -266.001591) (xy 368.940082 -266.050984) (xy 368.948207 -266.102279)
			(xy 368.948716 -266.128246) (xy 368.948207 -266.154213) (xy 370.167917 -266.154213) (xy 370.167917 -266.102279)
			(xy 370.176042 -266.050984) (xy 370.19209 -266.001591) (xy 370.215668 -265.955317) (xy 370.246194 -265.913301)
			(xy 370.282917 -265.876578) (xy 370.324933 -265.846052) (xy 370.371207 -265.822474) (xy 370.4206 -265.806426)
			(xy 370.471895 -265.798301) (xy 370.523829 -265.798301) (xy 370.575124 -265.806426) (xy 370.624517 -265.822474)
			(xy 370.670791 -265.846052) (xy 370.712807 -265.876578) (xy 370.74953 -265.913301) (xy 370.780056 -265.955317)
			(xy 370.803634 -266.001591) (xy 370.819682 -266.050984) (xy 370.827807 -266.102279) (xy 370.828316 -266.128246)
			(xy 370.827807 -266.154213) (xy 371.107717 -266.154213) (xy 371.107717 -266.102279) (xy 371.115842 -266.050984)
			(xy 371.13189 -266.001591) (xy 371.155468 -265.955317) (xy 371.185994 -265.913301) (xy 371.222717 -265.876578)
			(xy 371.264733 -265.846052) (xy 371.311007 -265.822474) (xy 371.3604 -265.806426) (xy 371.411695 -265.798301)
			(xy 371.463629 -265.798301) (xy 371.514924 -265.806426) (xy 371.564317 -265.822474) (xy 371.610591 -265.846052)
			(xy 371.652607 -265.876578) (xy 371.68933 -265.913301) (xy 371.719856 -265.955317) (xy 371.743434 -266.001591)
			(xy 371.759482 -266.050984) (xy 371.767607 -266.102279) (xy 371.768116 -266.128246) (xy 371.767607 -266.154213)
			(xy 372.047517 -266.154213) (xy 372.047517 -266.102279) (xy 372.055642 -266.050984) (xy 372.07169 -266.001591)
			(xy 372.095268 -265.955317) (xy 372.125794 -265.913301) (xy 372.162517 -265.876578) (xy 372.204533 -265.846052)
			(xy 372.250807 -265.822474) (xy 372.3002 -265.806426) (xy 372.351495 -265.798301) (xy 372.403429 -265.798301)
			(xy 372.454724 -265.806426) (xy 372.504117 -265.822474) (xy 372.550391 -265.846052) (xy 372.592407 -265.876578)
			(xy 372.62913 -265.913301) (xy 372.659656 -265.955317) (xy 372.683234 -266.001591) (xy 372.699282 -266.050984)
			(xy 372.707407 -266.102279) (xy 372.707916 -266.128246) (xy 372.707407 -266.154213) (xy 372.699282 -266.205508)
			(xy 372.683234 -266.254901) (xy 372.659656 -266.301175) (xy 372.62913 -266.343191) (xy 372.592407 -266.379914)
			(xy 372.550391 -266.41044) (xy 372.504117 -266.434018) (xy 372.454724 -266.450066) (xy 372.403429 -266.458191)
			(xy 372.351495 -266.458191) (xy 372.3002 -266.450066) (xy 372.250807 -266.434018) (xy 372.204533 -266.41044)
			(xy 372.162517 -266.379914) (xy 372.125794 -266.343191) (xy 372.095268 -266.301175) (xy 372.07169 -266.254901)
			(xy 372.055642 -266.205508) (xy 372.047517 -266.154213) (xy 371.767607 -266.154213) (xy 371.759482 -266.205508)
			(xy 371.743434 -266.254901) (xy 371.719856 -266.301175) (xy 371.68933 -266.343191) (xy 371.652607 -266.379914)
			(xy 371.610591 -266.41044) (xy 371.564317 -266.434018) (xy 371.514924 -266.450066) (xy 371.463629 -266.458191)
			(xy 371.411695 -266.458191) (xy 371.3604 -266.450066) (xy 371.311007 -266.434018) (xy 371.264733 -266.41044)
			(xy 371.222717 -266.379914) (xy 371.185994 -266.343191) (xy 371.155468 -266.301175) (xy 371.13189 -266.254901)
			(xy 371.115842 -266.205508) (xy 371.107717 -266.154213) (xy 370.827807 -266.154213) (xy 370.819682 -266.205508)
			(xy 370.803634 -266.254901) (xy 370.780056 -266.301175) (xy 370.74953 -266.343191) (xy 370.712807 -266.379914)
			(xy 370.670791 -266.41044) (xy 370.624517 -266.434018) (xy 370.575124 -266.450066) (xy 370.523829 -266.458191)
			(xy 370.471895 -266.458191) (xy 370.4206 -266.450066) (xy 370.371207 -266.434018) (xy 370.324933 -266.41044)
			(xy 370.282917 -266.379914) (xy 370.246194 -266.343191) (xy 370.215668 -266.301175) (xy 370.19209 -266.254901)
			(xy 370.176042 -266.205508) (xy 370.167917 -266.154213) (xy 368.948207 -266.154213) (xy 368.940082 -266.205508)
			(xy 368.924034 -266.254901) (xy 368.900456 -266.301175) (xy 368.86993 -266.343191) (xy 368.833207 -266.379914)
			(xy 368.791191 -266.41044) (xy 368.744917 -266.434018) (xy 368.695524 -266.450066) (xy 368.644229 -266.458191)
			(xy 368.592295 -266.458191) (xy 368.541 -266.450066) (xy 368.491607 -266.434018) (xy 368.445333 -266.41044)
			(xy 368.403317 -266.379914) (xy 368.366594 -266.343191) (xy 368.336068 -266.301175) (xy 368.31249 -266.254901)
			(xy 368.296442 -266.205508) (xy 368.288317 -266.154213) (xy 368.008407 -266.154213) (xy 368.000282 -266.205508)
			(xy 367.984234 -266.254901) (xy 367.960656 -266.301175) (xy 367.93013 -266.343191) (xy 367.893407 -266.379914)
			(xy 367.851391 -266.41044) (xy 367.805117 -266.434018) (xy 367.755724 -266.450066) (xy 367.704429 -266.458191)
			(xy 367.652495 -266.458191) (xy 367.6012 -266.450066) (xy 367.551807 -266.434018) (xy 367.505533 -266.41044)
			(xy 367.463517 -266.379914) (xy 367.426794 -266.343191) (xy 367.396268 -266.301175) (xy 367.37269 -266.254901)
			(xy 367.356642 -266.205508) (xy 367.348517 -266.154213) (xy 367.068612 -266.154213) (xy 367.068607 -266.154467)
			(xy 367.060482 -266.205762) (xy 367.044434 -266.255155) (xy 367.020856 -266.301429) (xy 366.99033 -266.343445)
			(xy 366.953607 -266.380168) (xy 366.911591 -266.410694) (xy 366.865317 -266.434272) (xy 366.815924 -266.45032)
			(xy 366.764629 -266.458445) (xy 366.712695 -266.458445) (xy 366.6614 -266.45032) (xy 366.612007 -266.434272)
			(xy 366.565733 -266.410694) (xy 366.523717 -266.380168) (xy 366.486994 -266.343445) (xy 366.456468 -266.301429)
			(xy 366.43289 -266.255155) (xy 366.416842 -266.205762) (xy 366.408717 -266.154467) (xy 366.128778 -266.154467)
			(xy 366.1207 -266.205463) (xy 366.10465 -266.254856) (xy 366.08107 -266.30113) (xy 366.050542 -266.343145)
			(xy 366.013816 -266.379867) (xy 365.971797 -266.41039) (xy 365.925521 -266.433965) (xy 365.876126 -266.450009)
			(xy 365.82483 -266.458128) (xy 365.798862 -266.4587) (xy 365.787328 -266.458587) (xy 365.764319 -266.456937)
			(xy 365.752888 -266.455398) (xy 365.738449 -266.45388) (xy 365.709736 -266.458074) (xy 365.683361 -266.470174)
			(xy 365.661455 -266.489204) (xy 365.645785 -266.513628) (xy 365.637618 -266.541473) (xy 365.637064 -266.555982)
			(xy 365.637064 -266.821412) (xy 365.640112 -266.829794) (xy 365.649232 -266.856895) (xy 365.659067 -266.913219)
			(xy 365.659066 -266.967775) (xy 365.938563 -266.967775) (xy 365.938563 -266.915841) (xy 365.946688 -266.864546)
			(xy 365.962736 -266.815153) (xy 365.986314 -266.768879) (xy 366.01684 -266.726863) (xy 366.053563 -266.69014)
			(xy 366.095579 -266.659614) (xy 366.141853 -266.636036) (xy 366.191246 -266.619988) (xy 366.242541 -266.611863)
			(xy 366.294475 -266.611863) (xy 366.34577 -266.619988) (xy 366.395163 -266.636036) (xy 366.441437 -266.659614)
			(xy 366.483453 -266.69014) (xy 366.520176 -266.726863) (xy 366.550702 -266.768879) (xy 366.57428 -266.815153)
			(xy 366.590328 -266.864546) (xy 366.598453 -266.915841) (xy 366.598962 -266.941808) (xy 366.598453 -266.967775)
			(xy 369.698271 -266.967775) (xy 369.698271 -266.915841) (xy 369.706396 -266.864546) (xy 369.722444 -266.815153)
			(xy 369.746022 -266.768879) (xy 369.776548 -266.726863) (xy 369.813271 -266.69014) (xy 369.855287 -266.659614)
			(xy 369.901561 -266.636036) (xy 369.950954 -266.619988) (xy 370.002249 -266.611863) (xy 370.054183 -266.611863)
			(xy 370.105478 -266.619988) (xy 370.154871 -266.636036) (xy 370.201145 -266.659614) (xy 370.243161 -266.69014)
			(xy 370.279884 -266.726863) (xy 370.31041 -266.768879) (xy 370.333988 -266.815153) (xy 370.350036 -266.864546)
			(xy 370.358161 -266.915841) (xy 370.35867 -266.941808) (xy 370.358161 -266.967775) (xy 370.638071 -266.967775)
			(xy 370.638071 -266.915841) (xy 370.646196 -266.864546) (xy 370.662244 -266.815153) (xy 370.685822 -266.768879)
			(xy 370.716348 -266.726863) (xy 370.753071 -266.69014) (xy 370.795087 -266.659614) (xy 370.841361 -266.636036)
			(xy 370.890754 -266.619988) (xy 370.942049 -266.611863) (xy 370.993983 -266.611863) (xy 371.045278 -266.619988)
			(xy 371.094671 -266.636036) (xy 371.140945 -266.659614) (xy 371.182961 -266.69014) (xy 371.219684 -266.726863)
			(xy 371.25021 -266.768879) (xy 371.273788 -266.815153) (xy 371.289836 -266.864546) (xy 371.297961 -266.915841)
			(xy 371.29847 -266.941808) (xy 371.297961 -266.967775) (xy 371.577871 -266.967775) (xy 371.577871 -266.915841)
			(xy 371.585996 -266.864546) (xy 371.602044 -266.815153) (xy 371.625622 -266.768879) (xy 371.656148 -266.726863)
			(xy 371.692871 -266.69014) (xy 371.734887 -266.659614) (xy 371.781161 -266.636036) (xy 371.830554 -266.619988)
			(xy 371.881849 -266.611863) (xy 371.933783 -266.611863) (xy 371.985078 -266.619988) (xy 372.034471 -266.636036)
			(xy 372.080745 -266.659614) (xy 372.122761 -266.69014) (xy 372.159484 -266.726863) (xy 372.19001 -266.768879)
			(xy 372.213588 -266.815153) (xy 372.229636 -266.864546) (xy 372.237761 -266.915841) (xy 372.23827 -266.941808)
			(xy 372.237761 -266.967775) (xy 372.517671 -266.967775) (xy 372.517671 -266.915841) (xy 372.525796 -266.864546)
			(xy 372.541844 -266.815153) (xy 372.565422 -266.768879) (xy 372.595948 -266.726863) (xy 372.632671 -266.69014)
			(xy 372.674687 -266.659614) (xy 372.720961 -266.636036) (xy 372.770354 -266.619988) (xy 372.821649 -266.611863)
			(xy 372.873583 -266.611863) (xy 372.924878 -266.619988) (xy 372.974271 -266.636036) (xy 373.020545 -266.659614)
			(xy 373.062561 -266.69014) (xy 373.099284 -266.726863) (xy 373.12981 -266.768879) (xy 373.153388 -266.815153)
			(xy 373.169436 -266.864546) (xy 373.177561 -266.915841) (xy 373.17807 -266.941808) (xy 373.177561 -266.967775)
			(xy 373.169436 -267.01907) (xy 373.153388 -267.068463) (xy 373.12981 -267.114737) (xy 373.099284 -267.156753)
			(xy 373.062561 -267.193476) (xy 373.020545 -267.224002) (xy 372.974271 -267.24758) (xy 372.924878 -267.263628)
			(xy 372.873583 -267.271753) (xy 372.821649 -267.271753) (xy 372.770354 -267.263628) (xy 372.720961 -267.24758)
			(xy 372.674687 -267.224002) (xy 372.632671 -267.193476) (xy 372.595948 -267.156753) (xy 372.565422 -267.114737)
			(xy 372.541844 -267.068463) (xy 372.525796 -267.01907) (xy 372.517671 -266.967775) (xy 372.237761 -266.967775)
			(xy 372.229636 -267.01907) (xy 372.213588 -267.068463) (xy 372.19001 -267.114737) (xy 372.159484 -267.156753)
			(xy 372.122761 -267.193476) (xy 372.080745 -267.224002) (xy 372.034471 -267.24758) (xy 371.985078 -267.263628)
			(xy 371.933783 -267.271753) (xy 371.881849 -267.271753) (xy 371.830554 -267.263628) (xy 371.781161 -267.24758)
			(xy 371.734887 -267.224002) (xy 371.692871 -267.193476) (xy 371.656148 -267.156753) (xy 371.625622 -267.114737)
			(xy 371.602044 -267.068463) (xy 371.585996 -267.01907) (xy 371.577871 -266.967775) (xy 371.297961 -266.967775)
			(xy 371.289836 -267.01907) (xy 371.273788 -267.068463) (xy 371.25021 -267.114737) (xy 371.219684 -267.156753)
			(xy 371.182961 -267.193476) (xy 371.140945 -267.224002) (xy 371.094671 -267.24758) (xy 371.045278 -267.263628)
			(xy 370.993983 -267.271753) (xy 370.942049 -267.271753) (xy 370.890754 -267.263628) (xy 370.841361 -267.24758)
			(xy 370.795087 -267.224002) (xy 370.753071 -267.193476) (xy 370.716348 -267.156753) (xy 370.685822 -267.114737)
			(xy 370.662244 -267.068463) (xy 370.646196 -267.01907) (xy 370.638071 -266.967775) (xy 370.358161 -266.967775)
			(xy 370.350036 -267.01907) (xy 370.333988 -267.068463) (xy 370.31041 -267.114737) (xy 370.279884 -267.156753)
			(xy 370.243161 -267.193476) (xy 370.201145 -267.224002) (xy 370.154871 -267.24758) (xy 370.105478 -267.263628)
			(xy 370.054183 -267.271753) (xy 370.002249 -267.271753) (xy 369.950954 -267.263628) (xy 369.901561 -267.24758)
			(xy 369.855287 -267.224002) (xy 369.813271 -267.193476) (xy 369.776548 -267.156753) (xy 369.746022 -267.114737)
			(xy 369.722444 -267.068463) (xy 369.706396 -267.01907) (xy 369.698271 -266.967775) (xy 366.598453 -266.967775)
			(xy 366.590328 -267.01907) (xy 366.57428 -267.068463) (xy 366.550702 -267.114737) (xy 366.520176 -267.156753)
			(xy 366.483453 -267.193476) (xy 366.441437 -267.224002) (xy 366.395163 -267.24758) (xy 366.34577 -267.263628)
			(xy 366.294475 -267.271753) (xy 366.242541 -267.271753) (xy 366.191246 -267.263628) (xy 366.141853 -267.24758)
			(xy 366.095579 -267.224002) (xy 366.053563 -267.193476) (xy 366.01684 -267.156753) (xy 365.986314 -267.114737)
			(xy 365.962736 -267.068463) (xy 365.946688 -267.01907) (xy 365.938563 -266.967775) (xy 365.659066 -266.967775)
			(xy 365.659066 -266.970396) (xy 365.649228 -267.026719) (xy 365.640112 -267.053822) (xy 365.637064 -267.062204)
			(xy 365.637064 -267.328142) (xy 365.637571 -267.342658) (xy 365.64573 -267.370519) (xy 365.661403 -267.394956)
			(xy 365.683322 -267.413992) (xy 365.709715 -267.426085) (xy 365.738444 -267.430258) (xy 365.752888 -267.428726)
			(xy 365.764321 -267.427206) (xy 365.787329 -267.425556) (xy 365.798862 -267.425424) (xy 365.824835 -267.425904)
			(xy 365.876142 -267.434025) (xy 365.925547 -267.450072) (xy 365.971833 -267.473652) (xy 366.01386 -267.504182)
			(xy 366.050594 -267.540911) (xy 366.081128 -267.582935) (xy 366.104713 -267.629218) (xy 366.120766 -267.678621)
			(xy 366.128893 -267.729927) (xy 366.128893 -267.781845) (xy 367.348517 -267.781845) (xy 367.348517 -267.729911)
			(xy 367.356642 -267.678616) (xy 367.37269 -267.629223) (xy 367.396268 -267.582949) (xy 367.426794 -267.540933)
			(xy 367.463517 -267.50421) (xy 367.505533 -267.473684) (xy 367.551807 -267.450106) (xy 367.6012 -267.434058)
			(xy 367.652495 -267.425933) (xy 367.704429 -267.425933) (xy 367.755724 -267.434058) (xy 367.805117 -267.450106)
			(xy 367.851391 -267.473684) (xy 367.893407 -267.50421) (xy 367.93013 -267.540933) (xy 367.960656 -267.582949)
			(xy 367.984234 -267.629223) (xy 368.000282 -267.678616) (xy 368.008407 -267.729911) (xy 368.008916 -267.755878)
			(xy 368.008407 -267.781845) (xy 371.107717 -267.781845) (xy 371.107717 -267.729911) (xy 371.115842 -267.678616)
			(xy 371.13189 -267.629223) (xy 371.155468 -267.582949) (xy 371.185994 -267.540933) (xy 371.222717 -267.50421)
			(xy 371.264733 -267.473684) (xy 371.311007 -267.450106) (xy 371.3604 -267.434058) (xy 371.411695 -267.425933)
			(xy 371.463629 -267.425933) (xy 371.514924 -267.434058) (xy 371.564317 -267.450106) (xy 371.610591 -267.473684)
			(xy 371.652607 -267.50421) (xy 371.68933 -267.540933) (xy 371.719856 -267.582949) (xy 371.743434 -267.629223)
			(xy 371.759482 -267.678616) (xy 371.767607 -267.729911) (xy 371.768116 -267.755878) (xy 371.767607 -267.781845)
			(xy 372.047517 -267.781845) (xy 372.047517 -267.729911) (xy 372.055642 -267.678616) (xy 372.07169 -267.629223)
			(xy 372.095268 -267.582949) (xy 372.125794 -267.540933) (xy 372.162517 -267.50421) (xy 372.204533 -267.473684)
			(xy 372.250807 -267.450106) (xy 372.3002 -267.434058) (xy 372.351495 -267.425933) (xy 372.403429 -267.425933)
			(xy 372.454724 -267.434058) (xy 372.504117 -267.450106) (xy 372.550391 -267.473684) (xy 372.592407 -267.50421)
			(xy 372.62913 -267.540933) (xy 372.659656 -267.582949) (xy 372.683234 -267.629223) (xy 372.699282 -267.678616)
			(xy 372.707407 -267.729911) (xy 372.707916 -267.755878) (xy 372.707407 -267.781845) (xy 372.699282 -267.83314)
			(xy 372.683234 -267.882533) (xy 372.659656 -267.928807) (xy 372.62913 -267.970823) (xy 372.592407 -268.007546)
			(xy 372.550391 -268.038072) (xy 372.504117 -268.06165) (xy 372.454724 -268.077698) (xy 372.403429 -268.085823)
			(xy 372.351495 -268.085823) (xy 372.3002 -268.077698) (xy 372.250807 -268.06165) (xy 372.204533 -268.038072)
			(xy 372.162517 -268.007546) (xy 372.125794 -267.970823) (xy 372.095268 -267.928807) (xy 372.07169 -267.882533)
			(xy 372.055642 -267.83314) (xy 372.047517 -267.781845) (xy 371.767607 -267.781845) (xy 371.759482 -267.83314)
			(xy 371.743434 -267.882533) (xy 371.719856 -267.928807) (xy 371.68933 -267.970823) (xy 371.652607 -268.007546)
			(xy 371.610591 -268.038072) (xy 371.564317 -268.06165) (xy 371.514924 -268.077698) (xy 371.463629 -268.085823)
			(xy 371.411695 -268.085823) (xy 371.3604 -268.077698) (xy 371.311007 -268.06165) (xy 371.264733 -268.038072)
			(xy 371.222717 -268.007546) (xy 371.185994 -267.970823) (xy 371.155468 -267.928807) (xy 371.13189 -267.882533)
			(xy 371.115842 -267.83314) (xy 371.107717 -267.781845) (xy 368.008407 -267.781845) (xy 368.000282 -267.83314)
			(xy 367.984234 -267.882533) (xy 367.960656 -267.928807) (xy 367.93013 -267.970823) (xy 367.893407 -268.007546)
			(xy 367.851391 -268.038072) (xy 367.805117 -268.06165) (xy 367.755724 -268.077698) (xy 367.704429 -268.085823)
			(xy 367.652495 -268.085823) (xy 367.6012 -268.077698) (xy 367.551807 -268.06165) (xy 367.505533 -268.038072)
			(xy 367.463517 -268.007546) (xy 367.426794 -267.970823) (xy 367.396268 -267.928807) (xy 367.37269 -267.882533)
			(xy 367.356642 -267.83314) (xy 367.348517 -267.781845) (xy 366.128893 -267.781845) (xy 366.128893 -267.781873)
			(xy 366.120766 -267.833179) (xy 366.104713 -267.882582) (xy 366.081128 -267.928865) (xy 366.050594 -267.970889)
			(xy 366.01386 -268.007618) (xy 365.971833 -268.038148) (xy 365.925547 -268.061728) (xy 365.876142 -268.077775)
			(xy 365.824835 -268.085896) (xy 365.798862 -268.086332) (xy 365.787328 -268.086219) (xy 365.764319 -268.084569)
			(xy 365.752888 -268.08303) (xy 365.738451 -268.081512) (xy 365.709741 -268.085706) (xy 365.68337 -268.097807)
			(xy 365.661468 -268.116838) (xy 365.645805 -268.141262) (xy 365.637646 -268.169106) (xy 365.637064 -268.183614)
			(xy 365.637064 -268.449806) (xy 365.640112 -268.458188) (xy 365.649134 -268.485177) (xy 365.658847 -268.541243)
			(xy 365.659416 -268.569694) (xy 365.658897 -268.595661) (xy 365.939071 -268.595661) (xy 365.939071 -268.543727)
			(xy 365.947196 -268.492432) (xy 365.963244 -268.443039) (xy 365.986822 -268.396765) (xy 366.017348 -268.354749)
			(xy 366.054071 -268.318026) (xy 366.096087 -268.2875) (xy 366.142361 -268.263922) (xy 366.191754 -268.247874)
			(xy 366.243049 -268.239749) (xy 366.294983 -268.239749) (xy 366.346278 -268.247874) (xy 366.395671 -268.263922)
			(xy 366.441945 -268.2875) (xy 366.483961 -268.318026) (xy 366.520684 -268.354749) (xy 366.55121 -268.396765)
			(xy 366.574788 -268.443039) (xy 366.590836 -268.492432) (xy 366.598961 -268.543727) (xy 366.59947 -268.569694)
			(xy 366.598961 -268.595661) (xy 370.637817 -268.595661) (xy 370.637817 -268.543727) (xy 370.645942 -268.492432)
			(xy 370.66199 -268.443039) (xy 370.685568 -268.396765) (xy 370.716094 -268.354749) (xy 370.752817 -268.318026)
			(xy 370.794833 -268.2875) (xy 370.841107 -268.263922) (xy 370.8905 -268.247874) (xy 370.941795 -268.239749)
			(xy 370.993729 -268.239749) (xy 371.045024 -268.247874) (xy 371.094417 -268.263922) (xy 371.140691 -268.2875)
			(xy 371.182707 -268.318026) (xy 371.21943 -268.354749) (xy 371.249956 -268.396765) (xy 371.273534 -268.443039)
			(xy 371.289582 -268.492432) (xy 371.297707 -268.543727) (xy 371.298216 -268.569694) (xy 371.297707 -268.595661)
			(xy 371.577871 -268.595661) (xy 371.577871 -268.543727) (xy 371.585996 -268.492432) (xy 371.602044 -268.443039)
			(xy 371.625622 -268.396765) (xy 371.656148 -268.354749) (xy 371.692871 -268.318026) (xy 371.734887 -268.2875)
			(xy 371.781161 -268.263922) (xy 371.830554 -268.247874) (xy 371.881849 -268.239749) (xy 371.933783 -268.239749)
			(xy 371.985078 -268.247874) (xy 372.034471 -268.263922) (xy 372.080745 -268.2875) (xy 372.122761 -268.318026)
			(xy 372.159484 -268.354749) (xy 372.19001 -268.396765) (xy 372.213588 -268.443039) (xy 372.229636 -268.492432)
			(xy 372.237761 -268.543727) (xy 372.23827 -268.569694) (xy 372.237761 -268.595661) (xy 372.517671 -268.595661)
			(xy 372.517671 -268.543727) (xy 372.525796 -268.492432) (xy 372.541844 -268.443039) (xy 372.565422 -268.396765)
			(xy 372.595948 -268.354749) (xy 372.632671 -268.318026) (xy 372.674687 -268.2875) (xy 372.720961 -268.263922)
			(xy 372.770354 -268.247874) (xy 372.821649 -268.239749) (xy 372.873583 -268.239749) (xy 372.924878 -268.247874)
			(xy 372.974271 -268.263922) (xy 373.020545 -268.2875) (xy 373.062561 -268.318026) (xy 373.099284 -268.354749)
			(xy 373.12981 -268.396765) (xy 373.153388 -268.443039) (xy 373.169436 -268.492432) (xy 373.177561 -268.543727)
			(xy 373.17807 -268.569694) (xy 373.177561 -268.595661) (xy 373.169436 -268.646956) (xy 373.153388 -268.696349)
			(xy 373.12981 -268.742623) (xy 373.099284 -268.784639) (xy 373.062561 -268.821362) (xy 373.020545 -268.851888)
			(xy 372.974271 -268.875466) (xy 372.924878 -268.891514) (xy 372.873583 -268.899639) (xy 372.821649 -268.899639)
			(xy 372.770354 -268.891514) (xy 372.720961 -268.875466) (xy 372.674687 -268.851888) (xy 372.632671 -268.821362)
			(xy 372.595948 -268.784639) (xy 372.565422 -268.742623) (xy 372.541844 -268.696349) (xy 372.525796 -268.646956)
			(xy 372.517671 -268.595661) (xy 372.237761 -268.595661) (xy 372.229636 -268.646956) (xy 372.213588 -268.696349)
			(xy 372.19001 -268.742623) (xy 372.159484 -268.784639) (xy 372.122761 -268.821362) (xy 372.080745 -268.851888)
			(xy 372.034471 -268.875466) (xy 371.985078 -268.891514) (xy 371.933783 -268.899639) (xy 371.881849 -268.899639)
			(xy 371.830554 -268.891514) (xy 371.781161 -268.875466) (xy 371.734887 -268.851888) (xy 371.692871 -268.821362)
			(xy 371.656148 -268.784639) (xy 371.625622 -268.742623) (xy 371.602044 -268.696349) (xy 371.585996 -268.646956)
			(xy 371.577871 -268.595661) (xy 371.297707 -268.595661) (xy 371.289582 -268.646956) (xy 371.273534 -268.696349)
			(xy 371.249956 -268.742623) (xy 371.21943 -268.784639) (xy 371.182707 -268.821362) (xy 371.140691 -268.851888)
			(xy 371.094417 -268.875466) (xy 371.045024 -268.891514) (xy 370.993729 -268.899639) (xy 370.941795 -268.899639)
			(xy 370.8905 -268.891514) (xy 370.841107 -268.875466) (xy 370.794833 -268.851888) (xy 370.752817 -268.821362)
			(xy 370.716094 -268.784639) (xy 370.685568 -268.742623) (xy 370.66199 -268.696349) (xy 370.645942 -268.646956)
			(xy 370.637817 -268.595661) (xy 366.598961 -268.595661) (xy 366.590836 -268.646956) (xy 366.574788 -268.696349)
			(xy 366.55121 -268.742623) (xy 366.520684 -268.784639) (xy 366.483961 -268.821362) (xy 366.441945 -268.851888)
			(xy 366.395671 -268.875466) (xy 366.346278 -268.891514) (xy 366.294983 -268.899639) (xy 366.243049 -268.899639)
			(xy 366.191754 -268.891514) (xy 366.142361 -268.875466) (xy 366.096087 -268.851888) (xy 366.054071 -268.821362)
			(xy 366.017348 -268.784639) (xy 365.986822 -268.742623) (xy 365.963244 -268.696349) (xy 365.947196 -268.646956)
			(xy 365.939071 -268.595661) (xy 365.658897 -268.595661) (xy 365.658847 -268.598145) (xy 365.649142 -268.654214)
			(xy 365.640112 -268.6812) (xy 365.637064 -268.689582) (xy 365.637064 -268.955774) (xy 365.637575 -268.970287)
			(xy 365.645739 -268.99814) (xy 365.661414 -269.022569) (xy 365.683331 -269.041597) (xy 365.709719 -269.053686)
			(xy 365.738443 -269.057858) (xy 365.752888 -269.056358) (xy 365.764384 -269.054831) (xy 365.787519 -269.05318)
			(xy 365.799116 -269.053056) (xy 365.825082 -269.053566) (xy 365.876373 -269.061692) (xy 365.925762 -269.077742)
			(xy 365.972032 -269.10132) (xy 366.014045 -269.131846) (xy 366.050765 -269.168567) (xy 366.081288 -269.210581)
			(xy 366.104864 -269.256853) (xy 366.120911 -269.306242) (xy 366.129035 -269.357534) (xy 366.129035 -269.409466)
			(xy 366.129033 -269.409477) (xy 368.288317 -269.409477) (xy 368.288317 -269.357543) (xy 368.296442 -269.306248)
			(xy 368.31249 -269.256855) (xy 368.336068 -269.210581) (xy 368.366594 -269.168565) (xy 368.403317 -269.131842)
			(xy 368.445333 -269.101316) (xy 368.491607 -269.077738) (xy 368.541 -269.06169) (xy 368.592295 -269.053565)
			(xy 368.644229 -269.053565) (xy 368.695524 -269.06169) (xy 368.744917 -269.077738) (xy 368.791191 -269.101316)
			(xy 368.833207 -269.131842) (xy 368.86993 -269.168565) (xy 368.900456 -269.210581) (xy 368.924034 -269.256855)
			(xy 368.940082 -269.306248) (xy 368.948207 -269.357543) (xy 368.948716 -269.38351) (xy 368.948207 -269.409477)
			(xy 370.167917 -269.409477) (xy 370.167917 -269.357543) (xy 370.176042 -269.306248) (xy 370.19209 -269.256855)
			(xy 370.215668 -269.210581) (xy 370.246194 -269.168565) (xy 370.282917 -269.131842) (xy 370.324933 -269.101316)
			(xy 370.371207 -269.077738) (xy 370.4206 -269.06169) (xy 370.471895 -269.053565) (xy 370.523829 -269.053565)
			(xy 370.575124 -269.06169) (xy 370.624517 -269.077738) (xy 370.670791 -269.101316) (xy 370.712807 -269.131842)
			(xy 370.74953 -269.168565) (xy 370.780056 -269.210581) (xy 370.803634 -269.256855) (xy 370.819682 -269.306248)
			(xy 370.827807 -269.357543) (xy 370.828316 -269.38351) (xy 370.827807 -269.409477) (xy 371.107717 -269.409477)
			(xy 371.107717 -269.357543) (xy 371.115842 -269.306248) (xy 371.13189 -269.256855) (xy 371.155468 -269.210581)
			(xy 371.185994 -269.168565) (xy 371.222717 -269.131842) (xy 371.264733 -269.101316) (xy 371.311007 -269.077738)
			(xy 371.3604 -269.06169) (xy 371.411695 -269.053565) (xy 371.463629 -269.053565) (xy 371.514924 -269.06169)
			(xy 371.564317 -269.077738) (xy 371.610591 -269.101316) (xy 371.652607 -269.131842) (xy 371.68933 -269.168565)
			(xy 371.719856 -269.210581) (xy 371.743434 -269.256855) (xy 371.759482 -269.306248) (xy 371.767607 -269.357543)
			(xy 371.768116 -269.38351) (xy 371.767607 -269.409477) (xy 372.047517 -269.409477) (xy 372.047517 -269.357543)
			(xy 372.055642 -269.306248) (xy 372.07169 -269.256855) (xy 372.095268 -269.210581) (xy 372.125794 -269.168565)
			(xy 372.162517 -269.131842) (xy 372.204533 -269.101316) (xy 372.250807 -269.077738) (xy 372.3002 -269.06169)
			(xy 372.351495 -269.053565) (xy 372.403429 -269.053565) (xy 372.454724 -269.06169) (xy 372.504117 -269.077738)
			(xy 372.550391 -269.101316) (xy 372.592407 -269.131842) (xy 372.62913 -269.168565) (xy 372.659656 -269.210581)
			(xy 372.683234 -269.256855) (xy 372.699282 -269.306248) (xy 372.707407 -269.357543) (xy 372.707916 -269.38351)
			(xy 372.707407 -269.409477) (xy 372.699282 -269.460772) (xy 372.683234 -269.510165) (xy 372.659656 -269.556439)
			(xy 372.62913 -269.598455) (xy 372.592407 -269.635178) (xy 372.550391 -269.665704) (xy 372.504117 -269.689282)
			(xy 372.454724 -269.70533) (xy 372.403429 -269.713455) (xy 372.351495 -269.713455) (xy 372.3002 -269.70533)
			(xy 372.250807 -269.689282) (xy 372.204533 -269.665704) (xy 372.162517 -269.635178) (xy 372.125794 -269.598455)
			(xy 372.095268 -269.556439) (xy 372.07169 -269.510165) (xy 372.055642 -269.460772) (xy 372.047517 -269.409477)
			(xy 371.767607 -269.409477) (xy 371.759482 -269.460772) (xy 371.743434 -269.510165) (xy 371.719856 -269.556439)
			(xy 371.68933 -269.598455) (xy 371.652607 -269.635178) (xy 371.610591 -269.665704) (xy 371.564317 -269.689282)
			(xy 371.514924 -269.70533) (xy 371.463629 -269.713455) (xy 371.411695 -269.713455) (xy 371.3604 -269.70533)
			(xy 371.311007 -269.689282) (xy 371.264733 -269.665704) (xy 371.222717 -269.635178) (xy 371.185994 -269.598455)
			(xy 371.155468 -269.556439) (xy 371.13189 -269.510165) (xy 371.115842 -269.460772) (xy 371.107717 -269.409477)
			(xy 370.827807 -269.409477) (xy 370.819682 -269.460772) (xy 370.803634 -269.510165) (xy 370.780056 -269.556439)
			(xy 370.74953 -269.598455) (xy 370.712807 -269.635178) (xy 370.670791 -269.665704) (xy 370.624517 -269.689282)
			(xy 370.575124 -269.70533) (xy 370.523829 -269.713455) (xy 370.471895 -269.713455) (xy 370.4206 -269.70533)
			(xy 370.371207 -269.689282) (xy 370.324933 -269.665704) (xy 370.282917 -269.635178) (xy 370.246194 -269.598455)
			(xy 370.215668 -269.556439) (xy 370.19209 -269.510165) (xy 370.176042 -269.460772) (xy 370.167917 -269.409477)
			(xy 368.948207 -269.409477) (xy 368.940082 -269.460772) (xy 368.924034 -269.510165) (xy 368.900456 -269.556439)
			(xy 368.86993 -269.598455) (xy 368.833207 -269.635178) (xy 368.791191 -269.665704) (xy 368.744917 -269.689282)
			(xy 368.695524 -269.70533) (xy 368.644229 -269.713455) (xy 368.592295 -269.713455) (xy 368.541 -269.70533)
			(xy 368.491607 -269.689282) (xy 368.445333 -269.665704) (xy 368.403317 -269.635178) (xy 368.366594 -269.598455)
			(xy 368.336068 -269.556439) (xy 368.31249 -269.510165) (xy 368.296442 -269.460772) (xy 368.288317 -269.409477)
			(xy 366.129033 -269.409477) (xy 366.120911 -269.460758) (xy 366.104864 -269.510147) (xy 366.081288 -269.556419)
			(xy 366.050765 -269.598433) (xy 366.014045 -269.635154) (xy 365.972032 -269.66568) (xy 365.925762 -269.689258)
			(xy 365.876373 -269.705308) (xy 365.825082 -269.713434) (xy 365.799116 -269.713964) (xy 365.787519 -269.713859)
			(xy 365.764382 -269.712209) (xy 365.752888 -269.710662) (xy 365.738448 -269.709145) (xy 365.709731 -269.713338)
			(xy 365.683352 -269.725437) (xy 365.66144 -269.744467) (xy 365.645764 -269.76889) (xy 365.637588 -269.796736)
			(xy 365.637064 -269.811246) (xy 365.637064 -270.077692) (xy 365.640112 -270.086074) (xy 365.643411 -270.095444)
			(xy 365.649002 -270.114507) (xy 365.651288 -270.124174) (xy 365.654336 -270.138398) (xy 365.765588 -270.24965)
			(xy 365.776324 -270.259713) (xy 365.802175 -270.273742) (xy 365.830954 -270.279812) (xy 365.860269 -270.27742)
			(xy 365.887683 -270.266763) (xy 365.910917 -270.248728) (xy 365.92804 -270.224814) (xy 365.937629 -270.197009)
			(xy 365.938816 -270.18234) (xy 365.940448 -270.157179) (xy 365.950389 -270.10775) (xy 365.967726 -270.060406)
			(xy 365.992056 -270.016246) (xy 366.022814 -269.976296) (xy 366.059285 -269.941484) (xy 366.100624 -269.912619)
			(xy 366.145868 -269.890371) (xy 366.193968 -269.875257) (xy 366.243806 -269.867627) (xy 366.269016 -269.867126)
			(xy 366.294984 -269.867637) (xy 366.34628 -269.875763) (xy 366.395674 -269.891814) (xy 366.441948 -269.915394)
			(xy 366.483964 -269.945923) (xy 366.520688 -269.982648) (xy 366.551214 -270.024666) (xy 366.574792 -270.070941)
			(xy 366.59084 -270.120335) (xy 366.598965 -270.171632) (xy 366.598965 -270.223547) (xy 370.638071 -270.223547)
			(xy 370.638071 -270.171613) (xy 370.646196 -270.120318) (xy 370.662244 -270.070925) (xy 370.685822 -270.024651)
			(xy 370.716348 -269.982635) (xy 370.753071 -269.945912) (xy 370.795087 -269.915386) (xy 370.841361 -269.891808)
			(xy 370.890754 -269.87576) (xy 370.942049 -269.867635) (xy 370.993983 -269.867635) (xy 371.045278 -269.87576)
			(xy 371.094671 -269.891808) (xy 371.140945 -269.915386) (xy 371.182961 -269.945912) (xy 371.219684 -269.982635)
			(xy 371.25021 -270.024651) (xy 371.273788 -270.070925) (xy 371.289836 -270.120318) (xy 371.297961 -270.171613)
			(xy 371.29847 -270.19758) (xy 371.297961 -270.223547) (xy 371.577871 -270.223547) (xy 371.577871 -270.171613)
			(xy 371.585996 -270.120318) (xy 371.602044 -270.070925) (xy 371.625622 -270.024651) (xy 371.656148 -269.982635)
			(xy 371.692871 -269.945912) (xy 371.734887 -269.915386) (xy 371.781161 -269.891808) (xy 371.830554 -269.87576)
			(xy 371.881849 -269.867635) (xy 371.933783 -269.867635) (xy 371.985078 -269.87576) (xy 372.034471 -269.891808)
			(xy 372.080745 -269.915386) (xy 372.122761 -269.945912) (xy 372.159484 -269.982635) (xy 372.19001 -270.024651)
			(xy 372.213588 -270.070925) (xy 372.229636 -270.120318) (xy 372.237761 -270.171613) (xy 372.23827 -270.19758)
			(xy 372.237761 -270.223547) (xy 372.517671 -270.223547) (xy 372.517671 -270.171613) (xy 372.525796 -270.120318)
			(xy 372.541844 -270.070925) (xy 372.565422 -270.024651) (xy 372.595948 -269.982635) (xy 372.632671 -269.945912)
			(xy 372.674687 -269.915386) (xy 372.720961 -269.891808) (xy 372.770354 -269.87576) (xy 372.821649 -269.867635)
			(xy 372.873583 -269.867635) (xy 372.924878 -269.87576) (xy 372.974271 -269.891808) (xy 373.020545 -269.915386)
			(xy 373.062561 -269.945912) (xy 373.099284 -269.982635) (xy 373.12981 -270.024651) (xy 373.153388 -270.070925)
			(xy 373.169436 -270.120318) (xy 373.177561 -270.171613) (xy 373.17807 -270.19758) (xy 373.177561 -270.223547)
			(xy 373.169436 -270.274842) (xy 373.153388 -270.324235) (xy 373.12981 -270.370509) (xy 373.099284 -270.412525)
			(xy 373.062561 -270.449248) (xy 373.020545 -270.479774) (xy 372.974271 -270.503352) (xy 372.924878 -270.5194)
			(xy 372.873583 -270.527525) (xy 372.821649 -270.527525) (xy 372.770354 -270.5194) (xy 372.720961 -270.503352)
			(xy 372.674687 -270.479774) (xy 372.632671 -270.449248) (xy 372.595948 -270.412525) (xy 372.565422 -270.370509)
			(xy 372.541844 -270.324235) (xy 372.525796 -270.274842) (xy 372.517671 -270.223547) (xy 372.237761 -270.223547)
			(xy 372.229636 -270.274842) (xy 372.213588 -270.324235) (xy 372.19001 -270.370509) (xy 372.159484 -270.412525)
			(xy 372.122761 -270.449248) (xy 372.080745 -270.479774) (xy 372.034471 -270.503352) (xy 371.985078 -270.5194)
			(xy 371.933783 -270.527525) (xy 371.881849 -270.527525) (xy 371.830554 -270.5194) (xy 371.781161 -270.503352)
			(xy 371.734887 -270.479774) (xy 371.692871 -270.449248) (xy 371.656148 -270.412525) (xy 371.625622 -270.370509)
			(xy 371.602044 -270.324235) (xy 371.585996 -270.274842) (xy 371.577871 -270.223547) (xy 371.297961 -270.223547)
			(xy 371.289836 -270.274842) (xy 371.273788 -270.324235) (xy 371.25021 -270.370509) (xy 371.219684 -270.412525)
			(xy 371.182961 -270.449248) (xy 371.140945 -270.479774) (xy 371.094671 -270.503352) (xy 371.045278 -270.5194)
			(xy 370.993983 -270.527525) (xy 370.942049 -270.527525) (xy 370.890754 -270.5194) (xy 370.841361 -270.503352)
			(xy 370.795087 -270.479774) (xy 370.753071 -270.449248) (xy 370.716348 -270.412525) (xy 370.685822 -270.370509)
			(xy 370.662244 -270.324235) (xy 370.646196 -270.274842) (xy 370.638071 -270.223547) (xy 366.598965 -270.223547)
			(xy 366.598965 -270.223568) (xy 366.59084 -270.274865) (xy 366.574792 -270.324259) (xy 366.551214 -270.370534)
			(xy 366.520688 -270.412552) (xy 366.483964 -270.449277) (xy 366.441948 -270.479806) (xy 366.395674 -270.503386)
			(xy 366.34628 -270.519437) (xy 366.294984 -270.527563) (xy 366.269016 -270.528034) (xy 366.241913 -270.527514)
			(xy 366.188427 -270.518713) (xy 366.16259 -270.510508) (xy 366.132872 -270.500348) (xy 366.074452 -270.558514)
			(xy 366.195864 -270.679926) (xy 373.592344 -270.679926)
		)
		(stroke
			(width 0)
			(type solid)
		)
		(fill yes)
		(layer "In4.Cu")
		(net "PVCCINFAON_CPU0")
	)
	(gr_poly
		(pts
			(xy 342.647524 -326.257412) (xy 371.674644 -326.257412) (xy 374.979184 -329.561952) (xy 379.80366 -329.561952)
			(xy 382.630934 -332.389226) (xy 388.471918 -332.389226) (xy 388.832344 -332.0288) (xy 388.832344 -327.89495)
			(xy 388.287514 -327.198482) (xy 379.530864 -318.441832) (xy 375.835418 -313.715146) (xy 364.490254 -299.481494)
			(xy 364.490254 -297.567858) (xy 364.45698 -297.555666) (xy 364.435266 -297.547337) (xy 364.393869 -297.526143)
			(xy 364.35535 -297.50008) (xy 364.3376 -297.485054) (xy 364.326272 -297.475818) (xy 364.299715 -297.463642)
			(xy 364.270798 -297.459469) (xy 364.241881 -297.463642) (xy 364.215324 -297.475818) (xy 364.203996 -297.485054)
			(xy 364.183065 -297.502698) (xy 364.1371 -297.532427) (xy 364.087353 -297.555272) (xy 364.034849 -297.570764)
			(xy 363.980669 -297.578583) (xy 363.953298 -297.579034) (xy 363.926045 -297.578548) (xy 363.872094 -297.570791)
			(xy 363.819796 -297.555434) (xy 363.770215 -297.532792) (xy 363.724362 -297.503323) (xy 363.683169 -297.467629)
			(xy 363.647476 -297.426436) (xy 363.618007 -297.380583) (xy 363.595365 -297.331002) (xy 363.580009 -297.278704)
			(xy 363.572252 -297.224753) (xy 363.572252 -297.170247) (xy 363.580009 -297.116296) (xy 363.595365 -297.063998)
			(xy 363.618007 -297.014417) (xy 363.647476 -296.968564) (xy 363.683169 -296.927371) (xy 363.724362 -296.891677)
			(xy 363.770215 -296.862208) (xy 363.819796 -296.839566) (xy 363.872094 -296.824209) (xy 363.926045 -296.816452)
			(xy 363.953298 -296.816018) (xy 363.980668 -296.81649) (xy 364.034846 -296.824314) (xy 364.08735 -296.839801)
			(xy 364.1371 -296.862634) (xy 364.183077 -296.892343) (xy 364.203996 -296.909998) (xy 364.215324 -296.919234)
			(xy 364.241881 -296.93141) (xy 364.270798 -296.935583) (xy 364.299715 -296.93141) (xy 364.326272 -296.919234)
			(xy 364.3376 -296.909998) (xy 364.355354 -296.894975) (xy 364.393864 -296.8689) (xy 364.435263 -296.847707)
			(xy 364.45698 -296.839386) (xy 364.490254 -296.827194) (xy 364.490254 -295.408858) (xy 364.45698 -295.396666)
			(xy 364.435266 -295.388337) (xy 364.393869 -295.367143) (xy 364.35535 -295.34108) (xy 364.3376 -295.326054)
			(xy 364.326272 -295.316818) (xy 364.299715 -295.304642) (xy 364.270798 -295.300469) (xy 364.241881 -295.304642)
			(xy 364.215324 -295.316818) (xy 364.203996 -295.326054) (xy 364.183065 -295.343698) (xy 364.1371 -295.373427)
			(xy 364.087353 -295.396272) (xy 364.034849 -295.411764) (xy 363.980669 -295.419583) (xy 363.953298 -295.420034)
			(xy 363.926045 -295.419548) (xy 363.872094 -295.411791) (xy 363.819796 -295.396434) (xy 363.770215 -295.373792)
			(xy 363.724362 -295.344323) (xy 363.683169 -295.308629) (xy 363.647476 -295.267436) (xy 363.618007 -295.221583)
			(xy 363.595365 -295.172002) (xy 363.580009 -295.119704) (xy 363.572252 -295.065753) (xy 363.572252 -295.011247)
			(xy 363.580009 -294.957296) (xy 363.595365 -294.904998) (xy 363.618007 -294.855417) (xy 363.647476 -294.809564)
			(xy 363.683169 -294.768371) (xy 363.724362 -294.732677) (xy 363.770215 -294.703208) (xy 363.819796 -294.680566)
			(xy 363.872094 -294.665209) (xy 363.926045 -294.657452) (xy 363.953298 -294.657018) (xy 363.980668 -294.65749)
			(xy 364.034846 -294.665314) (xy 364.08735 -294.680801) (xy 364.1371 -294.703634) (xy 364.183077 -294.733343)
			(xy 364.203996 -294.750998) (xy 364.215324 -294.760234) (xy 364.241881 -294.77241) (xy 364.270798 -294.776583)
			(xy 364.299715 -294.77241) (xy 364.326272 -294.760234) (xy 364.3376 -294.750998) (xy 364.355354 -294.735975)
			(xy 364.393864 -294.7099) (xy 364.435263 -294.688707) (xy 364.45698 -294.680386) (xy 364.490254 -294.668194)
			(xy 364.490254 -293.272718) (xy 364.480264 -293.265889) (xy 364.461073 -293.251146) (xy 364.4519 -293.243254)
			(xy 364.440572 -293.234018) (xy 364.414015 -293.221842) (xy 364.385098 -293.217669) (xy 364.356181 -293.221842)
			(xy 364.329624 -293.234018) (xy 364.318296 -293.243254) (xy 364.297365 -293.260898) (xy 364.2514 -293.290627)
			(xy 364.201653 -293.313472) (xy 364.149149 -293.328964) (xy 364.094969 -293.336783) (xy 364.067598 -293.337234)
			(xy 364.040345 -293.336748) (xy 363.986394 -293.328991) (xy 363.934096 -293.313634) (xy 363.884515 -293.290992)
			(xy 363.838662 -293.261523) (xy 363.797469 -293.225829) (xy 363.761776 -293.184636) (xy 363.732307 -293.138783)
			(xy 363.709665 -293.089202) (xy 363.694309 -293.036904) (xy 363.686552 -292.982953) (xy 363.686552 -292.928447)
			(xy 363.694309 -292.874496) (xy 363.709665 -292.822198) (xy 363.732307 -292.772617) (xy 363.761776 -292.726764)
			(xy 363.797469 -292.685571) (xy 363.838662 -292.649877) (xy 363.884515 -292.620408) (xy 363.934096 -292.597766)
			(xy 363.986394 -292.582409) (xy 364.040345 -292.574652) (xy 364.067598 -292.574218) (xy 364.094968 -292.57469)
			(xy 364.149146 -292.582514) (xy 364.20165 -292.598001) (xy 364.2514 -292.620834) (xy 364.297377 -292.650543)
			(xy 364.318296 -292.668198) (xy 364.329624 -292.677434) (xy 364.356181 -292.68961) (xy 364.385098 -292.693783)
			(xy 364.414015 -292.68961) (xy 364.440572 -292.677434) (xy 364.4519 -292.668198) (xy 364.461071 -292.660303)
			(xy 364.480262 -292.64556) (xy 364.490254 -292.638734) (xy 364.490254 -292.298374) (xy 366.889792 -289.898836)
			(xy 366.884458 -289.872166) (xy 366.88146 -289.856078) (xy 366.878281 -289.823506) (xy 366.878108 -289.807142)
			(xy 366.878588 -289.781169) (xy 366.886707 -289.729863) (xy 366.902753 -289.680458) (xy 366.92633 -289.634172)
			(xy 366.956857 -289.592144) (xy 366.993583 -289.555409) (xy 367.035604 -289.524872) (xy 367.081884 -289.501284)
			(xy 367.131285 -289.485226) (xy 367.18259 -289.477094) (xy 367.208562 -289.476688) (xy 367.218173 -289.476773)
			(xy 367.237362 -289.477917) (xy 367.246916 -289.478974) (xy 367.258451 -289.448232) (xy 367.285146 -289.388237)
			(xy 367.300256 -289.359086) (xy 367.42243 -289.127946) (xy 367.405158 -289.102546) (xy 367.39173 -289.081908)
			(xy 367.370471 -289.0375) (xy 367.356026 -288.990432) (xy 367.348713 -288.941743) (xy 367.348262 -288.917126)
			(xy 367.34875 -288.891482) (xy 367.356679 -288.840809) (xy 367.372335 -288.791968) (xy 367.395343 -288.746129)
			(xy 367.425152 -288.704392) (xy 367.44275 -288.685732) (xy 367.44275 -287.520634) (xy 367.425135 -287.501984)
			(xy 367.395303 -287.46025) (xy 367.372277 -287.414409) (xy 367.356611 -287.365561) (xy 367.348681 -287.314878)
			(xy 367.348676 -287.263579) (xy 367.356598 -287.212895) (xy 367.372256 -287.164044) (xy 367.395273 -287.118199)
			(xy 367.425098 -287.07646) (xy 367.44275 -287.057846) (xy 367.44275 -286.88665) (xy 367.442302 -286.87298)
			(xy 367.435036 -286.846623) (xy 367.421038 -286.823138) (xy 367.401311 -286.804209) (xy 367.377268 -286.791191)
			(xy 367.350634 -286.785018) (xy 367.323317 -286.786132) (xy 367.310162 -286.789876) (xy 367.28549 -286.797329)
			(xy 367.234584 -286.805367) (xy 367.208816 -286.805878) (xy 367.182844 -286.805396) (xy 367.131539 -286.797273)
			(xy 367.082137 -286.781223) (xy 367.035854 -286.757643) (xy 366.993829 -286.727112) (xy 366.957099 -286.690383)
			(xy 366.926566 -286.64836) (xy 366.902983 -286.602078) (xy 366.886931 -286.552676) (xy 366.878805 -286.501372)
			(xy 366.878805 -286.449428) (xy 366.886931 -286.398124) (xy 366.902983 -286.348722) (xy 366.926566 -286.30244)
			(xy 366.957099 -286.260417) (xy 366.993829 -286.223688) (xy 367.035854 -286.193157) (xy 367.082137 -286.169577)
			(xy 367.131539 -286.153527) (xy 367.182844 -286.145404) (xy 367.208816 -286.14497) (xy 367.234583 -286.145488)
			(xy 367.285487 -286.153532) (xy 367.310162 -286.160972) (xy 367.323322 -286.164728) (xy 367.350656 -286.165866)
			(xy 367.377311 -286.159706) (xy 367.401373 -286.14669) (xy 367.421116 -286.127752) (xy 367.435122 -286.104252)
			(xy 367.442385 -286.077877) (xy 367.44275 -286.064198) (xy 367.44275 -285.893002) (xy 367.425097 -285.874344)
			(xy 367.395199 -285.83258) (xy 367.372127 -285.78669) (xy 367.356438 -285.737783) (xy 367.348509 -285.687036)
			(xy 367.348008 -285.661354) (xy 367.348617 -285.633373) (xy 367.35806 -285.578212) (xy 367.366804 -285.551626)
			(xy 367.374424 -285.529528) (xy 367.170716 -285.176722) (xy 367.147856 -285.172404) (xy 367.122925 -285.167255)
			(xy 367.074922 -285.150315) (xy 367.030084 -285.126212) (xy 366.989475 -285.095517) (xy 366.954055 -285.058955)
			(xy 366.924663 -285.017393) (xy 366.901994 -284.971814) (xy 366.886586 -284.923297) (xy 366.878802 -284.872991)
			(xy 366.878362 -284.847538) (xy 366.878842 -284.821567) (xy 366.886962 -284.770264) (xy 366.903009 -284.720864)
			(xy 366.926587 -284.674582) (xy 366.957115 -284.632559) (xy 366.993842 -284.59583) (xy 367.035863 -284.565299)
			(xy 367.082143 -284.541718) (xy 367.131543 -284.525668) (xy 367.182845 -284.517544) (xy 367.208816 -284.517084)
			(xy 367.234583 -284.517602) (xy 367.285486 -284.525647) (xy 367.310162 -284.533086) (xy 367.323323 -284.536842)
			(xy 367.350658 -284.53798) (xy 367.377314 -284.53182) (xy 367.401377 -284.518804) (xy 367.421122 -284.499867)
			(xy 367.43513 -284.476367) (xy 367.442397 -284.449991) (xy 367.44275 -284.436312) (xy 367.44275 -284.26537)
			(xy 367.425096 -284.24671) (xy 367.395193 -284.204944) (xy 367.372112 -284.159055) (xy 367.356408 -284.110147)
			(xy 367.34846 -284.059399) (xy 367.348457 -284.008032) (xy 367.356401 -283.957283) (xy 367.372101 -283.908374)
			(xy 367.395177 -283.862483) (xy 367.425075 -283.820714) (xy 367.44275 -283.802074) (xy 367.44275 -283.631132)
			(xy 367.442298 -283.61744) (xy 367.435011 -283.591043) (xy 367.420978 -283.567527) (xy 367.401205 -283.54858)
			(xy 367.377113 -283.535562) (xy 367.350429 -283.529407) (xy 367.323068 -283.530556) (xy 367.309908 -283.534358)
			(xy 367.285236 -283.541813) (xy 367.23433 -283.549857) (xy 367.208562 -283.55036) (xy 367.182596 -283.549848)
			(xy 367.131305 -283.541719) (xy 367.081917 -283.525666) (xy 367.035647 -283.502086) (xy 366.993636 -283.471559)
			(xy 366.956917 -283.434835) (xy 366.926394 -283.392821) (xy 366.902819 -283.346548) (xy 366.886772 -283.297158)
			(xy 366.878649 -283.245866) (xy 366.878649 -283.193934) (xy 366.886772 -283.142642) (xy 366.902819 -283.093252)
			(xy 366.926394 -283.046979) (xy 366.956917 -283.004965) (xy 366.993636 -282.968241) (xy 367.035647 -282.937714)
			(xy 367.081917 -282.914134) (xy 367.131305 -282.898081) (xy 367.182596 -282.889952) (xy 367.208562 -282.889452)
			(xy 367.23433 -282.889965) (xy 367.285236 -282.898002) (xy 367.309908 -282.905454) (xy 367.323082 -282.90925)
			(xy 367.35046 -282.91045) (xy 367.37717 -282.904323) (xy 367.401288 -282.89131) (xy 367.421074 -282.872349)
			(xy 367.435103 -282.848808) (xy 367.442363 -282.822383) (xy 367.44275 -282.80868) (xy 367.44275 -282.637484)
			(xy 367.425094 -282.618824) (xy 367.39519 -282.577057) (xy 367.372107 -282.531168) (xy 367.356401 -282.482259)
			(xy 367.348451 -282.43151) (xy 367.348447 -282.380141) (xy 367.356389 -282.329391) (xy 367.372088 -282.28048)
			(xy 367.395164 -282.234587) (xy 367.425061 -282.192815) (xy 367.44275 -282.174188) (xy 367.44275 -282.003246)
			(xy 367.442302 -281.989576) (xy 367.435035 -281.96322) (xy 367.421036 -281.939737) (xy 367.40131 -281.920808)
			(xy 367.377268 -281.907791) (xy 367.350634 -281.901618) (xy 367.323318 -281.902732) (xy 367.310162 -281.906472)
			(xy 367.28549 -281.913925) (xy 367.234584 -281.921964) (xy 367.208816 -281.922474) (xy 367.182844 -281.921992)
			(xy 367.13154 -281.913869) (xy 367.082138 -281.897819) (xy 367.035856 -281.874239) (xy 366.993832 -281.843709)
			(xy 366.957102 -281.80698) (xy 366.926569 -281.764958) (xy 366.902987 -281.718676) (xy 366.886935 -281.669275)
			(xy 366.878809 -281.617972) (xy 366.878809 -281.566028) (xy 366.886935 -281.514725) (xy 366.902987 -281.465324)
			(xy 366.926569 -281.419042) (xy 366.957102 -281.37702) (xy 366.993832 -281.340291) (xy 367.035856 -281.309761)
			(xy 367.082138 -281.286181) (xy 367.13154 -281.270131) (xy 367.182844 -281.262008) (xy 367.208816 -281.261566)
			(xy 367.234583 -281.262084) (xy 367.285487 -281.270128) (xy 367.310162 -281.277568) (xy 367.323322 -281.281324)
			(xy 367.350656 -281.282463) (xy 367.37731 -281.276303) (xy 367.401372 -281.263286) (xy 367.421114 -281.244348)
			(xy 367.435119 -281.220848) (xy 367.442382 -281.194473) (xy 367.44275 -281.180794) (xy 367.44275 -281.009852)
			(xy 367.425097 -280.991192) (xy 367.395198 -280.949426) (xy 367.372119 -280.903538) (xy 367.356418 -280.854632)
			(xy 367.348471 -280.803885) (xy 367.348471 -280.75252) (xy 367.356416 -280.701774) (xy 367.372117 -280.652867)
			(xy 367.395195 -280.606979) (xy 367.425093 -280.565212) (xy 367.44275 -280.546556) (xy 367.44275 -280.37536)
			(xy 367.442303 -280.361689) (xy 367.435039 -280.33533) (xy 367.421041 -280.311843) (xy 367.401313 -280.292911)
			(xy 367.37727 -280.279892) (xy 367.350634 -280.273718) (xy 367.323315 -280.274833) (xy 367.310162 -280.278586)
			(xy 367.28549 -280.286039) (xy 367.234584 -280.294077) (xy 367.208816 -280.294588) (xy 367.182843 -280.294106)
			(xy 367.131537 -280.285982) (xy 367.082133 -280.269932) (xy 367.035849 -280.246351) (xy 366.993823 -280.215819)
			(xy 366.957091 -280.179089) (xy 366.926557 -280.137065) (xy 366.902974 -280.090782) (xy 366.886921 -280.041379)
			(xy 366.878795 -279.990073) (xy 366.878795 -279.938127) (xy 366.886921 -279.886821) (xy 366.902974 -279.837418)
			(xy 366.926557 -279.791135) (xy 366.957091 -279.749111) (xy 366.993823 -279.712381) (xy 367.035849 -279.681849)
			(xy 367.082133 -279.658268) (xy 367.131537 -279.642218) (xy 367.182843 -279.634094) (xy 367.208816 -279.63368)
			(xy 367.234583 -279.634198) (xy 367.285486 -279.642243) (xy 367.310162 -279.649682) (xy 367.323323 -279.653438)
			(xy 367.350657 -279.654576) (xy 367.377313 -279.648416) (xy 367.401376 -279.6354) (xy 367.42112 -279.616463)
			(xy 367.435128 -279.592963) (xy 367.442394 -279.566587) (xy 367.44275 -279.552908) (xy 367.44275 -279.381966)
			(xy 367.425096 -279.363306) (xy 367.395194 -279.32154) (xy 367.372114 -279.275651) (xy 367.356411 -279.226744)
			(xy 367.348462 -279.175996) (xy 367.34846 -279.12463) (xy 367.356405 -279.073881) (xy 367.372104 -279.024973)
			(xy 367.395181 -278.979082) (xy 367.425079 -278.937314) (xy 367.44275 -278.91867) (xy 367.44275 -278.747728)
			(xy 367.442312 -278.734051) (xy 367.435058 -278.707675) (xy 367.421064 -278.684171) (xy 367.401333 -278.665225)
			(xy 367.37728 -278.652195) (xy 367.350632 -278.646018) (xy 367.3233 -278.647135) (xy 367.310162 -278.650954)
			(xy 367.28549 -278.658406) (xy 367.234584 -278.666442) (xy 367.208816 -278.666956) (xy 367.182846 -278.666474)
			(xy 367.131544 -278.658351) (xy 367.082145 -278.642303) (xy 367.035865 -278.618724) (xy 366.993844 -278.588195)
			(xy 366.957115 -278.551469) (xy 366.926585 -278.509448) (xy 366.903003 -278.463169) (xy 366.886952 -278.413771)
			(xy 366.878827 -278.36247) (xy 366.878827 -278.31053) (xy 366.886952 -278.259229) (xy 366.903003 -278.209831)
			(xy 366.926585 -278.163552) (xy 366.957115 -278.121531) (xy 366.993844 -278.084805) (xy 367.035865 -278.054276)
			(xy 367.082145 -278.030697) (xy 367.131544 -278.014649) (xy 367.182846 -278.006526) (xy 367.208816 -278.006048)
			(xy 367.236433 -278.006607) (xy 367.290895 -278.015798) (xy 367.34307 -278.033922) (xy 367.367566 -278.046688)
			(xy 367.378996 -278.053038) (xy 367.44275 -278.053038) (xy 367.44275 -277.954994) (xy 367.173256 -277.6855)
			(xy 367.162174 -277.675243) (xy 367.135493 -277.661133) (xy 367.105854 -277.655435) (xy 367.075844 -277.658646)
			(xy 367.048082 -277.670487) (xy 367.024991 -277.689924) (xy 367.016284 -277.702264) (xy 367.000891 -277.724984)
			(xy 366.963824 -277.765449) (xy 366.920585 -277.79924) (xy 366.872362 -277.82543) (xy 366.820477 -277.843301)
			(xy 366.766354 -277.852362) (xy 366.738916 -277.852886) (xy 366.712947 -277.852378) (xy 366.661648 -277.844256)
			(xy 366.612251 -277.828209) (xy 366.565973 -277.804633) (xy 366.523952 -277.774107) (xy 366.487224 -277.737384)
			(xy 366.456692 -277.695368) (xy 366.433109 -277.649093) (xy 366.417055 -277.599699) (xy 366.408926 -277.548401)
			(xy 366.408462 -277.522432) (xy 366.409 -277.494994) (xy 366.418055 -277.440871) (xy 366.435921 -277.388985)
			(xy 366.462109 -277.340761) (xy 366.495899 -277.297522) (xy 366.536363 -277.260456) (xy 366.559084 -277.245064)
			(xy 366.57148 -277.236414) (xy 366.590962 -277.213324) (xy 366.602828 -277.185542) (xy 366.606038 -277.155502)
			(xy 366.60031 -277.125839) (xy 366.586148 -277.099154) (xy 366.575848 -277.088092) (xy 366.46485 -276.977094)
			(xy 366.431322 -276.996144) (xy 366.406347 -277.00955) (xy 366.352953 -277.028565) (xy 366.297101 -277.038218)
			(xy 366.268762 -277.038816) (xy 366.242798 -277.038304) (xy 366.19151 -277.030175) (xy 366.142125 -277.014122)
			(xy 366.095859 -276.990542) (xy 366.053851 -276.960014) (xy 366.017136 -276.923291) (xy 365.986618 -276.881276)
			(xy 365.963049 -276.835005) (xy 365.947008 -276.785616) (xy 365.93889 -276.734326) (xy 365.938308 -276.708362)
			(xy 365.938866 -276.680018) (xy 365.9485 -276.624157) (xy 365.967545 -276.570766) (xy 365.98098 -276.545802)
			(xy 366.00003 -276.512274) (xy 365.697262 -276.209506) (xy 365.686594 -276.205696) (xy 365.663987 -276.197082)
			(xy 365.621369 -276.17419) (xy 365.582543 -276.14533) (xy 365.548338 -276.11112) (xy 365.519484 -276.072289)
			(xy 365.496598 -276.029668) (xy 365.487966 -276.007068) (xy 365.484156 -275.9964) (xy 365.383064 -275.895308)
			(xy 365.383064 -275.461984) (xy 365.382628 -275.451905) (xy 365.37486 -275.433303) (xy 365.360527 -275.419127)
			(xy 365.34184 -275.411563) (xy 365.331756 -275.411184) (xy 365.329216 -275.411184) (xy 365.303244 -275.410702)
			(xy 365.251938 -275.402579) (xy 365.202535 -275.386529) (xy 365.156251 -275.362948) (xy 365.114225 -275.332416)
			(xy 365.077494 -275.295687) (xy 365.046961 -275.253663) (xy 365.023378 -275.20738) (xy 365.007325 -275.157978)
			(xy 364.999199 -275.106672) (xy 364.999199 -275.054728) (xy 365.007325 -275.003422) (xy 365.023378 -274.95402)
			(xy 365.046961 -274.907737) (xy 365.077494 -274.865713) (xy 365.114225 -274.828984) (xy 365.156251 -274.798452)
			(xy 365.202535 -274.774871) (xy 365.251938 -274.758821) (xy 365.303244 -274.750698) (xy 365.329216 -274.750276)
			(xy 365.331756 -274.750276) (xy 365.341848 -274.74995) (xy 365.360547 -274.742378) (xy 365.374886 -274.728185)
			(xy 365.38265 -274.709564) (xy 365.383064 -274.699476) (xy 365.383064 -273.834352) (xy 365.382623 -273.824277)
			(xy 365.374848 -273.805686) (xy 365.360517 -273.79152) (xy 365.341837 -273.783963) (xy 365.331756 -273.783552)
			(xy 365.329216 -273.783552) (xy 365.300479 -273.782934) (xy 365.243873 -273.772992) (xy 365.189841 -273.753404)
			(xy 365.164624 -273.73961) (xy 365.151162 -273.732424) (xy 365.121425 -273.725638) (xy 365.091009 -273.727925)
			(xy 365.062621 -273.739084) (xy 365.038787 -273.758119) (xy 365.02163 -273.783338) (xy 365.012675 -273.812496)
			(xy 365.012224 -273.827748) (xy 365.012224 -273.974052) (xy 365.034818 -273.986379) (xy 365.076219 -274.016956)
			(xy 365.112371 -274.053588) (xy 365.142401 -274.095387) (xy 365.165579 -274.14134) (xy 365.181344 -274.190333)
			(xy 365.189315 -274.24118) (xy 365.18977 -274.266914) (xy 365.189261 -274.292881) (xy 365.181136 -274.344176)
			(xy 365.165088 -274.393569) (xy 365.14151 -274.439843) (xy 365.110984 -274.481859) (xy 365.074261 -274.518582)
			(xy 365.032245 -274.549108) (xy 364.985971 -274.572686) (xy 364.936578 -274.588734) (xy 364.885283 -274.596859)
			(xy 364.833349 -274.596859) (xy 364.782054 -274.588734) (xy 364.732661 -274.572686) (xy 364.686387 -274.549108)
			(xy 364.644371 -274.518582) (xy 364.607648 -274.481859) (xy 364.577122 -274.439843) (xy 364.553544 -274.393569)
			(xy 364.537496 -274.344176) (xy 364.529371 -274.292881) (xy 364.528862 -274.266914) (xy 364.529363 -274.241146)
			(xy 364.53738 -274.190237) (xy 364.553206 -274.14119) (xy 364.576456 -274.095196) (xy 364.606567 -274.053371)
			(xy 364.642808 -274.016729) (xy 364.6843 -273.986161) (xy 364.706916 -273.973798) (xy 364.706916 -273.827494)
			(xy 364.706336 -273.812273) (xy 364.697346 -273.783187) (xy 364.680193 -273.758035) (xy 364.656399 -273.739045)
			(xy 364.628069 -273.727899) (xy 364.597713 -273.725584) (xy 364.56802 -273.732306) (xy 364.554516 -273.739356)
			(xy 364.529228 -273.753219) (xy 364.475037 -273.772927) (xy 364.418248 -273.782935) (xy 364.389416 -273.783552)
			(xy 364.363446 -273.78307) (xy 364.312145 -273.774947) (xy 364.262746 -273.758899) (xy 364.216467 -273.73532)
			(xy 364.174446 -273.704792) (xy 364.137718 -273.668065) (xy 364.107187 -273.626045) (xy 364.083607 -273.579767)
			(xy 364.067556 -273.530369) (xy 364.059431 -273.479068) (xy 364.058962 -273.453098) (xy 364.059442 -273.427079)
			(xy 364.067588 -273.375684) (xy 364.083693 -273.326203) (xy 364.107359 -273.279859) (xy 364.138001 -273.2378)
			(xy 364.174859 -273.201068) (xy 364.217022 -273.17057) (xy 364.263446 -273.147062) (xy 364.28807 -273.138646)
			(xy 364.300756 -273.134159) (xy 364.323348 -273.119556) (xy 364.341333 -273.099551) (xy 364.353458 -273.075538)
			(xy 364.35888 -273.04919) (xy 364.35722 -273.022341) (xy 364.348594 -272.996861) (xy 364.34141 -272.985484)
			(xy 364.330159 -272.968315) (xy 364.309694 -272.932726) (xy 364.300516 -272.914364) (xy 364.294187 -272.902521)
			(xy 364.276403 -272.882413) (xy 364.253993 -272.867637) (xy 364.228505 -272.859214) (xy 364.201702 -272.857728)
			(xy 364.175439 -272.86328) (xy 364.151532 -272.875488) (xy 364.141258 -272.884138) (xy 364.12292 -272.900165)
			(xy 364.082421 -272.927216) (xy 364.038393 -272.948035) (xy 363.991787 -272.962172) (xy 363.943613 -272.969323)
			(xy 363.919262 -272.969736) (xy 363.893298 -272.969224) (xy 363.842011 -272.961095) (xy 363.792626 -272.945044)
			(xy 363.74636 -272.921466) (xy 363.704351 -272.89094) (xy 363.667635 -272.85422) (xy 363.637114 -272.812208)
			(xy 363.613541 -272.765939) (xy 363.597496 -272.716552) (xy 363.589373 -272.665264) (xy 363.589373 -272.613336)
			(xy 363.597496 -272.562048) (xy 363.613541 -272.512661) (xy 363.637114 -272.466392) (xy 363.667635 -272.42438)
			(xy 363.704351 -272.38766) (xy 363.74636 -272.357134) (xy 363.792626 -272.333556) (xy 363.842011 -272.317505)
			(xy 363.893298 -272.309376) (xy 363.919262 -272.308828) (xy 363.943623 -272.309281) (xy 363.991813 -272.316466)
			(xy 364.038428 -272.330644) (xy 364.082458 -272.351506) (xy 364.122952 -272.378601) (xy 364.141258 -272.39468)
			(xy 364.151504 -272.403433) (xy 364.175484 -272.415708) (xy 364.201839 -272.421283) (xy 364.228736 -272.419768)
			(xy 364.254299 -272.411271) (xy 364.27675 -272.396382) (xy 364.294523 -272.376139) (xy 364.30077 -272.3642)
			(xy 364.31003 -272.345907) (xy 364.330622 -272.310446) (xy 364.341918 -272.293334) (xy 364.349089 -272.281911)
			(xy 364.357736 -272.256373) (xy 364.359393 -272.229461) (xy 364.353944 -272.203056) (xy 364.34177 -272.178998)
			(xy 364.323721 -272.158969) (xy 364.301056 -272.144365) (xy 364.288324 -272.139918) (xy 364.263648 -272.131512)
			(xy 364.217106 -272.108038) (xy 364.174825 -272.077549) (xy 364.137854 -272.040802) (xy 364.107109 -271.998706)
			(xy 364.083353 -271.952307) (xy 364.067175 -271.902754) (xy 364.058975 -271.851275) (xy 364.058454 -271.825212)
			(xy 364.058943 -271.799158) (xy 364.067119 -271.747696) (xy 364.08327 -271.698155) (xy 364.106996 -271.651763)
			(xy 364.13771 -271.609669) (xy 364.174649 -271.572918) (xy 364.216898 -271.542419) (xy 364.26341 -271.518928)
			(xy 364.28807 -271.510506) (xy 364.300752 -271.506018) (xy 364.323336 -271.491415) (xy 364.341312 -271.471413)
			(xy 364.353429 -271.447404) (xy 364.358843 -271.421062) (xy 364.357176 -271.39422) (xy 364.348545 -271.36875)
			(xy 364.34141 -271.357344) (xy 364.330175 -271.340231) (xy 364.309713 -271.304768) (xy 364.300516 -271.286478)
			(xy 364.294188 -271.274634) (xy 364.276405 -271.254523) (xy 364.253994 -271.239745) (xy 364.228505 -271.231321)
			(xy 364.201701 -271.229834) (xy 364.175437 -271.235388) (xy 364.151529 -271.247597) (xy 364.141258 -271.256252)
			(xy 364.12292 -271.272279) (xy 364.08242 -271.299328) (xy 364.038392 -271.320146) (xy 363.991787 -271.334283)
			(xy 363.943613 -271.341433) (xy 363.919262 -271.34185) (xy 363.893297 -271.341338) (xy 363.842007 -271.333209)
			(xy 363.79262 -271.317157) (xy 363.746352 -271.293578) (xy 363.704342 -271.263051) (xy 363.667624 -271.226329)
			(xy 363.637102 -271.184315) (xy 363.613528 -271.138045) (xy 363.597482 -271.088656) (xy 363.589359 -271.037365)
			(xy 363.589359 -270.985435) (xy 363.597482 -270.934144) (xy 363.613528 -270.884755) (xy 363.637102 -270.838485)
			(xy 363.667624 -270.796471) (xy 363.704342 -270.759749) (xy 363.746352 -270.729222) (xy 363.79262 -270.705643)
			(xy 363.842007 -270.689591) (xy 363.893297 -270.681462) (xy 363.919262 -270.680942) (xy 363.943623 -270.681395)
			(xy 363.991813 -270.688581) (xy 364.038427 -270.702758) (xy 364.082457 -270.723621) (xy 364.12295 -270.750717)
			(xy 364.141258 -270.766794) (xy 364.1515 -270.775553) (xy 364.175478 -270.787838) (xy 364.201835 -270.793418)
			(xy 364.228733 -270.791904) (xy 364.254298 -270.783401) (xy 364.276744 -270.768502) (xy 364.294508 -270.748247)
			(xy 364.30077 -270.736314) (xy 364.309964 -270.718023) (xy 364.330428 -270.682561) (xy 364.341664 -270.665448)
			(xy 364.348784 -270.654043) (xy 364.357359 -270.628571) (xy 364.358993 -270.601744) (xy 364.353574 -270.57542)
			(xy 364.341476 -270.55142) (xy 364.323538 -270.531406) (xy 364.301 -270.516763) (xy 364.288324 -270.512286)
			(xy 364.263694 -270.50384) (xy 364.217249 -270.480303) (xy 364.175068 -270.449778) (xy 364.138193 -270.413018)
			(xy 364.107536 -270.370932) (xy 364.083855 -270.324561) (xy 364.067735 -270.275052) (xy 364.059574 -270.223628)
			(xy 364.059575 -270.17156) (xy 364.067738 -270.120136) (xy 364.08386 -270.070627) (xy 364.107543 -270.024257)
			(xy 364.138201 -269.982173) (xy 364.175078 -269.945414) (xy 364.21726 -269.91489) (xy 364.263705 -269.891356)
			(xy 364.288324 -269.882874) (xy 364.301008 -269.87839) (xy 364.323595 -269.863792) (xy 364.341573 -269.843791)
			(xy 364.35369 -269.819781) (xy 364.3591 -269.793437) (xy 364.357426 -269.766596) (xy 364.348785 -269.741128)
			(xy 364.341664 -269.729712) (xy 364.330353 -269.712544) (xy 364.309763 -269.676954) (xy 364.300516 -269.658592)
			(xy 364.294189 -269.646746) (xy 364.276407 -269.626633) (xy 364.253996 -269.611852) (xy 364.228505 -269.603427)
			(xy 364.2017 -269.60194) (xy 364.175434 -269.607495) (xy 364.151526 -269.619707) (xy 364.141258 -269.628366)
			(xy 364.12292 -269.644393) (xy 364.08242 -269.671441) (xy 364.038391 -269.692258) (xy 363.991787 -269.706394)
			(xy 363.943613 -269.713544) (xy 363.919262 -269.713964) (xy 363.893296 -269.713452) (xy 363.842004 -269.705323)
			(xy 363.792615 -269.68927) (xy 363.746345 -269.66569) (xy 363.704333 -269.635162) (xy 363.667614 -269.598438)
			(xy 363.63709 -269.556423) (xy 363.613515 -269.51015) (xy 363.597469 -269.460759) (xy 363.589345 -269.409466)
			(xy 363.589345 -269.357534) (xy 363.597469 -269.306241) (xy 363.613515 -269.25685) (xy 363.63709 -269.210577)
			(xy 363.667614 -269.168562) (xy 363.704333 -269.131838) (xy 363.746345 -269.10131) (xy 363.792615 -269.07773)
			(xy 363.842004 -269.061677) (xy 363.893296 -269.053548) (xy 363.919262 -269.053056) (xy 363.943623 -269.053509)
			(xy 363.991813 -269.060695) (xy 364.038426 -269.074873) (xy 364.082456 -269.095736) (xy 364.122948 -269.122833)
			(xy 364.141258 -269.138908) (xy 364.151501 -269.147666) (xy 364.175479 -269.15995) (xy 364.201835 -269.165529)
			(xy 364.228734 -269.164015) (xy 364.254298 -269.155512) (xy 364.276745 -269.140615) (xy 364.294511 -269.120362)
			(xy 364.30077 -269.108428) (xy 364.309964 -269.090136) (xy 364.330427 -269.054674) (xy 364.341664 -269.037562)
			(xy 364.348786 -269.026157) (xy 364.357365 -269.000683) (xy 364.359002 -268.973853) (xy 364.353584 -268.947525)
			(xy 364.341487 -268.923521) (xy 364.323547 -268.903503) (xy 364.301008 -268.888858) (xy 364.288324 -268.8844)
			(xy 364.263692 -268.875954) (xy 364.217246 -268.852417) (xy 364.175063 -268.821891) (xy 364.138186 -268.78513)
			(xy 364.107527 -268.743043) (xy 364.083844 -268.696671) (xy 364.067723 -268.647159) (xy 364.059561 -268.595733)
			(xy 364.059562 -268.543663) (xy 364.067724 -268.492237) (xy 364.083846 -268.442726) (xy 364.107529 -268.396354)
			(xy 364.138188 -268.354268) (xy 364.175066 -268.317507) (xy 364.217249 -268.286981) (xy 364.263696 -268.263445)
			(xy 364.288324 -268.254988) (xy 364.301009 -268.250504) (xy 364.323599 -268.235906) (xy 364.34158 -268.215904)
			(xy 364.3537 -268.191893) (xy 364.359113 -268.165547) (xy 364.357441 -268.138703) (xy 364.348802 -268.113232)
			(xy 364.341664 -268.101826) (xy 364.330428 -268.084713) (xy 364.309966 -268.04925) (xy 364.30077 -268.03096)
			(xy 364.294469 -268.01906) (xy 364.276703 -267.998837) (xy 364.254268 -267.983963) (xy 364.228723 -267.975474)
			(xy 364.201847 -267.973961) (xy 364.175511 -267.979529) (xy 364.151548 -267.991791) (xy 364.141258 -268.00048)
			(xy 364.122936 -268.01654) (xy 364.082454 -268.043651) (xy 364.038428 -268.064519) (xy 363.991814 -268.07869)
			(xy 363.943623 -268.085859) (xy 363.919262 -268.086332) (xy 363.893298 -268.08582) (xy 363.842011 -268.077691)
			(xy 363.792627 -268.061641) (xy 363.746362 -268.038062) (xy 363.704354 -268.007537) (xy 363.667638 -267.970817)
			(xy 363.637118 -267.928806) (xy 363.613545 -267.882538) (xy 363.5975 -267.833152) (xy 363.589377 -267.781864)
			(xy 363.589377 -267.729936) (xy 363.5975 -267.678648) (xy 363.613545 -267.629262) (xy 363.637118 -267.582994)
			(xy 363.667638 -267.540983) (xy 363.704354 -267.504263) (xy 363.746362 -267.473738) (xy 363.792627 -267.450159)
			(xy 363.842011 -267.434109) (xy 363.893298 -267.42598) (xy 363.919262 -267.425424) (xy 363.943648 -267.425857)
			(xy 363.991891 -267.43302) (xy 364.038558 -267.447195) (xy 364.082634 -267.468076) (xy 364.123163 -267.495207)
			(xy 364.141512 -267.511276) (xy 364.151729 -267.520021) (xy 364.175647 -267.532295) (xy 364.201944 -267.537886)
			(xy 364.228787 -267.536405) (xy 364.254308 -267.527954) (xy 364.276731 -267.513123) (xy 364.294494 -267.492943)
			(xy 364.30077 -267.48105) (xy 364.310014 -267.462686) (xy 364.330605 -267.427097) (xy 364.341918 -267.40993)
			(xy 364.349075 -267.398519) (xy 364.35771 -267.373014) (xy 364.35938 -267.346138) (xy 364.353967 -267.31976)
			(xy 364.341848 -267.295714) (xy 364.323866 -267.275671) (xy 364.301271 -267.261024) (xy 364.288578 -267.256514)
			(xy 364.263905 -267.248106) (xy 364.217368 -267.224627) (xy 364.175094 -267.194136) (xy 364.138128 -267.157388)
			(xy 364.107389 -267.115293) (xy 364.083637 -267.068895) (xy 364.067462 -267.019345) (xy 364.059264 -266.96787)
			(xy 364.058708 -266.941808) (xy 364.059187 -266.915788) (xy 364.067331 -266.864389) (xy 364.083434 -266.814904)
			(xy 364.107097 -266.768555) (xy 364.137736 -266.726491) (xy 364.174593 -266.689752) (xy 364.216754 -266.659247)
			(xy 364.263177 -266.635731) (xy 364.287816 -266.627356) (xy 364.300499 -266.622863) (xy 364.323087 -266.608259)
			(xy 364.341082 -266.588267) (xy 364.353236 -266.564272) (xy 364.358708 -266.537937) (xy 364.357118 -266.511086)
			(xy 364.348576 -266.48558) (xy 364.34141 -266.474194) (xy 364.330178 -266.457144) (xy 364.309715 -266.421809)
			(xy 364.300516 -266.403582) (xy 364.294237 -266.391678) (xy 364.276511 -266.371438) (xy 364.254105 -266.356545)
			(xy 364.228581 -266.348035) (xy 364.20172 -266.346503) (xy 364.175395 -266.352056) (xy 364.151441 -266.364305)
			(xy 364.141258 -266.373102) (xy 364.122919 -266.389127) (xy 364.082418 -266.416172) (xy 364.03839 -266.436987)
			(xy 363.991785 -266.451122) (xy 363.943612 -266.458271) (xy 363.919262 -266.4587) (xy 363.893293 -266.458188)
			(xy 363.841996 -266.450058) (xy 363.792601 -266.434003) (xy 363.746326 -266.41042) (xy 363.70431 -266.379889)
			(xy 363.667586 -266.343161) (xy 363.63706 -266.301141) (xy 363.613482 -266.254864) (xy 363.597434 -266.205467)
			(xy 363.589309 -266.154169) (xy 363.589309 -266.102231) (xy 363.597434 -266.050933) (xy 363.613482 -266.001536)
			(xy 363.63706 -265.955259) (xy 363.667586 -265.913239) (xy 363.70431 -265.876511) (xy 363.746326 -265.84598)
			(xy 363.792601 -265.822397) (xy 363.841996 -265.806342) (xy 363.893293 -265.798212) (xy 363.919262 -265.797792)
			(xy 363.943648 -265.798225) (xy 363.991892 -265.805387) (xy 364.038559 -265.819562) (xy 364.082637 -265.84044)
			(xy 364.123168 -265.86757) (xy 364.141512 -265.883644) (xy 364.151727 -265.892392) (xy 364.175645 -265.904669)
			(xy 364.201942 -265.910263) (xy 364.228786 -265.908781) (xy 364.254308 -265.900328) (xy 364.276729 -265.885493)
			(xy 364.294488 -265.865309) (xy 364.30077 -265.853418) (xy 364.310007 -265.834989) (xy 364.330598 -265.799272)
			(xy 364.341918 -265.782044) (xy 364.34904 -265.770641) (xy 364.357618 -265.745171) (xy 364.359253 -265.718345)
			(xy 364.353832 -265.692022) (xy 364.341731 -265.668025) (xy 364.323788 -265.648016) (xy 364.301246 -265.633382)
			(xy 364.288578 -265.628882) (xy 364.263916 -265.620466) (xy 364.217402 -265.596976) (xy 364.175153 -265.566476)
			(xy 364.138213 -265.529724) (xy 364.1075 -265.487629) (xy 364.083774 -265.441236) (xy 364.067623 -265.391693)
			(xy 364.059449 -265.34023) (xy 364.058962 -265.314176) (xy 364.059444 -265.288158) (xy 364.067592 -265.236766)
			(xy 364.0837 -265.187287) (xy 364.107367 -265.140946) (xy 364.138009 -265.09889) (xy 364.174868 -265.06216)
			(xy 364.21703 -265.031665) (xy 364.263453 -265.008159) (xy 364.28807 -264.999724) (xy 364.300754 -264.995237)
			(xy 364.323341 -264.980634) (xy 364.341321 -264.96063) (xy 364.353442 -264.93662) (xy 364.35886 -264.910274)
			(xy 364.357196 -264.883429) (xy 364.348568 -264.857955) (xy 364.34141 -264.846562) (xy 364.33017 -264.829386)
			(xy 364.309706 -264.793797) (xy 364.300516 -264.775442) (xy 364.294185 -264.763601) (xy 364.2764 -264.743498)
			(xy 364.25399 -264.728725) (xy 364.228504 -264.720304) (xy 364.201704 -264.718818) (xy 364.175443 -264.724368)
			(xy 364.151536 -264.736572) (xy 364.141258 -264.745216) (xy 364.122919 -264.76124) (xy 364.082417 -264.788284)
			(xy 364.038389 -264.809098) (xy 363.991785 -264.823233) (xy 363.943612 -264.830381) (xy 363.919262 -264.830814)
			(xy 363.893296 -264.830328) (xy 363.842004 -264.822198) (xy 363.792615 -264.806145) (xy 363.746345 -264.782562)
			(xy 363.704335 -264.752032) (xy 363.667617 -264.715306) (xy 363.637097 -264.673288) (xy 363.613526 -264.627013)
			(xy 363.597483 -264.57762) (xy 363.589366 -264.526326) (xy 363.588808 -264.50036) (xy 363.589268 -264.475692)
			(xy 363.596608 -264.426906) (xy 363.611119 -264.379752) (xy 363.632478 -264.33528) (xy 363.660211 -264.294477)
			(xy 363.693701 -264.25825) (xy 363.732205 -264.227404) (xy 363.774867 -264.202624) (xy 363.820737 -264.184462)
			(xy 363.868799 -264.17332) (xy 363.893354 -264.170922) (xy 363.907751 -264.169252) (xy 363.934813 -264.158918)
			(xy 363.957887 -264.141403) (xy 363.975118 -264.118117) (xy 363.985121 -264.09093) (xy 363.987091 -264.062029)
			(xy 363.980871 -264.033736) (xy 363.96696 -264.008326) (xy 363.957108 -263.997694) (xy 363.798612 -263.839452)
			(xy 363.744002 -263.839452) (xy 363.729016 -263.863074) (xy 363.713712 -263.886243) (xy 363.676636 -263.927573)
			(xy 363.633173 -263.962123) (xy 363.584545 -263.98892) (xy 363.532121 -264.00721) (xy 363.477377 -264.016479)
			(xy 363.449616 -264.016998) (xy 363.423642 -264.016516) (xy 363.372335 -264.008392) (xy 363.322929 -263.992342)
			(xy 363.276643 -263.96876) (xy 363.234616 -263.938227) (xy 363.197883 -263.901496) (xy 363.167349 -263.85947)
			(xy 363.143765 -263.813186) (xy 363.127712 -263.763781) (xy 363.119585 -263.712474) (xy 363.119585 -263.660526)
			(xy 363.127712 -263.609219) (xy 363.143765 -263.559814) (xy 363.167349 -263.51353) (xy 363.197883 -263.471504)
			(xy 363.234616 -263.434773) (xy 363.276643 -263.40424) (xy 363.322929 -263.380658) (xy 363.372335 -263.364608)
			(xy 363.423642 -263.356484) (xy 363.449616 -263.35609) (xy 363.47536 -263.356582) (xy 363.526227 -263.364564)
			(xy 363.575241 -263.380333) (xy 363.62122 -263.403508) (xy 363.663051 -263.433529) (xy 363.699724 -263.469669)
			(xy 363.730353 -263.511057) (xy 363.742732 -263.533636) (xy 363.861858 -263.533636) (xy 363.881896 -263.534257)
			(xy 363.92059 -263.544692) (xy 363.955254 -263.564807) (xy 363.969808 -263.578594) (xy 364.16615 -263.774682)
			(xy 364.173572 -263.781378) (xy 364.192035 -263.788986) (xy 364.212004 -263.788978) (xy 364.230461 -263.781355)
			(xy 364.244616 -263.76727) (xy 364.252329 -263.74885) (xy 364.252764 -263.738868) (xy 364.252764 -263.687052)
			(xy 364.233968 -263.671812) (xy 364.213592 -263.654575) (xy 364.178145 -263.614678) (xy 364.14957 -263.569604)
			(xy 364.128611 -263.520523) (xy 364.115813 -263.468711) (xy 364.111508 -263.415516) (xy 364.115808 -263.362321)
			(xy 364.128601 -263.310509) (xy 364.149555 -263.261425) (xy 364.178125 -263.216348) (xy 364.213568 -263.176448)
			(xy 364.233968 -263.15924) (xy 364.252764 -263.144) (xy 364.252764 -263.07288) (xy 364.20933 -263.06653)
			(xy 364.183497 -263.062244) (xy 364.133529 -263.046585) (xy 364.086655 -263.023243) (xy 364.044049 -262.992803)
			(xy 364.006775 -262.956025) (xy 363.975766 -262.913829) (xy 363.951799 -262.867273) (xy 363.935472 -262.817519)
			(xy 363.927195 -262.765814) (xy 363.926628 -262.739632) (xy 363.927188 -262.712333) (xy 363.936162 -262.658479)
			(xy 363.953871 -262.606833) (xy 363.979832 -262.558804) (xy 364.01334 -262.515698) (xy 364.033054 -262.496808)
			(xy 364.043041 -262.486976) (xy 364.057681 -262.463091) (xy 364.06529 -262.436129) (xy 364.065296 -262.408114)
			(xy 364.057699 -262.381149) (xy 364.043069 -262.357257) (xy 364.033054 -262.347456) (xy 364.013364 -262.328543)
			(xy 363.979856 -262.285444) (xy 363.953894 -262.23742) (xy 363.936187 -262.185779) (xy 363.927217 -262.131928)
			(xy 363.926628 -262.104632) (xy 363.927137 -262.078665) (xy 363.935262 -262.02737) (xy 363.95131 -261.977977)
			(xy 363.974888 -261.931703) (xy 364.005414 -261.889687) (xy 364.042137 -261.852964) (xy 364.084153 -261.822438)
			(xy 364.130427 -261.79886) (xy 364.17982 -261.782812) (xy 364.231115 -261.774687) (xy 364.283049 -261.774687)
			(xy 364.334344 -261.782812) (xy 364.383737 -261.79886) (xy 364.430011 -261.822438) (xy 364.472027 -261.852964)
			(xy 364.50875 -261.889687) (xy 364.539276 -261.931703) (xy 364.562854 -261.977977) (xy 364.578902 -262.02737)
			(xy 364.587027 -262.078665) (xy 364.587536 -262.104632) (xy 364.587159 -262.127879) (xy 364.580675 -262.173919)
			(xy 364.567797 -262.218594) (xy 364.548781 -262.261021) (xy 364.536736 -262.280908) (xy 364.514892 -262.315198)
			(xy 364.579662 -262.379714) (xy 364.730792 -262.228584) (xy 366.19434 -262.228584) (xy 367.218976 -261.203948)
			(xy 367.222786 -261.196074) (xy 367.235437 -261.170785) (xy 367.268032 -261.124585) (xy 367.308016 -261.084607)
			(xy 367.35422 -261.052017) (xy 367.379504 -261.039356) (xy 367.387378 -261.035546) (xy 368.334036 -260.088888)
			(xy 368.67084 -260.088888) (xy 368.728752 -260.030976) (xy 368.691922 -259.9944) (xy 368.69116 -259.993638)
			(xy 368.671186 -259.974704) (xy 368.637202 -259.931418) (xy 368.61086 -259.883098) (xy 368.59289 -259.831082)
			(xy 368.583789 -259.776807) (xy 368.58321 -259.74929) (xy 368.583671 -259.723959) (xy 368.591406 -259.673892)
			(xy 368.606693 -259.625592) (xy 368.629175 -259.580191) (xy 368.658323 -259.538755) (xy 368.693455 -259.502254)
			(xy 368.733747 -259.471544) (xy 368.778256 -259.447344) (xy 368.825936 -259.430222) (xy 368.875672 -259.42058)
			(xy 368.900964 -259.41909) (xy 368.916534 -259.417916) (xy 368.945898 -259.407344) (xy 368.970702 -259.388402)
			(xy 368.988633 -259.362859) (xy 368.998019 -259.333095) (xy 368.9985 -259.31749) (xy 368.9985 -258.882896)
			(xy 368.997956 -258.867365) (xy 368.98863 -258.837737) (xy 368.970813 -258.812294) (xy 368.946162 -258.793398)
			(xy 368.916963 -258.782803) (xy 368.901472 -258.78155) (xy 368.876279 -258.779949) (xy 368.826778 -258.77006)
			(xy 368.779357 -258.752759) (xy 368.735116 -258.728451) (xy 368.695086 -258.697699) (xy 368.660196 -258.661219)
			(xy 368.631258 -258.619858) (xy 368.608944 -258.574579) (xy 368.593774 -258.526434) (xy 368.586099 -258.476542)
			(xy 368.586099 -258.426063) (xy 368.593773 -258.376171) (xy 368.608942 -258.328025) (xy 368.631256 -258.282746)
			(xy 368.660193 -258.241385) (xy 368.695083 -258.204904) (xy 368.735113 -258.174152) (xy 368.779353 -258.149842)
			(xy 368.826774 -258.132542) (xy 368.876274 -258.122652) (xy 368.901472 -258.12115) (xy 368.916953 -258.119888)
			(xy 368.946113 -258.109234) (xy 368.970739 -258.090331) (xy 368.988568 -258.064915) (xy 368.997961 -258.035325)
			(xy 368.9985 -258.019804) (xy 368.9985 -257.714496) (xy 368.997956 -257.698965) (xy 368.98863 -257.669337)
			(xy 368.970813 -257.643894) (xy 368.946162 -257.624998) (xy 368.916963 -257.614403) (xy 368.901472 -257.61315)
			(xy 368.876282 -257.611555) (xy 368.826786 -257.601677) (xy 368.779369 -257.584385) (xy 368.735133 -257.560083)
			(xy 368.695109 -257.529334) (xy 368.660227 -257.492856) (xy 368.6313 -257.451496) (xy 368.609 -257.406218)
			(xy 368.593847 -257.358074) (xy 368.586192 -257.308186) (xy 368.58575 -257.28295) (xy 368.586263 -257.256548)
			(xy 368.59465 -257.204414) (xy 368.611218 -257.154277) (xy 368.635546 -257.107412) (xy 368.667016 -257.06501)
			(xy 368.685572 -257.046222) (xy 368.694912 -257.036527) (xy 368.708583 -257.013347) (xy 368.715712 -256.987398)
			(xy 368.715803 -256.960487) (xy 368.70885 -256.93449) (xy 368.695337 -256.911218) (xy 368.68608 -256.901442)
			(xy 368.667878 -256.882708) (xy 368.637026 -256.840564) (xy 368.61319 -256.794089) (xy 368.596964 -256.744443)
			(xy 368.588754 -256.692861) (xy 368.58829 -256.666746) (xy 368.588756 -256.64162) (xy 368.596361 -256.591946)
			(xy 368.611403 -256.543998) (xy 368.633534 -256.498881) (xy 368.662243 -256.457637) (xy 368.696869 -256.421218)
			(xy 368.736612 -256.390464) (xy 368.780555 -256.366085) (xy 368.827683 -256.348643) (xy 368.87691 -256.338542)
			(xy 368.90198 -256.3368) (xy 368.917439 -256.335489) (xy 368.946529 -256.324745) (xy 368.971054 -256.305767)
			(xy 368.988755 -256.280306) (xy 368.998002 -256.250706) (xy 368.9985 -256.2352) (xy 368.9985 -255.961896)
			(xy 368.997956 -255.946365) (xy 368.98863 -255.916737) (xy 368.970813 -255.891294) (xy 368.946162 -255.872398)
			(xy 368.916963 -255.861803) (xy 368.901472 -255.86055) (xy 368.876282 -255.858955) (xy 368.826786 -255.849077)
			(xy 368.779369 -255.831785) (xy 368.735133 -255.807483) (xy 368.695109 -255.776734) (xy 368.660227 -255.740256)
			(xy 368.6313 -255.698896) (xy 368.609 -255.653618) (xy 368.593847 -255.605474) (xy 368.586192 -255.555586)
			(xy 368.58575 -255.53035) (xy 368.586181 -255.505798) (xy 368.593415 -255.457229) (xy 368.607761 -255.410267)
			(xy 368.628903 -255.365947) (xy 368.656373 -255.325246) (xy 368.672618 -255.30683) (xy 368.682426 -255.295339)
			(xy 368.695448 -255.268097) (xy 368.699927 -255.238237) (xy 368.69547 -255.208373) (xy 368.682467 -255.181122)
			(xy 368.672618 -255.16967) (xy 368.656362 -255.151265) (xy 368.628909 -255.110554) (xy 368.607778 -255.06623)
			(xy 368.593435 -255.019268) (xy 368.586195 -254.970702) (xy 368.58575 -254.94615) (xy 368.58623 -254.92092)
			(xy 368.593907 -254.871048) (xy 368.609074 -254.822922) (xy 368.63138 -254.77766) (xy 368.660306 -254.736314)
			(xy 368.69518 -254.699844) (xy 368.735191 -254.669099) (xy 368.779411 -254.644792) (xy 368.826811 -254.627489)
			(xy 368.87629 -254.61759) (xy 368.901472 -254.61595) (xy 368.916953 -254.614688) (xy 368.946113 -254.604034)
			(xy 368.970739 -254.585131) (xy 368.988568 -254.559715) (xy 368.997961 -254.530125) (xy 368.9985 -254.514604)
			(xy 368.9985 -253.625096) (xy 368.997956 -253.609565) (xy 368.98863 -253.579937) (xy 368.970813 -253.554494)
			(xy 368.946162 -253.535598) (xy 368.916963 -253.525003) (xy 368.901472 -253.52375) (xy 368.876282 -253.522155)
			(xy 368.826786 -253.512277) (xy 368.779369 -253.494985) (xy 368.735133 -253.470683) (xy 368.695109 -253.439934)
			(xy 368.660227 -253.403456) (xy 368.6313 -253.362096) (xy 368.609 -253.316818) (xy 368.593847 -253.268674)
			(xy 368.586192 -253.218786) (xy 368.58575 -253.19355) (xy 368.586181 -253.168998) (xy 368.593415 -253.120429)
			(xy 368.607761 -253.073467) (xy 368.628903 -253.029147) (xy 368.656373 -252.988446) (xy 368.672618 -252.97003)
			(xy 368.682426 -252.958539) (xy 368.695448 -252.931297) (xy 368.699927 -252.901437) (xy 368.69547 -252.871573)
			(xy 368.682467 -252.844322) (xy 368.672618 -252.83287) (xy 368.656362 -252.814465) (xy 368.628909 -252.773754)
			(xy 368.607778 -252.72943) (xy 368.593435 -252.682468) (xy 368.586195 -252.633902) (xy 368.58575 -252.60935)
			(xy 368.58623 -252.58412) (xy 368.593907 -252.534248) (xy 368.609074 -252.486122) (xy 368.63138 -252.44086)
			(xy 368.660306 -252.399514) (xy 368.69518 -252.363044) (xy 368.735191 -252.332299) (xy 368.779411 -252.307992)
			(xy 368.826811 -252.290689) (xy 368.87629 -252.28079) (xy 368.901472 -252.27915) (xy 368.916953 -252.277888)
			(xy 368.946113 -252.267234) (xy 368.970739 -252.248331) (xy 368.988568 -252.222915) (xy 368.997961 -252.193325)
			(xy 368.9985 -252.177804) (xy 368.9985 -251.872496) (xy 368.997956 -251.856965) (xy 368.98863 -251.827337)
			(xy 368.970813 -251.801894) (xy 368.946162 -251.782998) (xy 368.916963 -251.772403) (xy 368.901472 -251.77115)
			(xy 368.876282 -251.769555) (xy 368.826786 -251.759677) (xy 368.779369 -251.742385) (xy 368.735133 -251.718083)
			(xy 368.695109 -251.687334) (xy 368.660227 -251.650856) (xy 368.6313 -251.609496) (xy 368.609 -251.564218)
			(xy 368.593847 -251.516074) (xy 368.586192 -251.466186) (xy 368.58575 -251.44095) (xy 368.586181 -251.416398)
			(xy 368.593415 -251.367829) (xy 368.607761 -251.320867) (xy 368.628903 -251.276547) (xy 368.656373 -251.235846)
			(xy 368.672618 -251.21743) (xy 368.682426 -251.205939) (xy 368.695448 -251.178697) (xy 368.699927 -251.148837)
			(xy 368.69547 -251.118973) (xy 368.682467 -251.091722) (xy 368.672618 -251.08027) (xy 368.656362 -251.061865)
			(xy 368.628909 -251.021154) (xy 368.607778 -250.97683) (xy 368.593435 -250.929868) (xy 368.586195 -250.881302)
			(xy 368.58575 -250.85675) (xy 368.58623 -250.83152) (xy 368.593907 -250.781648) (xy 368.609074 -250.733522)
			(xy 368.63138 -250.68826) (xy 368.660306 -250.646914) (xy 368.69518 -250.610444) (xy 368.735191 -250.579699)
			(xy 368.779411 -250.555392) (xy 368.826811 -250.538089) (xy 368.87629 -250.52819) (xy 368.901472 -250.52655)
			(xy 368.916953 -250.525288) (xy 368.946113 -250.514634) (xy 368.970739 -250.495731) (xy 368.988568 -250.470315)
			(xy 368.997961 -250.440725) (xy 368.9985 -250.425204) (xy 368.9985 -249.537728) (xy 368.997924 -249.522504)
			(xy 368.98894 -249.493412) (xy 368.971789 -249.468253) (xy 368.947991 -249.449259) (xy 368.919657 -249.438112)
			(xy 368.90452 -249.436382) (xy 368.879883 -249.434089) (xy 368.831639 -249.423113) (xy 368.785569 -249.405069)
			(xy 368.742703 -249.38036) (xy 368.703998 -249.349538) (xy 368.67032 -249.313293) (xy 368.642419 -249.272433)
			(xy 368.620919 -249.22787) (xy 368.606301 -249.180602) (xy 368.598891 -249.131682) (xy 368.59845 -249.106944)
			(xy 368.59893 -249.080973) (xy 368.607049 -249.029668) (xy 368.623095 -248.980266) (xy 368.646673 -248.933983)
			(xy 368.677201 -248.891958) (xy 368.713927 -248.855227) (xy 368.755949 -248.824693) (xy 368.802229 -248.80111)
			(xy 368.851629 -248.785058) (xy 368.902933 -248.776933) (xy 368.928904 -248.77649) (xy 368.94516 -248.776998)
			(xy 368.955512 -248.777031) (xy 368.9749 -248.769829) (xy 368.989872 -248.75556) (xy 368.997997 -248.73654)
			(xy 368.9985 -248.726198) (xy 368.9985 -248.654316) (xy 368.94389 -248.654316) (xy 368.940334 -248.654824)
			(xy 368.928464 -248.656464) (xy 368.904564 -248.658242) (xy 368.892582 -248.65838) (xy 368.866614 -248.657869)
			(xy 368.815317 -248.649742) (xy 368.765923 -248.633691) (xy 368.719648 -248.61011) (xy 368.677631 -248.579581)
			(xy 368.640907 -248.542855) (xy 368.61038 -248.500837) (xy 368.586802 -248.454561) (xy 368.570754 -248.405166)
			(xy 368.562629 -248.353868) (xy 368.562629 -248.301932) (xy 368.570754 -248.250634) (xy 368.586802 -248.201239)
			(xy 368.61038 -248.154963) (xy 368.640907 -248.112945) (xy 368.677631 -248.076219) (xy 368.719648 -248.04569)
			(xy 368.765923 -248.022109) (xy 368.815317 -248.006058) (xy 368.866614 -247.997931) (xy 368.892582 -247.997472)
			(xy 368.895884 -247.997472) (xy 368.909295 -247.997199) (xy 368.935253 -247.990474) (xy 368.958563 -247.977219)
			(xy 368.977616 -247.958351) (xy 368.991096 -247.935171) (xy 368.998074 -247.90928) (xy 368.9985 -247.895872)
			(xy 368.9985 -247.783096) (xy 368.997956 -247.767565) (xy 368.98863 -247.737937) (xy 368.970813 -247.712494)
			(xy 368.946162 -247.693598) (xy 368.916963 -247.683003) (xy 368.901472 -247.68175) (xy 368.876282 -247.680155)
			(xy 368.826786 -247.670277) (xy 368.779369 -247.652985) (xy 368.735133 -247.628683) (xy 368.695109 -247.597934)
			(xy 368.660227 -247.561456) (xy 368.6313 -247.520096) (xy 368.609 -247.474818) (xy 368.593847 -247.426674)
			(xy 368.586192 -247.376786) (xy 368.58575 -247.35155) (xy 368.586181 -247.326998) (xy 368.593415 -247.278429)
			(xy 368.607761 -247.231467) (xy 368.628903 -247.187147) (xy 368.656373 -247.146446) (xy 368.672618 -247.12803)
			(xy 368.682426 -247.116539) (xy 368.695448 -247.089297) (xy 368.699927 -247.059437) (xy 368.69547 -247.029573)
			(xy 368.682467 -247.002322) (xy 368.672618 -246.99087) (xy 368.664899 -246.982299) (xy 368.650535 -246.964249)
			(xy 368.643916 -246.954802) (xy 368.635996 -246.943945) (xy 368.615571 -246.926495) (xy 368.591299 -246.914982)
			(xy 368.564862 -246.910205) (xy 368.538096 -246.912495) (xy 368.512855 -246.921694) (xy 368.501676 -246.929148)
			(xy 368.480685 -246.943391) (xy 368.435256 -246.965957) (xy 368.386914 -246.981319) (xy 368.336792 -246.989117)
			(xy 368.31143 -246.9896) (xy 368.286876 -246.989175) (xy 368.238302 -246.98195) (xy 368.191334 -246.967611)
			(xy 368.147008 -246.946475) (xy 368.106301 -246.919006) (xy 368.08791 -246.902732) (xy 368.076421 -246.892929)
			(xy 368.049184 -246.879915) (xy 368.01933 -246.875447) (xy 367.989476 -246.879915) (xy 367.962239 -246.892929)
			(xy 367.95075 -246.902732) (xy 367.932346 -246.918989) (xy 367.891635 -246.946444) (xy 367.847311 -246.967575)
			(xy 367.800349 -246.981917) (xy 367.751782 -246.989156) (xy 367.72723 -246.9896) (xy 367.702676 -246.989175)
			(xy 367.654102 -246.98195) (xy 367.607134 -246.967611) (xy 367.562808 -246.946475) (xy 367.522101 -246.919006)
			(xy 367.50371 -246.902732) (xy 367.492221 -246.892929) (xy 367.464984 -246.879915) (xy 367.43513 -246.875447)
			(xy 367.405276 -246.879915) (xy 367.378039 -246.892929) (xy 367.36655 -246.902732) (xy 367.348146 -246.918989)
			(xy 367.307435 -246.946444) (xy 367.263111 -246.967575) (xy 367.216149 -246.981917) (xy 367.167582 -246.989156)
			(xy 367.14303 -246.9896) (xy 367.117056 -246.989119) (xy 367.065746 -246.980997) (xy 367.016338 -246.964947)
			(xy 366.97005 -246.941366) (xy 366.928021 -246.910834) (xy 366.891286 -246.874102) (xy 366.86075 -246.832076)
			(xy 366.837164 -246.78579) (xy 366.82111 -246.736384) (xy 366.812983 -246.685074) (xy 366.812983 -246.633126)
			(xy 366.82111 -246.581816) (xy 366.837164 -246.53241) (xy 366.86075 -246.486124) (xy 366.891286 -246.444098)
			(xy 366.928021 -246.407366) (xy 366.97005 -246.376834) (xy 367.016338 -246.353253) (xy 367.065746 -246.337203)
			(xy 367.117056 -246.329081) (xy 367.14303 -246.328692) (xy 367.167583 -246.329122) (xy 367.216152 -246.336354)
			(xy 367.263115 -246.350699) (xy 367.307435 -246.371841) (xy 367.348136 -246.399313) (xy 367.36655 -246.41556)
			(xy 367.378039 -246.425363) (xy 367.405276 -246.438377) (xy 367.43513 -246.442845) (xy 367.464984 -246.438377)
			(xy 367.492221 -246.425363) (xy 367.50371 -246.41556) (xy 367.522113 -246.399301) (xy 367.562823 -246.371842)
			(xy 367.607147 -246.350706) (xy 367.654109 -246.336358) (xy 367.702677 -246.329114) (xy 367.72723 -246.328692)
			(xy 367.751783 -246.329122) (xy 367.800352 -246.336354) (xy 367.847315 -246.350699) (xy 367.891635 -246.371841)
			(xy 367.932336 -246.399313) (xy 367.95075 -246.41556) (xy 367.962239 -246.425363) (xy 367.989476 -246.438377)
			(xy 368.01933 -246.442845) (xy 368.049184 -246.438377) (xy 368.076421 -246.425363) (xy 368.08791 -246.41556)
			(xy 368.106313 -246.399301) (xy 368.147023 -246.371842) (xy 368.191347 -246.350706) (xy 368.238309 -246.336358)
			(xy 368.286877 -246.329114) (xy 368.31143 -246.328692) (xy 368.338102 -246.329203) (xy 368.390753 -246.33777)
			(xy 368.441347 -246.354676) (xy 368.488572 -246.379484) (xy 368.531202 -246.41155) (xy 368.568133 -246.450042)
			(xy 368.583718 -246.471694) (xy 368.591638 -246.482547) (xy 368.612062 -246.49999) (xy 368.636331 -246.511496)
			(xy 368.662763 -246.516266) (xy 368.689524 -246.513969) (xy 368.714756 -246.504766) (xy 368.725958 -246.497348)
			(xy 368.745405 -246.484111) (xy 368.787284 -246.462686) (xy 368.831781 -246.447423) (xy 368.877994 -246.438631)
			(xy 368.901472 -246.43715) (xy 368.916953 -246.435888) (xy 368.946113 -246.425234) (xy 368.970739 -246.406331)
			(xy 368.988568 -246.380915) (xy 368.997961 -246.351325) (xy 368.9985 -246.335804) (xy 368.9985 -246.030496)
			(xy 368.997956 -246.014965) (xy 368.98863 -245.985337) (xy 368.970813 -245.959894) (xy 368.946162 -245.940998)
			(xy 368.916963 -245.930403) (xy 368.901472 -245.92915) (xy 368.876282 -245.927555) (xy 368.826786 -245.917677)
			(xy 368.779369 -245.900385) (xy 368.735133 -245.876083) (xy 368.695109 -245.845334) (xy 368.660227 -245.808856)
			(xy 368.6313 -245.767496) (xy 368.609 -245.722218) (xy 368.593847 -245.674074) (xy 368.586192 -245.624186)
			(xy 368.58575 -245.59895) (xy 368.586181 -245.574398) (xy 368.593415 -245.525829) (xy 368.607761 -245.478867)
			(xy 368.628903 -245.434547) (xy 368.656373 -245.393846) (xy 368.672618 -245.37543) (xy 368.682426 -245.363939)
			(xy 368.695448 -245.336697) (xy 368.699927 -245.306837) (xy 368.69547 -245.276973) (xy 368.682467 -245.249722)
			(xy 368.672618 -245.23827) (xy 368.656362 -245.219865) (xy 368.628909 -245.179154) (xy 368.607778 -245.13483)
			(xy 368.593435 -245.087868) (xy 368.586195 -245.039302) (xy 368.58575 -245.01475) (xy 368.586181 -244.990198)
			(xy 368.593415 -244.941629) (xy 368.607761 -244.894667) (xy 368.628903 -244.850347) (xy 368.656373 -244.809646)
			(xy 368.672618 -244.79123) (xy 368.682426 -244.779739) (xy 368.695448 -244.752497) (xy 368.699927 -244.722637)
			(xy 368.69547 -244.692773) (xy 368.682467 -244.665522) (xy 368.672618 -244.65407) (xy 368.656362 -244.635665)
			(xy 368.628909 -244.594954) (xy 368.607778 -244.55063) (xy 368.593435 -244.503668) (xy 368.586195 -244.455102)
			(xy 368.58575 -244.43055) (xy 368.586181 -244.405998) (xy 368.593415 -244.357429) (xy 368.607761 -244.310467)
			(xy 368.628903 -244.266147) (xy 368.656373 -244.225446) (xy 368.672618 -244.20703) (xy 368.682426 -244.195539)
			(xy 368.695448 -244.168297) (xy 368.699927 -244.138437) (xy 368.69547 -244.108573) (xy 368.682467 -244.081322)
			(xy 368.672618 -244.06987) (xy 368.656362 -244.051465) (xy 368.628909 -244.010754) (xy 368.607778 -243.96643)
			(xy 368.593435 -243.919468) (xy 368.586195 -243.870902) (xy 368.58575 -243.84635) (xy 368.58623 -243.82112)
			(xy 368.593907 -243.771248) (xy 368.609074 -243.723122) (xy 368.63138 -243.67786) (xy 368.660306 -243.636514)
			(xy 368.69518 -243.600044) (xy 368.735191 -243.569299) (xy 368.779411 -243.544992) (xy 368.826811 -243.527689)
			(xy 368.87629 -243.51779) (xy 368.901472 -243.51615) (xy 368.916953 -243.514888) (xy 368.946113 -243.504234)
			(xy 368.970739 -243.485331) (xy 368.988568 -243.459915) (xy 368.997961 -243.430325) (xy 368.9985 -243.414804)
			(xy 368.9985 -241.13617) (xy 368.998081 -241.122701) (xy 368.991027 -241.096704) (xy 368.977418 -241.073457)
			(xy 368.958201 -241.054579) (xy 368.934716 -241.041386) (xy 368.908597 -241.034795) (xy 368.895122 -241.03457)
			(xy 368.889534 -241.03457) (xy 368.863563 -241.03409) (xy 368.812258 -241.025969) (xy 368.762856 -241.009922)
			(xy 368.716573 -240.986345) (xy 368.674548 -240.955817) (xy 368.637816 -240.919091) (xy 368.607281 -240.87707)
			(xy 368.583697 -240.83079) (xy 368.567643 -240.78139) (xy 368.559514 -240.730087) (xy 368.55908 -240.704116)
			(xy 368.559506 -240.679562) (xy 368.566732 -240.630989) (xy 368.581072 -240.584022) (xy 368.602209 -240.539696)
			(xy 368.629677 -240.49899) (xy 368.645948 -240.480596) (xy 368.655756 -240.469108) (xy 368.668778 -240.44187)
			(xy 368.673252 -240.412012) (xy 368.668785 -240.382153) (xy 368.655769 -240.354912) (xy 368.645948 -240.343436)
			(xy 368.629693 -240.325031) (xy 368.602241 -240.28432) (xy 368.581113 -240.239995) (xy 368.566774 -240.193034)
			(xy 368.559538 -240.144467) (xy 368.55908 -240.119916) (xy 368.559562 -240.093947) (xy 368.567685 -240.042648)
			(xy 368.583734 -239.993251) (xy 368.607313 -239.946974) (xy 368.637842 -239.904955) (xy 368.674569 -239.86823)
			(xy 368.716589 -239.837704) (xy 368.762868 -239.814127) (xy 368.812265 -239.798081) (xy 368.863565 -239.78996)
			(xy 368.889534 -239.789462) (xy 368.895122 -239.789462) (xy 368.908599 -239.789282) (xy 368.934722 -239.782688)
			(xy 368.95821 -239.769486) (xy 368.977424 -239.750598) (xy 368.991026 -239.727341) (xy 368.998067 -239.701334)
			(xy 368.9985 -239.687862) (xy 368.9985 -239.093248) (xy 368.654584 -238.749332) (xy 363.483906 -238.749332)
			(xy 363.477556 -238.792766) (xy 363.473208 -238.818568) (xy 363.457443 -238.868458) (xy 363.43402 -238.915244)
			(xy 363.403523 -238.957759) (xy 363.366713 -238.994943) (xy 363.324509 -239.025867) (xy 363.277962 -239.049762)
			(xy 363.228234 -239.066031) (xy 363.176565 -239.074268) (xy 363.124243 -239.074268) (xy 363.072574 -239.066031)
			(xy 363.022846 -239.049762) (xy 362.976299 -239.025867) (xy 362.934095 -238.994943) (xy 362.897285 -238.957759)
			(xy 362.866788 -238.915244) (xy 362.843365 -238.868458) (xy 362.8276 -238.818568) (xy 362.823252 -238.792766)
			(xy 362.816902 -238.749332) (xy 361.848654 -238.749332) (xy 361.833952 -238.749814) (xy 361.805763 -238.758175)
			(xy 361.781124 -238.77422) (xy 361.762076 -238.796618) (xy 361.750198 -238.823515) (xy 361.746474 -238.852681)
			(xy 361.751213 -238.8817) (xy 361.757214 -238.895128) (xy 361.767659 -238.917727) (xy 361.782391 -238.965281)
			(xy 361.789819 -239.014508) (xy 361.790234 -239.0394) (xy 361.789725 -239.065367) (xy 361.7816 -239.116662)
			(xy 361.765552 -239.166055) (xy 361.741974 -239.212329) (xy 361.711448 -239.254345) (xy 361.674725 -239.291068)
			(xy 361.632709 -239.321594) (xy 361.611554 -239.332373) (xy 365.024083 -239.332373) (xy 365.024083 -239.280427)
			(xy 365.032209 -239.22912) (xy 365.048262 -239.179716) (xy 365.071846 -239.133431) (xy 365.102379 -239.091406)
			(xy 365.139112 -239.054674) (xy 365.181138 -239.024141) (xy 365.227423 -239.000559) (xy 365.276827 -238.984508)
			(xy 365.328135 -238.976382) (xy 365.354108 -238.9759) (xy 365.378659 -238.976358) (xy 365.427226 -238.983593)
			(xy 365.474188 -238.997932) (xy 365.518512 -239.01906) (xy 365.559224 -239.046512) (xy 365.577628 -239.062768)
			(xy 365.589117 -239.072571) (xy 365.616354 -239.085585) (xy 365.646208 -239.090053) (xy 365.676062 -239.085585)
			(xy 365.703299 -239.072571) (xy 365.714788 -239.062768) (xy 365.733188 -239.046504) (xy 365.773892 -239.019034)
			(xy 365.818216 -238.997895) (xy 365.865182 -238.983554) (xy 365.913754 -238.976327) (xy 365.938308 -238.9759)
			(xy 365.962859 -238.976358) (xy 366.011426 -238.983593) (xy 366.058388 -238.997932) (xy 366.102712 -239.01906)
			(xy 366.143424 -239.046512) (xy 366.161828 -239.062768) (xy 366.173317 -239.072571) (xy 366.200554 -239.085585)
			(xy 366.230408 -239.090053) (xy 366.260262 -239.085585) (xy 366.287499 -239.072571) (xy 366.298988 -239.062768)
			(xy 366.317388 -239.046504) (xy 366.358092 -239.019034) (xy 366.402416 -238.997895) (xy 366.449382 -238.983554)
			(xy 366.497954 -238.976327) (xy 366.522508 -238.9759) (xy 366.548871 -238.976435) (xy 366.600927 -238.984813)
			(xy 366.650996 -239.001341) (xy 366.69781 -239.0256) (xy 366.740185 -239.056977) (xy 366.758982 -239.075468)
			(xy 366.768533 -239.084596) (xy 366.791212 -239.098123) (xy 366.816599 -239.105389) (xy 366.843 -239.105911)
			(xy 366.868654 -239.099651) (xy 366.891849 -239.08703) (xy 366.90173 -239.078262) (xy 366.92028 -239.061264)
			(xy 366.961541 -239.032475) (xy 367.00669 -239.010278) (xy 367.054684 -238.995187) (xy 367.104413 -238.987551)
			(xy 367.129568 -238.987076) (xy 367.154121 -238.987504) (xy 367.202688 -238.994747) (xy 367.24965 -239.009094)
			(xy 367.293974 -239.030228) (xy 367.334684 -239.057686) (xy 367.353088 -239.073944) (xy 367.364577 -239.083747)
			(xy 367.391814 -239.096761) (xy 367.421668 -239.101229) (xy 367.451522 -239.096761) (xy 367.478759 -239.083747)
			(xy 367.490248 -239.073944) (xy 367.50866 -239.057695) (xy 367.549362 -239.030224) (xy 367.593683 -239.009083)
			(xy 367.640646 -238.994738) (xy 367.689215 -238.987506) (xy 367.713768 -238.987076) (xy 367.738321 -238.987504)
			(xy 367.786888 -238.994747) (xy 367.83385 -239.009094) (xy 367.878174 -239.030228) (xy 367.918884 -239.057686)
			(xy 367.937288 -239.073944) (xy 367.948777 -239.083747) (xy 367.976014 -239.096761) (xy 368.005868 -239.101229)
			(xy 368.035722 -239.096761) (xy 368.062959 -239.083747) (xy 368.074448 -239.073944) (xy 368.09286 -239.057695)
			(xy 368.133562 -239.030224) (xy 368.177883 -239.009083) (xy 368.224846 -238.994738) (xy 368.273415 -238.987506)
			(xy 368.297968 -238.987076) (xy 368.323941 -238.987497) (xy 368.375249 -238.995618) (xy 368.424654 -239.011667)
			(xy 368.47094 -239.035247) (xy 368.512968 -239.065778) (xy 368.549701 -239.102508) (xy 368.580236 -239.144532)
			(xy 368.603821 -239.190816) (xy 368.619874 -239.24022) (xy 368.628001 -239.291527) (xy 368.628001 -239.343473)
			(xy 368.619874 -239.39478) (xy 368.603821 -239.444184) (xy 368.580236 -239.490468) (xy 368.549701 -239.532492)
			(xy 368.512968 -239.569222) (xy 368.47094 -239.599753) (xy 368.424654 -239.623333) (xy 368.375249 -239.639382)
			(xy 368.323941 -239.647503) (xy 368.297968 -239.647984) (xy 368.273416 -239.647545) (xy 368.224848 -239.640306)
			(xy 368.177886 -239.625963) (xy 368.133562 -239.60483) (xy 368.092851 -239.577374) (xy 368.074448 -239.561116)
			(xy 368.062959 -239.551313) (xy 368.035722 -239.538299) (xy 368.005868 -239.533831) (xy 367.976014 -239.538299)
			(xy 367.948777 -239.551313) (xy 367.937288 -239.561116) (xy 367.91891 -239.577405) (xy 367.878198 -239.604868)
			(xy 367.833868 -239.626001) (xy 367.786898 -239.640336) (xy 367.738323 -239.647559) (xy 367.713768 -239.647984)
			(xy 367.689216 -239.647545) (xy 367.640648 -239.640306) (xy 367.593686 -239.625963) (xy 367.549362 -239.60483)
			(xy 367.508651 -239.577374) (xy 367.490248 -239.561116) (xy 367.478759 -239.551313) (xy 367.451522 -239.538299)
			(xy 367.421668 -239.533831) (xy 367.391814 -239.538299) (xy 367.364577 -239.551313) (xy 367.353088 -239.561116)
			(xy 367.33471 -239.577405) (xy 367.293998 -239.604868) (xy 367.249668 -239.626001) (xy 367.202698 -239.640336)
			(xy 367.154123 -239.647559) (xy 367.129568 -239.647984) (xy 367.103204 -239.647469) (xy 367.051147 -239.639086)
			(xy 367.001078 -239.622554) (xy 366.954264 -239.59829) (xy 366.911891 -239.56691) (xy 366.893094 -239.548416)
			(xy 366.883564 -239.539265) (xy 366.860879 -239.525742) (xy 366.835487 -239.518479) (xy 366.809081 -239.517963)
			(xy 366.783424 -239.524226) (xy 366.760227 -239.536852) (xy 366.750346 -239.545622) (xy 366.731818 -239.562645)
			(xy 366.69055 -239.591428) (xy 366.645395 -239.613618) (xy 366.597396 -239.628704) (xy 366.547665 -239.636335)
			(xy 366.522508 -239.636808) (xy 366.497955 -239.636399) (xy 366.449386 -239.629152) (xy 366.402424 -239.614801)
			(xy 366.3581 -239.593662) (xy 366.317391 -239.5662) (xy 366.298988 -239.54994) (xy 366.287499 -239.540137)
			(xy 366.260262 -239.527123) (xy 366.230408 -239.522655) (xy 366.200554 -239.527123) (xy 366.173317 -239.540137)
			(xy 366.161828 -239.54994) (xy 366.143423 -239.566198) (xy 366.10272 -239.593668) (xy 366.058397 -239.614808)
			(xy 366.011432 -239.629151) (xy 365.962861 -239.63638) (xy 365.938308 -239.636808) (xy 365.913755 -239.636399)
			(xy 365.865186 -239.629152) (xy 365.818224 -239.614801) (xy 365.7739 -239.593662) (xy 365.733191 -239.5662)
			(xy 365.714788 -239.54994) (xy 365.703299 -239.540137) (xy 365.676062 -239.527123) (xy 365.646208 -239.522655)
			(xy 365.616354 -239.527123) (xy 365.589117 -239.540137) (xy 365.577628 -239.54994) (xy 365.559223 -239.566198)
			(xy 365.51852 -239.593668) (xy 365.474197 -239.614808) (xy 365.427232 -239.629151) (xy 365.378661 -239.63638)
			(xy 365.354108 -239.636808) (xy 365.328135 -239.636418) (xy 365.276827 -239.628292) (xy 365.227423 -239.612241)
			(xy 365.181138 -239.588659) (xy 365.139112 -239.558126) (xy 365.102379 -239.521394) (xy 365.071846 -239.479369)
			(xy 365.048262 -239.433084) (xy 365.032209 -239.38368) (xy 365.024083 -239.332373) (xy 361.611554 -239.332373)
			(xy 361.586435 -239.345172) (xy 361.537042 -239.36122) (xy 361.485747 -239.369345) (xy 361.433813 -239.369345)
			(xy 361.382518 -239.36122) (xy 361.333125 -239.345172) (xy 361.286851 -239.321594) (xy 361.244835 -239.291068)
			(xy 361.208112 -239.254345) (xy 361.177586 -239.212329) (xy 361.154008 -239.166055) (xy 361.13796 -239.116662)
			(xy 361.129835 -239.065367) (xy 361.129326 -239.0394) (xy 361.129761 -239.014509) (xy 361.137193 -238.965287)
			(xy 361.15192 -238.917734) (xy 361.162346 -238.895128) (xy 361.168305 -238.881684) (xy 361.173038 -238.852674)
			(xy 361.169315 -238.823517) (xy 361.157443 -238.796627) (xy 361.138406 -238.77423) (xy 361.11378 -238.758182)
			(xy 361.085603 -238.74981) (xy 361.070906 -238.749332) (xy 350.818704 -238.749332) (xy 350.503744 -239.064292)
			(xy 350.503744 -239.166908) (xy 350.5835 -239.166908) (xy 350.598232 -239.142016) (xy 350.611051 -239.121063)
			(xy 350.641911 -239.08285) (xy 350.67809 -239.049629) (xy 350.71879 -239.022131) (xy 350.763113 -239.000964)
			(xy 350.810082 -238.986594) (xy 350.858661 -238.979338) (xy 350.88322 -238.978948) (xy 350.907773 -238.979377)
			(xy 350.956344 -238.986607) (xy 351.003309 -239.000949) (xy 351.047632 -239.022088) (xy 351.088336 -239.049557)
			(xy 351.10674 -239.065816) (xy 351.118229 -239.075619) (xy 351.145466 -239.088633) (xy 351.17532 -239.093101)
			(xy 351.205174 -239.088633) (xy 351.232411 -239.075619) (xy 351.2439 -239.065816) (xy 351.262304 -239.049558)
			(xy 351.303015 -239.022102) (xy 351.347339 -239.000967) (xy 351.3943 -238.98662) (xy 351.442868 -238.979376)
			(xy 351.46742 -238.978948) (xy 351.491973 -238.979377) (xy 351.540544 -238.986607) (xy 351.587509 -239.000949)
			(xy 351.631832 -239.022088) (xy 351.672536 -239.049557) (xy 351.69094 -239.065816) (xy 351.702429 -239.075619)
			(xy 351.729666 -239.088633) (xy 351.75952 -239.093101) (xy 351.789374 -239.088633) (xy 351.816611 -239.075619)
			(xy 351.8281 -239.065816) (xy 351.846504 -239.049558) (xy 351.887215 -239.022102) (xy 351.931539 -239.000967)
			(xy 351.9785 -238.98662) (xy 352.027068 -238.979376) (xy 352.05162 -238.978948) (xy 352.077586 -238.979459)
			(xy 352.128878 -238.987586) (xy 352.178268 -239.003636) (xy 352.224539 -239.027214) (xy 352.266552 -239.057741)
			(xy 352.303272 -239.094464) (xy 352.333796 -239.136478) (xy 352.357372 -239.182751) (xy 352.373419 -239.232141)
			(xy 352.381543 -239.283434) (xy 352.381543 -239.318605) (xy 352.789491 -239.318605) (xy 352.789491 -239.266671)
			(xy 352.797616 -239.215376) (xy 352.813664 -239.165983) (xy 352.837242 -239.119709) (xy 352.867768 -239.077693)
			(xy 352.904491 -239.04097) (xy 352.946507 -239.010444) (xy 352.992781 -238.986866) (xy 353.042174 -238.970818)
			(xy 353.093469 -238.962693) (xy 353.145403 -238.962693) (xy 353.196698 -238.970818) (xy 353.246091 -238.986866)
			(xy 353.292365 -239.010444) (xy 353.334381 -239.04097) (xy 353.371104 -239.077693) (xy 353.40163 -239.119709)
			(xy 353.425208 -239.165983) (xy 353.441256 -239.215376) (xy 353.449381 -239.266671) (xy 353.44989 -239.292638)
			(xy 353.449381 -239.318605) (xy 353.441256 -239.3699) (xy 353.425208 -239.419293) (xy 353.40163 -239.465567)
			(xy 353.371104 -239.507583) (xy 353.334381 -239.544306) (xy 353.292365 -239.574832) (xy 353.246091 -239.59841)
			(xy 353.196698 -239.614458) (xy 353.145403 -239.622583) (xy 353.093469 -239.622583) (xy 353.042174 -239.614458)
			(xy 352.992781 -239.59841) (xy 352.946507 -239.574832) (xy 352.904491 -239.544306) (xy 352.867768 -239.507583)
			(xy 352.837242 -239.465567) (xy 352.813664 -239.419293) (xy 352.797616 -239.3699) (xy 352.789491 -239.318605)
			(xy 352.381543 -239.318605) (xy 352.381543 -239.335366) (xy 352.373419 -239.386659) (xy 352.357372 -239.436049)
			(xy 352.333796 -239.482322) (xy 352.303272 -239.524336) (xy 352.266552 -239.561059) (xy 352.224539 -239.591586)
			(xy 352.178268 -239.615164) (xy 352.128878 -239.631214) (xy 352.077586 -239.639341) (xy 352.05162 -239.639856)
			(xy 352.027066 -239.63943) (xy 351.978492 -239.632205) (xy 351.931524 -239.617867) (xy 351.887196 -239.596733)
			(xy 351.846487 -239.569267) (xy 351.8281 -239.552988) (xy 351.816611 -239.543185) (xy 351.789374 -239.530171)
			(xy 351.75952 -239.525703) (xy 351.729666 -239.530171) (xy 351.702429 -239.543185) (xy 351.69094 -239.552988)
			(xy 351.672535 -239.569242) (xy 351.631822 -239.596691) (xy 351.587498 -239.617817) (xy 351.540537 -239.632156)
			(xy 351.491971 -239.639391) (xy 351.46742 -239.639856) (xy 351.442866 -239.63943) (xy 351.394292 -239.632205)
			(xy 351.347324 -239.617867) (xy 351.302996 -239.596733) (xy 351.262287 -239.569267) (xy 351.2439 -239.552988)
			(xy 351.232411 -239.543185) (xy 351.205174 -239.530171) (xy 351.17532 -239.525703) (xy 351.145466 -239.530171)
			(xy 351.118229 -239.543185) (xy 351.10674 -239.552988) (xy 351.088335 -239.569242) (xy 351.047622 -239.596691)
			(xy 351.003298 -239.617817) (xy 350.956337 -239.632156) (xy 350.907771 -239.639391) (xy 350.88322 -239.639856)
			(xy 350.85433 -239.639263) (xy 350.797428 -239.629222) (xy 350.743138 -239.609443) (xy 350.693113 -239.580528)
			(xy 350.670622 -239.562386) (xy 350.659248 -239.553494) (xy 350.632838 -239.541864) (xy 350.604229 -239.538086)
			(xy 350.575706 -239.542463) (xy 350.549546 -239.554644) (xy 350.527837 -239.573657) (xy 350.512315 -239.597984)
			(xy 350.504218 -239.625682) (xy 350.503744 -239.64011) (xy 350.503744 -239.879183) (xy 357.840789 -239.879183)
			(xy 357.840789 -239.827249) (xy 357.848914 -239.775954) (xy 357.864962 -239.726561) (xy 357.88854 -239.680287)
			(xy 357.919066 -239.638271) (xy 357.955789 -239.601548) (xy 357.997805 -239.571022) (xy 358.044079 -239.547444)
			(xy 358.093472 -239.531396) (xy 358.144767 -239.523271) (xy 358.196701 -239.523271) (xy 358.247996 -239.531396)
			(xy 358.297389 -239.547444) (xy 358.343663 -239.571022) (xy 358.385679 -239.601548) (xy 358.422402 -239.638271)
			(xy 358.452928 -239.680287) (xy 358.476506 -239.726561) (xy 358.492554 -239.775954) (xy 358.500679 -239.827249)
			(xy 358.501188 -239.853216) (xy 358.500679 -239.879183) (xy 358.492554 -239.930478) (xy 358.476506 -239.979871)
			(xy 358.452928 -240.026145) (xy 358.422402 -240.068161) (xy 358.385679 -240.104884) (xy 358.343663 -240.13541)
			(xy 358.297389 -240.158988) (xy 358.247996 -240.175036) (xy 358.196701 -240.183161) (xy 358.144767 -240.183161)
			(xy 358.093472 -240.175036) (xy 358.044079 -240.158988) (xy 357.997805 -240.13541) (xy 357.955789 -240.104884)
			(xy 357.919066 -240.068161) (xy 357.88854 -240.026145) (xy 357.864962 -239.979871) (xy 357.848914 -239.930478)
			(xy 357.840789 -239.879183) (xy 350.503744 -239.879183) (xy 350.503744 -239.986566) (xy 350.504196 -240.000341)
			(xy 350.511557 -240.026888) (xy 350.525752 -240.050498) (xy 350.545747 -240.069451) (xy 350.570082 -240.082363)
			(xy 350.596985 -240.088294) (xy 350.624495 -240.086812) (xy 350.650604 -240.078024) (xy 350.66224 -240.07064)
			(xy 350.682809 -240.057316) (xy 350.727051 -240.036234) (xy 350.773922 -240.021922) (xy 350.822394 -240.014694)
			(xy 350.846898 -240.014252) (xy 350.872867 -240.014735) (xy 350.924166 -240.022859) (xy 350.973563 -240.038909)
			(xy 351.01984 -240.062489) (xy 351.061859 -240.093018) (xy 351.098585 -240.129744) (xy 351.129113 -240.171763)
			(xy 351.152692 -240.218041) (xy 351.168741 -240.267438) (xy 351.176866 -240.318737) (xy 351.177352 -240.344706)
			(xy 351.176924 -240.36926) (xy 351.169696 -240.417831) (xy 351.155355 -240.464797) (xy 351.134218 -240.509122)
			(xy 351.10675 -240.549828) (xy 351.090484 -240.568226) (xy 351.080684 -240.579716) (xy 351.067678 -240.606953)
			(xy 351.063213 -240.636804) (xy 351.06768 -240.666655) (xy 351.080689 -240.693891) (xy 351.090484 -240.705386)
			(xy 351.106742 -240.72379) (xy 351.134201 -240.7645) (xy 351.155337 -240.808824) (xy 351.169686 -240.855786)
			(xy 351.176933 -240.904353) (xy 351.177352 -240.928906) (xy 351.176842 -240.954873) (xy 351.168717 -241.006167)
			(xy 351.152668 -241.055559) (xy 351.12909 -241.101832) (xy 351.098564 -241.143846) (xy 351.069917 -241.172492)
			(xy 356.03561 -241.172492) (xy 356.036065 -241.14794) (xy 356.0433 -241.099374) (xy 356.05764 -241.052412)
			(xy 356.078769 -241.008087) (xy 356.106222 -240.967376) (xy 356.122478 -240.948972) (xy 356.132289 -240.937489)
			(xy 356.145302 -240.91025) (xy 356.149768 -240.880394) (xy 356.145298 -240.850539) (xy 356.132282 -240.823301)
			(xy 356.122478 -240.811812) (xy 356.106199 -240.793425) (xy 356.078735 -240.752715) (xy 356.057601 -240.708388)
			(xy 356.043263 -240.66142) (xy 356.036037 -240.612846) (xy 356.03561 -240.588292) (xy 356.036119 -240.562325)
			(xy 356.044244 -240.51103) (xy 356.060292 -240.461637) (xy 356.08387 -240.415363) (xy 356.114396 -240.373347)
			(xy 356.151119 -240.336624) (xy 356.193135 -240.306098) (xy 356.239409 -240.28252) (xy 356.288802 -240.266472)
			(xy 356.340097 -240.258347) (xy 356.392031 -240.258347) (xy 356.443326 -240.266472) (xy 356.492719 -240.28252)
			(xy 356.538993 -240.306098) (xy 356.581009 -240.336624) (xy 356.617732 -240.373347) (xy 356.648258 -240.415363)
			(xy 356.671836 -240.461637) (xy 356.687884 -240.51103) (xy 356.696009 -240.562325) (xy 356.696518 -240.588292)
			(xy 356.696106 -240.612845) (xy 356.688859 -240.661413) (xy 356.67913 -240.693253) (xy 361.130089 -240.693253)
			(xy 361.130089 -240.641319) (xy 361.138214 -240.590024) (xy 361.154262 -240.540631) (xy 361.17784 -240.494357)
			(xy 361.208366 -240.452341) (xy 361.245089 -240.415618) (xy 361.287105 -240.385092) (xy 361.333379 -240.361514)
			(xy 361.382772 -240.345466) (xy 361.434067 -240.337341) (xy 361.486001 -240.337341) (xy 361.537296 -240.345466)
			(xy 361.586689 -240.361514) (xy 361.632963 -240.385092) (xy 361.674979 -240.415618) (xy 361.711702 -240.452341)
			(xy 361.742228 -240.494357) (xy 361.765806 -240.540631) (xy 361.781854 -240.590024) (xy 361.789979 -240.641319)
			(xy 361.790488 -240.667286) (xy 361.789979 -240.693253) (xy 361.781854 -240.744548) (xy 361.765806 -240.793941)
			(xy 361.742228 -240.840215) (xy 361.711702 -240.882231) (xy 361.674979 -240.918954) (xy 361.632963 -240.94948)
			(xy 361.586689 -240.973058) (xy 361.537296 -240.989106) (xy 361.486001 -240.997231) (xy 361.434067 -240.997231)
			(xy 361.382772 -240.989106) (xy 361.333379 -240.973058) (xy 361.287105 -240.94948) (xy 361.245089 -240.918954)
			(xy 361.208366 -240.882231) (xy 361.17784 -240.840215) (xy 361.154262 -240.793941) (xy 361.138214 -240.744548)
			(xy 361.130089 -240.693253) (xy 356.67913 -240.693253) (xy 356.674509 -240.708376) (xy 356.653371 -240.752699)
			(xy 356.62591 -240.793409) (xy 356.60965 -240.811812) (xy 356.599852 -240.823306) (xy 356.586834 -240.850541)
			(xy 356.582363 -240.880394) (xy 356.586831 -240.910248) (xy 356.599846 -240.937484) (xy 356.60965 -240.948972)
			(xy 356.625909 -240.967376) (xy 356.653379 -241.00808) (xy 356.674518 -241.052403) (xy 356.688861 -241.099368)
			(xy 356.69609 -241.147939) (xy 356.696518 -241.172492) (xy 356.696009 -241.198459) (xy 356.687884 -241.249754)
			(xy 356.671836 -241.299147) (xy 356.648258 -241.345421) (xy 356.617732 -241.387437) (xy 356.581009 -241.42416)
			(xy 356.538993 -241.454686) (xy 356.492719 -241.478264) (xy 356.443326 -241.494312) (xy 356.392031 -241.502437)
			(xy 356.340097 -241.502437) (xy 356.288802 -241.494312) (xy 356.239409 -241.478264) (xy 356.193135 -241.454686)
			(xy 356.151119 -241.42416) (xy 356.114396 -241.387437) (xy 356.08387 -241.345421) (xy 356.060292 -241.299147)
			(xy 356.044244 -241.249754) (xy 356.036119 -241.198459) (xy 356.03561 -241.172492) (xy 351.069917 -241.172492)
			(xy 351.06184 -241.180569) (xy 351.019825 -241.211094) (xy 350.973551 -241.234671) (xy 350.924159 -241.250719)
			(xy 350.872865 -241.258843) (xy 350.846898 -241.25936) (xy 350.822394 -241.258915) (xy 350.773924 -241.251682)
			(xy 350.727051 -241.237373) (xy 350.682805 -241.216303) (xy 350.66224 -241.202972) (xy 350.650581 -241.195631)
			(xy 350.624477 -241.186854) (xy 350.596976 -241.185377) (xy 350.570082 -241.191305) (xy 350.545752 -241.204209)
			(xy 350.525758 -241.223148) (xy 350.511555 -241.246743) (xy 350.504177 -241.273276) (xy 350.503744 -241.287046)
			(xy 350.503744 -241.507069) (xy 357.840789 -241.507069) (xy 357.840789 -241.455135) (xy 357.848914 -241.40384)
			(xy 357.864962 -241.354447) (xy 357.88854 -241.308173) (xy 357.919066 -241.266157) (xy 357.955789 -241.229434)
			(xy 357.997805 -241.198908) (xy 358.044079 -241.17533) (xy 358.093472 -241.159282) (xy 358.144767 -241.151157)
			(xy 358.196701 -241.151157) (xy 358.247996 -241.159282) (xy 358.297389 -241.17533) (xy 358.343663 -241.198908)
			(xy 358.385679 -241.229434) (xy 358.422402 -241.266157) (xy 358.452928 -241.308173) (xy 358.476506 -241.354447)
			(xy 358.492554 -241.40384) (xy 358.500679 -241.455135) (xy 358.501188 -241.481102) (xy 358.500679 -241.507069)
			(xy 358.492554 -241.558364) (xy 358.476506 -241.607757) (xy 358.452928 -241.654031) (xy 358.444776 -241.665252)
			(xy 363.032802 -241.665252) (xy 363.033235 -241.6407) (xy 363.040476 -241.592132) (xy 363.054821 -241.54517)
			(xy 363.075955 -241.500846) (xy 363.103412 -241.460135) (xy 363.11967 -241.441732) (xy 363.129521 -241.43028)
			(xy 363.14253 -241.40303) (xy 363.14699 -241.373164) (xy 363.142509 -241.343302) (xy 363.129481 -241.316061)
			(xy 363.11967 -241.304572) (xy 363.103419 -241.286162) (xy 363.07595 -241.245458) (xy 363.054811 -241.201137)
			(xy 363.040467 -241.154174) (xy 363.033233 -241.105605) (xy 363.032802 -241.081052) (xy 363.033311 -241.055085)
			(xy 363.041436 -241.00379) (xy 363.057484 -240.954397) (xy 363.081062 -240.908123) (xy 363.111588 -240.866107)
			(xy 363.148311 -240.829384) (xy 363.190327 -240.798858) (xy 363.236601 -240.77528) (xy 363.285994 -240.759232)
			(xy 363.337289 -240.751107) (xy 363.389223 -240.751107) (xy 363.440518 -240.759232) (xy 363.489911 -240.77528)
			(xy 363.536185 -240.798858) (xy 363.578201 -240.829384) (xy 363.614924 -240.866107) (xy 363.64545 -240.908123)
			(xy 363.669028 -240.954397) (xy 363.685076 -241.00379) (xy 363.693201 -241.055085) (xy 363.69371 -241.081052)
			(xy 363.693276 -241.105604) (xy 363.686035 -241.154172) (xy 363.67169 -241.201134) (xy 363.650557 -241.245458)
			(xy 363.6231 -241.286168) (xy 363.606842 -241.304572) (xy 363.597084 -241.316097) (xy 363.584063 -241.343321)
			(xy 363.579584 -241.373164) (xy 363.584042 -241.403011) (xy 363.597044 -241.430244) (xy 363.606842 -241.441732)
			(xy 363.623081 -241.460153) (xy 363.650554 -241.500852) (xy 363.671697 -241.545171) (xy 363.686044 -241.592132)
			(xy 363.693279 -241.6407) (xy 363.69371 -241.665252) (xy 363.693201 -241.691219) (xy 363.685076 -241.742514)
			(xy 363.669028 -241.791907) (xy 363.64545 -241.838181) (xy 363.614924 -241.880197) (xy 363.578201 -241.91692)
			(xy 363.536185 -241.947446) (xy 363.489911 -241.971024) (xy 363.440518 -241.987072) (xy 363.389223 -241.995197)
			(xy 363.337289 -241.995197) (xy 363.285994 -241.987072) (xy 363.236601 -241.971024) (xy 363.190327 -241.947446)
			(xy 363.148311 -241.91692) (xy 363.111588 -241.880197) (xy 363.081062 -241.838181) (xy 363.057484 -241.791907)
			(xy 363.041436 -241.742514) (xy 363.033311 -241.691219) (xy 363.032802 -241.665252) (xy 358.444776 -241.665252)
			(xy 358.422402 -241.696047) (xy 358.385679 -241.73277) (xy 358.343663 -241.763296) (xy 358.297389 -241.786874)
			(xy 358.247996 -241.802922) (xy 358.196701 -241.811047) (xy 358.144767 -241.811047) (xy 358.093472 -241.802922)
			(xy 358.044079 -241.786874) (xy 357.997805 -241.763296) (xy 357.955789 -241.73277) (xy 357.919066 -241.696047)
			(xy 357.88854 -241.654031) (xy 357.864962 -241.607757) (xy 357.848914 -241.558364) (xy 357.840789 -241.507069)
			(xy 350.503744 -241.507069) (xy 350.503744 -242.217448) (xy 350.505014 -242.223036) (xy 350.5087 -242.240777)
			(xy 350.512644 -242.276799) (xy 350.512888 -242.294918) (xy 350.51266 -242.313038) (xy 350.511802 -242.320885)
			(xy 361.130089 -242.320885) (xy 361.130089 -242.268951) (xy 361.138214 -242.217656) (xy 361.154262 -242.168263)
			(xy 361.17784 -242.121989) (xy 361.208366 -242.079973) (xy 361.245089 -242.04325) (xy 361.287105 -242.012724)
			(xy 361.333379 -241.989146) (xy 361.382772 -241.973098) (xy 361.434067 -241.964973) (xy 361.486001 -241.964973)
			(xy 361.537296 -241.973098) (xy 361.586689 -241.989146) (xy 361.632963 -242.012724) (xy 361.674979 -242.04325)
			(xy 361.711702 -242.079973) (xy 361.742228 -242.121989) (xy 361.765806 -242.168263) (xy 361.781854 -242.217656)
			(xy 361.789979 -242.268951) (xy 361.790488 -242.294918) (xy 361.789979 -242.320885) (xy 361.781854 -242.37218)
			(xy 361.765806 -242.421573) (xy 361.742228 -242.467847) (xy 361.711702 -242.509863) (xy 361.674979 -242.546586)
			(xy 361.632963 -242.577112) (xy 361.586689 -242.60069) (xy 361.537296 -242.616738) (xy 361.486001 -242.624863)
			(xy 361.434067 -242.624863) (xy 361.382772 -242.616738) (xy 361.333379 -242.60069) (xy 361.287105 -242.577112)
			(xy 361.245089 -242.546586) (xy 361.208366 -242.509863) (xy 361.17784 -242.467847) (xy 361.154262 -242.421573)
			(xy 361.138214 -242.37218) (xy 361.130089 -242.320885) (xy 350.511802 -242.320885) (xy 350.508719 -242.349062)
			(xy 350.505014 -242.3668) (xy 350.503744 -242.372388) (xy 350.503744 -243.134955) (xy 357.840789 -243.134955)
			(xy 357.840789 -243.083021) (xy 357.848914 -243.031726) (xy 357.864962 -242.982333) (xy 357.88854 -242.936059)
			(xy 357.919066 -242.894043) (xy 357.955789 -242.85732) (xy 357.997805 -242.826794) (xy 358.044079 -242.803216)
			(xy 358.093472 -242.787168) (xy 358.144767 -242.779043) (xy 358.196701 -242.779043) (xy 358.247996 -242.787168)
			(xy 358.297389 -242.803216) (xy 358.343663 -242.826794) (xy 358.385679 -242.85732) (xy 358.422402 -242.894043)
			(xy 358.452928 -242.936059) (xy 358.476506 -242.982333) (xy 358.47798 -242.986869) (xy 365.433835 -242.986869)
			(xy 365.433835 -242.934931) (xy 365.44196 -242.883632) (xy 365.45801 -242.834235) (xy 365.48159 -242.787958)
			(xy 365.51212 -242.745939) (xy 365.548846 -242.709213) (xy 365.590866 -242.678685) (xy 365.637144 -242.655106)
			(xy 365.686541 -242.639058) (xy 365.737841 -242.630934) (xy 365.76381 -242.630452) (xy 365.789671 -242.630958)
			(xy 365.840762 -242.639005) (xy 365.889975 -242.654916) (xy 365.936106 -242.678303) (xy 365.978029 -242.708593)
			(xy 365.996728 -242.726464) (xy 366.006443 -242.735509) (xy 366.029452 -242.748721) (xy 366.055089 -242.755558)
			(xy 366.081623 -242.755558) (xy 366.10726 -242.748721) (xy 366.130269 -242.735509) (xy 366.139984 -242.726464)
			(xy 366.158664 -242.708574) (xy 366.200598 -242.678296) (xy 366.246735 -242.654916) (xy 366.295949 -242.639006)
			(xy 366.347041 -242.630952) (xy 366.372902 -242.630452) (xy 366.39887 -242.630949) (xy 366.450165 -242.639074)
			(xy 366.499559 -242.655123) (xy 366.545833 -242.678702) (xy 366.587849 -242.709228) (xy 366.624573 -242.745952)
			(xy 366.6551 -242.787969) (xy 366.678678 -242.834243) (xy 366.694726 -242.883637) (xy 366.702851 -242.934932)
			(xy 366.702851 -242.986868) (xy 366.694726 -243.038163) (xy 366.678678 -243.087557) (xy 366.6551 -243.133831)
			(xy 366.624573 -243.175848) (xy 366.587849 -243.212572) (xy 366.545833 -243.243098) (xy 366.499559 -243.266677)
			(xy 366.450165 -243.282726) (xy 366.39887 -243.290851) (xy 366.372902 -243.29136) (xy 366.347042 -243.290843)
			(xy 366.295951 -243.282798) (xy 366.246739 -243.26689) (xy 366.200607 -243.243506) (xy 366.158683 -243.213218)
			(xy 366.139984 -243.195348) (xy 366.130269 -243.186303) (xy 366.10726 -243.173091) (xy 366.081623 -243.166254)
			(xy 366.055089 -243.166254) (xy 366.029452 -243.173091) (xy 366.006443 -243.186303) (xy 365.996728 -243.195348)
			(xy 365.978028 -243.213217) (xy 365.936101 -243.243502) (xy 365.88997 -243.266887) (xy 365.840759 -243.282802)
			(xy 365.78967 -243.290859) (xy 365.76381 -243.29136) (xy 365.737841 -243.290866) (xy 365.686541 -243.282742)
			(xy 365.637144 -243.266694) (xy 365.590866 -243.243115) (xy 365.548846 -243.212587) (xy 365.51212 -243.175861)
			(xy 365.48159 -243.133842) (xy 365.45801 -243.087565) (xy 365.44196 -243.038168) (xy 365.433835 -242.986869)
			(xy 358.47798 -242.986869) (xy 358.492554 -243.031726) (xy 358.500679 -243.083021) (xy 358.501188 -243.108988)
			(xy 358.500679 -243.134955) (xy 358.492554 -243.18625) (xy 358.476506 -243.235643) (xy 358.452928 -243.281917)
			(xy 358.422402 -243.323933) (xy 358.385679 -243.360656) (xy 358.343663 -243.391182) (xy 358.297389 -243.41476)
			(xy 358.247996 -243.430808) (xy 358.196701 -243.438933) (xy 358.144767 -243.438933) (xy 358.093472 -243.430808)
			(xy 358.044079 -243.41476) (xy 357.997805 -243.391182) (xy 357.955789 -243.360656) (xy 357.919066 -243.323933)
			(xy 357.88854 -243.281917) (xy 357.864962 -243.235643) (xy 357.848914 -243.18625) (xy 357.840789 -243.134955)
			(xy 350.503744 -243.134955) (xy 350.503744 -243.845334) (xy 350.505014 -243.850922) (xy 350.508701 -243.868663)
			(xy 350.512647 -243.904685) (xy 350.512888 -243.922804) (xy 350.512655 -243.940923) (xy 350.511794 -243.948771)
			(xy 361.130089 -243.948771) (xy 361.130089 -243.896837) (xy 361.138214 -243.845542) (xy 361.154262 -243.796149)
			(xy 361.17784 -243.749875) (xy 361.208366 -243.707859) (xy 361.245089 -243.671136) (xy 361.287105 -243.64061)
			(xy 361.333379 -243.617032) (xy 361.382772 -243.600984) (xy 361.434067 -243.592859) (xy 361.486001 -243.592859)
			(xy 361.537296 -243.600984) (xy 361.586689 -243.617032) (xy 361.632963 -243.64061) (xy 361.674979 -243.671136)
			(xy 361.711702 -243.707859) (xy 361.742228 -243.749875) (xy 361.765806 -243.796149) (xy 361.781854 -243.845542)
			(xy 361.789979 -243.896837) (xy 361.790488 -243.922804) (xy 361.789979 -243.948771) (xy 361.781854 -244.000066)
			(xy 361.765806 -244.049459) (xy 361.742228 -244.095733) (xy 361.711702 -244.137749) (xy 361.674979 -244.174472)
			(xy 361.632963 -244.204998) (xy 361.586689 -244.228576) (xy 361.537296 -244.244624) (xy 361.486001 -244.252749)
			(xy 361.434067 -244.252749) (xy 361.382772 -244.244624) (xy 361.333379 -244.228576) (xy 361.287105 -244.204998)
			(xy 361.245089 -244.174472) (xy 361.208366 -244.137749) (xy 361.17784 -244.095733) (xy 361.154262 -244.049459)
			(xy 361.138214 -244.000066) (xy 361.130089 -243.948771) (xy 350.511794 -243.948771) (xy 350.508705 -243.976945)
			(xy 350.505014 -243.994686) (xy 350.503744 -244.000274) (xy 350.503744 -244.39118) (xy 350.504145 -244.404861)
			(xy 350.511331 -244.431259) (xy 350.525274 -244.454799) (xy 350.54497 -244.473787) (xy 350.569004 -244.48686)
			(xy 350.595647 -244.493076) (xy 350.622984 -244.49199) (xy 350.64905 -244.483678) (xy 350.660716 -244.476524)
			(xy 350.680932 -244.463848) (xy 350.724239 -244.443818) (xy 350.769979 -244.430231) (xy 350.817198 -244.42337)
			(xy 350.841056 -244.42293) (xy 350.867028 -244.42341) (xy 350.918333 -244.431529) (xy 350.967737 -244.447575)
			(xy 351.014022 -244.471152) (xy 351.056048 -244.501679) (xy 351.092781 -244.538406) (xy 351.123317 -244.580427)
			(xy 351.146902 -244.626708) (xy 351.162957 -244.676108) (xy 351.171086 -244.727412) (xy 351.17151 -244.753384)
			(xy 351.171084 -244.777938) (xy 351.163858 -244.826511) (xy 351.149518 -244.873477) (xy 351.12838 -244.917803)
			(xy 351.100911 -244.958509) (xy 351.084642 -244.976904) (xy 351.074835 -244.988393) (xy 351.061814 -245.015631)
			(xy 351.057341 -245.045488) (xy 351.061807 -245.075346) (xy 351.074821 -245.102588) (xy 351.084642 -245.114064)
			(xy 351.100898 -245.132468) (xy 351.12835 -245.17318) (xy 351.149479 -245.217504) (xy 351.163819 -245.264466)
			(xy 351.171055 -245.313032) (xy 351.17151 -245.337584) (xy 351.171331 -245.347236) (xy 356.04323 -245.347236)
			(xy 356.043672 -245.322684) (xy 356.050914 -245.274118) (xy 356.065258 -245.227156) (xy 356.086389 -245.182832)
			(xy 356.113842 -245.142121) (xy 356.130098 -245.123716) (xy 356.139864 -245.112198) (xy 356.152879 -245.084971)
			(xy 356.157353 -245.055127) (xy 356.152895 -245.02528) (xy 356.139894 -244.998046) (xy 356.130098 -244.986556)
			(xy 356.113843 -244.968148) (xy 356.086375 -244.927445) (xy 356.065236 -244.883122) (xy 356.050892 -244.836159)
			(xy 356.04366 -244.787589) (xy 356.04323 -244.763036) (xy 356.043739 -244.737069) (xy 356.051864 -244.685774)
			(xy 356.067912 -244.636381) (xy 356.09149 -244.590107) (xy 356.122016 -244.548091) (xy 356.158739 -244.511368)
			(xy 356.200755 -244.480842) (xy 356.247029 -244.457264) (xy 356.296422 -244.441216) (xy 356.347717 -244.433091)
			(xy 356.399651 -244.433091) (xy 356.450946 -244.441216) (xy 356.500339 -244.457264) (xy 356.546613 -244.480842)
			(xy 356.588629 -244.511368) (xy 356.625352 -244.548091) (xy 356.655878 -244.590107) (xy 356.679456 -244.636381)
			(xy 356.695504 -244.685774) (xy 356.703629 -244.737069) (xy 356.704129 -244.762587) (xy 357.840789 -244.762587)
			(xy 357.840789 -244.710653) (xy 357.848914 -244.659358) (xy 357.864962 -244.609965) (xy 357.88854 -244.563691)
			(xy 357.919066 -244.521675) (xy 357.955789 -244.484952) (xy 357.997805 -244.454426) (xy 358.044079 -244.430848)
			(xy 358.093472 -244.4148) (xy 358.144767 -244.406675) (xy 358.196701 -244.406675) (xy 358.247996 -244.4148)
			(xy 358.297389 -244.430848) (xy 358.343663 -244.454426) (xy 358.385679 -244.484952) (xy 358.422402 -244.521675)
			(xy 358.452928 -244.563691) (xy 358.476506 -244.609965) (xy 358.492554 -244.659358) (xy 358.500679 -244.710653)
			(xy 358.501188 -244.73662) (xy 358.500679 -244.762587) (xy 358.492554 -244.813882) (xy 358.476506 -244.863275)
			(xy 358.452928 -244.909549) (xy 358.422402 -244.951565) (xy 358.385679 -244.988288) (xy 358.343663 -245.018814)
			(xy 358.297389 -245.042392) (xy 358.247996 -245.05844) (xy 358.196701 -245.066565) (xy 358.144767 -245.066565)
			(xy 358.093472 -245.05844) (xy 358.044079 -245.042392) (xy 357.997805 -245.018814) (xy 357.955789 -244.988288)
			(xy 357.919066 -244.951565) (xy 357.88854 -244.909549) (xy 357.864962 -244.863275) (xy 357.848914 -244.813882)
			(xy 357.840789 -244.762587) (xy 356.704129 -244.762587) (xy 356.704138 -244.763036) (xy 356.703687 -244.787588)
			(xy 356.696449 -244.836154) (xy 356.682108 -244.883116) (xy 356.660978 -244.92744) (xy 356.633526 -244.968151)
			(xy 356.61727 -244.986556) (xy 356.607428 -244.998016) (xy 356.594412 -245.025263) (xy 356.589948 -245.055127)
			(xy 356.594428 -245.084988) (xy 356.607457 -245.112228) (xy 356.61727 -245.123716) (xy 356.633553 -245.142099)
			(xy 356.661019 -245.182809) (xy 356.682153 -245.227137) (xy 356.69649 -245.274107) (xy 356.703713 -245.322681)
			(xy 356.704138 -245.347236) (xy 356.703629 -245.373203) (xy 356.695504 -245.424498) (xy 356.679456 -245.473891)
			(xy 356.655878 -245.520165) (xy 356.625352 -245.562181) (xy 356.610876 -245.576657) (xy 361.130089 -245.576657)
			(xy 361.130089 -245.524723) (xy 361.138214 -245.473428) (xy 361.154262 -245.424035) (xy 361.17784 -245.377761)
			(xy 361.208366 -245.335745) (xy 361.245089 -245.299022) (xy 361.287105 -245.268496) (xy 361.333379 -245.244918)
			(xy 361.382772 -245.22887) (xy 361.434067 -245.220745) (xy 361.486001 -245.220745) (xy 361.537296 -245.22887)
			(xy 361.586689 -245.244918) (xy 361.632963 -245.268496) (xy 361.674979 -245.299022) (xy 361.711702 -245.335745)
			(xy 361.742228 -245.377761) (xy 361.751782 -245.396512) (xy 363.025182 -245.396512) (xy 363.025596 -245.371959)
			(xy 363.032842 -245.323391) (xy 363.047192 -245.276428) (xy 363.06833 -245.232105) (xy 363.095791 -245.191395)
			(xy 363.11205 -245.172992) (xy 363.121844 -245.161495) (xy 363.134862 -245.134261) (xy 363.139334 -245.104409)
			(xy 363.134867 -245.074556) (xy 363.121854 -245.04732) (xy 363.11205 -245.035832) (xy 363.095793 -245.017427)
			(xy 363.068322 -244.976723) (xy 363.047183 -244.932401) (xy 363.03284 -244.885436) (xy 363.02561 -244.836865)
			(xy 363.025182 -244.812312) (xy 363.025691 -244.786345) (xy 363.033816 -244.73505) (xy 363.049864 -244.685657)
			(xy 363.073442 -244.639383) (xy 363.103968 -244.597367) (xy 363.140691 -244.560644) (xy 363.182707 -244.530118)
			(xy 363.228981 -244.50654) (xy 363.278374 -244.490492) (xy 363.329669 -244.482367) (xy 363.381603 -244.482367)
			(xy 363.432898 -244.490492) (xy 363.482291 -244.50654) (xy 363.528565 -244.530118) (xy 363.570581 -244.560644)
			(xy 363.607304 -244.597367) (xy 363.63783 -244.639383) (xy 363.661408 -244.685657) (xy 363.677456 -244.73505)
			(xy 363.685581 -244.786345) (xy 363.68609 -244.812312) (xy 363.685637 -244.836864) (xy 363.678402 -244.88543)
			(xy 363.664061 -244.932393) (xy 363.642932 -244.976717) (xy 363.615478 -245.017428) (xy 363.599222 -245.035832)
			(xy 363.589407 -245.047312) (xy 363.576395 -245.074552) (xy 363.571929 -245.104409) (xy 363.5764 -245.134265)
			(xy 363.589417 -245.161503) (xy 363.599222 -245.172992) (xy 363.615503 -245.191378) (xy 363.642967 -245.232088)
			(xy 363.664101 -245.276415) (xy 363.678438 -245.323384) (xy 363.685664 -245.371958) (xy 363.68609 -245.396512)
			(xy 363.685581 -245.422479) (xy 363.677456 -245.473774) (xy 363.661408 -245.523167) (xy 363.63783 -245.569441)
			(xy 363.607304 -245.611457) (xy 363.570581 -245.64818) (xy 363.528565 -245.678706) (xy 363.482291 -245.702284)
			(xy 363.432898 -245.718332) (xy 363.381603 -245.726457) (xy 363.329669 -245.726457) (xy 363.278374 -245.718332)
			(xy 363.228981 -245.702284) (xy 363.182707 -245.678706) (xy 363.140691 -245.64818) (xy 363.103968 -245.611457)
			(xy 363.073442 -245.569441) (xy 363.049864 -245.523167) (xy 363.033816 -245.473774) (xy 363.025691 -245.422479)
			(xy 363.025182 -245.396512) (xy 361.751782 -245.396512) (xy 361.765806 -245.424035) (xy 361.781854 -245.473428)
			(xy 361.789979 -245.524723) (xy 361.790488 -245.55069) (xy 361.789979 -245.576657) (xy 361.781854 -245.627952)
			(xy 361.765806 -245.677345) (xy 361.742228 -245.723619) (xy 361.711702 -245.765635) (xy 361.674979 -245.802358)
			(xy 361.632963 -245.832884) (xy 361.586689 -245.856462) (xy 361.537296 -245.87251) (xy 361.486001 -245.880635)
			(xy 361.434067 -245.880635) (xy 361.382772 -245.87251) (xy 361.333379 -245.856462) (xy 361.287105 -245.832884)
			(xy 361.245089 -245.802358) (xy 361.208366 -245.765635) (xy 361.17784 -245.723619) (xy 361.154262 -245.677345)
			(xy 361.138214 -245.627952) (xy 361.130089 -245.576657) (xy 356.610876 -245.576657) (xy 356.588629 -245.598904)
			(xy 356.546613 -245.62943) (xy 356.500339 -245.653008) (xy 356.450946 -245.669056) (xy 356.399651 -245.677181)
			(xy 356.347717 -245.677181) (xy 356.296422 -245.669056) (xy 356.247029 -245.653008) (xy 356.200755 -245.62943)
			(xy 356.158739 -245.598904) (xy 356.122016 -245.562181) (xy 356.09149 -245.520165) (xy 356.067912 -245.473891)
			(xy 356.051864 -245.424498) (xy 356.043739 -245.373203) (xy 356.04323 -245.347236) (xy 351.171331 -245.347236)
			(xy 351.171028 -245.363553) (xy 351.162905 -245.414851) (xy 351.146856 -245.464247) (xy 351.123277 -245.510524)
			(xy 351.092747 -245.552542) (xy 351.05602 -245.589266) (xy 351.014 -245.619791) (xy 350.967721 -245.643367)
			(xy 350.918324 -245.659412) (xy 350.867025 -245.667531) (xy 350.841056 -245.668038) (xy 350.813773 -245.667476)
			(xy 350.759949 -245.658516) (xy 350.708324 -245.640844) (xy 350.660299 -245.614941) (xy 350.617175 -245.581509)
			(xy 350.598232 -245.561866) (xy 350.591383 -245.555043) (xy 350.573971 -245.546679) (xy 350.5547 -245.54536)
			(xy 350.536311 -245.551272) (xy 350.521419 -245.563575) (xy 350.512143 -245.580518) (xy 350.510602 -245.59006)
			(xy 350.505014 -245.622572) (xy 350.503744 -245.62816) (xy 350.503744 -246.254016) (xy 350.504189 -246.268014)
			(xy 350.511799 -246.294957) (xy 350.526443 -246.318819) (xy 350.547019 -246.337805) (xy 350.571979 -246.350486)
			(xy 350.599445 -246.35591) (xy 350.627352 -246.353668) (xy 350.64065 -246.349266) (xy 350.668315 -246.339683)
			(xy 350.725934 -246.329329) (xy 350.755204 -246.328692) (xy 350.779757 -246.32912) (xy 350.828329 -246.336349)
			(xy 350.875294 -246.350691) (xy 350.919617 -246.37183) (xy 350.960321 -246.3993) (xy 350.978724 -246.41556)
			(xy 350.990213 -246.425363) (xy 351.01745 -246.438377) (xy 351.047304 -246.442845) (xy 351.077158 -246.438377)
			(xy 351.104395 -246.425363) (xy 351.115884 -246.41556) (xy 351.134287 -246.3993) (xy 351.174996 -246.371837)
			(xy 351.21932 -246.350698) (xy 351.266282 -246.336346) (xy 351.314851 -246.329099) (xy 351.339404 -246.328692)
			(xy 351.363957 -246.32912) (xy 351.412529 -246.336349) (xy 351.459494 -246.350691) (xy 351.503817 -246.37183)
			(xy 351.544521 -246.3993) (xy 351.562924 -246.41556) (xy 351.574413 -246.425363) (xy 351.60165 -246.438377)
			(xy 351.631504 -246.442845) (xy 351.661358 -246.438377) (xy 351.688595 -246.425363) (xy 351.700084 -246.41556)
			(xy 351.718487 -246.3993) (xy 351.759196 -246.371837) (xy 351.80352 -246.350698) (xy 351.850482 -246.336346)
			(xy 351.899051 -246.329099) (xy 351.923604 -246.328692) (xy 351.948157 -246.32912) (xy 351.996729 -246.336349)
			(xy 352.043694 -246.350691) (xy 352.088017 -246.37183) (xy 352.128721 -246.3993) (xy 352.147124 -246.41556)
			(xy 352.158613 -246.425363) (xy 352.18585 -246.438377) (xy 352.215704 -246.442845) (xy 352.245558 -246.438377)
			(xy 352.272795 -246.425363) (xy 352.284284 -246.41556) (xy 352.302687 -246.3993) (xy 352.343396 -246.371837)
			(xy 352.38772 -246.350698) (xy 352.434682 -246.336346) (xy 352.483251 -246.329099) (xy 352.507804 -246.328692)
			(xy 352.533218 -246.329151) (xy 352.583449 -246.336918) (xy 352.631899 -246.352283) (xy 352.677425 -246.374885)
			(xy 352.718954 -246.404191) (xy 352.755507 -246.439509) (xy 352.771202 -246.459502) (xy 352.780911 -246.471465)
			(xy 352.805956 -246.489386) (xy 352.835203 -246.499029) (xy 352.865996 -246.499517) (xy 352.895534 -246.490806)
			(xy 352.921134 -246.473688) (xy 352.931222 -246.462042) (xy 352.94699 -246.443162) (xy 352.983167 -246.409833)
			(xy 353.023889 -246.382243) (xy 353.068255 -246.361001) (xy 353.115283 -246.34658) (xy 353.163929 -246.339298)
			(xy 353.188524 -246.338852) (xy 353.214277 -246.339346) (xy 353.265159 -246.347336) (xy 353.314187 -246.363119)
			(xy 353.360174 -246.386314) (xy 353.402009 -246.416359) (xy 353.42068 -246.434102) (xy 353.43037 -246.443095)
			(xy 353.453302 -246.456227) (xy 353.478841 -246.463022) (xy 353.505267 -246.463022) (xy 353.530806 -246.456227)
			(xy 353.553738 -246.443095) (xy 353.563428 -246.434102) (xy 353.582103 -246.416361) (xy 353.62393 -246.386304)
			(xy 353.669916 -246.363104) (xy 353.718946 -246.347322) (xy 353.76983 -246.339341) (xy 353.795584 -246.338852)
			(xy 353.821554 -246.339334) (xy 353.872854 -246.347456) (xy 353.922252 -246.363505) (xy 353.968531 -246.387083)
			(xy 353.973197 -246.390473) (xy 357.840789 -246.390473) (xy 357.840789 -246.338539) (xy 357.848914 -246.287244)
			(xy 357.864962 -246.237851) (xy 357.88854 -246.191577) (xy 357.919066 -246.149561) (xy 357.955789 -246.112838)
			(xy 357.997805 -246.082312) (xy 358.044079 -246.058734) (xy 358.093472 -246.042686) (xy 358.144767 -246.034561)
			(xy 358.196701 -246.034561) (xy 358.247996 -246.042686) (xy 358.297389 -246.058734) (xy 358.343663 -246.082312)
			(xy 358.385679 -246.112838) (xy 358.422402 -246.149561) (xy 358.452928 -246.191577) (xy 358.476506 -246.237851)
			(xy 358.492554 -246.287244) (xy 358.500679 -246.338539) (xy 358.501188 -246.364506) (xy 358.500679 -246.390473)
			(xy 358.492554 -246.441768) (xy 358.476506 -246.491161) (xy 358.452928 -246.537435) (xy 358.422402 -246.579451)
			(xy 358.385679 -246.616174) (xy 358.343663 -246.6467) (xy 358.297389 -246.670278) (xy 358.247996 -246.686326)
			(xy 358.196701 -246.694451) (xy 358.144767 -246.694451) (xy 358.093472 -246.686326) (xy 358.044079 -246.670278)
			(xy 357.997805 -246.6467) (xy 357.955789 -246.616174) (xy 357.919066 -246.579451) (xy 357.88854 -246.537435)
			(xy 357.864962 -246.491161) (xy 357.848914 -246.441768) (xy 357.840789 -246.390473) (xy 353.973197 -246.390473)
			(xy 354.010551 -246.417611) (xy 354.047279 -246.454337) (xy 354.077809 -246.496356) (xy 354.101389 -246.542634)
			(xy 354.11744 -246.592031) (xy 354.125565 -246.64333) (xy 354.125565 -246.695269) (xy 365.433835 -246.695269)
			(xy 365.433835 -246.643331) (xy 365.44196 -246.592032) (xy 365.45801 -246.542635) (xy 365.48159 -246.496358)
			(xy 365.51212 -246.454339) (xy 365.548846 -246.417613) (xy 365.590866 -246.387085) (xy 365.637144 -246.363506)
			(xy 365.686541 -246.347458) (xy 365.737841 -246.339334) (xy 365.76381 -246.338852) (xy 365.789131 -246.339362)
			(xy 365.839183 -246.347072) (xy 365.887474 -246.362324) (xy 365.932874 -246.384763) (xy 365.974321 -246.413862)
			(xy 365.992918 -246.431054) (xy 366.00276 -246.439978) (xy 366.025974 -246.452879) (xy 366.051735 -246.459337)
			(xy 366.078289 -246.458913) (xy 366.10383 -246.451636) (xy 366.12662 -246.438) (xy 366.136174 -246.428768)
			(xy 366.15495 -246.410186) (xy 366.197343 -246.378672) (xy 366.244205 -246.354294) (xy 366.294346 -246.337673)
			(xy 366.346491 -246.329232) (xy 366.372902 -246.328692) (xy 366.398873 -246.32911) (xy 366.450175 -246.337235)
			(xy 366.499574 -246.353286) (xy 366.545854 -246.376867) (xy 366.587875 -246.407398) (xy 366.624603 -246.444126)
			(xy 366.655134 -246.486148) (xy 366.678714 -246.532428) (xy 366.694765 -246.581827) (xy 366.702891 -246.633129)
			(xy 366.702891 -246.685071) (xy 366.694765 -246.736373) (xy 366.678714 -246.785772) (xy 366.655134 -246.832052)
			(xy 366.624603 -246.874074) (xy 366.587875 -246.910802) (xy 366.545854 -246.941333) (xy 366.499574 -246.964914)
			(xy 366.450175 -246.980965) (xy 366.398873 -246.98909) (xy 366.372902 -246.9896) (xy 366.347578 -246.989157)
			(xy 366.297522 -246.981433) (xy 366.24923 -246.966166) (xy 366.203831 -246.943712) (xy 366.162388 -246.914597)
			(xy 366.143794 -246.897398) (xy 366.133939 -246.888491) (xy 366.110728 -246.875595) (xy 366.084972 -246.869139)
			(xy 366.058422 -246.86956) (xy 366.032884 -246.876831) (xy 366.010094 -246.890457) (xy 366.000538 -246.899684)
			(xy 365.981748 -246.918251) (xy 365.93936 -246.94977) (xy 365.892501 -246.974151) (xy 365.842363 -246.990775)
			(xy 365.790221 -246.999219) (xy 365.76381 -246.99976) (xy 365.737841 -246.999266) (xy 365.686541 -246.991142)
			(xy 365.637144 -246.975094) (xy 365.590866 -246.951515) (xy 365.548846 -246.920987) (xy 365.51212 -246.884261)
			(xy 365.48159 -246.842242) (xy 365.45801 -246.795965) (xy 365.44196 -246.746568) (xy 365.433835 -246.695269)
			(xy 354.125565 -246.695269) (xy 354.125565 -246.69527) (xy 354.11744 -246.746569) (xy 354.101389 -246.795966)
			(xy 354.077809 -246.842244) (xy 354.047279 -246.884263) (xy 354.010551 -246.920989) (xy 353.968531 -246.951517)
			(xy 353.922252 -246.975095) (xy 353.872854 -246.991144) (xy 353.821554 -246.999266) (xy 353.795584 -246.99976)
			(xy 353.769831 -246.999267) (xy 353.718948 -246.991278) (xy 353.669919 -246.975496) (xy 353.62393 -246.952303)
			(xy 353.582094 -246.922259) (xy 353.563428 -246.90451) (xy 353.553738 -246.895517) (xy 353.530806 -246.882385)
			(xy 353.505267 -246.87559) (xy 353.478841 -246.87559) (xy 353.453302 -246.882385) (xy 353.43037 -246.895517)
			(xy 353.42068 -246.90451) (xy 353.402008 -246.922256) (xy 353.360183 -246.952321) (xy 353.314197 -246.975529)
			(xy 353.265166 -246.991317) (xy 353.214279 -246.999301) (xy 353.188524 -246.99976) (xy 353.163113 -246.999296)
			(xy 353.112889 -246.991519) (xy 353.064448 -246.976144) (xy 353.018933 -246.953534) (xy 352.977415 -246.924222)
			(xy 352.940875 -246.888899) (xy 352.925126 -246.86895) (xy 352.91542 -246.856978) (xy 352.890374 -246.839039)
			(xy 352.861119 -246.829384) (xy 352.830317 -246.82889) (xy 352.800768 -246.837603) (xy 352.77516 -246.85473)
			(xy 352.765106 -246.86641) (xy 352.74934 -246.885294) (xy 352.713166 -246.91863) (xy 352.672445 -246.946228)
			(xy 352.628078 -246.967477) (xy 352.58105 -246.981904) (xy 352.5324 -246.989191) (xy 352.507804 -246.9896)
			(xy 352.48325 -246.989173) (xy 352.434679 -246.981945) (xy 352.387713 -246.967603) (xy 352.34339 -246.946464)
			(xy 352.302685 -246.918994) (xy 352.284284 -246.902732) (xy 352.272795 -246.892929) (xy 352.245558 -246.879915)
			(xy 352.215704 -246.875447) (xy 352.18585 -246.879915) (xy 352.158613 -246.892929) (xy 352.147124 -246.902732)
			(xy 352.128722 -246.918993) (xy 352.088013 -246.946457) (xy 352.043689 -246.967598) (xy 351.996727 -246.981951)
			(xy 351.948158 -246.9892) (xy 351.923604 -246.9896) (xy 351.89905 -246.989173) (xy 351.850479 -246.981945)
			(xy 351.803513 -246.967603) (xy 351.75919 -246.946464) (xy 351.718485 -246.918994) (xy 351.700084 -246.902732)
			(xy 351.688595 -246.892929) (xy 351.661358 -246.879915) (xy 351.631504 -246.875447) (xy 351.60165 -246.879915)
			(xy 351.574413 -246.892929) (xy 351.562924 -246.902732) (xy 351.544522 -246.918993) (xy 351.503813 -246.946457)
			(xy 351.459489 -246.967598) (xy 351.412527 -246.981951) (xy 351.363958 -246.9892) (xy 351.339404 -246.9896)
			(xy 351.31485 -246.989173) (xy 351.266279 -246.981945) (xy 351.219313 -246.967603) (xy 351.17499 -246.946464)
			(xy 351.134285 -246.918994) (xy 351.115884 -246.902732) (xy 351.104395 -246.892929) (xy 351.077158 -246.879915)
			(xy 351.047304 -246.875447) (xy 351.01745 -246.879915) (xy 350.990213 -246.892929) (xy 350.978724 -246.902732)
			(xy 350.960322 -246.918993) (xy 350.919613 -246.946457) (xy 350.875289 -246.967598) (xy 350.828327 -246.981951)
			(xy 350.779758 -246.9892) (xy 350.755204 -246.9896) (xy 350.725935 -246.988947) (xy 350.668318 -246.978598)
			(xy 350.64065 -246.969026) (xy 350.627364 -246.964568) (xy 350.599441 -246.962325) (xy 350.571958 -246.967752)
			(xy 350.546984 -246.98044) (xy 350.526395 -246.999437) (xy 350.511742 -247.023312) (xy 350.504125 -247.050269)
			(xy 350.503744 -247.064276) (xy 350.503744 -247.100852) (xy 350.505014 -247.10644) (xy 350.5087 -247.124181)
			(xy 350.512644 -247.160203) (xy 350.512888 -247.178322) (xy 350.51266 -247.196442) (xy 350.511801 -247.204289)
			(xy 361.130089 -247.204289) (xy 361.130089 -247.152355) (xy 361.138214 -247.10106) (xy 361.154262 -247.051667)
			(xy 361.17784 -247.005393) (xy 361.208366 -246.963377) (xy 361.245089 -246.926654) (xy 361.287105 -246.896128)
			(xy 361.333379 -246.87255) (xy 361.382772 -246.856502) (xy 361.434067 -246.848377) (xy 361.486001 -246.848377)
			(xy 361.537296 -246.856502) (xy 361.586689 -246.87255) (xy 361.632963 -246.896128) (xy 361.674979 -246.926654)
			(xy 361.711702 -246.963377) (xy 361.742228 -247.005393) (xy 361.765806 -247.051667) (xy 361.781854 -247.10106)
			(xy 361.789979 -247.152355) (xy 361.790488 -247.178322) (xy 361.789979 -247.204289) (xy 361.781854 -247.255584)
			(xy 361.765806 -247.304977) (xy 361.742228 -247.351251) (xy 361.711702 -247.393267) (xy 361.674979 -247.42999)
			(xy 361.632963 -247.460516) (xy 361.586689 -247.484094) (xy 361.537296 -247.500142) (xy 361.486001 -247.508267)
			(xy 361.434067 -247.508267) (xy 361.382772 -247.500142) (xy 361.333379 -247.484094) (xy 361.287105 -247.460516)
			(xy 361.245089 -247.42999) (xy 361.208366 -247.393267) (xy 361.17784 -247.351251) (xy 361.154262 -247.304977)
			(xy 361.138214 -247.255584) (xy 361.130089 -247.204289) (xy 350.511801 -247.204289) (xy 350.508718 -247.232466)
			(xy 350.505014 -247.250204) (xy 350.503744 -247.255792) (xy 350.503744 -248.018105) (xy 357.840789 -248.018105)
			(xy 357.840789 -247.966171) (xy 357.848914 -247.914876) (xy 357.864962 -247.865483) (xy 357.88854 -247.819209)
			(xy 357.919066 -247.777193) (xy 357.955789 -247.74047) (xy 357.997805 -247.709944) (xy 358.044079 -247.686366)
			(xy 358.093472 -247.670318) (xy 358.144767 -247.662193) (xy 358.196701 -247.662193) (xy 358.247996 -247.670318)
			(xy 358.297389 -247.686366) (xy 358.343663 -247.709944) (xy 358.385679 -247.74047) (xy 358.422402 -247.777193)
			(xy 358.452928 -247.819209) (xy 358.476506 -247.865483) (xy 358.492554 -247.914876) (xy 358.500679 -247.966171)
			(xy 358.501188 -247.992138) (xy 358.500679 -248.018105) (xy 358.492554 -248.0694) (xy 358.476506 -248.118793)
			(xy 358.452928 -248.165067) (xy 358.422402 -248.207083) (xy 358.385679 -248.243806) (xy 358.343663 -248.274332)
			(xy 358.297389 -248.29791) (xy 358.247996 -248.313958) (xy 358.196701 -248.322083) (xy 358.144767 -248.322083)
			(xy 358.093472 -248.313958) (xy 358.044079 -248.29791) (xy 357.997805 -248.274332) (xy 357.955789 -248.243806)
			(xy 357.919066 -248.207083) (xy 357.88854 -248.165067) (xy 357.864962 -248.118793) (xy 357.848914 -248.0694)
			(xy 357.840789 -248.018105) (xy 350.503744 -248.018105) (xy 350.503744 -248.260616) (xy 350.504237 -248.27497)
			(xy 350.512228 -248.302545) (xy 350.527574 -248.326809) (xy 350.549064 -248.345845) (xy 350.575002 -248.358152)
			(xy 350.603339 -248.362758) (xy 350.631839 -248.359299) (xy 350.645222 -248.354088) (xy 350.66578 -248.345719)
			(xy 350.708578 -248.333951) (xy 350.752568 -248.328031) (xy 350.774762 -248.327672) (xy 350.800733 -248.328152)
			(xy 350.852035 -248.336272) (xy 350.901435 -248.352319) (xy 350.947716 -248.375897) (xy 350.989738 -248.406426)
			(xy 351.026466 -248.443153) (xy 351.056996 -248.485174) (xy 351.080576 -248.531454) (xy 351.096625 -248.580854)
			(xy 351.104747 -248.632156) (xy 351.105216 -248.658126) (xy 351.104787 -248.682679) (xy 351.097555 -248.731249)
			(xy 351.083211 -248.778212) (xy 351.06207 -248.822533) (xy 351.034598 -248.863235) (xy 351.018348 -248.881646)
			(xy 351.008546 -248.893134) (xy 350.995537 -248.920369) (xy 350.991074 -248.950219) (xy 350.995548 -248.980068)
			(xy 351.007512 -249.00509) (xy 356.04323 -249.00509) (xy 356.043705 -248.980539) (xy 356.050938 -248.931974)
			(xy 356.065275 -248.885013) (xy 356.086399 -248.840689) (xy 356.113845 -248.799976) (xy 356.130098 -248.78157)
			(xy 356.139909 -248.770088) (xy 356.152919 -248.742848) (xy 356.157384 -248.712993) (xy 356.152915 -248.683138)
			(xy 356.139901 -248.6559) (xy 356.130098 -248.64441) (xy 356.113822 -248.626021) (xy 356.086356 -248.585312)
			(xy 356.065221 -248.540985) (xy 356.050883 -248.494017) (xy 356.043657 -248.445444) (xy 356.04323 -248.42089)
			(xy 356.043739 -248.394923) (xy 356.051864 -248.343628) (xy 356.067912 -248.294235) (xy 356.09149 -248.247961)
			(xy 356.122016 -248.205945) (xy 356.158739 -248.169222) (xy 356.200755 -248.138696) (xy 356.247029 -248.115118)
			(xy 356.296422 -248.09907) (xy 356.347717 -248.090945) (xy 356.399651 -248.090945) (xy 356.450946 -248.09907)
			(xy 356.500339 -248.115118) (xy 356.546613 -248.138696) (xy 356.588629 -248.169222) (xy 356.625352 -248.205945)
			(xy 356.655878 -248.247961) (xy 356.679456 -248.294235) (xy 356.695504 -248.343628) (xy 356.703629 -248.394923)
			(xy 356.704138 -248.42089) (xy 356.70372 -248.445443) (xy 356.696474 -248.494011) (xy 356.682125 -248.540973)
			(xy 356.660988 -248.585296) (xy 356.633529 -248.626006) (xy 356.61727 -248.64441) (xy 356.607472 -248.655905)
			(xy 356.594452 -248.683139) (xy 356.589979 -248.712993) (xy 356.594447 -248.742847) (xy 356.607464 -248.770083)
			(xy 356.61727 -248.78157) (xy 356.633532 -248.799972) (xy 356.655264 -248.832175) (xy 361.130089 -248.832175)
			(xy 361.130089 -248.780241) (xy 361.138214 -248.728946) (xy 361.154262 -248.679553) (xy 361.17784 -248.633279)
			(xy 361.208366 -248.591263) (xy 361.245089 -248.55454) (xy 361.287105 -248.524014) (xy 361.333379 -248.500436)
			(xy 361.382772 -248.484388) (xy 361.434067 -248.476263) (xy 361.486001 -248.476263) (xy 361.537296 -248.484388)
			(xy 361.586689 -248.500436) (xy 361.632963 -248.524014) (xy 361.674979 -248.55454) (xy 361.711702 -248.591263)
			(xy 361.742228 -248.633279) (xy 361.765806 -248.679553) (xy 361.781854 -248.728946) (xy 361.789979 -248.780241)
			(xy 361.790488 -248.806208) (xy 361.789979 -248.832175) (xy 361.781854 -248.88347) (xy 361.765806 -248.932863)
			(xy 361.742228 -248.979137) (xy 361.711702 -249.021153) (xy 361.674979 -249.057876) (xy 361.632963 -249.088402)
			(xy 361.586689 -249.11198) (xy 361.537296 -249.128028) (xy 361.486001 -249.136153) (xy 361.434067 -249.136153)
			(xy 361.382772 -249.128028) (xy 361.333379 -249.11198) (xy 361.287105 -249.088402) (xy 361.245089 -249.057876)
			(xy 361.208366 -249.021153) (xy 361.17784 -248.979137) (xy 361.154262 -248.932863) (xy 361.138214 -248.88347)
			(xy 361.130089 -248.832175) (xy 356.655264 -248.832175) (xy 356.661001 -248.840676) (xy 356.682139 -248.885)
			(xy 356.696481 -248.931965) (xy 356.70371 -248.980537) (xy 356.704138 -249.00509) (xy 356.703629 -249.031057)
			(xy 356.695504 -249.082352) (xy 356.679456 -249.131745) (xy 356.655878 -249.178019) (xy 356.625352 -249.220035)
			(xy 356.618555 -249.226832) (xy 362.992162 -249.226832) (xy 362.992593 -249.20228) (xy 362.999836 -249.153712)
			(xy 363.014182 -249.106751) (xy 363.035316 -249.062427) (xy 363.062773 -249.021716) (xy 363.07903 -249.003312)
			(xy 363.088806 -248.9918) (xy 363.101829 -248.964572) (xy 363.106306 -248.934724) (xy 363.101843 -248.904873)
			(xy 363.088833 -248.877639) (xy 363.07903 -248.866152) (xy 363.062779 -248.847742) (xy 363.035308 -248.807039)
			(xy 363.014168 -248.762718) (xy 362.999824 -248.715754) (xy 362.992592 -248.667185) (xy 362.992162 -248.642632)
			(xy 362.992671 -248.616665) (xy 363.000796 -248.56537) (xy 363.016844 -248.515977) (xy 363.040422 -248.469703)
			(xy 363.070948 -248.427687) (xy 363.107671 -248.390964) (xy 363.149687 -248.360438) (xy 363.195961 -248.33686)
			(xy 363.245354 -248.320812) (xy 363.296649 -248.312687) (xy 363.348583 -248.312687) (xy 363.399878 -248.320812)
			(xy 363.449271 -248.33686) (xy 363.495545 -248.360438) (xy 363.537561 -248.390964) (xy 363.574284 -248.427687)
			(xy 363.60481 -248.469703) (xy 363.628388 -248.515977) (xy 363.644436 -248.56537) (xy 363.652561 -248.616665)
			(xy 363.65307 -248.642632) (xy 363.652609 -248.667183) (xy 363.645372 -248.715749) (xy 363.631032 -248.76271)
			(xy 363.609905 -248.807034) (xy 363.582456 -248.847747) (xy 363.566202 -248.866152) (xy 363.556369 -248.877617)
			(xy 363.543362 -248.904863) (xy 363.5389 -248.934724) (xy 363.543375 -248.964582) (xy 363.556395 -248.991822)
			(xy 363.566202 -249.003312) (xy 363.582489 -249.021692) (xy 363.609953 -249.062404) (xy 363.631086 -249.106733)
			(xy 363.645422 -249.153702) (xy 363.652645 -249.202277) (xy 363.65307 -249.226832) (xy 363.652561 -249.252799)
			(xy 363.644436 -249.304094) (xy 363.628388 -249.353487) (xy 363.60481 -249.399761) (xy 363.574284 -249.441777)
			(xy 363.537561 -249.4785) (xy 363.495545 -249.509026) (xy 363.449271 -249.532604) (xy 363.399878 -249.548652)
			(xy 363.348583 -249.556777) (xy 363.296649 -249.556777) (xy 363.245354 -249.548652) (xy 363.195961 -249.532604)
			(xy 363.149687 -249.509026) (xy 363.107671 -249.4785) (xy 363.070948 -249.441777) (xy 363.040422 -249.399761)
			(xy 363.016844 -249.353487) (xy 363.000796 -249.304094) (xy 362.992671 -249.252799) (xy 362.992162 -249.226832)
			(xy 356.618555 -249.226832) (xy 356.588629 -249.256758) (xy 356.546613 -249.287284) (xy 356.500339 -249.310862)
			(xy 356.450946 -249.32691) (xy 356.399651 -249.335035) (xy 356.347717 -249.335035) (xy 356.296422 -249.32691)
			(xy 356.247029 -249.310862) (xy 356.200755 -249.287284) (xy 356.158739 -249.256758) (xy 356.122016 -249.220035)
			(xy 356.09149 -249.178019) (xy 356.067912 -249.131745) (xy 356.051864 -249.082352) (xy 356.043739 -249.031057)
			(xy 356.04323 -249.00509) (xy 351.007512 -249.00509) (xy 351.008568 -249.007298) (xy 351.018348 -249.018806)
			(xy 351.034607 -249.037209) (xy 351.062066 -249.077919) (xy 351.083202 -249.122243) (xy 351.09755 -249.169205)
			(xy 351.104794 -249.217773) (xy 351.105216 -249.242326) (xy 351.104731 -249.268293) (xy 351.096603 -249.319587)
			(xy 351.08055 -249.368977) (xy 351.056968 -249.415249) (xy 351.026439 -249.457261) (xy 350.989712 -249.49398)
			(xy 350.947694 -249.524502) (xy 350.901418 -249.548075) (xy 350.852024 -249.564118) (xy 350.800729 -249.572236)
			(xy 350.774762 -249.57278) (xy 350.752569 -249.572421) (xy 350.708581 -249.566487) (xy 350.66578 -249.554732)
			(xy 350.645222 -249.546364) (xy 350.631824 -249.541175) (xy 350.603317 -249.537689) (xy 350.574968 -249.542278)
			(xy 350.549016 -249.554579) (xy 350.527515 -249.573618) (xy 350.512165 -249.59789) (xy 350.50418 -249.625476)
			(xy 350.503744 -249.639836) (xy 350.503744 -249.645991) (xy 357.840789 -249.645991) (xy 357.840789 -249.594057)
			(xy 357.848914 -249.542762) (xy 357.864962 -249.493369) (xy 357.88854 -249.447095) (xy 357.919066 -249.405079)
			(xy 357.955789 -249.368356) (xy 357.997805 -249.33783) (xy 358.044079 -249.314252) (xy 358.093472 -249.298204)
			(xy 358.144767 -249.290079) (xy 358.196701 -249.290079) (xy 358.247996 -249.298204) (xy 358.297389 -249.314252)
			(xy 358.343663 -249.33783) (xy 358.385679 -249.368356) (xy 358.422402 -249.405079) (xy 358.452928 -249.447095)
			(xy 358.476506 -249.493369) (xy 358.492554 -249.542762) (xy 358.500679 -249.594057) (xy 358.501188 -249.620024)
			(xy 358.500679 -249.645991) (xy 358.492554 -249.697286) (xy 358.476506 -249.746679) (xy 358.452928 -249.792953)
			(xy 358.422402 -249.834969) (xy 358.385679 -249.871692) (xy 358.343663 -249.902218) (xy 358.297389 -249.925796)
			(xy 358.247996 -249.941844) (xy 358.196701 -249.949969) (xy 358.144767 -249.949969) (xy 358.093472 -249.941844)
			(xy 358.044079 -249.925796) (xy 357.997805 -249.902218) (xy 357.955789 -249.871692) (xy 357.919066 -249.834969)
			(xy 357.88854 -249.792953) (xy 357.864962 -249.746679) (xy 357.848914 -249.697286) (xy 357.840789 -249.645991)
			(xy 350.503744 -249.645991) (xy 350.503744 -250.153424) (xy 350.504238 -250.167778) (xy 350.51223 -250.19535)
			(xy 350.527577 -250.219612) (xy 350.549066 -250.238646) (xy 350.575002 -250.250952) (xy 350.603338 -250.255558)
			(xy 350.631837 -250.252099) (xy 350.645222 -250.246896) (xy 350.66578 -250.238527) (xy 350.708578 -250.226758)
			(xy 350.752568 -250.220838) (xy 350.774762 -250.22048) (xy 350.800732 -250.22096) (xy 350.852034 -250.229081)
			(xy 350.901433 -250.245127) (xy 350.947714 -250.268706) (xy 350.989735 -250.299234) (xy 351.026463 -250.335962)
			(xy 351.046159 -250.363072) (xy 353.066795 -250.363072) (xy 353.066795 -250.311128) (xy 353.074921 -250.259823)
			(xy 353.090973 -250.210421) (xy 353.114555 -250.164138) (xy 353.145087 -250.122115) (xy 353.181818 -250.085385)
			(xy 353.223842 -250.054853) (xy 353.270125 -250.031271) (xy 353.319527 -250.01522) (xy 353.370832 -250.007095)
			(xy 353.396804 -250.006612) (xy 353.422558 -250.007091) (xy 353.473444 -250.015072) (xy 353.522474 -250.030855)
			(xy 353.56846 -250.054059) (xy 353.610287 -250.084119) (xy 353.62896 -250.101862) (xy 353.63865 -250.110855)
			(xy 353.661582 -250.123987) (xy 353.687121 -250.130782) (xy 353.713547 -250.130782) (xy 353.739086 -250.123987)
			(xy 353.762018 -250.110855) (xy 353.771708 -250.101862) (xy 353.790394 -250.084135) (xy 353.832224 -250.054086)
			(xy 353.878207 -250.030887) (xy 353.927232 -250.0151) (xy 353.978112 -250.007107) (xy 354.003864 -250.006612)
			(xy 354.029832 -250.00716) (xy 354.081131 -250.01528) (xy 354.130527 -250.031325) (xy 354.176805 -250.0549)
			(xy 354.218825 -250.085425) (xy 354.255552 -250.122148) (xy 354.286081 -250.164164) (xy 354.309661 -250.21044)
			(xy 354.325712 -250.259834) (xy 354.333837 -250.311132) (xy 354.333837 -250.363068) (xy 354.333836 -250.363072)
			(xy 365.433795 -250.363072) (xy 365.433795 -250.311128) (xy 365.441921 -250.259822) (xy 365.457973 -250.21042)
			(xy 365.481556 -250.164137) (xy 365.512089 -250.122113) (xy 365.54882 -250.085383) (xy 365.590845 -250.054851)
			(xy 365.637129 -250.031269) (xy 365.686532 -250.015219) (xy 365.737838 -250.007094) (xy 365.76381 -250.006612)
			(xy 365.789672 -250.007101) (xy 365.840764 -250.015149) (xy 365.889978 -250.031063) (xy 365.936109 -250.054454)
			(xy 365.978031 -250.08475) (xy 365.996728 -250.102624) (xy 366.006443 -250.111669) (xy 366.029452 -250.124881)
			(xy 366.055089 -250.131718) (xy 366.081623 -250.131718) (xy 366.10726 -250.124881) (xy 366.130269 -250.111669)
			(xy 366.139984 -250.102624) (xy 366.158674 -250.084744) (xy 366.200604 -250.054462) (xy 366.246738 -250.03108)
			(xy 366.295951 -250.015167) (xy 366.347041 -250.007112) (xy 366.372902 -250.006612) (xy 366.398866 -250.007189)
			(xy 366.450156 -250.015313) (xy 366.499543 -250.03136) (xy 366.545812 -250.054936) (xy 366.587823 -250.085459)
			(xy 366.624542 -250.122178) (xy 366.655065 -250.16419) (xy 366.678641 -250.210459) (xy 366.694687 -250.259846)
			(xy 366.702811 -250.311136) (xy 366.702811 -250.363064) (xy 366.694687 -250.414354) (xy 366.678641 -250.463741)
			(xy 366.655065 -250.51001) (xy 366.624542 -250.552022) (xy 366.587823 -250.588741) (xy 366.545812 -250.619264)
			(xy 366.499543 -250.64284) (xy 366.450156 -250.658887) (xy 366.398866 -250.667011) (xy 366.372902 -250.66752)
			(xy 366.347041 -250.667014) (xy 366.29595 -250.658969) (xy 366.246737 -250.643058) (xy 366.200605 -250.619671)
			(xy 366.158682 -250.58938) (xy 366.139984 -250.571508) (xy 366.130269 -250.562463) (xy 366.10726 -250.549251)
			(xy 366.081623 -250.542414) (xy 366.055089 -250.542414) (xy 366.029452 -250.549251) (xy 366.006443 -250.562463)
			(xy 365.996728 -250.571508) (xy 365.978038 -250.589387) (xy 365.936107 -250.619668) (xy 365.889973 -250.64305)
			(xy 365.840761 -250.658963) (xy 365.789671 -250.667019) (xy 365.76381 -250.66752) (xy 365.737838 -250.667106)
			(xy 365.686532 -250.658981) (xy 365.637129 -250.642931) (xy 365.590845 -250.619349) (xy 365.54882 -250.588817)
			(xy 365.512089 -250.552087) (xy 365.481556 -250.510063) (xy 365.457973 -250.46378) (xy 365.441921 -250.414378)
			(xy 365.433795 -250.363072) (xy 354.333836 -250.363072) (xy 354.325712 -250.414366) (xy 354.309661 -250.46376)
			(xy 354.286081 -250.510036) (xy 354.255552 -250.552052) (xy 354.218825 -250.588775) (xy 354.176805 -250.6193)
			(xy 354.130527 -250.642875) (xy 354.081131 -250.65892) (xy 354.029832 -250.66704) (xy 354.003864 -250.66752)
			(xy 353.97811 -250.667052) (xy 353.927223 -250.659067) (xy 353.878193 -250.64328) (xy 353.832208 -250.620075)
			(xy 353.790381 -250.590014) (xy 353.771708 -250.57227) (xy 353.762018 -250.563277) (xy 353.739086 -250.550145)
			(xy 353.713547 -250.54335) (xy 353.687121 -250.54335) (xy 353.661582 -250.550145) (xy 353.63865 -250.563277)
			(xy 353.62896 -250.57227) (xy 353.610293 -250.590018) (xy 353.568458 -250.620063) (xy 353.522469 -250.643258)
			(xy 353.47344 -250.65904) (xy 353.422557 -250.667028) (xy 353.396804 -250.66752) (xy 353.370832 -250.667105)
			(xy 353.319527 -250.65898) (xy 353.270125 -250.642929) (xy 353.223842 -250.619347) (xy 353.181818 -250.588815)
			(xy 353.145087 -250.552085) (xy 353.114555 -250.510062) (xy 353.090973 -250.463779) (xy 353.074921 -250.414377)
			(xy 353.066795 -250.363072) (xy 351.046159 -250.363072) (xy 351.056992 -250.377983) (xy 351.080571 -250.424263)
			(xy 351.096619 -250.473662) (xy 351.10474 -250.524964) (xy 351.105216 -250.550934) (xy 351.104786 -250.575487)
			(xy 351.097553 -250.624056) (xy 351.083208 -250.671018) (xy 351.062066 -250.715339) (xy 351.034595 -250.75604)
			(xy 351.018348 -250.774454) (xy 351.008547 -250.785942) (xy 350.99554 -250.813176) (xy 350.991079 -250.843025)
			(xy 350.995555 -250.872872) (xy 351.008576 -250.9001) (xy 351.018348 -250.911614) (xy 351.034606 -250.930017)
			(xy 351.062064 -250.970728) (xy 351.083199 -251.015052) (xy 351.097546 -251.062014) (xy 351.104789 -251.110581)
			(xy 351.105216 -251.135134) (xy 351.104731 -251.1611) (xy 351.096601 -251.212393) (xy 351.080548 -251.261783)
			(xy 351.056966 -251.308053) (xy 351.026436 -251.350064) (xy 350.98971 -251.386783) (xy 350.947691 -251.417303)
			(xy 350.901416 -251.440875) (xy 350.852023 -251.456918) (xy 350.800729 -251.465036) (xy 350.774762 -251.465588)
			(xy 350.752569 -251.465229) (xy 350.708581 -251.459295) (xy 350.66578 -251.44754) (xy 350.645222 -251.439172)
			(xy 350.631824 -251.433982) (xy 350.603318 -251.430497) (xy 350.574969 -251.435086) (xy 350.549018 -251.447386)
			(xy 350.527518 -251.466426) (xy 350.51217 -251.490698) (xy 350.504186 -251.518285) (xy 350.503744 -251.532644)
			(xy 350.503744 -251.849128) (xy 350.504164 -251.862692) (xy 350.511301 -251.888864) (xy 350.525088 -251.912227)
			(xy 350.54455 -251.931126) (xy 350.568307 -251.944222) (xy 350.594677 -251.950588) (xy 350.621792 -251.949774)
			(xy 350.647733 -251.941835) (xy 350.659446 -251.93498) (xy 350.679332 -251.922935) (xy 350.721763 -251.903934)
			(xy 350.766439 -251.891066) (xy 350.812476 -251.884583) (xy 350.835722 -251.88418) (xy 350.861689 -251.884665)
			(xy 350.912984 -251.892792) (xy 350.962375 -251.908845) (xy 351.008647 -251.932426) (xy 351.050661 -251.962956)
			(xy 351.087381 -251.999682) (xy 351.117903 -252.041701) (xy 351.141477 -252.087977) (xy 351.157521 -252.137371)
			(xy 351.16564 -252.188667) (xy 351.166176 -252.214634) (xy 351.165746 -252.239187) (xy 351.158515 -252.287757)
			(xy 351.144171 -252.334721) (xy 351.123033 -252.379044) (xy 351.095564 -252.419748) (xy 351.079308 -252.438154)
			(xy 351.069511 -252.449643) (xy 351.056509 -252.476878) (xy 351.05205 -252.506725) (xy 351.056524 -252.53657)
			(xy 351.069539 -252.563798) (xy 351.079308 -252.575314) (xy 351.095564 -252.593719) (xy 351.123017 -252.634431)
			(xy 351.134794 -252.659134) (xy 356.04323 -252.659134) (xy 356.043671 -252.634582) (xy 356.050913 -252.586016)
			(xy 356.065257 -252.539054) (xy 356.086388 -252.49473) (xy 356.113842 -252.454019) (xy 356.130098 -252.435614)
			(xy 356.139866 -252.424098) (xy 356.152881 -252.39687) (xy 356.157355 -252.367025) (xy 356.152896 -252.337178)
			(xy 356.139895 -252.309944) (xy 356.130098 -252.298454) (xy 356.113843 -252.280047) (xy 356.086374 -252.239343)
			(xy 356.065235 -252.195021) (xy 356.050891 -252.148057) (xy 356.04366 -252.099487) (xy 356.04323 -252.074934)
			(xy 356.043739 -252.048967) (xy 356.051864 -251.997672) (xy 356.067912 -251.948279) (xy 356.09149 -251.902005)
			(xy 356.122016 -251.859989) (xy 356.158739 -251.823266) (xy 356.200755 -251.79274) (xy 356.247029 -251.769162)
			(xy 356.296422 -251.753114) (xy 356.347717 -251.744989) (xy 356.399651 -251.744989) (xy 356.450946 -251.753114)
			(xy 356.500339 -251.769162) (xy 356.546613 -251.79274) (xy 356.588629 -251.823266) (xy 356.625352 -251.859989)
			(xy 356.655878 -251.902005) (xy 356.679456 -251.948279) (xy 356.695504 -251.997672) (xy 356.703629 -252.048967)
			(xy 356.704138 -252.074934) (xy 356.703686 -252.099486) (xy 356.696448 -252.148052) (xy 356.682107 -252.195014)
			(xy 356.660978 -252.239338) (xy 356.633525 -252.280049) (xy 356.61727 -252.298454) (xy 356.60743 -252.309915)
			(xy 356.594414 -252.337162) (xy 356.589949 -252.367025) (xy 356.594428 -252.396887) (xy 356.607458 -252.424126)
			(xy 356.61727 -252.435614) (xy 356.633552 -252.453998) (xy 356.661018 -252.494708) (xy 356.682153 -252.539036)
			(xy 356.69649 -252.586005) (xy 356.703713 -252.634579) (xy 356.704138 -252.659134) (xy 356.703629 -252.685101)
			(xy 356.695504 -252.736396) (xy 356.679456 -252.785789) (xy 356.669315 -252.805692) (xy 363.042962 -252.805692)
			(xy 363.04343 -252.781141) (xy 363.050664 -252.732575) (xy 363.065001 -252.685614) (xy 363.086127 -252.641289)
			(xy 363.113576 -252.600577) (xy 363.12983 -252.582172) (xy 363.139645 -252.570691) (xy 363.152664 -252.543452)
			(xy 363.157133 -252.513594) (xy 363.15266 -252.483737) (xy 363.139638 -252.456499) (xy 363.12983 -252.445012)
			(xy 363.11356 -252.426618) (xy 363.086092 -252.385911) (xy 363.064955 -252.341585) (xy 363.050616 -252.294618)
			(xy 363.043389 -252.246046) (xy 363.042962 -252.221492) (xy 363.043471 -252.195525) (xy 363.051596 -252.14423)
			(xy 363.067644 -252.094837) (xy 363.091222 -252.048563) (xy 363.121748 -252.006547) (xy 363.158471 -251.969824)
			(xy 363.200487 -251.939298) (xy 363.246761 -251.91572) (xy 363.296154 -251.899672) (xy 363.347449 -251.891547)
			(xy 363.399383 -251.891547) (xy 363.450678 -251.899672) (xy 363.500071 -251.91572) (xy 363.546345 -251.939298)
			(xy 363.588361 -251.969824) (xy 363.625084 -252.006547) (xy 363.65561 -252.048563) (xy 363.679188 -252.094837)
			(xy 363.695236 -252.14423) (xy 363.703361 -252.195525) (xy 363.70387 -252.221492) (xy 363.703445 -252.246044)
			(xy 363.696199 -252.294612) (xy 363.681851 -252.341573) (xy 363.660716 -252.385897) (xy 363.633259 -252.426608)
			(xy 363.617002 -252.445012) (xy 363.607208 -252.456508) (xy 363.594197 -252.483743) (xy 363.589728 -252.513594)
			(xy 363.594193 -252.543446) (xy 363.607202 -252.570682) (xy 363.617002 -252.582172) (xy 363.63327 -252.600568)
			(xy 363.660737 -252.641275) (xy 363.681873 -252.6856) (xy 363.696214 -252.732566) (xy 363.703442 -252.781138)
			(xy 363.70387 -252.805692) (xy 363.703361 -252.831659) (xy 363.695236 -252.882954) (xy 363.679188 -252.932347)
			(xy 363.65561 -252.978621) (xy 363.625084 -253.020637) (xy 363.588361 -253.05736) (xy 363.546345 -253.087886)
			(xy 363.500071 -253.111464) (xy 363.450678 -253.127512) (xy 363.399383 -253.135637) (xy 363.347449 -253.135637)
			(xy 363.296154 -253.127512) (xy 363.246761 -253.111464) (xy 363.200487 -253.087886) (xy 363.158471 -253.05736)
			(xy 363.121748 -253.020637) (xy 363.091222 -252.978621) (xy 363.067644 -252.932347) (xy 363.051596 -252.882954)
			(xy 363.043471 -252.831659) (xy 363.042962 -252.805692) (xy 356.669315 -252.805692) (xy 356.655878 -252.832063)
			(xy 356.625352 -252.874079) (xy 356.588629 -252.910802) (xy 356.546613 -252.941328) (xy 356.500339 -252.964906)
			(xy 356.450946 -252.980954) (xy 356.399651 -252.989079) (xy 356.347717 -252.989079) (xy 356.296422 -252.980954)
			(xy 356.247029 -252.964906) (xy 356.200755 -252.941328) (xy 356.158739 -252.910802) (xy 356.122016 -252.874079)
			(xy 356.09149 -252.832063) (xy 356.067912 -252.785789) (xy 356.051864 -252.736396) (xy 356.043739 -252.685101)
			(xy 356.04323 -252.659134) (xy 351.134794 -252.659134) (xy 351.144148 -252.678754) (xy 351.158492 -252.725716)
			(xy 351.165733 -252.774282) (xy 351.166176 -252.798834) (xy 351.165664 -252.8248) (xy 351.157536 -252.876092)
			(xy 351.141484 -252.925482) (xy 351.117905 -252.971753) (xy 351.087379 -253.013766) (xy 351.050656 -253.050487)
			(xy 351.008642 -253.081012) (xy 350.962371 -253.104589) (xy 350.912981 -253.120639) (xy 350.861688 -253.128765)
			(xy 350.835722 -253.129288) (xy 350.812473 -253.128915) (xy 350.76643 -253.122438) (xy 350.721751 -253.109569)
			(xy 350.679317 -253.09056) (xy 350.659446 -253.078488) (xy 350.647743 -253.071625) (xy 350.621797 -253.063728)
			(xy 350.594688 -253.062939) (xy 350.568327 -253.069315) (xy 350.544574 -253.082405) (xy 350.525105 -253.101286)
			(xy 350.511293 -253.124627) (xy 350.504112 -253.15078) (xy 350.503744 -253.16434) (xy 350.503744 -253.665736)
			(xy 350.523671 -253.682986) (xy 350.558315 -253.722701) (xy 350.586216 -253.767412) (xy 350.606665 -253.815985)
			(xy 350.619144 -253.867188) (xy 350.623337 -253.919723) (xy 350.619137 -253.972257) (xy 350.606651 -254.023459)
			(xy 350.599276 -254.040971) (xy 353.066815 -254.040971) (xy 353.066815 -253.989029) (xy 353.07494 -253.937728)
			(xy 353.090991 -253.888329) (xy 353.114572 -253.842049) (xy 353.145103 -253.800028) (xy 353.181831 -253.7633)
			(xy 353.223852 -253.73277) (xy 353.270132 -253.70919) (xy 353.319532 -253.693139) (xy 353.370833 -253.685015)
			(xy 353.396804 -253.684532) (xy 353.422558 -253.685005) (xy 353.473445 -253.692987) (xy 353.522475 -253.708771)
			(xy 353.568461 -253.731976) (xy 353.610287 -253.762038) (xy 353.62896 -253.779782) (xy 353.63865 -253.788775)
			(xy 353.661582 -253.801907) (xy 353.687121 -253.808702) (xy 353.713547 -253.808702) (xy 353.739086 -253.801907)
			(xy 353.762018 -253.788775) (xy 353.771708 -253.779782) (xy 353.790381 -253.762041) (xy 353.832216 -253.731997)
			(xy 353.878203 -253.708802) (xy 353.92723 -253.693018) (xy 353.978111 -253.685027) (xy 354.003864 -253.684532)
			(xy 354.029834 -253.68504) (xy 354.081135 -253.69316) (xy 354.130535 -253.709206) (xy 354.176815 -253.732783)
			(xy 354.218838 -253.76331) (xy 354.255567 -253.800035) (xy 354.286098 -253.842054) (xy 354.30968 -253.888332)
			(xy 354.325731 -253.93773) (xy 354.326994 -253.945703) (xy 361.239817 -253.945703) (xy 361.239817 -253.893769)
			(xy 361.247942 -253.842474) (xy 361.26399 -253.793081) (xy 361.287568 -253.746807) (xy 361.318094 -253.704791)
			(xy 361.354817 -253.668068) (xy 361.396833 -253.637542) (xy 361.443107 -253.613964) (xy 361.4925 -253.597916)
			(xy 361.543795 -253.589791) (xy 361.595729 -253.589791) (xy 361.647024 -253.597916) (xy 361.696417 -253.613964)
			(xy 361.742691 -253.637542) (xy 361.784707 -253.668068) (xy 361.82143 -253.704791) (xy 361.851956 -253.746807)
			(xy 361.875534 -253.793081) (xy 361.891582 -253.842474) (xy 361.899707 -253.893769) (xy 361.900216 -253.919736)
			(xy 361.899707 -253.945703) (xy 361.891582 -253.996998) (xy 361.877295 -254.040971) (xy 365.433815 -254.040971)
			(xy 365.433815 -253.989029) (xy 365.441941 -253.937727) (xy 365.457992 -253.888327) (xy 365.481573 -253.842047)
			(xy 365.512104 -253.800026) (xy 365.548833 -253.763298) (xy 365.590856 -253.732768) (xy 365.637137 -253.709188)
			(xy 365.686537 -253.693138) (xy 365.737839 -253.685014) (xy 365.76381 -253.684532) (xy 365.78967 -253.685043)
			(xy 365.840761 -253.69309) (xy 365.889974 -253.709) (xy 365.936105 -253.732385) (xy 365.978029 -253.762674)
			(xy 365.996728 -253.780544) (xy 366.006443 -253.789589) (xy 366.029452 -253.802801) (xy 366.055089 -253.809638)
			(xy 366.081623 -253.809638) (xy 366.10726 -253.802801) (xy 366.130269 -253.789589) (xy 366.139984 -253.780544)
			(xy 366.158678 -253.762668) (xy 366.200606 -253.732384) (xy 366.246739 -253.709001) (xy 366.295951 -253.693087)
			(xy 366.347041 -253.685032) (xy 366.372902 -253.684532) (xy 366.398868 -253.685069) (xy 366.450161 -253.693194)
			(xy 366.499551 -253.709242) (xy 366.545823 -253.732819) (xy 366.587836 -253.763344) (xy 366.624558 -253.800065)
			(xy 366.655082 -253.842079) (xy 366.678659 -253.888351) (xy 366.694707 -253.937741) (xy 366.702831 -253.989034)
			(xy 366.702831 -254.040966) (xy 366.694707 -254.092259) (xy 366.678659 -254.141649) (xy 366.655082 -254.187921)
			(xy 366.624558 -254.229935) (xy 366.587836 -254.266656) (xy 366.545823 -254.297181) (xy 366.499551 -254.320758)
			(xy 366.450161 -254.336806) (xy 366.398868 -254.344931) (xy 366.372902 -254.34544) (xy 366.347042 -254.344929)
			(xy 366.295951 -254.336883) (xy 366.246738 -254.320974) (xy 366.200606 -254.297588) (xy 366.158683 -254.267299)
			(xy 366.139984 -254.249428) (xy 366.130269 -254.240383) (xy 366.10726 -254.227171) (xy 366.081623 -254.220334)
			(xy 366.055089 -254.220334) (xy 366.029452 -254.227171) (xy 366.006443 -254.240383) (xy 365.996728 -254.249428)
			(xy 365.978041 -254.267311) (xy 365.936109 -254.297591) (xy 365.889974 -254.320972) (xy 365.840761 -254.336884)
			(xy 365.789671 -254.344939) (xy 365.76381 -254.34544) (xy 365.737839 -254.344986) (xy 365.686537 -254.336862)
			(xy 365.637137 -254.320812) (xy 365.590856 -254.297232) (xy 365.548833 -254.266702) (xy 365.512104 -254.229974)
			(xy 365.481573 -254.187953) (xy 365.457992 -254.141673) (xy 365.441941 -254.092273) (xy 365.433815 -254.040971)
			(xy 361.877295 -254.040971) (xy 361.875534 -254.046391) (xy 361.851956 -254.092665) (xy 361.82143 -254.134681)
			(xy 361.784707 -254.171404) (xy 361.742691 -254.20193) (xy 361.696417 -254.225508) (xy 361.647024 -254.241556)
			(xy 361.595729 -254.249681) (xy 361.543795 -254.249681) (xy 361.4925 -254.241556) (xy 361.443107 -254.225508)
			(xy 361.396833 -254.20193) (xy 361.354817 -254.171404) (xy 361.318094 -254.134681) (xy 361.287568 -254.092665)
			(xy 361.26399 -254.046391) (xy 361.247942 -253.996998) (xy 361.239817 -253.945703) (xy 354.326994 -253.945703)
			(xy 354.333857 -253.98903) (xy 354.333857 -254.04097) (xy 354.325731 -254.09227) (xy 354.30968 -254.141668)
			(xy 354.286098 -254.187946) (xy 354.255567 -254.229965) (xy 354.218838 -254.26669) (xy 354.176815 -254.297217)
			(xy 354.130535 -254.320794) (xy 354.081135 -254.33684) (xy 354.029834 -254.34496) (xy 354.003864 -254.34544)
			(xy 353.97811 -254.344966) (xy 353.927224 -254.336982) (xy 353.878194 -254.321197) (xy 353.832209 -254.297993)
			(xy 353.790382 -254.267933) (xy 353.771708 -254.25019) (xy 353.762018 -254.241197) (xy 353.739086 -254.228065)
			(xy 353.713547 -254.22127) (xy 353.687121 -254.22127) (xy 353.661582 -254.228065) (xy 353.63865 -254.241197)
			(xy 353.62896 -254.25019) (xy 353.610296 -254.267941) (xy 353.56846 -254.297985) (xy 353.52247 -254.321179)
			(xy 353.473441 -254.33696) (xy 353.422557 -254.344948) (xy 353.396804 -254.34544) (xy 353.370833 -254.344985)
			(xy 353.319532 -254.336861) (xy 353.270132 -254.32081) (xy 353.223852 -254.29723) (xy 353.181831 -254.2667)
			(xy 353.145103 -254.229972) (xy 353.114572 -254.187951) (xy 353.090991 -254.141671) (xy 353.07494 -254.092272)
			(xy 353.066815 -254.040971) (xy 350.599276 -254.040971) (xy 350.586195 -254.072029) (xy 350.558288 -254.116736)
			(xy 350.523638 -254.156446) (xy 350.503744 -254.173736) (xy 350.503744 -254.759519) (xy 357.950517 -254.759519)
			(xy 357.950517 -254.707585) (xy 357.958642 -254.65629) (xy 357.97469 -254.606897) (xy 357.998268 -254.560623)
			(xy 358.028794 -254.518607) (xy 358.065517 -254.481884) (xy 358.107533 -254.451358) (xy 358.153807 -254.42778)
			(xy 358.2032 -254.411732) (xy 358.254495 -254.403607) (xy 358.306429 -254.403607) (xy 358.357724 -254.411732)
			(xy 358.407117 -254.42778) (xy 358.453391 -254.451358) (xy 358.495407 -254.481884) (xy 358.53213 -254.518607)
			(xy 358.562656 -254.560623) (xy 358.586234 -254.606897) (xy 358.602282 -254.65629) (xy 358.610407 -254.707585)
			(xy 358.610916 -254.733552) (xy 358.610407 -254.759519) (xy 358.602282 -254.810814) (xy 358.586234 -254.860207)
			(xy 358.562656 -254.906481) (xy 358.53213 -254.948497) (xy 358.495407 -254.98522) (xy 358.453391 -255.015746)
			(xy 358.407117 -255.039324) (xy 358.357724 -255.055372) (xy 358.306429 -255.063497) (xy 358.254495 -255.063497)
			(xy 358.2032 -255.055372) (xy 358.153807 -255.039324) (xy 358.107533 -255.015746) (xy 358.065517 -254.98522)
			(xy 358.028794 -254.948497) (xy 357.998268 -254.906481) (xy 357.97469 -254.860207) (xy 357.958642 -254.810814)
			(xy 357.950517 -254.759519) (xy 350.503744 -254.759519) (xy 350.503744 -254.889) (xy 350.504209 -254.903172)
			(xy 350.511996 -254.930426) (xy 350.52697 -254.954491) (xy 350.547979 -254.973518) (xy 350.573407 -254.986041)
			(xy 350.601296 -254.991096) (xy 350.629502 -254.988295) (xy 350.655852 -254.977854) (xy 350.66732 -254.969518)
			(xy 350.689131 -254.953434) (xy 350.736897 -254.927845) (xy 350.788192 -254.910376) (xy 350.841648 -254.901494)
			(xy 350.868742 -254.900938) (xy 350.894707 -254.90145) (xy 350.945998 -254.90958) (xy 350.995385 -254.925632)
			(xy 351.041654 -254.949212) (xy 351.083665 -254.979739) (xy 351.120383 -255.016461) (xy 351.150906 -255.058475)
			(xy 351.174481 -255.104746) (xy 351.190528 -255.154135) (xy 351.198652 -255.205427) (xy 351.199196 -255.231392)
			(xy 351.198709 -255.256092) (xy 351.191309 -255.304936) (xy 351.176731 -255.352138) (xy 351.1553 -255.396649)
			(xy 351.127491 -255.43748) (xy 351.111058 -255.455928) (xy 351.10114 -255.467444) (xy 351.087943 -255.494802)
			(xy 351.083376 -255.524831) (xy 351.087844 -255.554876) (xy 351.10095 -255.582278) (xy 351.110804 -255.59385)
			(xy 351.12714 -255.612246) (xy 351.154742 -255.652971) (xy 351.175996 -255.69734) (xy 351.190431 -255.744372)
			(xy 351.197727 -255.793025) (xy 351.19818 -255.817624) (xy 351.197669 -255.843591) (xy 351.189542 -255.894884)
			(xy 351.173491 -255.944275) (xy 351.149913 -255.990548) (xy 351.119387 -256.032563) (xy 351.082664 -256.069285)
			(xy 351.04065 -256.099812) (xy 350.994377 -256.123391) (xy 350.944986 -256.139441) (xy 350.893693 -256.147569)
			(xy 350.867726 -256.148078) (xy 350.840758 -256.147548) (xy 350.787536 -256.138801) (xy 350.736438 -256.121536)
			(xy 350.688818 -256.09621) (xy 350.667066 -256.08026) (xy 350.655559 -256.072028) (xy 350.629249 -256.061649)
			(xy 350.601102 -256.058887) (xy 350.573277 -256.063953) (xy 350.547909 -256.076457) (xy 350.526945 -256.095442)
			(xy 350.511993 -256.119449) (xy 350.504202 -256.146637) (xy 350.503744 -256.160778) (xy 350.503744 -256.330196)
			(xy 356.04323 -256.330196) (xy 356.043648 -256.305643) (xy 356.050895 -256.257076) (xy 356.065245 -256.210114)
			(xy 356.086382 -256.165791) (xy 356.11384 -256.12508) (xy 356.130098 -256.106676) (xy 356.139903 -256.095189)
			(xy 356.152914 -256.067951) (xy 356.15738 -256.038097) (xy 356.152912 -256.008244) (xy 356.1399 -255.981006)
			(xy 356.130098 -255.969516) (xy 356.113825 -255.951124) (xy 356.086359 -255.910416) (xy 356.065223 -255.86609)
			(xy 356.050884 -255.819123) (xy 356.043657 -255.77055) (xy 356.04323 -255.745996) (xy 356.043739 -255.720029)
			(xy 356.051864 -255.668734) (xy 356.067912 -255.619341) (xy 356.09149 -255.573067) (xy 356.122016 -255.531051)
			(xy 356.158739 -255.494328) (xy 356.200755 -255.463802) (xy 356.247029 -255.440224) (xy 356.296422 -255.424176)
			(xy 356.347717 -255.416051) (xy 356.399651 -255.416051) (xy 356.450946 -255.424176) (xy 356.500339 -255.440224)
			(xy 356.546613 -255.463802) (xy 356.588629 -255.494328) (xy 356.625352 -255.531051) (xy 356.655878 -255.573067)
			(xy 356.656144 -255.573589) (xy 361.239817 -255.573589) (xy 361.239817 -255.521655) (xy 361.247942 -255.47036)
			(xy 361.26399 -255.420967) (xy 361.287568 -255.374693) (xy 361.318094 -255.332677) (xy 361.354817 -255.295954)
			(xy 361.396833 -255.265428) (xy 361.443107 -255.24185) (xy 361.4925 -255.225802) (xy 361.543795 -255.217677)
			(xy 361.595729 -255.217677) (xy 361.647024 -255.225802) (xy 361.696417 -255.24185) (xy 361.742691 -255.265428)
			(xy 361.784707 -255.295954) (xy 361.82143 -255.332677) (xy 361.851956 -255.374693) (xy 361.875534 -255.420967)
			(xy 361.891582 -255.47036) (xy 361.899707 -255.521655) (xy 361.900216 -255.547622) (xy 361.899707 -255.573589)
			(xy 361.891582 -255.624884) (xy 361.875534 -255.674277) (xy 361.851956 -255.720551) (xy 361.82143 -255.762567)
			(xy 361.784707 -255.79929) (xy 361.742691 -255.829816) (xy 361.696417 -255.853394) (xy 361.647024 -255.869442)
			(xy 361.595729 -255.877567) (xy 361.543795 -255.877567) (xy 361.4925 -255.869442) (xy 361.443107 -255.853394)
			(xy 361.396833 -255.829816) (xy 361.354817 -255.79929) (xy 361.318094 -255.762567) (xy 361.287568 -255.720551)
			(xy 361.26399 -255.674277) (xy 361.247942 -255.624884) (xy 361.239817 -255.573589) (xy 356.656144 -255.573589)
			(xy 356.679456 -255.619341) (xy 356.695504 -255.668734) (xy 356.703629 -255.720029) (xy 356.704138 -255.745996)
			(xy 356.703723 -255.770549) (xy 356.696476 -255.819117) (xy 356.682126 -255.866079) (xy 356.660989 -255.910403)
			(xy 356.633529 -255.951113) (xy 356.61727 -255.969516) (xy 356.607467 -255.981006) (xy 356.594446 -256.008242)
			(xy 356.589975 -256.038097) (xy 356.594445 -256.067952) (xy 356.607463 -256.095189) (xy 356.61727 -256.106676)
			(xy 356.633534 -256.125075) (xy 356.661003 -256.165781) (xy 356.682141 -256.210105) (xy 356.696482 -256.257071)
			(xy 356.70371 -256.305642) (xy 356.704138 -256.330196) (xy 356.703629 -256.356163) (xy 356.69868 -256.387405)
			(xy 357.950517 -256.387405) (xy 357.950517 -256.335471) (xy 357.958642 -256.284176) (xy 357.97469 -256.234783)
			(xy 357.998268 -256.188509) (xy 358.028794 -256.146493) (xy 358.065517 -256.10977) (xy 358.107533 -256.079244)
			(xy 358.153807 -256.055666) (xy 358.2032 -256.039618) (xy 358.254495 -256.031493) (xy 358.306429 -256.031493)
			(xy 358.357724 -256.039618) (xy 358.407117 -256.055666) (xy 358.453391 -256.079244) (xy 358.495407 -256.10977)
			(xy 358.53213 -256.146493) (xy 358.562656 -256.188509) (xy 358.586234 -256.234783) (xy 358.602282 -256.284176)
			(xy 358.610407 -256.335471) (xy 358.610916 -256.361438) (xy 358.610407 -256.387405) (xy 358.610054 -256.389632)
			(xy 363.037882 -256.389632) (xy 363.038308 -256.365079) (xy 363.045552 -256.316512) (xy 363.059899 -256.26955)
			(xy 363.081034 -256.225226) (xy 363.108492 -256.184515) (xy 363.12475 -256.166112) (xy 363.134524 -256.154599)
			(xy 363.147545 -256.127371) (xy 363.152021 -256.097524) (xy 363.147559 -256.067674) (xy 363.134551 -256.04044)
			(xy 363.12475 -256.028952) (xy 363.108502 -256.010539) (xy 363.08103 -255.969837) (xy 363.059889 -255.925517)
			(xy 363.045544 -255.878554) (xy 363.038312 -255.829985) (xy 363.037882 -255.805432) (xy 363.038391 -255.779465)
			(xy 363.046516 -255.72817) (xy 363.062564 -255.678777) (xy 363.086142 -255.632503) (xy 363.116668 -255.590487)
			(xy 363.153391 -255.553764) (xy 363.195407 -255.523238) (xy 363.241681 -255.49966) (xy 363.291074 -255.483612)
			(xy 363.342369 -255.475487) (xy 363.394303 -255.475487) (xy 363.445598 -255.483612) (xy 363.494991 -255.49966)
			(xy 363.541265 -255.523238) (xy 363.583281 -255.553764) (xy 363.620004 -255.590487) (xy 363.65053 -255.632503)
			(xy 363.674108 -255.678777) (xy 363.690156 -255.72817) (xy 363.698281 -255.779465) (xy 363.69879 -255.805432)
			(xy 363.698349 -255.829984) (xy 363.691111 -255.878551) (xy 363.676767 -255.925514) (xy 363.655635 -255.969838)
			(xy 363.628179 -256.010548) (xy 363.611922 -256.028952) (xy 363.602088 -256.040417) (xy 363.589078 -256.067663)
			(xy 363.584615 -256.097524) (xy 363.589092 -256.127383) (xy 363.602114 -256.154623) (xy 363.611922 -256.166112)
			(xy 363.628212 -256.18449) (xy 363.655675 -256.225202) (xy 363.676807 -256.269532) (xy 363.691142 -256.316502)
			(xy 363.698365 -256.365077) (xy 363.69879 -256.389632) (xy 363.698281 -256.415599) (xy 363.690156 -256.466894)
			(xy 363.674108 -256.516287) (xy 363.65053 -256.562561) (xy 363.620004 -256.604577) (xy 363.583281 -256.6413)
			(xy 363.541265 -256.671826) (xy 363.494991 -256.695404) (xy 363.445598 -256.711452) (xy 363.394303 -256.719577)
			(xy 363.342369 -256.719577) (xy 363.291074 -256.711452) (xy 363.241681 -256.695404) (xy 363.195407 -256.671826)
			(xy 363.153391 -256.6413) (xy 363.116668 -256.604577) (xy 363.086142 -256.562561) (xy 363.062564 -256.516287)
			(xy 363.046516 -256.466894) (xy 363.038391 -256.415599) (xy 363.037882 -256.389632) (xy 358.610054 -256.389632)
			(xy 358.602282 -256.4387) (xy 358.586234 -256.488093) (xy 358.562656 -256.534367) (xy 358.53213 -256.576383)
			(xy 358.495407 -256.613106) (xy 358.453391 -256.643632) (xy 358.407117 -256.66721) (xy 358.357724 -256.683258)
			(xy 358.306429 -256.691383) (xy 358.254495 -256.691383) (xy 358.2032 -256.683258) (xy 358.153807 -256.66721)
			(xy 358.107533 -256.643632) (xy 358.065517 -256.613106) (xy 358.028794 -256.576383) (xy 357.998268 -256.534367)
			(xy 357.97469 -256.488093) (xy 357.958642 -256.4387) (xy 357.950517 -256.387405) (xy 356.69868 -256.387405)
			(xy 356.695504 -256.407458) (xy 356.679456 -256.456851) (xy 356.655878 -256.503125) (xy 356.625352 -256.545141)
			(xy 356.588629 -256.581864) (xy 356.546613 -256.61239) (xy 356.500339 -256.635968) (xy 356.450946 -256.652016)
			(xy 356.399651 -256.660141) (xy 356.347717 -256.660141) (xy 356.296422 -256.652016) (xy 356.247029 -256.635968)
			(xy 356.200755 -256.61239) (xy 356.158739 -256.581864) (xy 356.122016 -256.545141) (xy 356.09149 -256.503125)
			(xy 356.067912 -256.456851) (xy 356.051864 -256.407458) (xy 356.043739 -256.356163) (xy 356.04323 -256.330196)
			(xy 350.503744 -256.330196) (xy 350.503744 -256.921254) (xy 350.523677 -256.938504) (xy 350.558335 -256.978221)
			(xy 350.586248 -257.022936) (xy 350.606709 -257.071515) (xy 350.619198 -257.122726) (xy 350.6234 -257.175271)
			(xy 350.62133 -257.201221) (xy 361.239817 -257.201221) (xy 361.239817 -257.149287) (xy 361.247942 -257.097992)
			(xy 361.26399 -257.048599) (xy 361.287568 -257.002325) (xy 361.318094 -256.960309) (xy 361.354817 -256.923586)
			(xy 361.396833 -256.89306) (xy 361.443107 -256.869482) (xy 361.4925 -256.853434) (xy 361.543795 -256.845309)
			(xy 361.595729 -256.845309) (xy 361.647024 -256.853434) (xy 361.696417 -256.869482) (xy 361.742691 -256.89306)
			(xy 361.784707 -256.923586) (xy 361.82143 -256.960309) (xy 361.851956 -257.002325) (xy 361.875534 -257.048599)
			(xy 361.891582 -257.097992) (xy 361.899707 -257.149287) (xy 361.900216 -257.175254) (xy 361.899707 -257.201221)
			(xy 361.891582 -257.252516) (xy 361.875534 -257.301909) (xy 361.851956 -257.348183) (xy 361.82143 -257.390199)
			(xy 361.784707 -257.426922) (xy 361.742691 -257.457448) (xy 361.696417 -257.481026) (xy 361.647024 -257.497074)
			(xy 361.595729 -257.505199) (xy 361.543795 -257.505199) (xy 361.4925 -257.497074) (xy 361.443107 -257.481026)
			(xy 361.396833 -257.457448) (xy 361.354817 -257.426922) (xy 361.318094 -257.390199) (xy 361.287568 -257.348183)
			(xy 361.26399 -257.301909) (xy 361.247942 -257.252516) (xy 361.239817 -257.201221) (xy 350.62133 -257.201221)
			(xy 350.619208 -257.227816) (xy 350.606727 -257.279029) (xy 350.586275 -257.327612) (xy 350.55837 -257.372331)
			(xy 350.523719 -257.412054) (xy 350.503744 -257.429254) (xy 350.503744 -257.718869) (xy 351.009435 -257.718869)
			(xy 351.009435 -257.666931) (xy 351.01756 -257.615632) (xy 351.03361 -257.566236) (xy 351.057189 -257.519959)
			(xy 351.087718 -257.477941) (xy 351.124444 -257.441215) (xy 351.166463 -257.410687) (xy 351.21274 -257.387108)
			(xy 351.262136 -257.371059) (xy 351.313435 -257.362935) (xy 351.339404 -257.362452) (xy 351.363957 -257.362864)
			(xy 351.412525 -257.370112) (xy 351.459487 -257.384463) (xy 351.50381 -257.405601) (xy 351.544521 -257.433061)
			(xy 351.562924 -257.44932) (xy 351.574413 -257.459123) (xy 351.60165 -257.472137) (xy 351.631504 -257.476605)
			(xy 351.661358 -257.472137) (xy 351.688595 -257.459123) (xy 351.700084 -257.44932) (xy 351.718479 -257.43305)
			(xy 351.759186 -257.405583) (xy 351.803511 -257.384446) (xy 351.850478 -257.370106) (xy 351.89905 -257.362879)
			(xy 351.923604 -257.362452) (xy 351.948157 -257.362864) (xy 351.996725 -257.370112) (xy 352.043687 -257.384463)
			(xy 352.08801 -257.405601) (xy 352.128721 -257.433061) (xy 352.147124 -257.44932) (xy 352.158613 -257.459123)
			(xy 352.18585 -257.472137) (xy 352.215704 -257.476605) (xy 352.245558 -257.472137) (xy 352.272795 -257.459123)
			(xy 352.284284 -257.44932) (xy 352.302679 -257.43305) (xy 352.343386 -257.405583) (xy 352.387711 -257.384446)
			(xy 352.434678 -257.370106) (xy 352.48325 -257.362879) (xy 352.507804 -257.362452) (xy 352.533771 -257.36295)
			(xy 352.585067 -257.371075) (xy 352.63446 -257.387124) (xy 352.680734 -257.410702) (xy 352.72275 -257.441229)
			(xy 352.759473 -257.477953) (xy 352.79 -257.519969) (xy 352.813578 -257.566244) (xy 352.829626 -257.615637)
			(xy 352.837751 -257.666933) (xy 352.837751 -257.718867) (xy 352.837751 -257.718869) (xy 353.066835 -257.718869)
			(xy 353.066835 -257.666931) (xy 353.07496 -257.615632) (xy 353.09101 -257.566236) (xy 353.114589 -257.519959)
			(xy 353.145118 -257.477941) (xy 353.181844 -257.441215) (xy 353.223863 -257.410687) (xy 353.27014 -257.387108)
			(xy 353.319536 -257.371059) (xy 353.370835 -257.362935) (xy 353.396804 -257.362452) (xy 353.422557 -257.362948)
			(xy 353.473442 -257.370928) (xy 353.522471 -257.386708) (xy 353.568457 -257.409907) (xy 353.610285 -257.439962)
			(xy 353.62896 -257.457702) (xy 353.63865 -257.466695) (xy 353.661582 -257.479827) (xy 353.687121 -257.486622)
			(xy 353.713547 -257.486622) (xy 353.739086 -257.479827) (xy 353.762018 -257.466695) (xy 353.771708 -257.457702)
			(xy 353.790385 -257.439965) (xy 353.832218 -257.409919) (xy 353.878204 -257.386723) (xy 353.92723 -257.370938)
			(xy 353.978112 -257.362947) (xy 354.003864 -257.362452) (xy 354.029836 -257.36292) (xy 354.08114 -257.371041)
			(xy 354.130542 -257.387088) (xy 354.176826 -257.410666) (xy 354.218851 -257.441195) (xy 354.255582 -257.477922)
			(xy 354.286115 -257.519944) (xy 354.309698 -257.566224) (xy 354.325751 -257.615625) (xy 354.333877 -257.666928)
			(xy 354.333877 -257.718872) (xy 354.325751 -257.770175) (xy 354.309698 -257.819576) (xy 354.286115 -257.865856)
			(xy 354.255582 -257.907878) (xy 354.218851 -257.944605) (xy 354.176826 -257.975134) (xy 354.130542 -257.998712)
			(xy 354.08114 -258.014759) (xy 354.079384 -258.015037) (xy 357.950517 -258.015037) (xy 357.950517 -257.963103)
			(xy 357.958642 -257.911808) (xy 357.97469 -257.862415) (xy 357.998268 -257.816141) (xy 358.028794 -257.774125)
			(xy 358.065517 -257.737402) (xy 358.107533 -257.706876) (xy 358.153807 -257.683298) (xy 358.2032 -257.66725)
			(xy 358.254495 -257.659125) (xy 358.306429 -257.659125) (xy 358.357724 -257.66725) (xy 358.407117 -257.683298)
			(xy 358.453391 -257.706876) (xy 358.469898 -257.718869) (xy 365.433835 -257.718869) (xy 365.433835 -257.666931)
			(xy 365.44196 -257.615632) (xy 365.45801 -257.566235) (xy 365.48159 -257.519958) (xy 365.51212 -257.477939)
			(xy 365.548846 -257.441213) (xy 365.590866 -257.410685) (xy 365.637144 -257.387106) (xy 365.686541 -257.371058)
			(xy 365.737841 -257.362934) (xy 365.76381 -257.362452) (xy 365.789671 -257.362958) (xy 365.840762 -257.371005)
			(xy 365.889975 -257.386916) (xy 365.936106 -257.410303) (xy 365.978029 -257.440593) (xy 365.996728 -257.458464)
			(xy 366.006443 -257.467509) (xy 366.029452 -257.480721) (xy 366.055089 -257.487558) (xy 366.081623 -257.487558)
			(xy 366.10726 -257.480721) (xy 366.130269 -257.467509) (xy 366.139984 -257.458464) (xy 366.158664 -257.440574)
			(xy 366.200598 -257.410296) (xy 366.246735 -257.386916) (xy 366.295949 -257.371006) (xy 366.347041 -257.362952)
			(xy 366.372902 -257.362452) (xy 366.39887 -257.362949) (xy 366.450165 -257.371074) (xy 366.499559 -257.387123)
			(xy 366.545833 -257.410702) (xy 366.587849 -257.441228) (xy 366.624573 -257.477952) (xy 366.6551 -257.519969)
			(xy 366.678678 -257.566243) (xy 366.694726 -257.615637) (xy 366.702851 -257.666932) (xy 366.702851 -257.718868)
			(xy 366.694726 -257.770163) (xy 366.678678 -257.819557) (xy 366.6551 -257.865831) (xy 366.624573 -257.907848)
			(xy 366.587849 -257.944572) (xy 366.545833 -257.975098) (xy 366.499559 -257.998677) (xy 366.450165 -258.014726)
			(xy 366.39887 -258.022851) (xy 366.372902 -258.02336) (xy 366.347042 -258.022843) (xy 366.295951 -258.014798)
			(xy 366.246739 -257.99889) (xy 366.200607 -257.975506) (xy 366.158683 -257.945218) (xy 366.139984 -257.927348)
			(xy 366.130269 -257.918303) (xy 366.10726 -257.905091) (xy 366.081623 -257.898254) (xy 366.055089 -257.898254)
			(xy 366.029452 -257.905091) (xy 366.006443 -257.918303) (xy 365.996728 -257.927348) (xy 365.978028 -257.945217)
			(xy 365.936101 -257.975502) (xy 365.88997 -257.998887) (xy 365.840759 -258.014802) (xy 365.78967 -258.022859)
			(xy 365.76381 -258.02336) (xy 365.737841 -258.022866) (xy 365.686541 -258.014742) (xy 365.637144 -257.998694)
			(xy 365.590866 -257.975115) (xy 365.548846 -257.944587) (xy 365.51212 -257.907861) (xy 365.48159 -257.865842)
			(xy 365.45801 -257.819565) (xy 365.44196 -257.770168) (xy 365.433835 -257.718869) (xy 358.469898 -257.718869)
			(xy 358.495407 -257.737402) (xy 358.53213 -257.774125) (xy 358.562656 -257.816141) (xy 358.586234 -257.862415)
			(xy 358.602282 -257.911808) (xy 358.610407 -257.963103) (xy 358.610916 -257.98907) (xy 358.610407 -258.015037)
			(xy 358.602282 -258.066332) (xy 358.586234 -258.115725) (xy 358.562656 -258.161999) (xy 358.53213 -258.204015)
			(xy 358.495407 -258.240738) (xy 358.453391 -258.271264) (xy 358.407117 -258.294842) (xy 358.357724 -258.31089)
			(xy 358.306429 -258.319015) (xy 358.254495 -258.319015) (xy 358.2032 -258.31089) (xy 358.153807 -258.294842)
			(xy 358.107533 -258.271264) (xy 358.065517 -258.240738) (xy 358.028794 -258.204015) (xy 357.998268 -258.161999)
			(xy 357.97469 -258.115725) (xy 357.958642 -258.066332) (xy 357.950517 -258.015037) (xy 354.079384 -258.015037)
			(xy 354.029836 -258.02288) (xy 354.003864 -258.02336) (xy 353.978109 -258.022909) (xy 353.927221 -258.014922)
			(xy 353.87819 -257.999133) (xy 353.832205 -257.975923) (xy 353.79038 -257.945856) (xy 353.771708 -257.92811)
			(xy 353.762018 -257.919117) (xy 353.739086 -257.905985) (xy 353.713547 -257.89919) (xy 353.687121 -257.89919)
			(xy 353.661582 -257.905985) (xy 353.63865 -257.919117) (xy 353.62896 -257.92811) (xy 353.610299 -257.945865)
			(xy 353.568461 -257.975908) (xy 353.522471 -257.9991) (xy 353.473441 -258.014881) (xy 353.422557 -258.022868)
			(xy 353.396804 -258.02336) (xy 353.370835 -258.022865) (xy 353.319536 -258.014741) (xy 353.27014 -257.998692)
			(xy 353.223863 -257.975113) (xy 353.181844 -257.944585) (xy 353.145118 -257.907859) (xy 353.114589 -257.865841)
			(xy 353.09101 -257.819564) (xy 353.07496 -257.770168) (xy 353.066835 -257.718869) (xy 352.837751 -257.718869)
			(xy 352.829626 -257.770163) (xy 352.813578 -257.819556) (xy 352.79 -257.865831) (xy 352.759473 -257.907847)
			(xy 352.72275 -257.944571) (xy 352.680734 -257.975098) (xy 352.63446 -257.998676) (xy 352.585067 -258.014725)
			(xy 352.533771 -258.02285) (xy 352.507804 -258.02336) (xy 352.483251 -258.02294) (xy 352.434684 -258.015693)
			(xy 352.387722 -258.001344) (xy 352.343398 -257.980208) (xy 352.302688 -257.95275) (xy 352.284284 -257.936492)
			(xy 352.272795 -257.926689) (xy 352.245558 -257.913675) (xy 352.215704 -257.909207) (xy 352.18585 -257.913675)
			(xy 352.158613 -257.926689) (xy 352.147124 -257.936492) (xy 352.128728 -257.95276) (xy 352.088021 -257.980227)
			(xy 352.043696 -258.001364) (xy 351.99673 -258.015704) (xy 351.948158 -258.022932) (xy 351.923604 -258.02336)
			(xy 351.899051 -258.02294) (xy 351.850484 -258.015693) (xy 351.803522 -258.001344) (xy 351.759198 -257.980208)
			(xy 351.718488 -257.95275) (xy 351.700084 -257.936492) (xy 351.688595 -257.926689) (xy 351.661358 -257.913675)
			(xy 351.631504 -257.909207) (xy 351.60165 -257.913675) (xy 351.574413 -257.926689) (xy 351.562924 -257.936492)
			(xy 351.544528 -257.95276) (xy 351.503821 -257.980227) (xy 351.459496 -258.001364) (xy 351.41253 -258.015704)
			(xy 351.363958 -258.022932) (xy 351.339404 -258.02336) (xy 351.313435 -258.022865) (xy 351.262136 -258.014741)
			(xy 351.21274 -257.998692) (xy 351.166463 -257.975113) (xy 351.124444 -257.944585) (xy 351.087718 -257.907859)
			(xy 351.057189 -257.865841) (xy 351.03361 -257.819564) (xy 351.01756 -257.770168) (xy 351.009435 -257.718869)
			(xy 350.503744 -257.718869) (xy 350.503744 -258.549394) (xy 350.521966 -258.565193) (xy 350.554084 -258.601168)
			(xy 350.580636 -258.641428) (xy 350.601057 -258.685118) (xy 350.614915 -258.731311) (xy 350.621916 -258.779027)
			(xy 350.622362 -258.80314) (xy 350.62185 -258.829105) (xy 350.613721 -258.880396) (xy 350.597668 -258.929784)
			(xy 350.574089 -258.976053) (xy 350.543562 -259.018064) (xy 350.506839 -259.054783) (xy 350.464825 -259.085305)
			(xy 350.418554 -259.108881) (xy 350.369165 -259.124928) (xy 350.317873 -259.133052) (xy 350.291908 -259.133594)
			(xy 350.268208 -259.133166) (xy 350.221292 -259.126413) (xy 350.198436 -259.120132) (xy 350.16948 -259.111496)
			(xy 350.048576 -259.2324) (xy 350.039302 -259.242252) (xy 350.025853 -259.265719) (xy 350.019053 -259.291898)
			(xy 350.01938 -259.318944) (xy 350.026811 -259.34495) (xy 350.040823 -259.368086) (xy 350.050354 -259.377688)
			(xy 350.069358 -259.396542) (xy 350.101622 -259.439256) (xy 350.126588 -259.486608) (xy 350.143606 -259.537361)
			(xy 350.152231 -259.590191) (xy 350.152716 -259.616956) (xy 350.152236 -259.642926) (xy 350.144117 -259.694229)
			(xy 350.134958 -259.722425) (xy 350.476567 -259.722425) (xy 350.476567 -259.670491) (xy 350.484692 -259.619196)
			(xy 350.50074 -259.569803) (xy 350.524318 -259.523529) (xy 350.554844 -259.481513) (xy 350.591567 -259.44479)
			(xy 350.633583 -259.414264) (xy 350.679857 -259.390686) (xy 350.72925 -259.374638) (xy 350.780545 -259.366513)
			(xy 350.832479 -259.366513) (xy 350.883774 -259.374638) (xy 350.933167 -259.390686) (xy 350.979441 -259.414264)
			(xy 351.021457 -259.44479) (xy 351.05818 -259.481513) (xy 351.088706 -259.523529) (xy 351.112284 -259.569803)
			(xy 351.11506 -259.578348) (xy 356.04323 -259.578348) (xy 356.043679 -259.553796) (xy 356.050919 -259.50523)
			(xy 356.065261 -259.458269) (xy 356.086391 -259.413945) (xy 356.113843 -259.373233) (xy 356.130098 -259.354828)
			(xy 356.139853 -259.343301) (xy 356.152869 -259.316077) (xy 356.157345 -259.286236) (xy 356.15289 -259.256391)
			(xy 356.139893 -259.229158) (xy 356.130098 -259.217668) (xy 356.113849 -259.199256) (xy 356.08638 -259.158553)
			(xy 356.065239 -259.114232) (xy 356.050894 -259.06727) (xy 356.043661 -259.018701) (xy 356.04323 -258.994148)
			(xy 356.043739 -258.968181) (xy 356.051864 -258.916886) (xy 356.067912 -258.867493) (xy 356.09149 -258.821219)
			(xy 356.122016 -258.779203) (xy 356.158739 -258.74248) (xy 356.200755 -258.711954) (xy 356.247029 -258.688376)
			(xy 356.296422 -258.672328) (xy 356.347717 -258.664203) (xy 356.399651 -258.664203) (xy 356.450946 -258.672328)
			(xy 356.500339 -258.688376) (xy 356.546613 -258.711954) (xy 356.588629 -258.74248) (xy 356.625352 -258.779203)
			(xy 356.655878 -258.821219) (xy 356.659897 -258.829107) (xy 361.239817 -258.829107) (xy 361.239817 -258.777173)
			(xy 361.247942 -258.725878) (xy 361.26399 -258.676485) (xy 361.287568 -258.630211) (xy 361.318094 -258.588195)
			(xy 361.354817 -258.551472) (xy 361.396833 -258.520946) (xy 361.443107 -258.497368) (xy 361.4925 -258.48132)
			(xy 361.543795 -258.473195) (xy 361.595729 -258.473195) (xy 361.647024 -258.48132) (xy 361.696417 -258.497368)
			(xy 361.742691 -258.520946) (xy 361.784707 -258.551472) (xy 361.82143 -258.588195) (xy 361.851956 -258.630211)
			(xy 361.875534 -258.676485) (xy 361.891582 -258.725878) (xy 361.899707 -258.777173) (xy 361.900216 -258.80314)
			(xy 361.899707 -258.829107) (xy 361.891582 -258.880402) (xy 361.875534 -258.929795) (xy 361.851956 -258.976069)
			(xy 361.82143 -259.018085) (xy 361.784707 -259.054808) (xy 361.742691 -259.085334) (xy 361.696417 -259.108912)
			(xy 361.647024 -259.12496) (xy 361.595729 -259.133085) (xy 361.543795 -259.133085) (xy 361.4925 -259.12496)
			(xy 361.443107 -259.108912) (xy 361.396833 -259.085334) (xy 361.354817 -259.054808) (xy 361.318094 -259.018085)
			(xy 361.287568 -258.976069) (xy 361.26399 -258.929795) (xy 361.247942 -258.880402) (xy 361.239817 -258.829107)
			(xy 356.659897 -258.829107) (xy 356.679456 -258.867493) (xy 356.695504 -258.916886) (xy 356.703629 -258.968181)
			(xy 356.704138 -258.994148) (xy 356.703695 -259.0187) (xy 356.696455 -259.067267) (xy 356.682111 -259.114228)
			(xy 356.66098 -259.158552) (xy 356.633526 -259.199264) (xy 356.61727 -259.217668) (xy 356.607416 -259.229119)
			(xy 356.594402 -259.256369) (xy 356.58994 -259.286236) (xy 356.594422 -259.316099) (xy 356.607456 -259.34334)
			(xy 356.61727 -259.354828) (xy 356.633512 -259.373246) (xy 356.660983 -259.413947) (xy 356.682126 -259.458266)
			(xy 356.696472 -259.505228) (xy 356.703707 -259.553796) (xy 356.704138 -259.578348) (xy 356.703629 -259.604315)
			(xy 356.697514 -259.642923) (xy 357.950517 -259.642923) (xy 357.950517 -259.590989) (xy 357.958642 -259.539694)
			(xy 357.97469 -259.490301) (xy 357.998268 -259.444027) (xy 358.028794 -259.402011) (xy 358.065517 -259.365288)
			(xy 358.107533 -259.334762) (xy 358.153807 -259.311184) (xy 358.2032 -259.295136) (xy 358.254495 -259.287011)
			(xy 358.306429 -259.287011) (xy 358.357724 -259.295136) (xy 358.407117 -259.311184) (xy 358.453391 -259.334762)
			(xy 358.495407 -259.365288) (xy 358.53213 -259.402011) (xy 358.562656 -259.444027) (xy 358.586234 -259.490301)
			(xy 358.602282 -259.539694) (xy 358.610407 -259.590989) (xy 358.610916 -259.616956) (xy 358.610563 -259.63499)
			(xy 363.035596 -259.63499) (xy 363.036054 -259.610439) (xy 363.043289 -259.561872) (xy 363.057628 -259.51491)
			(xy 363.078756 -259.470586) (xy 363.106208 -259.429874) (xy 363.122464 -259.41147) (xy 363.132278 -259.399989)
			(xy 363.145292 -259.372749) (xy 363.149759 -259.342893) (xy 363.145288 -259.313037) (xy 363.13227 -259.285799)
			(xy 363.122464 -259.27431) (xy 363.106198 -259.255912) (xy 363.078729 -259.215206) (xy 363.057591 -259.170882)
			(xy 363.04325 -259.123916) (xy 363.036023 -259.075344) (xy 363.035596 -259.05079) (xy 363.036105 -259.024823)
			(xy 363.04423 -258.973528) (xy 363.060278 -258.924135) (xy 363.083856 -258.877861) (xy 363.114382 -258.835845)
			(xy 363.151105 -258.799122) (xy 363.193121 -258.768596) (xy 363.239395 -258.745018) (xy 363.288788 -258.72897)
			(xy 363.340083 -258.720845) (xy 363.392017 -258.720845) (xy 363.443312 -258.72897) (xy 363.492705 -258.745018)
			(xy 363.538979 -258.768596) (xy 363.580995 -258.799122) (xy 363.617718 -258.835845) (xy 363.648244 -258.877861)
			(xy 363.671822 -258.924135) (xy 363.68787 -258.973528) (xy 363.695995 -259.024823) (xy 363.696504 -259.05079)
			(xy 363.696095 -259.075343) (xy 363.688848 -259.123912) (xy 363.674497 -259.170874) (xy 363.653358 -259.215198)
			(xy 363.625896 -259.255907) (xy 363.609636 -259.27431) (xy 363.599841 -259.285806) (xy 363.586825 -259.313041)
			(xy 363.582354 -259.342893) (xy 363.586821 -259.372745) (xy 363.599833 -259.399981) (xy 363.609636 -259.41147)
			(xy 363.625892 -259.429876) (xy 363.653363 -259.470579) (xy 363.674503 -259.514902) (xy 363.688846 -259.561866)
			(xy 363.696076 -259.610437) (xy 363.696504 -259.63499) (xy 363.695995 -259.660957) (xy 363.68787 -259.712252)
			(xy 363.671822 -259.761645) (xy 363.648244 -259.807919) (xy 363.617718 -259.849935) (xy 363.580995 -259.886658)
			(xy 363.538979 -259.917184) (xy 363.492705 -259.940762) (xy 363.443312 -259.95681) (xy 363.392017 -259.964935)
			(xy 363.340083 -259.964935) (xy 363.288788 -259.95681) (xy 363.239395 -259.940762) (xy 363.193121 -259.917184)
			(xy 363.151105 -259.886658) (xy 363.114382 -259.849935) (xy 363.083856 -259.807919) (xy 363.060278 -259.761645)
			(xy 363.04423 -259.712252) (xy 363.036105 -259.660957) (xy 363.035596 -259.63499) (xy 358.610563 -259.63499)
			(xy 358.610407 -259.642923) (xy 358.602282 -259.694218) (xy 358.586234 -259.743611) (xy 358.562656 -259.789885)
			(xy 358.53213 -259.831901) (xy 358.495407 -259.868624) (xy 358.453391 -259.89915) (xy 358.407117 -259.922728)
			(xy 358.357724 -259.938776) (xy 358.306429 -259.946901) (xy 358.254495 -259.946901) (xy 358.2032 -259.938776)
			(xy 358.153807 -259.922728) (xy 358.107533 -259.89915) (xy 358.065517 -259.868624) (xy 358.028794 -259.831901)
			(xy 357.998268 -259.789885) (xy 357.97469 -259.743611) (xy 357.958642 -259.694218) (xy 357.950517 -259.642923)
			(xy 356.697514 -259.642923) (xy 356.695504 -259.65561) (xy 356.679456 -259.705003) (xy 356.655878 -259.751277)
			(xy 356.625352 -259.793293) (xy 356.588629 -259.830016) (xy 356.546613 -259.860542) (xy 356.500339 -259.88412)
			(xy 356.450946 -259.900168) (xy 356.399651 -259.908293) (xy 356.347717 -259.908293) (xy 356.296422 -259.900168)
			(xy 356.247029 -259.88412) (xy 356.200755 -259.860542) (xy 356.158739 -259.830016) (xy 356.122016 -259.793293)
			(xy 356.09149 -259.751277) (xy 356.067912 -259.705003) (xy 356.051864 -259.65561) (xy 356.043739 -259.604315)
			(xy 356.04323 -259.578348) (xy 351.11506 -259.578348) (xy 351.128332 -259.619196) (xy 351.136457 -259.670491)
			(xy 351.136966 -259.696458) (xy 351.136457 -259.722425) (xy 351.128332 -259.77372) (xy 351.112284 -259.823113)
			(xy 351.088706 -259.869387) (xy 351.05818 -259.911403) (xy 351.021457 -259.948126) (xy 350.979441 -259.978652)
			(xy 350.933167 -260.00223) (xy 350.883774 -260.018278) (xy 350.832479 -260.026403) (xy 350.780545 -260.026403)
			(xy 350.72925 -260.018278) (xy 350.679857 -260.00223) (xy 350.633583 -259.978652) (xy 350.591567 -259.948126)
			(xy 350.554844 -259.911403) (xy 350.524318 -259.869387) (xy 350.50074 -259.823113) (xy 350.484692 -259.77372)
			(xy 350.476567 -259.722425) (xy 350.134958 -259.722425) (xy 350.12807 -259.743629) (xy 350.104492 -259.78991)
			(xy 350.073964 -259.831932) (xy 350.037236 -259.86866) (xy 349.995215 -259.899189) (xy 349.948934 -259.922768)
			(xy 349.899535 -259.938815) (xy 349.848232 -259.946936) (xy 349.822262 -259.94741) (xy 349.795494 -259.946919)
			(xy 349.742651 -259.938336) (xy 349.691886 -259.921335) (xy 349.644531 -259.896363) (xy 349.601828 -259.864075)
			(xy 349.582994 -259.845048) (xy 349.573352 -259.83558) (xy 349.550213 -259.821641) (xy 349.52423 -259.81425)
			(xy 349.497219 -259.813923) (xy 349.471065 -259.820684) (xy 349.447596 -259.83406) (xy 349.437706 -259.84327)
			(xy 349.348806 -259.93217) (xy 349.339202 -259.942367) (xy 349.325487 -259.96678) (xy 349.318921 -259.994001)
			(xy 349.319999 -260.021982) (xy 349.328639 -260.048617) (xy 349.344191 -260.071903) (xy 349.365485 -260.090086)
			(xy 349.390919 -260.1018) (xy 349.404686 -260.104382) (xy 349.430232 -260.108968) (xy 349.479578 -260.125051)
			(xy 349.5258 -260.148652) (xy 349.567764 -260.179192) (xy 349.604434 -260.215919) (xy 349.63491 -260.257928)
			(xy 349.658442 -260.304187) (xy 349.674449 -260.353556) (xy 349.682539 -260.404822) (xy 349.68307 -260.430772)
			(xy 349.682589 -260.456743) (xy 349.682584 -260.456772) (xy 349.962401 -260.456772) (xy 349.962401 -260.404828)
			(xy 349.970527 -260.353523) (xy 349.986579 -260.304121) (xy 350.010162 -260.257838) (xy 350.040695 -260.215815)
			(xy 350.077427 -260.179085) (xy 350.119452 -260.148554) (xy 350.165735 -260.124973) (xy 350.215138 -260.108923)
			(xy 350.266444 -260.1008) (xy 350.292416 -260.100318) (xy 350.319503 -260.100867) (xy 350.37295 -260.109705)
			(xy 350.42424 -260.127142) (xy 350.472 -260.15271) (xy 350.51495 -260.185726) (xy 350.551941 -260.225304)
			(xy 350.581981 -260.270385) (xy 350.604267 -260.319763) (xy 350.6182 -260.372113) (xy 350.621346 -260.399022)
			(xy 350.623184 -260.413163) (xy 350.63358 -260.4397) (xy 350.646635 -260.456739) (xy 361.239817 -260.456739)
			(xy 361.239817 -260.404805) (xy 361.247942 -260.35351) (xy 361.26399 -260.304117) (xy 361.287568 -260.257843)
			(xy 361.318094 -260.215827) (xy 361.354817 -260.179104) (xy 361.396833 -260.148578) (xy 361.443107 -260.125)
			(xy 361.4925 -260.108952) (xy 361.543795 -260.100827) (xy 361.595729 -260.100827) (xy 361.647024 -260.108952)
			(xy 361.696417 -260.125) (xy 361.742691 -260.148578) (xy 361.784707 -260.179104) (xy 361.82143 -260.215827)
			(xy 361.851956 -260.257843) (xy 361.875534 -260.304117) (xy 361.891582 -260.35351) (xy 361.899707 -260.404805)
			(xy 361.900216 -260.430772) (xy 361.899707 -260.456739) (xy 361.891582 -260.508034) (xy 361.875534 -260.557427)
			(xy 361.851956 -260.603701) (xy 361.82143 -260.645717) (xy 361.784707 -260.68244) (xy 361.742691 -260.712966)
			(xy 361.696417 -260.736544) (xy 361.647024 -260.752592) (xy 361.595729 -260.760717) (xy 361.543795 -260.760717)
			(xy 361.4925 -260.752592) (xy 361.443107 -260.736544) (xy 361.396833 -260.712966) (xy 361.354817 -260.68244)
			(xy 361.318094 -260.645717) (xy 361.287568 -260.603701) (xy 361.26399 -260.557427) (xy 361.247942 -260.508034)
			(xy 361.239817 -260.456739) (xy 350.646635 -260.456739) (xy 350.650914 -260.462323) (xy 350.673831 -260.479266)
			(xy 350.700543 -260.489205) (xy 350.728962 -260.491364) (xy 350.743012 -260.488938) (xy 350.759467 -260.485761)
			(xy 350.792803 -260.482322) (xy 350.80956 -260.48208) (xy 350.835534 -260.482492) (xy 350.886843 -260.490613)
			(xy 350.93625 -260.506661) (xy 350.982538 -260.530241) (xy 351.024567 -260.560772) (xy 351.061302 -260.597502)
			(xy 351.091838 -260.639528) (xy 351.115424 -260.685813) (xy 351.131478 -260.735218) (xy 351.139605 -260.786526)
			(xy 351.139605 -260.838474) (xy 351.131478 -260.889782) (xy 351.115424 -260.939187) (xy 351.091838 -260.985472)
			(xy 351.061302 -261.027498) (xy 351.024567 -261.064228) (xy 350.982538 -261.094759) (xy 350.93625 -261.118339)
			(xy 350.886843 -261.134387) (xy 350.835534 -261.142508) (xy 350.80956 -261.142988) (xy 350.782473 -261.142455)
			(xy 350.729025 -261.133614) (xy 350.677735 -261.116174) (xy 350.629975 -261.090603) (xy 350.587026 -261.057585)
			(xy 350.550035 -261.018006) (xy 350.519996 -260.972923) (xy 350.49771 -260.923545) (xy 350.483776 -260.871193)
			(xy 350.48063 -260.844284) (xy 350.478815 -260.830139) (xy 350.468417 -260.803598) (xy 350.45108 -260.780972)
			(xy 350.428157 -260.764028) (xy 350.40144 -260.754092) (xy 350.373016 -260.751938) (xy 350.358964 -260.754368)
			(xy 350.34251 -260.757548) (xy 350.309173 -260.760986) (xy 350.292416 -260.761226) (xy 350.266444 -260.7608)
			(xy 350.215138 -260.752677) (xy 350.165735 -260.736627) (xy 350.119452 -260.713046) (xy 350.077427 -260.682515)
			(xy 350.040695 -260.645785) (xy 350.010162 -260.603762) (xy 349.986579 -260.557479) (xy 349.970527 -260.508077)
			(xy 349.962401 -260.456772) (xy 349.682584 -260.456772) (xy 349.674468 -260.508047) (xy 349.658421 -260.557448)
			(xy 349.634843 -260.603731) (xy 349.604315 -260.645755) (xy 349.567588 -260.682486) (xy 349.525568 -260.71302)
			(xy 349.479289 -260.736604) (xy 349.42989 -260.752658) (xy 349.378587 -260.760786) (xy 349.352616 -260.761226)
			(xy 349.326669 -260.760712) (xy 349.275415 -260.752592) (xy 349.226059 -260.736564) (xy 349.179813 -260.713021)
			(xy 349.137812 -260.682543) (xy 349.10109 -260.645877) (xy 349.070546 -260.603924) (xy 349.046933 -260.557714)
			(xy 349.030828 -260.508383) (xy 349.026226 -260.482842) (xy 349.023625 -260.469075) (xy 349.011937 -260.443624)
			(xy 348.993765 -260.422314) (xy 348.970481 -260.406751) (xy 348.943841 -260.39811) (xy 348.915855 -260.397043)
			(xy 348.888634 -260.40363) (xy 348.864233 -260.417375) (xy 348.854014 -260.426962) (xy 348.71406 -260.566916)
			(xy 348.71025 -260.57479) (xy 348.697699 -260.599435) (xy 348.665653 -260.644506) (xy 348.626551 -260.683615)
			(xy 348.581486 -260.715669) (xy 348.556834 -260.728206) (xy 348.54896 -260.732016) (xy 348.219776 -261.0612)
			(xy 348.236794 -261.093966) (xy 348.248263 -261.117443) (xy 348.264466 -261.167115) (xy 348.272651 -261.218718)
			(xy 348.273116 -261.244842) (xy 348.272604 -261.270806) (xy 348.272604 -261.270809) (xy 348.552517 -261.270809)
			(xy 348.552517 -261.218875) (xy 348.560642 -261.16758) (xy 348.57669 -261.118187) (xy 348.600268 -261.071913)
			(xy 348.630794 -261.029897) (xy 348.667517 -260.993174) (xy 348.709533 -260.962648) (xy 348.755807 -260.93907)
			(xy 348.8052 -260.923022) (xy 348.856495 -260.914897) (xy 348.908429 -260.914897) (xy 348.959724 -260.923022)
			(xy 349.009117 -260.93907) (xy 349.055391 -260.962648) (xy 349.097407 -260.993174) (xy 349.13413 -261.029897)
			(xy 349.164656 -261.071913) (xy 349.188234 -261.118187) (xy 349.204282 -261.16758) (xy 349.212407 -261.218875)
			(xy 349.212916 -261.244842) (xy 349.212407 -261.270809) (xy 349.492317 -261.270809) (xy 349.492317 -261.218875)
			(xy 349.500442 -261.16758) (xy 349.51649 -261.118187) (xy 349.540068 -261.071913) (xy 349.570594 -261.029897)
			(xy 349.607317 -260.993174) (xy 349.649333 -260.962648) (xy 349.695607 -260.93907) (xy 349.745 -260.923022)
			(xy 349.796295 -260.914897) (xy 349.848229 -260.914897) (xy 349.899524 -260.923022) (xy 349.948917 -260.93907)
			(xy 349.995191 -260.962648) (xy 350.037207 -260.993174) (xy 350.07393 -261.029897) (xy 350.104456 -261.071913)
			(xy 350.128034 -261.118187) (xy 350.144082 -261.16758) (xy 350.152207 -261.218875) (xy 350.152716 -261.244842)
			(xy 350.152207 -261.270809) (xy 350.144082 -261.322104) (xy 350.133437 -261.354868) (xy 352.247945 -261.354868)
			(xy 352.247945 -261.302932) (xy 352.25607 -261.251634) (xy 352.272119 -261.202239) (xy 352.295698 -261.155963)
			(xy 352.326227 -261.113946) (xy 352.362952 -261.077221) (xy 352.40497 -261.046694) (xy 352.451247 -261.023116)
			(xy 352.500642 -261.007068) (xy 352.55194 -260.998944) (xy 352.577908 -260.998462) (xy 352.605207 -260.99899)
			(xy 352.659061 -261.007973) (xy 352.710703 -261.025694) (xy 352.758726 -261.05167) (xy 352.801822 -261.085192)
			(xy 352.820732 -261.104888) (xy 352.830565 -261.114868) (xy 352.854449 -261.129494) (xy 352.881405 -261.137093)
			(xy 352.909411 -261.137093) (xy 352.936367 -261.129494) (xy 352.960251 -261.114868) (xy 352.970084 -261.104888)
			(xy 352.987229 -261.086943) (xy 353.025945 -261.055891) (xy 353.068872 -261.030983) (xy 353.115043 -261.01278)
			(xy 353.163418 -261.001691) (xy 353.212908 -260.997967) (xy 353.262398 -261.001691) (xy 353.310773 -261.01278)
			(xy 353.356944 -261.030983) (xy 353.399871 -261.055891) (xy 353.438587 -261.086943) (xy 353.455732 -261.104888)
			(xy 353.465565 -261.114868) (xy 353.489449 -261.129494) (xy 353.516405 -261.137093) (xy 353.544411 -261.137093)
			(xy 353.571367 -261.129494) (xy 353.595251 -261.114868) (xy 353.605084 -261.104888) (xy 353.622229 -261.086943)
			(xy 353.660945 -261.055891) (xy 353.703872 -261.030983) (xy 353.750043 -261.01278) (xy 353.798418 -261.001691)
			(xy 353.847908 -260.997967) (xy 353.897398 -261.001691) (xy 353.945773 -261.01278) (xy 353.991944 -261.030983)
			(xy 354.034871 -261.055891) (xy 354.073587 -261.086943) (xy 354.090732 -261.104888) (xy 354.100565 -261.114868)
			(xy 354.124449 -261.129494) (xy 354.151405 -261.137093) (xy 354.179411 -261.137093) (xy 354.206367 -261.129494)
			(xy 354.230251 -261.114868) (xy 354.240084 -261.104888) (xy 354.257229 -261.086943) (xy 354.295945 -261.055891)
			(xy 354.338872 -261.030983) (xy 354.385043 -261.01278) (xy 354.433418 -261.001691) (xy 354.482908 -260.997967)
			(xy 354.532398 -261.001691) (xy 354.580773 -261.01278) (xy 354.626944 -261.030983) (xy 354.669871 -261.055891)
			(xy 354.708587 -261.086943) (xy 354.725732 -261.104888) (xy 354.735565 -261.114868) (xy 354.759449 -261.129494)
			(xy 354.786405 -261.137093) (xy 354.814411 -261.137093) (xy 354.841367 -261.129494) (xy 354.865251 -261.114868)
			(xy 354.875084 -261.104888) (xy 354.893992 -261.085191) (xy 354.937092 -261.051681) (xy 354.985117 -261.025715)
			(xy 355.036759 -261.008002) (xy 355.09061 -260.999024) (xy 355.117908 -260.998462) (xy 355.143876 -260.99894)
			(xy 355.195173 -261.007066) (xy 355.244566 -261.023116) (xy 355.290842 -261.046695) (xy 355.332858 -261.077223)
			(xy 355.369582 -261.113948) (xy 355.400109 -261.155965) (xy 355.423687 -261.202241) (xy 355.439736 -261.251635)
			(xy 355.442773 -261.270809) (xy 357.950517 -261.270809) (xy 357.950517 -261.218875) (xy 357.958642 -261.16758)
			(xy 357.97469 -261.118187) (xy 357.998268 -261.071913) (xy 358.028794 -261.029897) (xy 358.065517 -260.993174)
			(xy 358.107533 -260.962648) (xy 358.153807 -260.93907) (xy 358.2032 -260.923022) (xy 358.254495 -260.914897)
			(xy 358.306429 -260.914897) (xy 358.357724 -260.923022) (xy 358.407117 -260.93907) (xy 358.453391 -260.962648)
			(xy 358.495407 -260.993174) (xy 358.53213 -261.029897) (xy 358.562656 -261.071913) (xy 358.586234 -261.118187)
			(xy 358.602282 -261.16758) (xy 358.610407 -261.218875) (xy 358.610916 -261.244842) (xy 358.610407 -261.270809)
			(xy 358.602282 -261.322104) (xy 358.591636 -261.35487) (xy 363.987545 -261.35487) (xy 363.987545 -261.30293)
			(xy 363.995671 -261.25163) (xy 364.011722 -261.202233) (xy 364.035303 -261.155956) (xy 364.065834 -261.113937)
			(xy 364.102563 -261.077212) (xy 364.144585 -261.046685) (xy 364.190865 -261.023109) (xy 364.240263 -261.007063)
			(xy 364.291564 -260.998942) (xy 364.317534 -260.998462) (xy 364.344831 -260.999039) (xy 364.398682 -261.00801)
			(xy 364.450324 -261.02572) (xy 364.498348 -261.051684) (xy 364.541446 -261.085196) (xy 364.560358 -261.104888)
			(xy 364.570191 -261.114868) (xy 364.594075 -261.129494) (xy 364.621031 -261.137093) (xy 364.649037 -261.137093)
			(xy 364.675993 -261.129494) (xy 364.699877 -261.114868) (xy 364.70971 -261.104888) (xy 364.726855 -261.086943)
			(xy 364.765571 -261.055891) (xy 364.808498 -261.030983) (xy 364.854669 -261.01278) (xy 364.903044 -261.001691)
			(xy 364.952534 -260.997967) (xy 365.002024 -261.001691) (xy 365.050399 -261.01278) (xy 365.09657 -261.030983)
			(xy 365.139497 -261.055891) (xy 365.178213 -261.086943) (xy 365.195358 -261.104888) (xy 365.205191 -261.114868)
			(xy 365.229075 -261.129494) (xy 365.256031 -261.137093) (xy 365.284037 -261.137093) (xy 365.310993 -261.129494)
			(xy 365.334877 -261.114868) (xy 365.34471 -261.104888) (xy 365.361855 -261.086943) (xy 365.400571 -261.055891)
			(xy 365.443498 -261.030983) (xy 365.489669 -261.01278) (xy 365.538044 -261.001691) (xy 365.587534 -260.997967)
			(xy 365.637024 -261.001691) (xy 365.685399 -261.01278) (xy 365.73157 -261.030983) (xy 365.774497 -261.055891)
			(xy 365.813213 -261.086943) (xy 365.830358 -261.104888) (xy 365.840191 -261.114868) (xy 365.864075 -261.129494)
			(xy 365.891031 -261.137093) (xy 365.919037 -261.137093) (xy 365.945993 -261.129494) (xy 365.969877 -261.114868)
			(xy 365.97971 -261.104888) (xy 365.998605 -261.085179) (xy 366.041709 -261.051669) (xy 366.089737 -261.025706)
			(xy 366.141382 -261.007996) (xy 366.195236 -260.999021) (xy 366.222534 -260.998462) (xy 366.248501 -260.998942)
			(xy 366.299794 -261.007071) (xy 366.349185 -261.023123) (xy 366.395456 -261.046704) (xy 366.437469 -261.077232)
			(xy 366.47419 -261.113957) (xy 366.504714 -261.155973) (xy 366.52829 -261.202247) (xy 366.544337 -261.251639)
			(xy 366.552461 -261.302933) (xy 366.552461 -261.354867) (xy 366.544337 -261.406161) (xy 366.52829 -261.455553)
			(xy 366.504714 -261.501827) (xy 366.47419 -261.543843) (xy 366.437469 -261.580568) (xy 366.395456 -261.611096)
			(xy 366.349185 -261.634677) (xy 366.299794 -261.650729) (xy 366.248501 -261.658858) (xy 366.222534 -261.65937)
			(xy 366.195237 -261.658805) (xy 366.141385 -261.649829) (xy 366.089744 -261.632116) (xy 366.04172 -261.606149)
			(xy 365.998622 -261.572636) (xy 365.97971 -261.552944) (xy 365.969877 -261.542964) (xy 365.945993 -261.528338)
			(xy 365.919037 -261.520739) (xy 365.891031 -261.520739) (xy 365.864075 -261.528338) (xy 365.840191 -261.542964)
			(xy 365.830358 -261.552944) (xy 365.813213 -261.570889) (xy 365.774497 -261.601941) (xy 365.73157 -261.626849)
			(xy 365.685399 -261.645052) (xy 365.637024 -261.656141) (xy 365.587534 -261.659865) (xy 365.538044 -261.656141)
			(xy 365.489669 -261.645052) (xy 365.443498 -261.626849) (xy 365.400571 -261.601941) (xy 365.361855 -261.570889)
			(xy 365.34471 -261.552944) (xy 365.334877 -261.542964) (xy 365.310993 -261.528338) (xy 365.284037 -261.520739)
			(xy 365.256031 -261.520739) (xy 365.229075 -261.528338) (xy 365.205191 -261.542964) (xy 365.195358 -261.552944)
			(xy 365.178213 -261.570889) (xy 365.139497 -261.601941) (xy 365.09657 -261.626849) (xy 365.050399 -261.645052)
			(xy 365.002024 -261.656141) (xy 364.952534 -261.659865) (xy 364.903044 -261.656141) (xy 364.854669 -261.645052)
			(xy 364.808498 -261.626849) (xy 364.765571 -261.601941) (xy 364.726855 -261.570889) (xy 364.70971 -261.552944)
			(xy 364.699877 -261.542964) (xy 364.675993 -261.528338) (xy 364.649037 -261.520739) (xy 364.621031 -261.520739)
			(xy 364.594075 -261.528338) (xy 364.570191 -261.542964) (xy 364.560358 -261.552944) (xy 364.541436 -261.572626)
			(xy 364.498339 -261.606137) (xy 364.450317 -261.632105) (xy 364.398679 -261.649822) (xy 364.34483 -261.658805)
			(xy 364.317534 -261.65937) (xy 364.291564 -261.658858) (xy 364.240263 -261.650737) (xy 364.190865 -261.634691)
			(xy 364.144585 -261.611115) (xy 364.102563 -261.580588) (xy 364.065834 -261.543863) (xy 364.035303 -261.501844)
			(xy 364.011722 -261.455567) (xy 363.995671 -261.40617) (xy 363.987545 -261.35487) (xy 358.591636 -261.35487)
			(xy 358.586234 -261.371497) (xy 358.562656 -261.417771) (xy 358.53213 -261.459787) (xy 358.495407 -261.49651)
			(xy 358.453391 -261.527036) (xy 358.407117 -261.550614) (xy 358.357724 -261.566662) (xy 358.306429 -261.574787)
			(xy 358.254495 -261.574787) (xy 358.2032 -261.566662) (xy 358.153807 -261.550614) (xy 358.107533 -261.527036)
			(xy 358.065517 -261.49651) (xy 358.028794 -261.459787) (xy 357.998268 -261.417771) (xy 357.97469 -261.371497)
			(xy 357.958642 -261.322104) (xy 357.950517 -261.270809) (xy 355.442773 -261.270809) (xy 355.447861 -261.302932)
			(xy 355.447861 -261.354868) (xy 355.439736 -261.406165) (xy 355.423687 -261.455559) (xy 355.400109 -261.501835)
			(xy 355.369582 -261.543852) (xy 355.332858 -261.580577) (xy 355.290842 -261.611105) (xy 355.244566 -261.634684)
			(xy 355.195173 -261.650734) (xy 355.143876 -261.65886) (xy 355.117908 -261.65937) (xy 355.09061 -261.658821)
			(xy 355.036758 -261.649842) (xy 354.985116 -261.632125) (xy 354.937093 -261.606154) (xy 354.893996 -261.572638)
			(xy 354.875084 -261.552944) (xy 354.865251 -261.542964) (xy 354.841367 -261.528338) (xy 354.814411 -261.520739)
			(xy 354.786405 -261.520739) (xy 354.759449 -261.528338) (xy 354.735565 -261.542964) (xy 354.725732 -261.552944)
			(xy 354.708587 -261.570889) (xy 354.669871 -261.601941) (xy 354.626944 -261.626849) (xy 354.580773 -261.645052)
			(xy 354.532398 -261.656141) (xy 354.482908 -261.659865) (xy 354.433418 -261.656141) (xy 354.385043 -261.645052)
			(xy 354.338872 -261.626849) (xy 354.295945 -261.601941) (xy 354.257229 -261.570889) (xy 354.240084 -261.552944)
			(xy 354.230251 -261.542964) (xy 354.206367 -261.528338) (xy 354.179411 -261.520739) (xy 354.151405 -261.520739)
			(xy 354.124449 -261.528338) (xy 354.100565 -261.542964) (xy 354.090732 -261.552944) (xy 354.073587 -261.570889)
			(xy 354.034871 -261.601941) (xy 353.991944 -261.626849) (xy 353.945773 -261.645052) (xy 353.897398 -261.656141)
			(xy 353.847908 -261.659865) (xy 353.798418 -261.656141) (xy 353.750043 -261.645052) (xy 353.703872 -261.626849)
			(xy 353.660945 -261.601941) (xy 353.622229 -261.570889) (xy 353.605084 -261.552944) (xy 353.595251 -261.542964)
			(xy 353.571367 -261.528338) (xy 353.544411 -261.520739) (xy 353.516405 -261.520739) (xy 353.489449 -261.528338)
			(xy 353.465565 -261.542964) (xy 353.455732 -261.552944) (xy 353.438587 -261.570889) (xy 353.399871 -261.601941)
			(xy 353.356944 -261.626849) (xy 353.310773 -261.645052) (xy 353.262398 -261.656141) (xy 353.212908 -261.659865)
			(xy 353.163418 -261.656141) (xy 353.115043 -261.645052) (xy 353.068872 -261.626849) (xy 353.025945 -261.601941)
			(xy 352.987229 -261.570889) (xy 352.970084 -261.552944) (xy 352.960251 -261.542964) (xy 352.936367 -261.528338)
			(xy 352.909411 -261.520739) (xy 352.881405 -261.520739) (xy 352.854449 -261.528338) (xy 352.830565 -261.542964)
			(xy 352.820732 -261.552944) (xy 352.801823 -261.572639) (xy 352.758722 -261.606149) (xy 352.710697 -261.632114)
			(xy 352.659056 -261.649827) (xy 352.605205 -261.658807) (xy 352.577908 -261.65937) (xy 352.55194 -261.658856)
			(xy 352.500642 -261.650732) (xy 352.451247 -261.634684) (xy 352.40497 -261.611106) (xy 352.362952 -261.580579)
			(xy 352.326227 -261.543854) (xy 352.295698 -261.501837) (xy 352.272119 -261.455561) (xy 352.25607 -261.406166)
			(xy 352.247945 -261.354868) (xy 350.133437 -261.354868) (xy 350.128034 -261.371497) (xy 350.104456 -261.417771)
			(xy 350.07393 -261.459787) (xy 350.037207 -261.49651) (xy 349.995191 -261.527036) (xy 349.948917 -261.550614)
			(xy 349.899524 -261.566662) (xy 349.848229 -261.574787) (xy 349.796295 -261.574787) (xy 349.745 -261.566662)
			(xy 349.695607 -261.550614) (xy 349.649333 -261.527036) (xy 349.607317 -261.49651) (xy 349.570594 -261.459787)
			(xy 349.540068 -261.417771) (xy 349.51649 -261.371497) (xy 349.500442 -261.322104) (xy 349.492317 -261.270809)
			(xy 349.212407 -261.270809) (xy 349.204282 -261.322104) (xy 349.188234 -261.371497) (xy 349.164656 -261.417771)
			(xy 349.13413 -261.459787) (xy 349.097407 -261.49651) (xy 349.055391 -261.527036) (xy 349.009117 -261.550614)
			(xy 348.959724 -261.566662) (xy 348.908429 -261.574787) (xy 348.856495 -261.574787) (xy 348.8052 -261.566662)
			(xy 348.755807 -261.550614) (xy 348.709533 -261.527036) (xy 348.667517 -261.49651) (xy 348.630794 -261.459787)
			(xy 348.600268 -261.417771) (xy 348.57669 -261.371497) (xy 348.560642 -261.322104) (xy 348.552517 -261.270809)
			(xy 348.272604 -261.270809) (xy 348.264474 -261.322094) (xy 348.248421 -261.371478) (xy 348.22484 -261.417744)
			(xy 348.194313 -261.459751) (xy 348.15759 -261.496465) (xy 348.115575 -261.526982) (xy 348.069304 -261.550552)
			(xy 348.019916 -261.566592) (xy 347.968626 -261.57471) (xy 347.942662 -261.575296) (xy 347.916538 -261.574822)
			(xy 347.864935 -261.566642) (xy 347.815261 -261.550445) (xy 347.791786 -261.538974) (xy 347.75902 -261.521956)
			(xy 347.64853 -261.632446) (xy 347.638399 -261.643284) (xy 347.624322 -261.669385) (xy 347.618338 -261.69843)
			(xy 347.62095 -261.72797) (xy 347.631938 -261.755514) (xy 347.650375 -261.77874) (xy 347.662246 -261.78764)
			(xy 347.683653 -261.803247) (xy 347.721673 -261.840136) (xy 347.753326 -261.882614) (xy 347.777805 -261.929594)
			(xy 347.794482 -261.979875) (xy 347.802933 -262.032171) (xy 347.80347 -262.058658) (xy 347.80299 -262.084625)
			(xy 348.082871 -262.084625) (xy 348.082871 -262.032691) (xy 348.090996 -261.981396) (xy 348.107044 -261.932003)
			(xy 348.130622 -261.885729) (xy 348.161148 -261.843713) (xy 348.197871 -261.80699) (xy 348.239887 -261.776464)
			(xy 348.286161 -261.752886) (xy 348.335554 -261.736838) (xy 348.386849 -261.728713) (xy 348.438783 -261.728713)
			(xy 348.490078 -261.736838) (xy 348.539471 -261.752886) (xy 348.585745 -261.776464) (xy 348.627761 -261.80699)
			(xy 348.664484 -261.843713) (xy 348.69501 -261.885729) (xy 348.718588 -261.932003) (xy 348.734636 -261.981396)
			(xy 348.742761 -262.032691) (xy 348.74327 -262.058658) (xy 348.742761 -262.084625) (xy 349.022671 -262.084625)
			(xy 349.022671 -262.032691) (xy 349.030796 -261.981396) (xy 349.046844 -261.932003) (xy 349.070422 -261.885729)
			(xy 349.100948 -261.843713) (xy 349.137671 -261.80699) (xy 349.179687 -261.776464) (xy 349.225961 -261.752886)
			(xy 349.275354 -261.736838) (xy 349.326649 -261.728713) (xy 349.378583 -261.728713) (xy 349.429878 -261.736838)
			(xy 349.479271 -261.752886) (xy 349.525545 -261.776464) (xy 349.567561 -261.80699) (xy 349.604284 -261.843713)
			(xy 349.63481 -261.885729) (xy 349.658388 -261.932003) (xy 349.674436 -261.981396) (xy 349.682561 -262.032691)
			(xy 349.68307 -262.058658) (xy 349.682561 -262.084625) (xy 349.962471 -262.084625) (xy 349.962471 -262.032691)
			(xy 349.970596 -261.981396) (xy 349.986644 -261.932003) (xy 350.010222 -261.885729) (xy 350.040748 -261.843713)
			(xy 350.077471 -261.80699) (xy 350.119487 -261.776464) (xy 350.165761 -261.752886) (xy 350.215154 -261.736838)
			(xy 350.266449 -261.728713) (xy 350.318383 -261.728713) (xy 350.369678 -261.736838) (xy 350.419071 -261.752886)
			(xy 350.465345 -261.776464) (xy 350.507361 -261.80699) (xy 350.544084 -261.843713) (xy 350.57461 -261.885729)
			(xy 350.598188 -261.932003) (xy 350.614236 -261.981396) (xy 350.622361 -262.032691) (xy 350.62287 -262.058658)
			(xy 350.622361 -262.084625) (xy 350.614236 -262.13592) (xy 350.598188 -262.185313) (xy 350.57461 -262.231587)
			(xy 350.544084 -262.273603) (xy 350.507361 -262.310326) (xy 350.465345 -262.340852) (xy 350.419071 -262.36443)
			(xy 350.369678 -262.380478) (xy 350.318383 -262.388603) (xy 350.266449 -262.388603) (xy 350.215154 -262.380478)
			(xy 350.165761 -262.36443) (xy 350.119487 -262.340852) (xy 350.077471 -262.310326) (xy 350.040748 -262.273603)
			(xy 350.010222 -262.231587) (xy 349.986644 -262.185313) (xy 349.970596 -262.13592) (xy 349.962471 -262.084625)
			(xy 349.682561 -262.084625) (xy 349.674436 -262.13592) (xy 349.658388 -262.185313) (xy 349.63481 -262.231587)
			(xy 349.604284 -262.273603) (xy 349.567561 -262.310326) (xy 349.525545 -262.340852) (xy 349.479271 -262.36443)
			(xy 349.429878 -262.380478) (xy 349.378583 -262.388603) (xy 349.326649 -262.388603) (xy 349.275354 -262.380478)
			(xy 349.225961 -262.36443) (xy 349.179687 -262.340852) (xy 349.137671 -262.310326) (xy 349.100948 -262.273603)
			(xy 349.070422 -262.231587) (xy 349.046844 -262.185313) (xy 349.030796 -262.13592) (xy 349.022671 -262.084625)
			(xy 348.742761 -262.084625) (xy 348.734636 -262.13592) (xy 348.718588 -262.185313) (xy 348.69501 -262.231587)
			(xy 348.664484 -262.273603) (xy 348.627761 -262.310326) (xy 348.585745 -262.340852) (xy 348.539471 -262.36443)
			(xy 348.490078 -262.380478) (xy 348.438783 -262.388603) (xy 348.386849 -262.388603) (xy 348.335554 -262.380478)
			(xy 348.286161 -262.36443) (xy 348.239887 -262.340852) (xy 348.197871 -262.310326) (xy 348.161148 -262.273603)
			(xy 348.130622 -262.231587) (xy 348.107044 -262.185313) (xy 348.090996 -262.13592) (xy 348.082871 -262.084625)
			(xy 347.80299 -262.084625) (xy 347.80299 -262.08463) (xy 347.794871 -262.135935) (xy 347.778825 -262.185338)
			(xy 347.755248 -262.231623) (xy 347.72472 -262.273649) (xy 347.687993 -262.310382) (xy 347.645972 -262.340917)
			(xy 347.599692 -262.364502) (xy 347.550292 -262.380557) (xy 347.498988 -262.388686) (xy 347.473016 -262.389112)
			(xy 347.446528 -262.38859) (xy 347.394228 -262.380145) (xy 347.343945 -262.363467) (xy 347.296965 -262.338985)
			(xy 347.25449 -262.307324) (xy 347.217607 -262.269295) (xy 347.201998 -262.247888) (xy 347.193096 -262.236018)
			(xy 347.169858 -262.217592) (xy 347.142311 -262.206607) (xy 347.112771 -262.203987) (xy 347.08372 -262.209952)
			(xy 347.057602 -262.224) (xy 347.046804 -262.234172) (xy 346.91193 -262.369046) (xy 346.902619 -262.378942)
			(xy 346.889135 -262.402521) (xy 346.882354 -262.428823) (xy 346.882758 -262.455981) (xy 346.890317 -262.48207)
			(xy 346.904497 -262.505237) (xy 346.924289 -262.523839) (xy 346.948291 -262.536555) (xy 346.974798 -262.542483)
			(xy 346.988384 -262.542274) (xy 347.002862 -262.54202) (xy 347.028834 -262.5425) (xy 347.080141 -262.55062)
			(xy 347.129545 -262.566667) (xy 347.17583 -262.590245) (xy 347.217857 -262.620774) (xy 347.254591 -262.657501)
			(xy 347.285126 -262.699523) (xy 347.308712 -262.745805) (xy 347.324767 -262.795206) (xy 347.332896 -262.846511)
			(xy 347.332898 -262.898441) (xy 347.612717 -262.898441) (xy 347.612717 -262.846507) (xy 347.620842 -262.795212)
			(xy 347.63689 -262.745819) (xy 347.660468 -262.699545) (xy 347.690994 -262.657529) (xy 347.727717 -262.620806)
			(xy 347.769733 -262.59028) (xy 347.816007 -262.566702) (xy 347.8654 -262.550654) (xy 347.916695 -262.542529)
			(xy 347.968629 -262.542529) (xy 348.019924 -262.550654) (xy 348.069317 -262.566702) (xy 348.115591 -262.59028)
			(xy 348.157607 -262.620806) (xy 348.19433 -262.657529) (xy 348.224856 -262.699545) (xy 348.248434 -262.745819)
			(xy 348.264482 -262.795212) (xy 348.272607 -262.846507) (xy 348.273116 -262.872474) (xy 348.272607 -262.898441)
			(xy 348.552517 -262.898441) (xy 348.552517 -262.846507) (xy 348.560642 -262.795212) (xy 348.57669 -262.745819)
			(xy 348.600268 -262.699545) (xy 348.630794 -262.657529) (xy 348.667517 -262.620806) (xy 348.709533 -262.59028)
			(xy 348.755807 -262.566702) (xy 348.8052 -262.550654) (xy 348.856495 -262.542529) (xy 348.908429 -262.542529)
			(xy 348.959724 -262.550654) (xy 349.009117 -262.566702) (xy 349.055391 -262.59028) (xy 349.097407 -262.620806)
			(xy 349.13413 -262.657529) (xy 349.164656 -262.699545) (xy 349.167221 -262.70458) (xy 351.32391 -262.70458)
			(xy 351.324358 -262.680028) (xy 351.331595 -262.631461) (xy 351.345936 -262.584499) (xy 351.367067 -262.540175)
			(xy 351.394521 -262.499464) (xy 351.410778 -262.48106) (xy 351.420601 -262.469586) (xy 351.433612 -262.442343)
			(xy 351.438076 -262.412485) (xy 351.433603 -262.382628) (xy 351.420584 -262.355389) (xy 351.410778 -262.3439)
			(xy 351.394494 -262.325518) (xy 351.36703 -262.284807) (xy 351.345897 -262.240478) (xy 351.33156 -262.193509)
			(xy 351.324336 -262.144935) (xy 351.32391 -262.12038) (xy 351.324419 -262.094413) (xy 351.332544 -262.043118)
			(xy 351.348592 -261.993725) (xy 351.37217 -261.947451) (xy 351.402696 -261.905435) (xy 351.439419 -261.868712)
			(xy 351.481435 -261.838186) (xy 351.527709 -261.814608) (xy 351.577102 -261.79856) (xy 351.628397 -261.790435)
			(xy 351.680331 -261.790435) (xy 351.731626 -261.79856) (xy 351.781019 -261.814608) (xy 351.827293 -261.838186)
			(xy 351.869309 -261.868712) (xy 351.906032 -261.905435) (xy 351.936558 -261.947451) (xy 351.960136 -261.993725)
			(xy 351.976184 -262.043118) (xy 351.982759 -262.084625) (xy 361.239817 -262.084625) (xy 361.239817 -262.032691)
			(xy 361.247942 -261.981396) (xy 361.26399 -261.932003) (xy 361.287568 -261.885729) (xy 361.318094 -261.843713)
			(xy 361.354817 -261.80699) (xy 361.396833 -261.776464) (xy 361.443107 -261.752886) (xy 361.4925 -261.736838)
			(xy 361.543795 -261.728713) (xy 361.595729 -261.728713) (xy 361.647024 -261.736838) (xy 361.696417 -261.752886)
			(xy 361.742691 -261.776464) (xy 361.784707 -261.80699) (xy 361.82143 -261.843713) (xy 361.851956 -261.885729)
			(xy 361.875534 -261.932003) (xy 361.891582 -261.981396) (xy 361.899707 -262.032691) (xy 361.900216 -262.058658)
			(xy 361.899707 -262.084625) (xy 361.891582 -262.13592) (xy 361.875534 -262.185313) (xy 361.851956 -262.231587)
			(xy 361.82143 -262.273603) (xy 361.784707 -262.310326) (xy 361.742691 -262.340852) (xy 361.696417 -262.36443)
			(xy 361.647024 -262.380478) (xy 361.595729 -262.388603) (xy 361.543795 -262.388603) (xy 361.4925 -262.380478)
			(xy 361.443107 -262.36443) (xy 361.396833 -262.340852) (xy 361.354817 -262.310326) (xy 361.318094 -262.273603)
			(xy 361.287568 -262.231587) (xy 361.26399 -262.185313) (xy 361.247942 -262.13592) (xy 361.239817 -262.084625)
			(xy 351.982759 -262.084625) (xy 351.984309 -262.094413) (xy 351.984818 -262.12038) (xy 351.984399 -262.144933)
			(xy 351.977154 -262.193501) (xy 351.962805 -262.240463) (xy 351.941669 -262.284787) (xy 351.914209 -262.325497)
			(xy 351.89795 -262.3439) (xy 351.888164 -262.355403) (xy 351.875145 -262.382635) (xy 351.870671 -262.412485)
			(xy 351.875136 -262.442337) (xy 351.888147 -262.469572) (xy 351.89795 -262.48106) (xy 351.914204 -262.499468)
			(xy 351.941674 -262.540171) (xy 351.962815 -262.584493) (xy 351.977158 -262.631457) (xy 351.984389 -262.680027)
			(xy 351.984818 -262.70458) (xy 351.984309 -262.730547) (xy 351.976184 -262.781842) (xy 351.960136 -262.831235)
			(xy 351.936558 -262.877509) (xy 351.92135 -262.898441) (xy 357.950517 -262.898441) (xy 357.950517 -262.846507)
			(xy 357.958642 -262.795212) (xy 357.97469 -262.745819) (xy 357.998268 -262.699545) (xy 358.028794 -262.657529)
			(xy 358.065517 -262.620806) (xy 358.107533 -262.59028) (xy 358.153807 -262.566702) (xy 358.2032 -262.550654)
			(xy 358.254495 -262.542529) (xy 358.306429 -262.542529) (xy 358.357724 -262.550654) (xy 358.407117 -262.566702)
			(xy 358.453391 -262.59028) (xy 358.495407 -262.620806) (xy 358.53213 -262.657529) (xy 358.562656 -262.699545)
			(xy 358.586234 -262.745819) (xy 358.602282 -262.795212) (xy 358.610407 -262.846507) (xy 358.610916 -262.872474)
			(xy 358.610407 -262.898441) (xy 358.602282 -262.949736) (xy 358.586234 -262.999129) (xy 358.562656 -263.045403)
			(xy 358.53213 -263.087419) (xy 358.495407 -263.124142) (xy 358.453391 -263.154668) (xy 358.407117 -263.178246)
			(xy 358.357724 -263.194294) (xy 358.306429 -263.202419) (xy 358.254495 -263.202419) (xy 358.2032 -263.194294)
			(xy 358.153807 -263.178246) (xy 358.107533 -263.154668) (xy 358.065517 -263.124142) (xy 358.028794 -263.087419)
			(xy 357.998268 -263.045403) (xy 357.97469 -262.999129) (xy 357.958642 -262.949736) (xy 357.950517 -262.898441)
			(xy 351.92135 -262.898441) (xy 351.906032 -262.919525) (xy 351.869309 -262.956248) (xy 351.827293 -262.986774)
			(xy 351.781019 -263.010352) (xy 351.731626 -263.0264) (xy 351.680331 -263.034525) (xy 351.628397 -263.034525)
			(xy 351.577102 -263.0264) (xy 351.527709 -263.010352) (xy 351.481435 -262.986774) (xy 351.439419 -262.956248)
			(xy 351.402696 -262.919525) (xy 351.37217 -262.877509) (xy 351.348592 -262.831235) (xy 351.332544 -262.781842)
			(xy 351.324419 -262.730547) (xy 351.32391 -262.70458) (xy 349.167221 -262.70458) (xy 349.188234 -262.745819)
			(xy 349.204282 -262.795212) (xy 349.212407 -262.846507) (xy 349.212916 -262.872474) (xy 349.212407 -262.898441)
			(xy 349.204282 -262.949736) (xy 349.188234 -262.999129) (xy 349.164656 -263.045403) (xy 349.13413 -263.087419)
			(xy 349.097407 -263.124142) (xy 349.055391 -263.154668) (xy 349.009117 -263.178246) (xy 348.959724 -263.194294)
			(xy 348.908429 -263.202419) (xy 348.856495 -263.202419) (xy 348.8052 -263.194294) (xy 348.755807 -263.178246)
			(xy 348.709533 -263.154668) (xy 348.667517 -263.124142) (xy 348.630794 -263.087419) (xy 348.600268 -263.045403)
			(xy 348.57669 -262.999129) (xy 348.560642 -262.949736) (xy 348.552517 -262.898441) (xy 348.272607 -262.898441)
			(xy 348.264482 -262.949736) (xy 348.248434 -262.999129) (xy 348.224856 -263.045403) (xy 348.19433 -263.087419)
			(xy 348.157607 -263.124142) (xy 348.115591 -263.154668) (xy 348.069317 -263.178246) (xy 348.019924 -263.194294)
			(xy 347.968629 -263.202419) (xy 347.916695 -263.202419) (xy 347.8654 -263.194294) (xy 347.816007 -263.178246)
			(xy 347.769733 -263.154668) (xy 347.727717 -263.124142) (xy 347.690994 -263.087419) (xy 347.660468 -263.045403)
			(xy 347.63689 -262.999129) (xy 347.620842 -262.949736) (xy 347.612717 -262.898441) (xy 347.332898 -262.898441)
			(xy 347.332898 -262.898456) (xy 347.324775 -262.949761) (xy 347.308725 -262.999164) (xy 347.285144 -263.045448)
			(xy 347.254612 -263.087473) (xy 347.217882 -263.124204) (xy 347.175859 -263.154737) (xy 347.129576 -263.17832)
			(xy 347.080173 -263.194372) (xy 347.028868 -263.202497) (xy 346.976923 -263.202497) (xy 346.925618 -263.19437)
			(xy 346.876216 -263.178316) (xy 346.829933 -263.154732) (xy 346.78791 -263.124198) (xy 346.751182 -263.087466)
			(xy 346.720651 -263.04544) (xy 346.697072 -262.999156) (xy 346.681023 -262.949752) (xy 346.672901 -262.898446)
			(xy 346.672408 -262.872474) (xy 346.672662 -262.857996) (xy 346.672835 -262.844421) (xy 346.666853 -262.81795)
			(xy 346.654111 -262.793989) (xy 346.635509 -262.774229) (xy 346.61236 -262.760065) (xy 346.586298 -262.752497)
			(xy 346.559162 -262.752061) (xy 346.53287 -262.758785) (xy 346.509277 -262.772196) (xy 346.499434 -262.781542)
			(xy 346.39377 -262.887206) (xy 346.391992 -262.90524) (xy 346.389022 -262.930282) (xy 346.376463 -262.979118)
			(xy 346.356631 -263.02548) (xy 346.329988 -263.068292) (xy 346.297151 -263.10656) (xy 346.258881 -263.139396)
			(xy 346.216069 -263.166038) (xy 346.169706 -263.185867) (xy 346.120869 -263.198424) (xy 346.095828 -263.201404)
			(xy 346.077794 -263.203182) (xy 345.829636 -263.45134) (xy 345.85656 -263.486646) (xy 345.872386 -263.508345)
			(xy 345.897529 -263.555799) (xy 345.914666 -263.606695) (xy 345.923345 -263.659692) (xy 345.92387 -263.686544)
			(xy 345.923357 -263.712509) (xy 345.923357 -263.712511) (xy 346.203271 -263.712511) (xy 346.203271 -263.660577)
			(xy 346.211396 -263.609282) (xy 346.227444 -263.559889) (xy 346.251022 -263.513615) (xy 346.281548 -263.471599)
			(xy 346.318271 -263.434876) (xy 346.360287 -263.40435) (xy 346.406561 -263.380772) (xy 346.455954 -263.364724)
			(xy 346.507249 -263.356599) (xy 346.559183 -263.356599) (xy 346.610478 -263.364724) (xy 346.659871 -263.380772)
			(xy 346.706145 -263.40435) (xy 346.748161 -263.434876) (xy 346.784884 -263.471599) (xy 346.81541 -263.513615)
			(xy 346.838988 -263.559889) (xy 346.855036 -263.609282) (xy 346.863161 -263.660577) (xy 346.86367 -263.686544)
			(xy 346.863161 -263.712511) (xy 347.143071 -263.712511) (xy 347.143071 -263.660577) (xy 347.151196 -263.609282)
			(xy 347.167244 -263.559889) (xy 347.190822 -263.513615) (xy 347.221348 -263.471599) (xy 347.258071 -263.434876)
			(xy 347.300087 -263.40435) (xy 347.346361 -263.380772) (xy 347.395754 -263.364724) (xy 347.447049 -263.356599)
			(xy 347.498983 -263.356599) (xy 347.550278 -263.364724) (xy 347.599671 -263.380772) (xy 347.645945 -263.40435)
			(xy 347.687961 -263.434876) (xy 347.724684 -263.471599) (xy 347.75521 -263.513615) (xy 347.778788 -263.559889)
			(xy 347.794836 -263.609282) (xy 347.802961 -263.660577) (xy 347.80347 -263.686544) (xy 347.802961 -263.712511)
			(xy 348.082871 -263.712511) (xy 348.082871 -263.660577) (xy 348.090996 -263.609282) (xy 348.107044 -263.559889)
			(xy 348.130622 -263.513615) (xy 348.161148 -263.471599) (xy 348.197871 -263.434876) (xy 348.239887 -263.40435)
			(xy 348.286161 -263.380772) (xy 348.335554 -263.364724) (xy 348.386849 -263.356599) (xy 348.438783 -263.356599)
			(xy 348.490078 -263.364724) (xy 348.539471 -263.380772) (xy 348.585745 -263.40435) (xy 348.627761 -263.434876)
			(xy 348.664484 -263.471599) (xy 348.69501 -263.513615) (xy 348.718588 -263.559889) (xy 348.734636 -263.609282)
			(xy 348.742761 -263.660577) (xy 348.74327 -263.686544) (xy 348.742761 -263.712511) (xy 349.022417 -263.712511)
			(xy 349.022417 -263.660577) (xy 349.030542 -263.609282) (xy 349.04659 -263.559889) (xy 349.070168 -263.513615)
			(xy 349.100694 -263.471599) (xy 349.137417 -263.434876) (xy 349.179433 -263.40435) (xy 349.225707 -263.380772)
			(xy 349.2751 -263.364724) (xy 349.326395 -263.356599) (xy 349.378329 -263.356599) (xy 349.429624 -263.364724)
			(xy 349.479017 -263.380772) (xy 349.525291 -263.40435) (xy 349.567307 -263.434876) (xy 349.60403 -263.471599)
			(xy 349.634556 -263.513615) (xy 349.658134 -263.559889) (xy 349.674182 -263.609282) (xy 349.682307 -263.660577)
			(xy 349.682816 -263.686544) (xy 349.682307 -263.712511) (xy 349.962471 -263.712511) (xy 349.962471 -263.660577)
			(xy 349.970596 -263.609282) (xy 349.986644 -263.559889) (xy 350.010222 -263.513615) (xy 350.040748 -263.471599)
			(xy 350.077471 -263.434876) (xy 350.119487 -263.40435) (xy 350.165761 -263.380772) (xy 350.215154 -263.364724)
			(xy 350.266449 -263.356599) (xy 350.318383 -263.356599) (xy 350.369678 -263.364724) (xy 350.419071 -263.380772)
			(xy 350.465345 -263.40435) (xy 350.507361 -263.434876) (xy 350.544084 -263.471599) (xy 350.57461 -263.513615)
			(xy 350.598188 -263.559889) (xy 350.614236 -263.609282) (xy 350.622361 -263.660577) (xy 350.62287 -263.686544)
			(xy 350.622361 -263.712511) (xy 361.239817 -263.712511) (xy 361.239817 -263.660577) (xy 361.247942 -263.609282)
			(xy 361.26399 -263.559889) (xy 361.287568 -263.513615) (xy 361.318094 -263.471599) (xy 361.354817 -263.434876)
			(xy 361.396833 -263.40435) (xy 361.443107 -263.380772) (xy 361.4925 -263.364724) (xy 361.543795 -263.356599)
			(xy 361.595729 -263.356599) (xy 361.647024 -263.364724) (xy 361.696417 -263.380772) (xy 361.742691 -263.40435)
			(xy 361.784707 -263.434876) (xy 361.82143 -263.471599) (xy 361.851956 -263.513615) (xy 361.875534 -263.559889)
			(xy 361.891582 -263.609282) (xy 361.899707 -263.660577) (xy 361.900216 -263.686544) (xy 361.899707 -263.712511)
			(xy 361.891582 -263.763806) (xy 361.875534 -263.813199) (xy 361.851956 -263.859473) (xy 361.82143 -263.901489)
			(xy 361.784707 -263.938212) (xy 361.742691 -263.968738) (xy 361.696417 -263.992316) (xy 361.647024 -264.008364)
			(xy 361.595729 -264.016489) (xy 361.543795 -264.016489) (xy 361.4925 -264.008364) (xy 361.443107 -263.992316)
			(xy 361.396833 -263.968738) (xy 361.354817 -263.938212) (xy 361.318094 -263.901489) (xy 361.287568 -263.859473)
			(xy 361.26399 -263.813199) (xy 361.247942 -263.763806) (xy 361.239817 -263.712511) (xy 350.622361 -263.712511)
			(xy 350.614236 -263.763806) (xy 350.598188 -263.813199) (xy 350.57461 -263.859473) (xy 350.544084 -263.901489)
			(xy 350.507361 -263.938212) (xy 350.465345 -263.968738) (xy 350.419071 -263.992316) (xy 350.369678 -264.008364)
			(xy 350.318383 -264.016489) (xy 350.266449 -264.016489) (xy 350.215154 -264.008364) (xy 350.165761 -263.992316)
			(xy 350.119487 -263.968738) (xy 350.077471 -263.938212) (xy 350.040748 -263.901489) (xy 350.010222 -263.859473)
			(xy 349.986644 -263.813199) (xy 349.970596 -263.763806) (xy 349.962471 -263.712511) (xy 349.682307 -263.712511)
			(xy 349.674182 -263.763806) (xy 349.658134 -263.813199) (xy 349.634556 -263.859473) (xy 349.60403 -263.901489)
			(xy 349.567307 -263.938212) (xy 349.525291 -263.968738) (xy 349.479017 -263.992316) (xy 349.429624 -264.008364)
			(xy 349.378329 -264.016489) (xy 349.326395 -264.016489) (xy 349.2751 -264.008364) (xy 349.225707 -263.992316)
			(xy 349.179433 -263.968738) (xy 349.137417 -263.938212) (xy 349.100694 -263.901489) (xy 349.070168 -263.859473)
			(xy 349.04659 -263.813199) (xy 349.030542 -263.763806) (xy 349.022417 -263.712511) (xy 348.742761 -263.712511)
			(xy 348.734636 -263.763806) (xy 348.718588 -263.813199) (xy 348.69501 -263.859473) (xy 348.664484 -263.901489)
			(xy 348.627761 -263.938212) (xy 348.585745 -263.968738) (xy 348.539471 -263.992316) (xy 348.490078 -264.008364)
			(xy 348.438783 -264.016489) (xy 348.386849 -264.016489) (xy 348.335554 -264.008364) (xy 348.286161 -263.992316)
			(xy 348.239887 -263.968738) (xy 348.197871 -263.938212) (xy 348.161148 -263.901489) (xy 348.130622 -263.859473)
			(xy 348.107044 -263.813199) (xy 348.090996 -263.763806) (xy 348.082871 -263.712511) (xy 347.802961 -263.712511)
			(xy 347.794836 -263.763806) (xy 347.778788 -263.813199) (xy 347.75521 -263.859473) (xy 347.724684 -263.901489)
			(xy 347.687961 -263.938212) (xy 347.645945 -263.968738) (xy 347.599671 -263.992316) (xy 347.550278 -264.008364)
			(xy 347.498983 -264.016489) (xy 347.447049 -264.016489) (xy 347.395754 -264.008364) (xy 347.346361 -263.992316)
			(xy 347.300087 -263.968738) (xy 347.258071 -263.938212) (xy 347.221348 -263.901489) (xy 347.190822 -263.859473)
			(xy 347.167244 -263.813199) (xy 347.151196 -263.763806) (xy 347.143071 -263.712511) (xy 346.863161 -263.712511)
			(xy 346.855036 -263.763806) (xy 346.838988 -263.813199) (xy 346.81541 -263.859473) (xy 346.784884 -263.901489)
			(xy 346.748161 -263.938212) (xy 346.706145 -263.968738) (xy 346.659871 -263.992316) (xy 346.610478 -264.008364)
			(xy 346.559183 -264.016489) (xy 346.507249 -264.016489) (xy 346.455954 -264.008364) (xy 346.406561 -263.992316)
			(xy 346.360287 -263.968738) (xy 346.318271 -263.938212) (xy 346.281548 -263.901489) (xy 346.251022 -263.859473)
			(xy 346.227444 -263.813199) (xy 346.211396 -263.763806) (xy 346.203271 -263.712511) (xy 345.923357 -263.712511)
			(xy 345.915228 -263.7638) (xy 345.899175 -263.813188) (xy 345.875596 -263.859457) (xy 345.845069 -263.901468)
			(xy 345.808347 -263.938187) (xy 345.766333 -263.96871) (xy 345.720062 -263.992286) (xy 345.670673 -264.008334)
			(xy 345.619381 -264.01646) (xy 345.593416 -264.016998) (xy 345.566564 -264.016475) (xy 345.513566 -264.007795)
			(xy 345.462669 -263.99066) (xy 345.415212 -263.965521) (xy 345.393518 -263.949688) (xy 345.358212 -263.922764)
			(xy 345.240864 -264.040112) (xy 345.231393 -264.050218) (xy 345.217766 -264.074316) (xy 345.211107 -264.101188)
			(xy 345.211907 -264.128861) (xy 345.220106 -264.155304) (xy 345.235103 -264.178575) (xy 345.255796 -264.196965)
			(xy 345.268042 -264.203434) (xy 345.291539 -264.215442) (xy 345.33471 -264.24578) (xy 345.372505 -264.282598)
			(xy 345.403963 -264.32496) (xy 345.428283 -264.371785) (xy 345.444845 -264.421883) (xy 345.453228 -264.473978)
			(xy 345.453716 -264.50036) (xy 345.453236 -264.526327) (xy 345.733371 -264.526327) (xy 345.733371 -264.474393)
			(xy 345.741496 -264.423098) (xy 345.757544 -264.373705) (xy 345.781122 -264.327431) (xy 345.811648 -264.285415)
			(xy 345.848371 -264.248692) (xy 345.890387 -264.218166) (xy 345.936661 -264.194588) (xy 345.986054 -264.17854)
			(xy 346.037349 -264.170415) (xy 346.089283 -264.170415) (xy 346.140578 -264.17854) (xy 346.189971 -264.194588)
			(xy 346.236245 -264.218166) (xy 346.278261 -264.248692) (xy 346.314984 -264.285415) (xy 346.34551 -264.327431)
			(xy 346.369088 -264.373705) (xy 346.385136 -264.423098) (xy 346.393261 -264.474393) (xy 346.39377 -264.50036)
			(xy 346.393261 -264.526327) (xy 346.672917 -264.526327) (xy 346.672917 -264.474393) (xy 346.681042 -264.423098)
			(xy 346.69709 -264.373705) (xy 346.720668 -264.327431) (xy 346.751194 -264.285415) (xy 346.787917 -264.248692)
			(xy 346.829933 -264.218166) (xy 346.876207 -264.194588) (xy 346.9256 -264.17854) (xy 346.976895 -264.170415)
			(xy 347.028829 -264.170415) (xy 347.080124 -264.17854) (xy 347.129517 -264.194588) (xy 347.175791 -264.218166)
			(xy 347.217807 -264.248692) (xy 347.25453 -264.285415) (xy 347.285056 -264.327431) (xy 347.308634 -264.373705)
			(xy 347.324682 -264.423098) (xy 347.332807 -264.474393) (xy 347.333316 -264.50036) (xy 347.332807 -264.526327)
			(xy 347.612717 -264.526327) (xy 347.612717 -264.474393) (xy 347.620842 -264.423098) (xy 347.63689 -264.373705)
			(xy 347.660468 -264.327431) (xy 347.690994 -264.285415) (xy 347.727717 -264.248692) (xy 347.769733 -264.218166)
			(xy 347.816007 -264.194588) (xy 347.8654 -264.17854) (xy 347.916695 -264.170415) (xy 347.968629 -264.170415)
			(xy 348.019924 -264.17854) (xy 348.069317 -264.194588) (xy 348.115591 -264.218166) (xy 348.157607 -264.248692)
			(xy 348.19433 -264.285415) (xy 348.224856 -264.327431) (xy 348.248434 -264.373705) (xy 348.264482 -264.423098)
			(xy 348.272607 -264.474393) (xy 348.273116 -264.50036) (xy 348.272607 -264.526327) (xy 348.552517 -264.526327)
			(xy 348.552517 -264.474393) (xy 348.560642 -264.423098) (xy 348.57669 -264.373705) (xy 348.600268 -264.327431)
			(xy 348.630794 -264.285415) (xy 348.667517 -264.248692) (xy 348.709533 -264.218166) (xy 348.755807 -264.194588)
			(xy 348.8052 -264.17854) (xy 348.856495 -264.170415) (xy 348.908429 -264.170415) (xy 348.959724 -264.17854)
			(xy 349.009117 -264.194588) (xy 349.055391 -264.218166) (xy 349.097407 -264.248692) (xy 349.13413 -264.285415)
			(xy 349.164656 -264.327431) (xy 349.188234 -264.373705) (xy 349.204282 -264.423098) (xy 349.212407 -264.474393)
			(xy 349.212916 -264.50036) (xy 349.212407 -264.526327) (xy 349.492317 -264.526327) (xy 349.492317 -264.474393)
			(xy 349.500442 -264.423098) (xy 349.51649 -264.373705) (xy 349.540068 -264.327431) (xy 349.570594 -264.285415)
			(xy 349.607317 -264.248692) (xy 349.649333 -264.218166) (xy 349.695607 -264.194588) (xy 349.745 -264.17854)
			(xy 349.796295 -264.170415) (xy 349.848229 -264.170415) (xy 349.899524 -264.17854) (xy 349.948917 -264.194588)
			(xy 349.995191 -264.218166) (xy 350.037207 -264.248692) (xy 350.07393 -264.285415) (xy 350.104456 -264.327431)
			(xy 350.128034 -264.373705) (xy 350.144082 -264.423098) (xy 350.152207 -264.474393) (xy 350.152716 -264.50036)
			(xy 350.152207 -264.526327) (xy 350.432117 -264.526327) (xy 350.432117 -264.474393) (xy 350.440242 -264.423098)
			(xy 350.45629 -264.373705) (xy 350.479868 -264.327431) (xy 350.510394 -264.285415) (xy 350.547117 -264.248692)
			(xy 350.589133 -264.218166) (xy 350.635407 -264.194588) (xy 350.6848 -264.17854) (xy 350.736095 -264.170415)
			(xy 350.788029 -264.170415) (xy 350.839324 -264.17854) (xy 350.888717 -264.194588) (xy 350.934991 -264.218166)
			(xy 350.977007 -264.248692) (xy 351.01373 -264.285415) (xy 351.044256 -264.327431) (xy 351.067834 -264.373705)
			(xy 351.083882 -264.423098) (xy 351.092007 -264.474393) (xy 351.092516 -264.50036) (xy 351.092007 -264.526327)
			(xy 351.371917 -264.526327) (xy 351.371917 -264.474393) (xy 351.380042 -264.423098) (xy 351.39609 -264.373705)
			(xy 351.419668 -264.327431) (xy 351.450194 -264.285415) (xy 351.486917 -264.248692) (xy 351.528933 -264.218166)
			(xy 351.575207 -264.194588) (xy 351.6246 -264.17854) (xy 351.675895 -264.170415) (xy 351.727829 -264.170415)
			(xy 351.779124 -264.17854) (xy 351.828517 -264.194588) (xy 351.874791 -264.218166) (xy 351.916807 -264.248692)
			(xy 351.95353 -264.285415) (xy 351.984056 -264.327431) (xy 352.007634 -264.373705) (xy 352.023682 -264.423098)
			(xy 352.031807 -264.474393) (xy 352.032316 -264.50036) (xy 352.031807 -264.526327) (xy 352.311717 -264.526327)
			(xy 352.311717 -264.474393) (xy 352.319842 -264.423098) (xy 352.33589 -264.373705) (xy 352.359468 -264.327431)
			(xy 352.389994 -264.285415) (xy 352.426717 -264.248692) (xy 352.468733 -264.218166) (xy 352.515007 -264.194588)
			(xy 352.5644 -264.17854) (xy 352.615695 -264.170415) (xy 352.667629 -264.170415) (xy 352.718924 -264.17854)
			(xy 352.768317 -264.194588) (xy 352.814591 -264.218166) (xy 352.856607 -264.248692) (xy 352.89333 -264.285415)
			(xy 352.923856 -264.327431) (xy 352.947434 -264.373705) (xy 352.963482 -264.423098) (xy 352.971607 -264.474393)
			(xy 352.972116 -264.50036) (xy 352.971607 -264.526327) (xy 353.251517 -264.526327) (xy 353.251517 -264.474393)
			(xy 353.259642 -264.423098) (xy 353.27569 -264.373705) (xy 353.299268 -264.327431) (xy 353.329794 -264.285415)
			(xy 353.366517 -264.248692) (xy 353.408533 -264.218166) (xy 353.454807 -264.194588) (xy 353.5042 -264.17854)
			(xy 353.555495 -264.170415) (xy 353.607429 -264.170415) (xy 353.658724 -264.17854) (xy 353.708117 -264.194588)
			(xy 353.754391 -264.218166) (xy 353.796407 -264.248692) (xy 353.83313 -264.285415) (xy 353.863656 -264.327431)
			(xy 353.887234 -264.373705) (xy 353.903282 -264.423098) (xy 353.911407 -264.474393) (xy 353.911916 -264.50036)
			(xy 353.911407 -264.526327) (xy 354.191317 -264.526327) (xy 354.191317 -264.474393) (xy 354.199442 -264.423098)
			(xy 354.21549 -264.373705) (xy 354.239068 -264.327431) (xy 354.269594 -264.285415) (xy 354.306317 -264.248692)
			(xy 354.348333 -264.218166) (xy 354.394607 -264.194588) (xy 354.444 -264.17854) (xy 354.495295 -264.170415)
			(xy 354.547229 -264.170415) (xy 354.598524 -264.17854) (xy 354.647917 -264.194588) (xy 354.694191 -264.218166)
			(xy 354.736207 -264.248692) (xy 354.77293 -264.285415) (xy 354.803456 -264.327431) (xy 354.827034 -264.373705)
			(xy 354.843082 -264.423098) (xy 354.851207 -264.474393) (xy 354.851716 -264.50036) (xy 354.851207 -264.526327)
			(xy 355.131371 -264.526327) (xy 355.131371 -264.474393) (xy 355.139496 -264.423098) (xy 355.155544 -264.373705)
			(xy 355.179122 -264.327431) (xy 355.209648 -264.285415) (xy 355.246371 -264.248692) (xy 355.288387 -264.218166)
			(xy 355.334661 -264.194588) (xy 355.384054 -264.17854) (xy 355.435349 -264.170415) (xy 355.487283 -264.170415)
			(xy 355.538578 -264.17854) (xy 355.587971 -264.194588) (xy 355.634245 -264.218166) (xy 355.676261 -264.248692)
			(xy 355.712984 -264.285415) (xy 355.74351 -264.327431) (xy 355.767088 -264.373705) (xy 355.783136 -264.423098)
			(xy 355.791261 -264.474393) (xy 355.79177 -264.50036) (xy 355.791261 -264.526327) (xy 356.071171 -264.526327)
			(xy 356.071171 -264.474393) (xy 356.079296 -264.423098) (xy 356.095344 -264.373705) (xy 356.118922 -264.327431)
			(xy 356.149448 -264.285415) (xy 356.186171 -264.248692) (xy 356.228187 -264.218166) (xy 356.274461 -264.194588)
			(xy 356.323854 -264.17854) (xy 356.375149 -264.170415) (xy 356.427083 -264.170415) (xy 356.478378 -264.17854)
			(xy 356.527771 -264.194588) (xy 356.574045 -264.218166) (xy 356.616061 -264.248692) (xy 356.652784 -264.285415)
			(xy 356.68331 -264.327431) (xy 356.706888 -264.373705) (xy 356.722936 -264.423098) (xy 356.731061 -264.474393)
			(xy 356.73157 -264.50036) (xy 356.731061 -264.526327) (xy 362.649517 -264.526327) (xy 362.649517 -264.474393)
			(xy 362.657642 -264.423098) (xy 362.67369 -264.373705) (xy 362.697268 -264.327431) (xy 362.727794 -264.285415)
			(xy 362.764517 -264.248692) (xy 362.806533 -264.218166) (xy 362.852807 -264.194588) (xy 362.9022 -264.17854)
			(xy 362.953495 -264.170415) (xy 363.005429 -264.170415) (xy 363.056724 -264.17854) (xy 363.106117 -264.194588)
			(xy 363.152391 -264.218166) (xy 363.194407 -264.248692) (xy 363.23113 -264.285415) (xy 363.261656 -264.327431)
			(xy 363.285234 -264.373705) (xy 363.301282 -264.423098) (xy 363.309407 -264.474393) (xy 363.309916 -264.50036)
			(xy 363.309407 -264.526327) (xy 363.301282 -264.577622) (xy 363.285234 -264.627015) (xy 363.261656 -264.673289)
			(xy 363.23113 -264.715305) (xy 363.194407 -264.752028) (xy 363.152391 -264.782554) (xy 363.106117 -264.806132)
			(xy 363.056724 -264.82218) (xy 363.005429 -264.830305) (xy 362.953495 -264.830305) (xy 362.9022 -264.82218)
			(xy 362.852807 -264.806132) (xy 362.806533 -264.782554) (xy 362.764517 -264.752028) (xy 362.727794 -264.715305)
			(xy 362.697268 -264.673289) (xy 362.67369 -264.627015) (xy 362.657642 -264.577622) (xy 362.649517 -264.526327)
			(xy 356.731061 -264.526327) (xy 356.722936 -264.577622) (xy 356.706888 -264.627015) (xy 356.68331 -264.673289)
			(xy 356.652784 -264.715305) (xy 356.616061 -264.752028) (xy 356.574045 -264.782554) (xy 356.527771 -264.806132)
			(xy 356.478378 -264.82218) (xy 356.427083 -264.830305) (xy 356.375149 -264.830305) (xy 356.323854 -264.82218)
			(xy 356.274461 -264.806132) (xy 356.228187 -264.782554) (xy 356.186171 -264.752028) (xy 356.149448 -264.715305)
			(xy 356.118922 -264.673289) (xy 356.095344 -264.627015) (xy 356.079296 -264.577622) (xy 356.071171 -264.526327)
			(xy 355.791261 -264.526327) (xy 355.783136 -264.577622) (xy 355.767088 -264.627015) (xy 355.74351 -264.673289)
			(xy 355.712984 -264.715305) (xy 355.676261 -264.752028) (xy 355.634245 -264.782554) (xy 355.587971 -264.806132)
			(xy 355.538578 -264.82218) (xy 355.487283 -264.830305) (xy 355.435349 -264.830305) (xy 355.384054 -264.82218)
			(xy 355.334661 -264.806132) (xy 355.288387 -264.782554) (xy 355.246371 -264.752028) (xy 355.209648 -264.715305)
			(xy 355.179122 -264.673289) (xy 355.155544 -264.627015) (xy 355.139496 -264.577622) (xy 355.131371 -264.526327)
			(xy 354.851207 -264.526327) (xy 354.843082 -264.577622) (xy 354.827034 -264.627015) (xy 354.803456 -264.673289)
			(xy 354.77293 -264.715305) (xy 354.736207 -264.752028) (xy 354.694191 -264.782554) (xy 354.647917 -264.806132)
			(xy 354.598524 -264.82218) (xy 354.547229 -264.830305) (xy 354.495295 -264.830305) (xy 354.444 -264.82218)
			(xy 354.394607 -264.806132) (xy 354.348333 -264.782554) (xy 354.306317 -264.752028) (xy 354.269594 -264.715305)
			(xy 354.239068 -264.673289) (xy 354.21549 -264.627015) (xy 354.199442 -264.577622) (xy 354.191317 -264.526327)
			(xy 353.911407 -264.526327) (xy 353.903282 -264.577622) (xy 353.887234 -264.627015) (xy 353.863656 -264.673289)
			(xy 353.83313 -264.715305) (xy 353.796407 -264.752028) (xy 353.754391 -264.782554) (xy 353.708117 -264.806132)
			(xy 353.658724 -264.82218) (xy 353.607429 -264.830305) (xy 353.555495 -264.830305) (xy 353.5042 -264.82218)
			(xy 353.454807 -264.806132) (xy 353.408533 -264.782554) (xy 353.366517 -264.752028) (xy 353.329794 -264.715305)
			(xy 353.299268 -264.673289) (xy 353.27569 -264.627015) (xy 353.259642 -264.577622) (xy 353.251517 -264.526327)
			(xy 352.971607 -264.526327) (xy 352.963482 -264.577622) (xy 352.947434 -264.627015) (xy 352.923856 -264.673289)
			(xy 352.89333 -264.715305) (xy 352.856607 -264.752028) (xy 352.814591 -264.782554) (xy 352.768317 -264.806132)
			(xy 352.718924 -264.82218) (xy 352.667629 -264.830305) (xy 352.615695 -264.830305) (xy 352.5644 -264.82218)
			(xy 352.515007 -264.806132) (xy 352.468733 -264.782554) (xy 352.426717 -264.752028) (xy 352.389994 -264.715305)
			(xy 352.359468 -264.673289) (xy 352.33589 -264.627015) (xy 352.319842 -264.577622) (xy 352.311717 -264.526327)
			(xy 352.031807 -264.526327) (xy 352.023682 -264.577622) (xy 352.007634 -264.627015) (xy 351.984056 -264.673289)
			(xy 351.95353 -264.715305) (xy 351.916807 -264.752028) (xy 351.874791 -264.782554) (xy 351.828517 -264.806132)
			(xy 351.779124 -264.82218) (xy 351.727829 -264.830305) (xy 351.675895 -264.830305) (xy 351.6246 -264.82218)
			(xy 351.575207 -264.806132) (xy 351.528933 -264.782554) (xy 351.486917 -264.752028) (xy 351.450194 -264.715305)
			(xy 351.419668 -264.673289) (xy 351.39609 -264.627015) (xy 351.380042 -264.577622) (xy 351.371917 -264.526327)
			(xy 351.092007 -264.526327) (xy 351.083882 -264.577622) (xy 351.067834 -264.627015) (xy 351.044256 -264.673289)
			(xy 351.01373 -264.715305) (xy 350.977007 -264.752028) (xy 350.934991 -264.782554) (xy 350.888717 -264.806132)
			(xy 350.839324 -264.82218) (xy 350.788029 -264.830305) (xy 350.736095 -264.830305) (xy 350.6848 -264.82218)
			(xy 350.635407 -264.806132) (xy 350.589133 -264.782554) (xy 350.547117 -264.752028) (xy 350.510394 -264.715305)
			(xy 350.479868 -264.673289) (xy 350.45629 -264.627015) (xy 350.440242 -264.577622) (xy 350.432117 -264.526327)
			(xy 350.152207 -264.526327) (xy 350.144082 -264.577622) (xy 350.128034 -264.627015) (xy 350.104456 -264.673289)
			(xy 350.07393 -264.715305) (xy 350.037207 -264.752028) (xy 349.995191 -264.782554) (xy 349.948917 -264.806132)
			(xy 349.899524 -264.82218) (xy 349.848229 -264.830305) (xy 349.796295 -264.830305) (xy 349.745 -264.82218)
			(xy 349.695607 -264.806132) (xy 349.649333 -264.782554) (xy 349.607317 -264.752028) (xy 349.570594 -264.715305)
			(xy 349.540068 -264.673289) (xy 349.51649 -264.627015) (xy 349.500442 -264.577622) (xy 349.492317 -264.526327)
			(xy 349.212407 -264.526327) (xy 349.204282 -264.577622) (xy 349.188234 -264.627015) (xy 349.164656 -264.673289)
			(xy 349.13413 -264.715305) (xy 349.097407 -264.752028) (xy 349.055391 -264.782554) (xy 349.009117 -264.806132)
			(xy 348.959724 -264.82218) (xy 348.908429 -264.830305) (xy 348.856495 -264.830305) (xy 348.8052 -264.82218)
			(xy 348.755807 -264.806132) (xy 348.709533 -264.782554) (xy 348.667517 -264.752028) (xy 348.630794 -264.715305)
			(xy 348.600268 -264.673289) (xy 348.57669 -264.627015) (xy 348.560642 -264.577622) (xy 348.552517 -264.526327)
			(xy 348.272607 -264.526327) (xy 348.264482 -264.577622) (xy 348.248434 -264.627015) (xy 348.224856 -264.673289)
			(xy 348.19433 -264.715305) (xy 348.157607 -264.752028) (xy 348.115591 -264.782554) (xy 348.069317 -264.806132)
			(xy 348.019924 -264.82218) (xy 347.968629 -264.830305) (xy 347.916695 -264.830305) (xy 347.8654 -264.82218)
			(xy 347.816007 -264.806132) (xy 347.769733 -264.782554) (xy 347.727717 -264.752028) (xy 347.690994 -264.715305)
			(xy 347.660468 -264.673289) (xy 347.63689 -264.627015) (xy 347.620842 -264.577622) (xy 347.612717 -264.526327)
			(xy 347.332807 -264.526327) (xy 347.324682 -264.577622) (xy 347.308634 -264.627015) (xy 347.285056 -264.673289)
			(xy 347.25453 -264.715305) (xy 347.217807 -264.752028) (xy 347.175791 -264.782554) (xy 347.129517 -264.806132)
			(xy 347.080124 -264.82218) (xy 347.028829 -264.830305) (xy 346.976895 -264.830305) (xy 346.9256 -264.82218)
			(xy 346.876207 -264.806132) (xy 346.829933 -264.782554) (xy 346.787917 -264.752028) (xy 346.751194 -264.715305)
			(xy 346.720668 -264.673289) (xy 346.69709 -264.627015) (xy 346.681042 -264.577622) (xy 346.672917 -264.526327)
			(xy 346.393261 -264.526327) (xy 346.385136 -264.577622) (xy 346.369088 -264.627015) (xy 346.34551 -264.673289)
			(xy 346.314984 -264.715305) (xy 346.278261 -264.752028) (xy 346.236245 -264.782554) (xy 346.189971 -264.806132)
			(xy 346.140578 -264.82218) (xy 346.089283 -264.830305) (xy 346.037349 -264.830305) (xy 345.986054 -264.82218)
			(xy 345.936661 -264.806132) (xy 345.890387 -264.782554) (xy 345.848371 -264.752028) (xy 345.811648 -264.715305)
			(xy 345.781122 -264.673289) (xy 345.757544 -264.627015) (xy 345.741496 -264.577622) (xy 345.733371 -264.526327)
			(xy 345.453236 -264.526327) (xy 345.453236 -264.52633) (xy 345.445116 -264.577632) (xy 345.429069 -264.627031)
			(xy 345.405491 -264.673312) (xy 345.374962 -264.715333) (xy 345.338235 -264.752061) (xy 345.296214 -264.78259)
			(xy 345.249933 -264.806168) (xy 345.200534 -264.822215) (xy 345.149232 -264.830336) (xy 345.123262 -264.830814)
			(xy 345.096883 -264.830295) (xy 345.044795 -264.821903) (xy 344.994704 -264.805337) (xy 344.947883 -264.78102)
			(xy 344.905523 -264.74957) (xy 344.868701 -264.711786) (xy 344.838352 -264.668629) (xy 344.826336 -264.64514)
			(xy 344.819869 -264.632884) (xy 344.801513 -264.61214) (xy 344.778249 -264.597107) (xy 344.751795 -264.588896)
			(xy 344.724107 -264.588113) (xy 344.697231 -264.594818) (xy 344.673155 -264.608513) (xy 344.663014 -264.617962)
			(xy 344.557604 -264.723372) (xy 344.557604 -264.882122) (xy 344.558027 -264.895333) (xy 344.564818 -264.920868)
			(xy 344.577937 -264.943804) (xy 344.596506 -264.962602) (xy 344.619279 -264.976001) (xy 344.644729 -264.983103)
			(xy 344.657934 -264.983722) (xy 344.68368 -264.984552) (xy 344.734457 -264.99321) (xy 344.783276 -265.00964)
			(xy 344.828955 -265.033446) (xy 344.870388 -265.064049) (xy 344.906572 -265.10071) (xy 344.936629 -265.142541)
			(xy 344.959834 -265.188528) (xy 344.975623 -265.237559) (xy 344.983614 -265.288445) (xy 344.983614 -265.339955)
			(xy 344.983584 -265.340143) (xy 345.263471 -265.340143) (xy 345.263471 -265.288209) (xy 345.271596 -265.236914)
			(xy 345.287644 -265.187521) (xy 345.311222 -265.141247) (xy 345.341748 -265.099231) (xy 345.378471 -265.062508)
			(xy 345.420487 -265.031982) (xy 345.466761 -265.008404) (xy 345.516154 -264.992356) (xy 345.567449 -264.984231)
			(xy 345.619383 -264.984231) (xy 345.670678 -264.992356) (xy 345.720071 -265.008404) (xy 345.766345 -265.031982)
			(xy 345.808361 -265.062508) (xy 345.845084 -265.099231) (xy 345.87561 -265.141247) (xy 345.899188 -265.187521)
			(xy 345.915236 -265.236914) (xy 345.923361 -265.288209) (xy 345.92387 -265.314176) (xy 345.923361 -265.340143)
			(xy 346.203017 -265.340143) (xy 346.203017 -265.288209) (xy 346.211142 -265.236914) (xy 346.22719 -265.187521)
			(xy 346.250768 -265.141247) (xy 346.281294 -265.099231) (xy 346.318017 -265.062508) (xy 346.360033 -265.031982)
			(xy 346.406307 -265.008404) (xy 346.4557 -264.992356) (xy 346.506995 -264.984231) (xy 346.558929 -264.984231)
			(xy 346.610224 -264.992356) (xy 346.659617 -265.008404) (xy 346.705891 -265.031982) (xy 346.747907 -265.062508)
			(xy 346.78463 -265.099231) (xy 346.815156 -265.141247) (xy 346.838734 -265.187521) (xy 346.854782 -265.236914)
			(xy 346.862907 -265.288209) (xy 346.863416 -265.314176) (xy 346.862907 -265.340143) (xy 347.143071 -265.340143)
			(xy 347.143071 -265.288209) (xy 347.151196 -265.236914) (xy 347.167244 -265.187521) (xy 347.190822 -265.141247)
			(xy 347.221348 -265.099231) (xy 347.258071 -265.062508) (xy 347.300087 -265.031982) (xy 347.346361 -265.008404)
			(xy 347.395754 -264.992356) (xy 347.447049 -264.984231) (xy 347.498983 -264.984231) (xy 347.550278 -264.992356)
			(xy 347.599671 -265.008404) (xy 347.645945 -265.031982) (xy 347.687961 -265.062508) (xy 347.724684 -265.099231)
			(xy 347.75521 -265.141247) (xy 347.778788 -265.187521) (xy 347.794836 -265.236914) (xy 347.802961 -265.288209)
			(xy 347.80347 -265.314176) (xy 347.802961 -265.340143) (xy 348.082871 -265.340143) (xy 348.082871 -265.288209)
			(xy 348.090996 -265.236914) (xy 348.107044 -265.187521) (xy 348.130622 -265.141247) (xy 348.161148 -265.099231)
			(xy 348.197871 -265.062508) (xy 348.239887 -265.031982) (xy 348.286161 -265.008404) (xy 348.335554 -264.992356)
			(xy 348.386849 -264.984231) (xy 348.438783 -264.984231) (xy 348.490078 -264.992356) (xy 348.539471 -265.008404)
			(xy 348.585745 -265.031982) (xy 348.627761 -265.062508) (xy 348.664484 -265.099231) (xy 348.69501 -265.141247)
			(xy 348.718588 -265.187521) (xy 348.734636 -265.236914) (xy 348.742761 -265.288209) (xy 348.74327 -265.314176)
			(xy 348.742761 -265.340143) (xy 349.022671 -265.340143) (xy 349.022671 -265.288209) (xy 349.030796 -265.236914)
			(xy 349.046844 -265.187521) (xy 349.070422 -265.141247) (xy 349.100948 -265.099231) (xy 349.137671 -265.062508)
			(xy 349.179687 -265.031982) (xy 349.225961 -265.008404) (xy 349.275354 -264.992356) (xy 349.326649 -264.984231)
			(xy 349.378583 -264.984231) (xy 349.429878 -264.992356) (xy 349.479271 -265.008404) (xy 349.525545 -265.031982)
			(xy 349.567561 -265.062508) (xy 349.604284 -265.099231) (xy 349.63481 -265.141247) (xy 349.658388 -265.187521)
			(xy 349.674436 -265.236914) (xy 349.682561 -265.288209) (xy 349.68307 -265.314176) (xy 349.682561 -265.340143)
			(xy 349.962471 -265.340143) (xy 349.962471 -265.288209) (xy 349.970596 -265.236914) (xy 349.986644 -265.187521)
			(xy 350.010222 -265.141247) (xy 350.040748 -265.099231) (xy 350.077471 -265.062508) (xy 350.119487 -265.031982)
			(xy 350.165761 -265.008404) (xy 350.215154 -264.992356) (xy 350.266449 -264.984231) (xy 350.318383 -264.984231)
			(xy 350.369678 -264.992356) (xy 350.419071 -265.008404) (xy 350.465345 -265.031982) (xy 350.507361 -265.062508)
			(xy 350.544084 -265.099231) (xy 350.57461 -265.141247) (xy 350.598188 -265.187521) (xy 350.614236 -265.236914)
			(xy 350.622361 -265.288209) (xy 350.62287 -265.314176) (xy 350.622361 -265.340143) (xy 350.902271 -265.340143)
			(xy 350.902271 -265.288209) (xy 350.910396 -265.236914) (xy 350.926444 -265.187521) (xy 350.950022 -265.141247)
			(xy 350.980548 -265.099231) (xy 351.017271 -265.062508) (xy 351.059287 -265.031982) (xy 351.105561 -265.008404)
			(xy 351.154954 -264.992356) (xy 351.206249 -264.984231) (xy 351.258183 -264.984231) (xy 351.309478 -264.992356)
			(xy 351.358871 -265.008404) (xy 351.405145 -265.031982) (xy 351.447161 -265.062508) (xy 351.483884 -265.099231)
			(xy 351.51441 -265.141247) (xy 351.537988 -265.187521) (xy 351.554036 -265.236914) (xy 351.562161 -265.288209)
			(xy 351.56267 -265.314176) (xy 351.562161 -265.340143) (xy 351.842071 -265.340143) (xy 351.842071 -265.288209)
			(xy 351.850196 -265.236914) (xy 351.866244 -265.187521) (xy 351.889822 -265.141247) (xy 351.920348 -265.099231)
			(xy 351.957071 -265.062508) (xy 351.999087 -265.031982) (xy 352.045361 -265.008404) (xy 352.094754 -264.992356)
			(xy 352.146049 -264.984231) (xy 352.197983 -264.984231) (xy 352.249278 -264.992356) (xy 352.298671 -265.008404)
			(xy 352.344945 -265.031982) (xy 352.386961 -265.062508) (xy 352.423684 -265.099231) (xy 352.45421 -265.141247)
			(xy 352.477788 -265.187521) (xy 352.493836 -265.236914) (xy 352.501961 -265.288209) (xy 352.50247 -265.314176)
			(xy 352.501961 -265.340143) (xy 352.781871 -265.340143) (xy 352.781871 -265.288209) (xy 352.789996 -265.236914)
			(xy 352.806044 -265.187521) (xy 352.829622 -265.141247) (xy 352.860148 -265.099231) (xy 352.896871 -265.062508)
			(xy 352.938887 -265.031982) (xy 352.985161 -265.008404) (xy 353.034554 -264.992356) (xy 353.085849 -264.984231)
			(xy 353.137783 -264.984231) (xy 353.189078 -264.992356) (xy 353.238471 -265.008404) (xy 353.284745 -265.031982)
			(xy 353.326761 -265.062508) (xy 353.363484 -265.099231) (xy 353.39401 -265.141247) (xy 353.417588 -265.187521)
			(xy 353.433636 -265.236914) (xy 353.441761 -265.288209) (xy 353.44227 -265.314176) (xy 353.441761 -265.340143)
			(xy 353.721671 -265.340143) (xy 353.721671 -265.288209) (xy 353.729796 -265.236914) (xy 353.745844 -265.187521)
			(xy 353.769422 -265.141247) (xy 353.799948 -265.099231) (xy 353.836671 -265.062508) (xy 353.878687 -265.031982)
			(xy 353.924961 -265.008404) (xy 353.974354 -264.992356) (xy 354.025649 -264.984231) (xy 354.077583 -264.984231)
			(xy 354.128878 -264.992356) (xy 354.178271 -265.008404) (xy 354.224545 -265.031982) (xy 354.266561 -265.062508)
			(xy 354.303284 -265.099231) (xy 354.33381 -265.141247) (xy 354.357388 -265.187521) (xy 354.373436 -265.236914)
			(xy 354.381561 -265.288209) (xy 354.38207 -265.314176) (xy 354.381561 -265.340143) (xy 354.661471 -265.340143)
			(xy 354.661471 -265.288209) (xy 354.669596 -265.236914) (xy 354.685644 -265.187521) (xy 354.709222 -265.141247)
			(xy 354.739748 -265.099231) (xy 354.776471 -265.062508) (xy 354.818487 -265.031982) (xy 354.864761 -265.008404)
			(xy 354.914154 -264.992356) (xy 354.965449 -264.984231) (xy 355.017383 -264.984231) (xy 355.068678 -264.992356)
			(xy 355.118071 -265.008404) (xy 355.164345 -265.031982) (xy 355.206361 -265.062508) (xy 355.243084 -265.099231)
			(xy 355.27361 -265.141247) (xy 355.297188 -265.187521) (xy 355.313236 -265.236914) (xy 355.321361 -265.288209)
			(xy 355.32187 -265.314176) (xy 355.321361 -265.340143) (xy 355.601271 -265.340143) (xy 355.601271 -265.288209)
			(xy 355.609396 -265.236914) (xy 355.625444 -265.187521) (xy 355.649022 -265.141247) (xy 355.679548 -265.099231)
			(xy 355.716271 -265.062508) (xy 355.758287 -265.031982) (xy 355.804561 -265.008404) (xy 355.853954 -264.992356)
			(xy 355.905249 -264.984231) (xy 355.957183 -264.984231) (xy 356.008478 -264.992356) (xy 356.057871 -265.008404)
			(xy 356.104145 -265.031982) (xy 356.146161 -265.062508) (xy 356.182884 -265.099231) (xy 356.21341 -265.141247)
			(xy 356.236988 -265.187521) (xy 356.253036 -265.236914) (xy 356.261161 -265.288209) (xy 356.26167 -265.314176)
			(xy 356.261161 -265.340143) (xy 356.541071 -265.340143) (xy 356.541071 -265.288209) (xy 356.549196 -265.236914)
			(xy 356.565244 -265.187521) (xy 356.588822 -265.141247) (xy 356.619348 -265.099231) (xy 356.656071 -265.062508)
			(xy 356.698087 -265.031982) (xy 356.744361 -265.008404) (xy 356.793754 -264.992356) (xy 356.845049 -264.984231)
			(xy 356.896983 -264.984231) (xy 356.948278 -264.992356) (xy 356.997671 -265.008404) (xy 357.043945 -265.031982)
			(xy 357.085961 -265.062508) (xy 357.122684 -265.099231) (xy 357.15321 -265.141247) (xy 357.176788 -265.187521)
			(xy 357.192836 -265.236914) (xy 357.200961 -265.288209) (xy 357.20147 -265.314176) (xy 357.200961 -265.340143)
			(xy 362.179617 -265.340143) (xy 362.179617 -265.288209) (xy 362.187742 -265.236914) (xy 362.20379 -265.187521)
			(xy 362.227368 -265.141247) (xy 362.257894 -265.099231) (xy 362.294617 -265.062508) (xy 362.336633 -265.031982)
			(xy 362.382907 -265.008404) (xy 362.4323 -264.992356) (xy 362.483595 -264.984231) (xy 362.535529 -264.984231)
			(xy 362.586824 -264.992356) (xy 362.636217 -265.008404) (xy 362.682491 -265.031982) (xy 362.724507 -265.062508)
			(xy 362.76123 -265.099231) (xy 362.791756 -265.141247) (xy 362.815334 -265.187521) (xy 362.831382 -265.236914)
			(xy 362.839507 -265.288209) (xy 362.840016 -265.314176) (xy 362.839507 -265.340143) (xy 363.119671 -265.340143)
			(xy 363.119671 -265.288209) (xy 363.127796 -265.236914) (xy 363.143844 -265.187521) (xy 363.167422 -265.141247)
			(xy 363.197948 -265.099231) (xy 363.234671 -265.062508) (xy 363.276687 -265.031982) (xy 363.322961 -265.008404)
			(xy 363.372354 -264.992356) (xy 363.423649 -264.984231) (xy 363.475583 -264.984231) (xy 363.526878 -264.992356)
			(xy 363.576271 -265.008404) (xy 363.622545 -265.031982) (xy 363.664561 -265.062508) (xy 363.701284 -265.099231)
			(xy 363.73181 -265.141247) (xy 363.755388 -265.187521) (xy 363.771436 -265.236914) (xy 363.779561 -265.288209)
			(xy 363.78007 -265.314176) (xy 363.779561 -265.340143) (xy 363.771436 -265.391438) (xy 363.755388 -265.440831)
			(xy 363.73181 -265.487105) (xy 363.701284 -265.529121) (xy 363.664561 -265.565844) (xy 363.622545 -265.59637)
			(xy 363.576271 -265.619948) (xy 363.526878 -265.635996) (xy 363.475583 -265.644121) (xy 363.423649 -265.644121)
			(xy 363.372354 -265.635996) (xy 363.322961 -265.619948) (xy 363.276687 -265.59637) (xy 363.234671 -265.565844)
			(xy 363.197948 -265.529121) (xy 363.167422 -265.487105) (xy 363.143844 -265.440831) (xy 363.127796 -265.391438)
			(xy 363.119671 -265.340143) (xy 362.839507 -265.340143) (xy 362.831382 -265.391438) (xy 362.815334 -265.440831)
			(xy 362.791756 -265.487105) (xy 362.76123 -265.529121) (xy 362.724507 -265.565844) (xy 362.682491 -265.59637)
			(xy 362.636217 -265.619948) (xy 362.586824 -265.635996) (xy 362.535529 -265.644121) (xy 362.483595 -265.644121)
			(xy 362.4323 -265.635996) (xy 362.382907 -265.619948) (xy 362.336633 -265.59637) (xy 362.294617 -265.565844)
			(xy 362.257894 -265.529121) (xy 362.227368 -265.487105) (xy 362.20379 -265.440831) (xy 362.187742 -265.391438)
			(xy 362.179617 -265.340143) (xy 357.200961 -265.340143) (xy 357.192836 -265.391438) (xy 357.176788 -265.440831)
			(xy 357.15321 -265.487105) (xy 357.122684 -265.529121) (xy 357.085961 -265.565844) (xy 357.043945 -265.59637)
			(xy 356.997671 -265.619948) (xy 356.948278 -265.635996) (xy 356.896983 -265.644121) (xy 356.845049 -265.644121)
			(xy 356.793754 -265.635996) (xy 356.744361 -265.619948) (xy 356.698087 -265.59637) (xy 356.656071 -265.565844)
			(xy 356.619348 -265.529121) (xy 356.588822 -265.487105) (xy 356.565244 -265.440831) (xy 356.549196 -265.391438)
			(xy 356.541071 -265.340143) (xy 356.261161 -265.340143) (xy 356.253036 -265.391438) (xy 356.236988 -265.440831)
			(xy 356.21341 -265.487105) (xy 356.182884 -265.529121) (xy 356.146161 -265.565844) (xy 356.104145 -265.59637)
			(xy 356.057871 -265.619948) (xy 356.008478 -265.635996) (xy 355.957183 -265.644121) (xy 355.905249 -265.644121)
			(xy 355.853954 -265.635996) (xy 355.804561 -265.619948) (xy 355.758287 -265.59637) (xy 355.716271 -265.565844)
			(xy 355.679548 -265.529121) (xy 355.649022 -265.487105) (xy 355.625444 -265.440831) (xy 355.609396 -265.391438)
			(xy 355.601271 -265.340143) (xy 355.321361 -265.340143) (xy 355.313236 -265.391438) (xy 355.297188 -265.440831)
			(xy 355.27361 -265.487105) (xy 355.243084 -265.529121) (xy 355.206361 -265.565844) (xy 355.164345 -265.59637)
			(xy 355.118071 -265.619948) (xy 355.068678 -265.635996) (xy 355.017383 -265.644121) (xy 354.965449 -265.644121)
			(xy 354.914154 -265.635996) (xy 354.864761 -265.619948) (xy 354.818487 -265.59637) (xy 354.776471 -265.565844)
			(xy 354.739748 -265.529121) (xy 354.709222 -265.487105) (xy 354.685644 -265.440831) (xy 354.669596 -265.391438)
			(xy 354.661471 -265.340143) (xy 354.381561 -265.340143) (xy 354.373436 -265.391438) (xy 354.357388 -265.440831)
			(xy 354.33381 -265.487105) (xy 354.303284 -265.529121) (xy 354.266561 -265.565844) (xy 354.224545 -265.59637)
			(xy 354.178271 -265.619948) (xy 354.128878 -265.635996) (xy 354.077583 -265.644121) (xy 354.025649 -265.644121)
			(xy 353.974354 -265.635996) (xy 353.924961 -265.619948) (xy 353.878687 -265.59637) (xy 353.836671 -265.565844)
			(xy 353.799948 -265.529121) (xy 353.769422 -265.487105) (xy 353.745844 -265.440831) (xy 353.729796 -265.391438)
			(xy 353.721671 -265.340143) (xy 353.441761 -265.340143) (xy 353.433636 -265.391438) (xy 353.417588 -265.440831)
			(xy 353.39401 -265.487105) (xy 353.363484 -265.529121) (xy 353.326761 -265.565844) (xy 353.284745 -265.59637)
			(xy 353.238471 -265.619948) (xy 353.189078 -265.635996) (xy 353.137783 -265.644121) (xy 353.085849 -265.644121)
			(xy 353.034554 -265.635996) (xy 352.985161 -265.619948) (xy 352.938887 -265.59637) (xy 352.896871 -265.565844)
			(xy 352.860148 -265.529121) (xy 352.829622 -265.487105) (xy 352.806044 -265.440831) (xy 352.789996 -265.391438)
			(xy 352.781871 -265.340143) (xy 352.501961 -265.340143) (xy 352.493836 -265.391438) (xy 352.477788 -265.440831)
			(xy 352.45421 -265.487105) (xy 352.423684 -265.529121) (xy 352.386961 -265.565844) (xy 352.344945 -265.59637)
			(xy 352.298671 -265.619948) (xy 352.249278 -265.635996) (xy 352.197983 -265.644121) (xy 352.146049 -265.644121)
			(xy 352.094754 -265.635996) (xy 352.045361 -265.619948) (xy 351.999087 -265.59637) (xy 351.957071 -265.565844)
			(xy 351.920348 -265.529121) (xy 351.889822 -265.487105) (xy 351.866244 -265.440831) (xy 351.850196 -265.391438)
			(xy 351.842071 -265.340143) (xy 351.562161 -265.340143) (xy 351.554036 -265.391438) (xy 351.537988 -265.440831)
			(xy 351.51441 -265.487105) (xy 351.483884 -265.529121) (xy 351.447161 -265.565844) (xy 351.405145 -265.59637)
			(xy 351.358871 -265.619948) (xy 351.309478 -265.635996) (xy 351.258183 -265.644121) (xy 351.206249 -265.644121)
			(xy 351.154954 -265.635996) (xy 351.105561 -265.619948) (xy 351.059287 -265.59637) (xy 351.017271 -265.565844)
			(xy 350.980548 -265.529121) (xy 350.950022 -265.487105) (xy 350.926444 -265.440831) (xy 350.910396 -265.391438)
			(xy 350.902271 -265.340143) (xy 350.622361 -265.340143) (xy 350.614236 -265.391438) (xy 350.598188 -265.440831)
			(xy 350.57461 -265.487105) (xy 350.544084 -265.529121) (xy 350.507361 -265.565844) (xy 350.465345 -265.59637)
			(xy 350.419071 -265.619948) (xy 350.369678 -265.635996) (xy 350.318383 -265.644121) (xy 350.266449 -265.644121)
			(xy 350.215154 -265.635996) (xy 350.165761 -265.619948) (xy 350.119487 -265.59637) (xy 350.077471 -265.565844)
			(xy 350.040748 -265.529121) (xy 350.010222 -265.487105) (xy 349.986644 -265.440831) (xy 349.970596 -265.391438)
			(xy 349.962471 -265.340143) (xy 349.682561 -265.340143) (xy 349.674436 -265.391438) (xy 349.658388 -265.440831)
			(xy 349.63481 -265.487105) (xy 349.604284 -265.529121) (xy 349.567561 -265.565844) (xy 349.525545 -265.59637)
			(xy 349.479271 -265.619948) (xy 349.429878 -265.635996) (xy 349.378583 -265.644121) (xy 349.326649 -265.644121)
			(xy 349.275354 -265.635996) (xy 349.225961 -265.619948) (xy 349.179687 -265.59637) (xy 349.137671 -265.565844)
			(xy 349.100948 -265.529121) (xy 349.070422 -265.487105) (xy 349.046844 -265.440831) (xy 349.030796 -265.391438)
			(xy 349.022671 -265.340143) (xy 348.742761 -265.340143) (xy 348.734636 -265.391438) (xy 348.718588 -265.440831)
			(xy 348.69501 -265.487105) (xy 348.664484 -265.529121) (xy 348.627761 -265.565844) (xy 348.585745 -265.59637)
			(xy 348.539471 -265.619948) (xy 348.490078 -265.635996) (xy 348.438783 -265.644121) (xy 348.386849 -265.644121)
			(xy 348.335554 -265.635996) (xy 348.286161 -265.619948) (xy 348.239887 -265.59637) (xy 348.197871 -265.565844)
			(xy 348.161148 -265.529121) (xy 348.130622 -265.487105) (xy 348.107044 -265.440831) (xy 348.090996 -265.391438)
			(xy 348.082871 -265.340143) (xy 347.802961 -265.340143) (xy 347.794836 -265.391438) (xy 347.778788 -265.440831)
			(xy 347.75521 -265.487105) (xy 347.724684 -265.529121) (xy 347.687961 -265.565844) (xy 347.645945 -265.59637)
			(xy 347.599671 -265.619948) (xy 347.550278 -265.635996) (xy 347.498983 -265.644121) (xy 347.447049 -265.644121)
			(xy 347.395754 -265.635996) (xy 347.346361 -265.619948) (xy 347.300087 -265.59637) (xy 347.258071 -265.565844)
			(xy 347.221348 -265.529121) (xy 347.190822 -265.487105) (xy 347.167244 -265.440831) (xy 347.151196 -265.391438)
			(xy 347.143071 -265.340143) (xy 346.862907 -265.340143) (xy 346.854782 -265.391438) (xy 346.838734 -265.440831)
			(xy 346.815156 -265.487105) (xy 346.78463 -265.529121) (xy 346.747907 -265.565844) (xy 346.705891 -265.59637)
			(xy 346.659617 -265.619948) (xy 346.610224 -265.635996) (xy 346.558929 -265.644121) (xy 346.506995 -265.644121)
			(xy 346.4557 -265.635996) (xy 346.406307 -265.619948) (xy 346.360033 -265.59637) (xy 346.318017 -265.565844)
			(xy 346.281294 -265.529121) (xy 346.250768 -265.487105) (xy 346.22719 -265.440831) (xy 346.211142 -265.391438)
			(xy 346.203017 -265.340143) (xy 345.923361 -265.340143) (xy 345.915236 -265.391438) (xy 345.899188 -265.440831)
			(xy 345.87561 -265.487105) (xy 345.845084 -265.529121) (xy 345.808361 -265.565844) (xy 345.766345 -265.59637)
			(xy 345.720071 -265.619948) (xy 345.670678 -265.635996) (xy 345.619383 -265.644121) (xy 345.567449 -265.644121)
			(xy 345.516154 -265.635996) (xy 345.466761 -265.619948) (xy 345.420487 -265.59637) (xy 345.378471 -265.565844)
			(xy 345.341748 -265.529121) (xy 345.311222 -265.487105) (xy 345.287644 -265.440831) (xy 345.271596 -265.391438)
			(xy 345.263471 -265.340143) (xy 344.983584 -265.340143) (xy 344.975623 -265.390841) (xy 344.959834 -265.439871)
			(xy 344.93663 -265.485859) (xy 344.906572 -265.527689) (xy 344.870389 -265.56435) (xy 344.828956 -265.594954)
			(xy 344.783277 -265.618759) (xy 344.734458 -265.63519) (xy 344.683681 -265.643848) (xy 344.657934 -265.64463)
			(xy 344.644727 -265.645215) (xy 344.619274 -265.652321) (xy 344.5965 -265.665726) (xy 344.577933 -265.684532)
			(xy 344.564819 -265.707475) (xy 344.558039 -265.733017) (xy 344.557604 -265.74623) (xy 344.557604 -266.154213)
			(xy 344.793317 -266.154213) (xy 344.793317 -266.102279) (xy 344.801442 -266.050984) (xy 344.81749 -266.001591)
			(xy 344.841068 -265.955317) (xy 344.871594 -265.913301) (xy 344.908317 -265.876578) (xy 344.950333 -265.846052)
			(xy 344.996607 -265.822474) (xy 345.046 -265.806426) (xy 345.097295 -265.798301) (xy 345.149229 -265.798301)
			(xy 345.200524 -265.806426) (xy 345.249917 -265.822474) (xy 345.296191 -265.846052) (xy 345.338207 -265.876578)
			(xy 345.37493 -265.913301) (xy 345.405456 -265.955317) (xy 345.429034 -266.001591) (xy 345.445082 -266.050984)
			(xy 345.453207 -266.102279) (xy 345.453716 -266.128246) (xy 345.453207 -266.154213) (xy 345.733117 -266.154213)
			(xy 345.733117 -266.102279) (xy 345.741242 -266.050984) (xy 345.75729 -266.001591) (xy 345.780868 -265.955317)
			(xy 345.811394 -265.913301) (xy 345.848117 -265.876578) (xy 345.890133 -265.846052) (xy 345.936407 -265.822474)
			(xy 345.9858 -265.806426) (xy 346.037095 -265.798301) (xy 346.089029 -265.798301) (xy 346.140324 -265.806426)
			(xy 346.189717 -265.822474) (xy 346.235991 -265.846052) (xy 346.278007 -265.876578) (xy 346.31473 -265.913301)
			(xy 346.345256 -265.955317) (xy 346.368834 -266.001591) (xy 346.384882 -266.050984) (xy 346.393007 -266.102279)
			(xy 346.393516 -266.128246) (xy 346.393007 -266.154213) (xy 346.672917 -266.154213) (xy 346.672917 -266.102279)
			(xy 346.681042 -266.050984) (xy 346.69709 -266.001591) (xy 346.720668 -265.955317) (xy 346.751194 -265.913301)
			(xy 346.787917 -265.876578) (xy 346.829933 -265.846052) (xy 346.876207 -265.822474) (xy 346.9256 -265.806426)
			(xy 346.976895 -265.798301) (xy 347.028829 -265.798301) (xy 347.080124 -265.806426) (xy 347.129517 -265.822474)
			(xy 347.175791 -265.846052) (xy 347.217807 -265.876578) (xy 347.25453 -265.913301) (xy 347.285056 -265.955317)
			(xy 347.308634 -266.001591) (xy 347.324682 -266.050984) (xy 347.332807 -266.102279) (xy 347.333316 -266.128246)
			(xy 347.332807 -266.154213) (xy 347.612717 -266.154213) (xy 347.612717 -266.102279) (xy 347.620842 -266.050984)
			(xy 347.63689 -266.001591) (xy 347.660468 -265.955317) (xy 347.690994 -265.913301) (xy 347.727717 -265.876578)
			(xy 347.769733 -265.846052) (xy 347.816007 -265.822474) (xy 347.8654 -265.806426) (xy 347.916695 -265.798301)
			(xy 347.968629 -265.798301) (xy 348.019924 -265.806426) (xy 348.069317 -265.822474) (xy 348.115591 -265.846052)
			(xy 348.157607 -265.876578) (xy 348.19433 -265.913301) (xy 348.224856 -265.955317) (xy 348.248434 -266.001591)
			(xy 348.264482 -266.050984) (xy 348.272607 -266.102279) (xy 348.273116 -266.128246) (xy 348.272607 -266.154213)
			(xy 348.552517 -266.154213) (xy 348.552517 -266.102279) (xy 348.560642 -266.050984) (xy 348.57669 -266.001591)
			(xy 348.600268 -265.955317) (xy 348.630794 -265.913301) (xy 348.667517 -265.876578) (xy 348.709533 -265.846052)
			(xy 348.755807 -265.822474) (xy 348.8052 -265.806426) (xy 348.856495 -265.798301) (xy 348.908429 -265.798301)
			(xy 348.959724 -265.806426) (xy 349.009117 -265.822474) (xy 349.055391 -265.846052) (xy 349.097407 -265.876578)
			(xy 349.13413 -265.913301) (xy 349.164656 -265.955317) (xy 349.188234 -266.001591) (xy 349.204282 -266.050984)
			(xy 349.212407 -266.102279) (xy 349.212916 -266.128246) (xy 349.212407 -266.154213) (xy 349.492317 -266.154213)
			(xy 349.492317 -266.102279) (xy 349.500442 -266.050984) (xy 349.51649 -266.001591) (xy 349.540068 -265.955317)
			(xy 349.570594 -265.913301) (xy 349.607317 -265.876578) (xy 349.649333 -265.846052) (xy 349.695607 -265.822474)
			(xy 349.745 -265.806426) (xy 349.796295 -265.798301) (xy 349.848229 -265.798301) (xy 349.899524 -265.806426)
			(xy 349.948917 -265.822474) (xy 349.995191 -265.846052) (xy 350.037207 -265.876578) (xy 350.07393 -265.913301)
			(xy 350.104456 -265.955317) (xy 350.128034 -266.001591) (xy 350.144082 -266.050984) (xy 350.152207 -266.102279)
			(xy 350.152716 -266.128246) (xy 350.152207 -266.154213) (xy 350.432117 -266.154213) (xy 350.432117 -266.102279)
			(xy 350.440242 -266.050984) (xy 350.45629 -266.001591) (xy 350.479868 -265.955317) (xy 350.510394 -265.913301)
			(xy 350.547117 -265.876578) (xy 350.589133 -265.846052) (xy 350.635407 -265.822474) (xy 350.6848 -265.806426)
			(xy 350.736095 -265.798301) (xy 350.788029 -265.798301) (xy 350.839324 -265.806426) (xy 350.888717 -265.822474)
			(xy 350.934991 -265.846052) (xy 350.977007 -265.876578) (xy 351.01373 -265.913301) (xy 351.044256 -265.955317)
			(xy 351.067834 -266.001591) (xy 351.083882 -266.050984) (xy 351.092007 -266.102279) (xy 351.092516 -266.128246)
			(xy 351.092007 -266.154213) (xy 351.371917 -266.154213) (xy 351.371917 -266.102279) (xy 351.380042 -266.050984)
			(xy 351.39609 -266.001591) (xy 351.419668 -265.955317) (xy 351.450194 -265.913301) (xy 351.486917 -265.876578)
			(xy 351.528933 -265.846052) (xy 351.575207 -265.822474) (xy 351.6246 -265.806426) (xy 351.675895 -265.798301)
			(xy 351.727829 -265.798301) (xy 351.779124 -265.806426) (xy 351.828517 -265.822474) (xy 351.874791 -265.846052)
			(xy 351.916807 -265.876578) (xy 351.95353 -265.913301) (xy 351.984056 -265.955317) (xy 352.007634 -266.001591)
			(xy 352.023682 -266.050984) (xy 352.031807 -266.102279) (xy 352.032316 -266.128246) (xy 352.031807 -266.154213)
			(xy 352.311717 -266.154213) (xy 352.311717 -266.102279) (xy 352.319842 -266.050984) (xy 352.33589 -266.001591)
			(xy 352.359468 -265.955317) (xy 352.389994 -265.913301) (xy 352.426717 -265.876578) (xy 352.468733 -265.846052)
			(xy 352.515007 -265.822474) (xy 352.5644 -265.806426) (xy 352.615695 -265.798301) (xy 352.667629 -265.798301)
			(xy 352.718924 -265.806426) (xy 352.768317 -265.822474) (xy 352.814591 -265.846052) (xy 352.856607 -265.876578)
			(xy 352.89333 -265.913301) (xy 352.923856 -265.955317) (xy 352.947434 -266.001591) (xy 352.963482 -266.050984)
			(xy 352.971607 -266.102279) (xy 352.972116 -266.128246) (xy 352.971607 -266.154213) (xy 353.251517 -266.154213)
			(xy 353.251517 -266.102279) (xy 353.259642 -266.050984) (xy 353.27569 -266.001591) (xy 353.299268 -265.955317)
			(xy 353.329794 -265.913301) (xy 353.366517 -265.876578) (xy 353.408533 -265.846052) (xy 353.454807 -265.822474)
			(xy 353.5042 -265.806426) (xy 353.555495 -265.798301) (xy 353.607429 -265.798301) (xy 353.658724 -265.806426)
			(xy 353.708117 -265.822474) (xy 353.754391 -265.846052) (xy 353.796407 -265.876578) (xy 353.83313 -265.913301)
			(xy 353.863656 -265.955317) (xy 353.887234 -266.001591) (xy 353.903282 -266.050984) (xy 353.911407 -266.102279)
			(xy 353.911916 -266.128246) (xy 353.911407 -266.154213) (xy 354.191317 -266.154213) (xy 354.191317 -266.102279)
			(xy 354.199442 -266.050984) (xy 354.21549 -266.001591) (xy 354.239068 -265.955317) (xy 354.269594 -265.913301)
			(xy 354.306317 -265.876578) (xy 354.348333 -265.846052) (xy 354.394607 -265.822474) (xy 354.444 -265.806426)
			(xy 354.495295 -265.798301) (xy 354.547229 -265.798301) (xy 354.598524 -265.806426) (xy 354.647917 -265.822474)
			(xy 354.694191 -265.846052) (xy 354.736207 -265.876578) (xy 354.77293 -265.913301) (xy 354.803456 -265.955317)
			(xy 354.827034 -266.001591) (xy 354.843082 -266.050984) (xy 354.851207 -266.102279) (xy 354.851716 -266.128246)
			(xy 354.851207 -266.154213) (xy 355.131117 -266.154213) (xy 355.131117 -266.102279) (xy 355.139242 -266.050984)
			(xy 355.15529 -266.001591) (xy 355.178868 -265.955317) (xy 355.209394 -265.913301) (xy 355.246117 -265.876578)
			(xy 355.288133 -265.846052) (xy 355.334407 -265.822474) (xy 355.3838 -265.806426) (xy 355.435095 -265.798301)
			(xy 355.487029 -265.798301) (xy 355.538324 -265.806426) (xy 355.587717 -265.822474) (xy 355.633991 -265.846052)
			(xy 355.676007 -265.876578) (xy 355.71273 -265.913301) (xy 355.743256 -265.955317) (xy 355.766834 -266.001591)
			(xy 355.782882 -266.050984) (xy 355.791007 -266.102279) (xy 355.791516 -266.128246) (xy 355.791007 -266.154213)
			(xy 356.070917 -266.154213) (xy 356.070917 -266.102279) (xy 356.079042 -266.050984) (xy 356.09509 -266.001591)
			(xy 356.118668 -265.955317) (xy 356.149194 -265.913301) (xy 356.185917 -265.876578) (xy 356.227933 -265.846052)
			(xy 356.274207 -265.822474) (xy 356.3236 -265.806426) (xy 356.374895 -265.798301) (xy 356.426829 -265.798301)
			(xy 356.478124 -265.806426) (xy 356.527517 -265.822474) (xy 356.573791 -265.846052) (xy 356.615807 -265.876578)
			(xy 356.65253 -265.913301) (xy 356.683056 -265.955317) (xy 356.706634 -266.001591) (xy 356.722682 -266.050984)
			(xy 356.730807 -266.102279) (xy 356.731316 -266.128246) (xy 356.730807 -266.154213) (xy 357.010971 -266.154213)
			(xy 357.010971 -266.102279) (xy 357.019096 -266.050984) (xy 357.035144 -266.001591) (xy 357.058722 -265.955317)
			(xy 357.089248 -265.913301) (xy 357.125971 -265.876578) (xy 357.167987 -265.846052) (xy 357.214261 -265.822474)
			(xy 357.263654 -265.806426) (xy 357.314949 -265.798301) (xy 357.366883 -265.798301) (xy 357.418178 -265.806426)
			(xy 357.467571 -265.822474) (xy 357.513845 -265.846052) (xy 357.555861 -265.876578) (xy 357.592584 -265.913301)
			(xy 357.62311 -265.955317) (xy 357.646688 -266.001591) (xy 357.662736 -266.050984) (xy 357.670861 -266.102279)
			(xy 357.67137 -266.128246) (xy 357.670861 -266.154213) (xy 361.709717 -266.154213) (xy 361.709717 -266.102279)
			(xy 361.717842 -266.050984) (xy 361.73389 -266.001591) (xy 361.757468 -265.955317) (xy 361.787994 -265.913301)
			(xy 361.824717 -265.876578) (xy 361.866733 -265.846052) (xy 361.913007 -265.822474) (xy 361.9624 -265.806426)
			(xy 362.013695 -265.798301) (xy 362.065629 -265.798301) (xy 362.116924 -265.806426) (xy 362.166317 -265.822474)
			(xy 362.212591 -265.846052) (xy 362.254607 -265.876578) (xy 362.29133 -265.913301) (xy 362.321856 -265.955317)
			(xy 362.345434 -266.001591) (xy 362.361482 -266.050984) (xy 362.369607 -266.102279) (xy 362.370116 -266.128246)
			(xy 362.369607 -266.154213) (xy 362.649517 -266.154213) (xy 362.649517 -266.102279) (xy 362.657642 -266.050984)
			(xy 362.67369 -266.001591) (xy 362.697268 -265.955317) (xy 362.727794 -265.913301) (xy 362.764517 -265.876578)
			(xy 362.806533 -265.846052) (xy 362.852807 -265.822474) (xy 362.9022 -265.806426) (xy 362.953495 -265.798301)
			(xy 363.005429 -265.798301) (xy 363.056724 -265.806426) (xy 363.106117 -265.822474) (xy 363.152391 -265.846052)
			(xy 363.194407 -265.876578) (xy 363.23113 -265.913301) (xy 363.261656 -265.955317) (xy 363.285234 -266.001591)
			(xy 363.301282 -266.050984) (xy 363.309407 -266.102279) (xy 363.309916 -266.128246) (xy 363.309407 -266.154213)
			(xy 363.301282 -266.205508) (xy 363.285234 -266.254901) (xy 363.261656 -266.301175) (xy 363.23113 -266.343191)
			(xy 363.194407 -266.379914) (xy 363.152391 -266.41044) (xy 363.106117 -266.434018) (xy 363.056724 -266.450066)
			(xy 363.005429 -266.458191) (xy 362.953495 -266.458191) (xy 362.9022 -266.450066) (xy 362.852807 -266.434018)
			(xy 362.806533 -266.41044) (xy 362.764517 -266.379914) (xy 362.727794 -266.343191) (xy 362.697268 -266.301175)
			(xy 362.67369 -266.254901) (xy 362.657642 -266.205508) (xy 362.649517 -266.154213) (xy 362.369607 -266.154213)
			(xy 362.361482 -266.205508) (xy 362.345434 -266.254901) (xy 362.321856 -266.301175) (xy 362.29133 -266.343191)
			(xy 362.254607 -266.379914) (xy 362.212591 -266.41044) (xy 362.166317 -266.434018) (xy 362.116924 -266.450066)
			(xy 362.065629 -266.458191) (xy 362.013695 -266.458191) (xy 361.9624 -266.450066) (xy 361.913007 -266.434018)
			(xy 361.866733 -266.41044) (xy 361.824717 -266.379914) (xy 361.787994 -266.343191) (xy 361.757468 -266.301175)
			(xy 361.73389 -266.254901) (xy 361.717842 -266.205508) (xy 361.709717 -266.154213) (xy 357.670861 -266.154213)
			(xy 357.662736 -266.205508) (xy 357.646688 -266.254901) (xy 357.62311 -266.301175) (xy 357.592584 -266.343191)
			(xy 357.555861 -266.379914) (xy 357.513845 -266.41044) (xy 357.467571 -266.434018) (xy 357.418178 -266.450066)
			(xy 357.366883 -266.458191) (xy 357.314949 -266.458191) (xy 357.263654 -266.450066) (xy 357.214261 -266.434018)
			(xy 357.167987 -266.41044) (xy 357.125971 -266.379914) (xy 357.089248 -266.343191) (xy 357.058722 -266.301175)
			(xy 357.035144 -266.254901) (xy 357.019096 -266.205508) (xy 357.010971 -266.154213) (xy 356.730807 -266.154213)
			(xy 356.722682 -266.205508) (xy 356.706634 -266.254901) (xy 356.683056 -266.301175) (xy 356.65253 -266.343191)
			(xy 356.615807 -266.379914) (xy 356.573791 -266.41044) (xy 356.527517 -266.434018) (xy 356.478124 -266.450066)
			(xy 356.426829 -266.458191) (xy 356.374895 -266.458191) (xy 356.3236 -266.450066) (xy 356.274207 -266.434018)
			(xy 356.227933 -266.41044) (xy 356.185917 -266.379914) (xy 356.149194 -266.343191) (xy 356.118668 -266.301175)
			(xy 356.09509 -266.254901) (xy 356.079042 -266.205508) (xy 356.070917 -266.154213) (xy 355.791007 -266.154213)
			(xy 355.782882 -266.205508) (xy 355.766834 -266.254901) (xy 355.743256 -266.301175) (xy 355.71273 -266.343191)
			(xy 355.676007 -266.379914) (xy 355.633991 -266.41044) (xy 355.587717 -266.434018) (xy 355.538324 -266.450066)
			(xy 355.487029 -266.458191) (xy 355.435095 -266.458191) (xy 355.3838 -266.450066) (xy 355.334407 -266.434018)
			(xy 355.288133 -266.41044) (xy 355.246117 -266.379914) (xy 355.209394 -266.343191) (xy 355.178868 -266.301175)
			(xy 355.15529 -266.254901) (xy 355.139242 -266.205508) (xy 355.131117 -266.154213) (xy 354.851207 -266.154213)
			(xy 354.843082 -266.205508) (xy 354.827034 -266.254901) (xy 354.803456 -266.301175) (xy 354.77293 -266.343191)
			(xy 354.736207 -266.379914) (xy 354.694191 -266.41044) (xy 354.647917 -266.434018) (xy 354.598524 -266.450066)
			(xy 354.547229 -266.458191) (xy 354.495295 -266.458191) (xy 354.444 -266.450066) (xy 354.394607 -266.434018)
			(xy 354.348333 -266.41044) (xy 354.306317 -266.379914) (xy 354.269594 -266.343191) (xy 354.239068 -266.301175)
			(xy 354.21549 -266.254901) (xy 354.199442 -266.205508) (xy 354.191317 -266.154213) (xy 353.911407 -266.154213)
			(xy 353.903282 -266.205508) (xy 353.887234 -266.254901) (xy 353.863656 -266.301175) (xy 353.83313 -266.343191)
			(xy 353.796407 -266.379914) (xy 353.754391 -266.41044) (xy 353.708117 -266.434018) (xy 353.658724 -266.450066)
			(xy 353.607429 -266.458191) (xy 353.555495 -266.458191) (xy 353.5042 -266.450066) (xy 353.454807 -266.434018)
			(xy 353.408533 -266.41044) (xy 353.366517 -266.379914) (xy 353.329794 -266.343191) (xy 353.299268 -266.301175)
			(xy 353.27569 -266.254901) (xy 353.259642 -266.205508) (xy 353.251517 -266.154213) (xy 352.971607 -266.154213)
			(xy 352.963482 -266.205508) (xy 352.947434 -266.254901) (xy 352.923856 -266.301175) (xy 352.89333 -266.343191)
			(xy 352.856607 -266.379914) (xy 352.814591 -266.41044) (xy 352.768317 -266.434018) (xy 352.718924 -266.450066)
			(xy 352.667629 -266.458191) (xy 352.615695 -266.458191) (xy 352.5644 -266.450066) (xy 352.515007 -266.434018)
			(xy 352.468733 -266.41044) (xy 352.426717 -266.379914) (xy 352.389994 -266.343191) (xy 352.359468 -266.301175)
			(xy 352.33589 -266.254901) (xy 352.319842 -266.205508) (xy 352.311717 -266.154213) (xy 352.031807 -266.154213)
			(xy 352.023682 -266.205508) (xy 352.007634 -266.254901) (xy 351.984056 -266.301175) (xy 351.95353 -266.343191)
			(xy 351.916807 -266.379914) (xy 351.874791 -266.41044) (xy 351.828517 -266.434018) (xy 351.779124 -266.450066)
			(xy 351.727829 -266.458191) (xy 351.675895 -266.458191) (xy 351.6246 -266.450066) (xy 351.575207 -266.434018)
			(xy 351.528933 -266.41044) (xy 351.486917 -266.379914) (xy 351.450194 -266.343191) (xy 351.419668 -266.301175)
			(xy 351.39609 -266.254901) (xy 351.380042 -266.205508) (xy 351.371917 -266.154213) (xy 351.092007 -266.154213)
			(xy 351.083882 -266.205508) (xy 351.067834 -266.254901) (xy 351.044256 -266.301175) (xy 351.01373 -266.343191)
			(xy 350.977007 -266.379914) (xy 350.934991 -266.41044) (xy 350.888717 -266.434018) (xy 350.839324 -266.450066)
			(xy 350.788029 -266.458191) (xy 350.736095 -266.458191) (xy 350.6848 -266.450066) (xy 350.635407 -266.434018)
			(xy 350.589133 -266.41044) (xy 350.547117 -266.379914) (xy 350.510394 -266.343191) (xy 350.479868 -266.301175)
			(xy 350.45629 -266.254901) (xy 350.440242 -266.205508) (xy 350.432117 -266.154213) (xy 350.152207 -266.154213)
			(xy 350.144082 -266.205508) (xy 350.128034 -266.254901) (xy 350.104456 -266.301175) (xy 350.07393 -266.343191)
			(xy 350.037207 -266.379914) (xy 349.995191 -266.41044) (xy 349.948917 -266.434018) (xy 349.899524 -266.450066)
			(xy 349.848229 -266.458191) (xy 349.796295 -266.458191) (xy 349.745 -266.450066) (xy 349.695607 -266.434018)
			(xy 349.649333 -266.41044) (xy 349.607317 -266.379914) (xy 349.570594 -266.343191) (xy 349.540068 -266.301175)
			(xy 349.51649 -266.254901) (xy 349.500442 -266.205508) (xy 349.492317 -266.154213) (xy 349.212407 -266.154213)
			(xy 349.204282 -266.205508) (xy 349.188234 -266.254901) (xy 349.164656 -266.301175) (xy 349.13413 -266.343191)
			(xy 349.097407 -266.379914) (xy 349.055391 -266.41044) (xy 349.009117 -266.434018) (xy 348.959724 -266.450066)
			(xy 348.908429 -266.458191) (xy 348.856495 -266.458191) (xy 348.8052 -266.450066) (xy 348.755807 -266.434018)
			(xy 348.709533 -266.41044) (xy 348.667517 -266.379914) (xy 348.630794 -266.343191) (xy 348.600268 -266.301175)
			(xy 348.57669 -266.254901) (xy 348.560642 -266.205508) (xy 348.552517 -266.154213) (xy 348.272607 -266.154213)
			(xy 348.264482 -266.205508) (xy 348.248434 -266.254901) (xy 348.224856 -266.301175) (xy 348.19433 -266.343191)
			(xy 348.157607 -266.379914) (xy 348.115591 -266.41044) (xy 348.069317 -266.434018) (xy 348.019924 -266.450066)
			(xy 347.968629 -266.458191) (xy 347.916695 -266.458191) (xy 347.8654 -266.450066) (xy 347.816007 -266.434018)
			(xy 347.769733 -266.41044) (xy 347.727717 -266.379914) (xy 347.690994 -266.343191) (xy 347.660468 -266.301175)
			(xy 347.63689 -266.254901) (xy 347.620842 -266.205508) (xy 347.612717 -266.154213) (xy 347.332807 -266.154213)
			(xy 347.324682 -266.205508) (xy 347.308634 -266.254901) (xy 347.285056 -266.301175) (xy 347.25453 -266.343191)
			(xy 347.217807 -266.379914) (xy 347.175791 -266.41044) (xy 347.129517 -266.434018) (xy 347.080124 -266.450066)
			(xy 347.028829 -266.458191) (xy 346.976895 -266.458191) (xy 346.9256 -266.450066) (xy 346.876207 -266.434018)
			(xy 346.829933 -266.41044) (xy 346.787917 -266.379914) (xy 346.751194 -266.343191) (xy 346.720668 -266.301175)
			(xy 346.69709 -266.254901) (xy 346.681042 -266.205508) (xy 346.672917 -266.154213) (xy 346.393007 -266.154213)
			(xy 346.384882 -266.205508) (xy 346.368834 -266.254901) (xy 346.345256 -266.301175) (xy 346.31473 -266.343191)
			(xy 346.278007 -266.379914) (xy 346.235991 -266.41044) (xy 346.189717 -266.434018) (xy 346.140324 -266.450066)
			(xy 346.089029 -266.458191) (xy 346.037095 -266.458191) (xy 345.9858 -266.450066) (xy 345.936407 -266.434018)
			(xy 345.890133 -266.41044) (xy 345.848117 -266.379914) (xy 345.811394 -266.343191) (xy 345.780868 -266.301175)
			(xy 345.75729 -266.254901) (xy 345.741242 -266.205508) (xy 345.733117 -266.154213) (xy 345.453207 -266.154213)
			(xy 345.445082 -266.205508) (xy 345.429034 -266.254901) (xy 345.405456 -266.301175) (xy 345.37493 -266.343191)
			(xy 345.338207 -266.379914) (xy 345.296191 -266.41044) (xy 345.249917 -266.434018) (xy 345.200524 -266.450066)
			(xy 345.149229 -266.458191) (xy 345.097295 -266.458191) (xy 345.046 -266.450066) (xy 344.996607 -266.434018)
			(xy 344.950333 -266.41044) (xy 344.908317 -266.379914) (xy 344.871594 -266.343191) (xy 344.841068 -266.301175)
			(xy 344.81749 -266.254901) (xy 344.801442 -266.205508) (xy 344.793317 -266.154213) (xy 344.557604 -266.154213)
			(xy 344.557604 -266.509754) (xy 344.558031 -266.522962) (xy 344.564827 -266.548491) (xy 344.577948 -266.571419)
			(xy 344.596517 -266.59021) (xy 344.619287 -266.603604) (xy 344.644732 -266.610704) (xy 344.657934 -266.611354)
			(xy 344.683678 -266.612184) (xy 344.73445 -266.620841) (xy 344.783264 -266.63727) (xy 344.828939 -266.661073)
			(xy 344.870368 -266.691674) (xy 344.906548 -266.728331) (xy 344.936602 -266.770158) (xy 344.959804 -266.816141)
			(xy 344.975592 -266.865166) (xy 344.983582 -266.916048) (xy 344.983582 -266.967553) (xy 344.983547 -266.967775)
			(xy 345.263217 -266.967775) (xy 345.263217 -266.915841) (xy 345.271342 -266.864546) (xy 345.28739 -266.815153)
			(xy 345.310968 -266.768879) (xy 345.341494 -266.726863) (xy 345.378217 -266.69014) (xy 345.420233 -266.659614)
			(xy 345.466507 -266.636036) (xy 345.5159 -266.619988) (xy 345.567195 -266.611863) (xy 345.619129 -266.611863)
			(xy 345.670424 -266.619988) (xy 345.719817 -266.636036) (xy 345.766091 -266.659614) (xy 345.808107 -266.69014)
			(xy 345.84483 -266.726863) (xy 345.875356 -266.768879) (xy 345.898934 -266.815153) (xy 345.914982 -266.864546)
			(xy 345.923107 -266.915841) (xy 345.923616 -266.941808) (xy 345.923107 -266.967775) (xy 346.203271 -266.967775)
			(xy 346.203271 -266.915841) (xy 346.211396 -266.864546) (xy 346.227444 -266.815153) (xy 346.251022 -266.768879)
			(xy 346.281548 -266.726863) (xy 346.318271 -266.69014) (xy 346.360287 -266.659614) (xy 346.406561 -266.636036)
			(xy 346.455954 -266.619988) (xy 346.507249 -266.611863) (xy 346.559183 -266.611863) (xy 346.610478 -266.619988)
			(xy 346.659871 -266.636036) (xy 346.706145 -266.659614) (xy 346.748161 -266.69014) (xy 346.784884 -266.726863)
			(xy 346.81541 -266.768879) (xy 346.838988 -266.815153) (xy 346.855036 -266.864546) (xy 346.863161 -266.915841)
			(xy 346.86367 -266.941808) (xy 346.863161 -266.967775) (xy 347.143071 -266.967775) (xy 347.143071 -266.915841)
			(xy 347.151196 -266.864546) (xy 347.167244 -266.815153) (xy 347.190822 -266.768879) (xy 347.221348 -266.726863)
			(xy 347.258071 -266.69014) (xy 347.300087 -266.659614) (xy 347.346361 -266.636036) (xy 347.395754 -266.619988)
			(xy 347.447049 -266.611863) (xy 347.498983 -266.611863) (xy 347.550278 -266.619988) (xy 347.599671 -266.636036)
			(xy 347.645945 -266.659614) (xy 347.687961 -266.69014) (xy 347.724684 -266.726863) (xy 347.75521 -266.768879)
			(xy 347.778788 -266.815153) (xy 347.794836 -266.864546) (xy 347.802961 -266.915841) (xy 347.80347 -266.941808)
			(xy 347.802961 -266.967775) (xy 348.082871 -266.967775) (xy 348.082871 -266.915841) (xy 348.090996 -266.864546)
			(xy 348.107044 -266.815153) (xy 348.130622 -266.768879) (xy 348.161148 -266.726863) (xy 348.197871 -266.69014)
			(xy 348.239887 -266.659614) (xy 348.286161 -266.636036) (xy 348.335554 -266.619988) (xy 348.386849 -266.611863)
			(xy 348.438783 -266.611863) (xy 348.490078 -266.619988) (xy 348.539471 -266.636036) (xy 348.585745 -266.659614)
			(xy 348.627761 -266.69014) (xy 348.664484 -266.726863) (xy 348.69501 -266.768879) (xy 348.718588 -266.815153)
			(xy 348.734636 -266.864546) (xy 348.742761 -266.915841) (xy 348.74327 -266.941808) (xy 348.742761 -266.967775)
			(xy 349.022671 -266.967775) (xy 349.022671 -266.915841) (xy 349.030796 -266.864546) (xy 349.046844 -266.815153)
			(xy 349.070422 -266.768879) (xy 349.100948 -266.726863) (xy 349.137671 -266.69014) (xy 349.179687 -266.659614)
			(xy 349.225961 -266.636036) (xy 349.275354 -266.619988) (xy 349.326649 -266.611863) (xy 349.378583 -266.611863)
			(xy 349.429878 -266.619988) (xy 349.479271 -266.636036) (xy 349.525545 -266.659614) (xy 349.567561 -266.69014)
			(xy 349.604284 -266.726863) (xy 349.63481 -266.768879) (xy 349.658388 -266.815153) (xy 349.674436 -266.864546)
			(xy 349.682561 -266.915841) (xy 349.68307 -266.941808) (xy 349.682561 -266.967775) (xy 349.962471 -266.967775)
			(xy 349.962471 -266.915841) (xy 349.970596 -266.864546) (xy 349.986644 -266.815153) (xy 350.010222 -266.768879)
			(xy 350.040748 -266.726863) (xy 350.077471 -266.69014) (xy 350.119487 -266.659614) (xy 350.165761 -266.636036)
			(xy 350.215154 -266.619988) (xy 350.266449 -266.611863) (xy 350.318383 -266.611863) (xy 350.369678 -266.619988)
			(xy 350.419071 -266.636036) (xy 350.465345 -266.659614) (xy 350.507361 -266.69014) (xy 350.544084 -266.726863)
			(xy 350.57461 -266.768879) (xy 350.598188 -266.815153) (xy 350.614236 -266.864546) (xy 350.622361 -266.915841)
			(xy 350.62287 -266.941808) (xy 350.622361 -266.967775) (xy 350.902271 -266.967775) (xy 350.902271 -266.915841)
			(xy 350.910396 -266.864546) (xy 350.926444 -266.815153) (xy 350.950022 -266.768879) (xy 350.980548 -266.726863)
			(xy 351.017271 -266.69014) (xy 351.059287 -266.659614) (xy 351.105561 -266.636036) (xy 351.154954 -266.619988)
			(xy 351.206249 -266.611863) (xy 351.258183 -266.611863) (xy 351.309478 -266.619988) (xy 351.358871 -266.636036)
			(xy 351.405145 -266.659614) (xy 351.447161 -266.69014) (xy 351.483884 -266.726863) (xy 351.51441 -266.768879)
			(xy 351.537988 -266.815153) (xy 351.554036 -266.864546) (xy 351.562161 -266.915841) (xy 351.56267 -266.941808)
			(xy 351.562161 -266.967775) (xy 351.842071 -266.967775) (xy 351.842071 -266.915841) (xy 351.850196 -266.864546)
			(xy 351.866244 -266.815153) (xy 351.889822 -266.768879) (xy 351.920348 -266.726863) (xy 351.957071 -266.69014)
			(xy 351.999087 -266.659614) (xy 352.045361 -266.636036) (xy 352.094754 -266.619988) (xy 352.146049 -266.611863)
			(xy 352.197983 -266.611863) (xy 352.249278 -266.619988) (xy 352.298671 -266.636036) (xy 352.344945 -266.659614)
			(xy 352.386961 -266.69014) (xy 352.423684 -266.726863) (xy 352.45421 -266.768879) (xy 352.477788 -266.815153)
			(xy 352.493836 -266.864546) (xy 352.501961 -266.915841) (xy 352.50247 -266.941808) (xy 352.501961 -266.967775)
			(xy 352.781871 -266.967775) (xy 352.781871 -266.915841) (xy 352.789996 -266.864546) (xy 352.806044 -266.815153)
			(xy 352.829622 -266.768879) (xy 352.860148 -266.726863) (xy 352.896871 -266.69014) (xy 352.938887 -266.659614)
			(xy 352.985161 -266.636036) (xy 353.034554 -266.619988) (xy 353.085849 -266.611863) (xy 353.137783 -266.611863)
			(xy 353.189078 -266.619988) (xy 353.238471 -266.636036) (xy 353.284745 -266.659614) (xy 353.326761 -266.69014)
			(xy 353.363484 -266.726863) (xy 353.39401 -266.768879) (xy 353.417588 -266.815153) (xy 353.433636 -266.864546)
			(xy 353.441761 -266.915841) (xy 353.44227 -266.941808) (xy 353.441761 -266.967775) (xy 353.721671 -266.967775)
			(xy 353.721671 -266.915841) (xy 353.729796 -266.864546) (xy 353.745844 -266.815153) (xy 353.769422 -266.768879)
			(xy 353.799948 -266.726863) (xy 353.836671 -266.69014) (xy 353.878687 -266.659614) (xy 353.924961 -266.636036)
			(xy 353.974354 -266.619988) (xy 354.025649 -266.611863) (xy 354.077583 -266.611863) (xy 354.128878 -266.619988)
			(xy 354.178271 -266.636036) (xy 354.224545 -266.659614) (xy 354.266561 -266.69014) (xy 354.303284 -266.726863)
			(xy 354.33381 -266.768879) (xy 354.357388 -266.815153) (xy 354.373436 -266.864546) (xy 354.381561 -266.915841)
			(xy 354.38207 -266.941808) (xy 354.381561 -266.967775) (xy 354.661471 -266.967775) (xy 354.661471 -266.915841)
			(xy 354.669596 -266.864546) (xy 354.685644 -266.815153) (xy 354.709222 -266.768879) (xy 354.739748 -266.726863)
			(xy 354.776471 -266.69014) (xy 354.818487 -266.659614) (xy 354.864761 -266.636036) (xy 354.914154 -266.619988)
			(xy 354.965449 -266.611863) (xy 355.017383 -266.611863) (xy 355.068678 -266.619988) (xy 355.118071 -266.636036)
			(xy 355.164345 -266.659614) (xy 355.206361 -266.69014) (xy 355.243084 -266.726863) (xy 355.27361 -266.768879)
			(xy 355.297188 -266.815153) (xy 355.313236 -266.864546) (xy 355.321361 -266.915841) (xy 355.32187 -266.941808)
			(xy 355.321361 -266.967775) (xy 355.601271 -266.967775) (xy 355.601271 -266.915841) (xy 355.609396 -266.864546)
			(xy 355.625444 -266.815153) (xy 355.649022 -266.768879) (xy 355.679548 -266.726863) (xy 355.716271 -266.69014)
			(xy 355.758287 -266.659614) (xy 355.804561 -266.636036) (xy 355.853954 -266.619988) (xy 355.905249 -266.611863)
			(xy 355.957183 -266.611863) (xy 356.008478 -266.619988) (xy 356.057871 -266.636036) (xy 356.104145 -266.659614)
			(xy 356.146161 -266.69014) (xy 356.182884 -266.726863) (xy 356.21341 -266.768879) (xy 356.236988 -266.815153)
			(xy 356.253036 -266.864546) (xy 356.261161 -266.915841) (xy 356.26167 -266.941808) (xy 356.261161 -266.967775)
			(xy 356.541071 -266.967775) (xy 356.541071 -266.915841) (xy 356.549196 -266.864546) (xy 356.565244 -266.815153)
			(xy 356.588822 -266.768879) (xy 356.619348 -266.726863) (xy 356.656071 -266.69014) (xy 356.698087 -266.659614)
			(xy 356.744361 -266.636036) (xy 356.793754 -266.619988) (xy 356.845049 -266.611863) (xy 356.896983 -266.611863)
			(xy 356.948278 -266.619988) (xy 356.997671 -266.636036) (xy 357.043945 -266.659614) (xy 357.085961 -266.69014)
			(xy 357.122684 -266.726863) (xy 357.15321 -266.768879) (xy 357.176788 -266.815153) (xy 357.192836 -266.864546)
			(xy 357.200961 -266.915841) (xy 357.20147 -266.941808) (xy 357.200961 -266.967775) (xy 357.480617 -266.967775)
			(xy 357.480617 -266.915841) (xy 357.488742 -266.864546) (xy 357.50479 -266.815153) (xy 357.528368 -266.768879)
			(xy 357.558894 -266.726863) (xy 357.595617 -266.69014) (xy 357.637633 -266.659614) (xy 357.683907 -266.636036)
			(xy 357.7333 -266.619988) (xy 357.784595 -266.611863) (xy 357.836529 -266.611863) (xy 357.887824 -266.619988)
			(xy 357.937217 -266.636036) (xy 357.983491 -266.659614) (xy 358.025507 -266.69014) (xy 358.06223 -266.726863)
			(xy 358.092756 -266.768879) (xy 358.116334 -266.815153) (xy 358.132382 -266.864546) (xy 358.140507 -266.915841)
			(xy 358.141016 -266.941808) (xy 358.140507 -266.967775) (xy 361.239817 -266.967775) (xy 361.239817 -266.915841)
			(xy 361.247942 -266.864546) (xy 361.26399 -266.815153) (xy 361.287568 -266.768879) (xy 361.318094 -266.726863)
			(xy 361.354817 -266.69014) (xy 361.396833 -266.659614) (xy 361.443107 -266.636036) (xy 361.4925 -266.619988)
			(xy 361.543795 -266.611863) (xy 361.595729 -266.611863) (xy 361.647024 -266.619988) (xy 361.696417 -266.636036)
			(xy 361.742691 -266.659614) (xy 361.784707 -266.69014) (xy 361.82143 -266.726863) (xy 361.851956 -266.768879)
			(xy 361.875534 -266.815153) (xy 361.891582 -266.864546) (xy 361.899707 -266.915841) (xy 361.900216 -266.941808)
			(xy 361.899707 -266.967775) (xy 362.179617 -266.967775) (xy 362.179617 -266.915841) (xy 362.187742 -266.864546)
			(xy 362.20379 -266.815153) (xy 362.227368 -266.768879) (xy 362.257894 -266.726863) (xy 362.294617 -266.69014)
			(xy 362.336633 -266.659614) (xy 362.382907 -266.636036) (xy 362.4323 -266.619988) (xy 362.483595 -266.611863)
			(xy 362.535529 -266.611863) (xy 362.586824 -266.619988) (xy 362.636217 -266.636036) (xy 362.682491 -266.659614)
			(xy 362.724507 -266.69014) (xy 362.76123 -266.726863) (xy 362.791756 -266.768879) (xy 362.815334 -266.815153)
			(xy 362.831382 -266.864546) (xy 362.839507 -266.915841) (xy 362.840016 -266.941808) (xy 362.839507 -266.967775)
			(xy 363.119417 -266.967775) (xy 363.119417 -266.915841) (xy 363.127542 -266.864546) (xy 363.14359 -266.815153)
			(xy 363.167168 -266.768879) (xy 363.197694 -266.726863) (xy 363.234417 -266.69014) (xy 363.276433 -266.659614)
			(xy 363.322707 -266.636036) (xy 363.3721 -266.619988) (xy 363.423395 -266.611863) (xy 363.475329 -266.611863)
			(xy 363.526624 -266.619988) (xy 363.576017 -266.636036) (xy 363.622291 -266.659614) (xy 363.664307 -266.69014)
			(xy 363.70103 -266.726863) (xy 363.731556 -266.768879) (xy 363.755134 -266.815153) (xy 363.771182 -266.864546)
			(xy 363.779307 -266.915841) (xy 363.779816 -266.941808) (xy 363.779307 -266.967775) (xy 363.771182 -267.01907)
			(xy 363.755134 -267.068463) (xy 363.731556 -267.114737) (xy 363.70103 -267.156753) (xy 363.664307 -267.193476)
			(xy 363.622291 -267.224002) (xy 363.576017 -267.24758) (xy 363.526624 -267.263628) (xy 363.475329 -267.271753)
			(xy 363.423395 -267.271753) (xy 363.3721 -267.263628) (xy 363.322707 -267.24758) (xy 363.276433 -267.224002)
			(xy 363.234417 -267.193476) (xy 363.197694 -267.156753) (xy 363.167168 -267.114737) (xy 363.14359 -267.068463)
			(xy 363.127542 -267.01907) (xy 363.119417 -266.967775) (xy 362.839507 -266.967775) (xy 362.831382 -267.01907)
			(xy 362.815334 -267.068463) (xy 362.791756 -267.114737) (xy 362.76123 -267.156753) (xy 362.724507 -267.193476)
			(xy 362.682491 -267.224002) (xy 362.636217 -267.24758) (xy 362.586824 -267.263628) (xy 362.535529 -267.271753)
			(xy 362.483595 -267.271753) (xy 362.4323 -267.263628) (xy 362.382907 -267.24758) (xy 362.336633 -267.224002)
			(xy 362.294617 -267.193476) (xy 362.257894 -267.156753) (xy 362.227368 -267.114737) (xy 362.20379 -267.068463)
			(xy 362.187742 -267.01907) (xy 362.179617 -266.967775) (xy 361.899707 -266.967775) (xy 361.891582 -267.01907)
			(xy 361.875534 -267.068463) (xy 361.851956 -267.114737) (xy 361.82143 -267.156753) (xy 361.784707 -267.193476)
			(xy 361.742691 -267.224002) (xy 361.696417 -267.24758) (xy 361.647024 -267.263628) (xy 361.595729 -267.271753)
			(xy 361.543795 -267.271753) (xy 361.4925 -267.263628) (xy 361.443107 -267.24758) (xy 361.396833 -267.224002)
			(xy 361.354817 -267.193476) (xy 361.318094 -267.156753) (xy 361.287568 -267.114737) (xy 361.26399 -267.068463)
			(xy 361.247942 -267.01907) (xy 361.239817 -266.967775) (xy 358.140507 -266.967775) (xy 358.132382 -267.01907)
			(xy 358.116334 -267.068463) (xy 358.092756 -267.114737) (xy 358.06223 -267.156753) (xy 358.025507 -267.193476)
			(xy 357.983491 -267.224002) (xy 357.937217 -267.24758) (xy 357.887824 -267.263628) (xy 357.836529 -267.271753)
			(xy 357.784595 -267.271753) (xy 357.7333 -267.263628) (xy 357.683907 -267.24758) (xy 357.637633 -267.224002)
			(xy 357.595617 -267.193476) (xy 357.558894 -267.156753) (xy 357.528368 -267.114737) (xy 357.50479 -267.068463)
			(xy 357.488742 -267.01907) (xy 357.480617 -266.967775) (xy 357.200961 -266.967775) (xy 357.192836 -267.01907)
			(xy 357.176788 -267.068463) (xy 357.15321 -267.114737) (xy 357.122684 -267.156753) (xy 357.085961 -267.193476)
			(xy 357.043945 -267.224002) (xy 356.997671 -267.24758) (xy 356.948278 -267.263628) (xy 356.896983 -267.271753)
			(xy 356.845049 -267.271753) (xy 356.793754 -267.263628) (xy 356.744361 -267.24758) (xy 356.698087 -267.224002)
			(xy 356.656071 -267.193476) (xy 356.619348 -267.156753) (xy 356.588822 -267.114737) (xy 356.565244 -267.068463)
			(xy 356.549196 -267.01907) (xy 356.541071 -266.967775) (xy 356.261161 -266.967775) (xy 356.253036 -267.01907)
			(xy 356.236988 -267.068463) (xy 356.21341 -267.114737) (xy 356.182884 -267.156753) (xy 356.146161 -267.193476)
			(xy 356.104145 -267.224002) (xy 356.057871 -267.24758) (xy 356.008478 -267.263628) (xy 355.957183 -267.271753)
			(xy 355.905249 -267.271753) (xy 355.853954 -267.263628) (xy 355.804561 -267.24758) (xy 355.758287 -267.224002)
			(xy 355.716271 -267.193476) (xy 355.679548 -267.156753) (xy 355.649022 -267.114737) (xy 355.625444 -267.068463)
			(xy 355.609396 -267.01907) (xy 355.601271 -266.967775) (xy 355.321361 -266.967775) (xy 355.313236 -267.01907)
			(xy 355.297188 -267.068463) (xy 355.27361 -267.114737) (xy 355.243084 -267.156753) (xy 355.206361 -267.193476)
			(xy 355.164345 -267.224002) (xy 355.118071 -267.24758) (xy 355.068678 -267.263628) (xy 355.017383 -267.271753)
			(xy 354.965449 -267.271753) (xy 354.914154 -267.263628) (xy 354.864761 -267.24758) (xy 354.818487 -267.224002)
			(xy 354.776471 -267.193476) (xy 354.739748 -267.156753) (xy 354.709222 -267.114737) (xy 354.685644 -267.068463)
			(xy 354.669596 -267.01907) (xy 354.661471 -266.967775) (xy 354.381561 -266.967775) (xy 354.373436 -267.01907)
			(xy 354.357388 -267.068463) (xy 354.33381 -267.114737) (xy 354.303284 -267.156753) (xy 354.266561 -267.193476)
			(xy 354.224545 -267.224002) (xy 354.178271 -267.24758) (xy 354.128878 -267.263628) (xy 354.077583 -267.271753)
			(xy 354.025649 -267.271753) (xy 353.974354 -267.263628) (xy 353.924961 -267.24758) (xy 353.878687 -267.224002)
			(xy 353.836671 -267.193476) (xy 353.799948 -267.156753) (xy 353.769422 -267.114737) (xy 353.745844 -267.068463)
			(xy 353.729796 -267.01907) (xy 353.721671 -266.967775) (xy 353.441761 -266.967775) (xy 353.433636 -267.01907)
			(xy 353.417588 -267.068463) (xy 353.39401 -267.114737) (xy 353.363484 -267.156753) (xy 353.326761 -267.193476)
			(xy 353.284745 -267.224002) (xy 353.238471 -267.24758) (xy 353.189078 -267.263628) (xy 353.137783 -267.271753)
			(xy 353.085849 -267.271753) (xy 353.034554 -267.263628) (xy 352.985161 -267.24758) (xy 352.938887 -267.224002)
			(xy 352.896871 -267.193476) (xy 352.860148 -267.156753) (xy 352.829622 -267.114737) (xy 352.806044 -267.068463)
			(xy 352.789996 -267.01907) (xy 352.781871 -266.967775) (xy 352.501961 -266.967775) (xy 352.493836 -267.01907)
			(xy 352.477788 -267.068463) (xy 352.45421 -267.114737) (xy 352.423684 -267.156753) (xy 352.386961 -267.193476)
			(xy 352.344945 -267.224002) (xy 352.298671 -267.24758) (xy 352.249278 -267.263628) (xy 352.197983 -267.271753)
			(xy 352.146049 -267.271753) (xy 352.094754 -267.263628) (xy 352.045361 -267.24758) (xy 351.999087 -267.224002)
			(xy 351.957071 -267.193476) (xy 351.920348 -267.156753) (xy 351.889822 -267.114737) (xy 351.866244 -267.068463)
			(xy 351.850196 -267.01907) (xy 351.842071 -266.967775) (xy 351.562161 -266.967775) (xy 351.554036 -267.01907)
			(xy 351.537988 -267.068463) (xy 351.51441 -267.114737) (xy 351.483884 -267.156753) (xy 351.447161 -267.193476)
			(xy 351.405145 -267.224002) (xy 351.358871 -267.24758) (xy 351.309478 -267.263628) (xy 351.258183 -267.271753)
			(xy 351.206249 -267.271753) (xy 351.154954 -267.263628) (xy 351.105561 -267.24758) (xy 351.059287 -267.224002)
			(xy 351.017271 -267.193476) (xy 350.980548 -267.156753) (xy 350.950022 -267.114737) (xy 350.926444 -267.068463)
			(xy 350.910396 -267.01907) (xy 350.902271 -266.967775) (xy 350.622361 -266.967775) (xy 350.614236 -267.01907)
			(xy 350.598188 -267.068463) (xy 350.57461 -267.114737) (xy 350.544084 -267.156753) (xy 350.507361 -267.193476)
			(xy 350.465345 -267.224002) (xy 350.419071 -267.24758) (xy 350.369678 -267.263628) (xy 350.318383 -267.271753)
			(xy 350.266449 -267.271753) (xy 350.215154 -267.263628) (xy 350.165761 -267.24758) (xy 350.119487 -267.224002)
			(xy 350.077471 -267.193476) (xy 350.040748 -267.156753) (xy 350.010222 -267.114737) (xy 349.986644 -267.068463)
			(xy 349.970596 -267.01907) (xy 349.962471 -266.967775) (xy 349.682561 -266.967775) (xy 349.674436 -267.01907)
			(xy 349.658388 -267.068463) (xy 349.63481 -267.114737) (xy 349.604284 -267.156753) (xy 349.567561 -267.193476)
			(xy 349.525545 -267.224002) (xy 349.479271 -267.24758) (xy 349.429878 -267.263628) (xy 349.378583 -267.271753)
			(xy 349.326649 -267.271753) (xy 349.275354 -267.263628) (xy 349.225961 -267.24758) (xy 349.179687 -267.224002)
			(xy 349.137671 -267.193476) (xy 349.100948 -267.156753) (xy 349.070422 -267.114737) (xy 349.046844 -267.068463)
			(xy 349.030796 -267.01907) (xy 349.022671 -266.967775) (xy 348.742761 -266.967775) (xy 348.734636 -267.01907)
			(xy 348.718588 -267.068463) (xy 348.69501 -267.114737) (xy 348.664484 -267.156753) (xy 348.627761 -267.193476)
			(xy 348.585745 -267.224002) (xy 348.539471 -267.24758) (xy 348.490078 -267.263628) (xy 348.438783 -267.271753)
			(xy 348.386849 -267.271753) (xy 348.335554 -267.263628) (xy 348.286161 -267.24758) (xy 348.239887 -267.224002)
			(xy 348.197871 -267.193476) (xy 348.161148 -267.156753) (xy 348.130622 -267.114737) (xy 348.107044 -267.068463)
			(xy 348.090996 -267.01907) (xy 348.082871 -266.967775) (xy 347.802961 -266.967775) (xy 347.794836 -267.01907)
			(xy 347.778788 -267.068463) (xy 347.75521 -267.114737) (xy 347.724684 -267.156753) (xy 347.687961 -267.193476)
			(xy 347.645945 -267.224002) (xy 347.599671 -267.24758) (xy 347.550278 -267.263628) (xy 347.498983 -267.271753)
			(xy 347.447049 -267.271753) (xy 347.395754 -267.263628) (xy 347.346361 -267.24758) (xy 347.300087 -267.224002)
			(xy 347.258071 -267.193476) (xy 347.221348 -267.156753) (xy 347.190822 -267.114737) (xy 347.167244 -267.068463)
			(xy 347.151196 -267.01907) (xy 347.143071 -266.967775) (xy 346.863161 -266.967775) (xy 346.855036 -267.01907)
			(xy 346.838988 -267.068463) (xy 346.81541 -267.114737) (xy 346.784884 -267.156753) (xy 346.748161 -267.193476)
			(xy 346.706145 -267.224002) (xy 346.659871 -267.24758) (xy 346.610478 -267.263628) (xy 346.559183 -267.271753)
			(xy 346.507249 -267.271753) (xy 346.455954 -267.263628) (xy 346.406561 -267.24758) (xy 346.360287 -267.224002)
			(xy 346.318271 -267.193476) (xy 346.281548 -267.156753) (xy 346.251022 -267.114737) (xy 346.227444 -267.068463)
			(xy 346.211396 -267.01907) (xy 346.203271 -266.967775) (xy 345.923107 -266.967775) (xy 345.914982 -267.01907)
			(xy 345.898934 -267.068463) (xy 345.875356 -267.114737) (xy 345.84483 -267.156753) (xy 345.808107 -267.193476)
			(xy 345.766091 -267.224002) (xy 345.719817 -267.24758) (xy 345.670424 -267.263628) (xy 345.619129 -267.271753)
			(xy 345.567195 -267.271753) (xy 345.5159 -267.263628) (xy 345.466507 -267.24758) (xy 345.420233 -267.224002)
			(xy 345.378217 -267.193476) (xy 345.341494 -267.156753) (xy 345.310968 -267.114737) (xy 345.28739 -267.068463)
			(xy 345.271342 -267.01907) (xy 345.263217 -266.967775) (xy 344.983547 -266.967775) (xy 344.975592 -267.018434)
			(xy 344.959804 -267.067459) (xy 344.936602 -267.113442) (xy 344.906547 -267.155269) (xy 344.870368 -267.191926)
			(xy 344.828939 -267.222527) (xy 344.783264 -267.24633) (xy 344.73445 -267.262759) (xy 344.683678 -267.271416)
			(xy 344.657934 -267.272262) (xy 344.644729 -267.272848) (xy 344.619279 -267.279954) (xy 344.596509 -267.29336)
			(xy 344.577947 -267.312166) (xy 344.56484 -267.33511) (xy 344.558067 -267.36065) (xy 344.557604 -267.373862)
			(xy 344.557604 -267.781845) (xy 344.793571 -267.781845) (xy 344.793571 -267.729911) (xy 344.801696 -267.678616)
			(xy 344.817744 -267.629223) (xy 344.841322 -267.582949) (xy 344.871848 -267.540933) (xy 344.908571 -267.50421)
			(xy 344.950587 -267.473684) (xy 344.996861 -267.450106) (xy 345.046254 -267.434058) (xy 345.097549 -267.425933)
			(xy 345.149483 -267.425933) (xy 345.200778 -267.434058) (xy 345.250171 -267.450106) (xy 345.296445 -267.473684)
			(xy 345.338461 -267.50421) (xy 345.375184 -267.540933) (xy 345.40571 -267.582949) (xy 345.429288 -267.629223)
			(xy 345.445336 -267.678616) (xy 345.453461 -267.729911) (xy 345.45397 -267.755878) (xy 345.453461 -267.781845)
			(xy 345.733117 -267.781845) (xy 345.733117 -267.729911) (xy 345.741242 -267.678616) (xy 345.75729 -267.629223)
			(xy 345.780868 -267.582949) (xy 345.811394 -267.540933) (xy 345.848117 -267.50421) (xy 345.890133 -267.473684)
			(xy 345.936407 -267.450106) (xy 345.9858 -267.434058) (xy 346.037095 -267.425933) (xy 346.089029 -267.425933)
			(xy 346.140324 -267.434058) (xy 346.189717 -267.450106) (xy 346.235991 -267.473684) (xy 346.278007 -267.50421)
			(xy 346.31473 -267.540933) (xy 346.345256 -267.582949) (xy 346.368834 -267.629223) (xy 346.384882 -267.678616)
			(xy 346.393007 -267.729911) (xy 346.393516 -267.755878) (xy 346.393007 -267.781845) (xy 346.672917 -267.781845)
			(xy 346.672917 -267.729911) (xy 346.681042 -267.678616) (xy 346.69709 -267.629223) (xy 346.720668 -267.582949)
			(xy 346.751194 -267.540933) (xy 346.787917 -267.50421) (xy 346.829933 -267.473684) (xy 346.876207 -267.450106)
			(xy 346.9256 -267.434058) (xy 346.976895 -267.425933) (xy 347.028829 -267.425933) (xy 347.080124 -267.434058)
			(xy 347.129517 -267.450106) (xy 347.175791 -267.473684) (xy 347.217807 -267.50421) (xy 347.25453 -267.540933)
			(xy 347.285056 -267.582949) (xy 347.308634 -267.629223) (xy 347.324682 -267.678616) (xy 347.332807 -267.729911)
			(xy 347.333316 -267.755878) (xy 347.332807 -267.781845) (xy 347.612717 -267.781845) (xy 347.612717 -267.729911)
			(xy 347.620842 -267.678616) (xy 347.63689 -267.629223) (xy 347.660468 -267.582949) (xy 347.690994 -267.540933)
			(xy 347.727717 -267.50421) (xy 347.769733 -267.473684) (xy 347.816007 -267.450106) (xy 347.8654 -267.434058)
			(xy 347.916695 -267.425933) (xy 347.968629 -267.425933) (xy 348.019924 -267.434058) (xy 348.069317 -267.450106)
			(xy 348.115591 -267.473684) (xy 348.157607 -267.50421) (xy 348.19433 -267.540933) (xy 348.224856 -267.582949)
			(xy 348.248434 -267.629223) (xy 348.264482 -267.678616) (xy 348.272607 -267.729911) (xy 348.273116 -267.755878)
			(xy 348.272607 -267.781845) (xy 348.552517 -267.781845) (xy 348.552517 -267.729911) (xy 348.560642 -267.678616)
			(xy 348.57669 -267.629223) (xy 348.600268 -267.582949) (xy 348.630794 -267.540933) (xy 348.667517 -267.50421)
			(xy 348.709533 -267.473684) (xy 348.755807 -267.450106) (xy 348.8052 -267.434058) (xy 348.856495 -267.425933)
			(xy 348.908429 -267.425933) (xy 348.959724 -267.434058) (xy 349.009117 -267.450106) (xy 349.055391 -267.473684)
			(xy 349.097407 -267.50421) (xy 349.13413 -267.540933) (xy 349.164656 -267.582949) (xy 349.188234 -267.629223)
			(xy 349.204282 -267.678616) (xy 349.212407 -267.729911) (xy 349.212916 -267.755878) (xy 349.212407 -267.781845)
			(xy 349.492317 -267.781845) (xy 349.492317 -267.729911) (xy 349.500442 -267.678616) (xy 349.51649 -267.629223)
			(xy 349.540068 -267.582949) (xy 349.570594 -267.540933) (xy 349.607317 -267.50421) (xy 349.649333 -267.473684)
			(xy 349.695607 -267.450106) (xy 349.745 -267.434058) (xy 349.796295 -267.425933) (xy 349.848229 -267.425933)
			(xy 349.899524 -267.434058) (xy 349.948917 -267.450106) (xy 349.995191 -267.473684) (xy 350.037207 -267.50421)
			(xy 350.07393 -267.540933) (xy 350.104456 -267.582949) (xy 350.128034 -267.629223) (xy 350.144082 -267.678616)
			(xy 350.152207 -267.729911) (xy 350.152716 -267.755878) (xy 350.152207 -267.781845) (xy 350.432117 -267.781845)
			(xy 350.432117 -267.729911) (xy 350.440242 -267.678616) (xy 350.45629 -267.629223) (xy 350.479868 -267.582949)
			(xy 350.510394 -267.540933) (xy 350.547117 -267.50421) (xy 350.589133 -267.473684) (xy 350.635407 -267.450106)
			(xy 350.6848 -267.434058) (xy 350.736095 -267.425933) (xy 350.788029 -267.425933) (xy 350.839324 -267.434058)
			(xy 350.888717 -267.450106) (xy 350.934991 -267.473684) (xy 350.977007 -267.50421) (xy 351.01373 -267.540933)
			(xy 351.044256 -267.582949) (xy 351.067834 -267.629223) (xy 351.083882 -267.678616) (xy 351.092007 -267.729911)
			(xy 351.092516 -267.755878) (xy 351.092007 -267.781845) (xy 351.371917 -267.781845) (xy 351.371917 -267.729911)
			(xy 351.380042 -267.678616) (xy 351.39609 -267.629223) (xy 351.419668 -267.582949) (xy 351.450194 -267.540933)
			(xy 351.486917 -267.50421) (xy 351.528933 -267.473684) (xy 351.575207 -267.450106) (xy 351.6246 -267.434058)
			(xy 351.675895 -267.425933) (xy 351.727829 -267.425933) (xy 351.779124 -267.434058) (xy 351.828517 -267.450106)
			(xy 351.874791 -267.473684) (xy 351.916807 -267.50421) (xy 351.95353 -267.540933) (xy 351.984056 -267.582949)
			(xy 352.007634 -267.629223) (xy 352.023682 -267.678616) (xy 352.031807 -267.729911) (xy 352.032316 -267.755878)
			(xy 352.031807 -267.781845) (xy 352.311717 -267.781845) (xy 352.311717 -267.729911) (xy 352.319842 -267.678616)
			(xy 352.33589 -267.629223) (xy 352.359468 -267.582949) (xy 352.389994 -267.540933) (xy 352.426717 -267.50421)
			(xy 352.468733 -267.473684) (xy 352.515007 -267.450106) (xy 352.5644 -267.434058) (xy 352.615695 -267.425933)
			(xy 352.667629 -267.425933) (xy 352.718924 -267.434058) (xy 352.768317 -267.450106) (xy 352.814591 -267.473684)
			(xy 352.856607 -267.50421) (xy 352.89333 -267.540933) (xy 352.923856 -267.582949) (xy 352.947434 -267.629223)
			(xy 352.963482 -267.678616) (xy 352.971607 -267.729911) (xy 352.972116 -267.755878) (xy 352.971607 -267.781845)
			(xy 353.251517 -267.781845) (xy 353.251517 -267.729911) (xy 353.259642 -267.678616) (xy 353.27569 -267.629223)
			(xy 353.299268 -267.582949) (xy 353.329794 -267.540933) (xy 353.366517 -267.50421) (xy 353.408533 -267.473684)
			(xy 353.454807 -267.450106) (xy 353.5042 -267.434058) (xy 353.555495 -267.425933) (xy 353.607429 -267.425933)
			(xy 353.658724 -267.434058) (xy 353.708117 -267.450106) (xy 353.754391 -267.473684) (xy 353.796407 -267.50421)
			(xy 353.83313 -267.540933) (xy 353.863656 -267.582949) (xy 353.887234 -267.629223) (xy 353.903282 -267.678616)
			(xy 353.911407 -267.729911) (xy 353.911916 -267.755878) (xy 353.911407 -267.781845) (xy 354.191317 -267.781845)
			(xy 354.191317 -267.729911) (xy 354.199442 -267.678616) (xy 354.21549 -267.629223) (xy 354.239068 -267.582949)
			(xy 354.269594 -267.540933) (xy 354.306317 -267.50421) (xy 354.348333 -267.473684) (xy 354.394607 -267.450106)
			(xy 354.444 -267.434058) (xy 354.495295 -267.425933) (xy 354.547229 -267.425933) (xy 354.598524 -267.434058)
			(xy 354.647917 -267.450106) (xy 354.694191 -267.473684) (xy 354.736207 -267.50421) (xy 354.77293 -267.540933)
			(xy 354.803456 -267.582949) (xy 354.827034 -267.629223) (xy 354.843082 -267.678616) (xy 354.851207 -267.729911)
			(xy 354.851716 -267.755878) (xy 354.851207 -267.781845) (xy 355.131117 -267.781845) (xy 355.131117 -267.729911)
			(xy 355.139242 -267.678616) (xy 355.15529 -267.629223) (xy 355.178868 -267.582949) (xy 355.209394 -267.540933)
			(xy 355.246117 -267.50421) (xy 355.288133 -267.473684) (xy 355.334407 -267.450106) (xy 355.3838 -267.434058)
			(xy 355.435095 -267.425933) (xy 355.487029 -267.425933) (xy 355.538324 -267.434058) (xy 355.587717 -267.450106)
			(xy 355.633991 -267.473684) (xy 355.676007 -267.50421) (xy 355.71273 -267.540933) (xy 355.743256 -267.582949)
			(xy 355.766834 -267.629223) (xy 355.782882 -267.678616) (xy 355.791007 -267.729911) (xy 355.791516 -267.755878)
			(xy 355.791007 -267.781845) (xy 356.070917 -267.781845) (xy 356.070917 -267.729911) (xy 356.079042 -267.678616)
			(xy 356.09509 -267.629223) (xy 356.118668 -267.582949) (xy 356.149194 -267.540933) (xy 356.185917 -267.50421)
			(xy 356.227933 -267.473684) (xy 356.274207 -267.450106) (xy 356.3236 -267.434058) (xy 356.374895 -267.425933)
			(xy 356.426829 -267.425933) (xy 356.478124 -267.434058) (xy 356.527517 -267.450106) (xy 356.573791 -267.473684)
			(xy 356.615807 -267.50421) (xy 356.65253 -267.540933) (xy 356.683056 -267.582949) (xy 356.706634 -267.629223)
			(xy 356.722682 -267.678616) (xy 356.730807 -267.729911) (xy 356.731316 -267.755878) (xy 356.730807 -267.781845)
			(xy 357.010717 -267.781845) (xy 357.010717 -267.729911) (xy 357.018842 -267.678616) (xy 357.03489 -267.629223)
			(xy 357.058468 -267.582949) (xy 357.088994 -267.540933) (xy 357.125717 -267.50421) (xy 357.167733 -267.473684)
			(xy 357.214007 -267.450106) (xy 357.2634 -267.434058) (xy 357.314695 -267.425933) (xy 357.366629 -267.425933)
			(xy 357.417924 -267.434058) (xy 357.467317 -267.450106) (xy 357.513591 -267.473684) (xy 357.555607 -267.50421)
			(xy 357.59233 -267.540933) (xy 357.622856 -267.582949) (xy 357.646434 -267.629223) (xy 357.662482 -267.678616)
			(xy 357.670607 -267.729911) (xy 357.671116 -267.755878) (xy 357.670607 -267.781845) (xy 357.950517 -267.781845)
			(xy 357.950517 -267.729911) (xy 357.958642 -267.678616) (xy 357.97469 -267.629223) (xy 357.998268 -267.582949)
			(xy 358.028794 -267.540933) (xy 358.065517 -267.50421) (xy 358.107533 -267.473684) (xy 358.153807 -267.450106)
			(xy 358.2032 -267.434058) (xy 358.254495 -267.425933) (xy 358.306429 -267.425933) (xy 358.357724 -267.434058)
			(xy 358.407117 -267.450106) (xy 358.453391 -267.473684) (xy 358.495407 -267.50421) (xy 358.53213 -267.540933)
			(xy 358.562656 -267.582949) (xy 358.586234 -267.629223) (xy 358.602282 -267.678616) (xy 358.610407 -267.729911)
			(xy 358.610916 -267.755878) (xy 358.610407 -267.781845) (xy 361.709717 -267.781845) (xy 361.709717 -267.729911)
			(xy 361.717842 -267.678616) (xy 361.73389 -267.629223) (xy 361.757468 -267.582949) (xy 361.787994 -267.540933)
			(xy 361.824717 -267.50421) (xy 361.866733 -267.473684) (xy 361.913007 -267.450106) (xy 361.9624 -267.434058)
			(xy 362.013695 -267.425933) (xy 362.065629 -267.425933) (xy 362.116924 -267.434058) (xy 362.166317 -267.450106)
			(xy 362.212591 -267.473684) (xy 362.254607 -267.50421) (xy 362.29133 -267.540933) (xy 362.321856 -267.582949)
			(xy 362.345434 -267.629223) (xy 362.361482 -267.678616) (xy 362.369607 -267.729911) (xy 362.370116 -267.755878)
			(xy 362.369607 -267.781845) (xy 362.649517 -267.781845) (xy 362.649517 -267.729911) (xy 362.657642 -267.678616)
			(xy 362.67369 -267.629223) (xy 362.697268 -267.582949) (xy 362.727794 -267.540933) (xy 362.764517 -267.50421)
			(xy 362.806533 -267.473684) (xy 362.852807 -267.450106) (xy 362.9022 -267.434058) (xy 362.953495 -267.425933)
			(xy 363.005429 -267.425933) (xy 363.056724 -267.434058) (xy 363.106117 -267.450106) (xy 363.152391 -267.473684)
			(xy 363.194407 -267.50421) (xy 363.23113 -267.540933) (xy 363.261656 -267.582949) (xy 363.285234 -267.629223)
			(xy 363.301282 -267.678616) (xy 363.309407 -267.729911) (xy 363.309916 -267.755878) (xy 363.309407 -267.781845)
			(xy 363.301282 -267.83314) (xy 363.285234 -267.882533) (xy 363.261656 -267.928807) (xy 363.23113 -267.970823)
			(xy 363.194407 -268.007546) (xy 363.152391 -268.038072) (xy 363.106117 -268.06165) (xy 363.056724 -268.077698)
			(xy 363.005429 -268.085823) (xy 362.953495 -268.085823) (xy 362.9022 -268.077698) (xy 362.852807 -268.06165)
			(xy 362.806533 -268.038072) (xy 362.764517 -268.007546) (xy 362.727794 -267.970823) (xy 362.697268 -267.928807)
			(xy 362.67369 -267.882533) (xy 362.657642 -267.83314) (xy 362.649517 -267.781845) (xy 362.369607 -267.781845)
			(xy 362.361482 -267.83314) (xy 362.345434 -267.882533) (xy 362.321856 -267.928807) (xy 362.29133 -267.970823)
			(xy 362.254607 -268.007546) (xy 362.212591 -268.038072) (xy 362.166317 -268.06165) (xy 362.116924 -268.077698)
			(xy 362.065629 -268.085823) (xy 362.013695 -268.085823) (xy 361.9624 -268.077698) (xy 361.913007 -268.06165)
			(xy 361.866733 -268.038072) (xy 361.824717 -268.007546) (xy 361.787994 -267.970823) (xy 361.757468 -267.928807)
			(xy 361.73389 -267.882533) (xy 361.717842 -267.83314) (xy 361.709717 -267.781845) (xy 358.610407 -267.781845)
			(xy 358.602282 -267.83314) (xy 358.586234 -267.882533) (xy 358.562656 -267.928807) (xy 358.53213 -267.970823)
			(xy 358.495407 -268.007546) (xy 358.453391 -268.038072) (xy 358.407117 -268.06165) (xy 358.357724 -268.077698)
			(xy 358.306429 -268.085823) (xy 358.254495 -268.085823) (xy 358.2032 -268.077698) (xy 358.153807 -268.06165)
			(xy 358.107533 -268.038072) (xy 358.065517 -268.007546) (xy 358.028794 -267.970823) (xy 357.998268 -267.928807)
			(xy 357.97469 -267.882533) (xy 357.958642 -267.83314) (xy 357.950517 -267.781845) (xy 357.670607 -267.781845)
			(xy 357.662482 -267.83314) (xy 357.646434 -267.882533) (xy 357.622856 -267.928807) (xy 357.59233 -267.970823)
			(xy 357.555607 -268.007546) (xy 357.513591 -268.038072) (xy 357.467317 -268.06165) (xy 357.417924 -268.077698)
			(xy 357.366629 -268.085823) (xy 357.314695 -268.085823) (xy 357.2634 -268.077698) (xy 357.214007 -268.06165)
			(xy 357.167733 -268.038072) (xy 357.125717 -268.007546) (xy 357.088994 -267.970823) (xy 357.058468 -267.928807)
			(xy 357.03489 -267.882533) (xy 357.018842 -267.83314) (xy 357.010717 -267.781845) (xy 356.730807 -267.781845)
			(xy 356.722682 -267.83314) (xy 356.706634 -267.882533) (xy 356.683056 -267.928807) (xy 356.65253 -267.970823)
			(xy 356.615807 -268.007546) (xy 356.573791 -268.038072) (xy 356.527517 -268.06165) (xy 356.478124 -268.077698)
			(xy 356.426829 -268.085823) (xy 356.374895 -268.085823) (xy 356.3236 -268.077698) (xy 356.274207 -268.06165)
			(xy 356.227933 -268.038072) (xy 356.185917 -268.007546) (xy 356.149194 -267.970823) (xy 356.118668 -267.928807)
			(xy 356.09509 -267.882533) (xy 356.079042 -267.83314) (xy 356.070917 -267.781845) (xy 355.791007 -267.781845)
			(xy 355.782882 -267.83314) (xy 355.766834 -267.882533) (xy 355.743256 -267.928807) (xy 355.71273 -267.970823)
			(xy 355.676007 -268.007546) (xy 355.633991 -268.038072) (xy 355.587717 -268.06165) (xy 355.538324 -268.077698)
			(xy 355.487029 -268.085823) (xy 355.435095 -268.085823) (xy 355.3838 -268.077698) (xy 355.334407 -268.06165)
			(xy 355.288133 -268.038072) (xy 355.246117 -268.007546) (xy 355.209394 -267.970823) (xy 355.178868 -267.928807)
			(xy 355.15529 -267.882533) (xy 355.139242 -267.83314) (xy 355.131117 -267.781845) (xy 354.851207 -267.781845)
			(xy 354.843082 -267.83314) (xy 354.827034 -267.882533) (xy 354.803456 -267.928807) (xy 354.77293 -267.970823)
			(xy 354.736207 -268.007546) (xy 354.694191 -268.038072) (xy 354.647917 -268.06165) (xy 354.598524 -268.077698)
			(xy 354.547229 -268.085823) (xy 354.495295 -268.085823) (xy 354.444 -268.077698) (xy 354.394607 -268.06165)
			(xy 354.348333 -268.038072) (xy 354.306317 -268.007546) (xy 354.269594 -267.970823) (xy 354.239068 -267.928807)
			(xy 354.21549 -267.882533) (xy 354.199442 -267.83314) (xy 354.191317 -267.781845) (xy 353.911407 -267.781845)
			(xy 353.903282 -267.83314) (xy 353.887234 -267.882533) (xy 353.863656 -267.928807) (xy 353.83313 -267.970823)
			(xy 353.796407 -268.007546) (xy 353.754391 -268.038072) (xy 353.708117 -268.06165) (xy 353.658724 -268.077698)
			(xy 353.607429 -268.085823) (xy 353.555495 -268.085823) (xy 353.5042 -268.077698) (xy 353.454807 -268.06165)
			(xy 353.408533 -268.038072) (xy 353.366517 -268.007546) (xy 353.329794 -267.970823) (xy 353.299268 -267.928807)
			(xy 353.27569 -267.882533) (xy 353.259642 -267.83314) (xy 353.251517 -267.781845) (xy 352.971607 -267.781845)
			(xy 352.963482 -267.83314) (xy 352.947434 -267.882533) (xy 352.923856 -267.928807) (xy 352.89333 -267.970823)
			(xy 352.856607 -268.007546) (xy 352.814591 -268.038072) (xy 352.768317 -268.06165) (xy 352.718924 -268.077698)
			(xy 352.667629 -268.085823) (xy 352.615695 -268.085823) (xy 352.5644 -268.077698) (xy 352.515007 -268.06165)
			(xy 352.468733 -268.038072) (xy 352.426717 -268.007546) (xy 352.389994 -267.970823) (xy 352.359468 -267.928807)
			(xy 352.33589 -267.882533) (xy 352.319842 -267.83314) (xy 352.311717 -267.781845) (xy 352.031807 -267.781845)
			(xy 352.023682 -267.83314) (xy 352.007634 -267.882533) (xy 351.984056 -267.928807) (xy 351.95353 -267.970823)
			(xy 351.916807 -268.007546) (xy 351.874791 -268.038072) (xy 351.828517 -268.06165) (xy 351.779124 -268.077698)
			(xy 351.727829 -268.085823) (xy 351.675895 -268.085823) (xy 351.6246 -268.077698) (xy 351.575207 -268.06165)
			(xy 351.528933 -268.038072) (xy 351.486917 -268.007546) (xy 351.450194 -267.970823) (xy 351.419668 -267.928807)
			(xy 351.39609 -267.882533) (xy 351.380042 -267.83314) (xy 351.371917 -267.781845) (xy 351.092007 -267.781845)
			(xy 351.083882 -267.83314) (xy 351.067834 -267.882533) (xy 351.044256 -267.928807) (xy 351.01373 -267.970823)
			(xy 350.977007 -268.007546) (xy 350.934991 -268.038072) (xy 350.888717 -268.06165) (xy 350.839324 -268.077698)
			(xy 350.788029 -268.085823) (xy 350.736095 -268.085823) (xy 350.6848 -268.077698) (xy 350.635407 -268.06165)
			(xy 350.589133 -268.038072) (xy 350.547117 -268.007546) (xy 350.510394 -267.970823) (xy 350.479868 -267.928807)
			(xy 350.45629 -267.882533) (xy 350.440242 -267.83314) (xy 350.432117 -267.781845) (xy 350.152207 -267.781845)
			(xy 350.144082 -267.83314) (xy 350.128034 -267.882533) (xy 350.104456 -267.928807) (xy 350.07393 -267.970823)
			(xy 350.037207 -268.007546) (xy 349.995191 -268.038072) (xy 349.948917 -268.06165) (xy 349.899524 -268.077698)
			(xy 349.848229 -268.085823) (xy 349.796295 -268.085823) (xy 349.745 -268.077698) (xy 349.695607 -268.06165)
			(xy 349.649333 -268.038072) (xy 349.607317 -268.007546) (xy 349.570594 -267.970823) (xy 349.540068 -267.928807)
			(xy 349.51649 -267.882533) (xy 349.500442 -267.83314) (xy 349.492317 -267.781845) (xy 349.212407 -267.781845)
			(xy 349.204282 -267.83314) (xy 349.188234 -267.882533) (xy 349.164656 -267.928807) (xy 349.13413 -267.970823)
			(xy 349.097407 -268.007546) (xy 349.055391 -268.038072) (xy 349.009117 -268.06165) (xy 348.959724 -268.077698)
			(xy 348.908429 -268.085823) (xy 348.856495 -268.085823) (xy 348.8052 -268.077698) (xy 348.755807 -268.06165)
			(xy 348.709533 -268.038072) (xy 348.667517 -268.007546) (xy 348.630794 -267.970823) (xy 348.600268 -267.928807)
			(xy 348.57669 -267.882533) (xy 348.560642 -267.83314) (xy 348.552517 -267.781845) (xy 348.272607 -267.781845)
			(xy 348.264482 -267.83314) (xy 348.248434 -267.882533) (xy 348.224856 -267.928807) (xy 348.19433 -267.970823)
			(xy 348.157607 -268.007546) (xy 348.115591 -268.038072) (xy 348.069317 -268.06165) (xy 348.019924 -268.077698)
			(xy 347.968629 -268.085823) (xy 347.916695 -268.085823) (xy 347.8654 -268.077698) (xy 347.816007 -268.06165)
			(xy 347.769733 -268.038072) (xy 347.727717 -268.007546) (xy 347.690994 -267.970823) (xy 347.660468 -267.928807)
			(xy 347.63689 -267.882533) (xy 347.620842 -267.83314) (xy 347.612717 -267.781845) (xy 347.332807 -267.781845)
			(xy 347.324682 -267.83314) (xy 347.308634 -267.882533) (xy 347.285056 -267.928807) (xy 347.25453 -267.970823)
			(xy 347.217807 -268.007546) (xy 347.175791 -268.038072) (xy 347.129517 -268.06165) (xy 347.080124 -268.077698)
			(xy 347.028829 -268.085823) (xy 346.976895 -268.085823) (xy 346.9256 -268.077698) (xy 346.876207 -268.06165)
			(xy 346.829933 -268.038072) (xy 346.787917 -268.007546) (xy 346.751194 -267.970823) (xy 346.720668 -267.928807)
			(xy 346.69709 -267.882533) (xy 346.681042 -267.83314) (xy 346.672917 -267.781845) (xy 346.393007 -267.781845)
			(xy 346.384882 -267.83314) (xy 346.368834 -267.882533) (xy 346.345256 -267.928807) (xy 346.31473 -267.970823)
			(xy 346.278007 -268.007546) (xy 346.235991 -268.038072) (xy 346.189717 -268.06165) (xy 346.140324 -268.077698)
			(xy 346.089029 -268.085823) (xy 346.037095 -268.085823) (xy 345.9858 -268.077698) (xy 345.936407 -268.06165)
			(xy 345.890133 -268.038072) (xy 345.848117 -268.007546) (xy 345.811394 -267.970823) (xy 345.780868 -267.928807)
			(xy 345.75729 -267.882533) (xy 345.741242 -267.83314) (xy 345.733117 -267.781845) (xy 345.453461 -267.781845)
			(xy 345.445336 -267.83314) (xy 345.429288 -267.882533) (xy 345.40571 -267.928807) (xy 345.375184 -267.970823)
			(xy 345.338461 -268.007546) (xy 345.296445 -268.038072) (xy 345.250171 -268.06165) (xy 345.200778 -268.077698)
			(xy 345.149483 -268.085823) (xy 345.097549 -268.085823) (xy 345.046254 -268.077698) (xy 344.996861 -268.06165)
			(xy 344.950587 -268.038072) (xy 344.908571 -268.007546) (xy 344.871848 -267.970823) (xy 344.841322 -267.928807)
			(xy 344.817744 -267.882533) (xy 344.801696 -267.83314) (xy 344.793571 -267.781845) (xy 344.557604 -267.781845)
			(xy 344.557604 -268.13764) (xy 344.558029 -268.15085) (xy 344.564823 -268.176381) (xy 344.577943 -268.199312)
			(xy 344.596512 -268.218106) (xy 344.619283 -268.231503) (xy 344.644731 -268.238603) (xy 344.657934 -268.23924)
			(xy 344.683679 -268.24007) (xy 344.734453 -268.248727) (xy 344.78327 -268.265157) (xy 344.828946 -268.288961)
			(xy 344.870377 -268.319563) (xy 344.906558 -268.356222) (xy 344.936614 -268.39805) (xy 344.959817 -268.444035)
			(xy 344.975605 -268.493063) (xy 344.983596 -268.543946) (xy 344.983596 -268.595453) (xy 344.983563 -268.595661)
			(xy 345.263471 -268.595661) (xy 345.263471 -268.543727) (xy 345.271596 -268.492432) (xy 345.287644 -268.443039)
			(xy 345.311222 -268.396765) (xy 345.341748 -268.354749) (xy 345.378471 -268.318026) (xy 345.420487 -268.2875)
			(xy 345.466761 -268.263922) (xy 345.516154 -268.247874) (xy 345.567449 -268.239749) (xy 345.619383 -268.239749)
			(xy 345.670678 -268.247874) (xy 345.720071 -268.263922) (xy 345.766345 -268.2875) (xy 345.808361 -268.318026)
			(xy 345.845084 -268.354749) (xy 345.87561 -268.396765) (xy 345.899188 -268.443039) (xy 345.915236 -268.492432)
			(xy 345.923361 -268.543727) (xy 345.92387 -268.569694) (xy 345.923361 -268.595661) (xy 346.203271 -268.595661)
			(xy 346.203271 -268.543727) (xy 346.211396 -268.492432) (xy 346.227444 -268.443039) (xy 346.251022 -268.396765)
			(xy 346.281548 -268.354749) (xy 346.318271 -268.318026) (xy 346.360287 -268.2875) (xy 346.406561 -268.263922)
			(xy 346.455954 -268.247874) (xy 346.507249 -268.239749) (xy 346.559183 -268.239749) (xy 346.610478 -268.247874)
			(xy 346.659871 -268.263922) (xy 346.706145 -268.2875) (xy 346.748161 -268.318026) (xy 346.784884 -268.354749)
			(xy 346.81541 -268.396765) (xy 346.838988 -268.443039) (xy 346.855036 -268.492432) (xy 346.863161 -268.543727)
			(xy 346.86367 -268.569694) (xy 346.863161 -268.595661) (xy 347.143071 -268.595661) (xy 347.143071 -268.543727)
			(xy 347.151196 -268.492432) (xy 347.167244 -268.443039) (xy 347.190822 -268.396765) (xy 347.221348 -268.354749)
			(xy 347.258071 -268.318026) (xy 347.300087 -268.2875) (xy 347.346361 -268.263922) (xy 347.395754 -268.247874)
			(xy 347.447049 -268.239749) (xy 347.498983 -268.239749) (xy 347.550278 -268.247874) (xy 347.599671 -268.263922)
			(xy 347.645945 -268.2875) (xy 347.687961 -268.318026) (xy 347.724684 -268.354749) (xy 347.75521 -268.396765)
			(xy 347.778788 -268.443039) (xy 347.794836 -268.492432) (xy 347.802961 -268.543727) (xy 347.80347 -268.569694)
			(xy 347.802961 -268.595661) (xy 348.082871 -268.595661) (xy 348.082871 -268.543727) (xy 348.090996 -268.492432)
			(xy 348.107044 -268.443039) (xy 348.130622 -268.396765) (xy 348.161148 -268.354749) (xy 348.197871 -268.318026)
			(xy 348.239887 -268.2875) (xy 348.286161 -268.263922) (xy 348.335554 -268.247874) (xy 348.386849 -268.239749)
			(xy 348.438783 -268.239749) (xy 348.490078 -268.247874) (xy 348.539471 -268.263922) (xy 348.585745 -268.2875)
			(xy 348.627761 -268.318026) (xy 348.664484 -268.354749) (xy 348.69501 -268.396765) (xy 348.718588 -268.443039)
			(xy 348.734636 -268.492432) (xy 348.742761 -268.543727) (xy 348.74327 -268.569694) (xy 348.742761 -268.595661)
			(xy 349.022417 -268.595661) (xy 349.022417 -268.543727) (xy 349.030542 -268.492432) (xy 349.04659 -268.443039)
			(xy 349.070168 -268.396765) (xy 349.100694 -268.354749) (xy 349.137417 -268.318026) (xy 349.179433 -268.2875)
			(xy 349.225707 -268.263922) (xy 349.2751 -268.247874) (xy 349.326395 -268.239749) (xy 349.378329 -268.239749)
			(xy 349.429624 -268.247874) (xy 349.479017 -268.263922) (xy 349.525291 -268.2875) (xy 349.567307 -268.318026)
			(xy 349.60403 -268.354749) (xy 349.634556 -268.396765) (xy 349.658134 -268.443039) (xy 349.674182 -268.492432)
			(xy 349.682307 -268.543727) (xy 349.682816 -268.569694) (xy 349.682307 -268.595661) (xy 349.962471 -268.595661)
			(xy 349.962471 -268.543727) (xy 349.970596 -268.492432) (xy 349.986644 -268.443039) (xy 350.010222 -268.396765)
			(xy 350.040748 -268.354749) (xy 350.077471 -268.318026) (xy 350.119487 -268.2875) (xy 350.165761 -268.263922)
			(xy 350.215154 -268.247874) (xy 350.266449 -268.239749) (xy 350.318383 -268.239749) (xy 350.369678 -268.247874)
			(xy 350.419071 -268.263922) (xy 350.465345 -268.2875) (xy 350.507361 -268.318026) (xy 350.544084 -268.354749)
			(xy 350.57461 -268.396765) (xy 350.598188 -268.443039) (xy 350.614236 -268.492432) (xy 350.622361 -268.543727)
			(xy 350.62287 -268.569694) (xy 350.622361 -268.595661) (xy 350.902271 -268.595661) (xy 350.902271 -268.543727)
			(xy 350.910396 -268.492432) (xy 350.926444 -268.443039) (xy 350.950022 -268.396765) (xy 350.980548 -268.354749)
			(xy 351.017271 -268.318026) (xy 351.059287 -268.2875) (xy 351.105561 -268.263922) (xy 351.154954 -268.247874)
			(xy 351.206249 -268.239749) (xy 351.258183 -268.239749) (xy 351.309478 -268.247874) (xy 351.358871 -268.263922)
			(xy 351.405145 -268.2875) (xy 351.447161 -268.318026) (xy 351.483884 -268.354749) (xy 351.51441 -268.396765)
			(xy 351.537988 -268.443039) (xy 351.554036 -268.492432) (xy 351.562161 -268.543727) (xy 351.56267 -268.569694)
			(xy 351.562161 -268.595661) (xy 351.842071 -268.595661) (xy 351.842071 -268.543727) (xy 351.850196 -268.492432)
			(xy 351.866244 -268.443039) (xy 351.889822 -268.396765) (xy 351.920348 -268.354749) (xy 351.957071 -268.318026)
			(xy 351.999087 -268.2875) (xy 352.045361 -268.263922) (xy 352.094754 -268.247874) (xy 352.146049 -268.239749)
			(xy 352.197983 -268.239749) (xy 352.249278 -268.247874) (xy 352.298671 -268.263922) (xy 352.344945 -268.2875)
			(xy 352.386961 -268.318026) (xy 352.423684 -268.354749) (xy 352.45421 -268.396765) (xy 352.477788 -268.443039)
			(xy 352.493836 -268.492432) (xy 352.501961 -268.543727) (xy 352.50247 -268.569694) (xy 352.501961 -268.595661)
			(xy 352.781871 -268.595661) (xy 352.781871 -268.543727) (xy 352.789996 -268.492432) (xy 352.806044 -268.443039)
			(xy 352.829622 -268.396765) (xy 352.860148 -268.354749) (xy 352.896871 -268.318026) (xy 352.938887 -268.2875)
			(xy 352.985161 -268.263922) (xy 353.034554 -268.247874) (xy 353.085849 -268.239749) (xy 353.137783 -268.239749)
			(xy 353.189078 -268.247874) (xy 353.238471 -268.263922) (xy 353.284745 -268.2875) (xy 353.326761 -268.318026)
			(xy 353.363484 -268.354749) (xy 353.39401 -268.396765) (xy 353.417588 -268.443039) (xy 353.433636 -268.492432)
			(xy 353.441761 -268.543727) (xy 353.44227 -268.569694) (xy 353.441761 -268.595661) (xy 353.721671 -268.595661)
			(xy 353.721671 -268.543727) (xy 353.729796 -268.492432) (xy 353.745844 -268.443039) (xy 353.769422 -268.396765)
			(xy 353.799948 -268.354749) (xy 353.836671 -268.318026) (xy 353.878687 -268.2875) (xy 353.924961 -268.263922)
			(xy 353.974354 -268.247874) (xy 354.025649 -268.239749) (xy 354.077583 -268.239749) (xy 354.128878 -268.247874)
			(xy 354.178271 -268.263922) (xy 354.224545 -268.2875) (xy 354.266561 -268.318026) (xy 354.303284 -268.354749)
			(xy 354.33381 -268.396765) (xy 354.357388 -268.443039) (xy 354.373436 -268.492432) (xy 354.381561 -268.543727)
			(xy 354.38207 -268.569694) (xy 354.381561 -268.595661) (xy 354.661471 -268.595661) (xy 354.661471 -268.543727)
			(xy 354.669596 -268.492432) (xy 354.685644 -268.443039) (xy 354.709222 -268.396765) (xy 354.739748 -268.354749)
			(xy 354.776471 -268.318026) (xy 354.818487 -268.2875) (xy 354.864761 -268.263922) (xy 354.914154 -268.247874)
			(xy 354.965449 -268.239749) (xy 355.017383 -268.239749) (xy 355.068678 -268.247874) (xy 355.118071 -268.263922)
			(xy 355.164345 -268.2875) (xy 355.206361 -268.318026) (xy 355.243084 -268.354749) (xy 355.27361 -268.396765)
			(xy 355.297188 -268.443039) (xy 355.313236 -268.492432) (xy 355.321361 -268.543727) (xy 355.32187 -268.569694)
			(xy 355.321361 -268.595661) (xy 355.601271 -268.595661) (xy 355.601271 -268.543727) (xy 355.609396 -268.492432)
			(xy 355.625444 -268.443039) (xy 355.649022 -268.396765) (xy 355.679548 -268.354749) (xy 355.716271 -268.318026)
			(xy 355.758287 -268.2875) (xy 355.804561 -268.263922) (xy 355.853954 -268.247874) (xy 355.905249 -268.239749)
			(xy 355.957183 -268.239749) (xy 356.008478 -268.247874) (xy 356.057871 -268.263922) (xy 356.104145 -268.2875)
			(xy 356.146161 -268.318026) (xy 356.182884 -268.354749) (xy 356.21341 -268.396765) (xy 356.236988 -268.443039)
			(xy 356.253036 -268.492432) (xy 356.261161 -268.543727) (xy 356.26167 -268.569694) (xy 356.261161 -268.595661)
			(xy 356.540817 -268.595661) (xy 356.540817 -268.543727) (xy 356.548942 -268.492432) (xy 356.56499 -268.443039)
			(xy 356.588568 -268.396765) (xy 356.619094 -268.354749) (xy 356.655817 -268.318026) (xy 356.697833 -268.2875)
			(xy 356.744107 -268.263922) (xy 356.7935 -268.247874) (xy 356.844795 -268.239749) (xy 356.896729 -268.239749)
			(xy 356.948024 -268.247874) (xy 356.997417 -268.263922) (xy 357.043691 -268.2875) (xy 357.085707 -268.318026)
			(xy 357.12243 -268.354749) (xy 357.152956 -268.396765) (xy 357.176534 -268.443039) (xy 357.192582 -268.492432)
			(xy 357.200707 -268.543727) (xy 357.201216 -268.569694) (xy 357.200707 -268.595661) (xy 357.480617 -268.595661)
			(xy 357.480617 -268.543727) (xy 357.488742 -268.492432) (xy 357.50479 -268.443039) (xy 357.528368 -268.396765)
			(xy 357.558894 -268.354749) (xy 357.595617 -268.318026) (xy 357.637633 -268.2875) (xy 357.683907 -268.263922)
			(xy 357.7333 -268.247874) (xy 357.784595 -268.239749) (xy 357.836529 -268.239749) (xy 357.887824 -268.247874)
			(xy 357.937217 -268.263922) (xy 357.983491 -268.2875) (xy 358.025507 -268.318026) (xy 358.06223 -268.354749)
			(xy 358.092756 -268.396765) (xy 358.116334 -268.443039) (xy 358.132382 -268.492432) (xy 358.140507 -268.543727)
			(xy 358.141016 -268.569694) (xy 358.140507 -268.595661) (xy 361.239817 -268.595661) (xy 361.239817 -268.543727)
			(xy 361.247942 -268.492432) (xy 361.26399 -268.443039) (xy 361.287568 -268.396765) (xy 361.318094 -268.354749)
			(xy 361.354817 -268.318026) (xy 361.396833 -268.2875) (xy 361.443107 -268.263922) (xy 361.4925 -268.247874)
			(xy 361.543795 -268.239749) (xy 361.595729 -268.239749) (xy 361.647024 -268.247874) (xy 361.696417 -268.263922)
			(xy 361.742691 -268.2875) (xy 361.784707 -268.318026) (xy 361.82143 -268.354749) (xy 361.851956 -268.396765)
			(xy 361.875534 -268.443039) (xy 361.891582 -268.492432) (xy 361.899707 -268.543727) (xy 361.900216 -268.569694)
			(xy 361.899707 -268.595661) (xy 362.179871 -268.595661) (xy 362.179871 -268.543727) (xy 362.187996 -268.492432)
			(xy 362.204044 -268.443039) (xy 362.227622 -268.396765) (xy 362.258148 -268.354749) (xy 362.294871 -268.318026)
			(xy 362.336887 -268.2875) (xy 362.383161 -268.263922) (xy 362.432554 -268.247874) (xy 362.483849 -268.239749)
			(xy 362.535783 -268.239749) (xy 362.587078 -268.247874) (xy 362.636471 -268.263922) (xy 362.682745 -268.2875)
			(xy 362.724761 -268.318026) (xy 362.761484 -268.354749) (xy 362.79201 -268.396765) (xy 362.815588 -268.443039)
			(xy 362.831636 -268.492432) (xy 362.839761 -268.543727) (xy 362.84027 -268.569694) (xy 362.839761 -268.595661)
			(xy 363.119671 -268.595661) (xy 363.119671 -268.543727) (xy 363.127796 -268.492432) (xy 363.143844 -268.443039)
			(xy 363.167422 -268.396765) (xy 363.197948 -268.354749) (xy 363.234671 -268.318026) (xy 363.276687 -268.2875)
			(xy 363.322961 -268.263922) (xy 363.372354 -268.247874) (xy 363.423649 -268.239749) (xy 363.475583 -268.239749)
			(xy 363.526878 -268.247874) (xy 363.576271 -268.263922) (xy 363.622545 -268.2875) (xy 363.664561 -268.318026)
			(xy 363.701284 -268.354749) (xy 363.73181 -268.396765) (xy 363.755388 -268.443039) (xy 363.771436 -268.492432)
			(xy 363.779561 -268.543727) (xy 363.78007 -268.569694) (xy 363.779561 -268.595661) (xy 363.771436 -268.646956)
			(xy 363.755388 -268.696349) (xy 363.73181 -268.742623) (xy 363.701284 -268.784639) (xy 363.664561 -268.821362)
			(xy 363.622545 -268.851888) (xy 363.576271 -268.875466) (xy 363.526878 -268.891514) (xy 363.475583 -268.899639)
			(xy 363.423649 -268.899639) (xy 363.372354 -268.891514) (xy 363.322961 -268.875466) (xy 363.276687 -268.851888)
			(xy 363.234671 -268.821362) (xy 363.197948 -268.784639) (xy 363.167422 -268.742623) (xy 363.143844 -268.696349)
			(xy 363.127796 -268.646956) (xy 363.119671 -268.595661) (xy 362.839761 -268.595661) (xy 362.831636 -268.646956)
			(xy 362.815588 -268.696349) (xy 362.79201 -268.742623) (xy 362.761484 -268.784639) (xy 362.724761 -268.821362)
			(xy 362.682745 -268.851888) (xy 362.636471 -268.875466) (xy 362.587078 -268.891514) (xy 362.535783 -268.899639)
			(xy 362.483849 -268.899639) (xy 362.432554 -268.891514) (xy 362.383161 -268.875466) (xy 362.336887 -268.851888)
			(xy 362.294871 -268.821362) (xy 362.258148 -268.784639) (xy 362.227622 -268.742623) (xy 362.204044 -268.696349)
			(xy 362.187996 -268.646956) (xy 362.179871 -268.595661) (xy 361.899707 -268.595661) (xy 361.891582 -268.646956)
			(xy 361.875534 -268.696349) (xy 361.851956 -268.742623) (xy 361.82143 -268.784639) (xy 361.784707 -268.821362)
			(xy 361.742691 -268.851888) (xy 361.696417 -268.875466) (xy 361.647024 -268.891514) (xy 361.595729 -268.899639)
			(xy 361.543795 -268.899639) (xy 361.4925 -268.891514) (xy 361.443107 -268.875466) (xy 361.396833 -268.851888)
			(xy 361.354817 -268.821362) (xy 361.318094 -268.784639) (xy 361.287568 -268.742623) (xy 361.26399 -268.696349)
			(xy 361.247942 -268.646956) (xy 361.239817 -268.595661) (xy 358.140507 -268.595661) (xy 358.132382 -268.646956)
			(xy 358.116334 -268.696349) (xy 358.092756 -268.742623) (xy 358.06223 -268.784639) (xy 358.025507 -268.821362)
			(xy 357.983491 -268.851888) (xy 357.937217 -268.875466) (xy 357.887824 -268.891514) (xy 357.836529 -268.899639)
			(xy 357.784595 -268.899639) (xy 357.7333 -268.891514) (xy 357.683907 -268.875466) (xy 357.637633 -268.851888)
			(xy 357.595617 -268.821362) (xy 357.558894 -268.784639) (xy 357.528368 -268.742623) (xy 357.50479 -268.696349)
			(xy 357.488742 -268.646956) (xy 357.480617 -268.595661) (xy 357.200707 -268.595661) (xy 357.192582 -268.646956)
			(xy 357.176534 -268.696349) (xy 357.152956 -268.742623) (xy 357.12243 -268.784639) (xy 357.085707 -268.821362)
			(xy 357.043691 -268.851888) (xy 356.997417 -268.875466) (xy 356.948024 -268.891514) (xy 356.896729 -268.899639)
			(xy 356.844795 -268.899639) (xy 356.7935 -268.891514) (xy 356.744107 -268.875466) (xy 356.697833 -268.851888)
			(xy 356.655817 -268.821362) (xy 356.619094 -268.784639) (xy 356.588568 -268.742623) (xy 356.56499 -268.696349)
			(xy 356.548942 -268.646956) (xy 356.540817 -268.595661) (xy 356.261161 -268.595661) (xy 356.253036 -268.646956)
			(xy 356.236988 -268.696349) (xy 356.21341 -268.742623) (xy 356.182884 -268.784639) (xy 356.146161 -268.821362)
			(xy 356.104145 -268.851888) (xy 356.057871 -268.875466) (xy 356.008478 -268.891514) (xy 355.957183 -268.899639)
			(xy 355.905249 -268.899639) (xy 355.853954 -268.891514) (xy 355.804561 -268.875466) (xy 355.758287 -268.851888)
			(xy 355.716271 -268.821362) (xy 355.679548 -268.784639) (xy 355.649022 -268.742623) (xy 355.625444 -268.696349)
			(xy 355.609396 -268.646956) (xy 355.601271 -268.595661) (xy 355.321361 -268.595661) (xy 355.313236 -268.646956)
			(xy 355.297188 -268.696349) (xy 355.27361 -268.742623) (xy 355.243084 -268.784639) (xy 355.206361 -268.821362)
			(xy 355.164345 -268.851888) (xy 355.118071 -268.875466) (xy 355.068678 -268.891514) (xy 355.017383 -268.899639)
			(xy 354.965449 -268.899639) (xy 354.914154 -268.891514) (xy 354.864761 -268.875466) (xy 354.818487 -268.851888)
			(xy 354.776471 -268.821362) (xy 354.739748 -268.784639) (xy 354.709222 -268.742623) (xy 354.685644 -268.696349)
			(xy 354.669596 -268.646956) (xy 354.661471 -268.595661) (xy 354.381561 -268.595661) (xy 354.373436 -268.646956)
			(xy 354.357388 -268.696349) (xy 354.33381 -268.742623) (xy 354.303284 -268.784639) (xy 354.266561 -268.821362)
			(xy 354.224545 -268.851888) (xy 354.178271 -268.875466) (xy 354.128878 -268.891514) (xy 354.077583 -268.899639)
			(xy 354.025649 -268.899639) (xy 353.974354 -268.891514) (xy 353.924961 -268.875466) (xy 353.878687 -268.851888)
			(xy 353.836671 -268.821362) (xy 353.799948 -268.784639) (xy 353.769422 -268.742623) (xy 353.745844 -268.696349)
			(xy 353.729796 -268.646956) (xy 353.721671 -268.595661) (xy 353.441761 -268.595661) (xy 353.433636 -268.646956)
			(xy 353.417588 -268.696349) (xy 353.39401 -268.742623) (xy 353.363484 -268.784639) (xy 353.326761 -268.821362)
			(xy 353.284745 -268.851888) (xy 353.238471 -268.875466) (xy 353.189078 -268.891514) (xy 353.137783 -268.899639)
			(xy 353.085849 -268.899639) (xy 353.034554 -268.891514) (xy 352.985161 -268.875466) (xy 352.938887 -268.851888)
			(xy 352.896871 -268.821362) (xy 352.860148 -268.784639) (xy 352.829622 -268.742623) (xy 352.806044 -268.696349)
			(xy 352.789996 -268.646956) (xy 352.781871 -268.595661) (xy 352.501961 -268.595661) (xy 352.493836 -268.646956)
			(xy 352.477788 -268.696349) (xy 352.45421 -268.742623) (xy 352.423684 -268.784639) (xy 352.386961 -268.821362)
			(xy 352.344945 -268.851888) (xy 352.298671 -268.875466) (xy 352.249278 -268.891514) (xy 352.197983 -268.899639)
			(xy 352.146049 -268.899639) (xy 352.094754 -268.891514) (xy 352.045361 -268.875466) (xy 351.999087 -268.851888)
			(xy 351.957071 -268.821362) (xy 351.920348 -268.784639) (xy 351.889822 -268.742623) (xy 351.866244 -268.696349)
			(xy 351.850196 -268.646956) (xy 351.842071 -268.595661) (xy 351.562161 -268.595661) (xy 351.554036 -268.646956)
			(xy 351.537988 -268.696349) (xy 351.51441 -268.742623) (xy 351.483884 -268.784639) (xy 351.447161 -268.821362)
			(xy 351.405145 -268.851888) (xy 351.358871 -268.875466) (xy 351.309478 -268.891514) (xy 351.258183 -268.899639)
			(xy 351.206249 -268.899639) (xy 351.154954 -268.891514) (xy 351.105561 -268.875466) (xy 351.059287 -268.851888)
			(xy 351.017271 -268.821362) (xy 350.980548 -268.784639) (xy 350.950022 -268.742623) (xy 350.926444 -268.696349)
			(xy 350.910396 -268.646956) (xy 350.902271 -268.595661) (xy 350.622361 -268.595661) (xy 350.614236 -268.646956)
			(xy 350.598188 -268.696349) (xy 350.57461 -268.742623) (xy 350.544084 -268.784639) (xy 350.507361 -268.821362)
			(xy 350.465345 -268.851888) (xy 350.419071 -268.875466) (xy 350.369678 -268.891514) (xy 350.318383 -268.899639)
			(xy 350.266449 -268.899639) (xy 350.215154 -268.891514) (xy 350.165761 -268.875466) (xy 350.119487 -268.851888)
			(xy 350.077471 -268.821362) (xy 350.040748 -268.784639) (xy 350.010222 -268.742623) (xy 349.986644 -268.696349)
			(xy 349.970596 -268.646956) (xy 349.962471 -268.595661) (xy 349.682307 -268.595661) (xy 349.674182 -268.646956)
			(xy 349.658134 -268.696349) (xy 349.634556 -268.742623) (xy 349.60403 -268.784639) (xy 349.567307 -268.821362)
			(xy 349.525291 -268.851888) (xy 349.479017 -268.875466) (xy 349.429624 -268.891514) (xy 349.378329 -268.899639)
			(xy 349.326395 -268.899639) (xy 349.2751 -268.891514) (xy 349.225707 -268.875466) (xy 349.179433 -268.851888)
			(xy 349.137417 -268.821362) (xy 349.100694 -268.784639) (xy 349.070168 -268.742623) (xy 349.04659 -268.696349)
			(xy 349.030542 -268.646956) (xy 349.022417 -268.595661) (xy 348.742761 -268.595661) (xy 348.734636 -268.646956)
			(xy 348.718588 -268.696349) (xy 348.69501 -268.742623) (xy 348.664484 -268.784639) (xy 348.627761 -268.821362)
			(xy 348.585745 -268.851888) (xy 348.539471 -268.875466) (xy 348.490078 -268.891514) (xy 348.438783 -268.899639)
			(xy 348.386849 -268.899639) (xy 348.335554 -268.891514) (xy 348.286161 -268.875466) (xy 348.239887 -268.851888)
			(xy 348.197871 -268.821362) (xy 348.161148 -268.784639) (xy 348.130622 -268.742623) (xy 348.107044 -268.696349)
			(xy 348.090996 -268.646956) (xy 348.082871 -268.595661) (xy 347.802961 -268.595661) (xy 347.794836 -268.646956)
			(xy 347.778788 -268.696349) (xy 347.75521 -268.742623) (xy 347.724684 -268.784639) (xy 347.687961 -268.821362)
			(xy 347.645945 -268.851888) (xy 347.599671 -268.875466) (xy 347.550278 -268.891514) (xy 347.498983 -268.899639)
			(xy 347.447049 -268.899639) (xy 347.395754 -268.891514) (xy 347.346361 -268.875466) (xy 347.300087 -268.851888)
			(xy 347.258071 -268.821362) (xy 347.221348 -268.784639) (xy 347.190822 -268.742623) (xy 347.167244 -268.696349)
			(xy 347.151196 -268.646956) (xy 347.143071 -268.595661) (xy 346.863161 -268.595661) (xy 346.855036 -268.646956)
			(xy 346.838988 -268.696349) (xy 346.81541 -268.742623) (xy 346.784884 -268.784639) (xy 346.748161 -268.821362)
			(xy 346.706145 -268.851888) (xy 346.659871 -268.875466) (xy 346.610478 -268.891514) (xy 346.559183 -268.899639)
			(xy 346.507249 -268.899639) (xy 346.455954 -268.891514) (xy 346.406561 -268.875466) (xy 346.360287 -268.851888)
			(xy 346.318271 -268.821362) (xy 346.281548 -268.784639) (xy 346.251022 -268.742623) (xy 346.227444 -268.696349)
			(xy 346.211396 -268.646956) (xy 346.203271 -268.595661) (xy 345.923361 -268.595661) (xy 345.915236 -268.646956)
			(xy 345.899188 -268.696349) (xy 345.87561 -268.742623) (xy 345.845084 -268.784639) (xy 345.808361 -268.821362)
			(xy 345.766345 -268.851888) (xy 345.720071 -268.875466) (xy 345.670678 -268.891514) (xy 345.619383 -268.899639)
			(xy 345.567449 -268.899639) (xy 345.516154 -268.891514) (xy 345.466761 -268.875466) (xy 345.420487 -268.851888)
			(xy 345.378471 -268.821362) (xy 345.341748 -268.784639) (xy 345.311222 -268.742623) (xy 345.287644 -268.696349)
			(xy 345.271596 -268.646956) (xy 345.263471 -268.595661) (xy 344.983563 -268.595661) (xy 344.975605 -268.646337)
			(xy 344.959817 -268.695365) (xy 344.936614 -268.741349) (xy 344.906558 -268.783178) (xy 344.870377 -268.819837)
			(xy 344.828946 -268.850439) (xy 344.78327 -268.874243) (xy 344.734453 -268.890673) (xy 344.683679 -268.89933)
			(xy 344.657934 -268.900148) (xy 344.644728 -268.900734) (xy 344.619277 -268.90784) (xy 344.596505 -268.921246)
			(xy 344.577941 -268.940051) (xy 344.564831 -268.962994) (xy 344.558055 -268.988535) (xy 344.557604 -269.001748)
			(xy 344.557604 -269.409477) (xy 344.793317 -269.409477) (xy 344.793317 -269.357543) (xy 344.801442 -269.306248)
			(xy 344.81749 -269.256855) (xy 344.841068 -269.210581) (xy 344.871594 -269.168565) (xy 344.908317 -269.131842)
			(xy 344.950333 -269.101316) (xy 344.996607 -269.077738) (xy 345.046 -269.06169) (xy 345.097295 -269.053565)
			(xy 345.149229 -269.053565) (xy 345.200524 -269.06169) (xy 345.249917 -269.077738) (xy 345.296191 -269.101316)
			(xy 345.338207 -269.131842) (xy 345.37493 -269.168565) (xy 345.405456 -269.210581) (xy 345.429034 -269.256855)
			(xy 345.445082 -269.306248) (xy 345.453207 -269.357543) (xy 345.453716 -269.38351) (xy 345.453207 -269.409477)
			(xy 345.733371 -269.409477) (xy 345.733371 -269.357543) (xy 345.741496 -269.306248) (xy 345.757544 -269.256855)
			(xy 345.781122 -269.210581) (xy 345.811648 -269.168565) (xy 345.848371 -269.131842) (xy 345.890387 -269.101316)
			(xy 345.936661 -269.077738) (xy 345.986054 -269.06169) (xy 346.037349 -269.053565) (xy 346.089283 -269.053565)
			(xy 346.140578 -269.06169) (xy 346.189971 -269.077738) (xy 346.236245 -269.101316) (xy 346.278261 -269.131842)
			(xy 346.314984 -269.168565) (xy 346.34551 -269.210581) (xy 346.369088 -269.256855) (xy 346.385136 -269.306248)
			(xy 346.393261 -269.357543) (xy 346.39377 -269.38351) (xy 346.393261 -269.409477) (xy 346.672917 -269.409477)
			(xy 346.672917 -269.357543) (xy 346.681042 -269.306248) (xy 346.69709 -269.256855) (xy 346.720668 -269.210581)
			(xy 346.751194 -269.168565) (xy 346.787917 -269.131842) (xy 346.829933 -269.101316) (xy 346.876207 -269.077738)
			(xy 346.9256 -269.06169) (xy 346.976895 -269.053565) (xy 347.028829 -269.053565) (xy 347.080124 -269.06169)
			(xy 347.129517 -269.077738) (xy 347.175791 -269.101316) (xy 347.217807 -269.131842) (xy 347.25453 -269.168565)
			(xy 347.285056 -269.210581) (xy 347.308634 -269.256855) (xy 347.324682 -269.306248) (xy 347.332807 -269.357543)
			(xy 347.333316 -269.38351) (xy 347.332807 -269.409477) (xy 347.612717 -269.409477) (xy 347.612717 -269.357543)
			(xy 347.620842 -269.306248) (xy 347.63689 -269.256855) (xy 347.660468 -269.210581) (xy 347.690994 -269.168565)
			(xy 347.727717 -269.131842) (xy 347.769733 -269.101316) (xy 347.816007 -269.077738) (xy 347.8654 -269.06169)
			(xy 347.916695 -269.053565) (xy 347.968629 -269.053565) (xy 348.019924 -269.06169) (xy 348.069317 -269.077738)
			(xy 348.115591 -269.101316) (xy 348.157607 -269.131842) (xy 348.19433 -269.168565) (xy 348.224856 -269.210581)
			(xy 348.248434 -269.256855) (xy 348.264482 -269.306248) (xy 348.272607 -269.357543) (xy 348.273116 -269.38351)
			(xy 348.272607 -269.409477) (xy 348.552517 -269.409477) (xy 348.552517 -269.357543) (xy 348.560642 -269.306248)
			(xy 348.57669 -269.256855) (xy 348.600268 -269.210581) (xy 348.630794 -269.168565) (xy 348.667517 -269.131842)
			(xy 348.709533 -269.101316) (xy 348.755807 -269.077738) (xy 348.8052 -269.06169) (xy 348.856495 -269.053565)
			(xy 348.908429 -269.053565) (xy 348.959724 -269.06169) (xy 349.009117 -269.077738) (xy 349.055391 -269.101316)
			(xy 349.097407 -269.131842) (xy 349.13413 -269.168565) (xy 349.164656 -269.210581) (xy 349.188234 -269.256855)
			(xy 349.204282 -269.306248) (xy 349.212407 -269.357543) (xy 349.212916 -269.38351) (xy 349.212407 -269.409477)
			(xy 349.492825 -269.409477) (xy 349.492825 -269.357543) (xy 349.50095 -269.306248) (xy 349.516998 -269.256855)
			(xy 349.540576 -269.210581) (xy 349.571102 -269.168565) (xy 349.607825 -269.131842) (xy 349.649841 -269.101316)
			(xy 349.696115 -269.077738) (xy 349.745508 -269.06169) (xy 349.796803 -269.053565) (xy 349.848737 -269.053565)
			(xy 349.900032 -269.06169) (xy 349.949425 -269.077738) (xy 349.995699 -269.101316) (xy 350.037715 -269.131842)
			(xy 350.074438 -269.168565) (xy 350.104964 -269.210581) (xy 350.128542 -269.256855) (xy 350.14459 -269.306248)
			(xy 350.152715 -269.357543) (xy 350.153224 -269.38351) (xy 350.152715 -269.409477) (xy 350.432117 -269.409477)
			(xy 350.432117 -269.357543) (xy 350.440242 -269.306248) (xy 350.45629 -269.256855) (xy 350.479868 -269.210581)
			(xy 350.510394 -269.168565) (xy 350.547117 -269.131842) (xy 350.589133 -269.101316) (xy 350.635407 -269.077738)
			(xy 350.6848 -269.06169) (xy 350.736095 -269.053565) (xy 350.788029 -269.053565) (xy 350.839324 -269.06169)
			(xy 350.888717 -269.077738) (xy 350.934991 -269.101316) (xy 350.977007 -269.131842) (xy 351.01373 -269.168565)
			(xy 351.044256 -269.210581) (xy 351.067834 -269.256855) (xy 351.083882 -269.306248) (xy 351.092007 -269.357543)
			(xy 351.092516 -269.38351) (xy 351.092007 -269.409477) (xy 351.371917 -269.409477) (xy 351.371917 -269.357543)
			(xy 351.380042 -269.306248) (xy 351.39609 -269.256855) (xy 351.419668 -269.210581) (xy 351.450194 -269.168565)
			(xy 351.486917 -269.131842) (xy 351.528933 -269.101316) (xy 351.575207 -269.077738) (xy 351.6246 -269.06169)
			(xy 351.675895 -269.053565) (xy 351.727829 -269.053565) (xy 351.779124 -269.06169) (xy 351.828517 -269.077738)
			(xy 351.874791 -269.101316) (xy 351.916807 -269.131842) (xy 351.95353 -269.168565) (xy 351.984056 -269.210581)
			(xy 352.007634 -269.256855) (xy 352.023682 -269.306248) (xy 352.031807 -269.357543) (xy 352.032316 -269.38351)
			(xy 352.031807 -269.409477) (xy 352.311717 -269.409477) (xy 352.311717 -269.357543) (xy 352.319842 -269.306248)
			(xy 352.33589 -269.256855) (xy 352.359468 -269.210581) (xy 352.389994 -269.168565) (xy 352.426717 -269.131842)
			(xy 352.468733 -269.101316) (xy 352.515007 -269.077738) (xy 352.5644 -269.06169) (xy 352.615695 -269.053565)
			(xy 352.667629 -269.053565) (xy 352.718924 -269.06169) (xy 352.768317 -269.077738) (xy 352.814591 -269.101316)
			(xy 352.856607 -269.131842) (xy 352.89333 -269.168565) (xy 352.923856 -269.210581) (xy 352.947434 -269.256855)
			(xy 352.963482 -269.306248) (xy 352.971607 -269.357543) (xy 352.972116 -269.38351) (xy 352.971607 -269.409477)
			(xy 353.251517 -269.409477) (xy 353.251517 -269.357543) (xy 353.259642 -269.306248) (xy 353.27569 -269.256855)
			(xy 353.299268 -269.210581) (xy 353.329794 -269.168565) (xy 353.366517 -269.131842) (xy 353.408533 -269.101316)
			(xy 353.454807 -269.077738) (xy 353.5042 -269.06169) (xy 353.555495 -269.053565) (xy 353.607429 -269.053565)
			(xy 353.658724 -269.06169) (xy 353.708117 -269.077738) (xy 353.754391 -269.101316) (xy 353.796407 -269.131842)
			(xy 353.83313 -269.168565) (xy 353.863656 -269.210581) (xy 353.887234 -269.256855) (xy 353.903282 -269.306248)
			(xy 353.911407 -269.357543) (xy 353.911916 -269.38351) (xy 353.911407 -269.409477) (xy 354.191317 -269.409477)
			(xy 354.191317 -269.357543) (xy 354.199442 -269.306248) (xy 354.21549 -269.256855) (xy 354.239068 -269.210581)
			(xy 354.269594 -269.168565) (xy 354.306317 -269.131842) (xy 354.348333 -269.101316) (xy 354.394607 -269.077738)
			(xy 354.444 -269.06169) (xy 354.495295 -269.053565) (xy 354.547229 -269.053565) (xy 354.598524 -269.06169)
			(xy 354.647917 -269.077738) (xy 354.694191 -269.101316) (xy 354.736207 -269.131842) (xy 354.77293 -269.168565)
			(xy 354.803456 -269.210581) (xy 354.827034 -269.256855) (xy 354.843082 -269.306248) (xy 354.851207 -269.357543)
			(xy 354.851716 -269.38351) (xy 354.851207 -269.409477) (xy 355.131117 -269.409477) (xy 355.131117 -269.357543)
			(xy 355.139242 -269.306248) (xy 355.15529 -269.256855) (xy 355.178868 -269.210581) (xy 355.209394 -269.168565)
			(xy 355.246117 -269.131842) (xy 355.288133 -269.101316) (xy 355.334407 -269.077738) (xy 355.3838 -269.06169)
			(xy 355.435095 -269.053565) (xy 355.487029 -269.053565) (xy 355.538324 -269.06169) (xy 355.587717 -269.077738)
			(xy 355.633991 -269.101316) (xy 355.676007 -269.131842) (xy 355.71273 -269.168565) (xy 355.743256 -269.210581)
			(xy 355.766834 -269.256855) (xy 355.782882 -269.306248) (xy 355.791007 -269.357543) (xy 355.791516 -269.38351)
			(xy 355.791007 -269.409477) (xy 356.070917 -269.409477) (xy 356.070917 -269.357543) (xy 356.079042 -269.306248)
			(xy 356.09509 -269.256855) (xy 356.118668 -269.210581) (xy 356.149194 -269.168565) (xy 356.185917 -269.131842)
			(xy 356.227933 -269.101316) (xy 356.274207 -269.077738) (xy 356.3236 -269.06169) (xy 356.374895 -269.053565)
			(xy 356.426829 -269.053565) (xy 356.478124 -269.06169) (xy 356.527517 -269.077738) (xy 356.573791 -269.101316)
			(xy 356.615807 -269.131842) (xy 356.65253 -269.168565) (xy 356.683056 -269.210581) (xy 356.706634 -269.256855)
			(xy 356.722682 -269.306248) (xy 356.730807 -269.357543) (xy 356.731316 -269.38351) (xy 356.730807 -269.409477)
			(xy 357.010717 -269.409477) (xy 357.010717 -269.357543) (xy 357.018842 -269.306248) (xy 357.03489 -269.256855)
			(xy 357.058468 -269.210581) (xy 357.088994 -269.168565) (xy 357.125717 -269.131842) (xy 357.167733 -269.101316)
			(xy 357.214007 -269.077738) (xy 357.2634 -269.06169) (xy 357.314695 -269.053565) (xy 357.366629 -269.053565)
			(xy 357.417924 -269.06169) (xy 357.467317 -269.077738) (xy 357.513591 -269.101316) (xy 357.555607 -269.131842)
			(xy 357.59233 -269.168565) (xy 357.622856 -269.210581) (xy 357.646434 -269.256855) (xy 357.662482 -269.306248)
			(xy 357.670607 -269.357543) (xy 357.671116 -269.38351) (xy 357.670607 -269.409477) (xy 357.950517 -269.409477)
			(xy 357.950517 -269.357543) (xy 357.958642 -269.306248) (xy 357.97469 -269.256855) (xy 357.998268 -269.210581)
			(xy 358.028794 -269.168565) (xy 358.065517 -269.131842) (xy 358.107533 -269.101316) (xy 358.153807 -269.077738)
			(xy 358.2032 -269.06169) (xy 358.254495 -269.053565) (xy 358.306429 -269.053565) (xy 358.357724 -269.06169)
			(xy 358.407117 -269.077738) (xy 358.453391 -269.101316) (xy 358.495407 -269.131842) (xy 358.53213 -269.168565)
			(xy 358.562656 -269.210581) (xy 358.586234 -269.256855) (xy 358.602282 -269.306248) (xy 358.610407 -269.357543)
			(xy 358.610916 -269.38351) (xy 358.610407 -269.409477) (xy 361.710225 -269.409477) (xy 361.710225 -269.357543)
			(xy 361.71835 -269.306248) (xy 361.734398 -269.256855) (xy 361.757976 -269.210581) (xy 361.788502 -269.168565)
			(xy 361.825225 -269.131842) (xy 361.867241 -269.101316) (xy 361.913515 -269.077738) (xy 361.962908 -269.06169)
			(xy 362.014203 -269.053565) (xy 362.066137 -269.053565) (xy 362.117432 -269.06169) (xy 362.166825 -269.077738)
			(xy 362.213099 -269.101316) (xy 362.255115 -269.131842) (xy 362.291838 -269.168565) (xy 362.322364 -269.210581)
			(xy 362.345942 -269.256855) (xy 362.36199 -269.306248) (xy 362.370115 -269.357543) (xy 362.370624 -269.38351)
			(xy 362.370115 -269.409477) (xy 362.649517 -269.409477) (xy 362.649517 -269.357543) (xy 362.657642 -269.306248)
			(xy 362.67369 -269.256855) (xy 362.697268 -269.210581) (xy 362.727794 -269.168565) (xy 362.764517 -269.131842)
			(xy 362.806533 -269.101316) (xy 362.852807 -269.077738) (xy 362.9022 -269.06169) (xy 362.953495 -269.053565)
			(xy 363.005429 -269.053565) (xy 363.056724 -269.06169) (xy 363.106117 -269.077738) (xy 363.152391 -269.101316)
			(xy 363.194407 -269.131842) (xy 363.23113 -269.168565) (xy 363.261656 -269.210581) (xy 363.285234 -269.256855)
			(xy 363.301282 -269.306248) (xy 363.309407 -269.357543) (xy 363.309916 -269.38351) (xy 363.309407 -269.409477)
			(xy 363.301282 -269.460772) (xy 363.285234 -269.510165) (xy 363.261656 -269.556439) (xy 363.23113 -269.598455)
			(xy 363.194407 -269.635178) (xy 363.152391 -269.665704) (xy 363.106117 -269.689282) (xy 363.056724 -269.70533)
			(xy 363.005429 -269.713455) (xy 362.953495 -269.713455) (xy 362.9022 -269.70533) (xy 362.852807 -269.689282)
			(xy 362.806533 -269.665704) (xy 362.764517 -269.635178) (xy 362.727794 -269.598455) (xy 362.697268 -269.556439)
			(xy 362.67369 -269.510165) (xy 362.657642 -269.460772) (xy 362.649517 -269.409477) (xy 362.370115 -269.409477)
			(xy 362.36199 -269.460772) (xy 362.345942 -269.510165) (xy 362.322364 -269.556439) (xy 362.291838 -269.598455)
			(xy 362.255115 -269.635178) (xy 362.213099 -269.665704) (xy 362.166825 -269.689282) (xy 362.117432 -269.70533)
			(xy 362.066137 -269.713455) (xy 362.014203 -269.713455) (xy 361.962908 -269.70533) (xy 361.913515 -269.689282)
			(xy 361.867241 -269.665704) (xy 361.825225 -269.635178) (xy 361.788502 -269.598455) (xy 361.757976 -269.556439)
			(xy 361.734398 -269.510165) (xy 361.71835 -269.460772) (xy 361.710225 -269.409477) (xy 358.610407 -269.409477)
			(xy 358.602282 -269.460772) (xy 358.586234 -269.510165) (xy 358.562656 -269.556439) (xy 358.53213 -269.598455)
			(xy 358.495407 -269.635178) (xy 358.453391 -269.665704) (xy 358.407117 -269.689282) (xy 358.357724 -269.70533)
			(xy 358.306429 -269.713455) (xy 358.254495 -269.713455) (xy 358.2032 -269.70533) (xy 358.153807 -269.689282)
			(xy 358.107533 -269.665704) (xy 358.065517 -269.635178) (xy 358.028794 -269.598455) (xy 357.998268 -269.556439)
			(xy 357.97469 -269.510165) (xy 357.958642 -269.460772) (xy 357.950517 -269.409477) (xy 357.670607 -269.409477)
			(xy 357.662482 -269.460772) (xy 357.646434 -269.510165) (xy 357.622856 -269.556439) (xy 357.59233 -269.598455)
			(xy 357.555607 -269.635178) (xy 357.513591 -269.665704) (xy 357.467317 -269.689282) (xy 357.417924 -269.70533)
			(xy 357.366629 -269.713455) (xy 357.314695 -269.713455) (xy 357.2634 -269.70533) (xy 357.214007 -269.689282)
			(xy 357.167733 -269.665704) (xy 357.125717 -269.635178) (xy 357.088994 -269.598455) (xy 357.058468 -269.556439)
			(xy 357.03489 -269.510165) (xy 357.018842 -269.460772) (xy 357.010717 -269.409477) (xy 356.730807 -269.409477)
			(xy 356.722682 -269.460772) (xy 356.706634 -269.510165) (xy 356.683056 -269.556439) (xy 356.65253 -269.598455)
			(xy 356.615807 -269.635178) (xy 356.573791 -269.665704) (xy 356.527517 -269.689282) (xy 356.478124 -269.70533)
			(xy 356.426829 -269.713455) (xy 356.374895 -269.713455) (xy 356.3236 -269.70533) (xy 356.274207 -269.689282)
			(xy 356.227933 -269.665704) (xy 356.185917 -269.635178) (xy 356.149194 -269.598455) (xy 356.118668 -269.556439)
			(xy 356.09509 -269.510165) (xy 356.079042 -269.460772) (xy 356.070917 -269.409477) (xy 355.791007 -269.409477)
			(xy 355.782882 -269.460772) (xy 355.766834 -269.510165) (xy 355.743256 -269.556439) (xy 355.71273 -269.598455)
			(xy 355.676007 -269.635178) (xy 355.633991 -269.665704) (xy 355.587717 -269.689282) (xy 355.538324 -269.70533)
			(xy 355.487029 -269.713455) (xy 355.435095 -269.713455) (xy 355.3838 -269.70533) (xy 355.334407 -269.689282)
			(xy 355.288133 -269.665704) (xy 355.246117 -269.635178) (xy 355.209394 -269.598455) (xy 355.178868 -269.556439)
			(xy 355.15529 -269.510165) (xy 355.139242 -269.460772) (xy 355.131117 -269.409477) (xy 354.851207 -269.409477)
			(xy 354.843082 -269.460772) (xy 354.827034 -269.510165) (xy 354.803456 -269.556439) (xy 354.77293 -269.598455)
			(xy 354.736207 -269.635178) (xy 354.694191 -269.665704) (xy 354.647917 -269.689282) (xy 354.598524 -269.70533)
			(xy 354.547229 -269.713455) (xy 354.495295 -269.713455) (xy 354.444 -269.70533) (xy 354.394607 -269.689282)
			(xy 354.348333 -269.665704) (xy 354.306317 -269.635178) (xy 354.269594 -269.598455) (xy 354.239068 -269.556439)
			(xy 354.21549 -269.510165) (xy 354.199442 -269.460772) (xy 354.191317 -269.409477) (xy 353.911407 -269.409477)
			(xy 353.903282 -269.460772) (xy 353.887234 -269.510165) (xy 353.863656 -269.556439) (xy 353.83313 -269.598455)
			(xy 353.796407 -269.635178) (xy 353.754391 -269.665704) (xy 353.708117 -269.689282) (xy 353.658724 -269.70533)
			(xy 353.607429 -269.713455) (xy 353.555495 -269.713455) (xy 353.5042 -269.70533) (xy 353.454807 -269.689282)
			(xy 353.408533 -269.665704) (xy 353.366517 -269.635178) (xy 353.329794 -269.598455) (xy 353.299268 -269.556439)
			(xy 353.27569 -269.510165) (xy 353.259642 -269.460772) (xy 353.251517 -269.409477) (xy 352.971607 -269.409477)
			(xy 352.963482 -269.460772) (xy 352.947434 -269.510165) (xy 352.923856 -269.556439) (xy 352.89333 -269.598455)
			(xy 352.856607 -269.635178) (xy 352.814591 -269.665704) (xy 352.768317 -269.689282) (xy 352.718924 -269.70533)
			(xy 352.667629 -269.713455) (xy 352.615695 -269.713455) (xy 352.5644 -269.70533) (xy 352.515007 -269.689282)
			(xy 352.468733 -269.665704) (xy 352.426717 -269.635178) (xy 352.389994 -269.598455) (xy 352.359468 -269.556439)
			(xy 352.33589 -269.510165) (xy 352.319842 -269.460772) (xy 352.311717 -269.409477) (xy 352.031807 -269.409477)
			(xy 352.023682 -269.460772) (xy 352.007634 -269.510165) (xy 351.984056 -269.556439) (xy 351.95353 -269.598455)
			(xy 351.916807 -269.635178) (xy 351.874791 -269.665704) (xy 351.828517 -269.689282) (xy 351.779124 -269.70533)
			(xy 351.727829 -269.713455) (xy 351.675895 -269.713455) (xy 351.6246 -269.70533) (xy 351.575207 -269.689282)
			(xy 351.528933 -269.665704) (xy 351.486917 -269.635178) (xy 351.450194 -269.598455) (xy 351.419668 -269.556439)
			(xy 351.39609 -269.510165) (xy 351.380042 -269.460772) (xy 351.371917 -269.409477) (xy 351.092007 -269.409477)
			(xy 351.083882 -269.460772) (xy 351.067834 -269.510165) (xy 351.044256 -269.556439) (xy 351.01373 -269.598455)
			(xy 350.977007 -269.635178) (xy 350.934991 -269.665704) (xy 350.888717 -269.689282) (xy 350.839324 -269.70533)
			(xy 350.788029 -269.713455) (xy 350.736095 -269.713455) (xy 350.6848 -269.70533) (xy 350.635407 -269.689282)
			(xy 350.589133 -269.665704) (xy 350.547117 -269.635178) (xy 350.510394 -269.598455) (xy 350.479868 -269.556439)
			(xy 350.45629 -269.510165) (xy 350.440242 -269.460772) (xy 350.432117 -269.409477) (xy 350.152715 -269.409477)
			(xy 350.14459 -269.460772) (xy 350.128542 -269.510165) (xy 350.104964 -269.556439) (xy 350.074438 -269.598455)
			(xy 350.037715 -269.635178) (xy 349.995699 -269.665704) (xy 349.949425 -269.689282) (xy 349.900032 -269.70533)
			(xy 349.848737 -269.713455) (xy 349.796803 -269.713455) (xy 349.745508 -269.70533) (xy 349.696115 -269.689282)
			(xy 349.649841 -269.665704) (xy 349.607825 -269.635178) (xy 349.571102 -269.598455) (xy 349.540576 -269.556439)
			(xy 349.516998 -269.510165) (xy 349.50095 -269.460772) (xy 349.492825 -269.409477) (xy 349.212407 -269.409477)
			(xy 349.204282 -269.460772) (xy 349.188234 -269.510165) (xy 349.164656 -269.556439) (xy 349.13413 -269.598455)
			(xy 349.097407 -269.635178) (xy 349.055391 -269.665704) (xy 349.009117 -269.689282) (xy 348.959724 -269.70533)
			(xy 348.908429 -269.713455) (xy 348.856495 -269.713455) (xy 348.8052 -269.70533) (xy 348.755807 -269.689282)
			(xy 348.709533 -269.665704) (xy 348.667517 -269.635178) (xy 348.630794 -269.598455) (xy 348.600268 -269.556439)
			(xy 348.57669 -269.510165) (xy 348.560642 -269.460772) (xy 348.552517 -269.409477) (xy 348.272607 -269.409477)
			(xy 348.264482 -269.460772) (xy 348.248434 -269.510165) (xy 348.224856 -269.556439) (xy 348.19433 -269.598455)
			(xy 348.157607 -269.635178) (xy 348.115591 -269.665704) (xy 348.069317 -269.689282) (xy 348.019924 -269.70533)
			(xy 347.968629 -269.713455) (xy 347.916695 -269.713455) (xy 347.8654 -269.70533) (xy 347.816007 -269.689282)
			(xy 347.769733 -269.665704) (xy 347.727717 -269.635178) (xy 347.690994 -269.598455) (xy 347.660468 -269.556439)
			(xy 347.63689 -269.510165) (xy 347.620842 -269.460772) (xy 347.612717 -269.409477) (xy 347.332807 -269.409477)
			(xy 347.324682 -269.460772) (xy 347.308634 -269.510165) (xy 347.285056 -269.556439) (xy 347.25453 -269.598455)
			(xy 347.217807 -269.635178) (xy 347.175791 -269.665704) (xy 347.129517 -269.689282) (xy 347.080124 -269.70533)
			(xy 347.028829 -269.713455) (xy 346.976895 -269.713455) (xy 346.9256 -269.70533) (xy 346.876207 -269.689282)
			(xy 346.829933 -269.665704) (xy 346.787917 -269.635178) (xy 346.751194 -269.598455) (xy 346.720668 -269.556439)
			(xy 346.69709 -269.510165) (xy 346.681042 -269.460772) (xy 346.672917 -269.409477) (xy 346.393261 -269.409477)
			(xy 346.385136 -269.460772) (xy 346.369088 -269.510165) (xy 346.34551 -269.556439) (xy 346.314984 -269.598455)
			(xy 346.278261 -269.635178) (xy 346.236245 -269.665704) (xy 346.189971 -269.689282) (xy 346.140578 -269.70533)
			(xy 346.089283 -269.713455) (xy 346.037349 -269.713455) (xy 345.986054 -269.70533) (xy 345.936661 -269.689282)
			(xy 345.890387 -269.665704) (xy 345.848371 -269.635178) (xy 345.811648 -269.598455) (xy 345.781122 -269.556439)
			(xy 345.757544 -269.510165) (xy 345.741496 -269.460772) (xy 345.733371 -269.409477) (xy 345.453207 -269.409477)
			(xy 345.445082 -269.460772) (xy 345.429034 -269.510165) (xy 345.405456 -269.556439) (xy 345.37493 -269.598455)
			(xy 345.338207 -269.635178) (xy 345.296191 -269.665704) (xy 345.249917 -269.689282) (xy 345.200524 -269.70533)
			(xy 345.149229 -269.713455) (xy 345.097295 -269.713455) (xy 345.046 -269.70533) (xy 344.996607 -269.689282)
			(xy 344.950333 -269.665704) (xy 344.908317 -269.635178) (xy 344.871594 -269.598455) (xy 344.841068 -269.556439)
			(xy 344.81749 -269.510165) (xy 344.801442 -269.460772) (xy 344.793317 -269.409477) (xy 344.557604 -269.409477)
			(xy 344.557604 -269.765526) (xy 344.558028 -269.778737) (xy 344.564819 -269.804271) (xy 344.577938 -269.827206)
			(xy 344.596507 -269.846003) (xy 344.61928 -269.859401) (xy 344.64473 -269.866503) (xy 344.657934 -269.867126)
			(xy 344.68368 -269.867956) (xy 344.734456 -269.876614) (xy 344.783275 -269.893044) (xy 344.828953 -269.916849)
			(xy 344.870386 -269.947452) (xy 344.906569 -269.984113) (xy 344.936626 -270.025943) (xy 344.95983 -270.07193)
			(xy 344.975619 -270.12096) (xy 344.98361 -270.171845) (xy 344.98361 -270.223354) (xy 344.98358 -270.223547)
			(xy 345.263471 -270.223547) (xy 345.263471 -270.171613) (xy 345.271596 -270.120318) (xy 345.287644 -270.070925)
			(xy 345.311222 -270.024651) (xy 345.341748 -269.982635) (xy 345.378471 -269.945912) (xy 345.420487 -269.915386)
			(xy 345.466761 -269.891808) (xy 345.516154 -269.87576) (xy 345.567449 -269.867635) (xy 345.619383 -269.867635)
			(xy 345.670678 -269.87576) (xy 345.720071 -269.891808) (xy 345.766345 -269.915386) (xy 345.808361 -269.945912)
			(xy 345.845084 -269.982635) (xy 345.87561 -270.024651) (xy 345.899188 -270.070925) (xy 345.915236 -270.120318)
			(xy 345.923361 -270.171613) (xy 345.92387 -270.19758) (xy 345.923361 -270.223547) (xy 346.203017 -270.223547)
			(xy 346.203017 -270.171613) (xy 346.211142 -270.120318) (xy 346.22719 -270.070925) (xy 346.250768 -270.024651)
			(xy 346.281294 -269.982635) (xy 346.318017 -269.945912) (xy 346.360033 -269.915386) (xy 346.406307 -269.891808)
			(xy 346.4557 -269.87576) (xy 346.506995 -269.867635) (xy 346.558929 -269.867635) (xy 346.610224 -269.87576)
			(xy 346.659617 -269.891808) (xy 346.705891 -269.915386) (xy 346.747907 -269.945912) (xy 346.78463 -269.982635)
			(xy 346.815156 -270.024651) (xy 346.838734 -270.070925) (xy 346.854782 -270.120318) (xy 346.862907 -270.171613)
			(xy 346.863416 -270.19758) (xy 346.862907 -270.223547) (xy 347.143071 -270.223547) (xy 347.143071 -270.171613)
			(xy 347.151196 -270.120318) (xy 347.167244 -270.070925) (xy 347.190822 -270.024651) (xy 347.221348 -269.982635)
			(xy 347.258071 -269.945912) (xy 347.300087 -269.915386) (xy 347.346361 -269.891808) (xy 347.395754 -269.87576)
			(xy 347.447049 -269.867635) (xy 347.498983 -269.867635) (xy 347.550278 -269.87576) (xy 347.599671 -269.891808)
			(xy 347.645945 -269.915386) (xy 347.687961 -269.945912) (xy 347.724684 -269.982635) (xy 347.75521 -270.024651)
			(xy 347.778788 -270.070925) (xy 347.794836 -270.120318) (xy 347.802961 -270.171613) (xy 347.80347 -270.19758)
			(xy 347.802961 -270.223547) (xy 348.082871 -270.223547) (xy 348.082871 -270.171613) (xy 348.090996 -270.120318)
			(xy 348.107044 -270.070925) (xy 348.130622 -270.024651) (xy 348.161148 -269.982635) (xy 348.197871 -269.945912)
			(xy 348.239887 -269.915386) (xy 348.286161 -269.891808) (xy 348.335554 -269.87576) (xy 348.386849 -269.867635)
			(xy 348.438783 -269.867635) (xy 348.490078 -269.87576) (xy 348.539471 -269.891808) (xy 348.585745 -269.915386)
			(xy 348.627761 -269.945912) (xy 348.664484 -269.982635) (xy 348.69501 -270.024651) (xy 348.718588 -270.070925)
			(xy 348.734636 -270.120318) (xy 348.742761 -270.171613) (xy 348.74327 -270.19758) (xy 348.742761 -270.223547)
			(xy 349.022671 -270.223547) (xy 349.022671 -270.171613) (xy 349.030796 -270.120318) (xy 349.046844 -270.070925)
			(xy 349.070422 -270.024651) (xy 349.100948 -269.982635) (xy 349.137671 -269.945912) (xy 349.179687 -269.915386)
			(xy 349.225961 -269.891808) (xy 349.275354 -269.87576) (xy 349.326649 -269.867635) (xy 349.378583 -269.867635)
			(xy 349.429878 -269.87576) (xy 349.479271 -269.891808) (xy 349.525545 -269.915386) (xy 349.567561 -269.945912)
			(xy 349.604284 -269.982635) (xy 349.63481 -270.024651) (xy 349.658388 -270.070925) (xy 349.674436 -270.120318)
			(xy 349.682561 -270.171613) (xy 349.68307 -270.19758) (xy 349.682561 -270.223547) (xy 349.962471 -270.223547)
			(xy 349.962471 -270.171613) (xy 349.970596 -270.120318) (xy 349.986644 -270.070925) (xy 350.010222 -270.024651)
			(xy 350.040748 -269.982635) (xy 350.077471 -269.945912) (xy 350.119487 -269.915386) (xy 350.165761 -269.891808)
			(xy 350.215154 -269.87576) (xy 350.266449 -269.867635) (xy 350.318383 -269.867635) (xy 350.369678 -269.87576)
			(xy 350.419071 -269.891808) (xy 350.465345 -269.915386) (xy 350.507361 -269.945912) (xy 350.544084 -269.982635)
			(xy 350.57461 -270.024651) (xy 350.598188 -270.070925) (xy 350.614236 -270.120318) (xy 350.622361 -270.171613)
			(xy 350.62287 -270.19758) (xy 350.622361 -270.223547) (xy 350.902271 -270.223547) (xy 350.902271 -270.171613)
			(xy 350.910396 -270.120318) (xy 350.926444 -270.070925) (xy 350.950022 -270.024651) (xy 350.980548 -269.982635)
			(xy 351.017271 -269.945912) (xy 351.059287 -269.915386) (xy 351.105561 -269.891808) (xy 351.154954 -269.87576)
			(xy 351.206249 -269.867635) (xy 351.258183 -269.867635) (xy 351.309478 -269.87576) (xy 351.358871 -269.891808)
			(xy 351.405145 -269.915386) (xy 351.447161 -269.945912) (xy 351.483884 -269.982635) (xy 351.51441 -270.024651)
			(xy 351.537988 -270.070925) (xy 351.554036 -270.120318) (xy 351.562161 -270.171613) (xy 351.56267 -270.19758)
			(xy 351.562161 -270.223547) (xy 351.842071 -270.223547) (xy 351.842071 -270.171613) (xy 351.850196 -270.120318)
			(xy 351.866244 -270.070925) (xy 351.889822 -270.024651) (xy 351.920348 -269.982635) (xy 351.957071 -269.945912)
			(xy 351.999087 -269.915386) (xy 352.045361 -269.891808) (xy 352.094754 -269.87576) (xy 352.146049 -269.867635)
			(xy 352.197983 -269.867635) (xy 352.249278 -269.87576) (xy 352.298671 -269.891808) (xy 352.344945 -269.915386)
			(xy 352.386961 -269.945912) (xy 352.423684 -269.982635) (xy 352.45421 -270.024651) (xy 352.477788 -270.070925)
			(xy 352.493836 -270.120318) (xy 352.501961 -270.171613) (xy 352.50247 -270.19758) (xy 352.501961 -270.223547)
			(xy 352.781871 -270.223547) (xy 352.781871 -270.171613) (xy 352.789996 -270.120318) (xy 352.806044 -270.070925)
			(xy 352.829622 -270.024651) (xy 352.860148 -269.982635) (xy 352.896871 -269.945912) (xy 352.938887 -269.915386)
			(xy 352.985161 -269.891808) (xy 353.034554 -269.87576) (xy 353.085849 -269.867635) (xy 353.137783 -269.867635)
			(xy 353.189078 -269.87576) (xy 353.238471 -269.891808) (xy 353.284745 -269.915386) (xy 353.326761 -269.945912)
			(xy 353.363484 -269.982635) (xy 353.39401 -270.024651) (xy 353.417588 -270.070925) (xy 353.433636 -270.120318)
			(xy 353.441761 -270.171613) (xy 353.44227 -270.19758) (xy 353.441761 -270.223547) (xy 353.721671 -270.223547)
			(xy 353.721671 -270.171613) (xy 353.729796 -270.120318) (xy 353.745844 -270.070925) (xy 353.769422 -270.024651)
			(xy 353.799948 -269.982635) (xy 353.836671 -269.945912) (xy 353.878687 -269.915386) (xy 353.924961 -269.891808)
			(xy 353.974354 -269.87576) (xy 354.025649 -269.867635) (xy 354.077583 -269.867635) (xy 354.128878 -269.87576)
			(xy 354.178271 -269.891808) (xy 354.224545 -269.915386) (xy 354.266561 -269.945912) (xy 354.303284 -269.982635)
			(xy 354.33381 -270.024651) (xy 354.357388 -270.070925) (xy 354.373436 -270.120318) (xy 354.381561 -270.171613)
			(xy 354.38207 -270.19758) (xy 354.381561 -270.223547) (xy 354.661471 -270.223547) (xy 354.661471 -270.171613)
			(xy 354.669596 -270.120318) (xy 354.685644 -270.070925) (xy 354.709222 -270.024651) (xy 354.739748 -269.982635)
			(xy 354.776471 -269.945912) (xy 354.818487 -269.915386) (xy 354.864761 -269.891808) (xy 354.914154 -269.87576)
			(xy 354.965449 -269.867635) (xy 355.017383 -269.867635) (xy 355.068678 -269.87576) (xy 355.118071 -269.891808)
			(xy 355.164345 -269.915386) (xy 355.206361 -269.945912) (xy 355.243084 -269.982635) (xy 355.27361 -270.024651)
			(xy 355.297188 -270.070925) (xy 355.313236 -270.120318) (xy 355.321361 -270.171613) (xy 355.32187 -270.19758)
			(xy 355.321361 -270.223547) (xy 355.601271 -270.223547) (xy 355.601271 -270.171613) (xy 355.609396 -270.120318)
			(xy 355.625444 -270.070925) (xy 355.649022 -270.024651) (xy 355.679548 -269.982635) (xy 355.716271 -269.945912)
			(xy 355.758287 -269.915386) (xy 355.804561 -269.891808) (xy 355.853954 -269.87576) (xy 355.905249 -269.867635)
			(xy 355.957183 -269.867635) (xy 356.008478 -269.87576) (xy 356.057871 -269.891808) (xy 356.104145 -269.915386)
			(xy 356.146161 -269.945912) (xy 356.182884 -269.982635) (xy 356.21341 -270.024651) (xy 356.236988 -270.070925)
			(xy 356.253036 -270.120318) (xy 356.261161 -270.171613) (xy 356.26167 -270.19758) (xy 356.261161 -270.223547)
			(xy 356.540817 -270.223547) (xy 356.540817 -270.171613) (xy 356.548942 -270.120318) (xy 356.56499 -270.070925)
			(xy 356.588568 -270.024651) (xy 356.619094 -269.982635) (xy 356.655817 -269.945912) (xy 356.697833 -269.915386)
			(xy 356.744107 -269.891808) (xy 356.7935 -269.87576) (xy 356.844795 -269.867635) (xy 356.896729 -269.867635)
			(xy 356.948024 -269.87576) (xy 356.997417 -269.891808) (xy 357.043691 -269.915386) (xy 357.085707 -269.945912)
			(xy 357.12243 -269.982635) (xy 357.152956 -270.024651) (xy 357.176534 -270.070925) (xy 357.192582 -270.120318)
			(xy 357.200707 -270.171613) (xy 357.201216 -270.19758) (xy 357.200707 -270.223547) (xy 357.480617 -270.223547)
			(xy 357.480617 -270.171613) (xy 357.488742 -270.120318) (xy 357.50479 -270.070925) (xy 357.528368 -270.024651)
			(xy 357.558894 -269.982635) (xy 357.595617 -269.945912) (xy 357.637633 -269.915386) (xy 357.683907 -269.891808)
			(xy 357.7333 -269.87576) (xy 357.784595 -269.867635) (xy 357.836529 -269.867635) (xy 357.887824 -269.87576)
			(xy 357.937217 -269.891808) (xy 357.983491 -269.915386) (xy 358.025507 -269.945912) (xy 358.06223 -269.982635)
			(xy 358.092756 -270.024651) (xy 358.116334 -270.070925) (xy 358.132382 -270.120318) (xy 358.140507 -270.171613)
			(xy 358.141016 -270.19758) (xy 358.140507 -270.223547) (xy 361.239817 -270.223547) (xy 361.239817 -270.171613)
			(xy 361.247942 -270.120318) (xy 361.26399 -270.070925) (xy 361.287568 -270.024651) (xy 361.318094 -269.982635)
			(xy 361.354817 -269.945912) (xy 361.396833 -269.915386) (xy 361.443107 -269.891808) (xy 361.4925 -269.87576)
			(xy 361.543795 -269.867635) (xy 361.595729 -269.867635) (xy 361.647024 -269.87576) (xy 361.696417 -269.891808)
			(xy 361.742691 -269.915386) (xy 361.784707 -269.945912) (xy 361.82143 -269.982635) (xy 361.851956 -270.024651)
			(xy 361.875534 -270.070925) (xy 361.891582 -270.120318) (xy 361.899707 -270.171613) (xy 361.900216 -270.19758)
			(xy 361.899707 -270.223547) (xy 362.179617 -270.223547) (xy 362.179617 -270.171613) (xy 362.187742 -270.120318)
			(xy 362.20379 -270.070925) (xy 362.227368 -270.024651) (xy 362.257894 -269.982635) (xy 362.294617 -269.945912)
			(xy 362.336633 -269.915386) (xy 362.382907 -269.891808) (xy 362.4323 -269.87576) (xy 362.483595 -269.867635)
			(xy 362.535529 -269.867635) (xy 362.586824 -269.87576) (xy 362.636217 -269.891808) (xy 362.682491 -269.915386)
			(xy 362.724507 -269.945912) (xy 362.76123 -269.982635) (xy 362.791756 -270.024651) (xy 362.815334 -270.070925)
			(xy 362.831382 -270.120318) (xy 362.839507 -270.171613) (xy 362.840016 -270.19758) (xy 362.839507 -270.223547)
			(xy 363.119417 -270.223547) (xy 363.119417 -270.171613) (xy 363.127542 -270.120318) (xy 363.14359 -270.070925)
			(xy 363.167168 -270.024651) (xy 363.197694 -269.982635) (xy 363.234417 -269.945912) (xy 363.276433 -269.915386)
			(xy 363.322707 -269.891808) (xy 363.3721 -269.87576) (xy 363.423395 -269.867635) (xy 363.475329 -269.867635)
			(xy 363.526624 -269.87576) (xy 363.576017 -269.891808) (xy 363.622291 -269.915386) (xy 363.664307 -269.945912)
			(xy 363.70103 -269.982635) (xy 363.731556 -270.024651) (xy 363.755134 -270.070925) (xy 363.771182 -270.120318)
			(xy 363.779307 -270.171613) (xy 363.779816 -270.19758) (xy 363.779307 -270.223547) (xy 363.771182 -270.274842)
			(xy 363.755134 -270.324235) (xy 363.731556 -270.370509) (xy 363.70103 -270.412525) (xy 363.664307 -270.449248)
			(xy 363.622291 -270.479774) (xy 363.576017 -270.503352) (xy 363.526624 -270.5194) (xy 363.475329 -270.527525)
			(xy 363.423395 -270.527525) (xy 363.3721 -270.5194) (xy 363.322707 -270.503352) (xy 363.276433 -270.479774)
			(xy 363.234417 -270.449248) (xy 363.197694 -270.412525) (xy 363.167168 -270.370509) (xy 363.14359 -270.324235)
			(xy 363.127542 -270.274842) (xy 363.119417 -270.223547) (xy 362.839507 -270.223547) (xy 362.831382 -270.274842)
			(xy 362.815334 -270.324235) (xy 362.791756 -270.370509) (xy 362.76123 -270.412525) (xy 362.724507 -270.449248)
			(xy 362.682491 -270.479774) (xy 362.636217 -270.503352) (xy 362.586824 -270.5194) (xy 362.535529 -270.527525)
			(xy 362.483595 -270.527525) (xy 362.4323 -270.5194) (xy 362.382907 -270.503352) (xy 362.336633 -270.479774)
			(xy 362.294617 -270.449248) (xy 362.257894 -270.412525) (xy 362.227368 -270.370509) (xy 362.20379 -270.324235)
			(xy 362.187742 -270.274842) (xy 362.179617 -270.223547) (xy 361.899707 -270.223547) (xy 361.891582 -270.274842)
			(xy 361.875534 -270.324235) (xy 361.851956 -270.370509) (xy 361.82143 -270.412525) (xy 361.784707 -270.449248)
			(xy 361.742691 -270.479774) (xy 361.696417 -270.503352) (xy 361.647024 -270.5194) (xy 361.595729 -270.527525)
			(xy 361.543795 -270.527525) (xy 361.4925 -270.5194) (xy 361.443107 -270.503352) (xy 361.396833 -270.479774)
			(xy 361.354817 -270.449248) (xy 361.318094 -270.412525) (xy 361.287568 -270.370509) (xy 361.26399 -270.324235)
			(xy 361.247942 -270.274842) (xy 361.239817 -270.223547) (xy 358.140507 -270.223547) (xy 358.132382 -270.274842)
			(xy 358.116334 -270.324235) (xy 358.092756 -270.370509) (xy 358.06223 -270.412525) (xy 358.025507 -270.449248)
			(xy 357.983491 -270.479774) (xy 357.937217 -270.503352) (xy 357.887824 -270.5194) (xy 357.836529 -270.527525)
			(xy 357.784595 -270.527525) (xy 357.7333 -270.5194) (xy 357.683907 -270.503352) (xy 357.637633 -270.479774)
			(xy 357.595617 -270.449248) (xy 357.558894 -270.412525) (xy 357.528368 -270.370509) (xy 357.50479 -270.324235)
			(xy 357.488742 -270.274842) (xy 357.480617 -270.223547) (xy 357.200707 -270.223547) (xy 357.192582 -270.274842)
			(xy 357.176534 -270.324235) (xy 357.152956 -270.370509) (xy 357.12243 -270.412525) (xy 357.085707 -270.449248)
			(xy 357.043691 -270.479774) (xy 356.997417 -270.503352) (xy 356.948024 -270.5194) (xy 356.896729 -270.527525)
			(xy 356.844795 -270.527525) (xy 356.7935 -270.5194) (xy 356.744107 -270.503352) (xy 356.697833 -270.479774)
			(xy 356.655817 -270.449248) (xy 356.619094 -270.412525) (xy 356.588568 -270.370509) (xy 356.56499 -270.324235)
			(xy 356.548942 -270.274842) (xy 356.540817 -270.223547) (xy 356.261161 -270.223547) (xy 356.253036 -270.274842)
			(xy 356.236988 -270.324235) (xy 356.21341 -270.370509) (xy 356.182884 -270.412525) (xy 356.146161 -270.449248)
			(xy 356.104145 -270.479774) (xy 356.057871 -270.503352) (xy 356.008478 -270.5194) (xy 355.957183 -270.527525)
			(xy 355.905249 -270.527525) (xy 355.853954 -270.5194) (xy 355.804561 -270.503352) (xy 355.758287 -270.479774)
			(xy 355.716271 -270.449248) (xy 355.679548 -270.412525) (xy 355.649022 -270.370509) (xy 355.625444 -270.324235)
			(xy 355.609396 -270.274842) (xy 355.601271 -270.223547) (xy 355.321361 -270.223547) (xy 355.313236 -270.274842)
			(xy 355.297188 -270.324235) (xy 355.27361 -270.370509) (xy 355.243084 -270.412525) (xy 355.206361 -270.449248)
			(xy 355.164345 -270.479774) (xy 355.118071 -270.503352) (xy 355.068678 -270.5194) (xy 355.017383 -270.527525)
			(xy 354.965449 -270.527525) (xy 354.914154 -270.5194) (xy 354.864761 -270.503352) (xy 354.818487 -270.479774)
			(xy 354.776471 -270.449248) (xy 354.739748 -270.412525) (xy 354.709222 -270.370509) (xy 354.685644 -270.324235)
			(xy 354.669596 -270.274842) (xy 354.661471 -270.223547) (xy 354.381561 -270.223547) (xy 354.373436 -270.274842)
			(xy 354.357388 -270.324235) (xy 354.33381 -270.370509) (xy 354.303284 -270.412525) (xy 354.266561 -270.449248)
			(xy 354.224545 -270.479774) (xy 354.178271 -270.503352) (xy 354.128878 -270.5194) (xy 354.077583 -270.527525)
			(xy 354.025649 -270.527525) (xy 353.974354 -270.5194) (xy 353.924961 -270.503352) (xy 353.878687 -270.479774)
			(xy 353.836671 -270.449248) (xy 353.799948 -270.412525) (xy 353.769422 -270.370509) (xy 353.745844 -270.324235)
			(xy 353.729796 -270.274842) (xy 353.721671 -270.223547) (xy 353.441761 -270.223547) (xy 353.433636 -270.274842)
			(xy 353.417588 -270.324235) (xy 353.39401 -270.370509) (xy 353.363484 -270.412525) (xy 353.326761 -270.449248)
			(xy 353.284745 -270.479774) (xy 353.238471 -270.503352) (xy 353.189078 -270.5194) (xy 353.137783 -270.527525)
			(xy 353.085849 -270.527525) (xy 353.034554 -270.5194) (xy 352.985161 -270.503352) (xy 352.938887 -270.479774)
			(xy 352.896871 -270.449248) (xy 352.860148 -270.412525) (xy 352.829622 -270.370509) (xy 352.806044 -270.324235)
			(xy 352.789996 -270.274842) (xy 352.781871 -270.223547) (xy 352.501961 -270.223547) (xy 352.493836 -270.274842)
			(xy 352.477788 -270.324235) (xy 352.45421 -270.370509) (xy 352.423684 -270.412525) (xy 352.386961 -270.449248)
			(xy 352.344945 -270.479774) (xy 352.298671 -270.503352) (xy 352.249278 -270.5194) (xy 352.197983 -270.527525)
			(xy 352.146049 -270.527525) (xy 352.094754 -270.5194) (xy 352.045361 -270.503352) (xy 351.999087 -270.479774)
			(xy 351.957071 -270.449248) (xy 351.920348 -270.412525) (xy 351.889822 -270.370509) (xy 351.866244 -270.324235)
			(xy 351.850196 -270.274842) (xy 351.842071 -270.223547) (xy 351.562161 -270.223547) (xy 351.554036 -270.274842)
			(xy 351.537988 -270.324235) (xy 351.51441 -270.370509) (xy 351.483884 -270.412525) (xy 351.447161 -270.449248)
			(xy 351.405145 -270.479774) (xy 351.358871 -270.503352) (xy 351.309478 -270.5194) (xy 351.258183 -270.527525)
			(xy 351.206249 -270.527525) (xy 351.154954 -270.5194) (xy 351.105561 -270.503352) (xy 351.059287 -270.479774)
			(xy 351.017271 -270.449248) (xy 350.980548 -270.412525) (xy 350.950022 -270.370509) (xy 350.926444 -270.324235)
			(xy 350.910396 -270.274842) (xy 350.902271 -270.223547) (xy 350.622361 -270.223547) (xy 350.614236 -270.274842)
			(xy 350.598188 -270.324235) (xy 350.57461 -270.370509) (xy 350.544084 -270.412525) (xy 350.507361 -270.449248)
			(xy 350.465345 -270.479774) (xy 350.419071 -270.503352) (xy 350.369678 -270.5194) (xy 350.318383 -270.527525)
			(xy 350.266449 -270.527525) (xy 350.215154 -270.5194) (xy 350.165761 -270.503352) (xy 350.119487 -270.479774)
			(xy 350.077471 -270.449248) (xy 350.040748 -270.412525) (xy 350.010222 -270.370509) (xy 349.986644 -270.324235)
			(xy 349.970596 -270.274842) (xy 349.962471 -270.223547) (xy 349.682561 -270.223547) (xy 349.674436 -270.274842)
			(xy 349.658388 -270.324235) (xy 349.63481 -270.370509) (xy 349.604284 -270.412525) (xy 349.567561 -270.449248)
			(xy 349.525545 -270.479774) (xy 349.479271 -270.503352) (xy 349.429878 -270.5194) (xy 349.378583 -270.527525)
			(xy 349.326649 -270.527525) (xy 349.275354 -270.5194) (xy 349.225961 -270.503352) (xy 349.179687 -270.479774)
			(xy 349.137671 -270.449248) (xy 349.100948 -270.412525) (xy 349.070422 -270.370509) (xy 349.046844 -270.324235)
			(xy 349.030796 -270.274842) (xy 349.022671 -270.223547) (xy 348.742761 -270.223547) (xy 348.734636 -270.274842)
			(xy 348.718588 -270.324235) (xy 348.69501 -270.370509) (xy 348.664484 -270.412525) (xy 348.627761 -270.449248)
			(xy 348.585745 -270.479774) (xy 348.539471 -270.503352) (xy 348.490078 -270.5194) (xy 348.438783 -270.527525)
			(xy 348.386849 -270.527525) (xy 348.335554 -270.5194) (xy 348.286161 -270.503352) (xy 348.239887 -270.479774)
			(xy 348.197871 -270.449248) (xy 348.161148 -270.412525) (xy 348.130622 -270.370509) (xy 348.107044 -270.324235)
			(xy 348.090996 -270.274842) (xy 348.082871 -270.223547) (xy 347.802961 -270.223547) (xy 347.794836 -270.274842)
			(xy 347.778788 -270.324235) (xy 347.75521 -270.370509) (xy 347.724684 -270.412525) (xy 347.687961 -270.449248)
			(xy 347.645945 -270.479774) (xy 347.599671 -270.503352) (xy 347.550278 -270.5194) (xy 347.498983 -270.527525)
			(xy 347.447049 -270.527525) (xy 347.395754 -270.5194) (xy 347.346361 -270.503352) (xy 347.300087 -270.479774)
			(xy 347.258071 -270.449248) (xy 347.221348 -270.412525) (xy 347.190822 -270.370509) (xy 347.167244 -270.324235)
			(xy 347.151196 -270.274842) (xy 347.143071 -270.223547) (xy 346.862907 -270.223547) (xy 346.854782 -270.274842)
			(xy 346.838734 -270.324235) (xy 346.815156 -270.370509) (xy 346.78463 -270.412525) (xy 346.747907 -270.449248)
			(xy 346.705891 -270.479774) (xy 346.659617 -270.503352) (xy 346.610224 -270.5194) (xy 346.558929 -270.527525)
			(xy 346.506995 -270.527525) (xy 346.4557 -270.5194) (xy 346.406307 -270.503352) (xy 346.360033 -270.479774)
			(xy 346.318017 -270.449248) (xy 346.281294 -270.412525) (xy 346.250768 -270.370509) (xy 346.22719 -270.324235)
			(xy 346.211142 -270.274842) (xy 346.203017 -270.223547) (xy 345.923361 -270.223547) (xy 345.915236 -270.274842)
			(xy 345.899188 -270.324235) (xy 345.87561 -270.370509) (xy 345.845084 -270.412525) (xy 345.808361 -270.449248)
			(xy 345.766345 -270.479774) (xy 345.720071 -270.503352) (xy 345.670678 -270.5194) (xy 345.619383 -270.527525)
			(xy 345.567449 -270.527525) (xy 345.516154 -270.5194) (xy 345.466761 -270.503352) (xy 345.420487 -270.479774)
			(xy 345.378471 -270.449248) (xy 345.341748 -270.412525) (xy 345.311222 -270.370509) (xy 345.287644 -270.324235)
			(xy 345.271596 -270.274842) (xy 345.263471 -270.223547) (xy 344.98358 -270.223547) (xy 344.975619 -270.27424)
			(xy 344.95983 -270.32327) (xy 344.936626 -270.369257) (xy 344.906569 -270.411087) (xy 344.870386 -270.447747)
			(xy 344.828954 -270.478351) (xy 344.783275 -270.502156) (xy 344.734457 -270.518586) (xy 344.68368 -270.527244)
			(xy 344.657934 -270.528034) (xy 344.644727 -270.52862) (xy 344.619275 -270.535726) (xy 344.596501 -270.549131)
			(xy 344.577935 -270.567936) (xy 344.564822 -270.590879) (xy 344.558043 -270.616421) (xy 344.557604 -270.629634)
			(xy 344.557604 -271.037363) (xy 344.793317 -271.037363) (xy 344.793317 -270.985429) (xy 344.801442 -270.934134)
			(xy 344.81749 -270.884741) (xy 344.841068 -270.838467) (xy 344.871594 -270.796451) (xy 344.908317 -270.759728)
			(xy 344.950333 -270.729202) (xy 344.996607 -270.705624) (xy 345.046 -270.689576) (xy 345.097295 -270.681451)
			(xy 345.149229 -270.681451) (xy 345.200524 -270.689576) (xy 345.249917 -270.705624) (xy 345.296191 -270.729202)
			(xy 345.338207 -270.759728) (xy 345.37493 -270.796451) (xy 345.405456 -270.838467) (xy 345.429034 -270.884741)
			(xy 345.445082 -270.934134) (xy 345.453207 -270.985429) (xy 345.453716 -271.011396) (xy 345.453207 -271.037363)
			(xy 345.733117 -271.037363) (xy 345.733117 -270.985429) (xy 345.741242 -270.934134) (xy 345.75729 -270.884741)
			(xy 345.780868 -270.838467) (xy 345.811394 -270.796451) (xy 345.848117 -270.759728) (xy 345.890133 -270.729202)
			(xy 345.936407 -270.705624) (xy 345.9858 -270.689576) (xy 346.037095 -270.681451) (xy 346.089029 -270.681451)
			(xy 346.140324 -270.689576) (xy 346.189717 -270.705624) (xy 346.235991 -270.729202) (xy 346.278007 -270.759728)
			(xy 346.31473 -270.796451) (xy 346.345256 -270.838467) (xy 346.368834 -270.884741) (xy 346.384882 -270.934134)
			(xy 346.393007 -270.985429) (xy 346.393516 -271.011396) (xy 346.393007 -271.037363) (xy 346.672917 -271.037363)
			(xy 346.672917 -270.985429) (xy 346.681042 -270.934134) (xy 346.69709 -270.884741) (xy 346.720668 -270.838467)
			(xy 346.751194 -270.796451) (xy 346.787917 -270.759728) (xy 346.829933 -270.729202) (xy 346.876207 -270.705624)
			(xy 346.9256 -270.689576) (xy 346.976895 -270.681451) (xy 347.028829 -270.681451) (xy 347.080124 -270.689576)
			(xy 347.129517 -270.705624) (xy 347.175791 -270.729202) (xy 347.217807 -270.759728) (xy 347.25453 -270.796451)
			(xy 347.285056 -270.838467) (xy 347.308634 -270.884741) (xy 347.324682 -270.934134) (xy 347.332807 -270.985429)
			(xy 347.333316 -271.011396) (xy 347.332807 -271.037363) (xy 347.612717 -271.037363) (xy 347.612717 -270.985429)
			(xy 347.620842 -270.934134) (xy 347.63689 -270.884741) (xy 347.660468 -270.838467) (xy 347.690994 -270.796451)
			(xy 347.727717 -270.759728) (xy 347.769733 -270.729202) (xy 347.816007 -270.705624) (xy 347.8654 -270.689576)
			(xy 347.916695 -270.681451) (xy 347.968629 -270.681451) (xy 348.019924 -270.689576) (xy 348.069317 -270.705624)
			(xy 348.115591 -270.729202) (xy 348.157607 -270.759728) (xy 348.19433 -270.796451) (xy 348.224856 -270.838467)
			(xy 348.248434 -270.884741) (xy 348.264482 -270.934134) (xy 348.272607 -270.985429) (xy 348.273116 -271.011396)
			(xy 348.272607 -271.037363) (xy 348.552771 -271.037363) (xy 348.552771 -270.985429) (xy 348.560896 -270.934134)
			(xy 348.576944 -270.884741) (xy 348.600522 -270.838467) (xy 348.631048 -270.796451) (xy 348.667771 -270.759728)
			(xy 348.709787 -270.729202) (xy 348.756061 -270.705624) (xy 348.805454 -270.689576) (xy 348.856749 -270.681451)
			(xy 348.908683 -270.681451) (xy 348.959978 -270.689576) (xy 349.009371 -270.705624) (xy 349.055645 -270.729202)
			(xy 349.097661 -270.759728) (xy 349.134384 -270.796451) (xy 349.16491 -270.838467) (xy 349.188488 -270.884741)
			(xy 349.204536 -270.934134) (xy 349.212661 -270.985429) (xy 349.21317 -271.011396) (xy 349.212661 -271.037363)
			(xy 349.492571 -271.037363) (xy 349.492571 -270.985429) (xy 349.500696 -270.934134) (xy 349.516744 -270.884741)
			(xy 349.540322 -270.838467) (xy 349.570848 -270.796451) (xy 349.607571 -270.759728) (xy 349.649587 -270.729202)
			(xy 349.695861 -270.705624) (xy 349.745254 -270.689576) (xy 349.796549 -270.681451) (xy 349.848483 -270.681451)
			(xy 349.899778 -270.689576) (xy 349.949171 -270.705624) (xy 349.995445 -270.729202) (xy 350.037461 -270.759728)
			(xy 350.074184 -270.796451) (xy 350.10471 -270.838467) (xy 350.128288 -270.884741) (xy 350.144336 -270.934134)
			(xy 350.152461 -270.985429) (xy 350.15297 -271.011396) (xy 350.152461 -271.037363) (xy 350.432117 -271.037363)
			(xy 350.432117 -270.985429) (xy 350.440242 -270.934134) (xy 350.45629 -270.884741) (xy 350.479868 -270.838467)
			(xy 350.510394 -270.796451) (xy 350.547117 -270.759728) (xy 350.589133 -270.729202) (xy 350.635407 -270.705624)
			(xy 350.6848 -270.689576) (xy 350.736095 -270.681451) (xy 350.788029 -270.681451) (xy 350.839324 -270.689576)
			(xy 350.888717 -270.705624) (xy 350.934991 -270.729202) (xy 350.977007 -270.759728) (xy 351.01373 -270.796451)
			(xy 351.044256 -270.838467) (xy 351.067834 -270.884741) (xy 351.083882 -270.934134) (xy 351.092007 -270.985429)
			(xy 351.092516 -271.011396) (xy 351.092007 -271.037363) (xy 351.371917 -271.037363) (xy 351.371917 -270.985429)
			(xy 351.380042 -270.934134) (xy 351.39609 -270.884741) (xy 351.419668 -270.838467) (xy 351.450194 -270.796451)
			(xy 351.486917 -270.759728) (xy 351.528933 -270.729202) (xy 351.575207 -270.705624) (xy 351.6246 -270.689576)
			(xy 351.675895 -270.681451) (xy 351.727829 -270.681451) (xy 351.779124 -270.689576) (xy 351.828517 -270.705624)
			(xy 351.874791 -270.729202) (xy 351.916807 -270.759728) (xy 351.95353 -270.796451) (xy 351.984056 -270.838467)
			(xy 352.007634 -270.884741) (xy 352.023682 -270.934134) (xy 352.031807 -270.985429) (xy 352.032316 -271.011396)
			(xy 352.031807 -271.037363) (xy 352.311717 -271.037363) (xy 352.311717 -270.985429) (xy 352.319842 -270.934134)
			(xy 352.33589 -270.884741) (xy 352.359468 -270.838467) (xy 352.389994 -270.796451) (xy 352.426717 -270.759728)
			(xy 352.468733 -270.729202) (xy 352.515007 -270.705624) (xy 352.5644 -270.689576) (xy 352.615695 -270.681451)
			(xy 352.667629 -270.681451) (xy 352.718924 -270.689576) (xy 352.768317 -270.705624) (xy 352.814591 -270.729202)
			(xy 352.856607 -270.759728) (xy 352.89333 -270.796451) (xy 352.923856 -270.838467) (xy 352.947434 -270.884741)
			(xy 352.963482 -270.934134) (xy 352.971607 -270.985429) (xy 352.972116 -271.011396) (xy 352.971607 -271.037363)
			(xy 353.251517 -271.037363) (xy 353.251517 -270.985429) (xy 353.259642 -270.934134) (xy 353.27569 -270.884741)
			(xy 353.299268 -270.838467) (xy 353.329794 -270.796451) (xy 353.366517 -270.759728) (xy 353.408533 -270.729202)
			(xy 353.454807 -270.705624) (xy 353.5042 -270.689576) (xy 353.555495 -270.681451) (xy 353.607429 -270.681451)
			(xy 353.658724 -270.689576) (xy 353.708117 -270.705624) (xy 353.754391 -270.729202) (xy 353.796407 -270.759728)
			(xy 353.83313 -270.796451) (xy 353.863656 -270.838467) (xy 353.887234 -270.884741) (xy 353.903282 -270.934134)
			(xy 353.911407 -270.985429) (xy 353.911916 -271.011396) (xy 353.911407 -271.037363) (xy 354.191317 -271.037363)
			(xy 354.191317 -270.985429) (xy 354.199442 -270.934134) (xy 354.21549 -270.884741) (xy 354.239068 -270.838467)
			(xy 354.269594 -270.796451) (xy 354.306317 -270.759728) (xy 354.348333 -270.729202) (xy 354.394607 -270.705624)
			(xy 354.444 -270.689576) (xy 354.495295 -270.681451) (xy 354.547229 -270.681451) (xy 354.598524 -270.689576)
			(xy 354.647917 -270.705624) (xy 354.694191 -270.729202) (xy 354.736207 -270.759728) (xy 354.77293 -270.796451)
			(xy 354.803456 -270.838467) (xy 354.827034 -270.884741) (xy 354.843082 -270.934134) (xy 354.851207 -270.985429)
			(xy 354.851716 -271.011396) (xy 354.851207 -271.037363) (xy 355.131117 -271.037363) (xy 355.131117 -270.985429)
			(xy 355.139242 -270.934134) (xy 355.15529 -270.884741) (xy 355.178868 -270.838467) (xy 355.209394 -270.796451)
			(xy 355.246117 -270.759728) (xy 355.288133 -270.729202) (xy 355.334407 -270.705624) (xy 355.3838 -270.689576)
			(xy 355.435095 -270.681451) (xy 355.487029 -270.681451) (xy 355.538324 -270.689576) (xy 355.587717 -270.705624)
			(xy 355.633991 -270.729202) (xy 355.676007 -270.759728) (xy 355.71273 -270.796451) (xy 355.743256 -270.838467)
			(xy 355.766834 -270.884741) (xy 355.782882 -270.934134) (xy 355.791007 -270.985429) (xy 355.791516 -271.011396)
			(xy 355.791007 -271.037363) (xy 356.070917 -271.037363) (xy 356.070917 -270.985429) (xy 356.079042 -270.934134)
			(xy 356.09509 -270.884741) (xy 356.118668 -270.838467) (xy 356.149194 -270.796451) (xy 356.185917 -270.759728)
			(xy 356.227933 -270.729202) (xy 356.274207 -270.705624) (xy 356.3236 -270.689576) (xy 356.374895 -270.681451)
			(xy 356.426829 -270.681451) (xy 356.478124 -270.689576) (xy 356.527517 -270.705624) (xy 356.573791 -270.729202)
			(xy 356.615807 -270.759728) (xy 356.65253 -270.796451) (xy 356.683056 -270.838467) (xy 356.706634 -270.884741)
			(xy 356.722682 -270.934134) (xy 356.730807 -270.985429) (xy 356.731316 -271.011396) (xy 356.730807 -271.037363)
			(xy 357.010717 -271.037363) (xy 357.010717 -270.985429) (xy 357.018842 -270.934134) (xy 357.03489 -270.884741)
			(xy 357.058468 -270.838467) (xy 357.088994 -270.796451) (xy 357.125717 -270.759728) (xy 357.167733 -270.729202)
			(xy 357.214007 -270.705624) (xy 357.2634 -270.689576) (xy 357.314695 -270.681451) (xy 357.366629 -270.681451)
			(xy 357.417924 -270.689576) (xy 357.467317 -270.705624) (xy 357.513591 -270.729202) (xy 357.555607 -270.759728)
			(xy 357.59233 -270.796451) (xy 357.622856 -270.838467) (xy 357.646434 -270.884741) (xy 357.662482 -270.934134)
			(xy 357.670607 -270.985429) (xy 357.671116 -271.011396) (xy 357.670607 -271.037363) (xy 357.950517 -271.037363)
			(xy 357.950517 -270.985429) (xy 357.958642 -270.934134) (xy 357.97469 -270.884741) (xy 357.998268 -270.838467)
			(xy 358.028794 -270.796451) (xy 358.065517 -270.759728) (xy 358.107533 -270.729202) (xy 358.153807 -270.705624)
			(xy 358.2032 -270.689576) (xy 358.254495 -270.681451) (xy 358.306429 -270.681451) (xy 358.357724 -270.689576)
			(xy 358.407117 -270.705624) (xy 358.453391 -270.729202) (xy 358.495407 -270.759728) (xy 358.53213 -270.796451)
			(xy 358.562656 -270.838467) (xy 358.586234 -270.884741) (xy 358.602282 -270.934134) (xy 358.610407 -270.985429)
			(xy 358.610916 -271.011396) (xy 358.610407 -271.037363) (xy 361.709717 -271.037363) (xy 361.709717 -270.985429)
			(xy 361.717842 -270.934134) (xy 361.73389 -270.884741) (xy 361.757468 -270.838467) (xy 361.787994 -270.796451)
			(xy 361.824717 -270.759728) (xy 361.866733 -270.729202) (xy 361.913007 -270.705624) (xy 361.9624 -270.689576)
			(xy 362.013695 -270.681451) (xy 362.065629 -270.681451) (xy 362.116924 -270.689576) (xy 362.166317 -270.705624)
			(xy 362.212591 -270.729202) (xy 362.254607 -270.759728) (xy 362.29133 -270.796451) (xy 362.321856 -270.838467)
			(xy 362.345434 -270.884741) (xy 362.361482 -270.934134) (xy 362.369607 -270.985429) (xy 362.370116 -271.011396)
			(xy 362.369607 -271.037363) (xy 362.649517 -271.037363) (xy 362.649517 -270.985429) (xy 362.657642 -270.934134)
			(xy 362.67369 -270.884741) (xy 362.697268 -270.838467) (xy 362.727794 -270.796451) (xy 362.764517 -270.759728)
			(xy 362.806533 -270.729202) (xy 362.852807 -270.705624) (xy 362.9022 -270.689576) (xy 362.953495 -270.681451)
			(xy 363.005429 -270.681451) (xy 363.056724 -270.689576) (xy 363.106117 -270.705624) (xy 363.152391 -270.729202)
			(xy 363.194407 -270.759728) (xy 363.23113 -270.796451) (xy 363.261656 -270.838467) (xy 363.285234 -270.884741)
			(xy 363.301282 -270.934134) (xy 363.309407 -270.985429) (xy 363.309916 -271.011396) (xy 363.309407 -271.037363)
			(xy 363.301282 -271.088658) (xy 363.285234 -271.138051) (xy 363.261656 -271.184325) (xy 363.23113 -271.226341)
			(xy 363.194407 -271.263064) (xy 363.152391 -271.29359) (xy 363.106117 -271.317168) (xy 363.056724 -271.333216)
			(xy 363.005429 -271.341341) (xy 362.953495 -271.341341) (xy 362.9022 -271.333216) (xy 362.852807 -271.317168)
			(xy 362.806533 -271.29359) (xy 362.764517 -271.263064) (xy 362.727794 -271.226341) (xy 362.697268 -271.184325)
			(xy 362.67369 -271.138051) (xy 362.657642 -271.088658) (xy 362.649517 -271.037363) (xy 362.369607 -271.037363)
			(xy 362.361482 -271.088658) (xy 362.345434 -271.138051) (xy 362.321856 -271.184325) (xy 362.29133 -271.226341)
			(xy 362.254607 -271.263064) (xy 362.212591 -271.29359) (xy 362.166317 -271.317168) (xy 362.116924 -271.333216)
			(xy 362.065629 -271.341341) (xy 362.013695 -271.341341) (xy 361.9624 -271.333216) (xy 361.913007 -271.317168)
			(xy 361.866733 -271.29359) (xy 361.824717 -271.263064) (xy 361.787994 -271.226341) (xy 361.757468 -271.184325)
			(xy 361.73389 -271.138051) (xy 361.717842 -271.088658) (xy 361.709717 -271.037363) (xy 358.610407 -271.037363)
			(xy 358.602282 -271.088658) (xy 358.586234 -271.138051) (xy 358.562656 -271.184325) (xy 358.53213 -271.226341)
			(xy 358.495407 -271.263064) (xy 358.453391 -271.29359) (xy 358.407117 -271.317168) (xy 358.357724 -271.333216)
			(xy 358.306429 -271.341341) (xy 358.254495 -271.341341) (xy 358.2032 -271.333216) (xy 358.153807 -271.317168)
			(xy 358.107533 -271.29359) (xy 358.065517 -271.263064) (xy 358.028794 -271.226341) (xy 357.998268 -271.184325)
			(xy 357.97469 -271.138051) (xy 357.958642 -271.088658) (xy 357.950517 -271.037363) (xy 357.670607 -271.037363)
			(xy 357.662482 -271.088658) (xy 357.646434 -271.138051) (xy 357.622856 -271.184325) (xy 357.59233 -271.226341)
			(xy 357.555607 -271.263064) (xy 357.513591 -271.29359) (xy 357.467317 -271.317168) (xy 357.417924 -271.333216)
			(xy 357.366629 -271.341341) (xy 357.314695 -271.341341) (xy 357.2634 -271.333216) (xy 357.214007 -271.317168)
			(xy 357.167733 -271.29359) (xy 357.125717 -271.263064) (xy 357.088994 -271.226341) (xy 357.058468 -271.184325)
			(xy 357.03489 -271.138051) (xy 357.018842 -271.088658) (xy 357.010717 -271.037363) (xy 356.730807 -271.037363)
			(xy 356.722682 -271.088658) (xy 356.706634 -271.138051) (xy 356.683056 -271.184325) (xy 356.65253 -271.226341)
			(xy 356.615807 -271.263064) (xy 356.573791 -271.29359) (xy 356.527517 -271.317168) (xy 356.478124 -271.333216)
			(xy 356.426829 -271.341341) (xy 356.374895 -271.341341) (xy 356.3236 -271.333216) (xy 356.274207 -271.317168)
			(xy 356.227933 -271.29359) (xy 356.185917 -271.263064) (xy 356.149194 -271.226341) (xy 356.118668 -271.184325)
			(xy 356.09509 -271.138051) (xy 356.079042 -271.088658) (xy 356.070917 -271.037363) (xy 355.791007 -271.037363)
			(xy 355.782882 -271.088658) (xy 355.766834 -271.138051) (xy 355.743256 -271.184325) (xy 355.71273 -271.226341)
			(xy 355.676007 -271.263064) (xy 355.633991 -271.29359) (xy 355.587717 -271.317168) (xy 355.538324 -271.333216)
			(xy 355.487029 -271.341341) (xy 355.435095 -271.341341) (xy 355.3838 -271.333216) (xy 355.334407 -271.317168)
			(xy 355.288133 -271.29359) (xy 355.246117 -271.263064) (xy 355.209394 -271.226341) (xy 355.178868 -271.184325)
			(xy 355.15529 -271.138051) (xy 355.139242 -271.088658) (xy 355.131117 -271.037363) (xy 354.851207 -271.037363)
			(xy 354.843082 -271.088658) (xy 354.827034 -271.138051) (xy 354.803456 -271.184325) (xy 354.77293 -271.226341)
			(xy 354.736207 -271.263064) (xy 354.694191 -271.29359) (xy 354.647917 -271.317168) (xy 354.598524 -271.333216)
			(xy 354.547229 -271.341341) (xy 354.495295 -271.341341) (xy 354.444 -271.333216) (xy 354.394607 -271.317168)
			(xy 354.348333 -271.29359) (xy 354.306317 -271.263064) (xy 354.269594 -271.226341) (xy 354.239068 -271.184325)
			(xy 354.21549 -271.138051) (xy 354.199442 -271.088658) (xy 354.191317 -271.037363) (xy 353.911407 -271.037363)
			(xy 353.903282 -271.088658) (xy 353.887234 -271.138051) (xy 353.863656 -271.184325) (xy 353.83313 -271.226341)
			(xy 353.796407 -271.263064) (xy 353.754391 -271.29359) (xy 353.708117 -271.317168) (xy 353.658724 -271.333216)
			(xy 353.607429 -271.341341) (xy 353.555495 -271.341341) (xy 353.5042 -271.333216) (xy 353.454807 -271.317168)
			(xy 353.408533 -271.29359) (xy 353.366517 -271.263064) (xy 353.329794 -271.226341) (xy 353.299268 -271.184325)
			(xy 353.27569 -271.138051) (xy 353.259642 -271.088658) (xy 353.251517 -271.037363) (xy 352.971607 -271.037363)
			(xy 352.963482 -271.088658) (xy 352.947434 -271.138051) (xy 352.923856 -271.184325) (xy 352.89333 -271.226341)
			(xy 352.856607 -271.263064) (xy 352.814591 -271.29359) (xy 352.768317 -271.317168) (xy 352.718924 -271.333216)
			(xy 352.667629 -271.341341) (xy 352.615695 -271.341341) (xy 352.5644 -271.333216) (xy 352.515007 -271.317168)
			(xy 352.468733 -271.29359) (xy 352.426717 -271.263064) (xy 352.389994 -271.226341) (xy 352.359468 -271.184325)
			(xy 352.33589 -271.138051) (xy 352.319842 -271.088658) (xy 352.311717 -271.037363) (xy 352.031807 -271.037363)
			(xy 352.023682 -271.088658) (xy 352.007634 -271.138051) (xy 351.984056 -271.184325) (xy 351.95353 -271.226341)
			(xy 351.916807 -271.263064) (xy 351.874791 -271.29359) (xy 351.828517 -271.317168) (xy 351.779124 -271.333216)
			(xy 351.727829 -271.341341) (xy 351.675895 -271.341341) (xy 351.6246 -271.333216) (xy 351.575207 -271.317168)
			(xy 351.528933 -271.29359) (xy 351.486917 -271.263064) (xy 351.450194 -271.226341) (xy 351.419668 -271.184325)
			(xy 351.39609 -271.138051) (xy 351.380042 -271.088658) (xy 351.371917 -271.037363) (xy 351.092007 -271.037363)
			(xy 351.083882 -271.088658) (xy 351.067834 -271.138051) (xy 351.044256 -271.184325) (xy 351.01373 -271.226341)
			(xy 350.977007 -271.263064) (xy 350.934991 -271.29359) (xy 350.888717 -271.317168) (xy 350.839324 -271.333216)
			(xy 350.788029 -271.341341) (xy 350.736095 -271.341341) (xy 350.6848 -271.333216) (xy 350.635407 -271.317168)
			(xy 350.589133 -271.29359) (xy 350.547117 -271.263064) (xy 350.510394 -271.226341) (xy 350.479868 -271.184325)
			(xy 350.45629 -271.138051) (xy 350.440242 -271.088658) (xy 350.432117 -271.037363) (xy 350.152461 -271.037363)
			(xy 350.144336 -271.088658) (xy 350.128288 -271.138051) (xy 350.10471 -271.184325) (xy 350.074184 -271.226341)
			(xy 350.037461 -271.263064) (xy 349.995445 -271.29359) (xy 349.949171 -271.317168) (xy 349.899778 -271.333216)
			(xy 349.848483 -271.341341) (xy 349.796549 -271.341341) (xy 349.745254 -271.333216) (xy 349.695861 -271.317168)
			(xy 349.649587 -271.29359) (xy 349.607571 -271.263064) (xy 349.570848 -271.226341) (xy 349.540322 -271.184325)
			(xy 349.516744 -271.138051) (xy 349.500696 -271.088658) (xy 349.492571 -271.037363) (xy 349.212661 -271.037363)
			(xy 349.204536 -271.088658) (xy 349.188488 -271.138051) (xy 349.16491 -271.184325) (xy 349.134384 -271.226341)
			(xy 349.097661 -271.263064) (xy 349.055645 -271.29359) (xy 349.009371 -271.317168) (xy 348.959978 -271.333216)
			(xy 348.908683 -271.341341) (xy 348.856749 -271.341341) (xy 348.805454 -271.333216) (xy 348.756061 -271.317168)
			(xy 348.709787 -271.29359) (xy 348.667771 -271.263064) (xy 348.631048 -271.226341) (xy 348.600522 -271.184325)
			(xy 348.576944 -271.138051) (xy 348.560896 -271.088658) (xy 348.552771 -271.037363) (xy 348.272607 -271.037363)
			(xy 348.264482 -271.088658) (xy 348.248434 -271.138051) (xy 348.224856 -271.184325) (xy 348.19433 -271.226341)
			(xy 348.157607 -271.263064) (xy 348.115591 -271.29359) (xy 348.069317 -271.317168) (xy 348.019924 -271.333216)
			(xy 347.968629 -271.341341) (xy 347.916695 -271.341341) (xy 347.8654 -271.333216) (xy 347.816007 -271.317168)
			(xy 347.769733 -271.29359) (xy 347.727717 -271.263064) (xy 347.690994 -271.226341) (xy 347.660468 -271.184325)
			(xy 347.63689 -271.138051) (xy 347.620842 -271.088658) (xy 347.612717 -271.037363) (xy 347.332807 -271.037363)
			(xy 347.324682 -271.088658) (xy 347.308634 -271.138051) (xy 347.285056 -271.184325) (xy 347.25453 -271.226341)
			(xy 347.217807 -271.263064) (xy 347.175791 -271.29359) (xy 347.129517 -271.317168) (xy 347.080124 -271.333216)
			(xy 347.028829 -271.341341) (xy 346.976895 -271.341341) (xy 346.9256 -271.333216) (xy 346.876207 -271.317168)
			(xy 346.829933 -271.29359) (xy 346.787917 -271.263064) (xy 346.751194 -271.226341) (xy 346.720668 -271.184325)
			(xy 346.69709 -271.138051) (xy 346.681042 -271.088658) (xy 346.672917 -271.037363) (xy 346.393007 -271.037363)
			(xy 346.384882 -271.088658) (xy 346.368834 -271.138051) (xy 346.345256 -271.184325) (xy 346.31473 -271.226341)
			(xy 346.278007 -271.263064) (xy 346.235991 -271.29359) (xy 346.189717 -271.317168) (xy 346.140324 -271.333216)
			(xy 346.089029 -271.341341) (xy 346.037095 -271.341341) (xy 345.9858 -271.333216) (xy 345.936407 -271.317168)
			(xy 345.890133 -271.29359) (xy 345.848117 -271.263064) (xy 345.811394 -271.226341) (xy 345.780868 -271.184325)
			(xy 345.75729 -271.138051) (xy 345.741242 -271.088658) (xy 345.733117 -271.037363) (xy 345.453207 -271.037363)
			(xy 345.445082 -271.088658) (xy 345.429034 -271.138051) (xy 345.405456 -271.184325) (xy 345.37493 -271.226341)
			(xy 345.338207 -271.263064) (xy 345.296191 -271.29359) (xy 345.249917 -271.317168) (xy 345.200524 -271.333216)
			(xy 345.149229 -271.341341) (xy 345.097295 -271.341341) (xy 345.046 -271.333216) (xy 344.996607 -271.317168)
			(xy 344.950333 -271.29359) (xy 344.908317 -271.263064) (xy 344.871594 -271.226341) (xy 344.841068 -271.184325)
			(xy 344.81749 -271.138051) (xy 344.801442 -271.088658) (xy 344.793317 -271.037363) (xy 344.557604 -271.037363)
			(xy 344.557604 -271.393158) (xy 344.55802 -271.406375) (xy 344.564799 -271.431924) (xy 344.577914 -271.454874)
			(xy 344.596484 -271.473685) (xy 344.619264 -271.487094) (xy 344.644723 -271.494202) (xy 344.657934 -271.494758)
			(xy 344.683677 -271.495588) (xy 344.734449 -271.504245) (xy 344.783263 -271.520674) (xy 344.828937 -271.544476)
			(xy 344.870365 -271.575077) (xy 344.906545 -271.611734) (xy 344.936599 -271.65356) (xy 344.959801 -271.699542)
			(xy 344.975588 -271.748567) (xy 344.983578 -271.799448) (xy 344.983578 -271.850952) (xy 344.983542 -271.851179)
			(xy 345.263217 -271.851179) (xy 345.263217 -271.799245) (xy 345.271342 -271.74795) (xy 345.28739 -271.698557)
			(xy 345.310968 -271.652283) (xy 345.341494 -271.610267) (xy 345.378217 -271.573544) (xy 345.420233 -271.543018)
			(xy 345.466507 -271.51944) (xy 345.5159 -271.503392) (xy 345.567195 -271.495267) (xy 345.619129 -271.495267)
			(xy 345.670424 -271.503392) (xy 345.719817 -271.51944) (xy 345.766091 -271.543018) (xy 345.808107 -271.573544)
			(xy 345.84483 -271.610267) (xy 345.875356 -271.652283) (xy 345.898934 -271.698557) (xy 345.914982 -271.74795)
			(xy 345.923107 -271.799245) (xy 345.923616 -271.825212) (xy 345.923107 -271.851179) (xy 346.203271 -271.851179)
			(xy 346.203271 -271.799245) (xy 346.211396 -271.74795) (xy 346.227444 -271.698557) (xy 346.251022 -271.652283)
			(xy 346.281548 -271.610267) (xy 346.318271 -271.573544) (xy 346.360287 -271.543018) (xy 346.406561 -271.51944)
			(xy 346.455954 -271.503392) (xy 346.507249 -271.495267) (xy 346.559183 -271.495267) (xy 346.610478 -271.503392)
			(xy 346.659871 -271.51944) (xy 346.706145 -271.543018) (xy 346.748161 -271.573544) (xy 346.784884 -271.610267)
			(xy 346.81541 -271.652283) (xy 346.838988 -271.698557) (xy 346.855036 -271.74795) (xy 346.863161 -271.799245)
			(xy 346.86367 -271.825212) (xy 346.863161 -271.851179) (xy 347.143071 -271.851179) (xy 347.143071 -271.799245)
			(xy 347.151196 -271.74795) (xy 347.167244 -271.698557) (xy 347.190822 -271.652283) (xy 347.221348 -271.610267)
			(xy 347.258071 -271.573544) (xy 347.300087 -271.543018) (xy 347.346361 -271.51944) (xy 347.395754 -271.503392)
			(xy 347.447049 -271.495267) (xy 347.498983 -271.495267) (xy 347.550278 -271.503392) (xy 347.599671 -271.51944)
			(xy 347.645945 -271.543018) (xy 347.687961 -271.573544) (xy 347.724684 -271.610267) (xy 347.75521 -271.652283)
			(xy 347.778788 -271.698557) (xy 347.794836 -271.74795) (xy 347.802961 -271.799245) (xy 347.80347 -271.825212)
			(xy 347.802961 -271.851179) (xy 348.082871 -271.851179) (xy 348.082871 -271.799245) (xy 348.090996 -271.74795)
			(xy 348.107044 -271.698557) (xy 348.130622 -271.652283) (xy 348.161148 -271.610267) (xy 348.197871 -271.573544)
			(xy 348.239887 -271.543018) (xy 348.286161 -271.51944) (xy 348.335554 -271.503392) (xy 348.386849 -271.495267)
			(xy 348.438783 -271.495267) (xy 348.490078 -271.503392) (xy 348.539471 -271.51944) (xy 348.585745 -271.543018)
			(xy 348.627761 -271.573544) (xy 348.664484 -271.610267) (xy 348.69501 -271.652283) (xy 348.718588 -271.698557)
			(xy 348.734636 -271.74795) (xy 348.742761 -271.799245) (xy 348.74327 -271.825212) (xy 348.742761 -271.851179)
			(xy 349.022671 -271.851179) (xy 349.022671 -271.799245) (xy 349.030796 -271.74795) (xy 349.046844 -271.698557)
			(xy 349.070422 -271.652283) (xy 349.100948 -271.610267) (xy 349.137671 -271.573544) (xy 349.179687 -271.543018)
			(xy 349.225961 -271.51944) (xy 349.275354 -271.503392) (xy 349.326649 -271.495267) (xy 349.378583 -271.495267)
			(xy 349.429878 -271.503392) (xy 349.479271 -271.51944) (xy 349.525545 -271.543018) (xy 349.567561 -271.573544)
			(xy 349.604284 -271.610267) (xy 349.63481 -271.652283) (xy 349.658388 -271.698557) (xy 349.674436 -271.74795)
			(xy 349.682561 -271.799245) (xy 349.68307 -271.825212) (xy 349.682561 -271.851179) (xy 349.962471 -271.851179)
			(xy 349.962471 -271.799245) (xy 349.970596 -271.74795) (xy 349.986644 -271.698557) (xy 350.010222 -271.652283)
			(xy 350.040748 -271.610267) (xy 350.077471 -271.573544) (xy 350.119487 -271.543018) (xy 350.165761 -271.51944)
			(xy 350.215154 -271.503392) (xy 350.266449 -271.495267) (xy 350.318383 -271.495267) (xy 350.369678 -271.503392)
			(xy 350.419071 -271.51944) (xy 350.465345 -271.543018) (xy 350.507361 -271.573544) (xy 350.544084 -271.610267)
			(xy 350.57461 -271.652283) (xy 350.598188 -271.698557) (xy 350.614236 -271.74795) (xy 350.622361 -271.799245)
			(xy 350.62287 -271.825212) (xy 350.622361 -271.851179) (xy 350.902271 -271.851179) (xy 350.902271 -271.799245)
			(xy 350.910396 -271.74795) (xy 350.926444 -271.698557) (xy 350.950022 -271.652283) (xy 350.980548 -271.610267)
			(xy 351.017271 -271.573544) (xy 351.059287 -271.543018) (xy 351.105561 -271.51944) (xy 351.154954 -271.503392)
			(xy 351.206249 -271.495267) (xy 351.258183 -271.495267) (xy 351.309478 -271.503392) (xy 351.358871 -271.51944)
			(xy 351.405145 -271.543018) (xy 351.447161 -271.573544) (xy 351.483884 -271.610267) (xy 351.51441 -271.652283)
			(xy 351.537988 -271.698557) (xy 351.554036 -271.74795) (xy 351.562161 -271.799245) (xy 351.56267 -271.825212)
			(xy 351.562161 -271.851179) (xy 351.842071 -271.851179) (xy 351.842071 -271.799245) (xy 351.850196 -271.74795)
			(xy 351.866244 -271.698557) (xy 351.889822 -271.652283) (xy 351.920348 -271.610267) (xy 351.957071 -271.573544)
			(xy 351.999087 -271.543018) (xy 352.045361 -271.51944) (xy 352.094754 -271.503392) (xy 352.146049 -271.495267)
			(xy 352.197983 -271.495267) (xy 352.249278 -271.503392) (xy 352.298671 -271.51944) (xy 352.344945 -271.543018)
			(xy 352.386961 -271.573544) (xy 352.423684 -271.610267) (xy 352.45421 -271.652283) (xy 352.477788 -271.698557)
			(xy 352.493836 -271.74795) (xy 352.501961 -271.799245) (xy 352.50247 -271.825212) (xy 352.501961 -271.851179)
			(xy 352.781871 -271.851179) (xy 352.781871 -271.799245) (xy 352.789996 -271.74795) (xy 352.806044 -271.698557)
			(xy 352.829622 -271.652283) (xy 352.860148 -271.610267) (xy 352.896871 -271.573544) (xy 352.938887 -271.543018)
			(xy 352.985161 -271.51944) (xy 353.034554 -271.503392) (xy 353.085849 -271.495267) (xy 353.137783 -271.495267)
			(xy 353.189078 -271.503392) (xy 353.238471 -271.51944) (xy 353.284745 -271.543018) (xy 353.326761 -271.573544)
			(xy 353.363484 -271.610267) (xy 353.39401 -271.652283) (xy 353.417588 -271.698557) (xy 353.433636 -271.74795)
			(xy 353.441761 -271.799245) (xy 353.44227 -271.825212) (xy 353.441761 -271.851179) (xy 353.721671 -271.851179)
			(xy 353.721671 -271.799245) (xy 353.729796 -271.74795) (xy 353.745844 -271.698557) (xy 353.769422 -271.652283)
			(xy 353.799948 -271.610267) (xy 353.836671 -271.573544) (xy 353.878687 -271.543018) (xy 353.924961 -271.51944)
			(xy 353.974354 -271.503392) (xy 354.025649 -271.495267) (xy 354.077583 -271.495267) (xy 354.128878 -271.503392)
			(xy 354.178271 -271.51944) (xy 354.224545 -271.543018) (xy 354.266561 -271.573544) (xy 354.303284 -271.610267)
			(xy 354.33381 -271.652283) (xy 354.357388 -271.698557) (xy 354.373436 -271.74795) (xy 354.381561 -271.799245)
			(xy 354.38207 -271.825212) (xy 354.381561 -271.851179) (xy 354.661471 -271.851179) (xy 354.661471 -271.799245)
			(xy 354.669596 -271.74795) (xy 354.685644 -271.698557) (xy 354.709222 -271.652283) (xy 354.739748 -271.610267)
			(xy 354.776471 -271.573544) (xy 354.818487 -271.543018) (xy 354.864761 -271.51944) (xy 354.914154 -271.503392)
			(xy 354.965449 -271.495267) (xy 355.017383 -271.495267) (xy 355.068678 -271.503392) (xy 355.118071 -271.51944)
			(xy 355.164345 -271.543018) (xy 355.206361 -271.573544) (xy 355.243084 -271.610267) (xy 355.27361 -271.652283)
			(xy 355.297188 -271.698557) (xy 355.313236 -271.74795) (xy 355.321361 -271.799245) (xy 355.32187 -271.825212)
			(xy 355.321361 -271.851179) (xy 355.601271 -271.851179) (xy 355.601271 -271.799245) (xy 355.609396 -271.74795)
			(xy 355.625444 -271.698557) (xy 355.649022 -271.652283) (xy 355.679548 -271.610267) (xy 355.716271 -271.573544)
			(xy 355.758287 -271.543018) (xy 355.804561 -271.51944) (xy 355.853954 -271.503392) (xy 355.905249 -271.495267)
			(xy 355.957183 -271.495267) (xy 356.008478 -271.503392) (xy 356.057871 -271.51944) (xy 356.104145 -271.543018)
			(xy 356.146161 -271.573544) (xy 356.182884 -271.610267) (xy 356.21341 -271.652283) (xy 356.236988 -271.698557)
			(xy 356.253036 -271.74795) (xy 356.261161 -271.799245) (xy 356.26167 -271.825212) (xy 356.261161 -271.851179)
			(xy 356.541071 -271.851179) (xy 356.541071 -271.799245) (xy 356.549196 -271.74795) (xy 356.565244 -271.698557)
			(xy 356.588822 -271.652283) (xy 356.619348 -271.610267) (xy 356.656071 -271.573544) (xy 356.698087 -271.543018)
			(xy 356.744361 -271.51944) (xy 356.793754 -271.503392) (xy 356.845049 -271.495267) (xy 356.896983 -271.495267)
			(xy 356.948278 -271.503392) (xy 356.997671 -271.51944) (xy 357.043945 -271.543018) (xy 357.085961 -271.573544)
			(xy 357.122684 -271.610267) (xy 357.15321 -271.652283) (xy 357.176788 -271.698557) (xy 357.192836 -271.74795)
			(xy 357.200961 -271.799245) (xy 357.20147 -271.825212) (xy 357.200961 -271.851179) (xy 357.480363 -271.851179)
			(xy 357.480363 -271.799245) (xy 357.488488 -271.74795) (xy 357.504536 -271.698557) (xy 357.528114 -271.652283)
			(xy 357.55864 -271.610267) (xy 357.595363 -271.573544) (xy 357.637379 -271.543018) (xy 357.683653 -271.51944)
			(xy 357.733046 -271.503392) (xy 357.784341 -271.495267) (xy 357.836275 -271.495267) (xy 357.88757 -271.503392)
			(xy 357.936963 -271.51944) (xy 357.983237 -271.543018) (xy 358.025253 -271.573544) (xy 358.061976 -271.610267)
			(xy 358.092502 -271.652283) (xy 358.11608 -271.698557) (xy 358.132128 -271.74795) (xy 358.140253 -271.799245)
			(xy 358.140762 -271.825212) (xy 358.140253 -271.851179) (xy 361.239817 -271.851179) (xy 361.239817 -271.799245)
			(xy 361.247942 -271.74795) (xy 361.26399 -271.698557) (xy 361.287568 -271.652283) (xy 361.318094 -271.610267)
			(xy 361.354817 -271.573544) (xy 361.396833 -271.543018) (xy 361.443107 -271.51944) (xy 361.4925 -271.503392)
			(xy 361.543795 -271.495267) (xy 361.595729 -271.495267) (xy 361.647024 -271.503392) (xy 361.696417 -271.51944)
			(xy 361.742691 -271.543018) (xy 361.784707 -271.573544) (xy 361.82143 -271.610267) (xy 361.851956 -271.652283)
			(xy 361.875534 -271.698557) (xy 361.891582 -271.74795) (xy 361.899707 -271.799245) (xy 361.900216 -271.825212)
			(xy 361.899707 -271.851179) (xy 362.179871 -271.851179) (xy 362.179871 -271.799245) (xy 362.187996 -271.74795)
			(xy 362.204044 -271.698557) (xy 362.227622 -271.652283) (xy 362.258148 -271.610267) (xy 362.294871 -271.573544)
			(xy 362.336887 -271.543018) (xy 362.383161 -271.51944) (xy 362.432554 -271.503392) (xy 362.483849 -271.495267)
			(xy 362.535783 -271.495267) (xy 362.587078 -271.503392) (xy 362.636471 -271.51944) (xy 362.682745 -271.543018)
			(xy 362.724761 -271.573544) (xy 362.761484 -271.610267) (xy 362.79201 -271.652283) (xy 362.815588 -271.698557)
			(xy 362.831636 -271.74795) (xy 362.839761 -271.799245) (xy 362.84027 -271.825212) (xy 362.839761 -271.851179)
			(xy 363.119671 -271.851179) (xy 363.119671 -271.799245) (xy 363.127796 -271.74795) (xy 363.143844 -271.698557)
			(xy 363.167422 -271.652283) (xy 363.197948 -271.610267) (xy 363.234671 -271.573544) (xy 363.276687 -271.543018)
			(xy 363.322961 -271.51944) (xy 363.372354 -271.503392) (xy 363.423649 -271.495267) (xy 363.475583 -271.495267)
			(xy 363.526878 -271.503392) (xy 363.576271 -271.51944) (xy 363.622545 -271.543018) (xy 363.664561 -271.573544)
			(xy 363.701284 -271.610267) (xy 363.73181 -271.652283) (xy 363.755388 -271.698557) (xy 363.771436 -271.74795)
			(xy 363.779561 -271.799245) (xy 363.78007 -271.825212) (xy 363.779561 -271.851179) (xy 363.771436 -271.902474)
			(xy 363.755388 -271.951867) (xy 363.73181 -271.998141) (xy 363.701284 -272.040157) (xy 363.664561 -272.07688)
			(xy 363.622545 -272.107406) (xy 363.576271 -272.130984) (xy 363.526878 -272.147032) (xy 363.475583 -272.155157)
			(xy 363.423649 -272.155157) (xy 363.372354 -272.147032) (xy 363.322961 -272.130984) (xy 363.276687 -272.107406)
			(xy 363.234671 -272.07688) (xy 363.197948 -272.040157) (xy 363.167422 -271.998141) (xy 363.143844 -271.951867)
			(xy 363.127796 -271.902474) (xy 363.119671 -271.851179) (xy 362.839761 -271.851179) (xy 362.831636 -271.902474)
			(xy 362.815588 -271.951867) (xy 362.79201 -271.998141) (xy 362.761484 -272.040157) (xy 362.724761 -272.07688)
			(xy 362.682745 -272.107406) (xy 362.636471 -272.130984) (xy 362.587078 -272.147032) (xy 362.535783 -272.155157)
			(xy 362.483849 -272.155157) (xy 362.432554 -272.147032) (xy 362.383161 -272.130984) (xy 362.336887 -272.107406)
			(xy 362.294871 -272.07688) (xy 362.258148 -272.040157) (xy 362.227622 -271.998141) (xy 362.204044 -271.951867)
			(xy 362.187996 -271.902474) (xy 362.179871 -271.851179) (xy 361.899707 -271.851179) (xy 361.891582 -271.902474)
			(xy 361.875534 -271.951867) (xy 361.851956 -271.998141) (xy 361.82143 -272.040157) (xy 361.784707 -272.07688)
			(xy 361.742691 -272.107406) (xy 361.696417 -272.130984) (xy 361.647024 -272.147032) (xy 361.595729 -272.155157)
			(xy 361.543795 -272.155157) (xy 361.4925 -272.147032) (xy 361.443107 -272.130984) (xy 361.396833 -272.107406)
			(xy 361.354817 -272.07688) (xy 361.318094 -272.040157) (xy 361.287568 -271.998141) (xy 361.26399 -271.951867)
			(xy 361.247942 -271.902474) (xy 361.239817 -271.851179) (xy 358.140253 -271.851179) (xy 358.132128 -271.902474)
			(xy 358.11608 -271.951867) (xy 358.092502 -271.998141) (xy 358.061976 -272.040157) (xy 358.025253 -272.07688)
			(xy 357.983237 -272.107406) (xy 357.936963 -272.130984) (xy 357.88757 -272.147032) (xy 357.836275 -272.155157)
			(xy 357.784341 -272.155157) (xy 357.733046 -272.147032) (xy 357.683653 -272.130984) (xy 357.637379 -272.107406)
			(xy 357.595363 -272.07688) (xy 357.55864 -272.040157) (xy 357.528114 -271.998141) (xy 357.504536 -271.951867)
			(xy 357.488488 -271.902474) (xy 357.480363 -271.851179) (xy 357.200961 -271.851179) (xy 357.192836 -271.902474)
			(xy 357.176788 -271.951867) (xy 357.15321 -271.998141) (xy 357.122684 -272.040157) (xy 357.085961 -272.07688)
			(xy 357.043945 -272.107406) (xy 356.997671 -272.130984) (xy 356.948278 -272.147032) (xy 356.896983 -272.155157)
			(xy 356.845049 -272.155157) (xy 356.793754 -272.147032) (xy 356.744361 -272.130984) (xy 356.698087 -272.107406)
			(xy 356.656071 -272.07688) (xy 356.619348 -272.040157) (xy 356.588822 -271.998141) (xy 356.565244 -271.951867)
			(xy 356.549196 -271.902474) (xy 356.541071 -271.851179) (xy 356.261161 -271.851179) (xy 356.253036 -271.902474)
			(xy 356.236988 -271.951867) (xy 356.21341 -271.998141) (xy 356.182884 -272.040157) (xy 356.146161 -272.07688)
			(xy 356.104145 -272.107406) (xy 356.057871 -272.130984) (xy 356.008478 -272.147032) (xy 355.957183 -272.155157)
			(xy 355.905249 -272.155157) (xy 355.853954 -272.147032) (xy 355.804561 -272.130984) (xy 355.758287 -272.107406)
			(xy 355.716271 -272.07688) (xy 355.679548 -272.040157) (xy 355.649022 -271.998141) (xy 355.625444 -271.951867)
			(xy 355.609396 -271.902474) (xy 355.601271 -271.851179) (xy 355.321361 -271.851179) (xy 355.313236 -271.902474)
			(xy 355.297188 -271.951867) (xy 355.27361 -271.998141) (xy 355.243084 -272.040157) (xy 355.206361 -272.07688)
			(xy 355.164345 -272.107406) (xy 355.118071 -272.130984) (xy 355.068678 -272.147032) (xy 355.017383 -272.155157)
			(xy 354.965449 -272.155157) (xy 354.914154 -272.147032) (xy 354.864761 -272.130984) (xy 354.818487 -272.107406)
			(xy 354.776471 -272.07688) (xy 354.739748 -272.040157) (xy 354.709222 -271.998141) (xy 354.685644 -271.951867)
			(xy 354.669596 -271.902474) (xy 354.661471 -271.851179) (xy 354.381561 -271.851179) (xy 354.373436 -271.902474)
			(xy 354.357388 -271.951867) (xy 354.33381 -271.998141) (xy 354.303284 -272.040157) (xy 354.266561 -272.07688)
			(xy 354.224545 -272.107406) (xy 354.178271 -272.130984) (xy 354.128878 -272.147032) (xy 354.077583 -272.155157)
			(xy 354.025649 -272.155157) (xy 353.974354 -272.147032) (xy 353.924961 -272.130984) (xy 353.878687 -272.107406)
			(xy 353.836671 -272.07688) (xy 353.799948 -272.040157) (xy 353.769422 -271.998141) (xy 353.745844 -271.951867)
			(xy 353.729796 -271.902474) (xy 353.721671 -271.851179) (xy 353.441761 -271.851179) (xy 353.433636 -271.902474)
			(xy 353.417588 -271.951867) (xy 353.39401 -271.998141) (xy 353.363484 -272.040157) (xy 353.326761 -272.07688)
			(xy 353.284745 -272.107406) (xy 353.238471 -272.130984) (xy 353.189078 -272.147032) (xy 353.137783 -272.155157)
			(xy 353.085849 -272.155157) (xy 353.034554 -272.147032) (xy 352.985161 -272.130984) (xy 352.938887 -272.107406)
			(xy 352.896871 -272.07688) (xy 352.860148 -272.040157) (xy 352.829622 -271.998141) (xy 352.806044 -271.951867)
			(xy 352.789996 -271.902474) (xy 352.781871 -271.851179) (xy 352.501961 -271.851179) (xy 352.493836 -271.902474)
			(xy 352.477788 -271.951867) (xy 352.45421 -271.998141) (xy 352.423684 -272.040157) (xy 352.386961 -272.07688)
			(xy 352.344945 -272.107406) (xy 352.298671 -272.130984) (xy 352.249278 -272.147032) (xy 352.197983 -272.155157)
			(xy 352.146049 -272.155157) (xy 352.094754 -272.147032) (xy 352.045361 -272.130984) (xy 351.999087 -272.107406)
			(xy 351.957071 -272.07688) (xy 351.920348 -272.040157) (xy 351.889822 -271.998141) (xy 351.866244 -271.951867)
			(xy 351.850196 -271.902474) (xy 351.842071 -271.851179) (xy 351.562161 -271.851179) (xy 351.554036 -271.902474)
			(xy 351.537988 -271.951867) (xy 351.51441 -271.998141) (xy 351.483884 -272.040157) (xy 351.447161 -272.07688)
			(xy 351.405145 -272.107406) (xy 351.358871 -272.130984) (xy 351.309478 -272.147032) (xy 351.258183 -272.155157)
			(xy 351.206249 -272.155157) (xy 351.154954 -272.147032) (xy 351.105561 -272.130984) (xy 351.059287 -272.107406)
			(xy 351.017271 -272.07688) (xy 350.980548 -272.040157) (xy 350.950022 -271.998141) (xy 350.926444 -271.951867)
			(xy 350.910396 -271.902474) (xy 350.902271 -271.851179) (xy 350.622361 -271.851179) (xy 350.614236 -271.902474)
			(xy 350.598188 -271.951867) (xy 350.57461 -271.998141) (xy 350.544084 -272.040157) (xy 350.507361 -272.07688)
			(xy 350.465345 -272.107406) (xy 350.419071 -272.130984) (xy 350.369678 -272.147032) (xy 350.318383 -272.155157)
			(xy 350.266449 -272.155157) (xy 350.215154 -272.147032) (xy 350.165761 -272.130984) (xy 350.119487 -272.107406)
			(xy 350.077471 -272.07688) (xy 350.040748 -272.040157) (xy 350.010222 -271.998141) (xy 349.986644 -271.951867)
			(xy 349.970596 -271.902474) (xy 349.962471 -271.851179) (xy 349.682561 -271.851179) (xy 349.674436 -271.902474)
			(xy 349.658388 -271.951867) (xy 349.63481 -271.998141) (xy 349.604284 -272.040157) (xy 349.567561 -272.07688)
			(xy 349.525545 -272.107406) (xy 349.479271 -272.130984) (xy 349.429878 -272.147032) (xy 349.378583 -272.155157)
			(xy 349.326649 -272.155157) (xy 349.275354 -272.147032) (xy 349.225961 -272.130984) (xy 349.179687 -272.107406)
			(xy 349.137671 -272.07688) (xy 349.100948 -272.040157) (xy 349.070422 -271.998141) (xy 349.046844 -271.951867)
			(xy 349.030796 -271.902474) (xy 349.022671 -271.851179) (xy 348.742761 -271.851179) (xy 348.734636 -271.902474)
			(xy 348.718588 -271.951867) (xy 348.69501 -271.998141) (xy 348.664484 -272.040157) (xy 348.627761 -272.07688)
			(xy 348.585745 -272.107406) (xy 348.539471 -272.130984) (xy 348.490078 -272.147032) (xy 348.438783 -272.155157)
			(xy 348.386849 -272.155157) (xy 348.335554 -272.147032) (xy 348.286161 -272.130984) (xy 348.239887 -272.107406)
			(xy 348.197871 -272.07688) (xy 348.161148 -272.040157) (xy 348.130622 -271.998141) (xy 348.107044 -271.951867)
			(xy 348.090996 -271.902474) (xy 348.082871 -271.851179) (xy 347.802961 -271.851179) (xy 347.794836 -271.902474)
			(xy 347.778788 -271.951867) (xy 347.75521 -271.998141) (xy 347.724684 -272.040157) (xy 347.687961 -272.07688)
			(xy 347.645945 -272.107406) (xy 347.599671 -272.130984) (xy 347.550278 -272.147032) (xy 347.498983 -272.155157)
			(xy 347.447049 -272.155157) (xy 347.395754 -272.147032) (xy 347.346361 -272.130984) (xy 347.300087 -272.107406)
			(xy 347.258071 -272.07688) (xy 347.221348 -272.040157) (xy 347.190822 -271.998141) (xy 347.167244 -271.951867)
			(xy 347.151196 -271.902474) (xy 347.143071 -271.851179) (xy 346.863161 -271.851179) (xy 346.855036 -271.902474)
			(xy 346.838988 -271.951867) (xy 346.81541 -271.998141) (xy 346.784884 -272.040157) (xy 346.748161 -272.07688)
			(xy 346.706145 -272.107406) (xy 346.659871 -272.130984) (xy 346.610478 -272.147032) (xy 346.559183 -272.155157)
			(xy 346.507249 -272.155157) (xy 346.455954 -272.147032) (xy 346.406561 -272.130984) (xy 346.360287 -272.107406)
			(xy 346.318271 -272.07688) (xy 346.281548 -272.040157) (xy 346.251022 -271.998141) (xy 346.227444 -271.951867)
			(xy 346.211396 -271.902474) (xy 346.203271 -271.851179) (xy 345.923107 -271.851179) (xy 345.914982 -271.902474)
			(xy 345.898934 -271.951867) (xy 345.875356 -271.998141) (xy 345.84483 -272.040157) (xy 345.808107 -272.07688)
			(xy 345.766091 -272.107406) (xy 345.719817 -272.130984) (xy 345.670424 -272.147032) (xy 345.619129 -272.155157)
			(xy 345.567195 -272.155157) (xy 345.5159 -272.147032) (xy 345.466507 -272.130984) (xy 345.420233 -272.107406)
			(xy 345.378217 -272.07688) (xy 345.341494 -272.040157) (xy 345.310968 -271.998141) (xy 345.28739 -271.951867)
			(xy 345.271342 -271.902474) (xy 345.263217 -271.851179) (xy 344.983542 -271.851179) (xy 344.975588 -271.901833)
			(xy 344.959801 -271.950858) (xy 344.936599 -271.99684) (xy 344.906544 -272.038666) (xy 344.870365 -272.075323)
			(xy 344.828937 -272.105924) (xy 344.783262 -272.129726) (xy 344.734449 -272.146155) (xy 344.683677 -272.154812)
			(xy 344.657934 -272.155666) (xy 344.644724 -272.156251) (xy 344.619264 -272.163356) (xy 344.596482 -272.176759)
			(xy 344.577905 -272.195563) (xy 344.564779 -272.218506) (xy 344.557983 -272.24405) (xy 344.557604 -272.257266)
			(xy 344.557604 -272.665249) (xy 344.793571 -272.665249) (xy 344.793571 -272.613315) (xy 344.801696 -272.56202)
			(xy 344.817744 -272.512627) (xy 344.841322 -272.466353) (xy 344.871848 -272.424337) (xy 344.908571 -272.387614)
			(xy 344.950587 -272.357088) (xy 344.996861 -272.33351) (xy 345.046254 -272.317462) (xy 345.097549 -272.309337)
			(xy 345.149483 -272.309337) (xy 345.200778 -272.317462) (xy 345.250171 -272.33351) (xy 345.296445 -272.357088)
			(xy 345.338461 -272.387614) (xy 345.375184 -272.424337) (xy 345.40571 -272.466353) (xy 345.429288 -272.512627)
			(xy 345.445336 -272.56202) (xy 345.453461 -272.613315) (xy 345.45397 -272.639282) (xy 345.453461 -272.665249)
			(xy 345.733117 -272.665249) (xy 345.733117 -272.613315) (xy 345.741242 -272.56202) (xy 345.75729 -272.512627)
			(xy 345.780868 -272.466353) (xy 345.811394 -272.424337) (xy 345.848117 -272.387614) (xy 345.890133 -272.357088)
			(xy 345.936407 -272.33351) (xy 345.9858 -272.317462) (xy 346.037095 -272.309337) (xy 346.089029 -272.309337)
			(xy 346.140324 -272.317462) (xy 346.189717 -272.33351) (xy 346.235991 -272.357088) (xy 346.278007 -272.387614)
			(xy 346.31473 -272.424337) (xy 346.345256 -272.466353) (xy 346.368834 -272.512627) (xy 346.384882 -272.56202)
			(xy 346.393007 -272.613315) (xy 346.393516 -272.639282) (xy 346.393007 -272.665249) (xy 346.672917 -272.665249)
			(xy 346.672917 -272.613315) (xy 346.681042 -272.56202) (xy 346.69709 -272.512627) (xy 346.720668 -272.466353)
			(xy 346.751194 -272.424337) (xy 346.787917 -272.387614) (xy 346.829933 -272.357088) (xy 346.876207 -272.33351)
			(xy 346.9256 -272.317462) (xy 346.976895 -272.309337) (xy 347.028829 -272.309337) (xy 347.080124 -272.317462)
			(xy 347.129517 -272.33351) (xy 347.175791 -272.357088) (xy 347.217807 -272.387614) (xy 347.25453 -272.424337)
			(xy 347.285056 -272.466353) (xy 347.308634 -272.512627) (xy 347.324682 -272.56202) (xy 347.332807 -272.613315)
			(xy 347.333316 -272.639282) (xy 347.332807 -272.665249) (xy 347.612717 -272.665249) (xy 347.612717 -272.613315)
			(xy 347.620842 -272.56202) (xy 347.63689 -272.512627) (xy 347.660468 -272.466353) (xy 347.690994 -272.424337)
			(xy 347.727717 -272.387614) (xy 347.769733 -272.357088) (xy 347.816007 -272.33351) (xy 347.8654 -272.317462)
			(xy 347.916695 -272.309337) (xy 347.968629 -272.309337) (xy 348.019924 -272.317462) (xy 348.069317 -272.33351)
			(xy 348.115591 -272.357088) (xy 348.157607 -272.387614) (xy 348.19433 -272.424337) (xy 348.224856 -272.466353)
			(xy 348.248434 -272.512627) (xy 348.264482 -272.56202) (xy 348.272607 -272.613315) (xy 348.273116 -272.639282)
			(xy 348.272607 -272.665249) (xy 348.552517 -272.665249) (xy 348.552517 -272.613315) (xy 348.560642 -272.56202)
			(xy 348.57669 -272.512627) (xy 348.600268 -272.466353) (xy 348.630794 -272.424337) (xy 348.667517 -272.387614)
			(xy 348.709533 -272.357088) (xy 348.755807 -272.33351) (xy 348.8052 -272.317462) (xy 348.856495 -272.309337)
			(xy 348.908429 -272.309337) (xy 348.959724 -272.317462) (xy 349.009117 -272.33351) (xy 349.055391 -272.357088)
			(xy 349.097407 -272.387614) (xy 349.13413 -272.424337) (xy 349.164656 -272.466353) (xy 349.188234 -272.512627)
			(xy 349.204282 -272.56202) (xy 349.212407 -272.613315) (xy 349.212916 -272.639282) (xy 349.212407 -272.665249)
			(xy 349.492317 -272.665249) (xy 349.492317 -272.613315) (xy 349.500442 -272.56202) (xy 349.51649 -272.512627)
			(xy 349.540068 -272.466353) (xy 349.570594 -272.424337) (xy 349.607317 -272.387614) (xy 349.649333 -272.357088)
			(xy 349.695607 -272.33351) (xy 349.745 -272.317462) (xy 349.796295 -272.309337) (xy 349.848229 -272.309337)
			(xy 349.899524 -272.317462) (xy 349.948917 -272.33351) (xy 349.995191 -272.357088) (xy 350.037207 -272.387614)
			(xy 350.07393 -272.424337) (xy 350.104456 -272.466353) (xy 350.128034 -272.512627) (xy 350.144082 -272.56202)
			(xy 350.152207 -272.613315) (xy 350.152716 -272.639282) (xy 350.152207 -272.665249) (xy 350.432117 -272.665249)
			(xy 350.432117 -272.613315) (xy 350.440242 -272.56202) (xy 350.45629 -272.512627) (xy 350.479868 -272.466353)
			(xy 350.510394 -272.424337) (xy 350.547117 -272.387614) (xy 350.589133 -272.357088) (xy 350.635407 -272.33351)
			(xy 350.6848 -272.317462) (xy 350.736095 -272.309337) (xy 350.788029 -272.309337) (xy 350.839324 -272.317462)
			(xy 350.888717 -272.33351) (xy 350.934991 -272.357088) (xy 350.977007 -272.387614) (xy 351.01373 -272.424337)
			(xy 351.044256 -272.466353) (xy 351.067834 -272.512627) (xy 351.083882 -272.56202) (xy 351.092007 -272.613315)
			(xy 351.092516 -272.639282) (xy 351.092007 -272.665249) (xy 351.371917 -272.665249) (xy 351.371917 -272.613315)
			(xy 351.380042 -272.56202) (xy 351.39609 -272.512627) (xy 351.419668 -272.466353) (xy 351.450194 -272.424337)
			(xy 351.486917 -272.387614) (xy 351.528933 -272.357088) (xy 351.575207 -272.33351) (xy 351.6246 -272.317462)
			(xy 351.675895 -272.309337) (xy 351.727829 -272.309337) (xy 351.779124 -272.317462) (xy 351.828517 -272.33351)
			(xy 351.874791 -272.357088) (xy 351.916807 -272.387614) (xy 351.95353 -272.424337) (xy 351.984056 -272.466353)
			(xy 352.007634 -272.512627) (xy 352.023682 -272.56202) (xy 352.031807 -272.613315) (xy 352.032316 -272.639282)
			(xy 352.031807 -272.665249) (xy 352.311717 -272.665249) (xy 352.311717 -272.613315) (xy 352.319842 -272.56202)
			(xy 352.33589 -272.512627) (xy 352.359468 -272.466353) (xy 352.389994 -272.424337) (xy 352.426717 -272.387614)
			(xy 352.468733 -272.357088) (xy 352.515007 -272.33351) (xy 352.5644 -272.317462) (xy 352.615695 -272.309337)
			(xy 352.667629 -272.309337) (xy 352.718924 -272.317462) (xy 352.768317 -272.33351) (xy 352.814591 -272.357088)
			(xy 352.856607 -272.387614) (xy 352.89333 -272.424337) (xy 352.923856 -272.466353) (xy 352.947434 -272.512627)
			(xy 352.963482 -272.56202) (xy 352.971607 -272.613315) (xy 352.972116 -272.639282) (xy 352.971607 -272.665249)
			(xy 353.251517 -272.665249) (xy 353.251517 -272.613315) (xy 353.259642 -272.56202) (xy 353.27569 -272.512627)
			(xy 353.299268 -272.466353) (xy 353.329794 -272.424337) (xy 353.366517 -272.387614) (xy 353.408533 -272.357088)
			(xy 353.454807 -272.33351) (xy 353.5042 -272.317462) (xy 353.555495 -272.309337) (xy 353.607429 -272.309337)
			(xy 353.658724 -272.317462) (xy 353.708117 -272.33351) (xy 353.754391 -272.357088) (xy 353.796407 -272.387614)
			(xy 353.83313 -272.424337) (xy 353.863656 -272.466353) (xy 353.887234 -272.512627) (xy 353.903282 -272.56202)
			(xy 353.911407 -272.613315) (xy 353.911916 -272.639282) (xy 353.911407 -272.665249) (xy 354.191317 -272.665249)
			(xy 354.191317 -272.613315) (xy 354.199442 -272.56202) (xy 354.21549 -272.512627) (xy 354.239068 -272.466353)
			(xy 354.269594 -272.424337) (xy 354.306317 -272.387614) (xy 354.348333 -272.357088) (xy 354.394607 -272.33351)
			(xy 354.444 -272.317462) (xy 354.495295 -272.309337) (xy 354.547229 -272.309337) (xy 354.598524 -272.317462)
			(xy 354.647917 -272.33351) (xy 354.694191 -272.357088) (xy 354.736207 -272.387614) (xy 354.77293 -272.424337)
			(xy 354.803456 -272.466353) (xy 354.827034 -272.512627) (xy 354.843082 -272.56202) (xy 354.851207 -272.613315)
			(xy 354.851716 -272.639282) (xy 354.851207 -272.665249) (xy 355.131117 -272.665249) (xy 355.131117 -272.613315)
			(xy 355.139242 -272.56202) (xy 355.15529 -272.512627) (xy 355.178868 -272.466353) (xy 355.209394 -272.424337)
			(xy 355.246117 -272.387614) (xy 355.288133 -272.357088) (xy 355.334407 -272.33351) (xy 355.3838 -272.317462)
			(xy 355.435095 -272.309337) (xy 355.487029 -272.309337) (xy 355.538324 -272.317462) (xy 355.587717 -272.33351)
			(xy 355.633991 -272.357088) (xy 355.676007 -272.387614) (xy 355.71273 -272.424337) (xy 355.743256 -272.466353)
			(xy 355.766834 -272.512627) (xy 355.782882 -272.56202) (xy 355.791007 -272.613315) (xy 355.791516 -272.639282)
			(xy 355.791007 -272.665249) (xy 356.070917 -272.665249) (xy 356.070917 -272.613315) (xy 356.079042 -272.56202)
			(xy 356.09509 -272.512627) (xy 356.118668 -272.466353) (xy 356.149194 -272.424337) (xy 356.185917 -272.387614)
			(xy 356.227933 -272.357088) (xy 356.274207 -272.33351) (xy 356.3236 -272.317462) (xy 356.374895 -272.309337)
			(xy 356.426829 -272.309337) (xy 356.478124 -272.317462) (xy 356.527517 -272.33351) (xy 356.573791 -272.357088)
			(xy 356.615807 -272.387614) (xy 356.65253 -272.424337) (xy 356.683056 -272.466353) (xy 356.706634 -272.512627)
			(xy 356.722682 -272.56202) (xy 356.730807 -272.613315) (xy 356.731316 -272.639282) (xy 356.730807 -272.665249)
			(xy 357.010717 -272.665249) (xy 357.010717 -272.613315) (xy 357.018842 -272.56202) (xy 357.03489 -272.512627)
			(xy 357.058468 -272.466353) (xy 357.088994 -272.424337) (xy 357.125717 -272.387614) (xy 357.167733 -272.357088)
			(xy 357.214007 -272.33351) (xy 357.2634 -272.317462) (xy 357.314695 -272.309337) (xy 357.366629 -272.309337)
			(xy 357.417924 -272.317462) (xy 357.467317 -272.33351) (xy 357.513591 -272.357088) (xy 357.555607 -272.387614)
			(xy 357.59233 -272.424337) (xy 357.622856 -272.466353) (xy 357.646434 -272.512627) (xy 357.662482 -272.56202)
			(xy 357.670607 -272.613315) (xy 357.671116 -272.639282) (xy 357.670607 -272.665249) (xy 357.950517 -272.665249)
			(xy 357.950517 -272.613315) (xy 357.958642 -272.56202) (xy 357.97469 -272.512627) (xy 357.998268 -272.466353)
			(xy 358.028794 -272.424337) (xy 358.065517 -272.387614) (xy 358.107533 -272.357088) (xy 358.153807 -272.33351)
			(xy 358.2032 -272.317462) (xy 358.254495 -272.309337) (xy 358.306429 -272.309337) (xy 358.357724 -272.317462)
			(xy 358.407117 -272.33351) (xy 358.453391 -272.357088) (xy 358.495407 -272.387614) (xy 358.53213 -272.424337)
			(xy 358.562656 -272.466353) (xy 358.586234 -272.512627) (xy 358.602282 -272.56202) (xy 358.610407 -272.613315)
			(xy 358.610916 -272.639282) (xy 358.610407 -272.665249) (xy 361.709717 -272.665249) (xy 361.709717 -272.613315)
			(xy 361.717842 -272.56202) (xy 361.73389 -272.512627) (xy 361.757468 -272.466353) (xy 361.787994 -272.424337)
			(xy 361.824717 -272.387614) (xy 361.866733 -272.357088) (xy 361.913007 -272.33351) (xy 361.9624 -272.317462)
			(xy 362.013695 -272.309337) (xy 362.065629 -272.309337) (xy 362.116924 -272.317462) (xy 362.166317 -272.33351)
			(xy 362.212591 -272.357088) (xy 362.254607 -272.387614) (xy 362.29133 -272.424337) (xy 362.321856 -272.466353)
			(xy 362.345434 -272.512627) (xy 362.361482 -272.56202) (xy 362.369607 -272.613315) (xy 362.370116 -272.639282)
			(xy 362.369607 -272.665249) (xy 362.649517 -272.665249) (xy 362.649517 -272.613315) (xy 362.657642 -272.56202)
			(xy 362.67369 -272.512627) (xy 362.697268 -272.466353) (xy 362.727794 -272.424337) (xy 362.764517 -272.387614)
			(xy 362.806533 -272.357088) (xy 362.852807 -272.33351) (xy 362.9022 -272.317462) (xy 362.953495 -272.309337)
			(xy 363.005429 -272.309337) (xy 363.056724 -272.317462) (xy 363.106117 -272.33351) (xy 363.152391 -272.357088)
			(xy 363.194407 -272.387614) (xy 363.23113 -272.424337) (xy 363.261656 -272.466353) (xy 363.285234 -272.512627)
			(xy 363.301282 -272.56202) (xy 363.309407 -272.613315) (xy 363.309916 -272.639282) (xy 363.309407 -272.665249)
			(xy 363.301282 -272.716544) (xy 363.285234 -272.765937) (xy 363.261656 -272.812211) (xy 363.23113 -272.854227)
			(xy 363.194407 -272.89095) (xy 363.152391 -272.921476) (xy 363.106117 -272.945054) (xy 363.056724 -272.961102)
			(xy 363.005429 -272.969227) (xy 362.953495 -272.969227) (xy 362.9022 -272.961102) (xy 362.852807 -272.945054)
			(xy 362.806533 -272.921476) (xy 362.764517 -272.89095) (xy 362.727794 -272.854227) (xy 362.697268 -272.812211)
			(xy 362.67369 -272.765937) (xy 362.657642 -272.716544) (xy 362.649517 -272.665249) (xy 362.369607 -272.665249)
			(xy 362.361482 -272.716544) (xy 362.345434 -272.765937) (xy 362.321856 -272.812211) (xy 362.29133 -272.854227)
			(xy 362.254607 -272.89095) (xy 362.212591 -272.921476) (xy 362.166317 -272.945054) (xy 362.116924 -272.961102)
			(xy 362.065629 -272.969227) (xy 362.013695 -272.969227) (xy 361.9624 -272.961102) (xy 361.913007 -272.945054)
			(xy 361.866733 -272.921476) (xy 361.824717 -272.89095) (xy 361.787994 -272.854227) (xy 361.757468 -272.812211)
			(xy 361.73389 -272.765937) (xy 361.717842 -272.716544) (xy 361.709717 -272.665249) (xy 358.610407 -272.665249)
			(xy 358.602282 -272.716544) (xy 358.586234 -272.765937) (xy 358.562656 -272.812211) (xy 358.53213 -272.854227)
			(xy 358.495407 -272.89095) (xy 358.453391 -272.921476) (xy 358.407117 -272.945054) (xy 358.357724 -272.961102)
			(xy 358.306429 -272.969227) (xy 358.254495 -272.969227) (xy 358.2032 -272.961102) (xy 358.153807 -272.945054)
			(xy 358.107533 -272.921476) (xy 358.065517 -272.89095) (xy 358.028794 -272.854227) (xy 357.998268 -272.812211)
			(xy 357.97469 -272.765937) (xy 357.958642 -272.716544) (xy 357.950517 -272.665249) (xy 357.670607 -272.665249)
			(xy 357.662482 -272.716544) (xy 357.646434 -272.765937) (xy 357.622856 -272.812211) (xy 357.59233 -272.854227)
			(xy 357.555607 -272.89095) (xy 357.513591 -272.921476) (xy 357.467317 -272.945054) (xy 357.417924 -272.961102)
			(xy 357.366629 -272.969227) (xy 357.314695 -272.969227) (xy 357.2634 -272.961102) (xy 357.214007 -272.945054)
			(xy 357.167733 -272.921476) (xy 357.125717 -272.89095) (xy 357.088994 -272.854227) (xy 357.058468 -272.812211)
			(xy 357.03489 -272.765937) (xy 357.018842 -272.716544) (xy 357.010717 -272.665249) (xy 356.730807 -272.665249)
			(xy 356.722682 -272.716544) (xy 356.706634 -272.765937) (xy 356.683056 -272.812211) (xy 356.65253 -272.854227)
			(xy 356.615807 -272.89095) (xy 356.573791 -272.921476) (xy 356.527517 -272.945054) (xy 356.478124 -272.961102)
			(xy 356.426829 -272.969227) (xy 356.374895 -272.969227) (xy 356.3236 -272.961102) (xy 356.274207 -272.945054)
			(xy 356.227933 -272.921476) (xy 356.185917 -272.89095) (xy 356.149194 -272.854227) (xy 356.118668 -272.812211)
			(xy 356.09509 -272.765937) (xy 356.079042 -272.716544) (xy 356.070917 -272.665249) (xy 355.791007 -272.665249)
			(xy 355.782882 -272.716544) (xy 355.766834 -272.765937) (xy 355.743256 -272.812211) (xy 355.71273 -272.854227)
			(xy 355.676007 -272.89095) (xy 355.633991 -272.921476) (xy 355.587717 -272.945054) (xy 355.538324 -272.961102)
			(xy 355.487029 -272.969227) (xy 355.435095 -272.969227) (xy 355.3838 -272.961102) (xy 355.334407 -272.945054)
			(xy 355.288133 -272.921476) (xy 355.246117 -272.89095) (xy 355.209394 -272.854227) (xy 355.178868 -272.812211)
			(xy 355.15529 -272.765937) (xy 355.139242 -272.716544) (xy 355.131117 -272.665249) (xy 354.851207 -272.665249)
			(xy 354.843082 -272.716544) (xy 354.827034 -272.765937) (xy 354.803456 -272.812211) (xy 354.77293 -272.854227)
			(xy 354.736207 -272.89095) (xy 354.694191 -272.921476) (xy 354.647917 -272.945054) (xy 354.598524 -272.961102)
			(xy 354.547229 -272.969227) (xy 354.495295 -272.969227) (xy 354.444 -272.961102) (xy 354.394607 -272.945054)
			(xy 354.348333 -272.921476) (xy 354.306317 -272.89095) (xy 354.269594 -272.854227) (xy 354.239068 -272.812211)
			(xy 354.21549 -272.765937) (xy 354.199442 -272.716544) (xy 354.191317 -272.665249) (xy 353.911407 -272.665249)
			(xy 353.903282 -272.716544) (xy 353.887234 -272.765937) (xy 353.863656 -272.812211) (xy 353.83313 -272.854227)
			(xy 353.796407 -272.89095) (xy 353.754391 -272.921476) (xy 353.708117 -272.945054) (xy 353.658724 -272.961102)
			(xy 353.607429 -272.969227) (xy 353.555495 -272.969227) (xy 353.5042 -272.961102) (xy 353.454807 -272.945054)
			(xy 353.408533 -272.921476) (xy 353.366517 -272.89095) (xy 353.329794 -272.854227) (xy 353.299268 -272.812211)
			(xy 353.27569 -272.765937) (xy 353.259642 -272.716544) (xy 353.251517 -272.665249) (xy 352.971607 -272.665249)
			(xy 352.963482 -272.716544) (xy 352.947434 -272.765937) (xy 352.923856 -272.812211) (xy 352.89333 -272.854227)
			(xy 352.856607 -272.89095) (xy 352.814591 -272.921476) (xy 352.768317 -272.945054) (xy 352.718924 -272.961102)
			(xy 352.667629 -272.969227) (xy 352.615695 -272.969227) (xy 352.5644 -272.961102) (xy 352.515007 -272.945054)
			(xy 352.468733 -272.921476) (xy 352.426717 -272.89095) (xy 352.389994 -272.854227) (xy 352.359468 -272.812211)
			(xy 352.33589 -272.765937) (xy 352.319842 -272.716544) (xy 352.311717 -272.665249) (xy 352.031807 -272.665249)
			(xy 352.023682 -272.716544) (xy 352.007634 -272.765937) (xy 351.984056 -272.812211) (xy 351.95353 -272.854227)
			(xy 351.916807 -272.89095) (xy 351.874791 -272.921476) (xy 351.828517 -272.945054) (xy 351.779124 -272.961102)
			(xy 351.727829 -272.969227) (xy 351.675895 -272.969227) (xy 351.6246 -272.961102) (xy 351.575207 -272.945054)
			(xy 351.528933 -272.921476) (xy 351.486917 -272.89095) (xy 351.450194 -272.854227) (xy 351.419668 -272.812211)
			(xy 351.39609 -272.765937) (xy 351.380042 -272.716544) (xy 351.371917 -272.665249) (xy 351.092007 -272.665249)
			(xy 351.083882 -272.716544) (xy 351.067834 -272.765937) (xy 351.044256 -272.812211) (xy 351.01373 -272.854227)
			(xy 350.977007 -272.89095) (xy 350.934991 -272.921476) (xy 350.888717 -272.945054) (xy 350.839324 -272.961102)
			(xy 350.788029 -272.969227) (xy 350.736095 -272.969227) (xy 350.6848 -272.961102) (xy 350.635407 -272.945054)
			(xy 350.589133 -272.921476) (xy 350.547117 -272.89095) (xy 350.510394 -272.854227) (xy 350.479868 -272.812211)
			(xy 350.45629 -272.765937) (xy 350.440242 -272.716544) (xy 350.432117 -272.665249) (xy 350.152207 -272.665249)
			(xy 350.144082 -272.716544) (xy 350.128034 -272.765937) (xy 350.104456 -272.812211) (xy 350.07393 -272.854227)
			(xy 350.037207 -272.89095) (xy 349.995191 -272.921476) (xy 349.948917 -272.945054) (xy 349.899524 -272.961102)
			(xy 349.848229 -272.969227) (xy 349.796295 -272.969227) (xy 349.745 -272.961102) (xy 349.695607 -272.945054)
			(xy 349.649333 -272.921476) (xy 349.607317 -272.89095) (xy 349.570594 -272.854227) (xy 349.540068 -272.812211)
			(xy 349.51649 -272.765937) (xy 349.500442 -272.716544) (xy 349.492317 -272.665249) (xy 349.212407 -272.665249)
			(xy 349.204282 -272.716544) (xy 349.188234 -272.765937) (xy 349.164656 -272.812211) (xy 349.13413 -272.854227)
			(xy 349.097407 -272.89095) (xy 349.055391 -272.921476) (xy 349.009117 -272.945054) (xy 348.959724 -272.961102)
			(xy 348.908429 -272.969227) (xy 348.856495 -272.969227) (xy 348.8052 -272.961102) (xy 348.755807 -272.945054)
			(xy 348.709533 -272.921476) (xy 348.667517 -272.89095) (xy 348.630794 -272.854227) (xy 348.600268 -272.812211)
			(xy 348.57669 -272.765937) (xy 348.560642 -272.716544) (xy 348.552517 -272.665249) (xy 348.272607 -272.665249)
			(xy 348.264482 -272.716544) (xy 348.248434 -272.765937) (xy 348.224856 -272.812211) (xy 348.19433 -272.854227)
			(xy 348.157607 -272.89095) (xy 348.115591 -272.921476) (xy 348.069317 -272.945054) (xy 348.019924 -272.961102)
			(xy 347.968629 -272.969227) (xy 347.916695 -272.969227) (xy 347.8654 -272.961102) (xy 347.816007 -272.945054)
			(xy 347.769733 -272.921476) (xy 347.727717 -272.89095) (xy 347.690994 -272.854227) (xy 347.660468 -272.812211)
			(xy 347.63689 -272.765937) (xy 347.620842 -272.716544) (xy 347.612717 -272.665249) (xy 347.332807 -272.665249)
			(xy 347.324682 -272.716544) (xy 347.308634 -272.765937) (xy 347.285056 -272.812211) (xy 347.25453 -272.854227)
			(xy 347.217807 -272.89095) (xy 347.175791 -272.921476) (xy 347.129517 -272.945054) (xy 347.080124 -272.961102)
			(xy 347.028829 -272.969227) (xy 346.976895 -272.969227) (xy 346.9256 -272.961102) (xy 346.876207 -272.945054)
			(xy 346.829933 -272.921476) (xy 346.787917 -272.89095) (xy 346.751194 -272.854227) (xy 346.720668 -272.812211)
			(xy 346.69709 -272.765937) (xy 346.681042 -272.716544) (xy 346.672917 -272.665249) (xy 346.393007 -272.665249)
			(xy 346.384882 -272.716544) (xy 346.368834 -272.765937) (xy 346.345256 -272.812211) (xy 346.31473 -272.854227)
			(xy 346.278007 -272.89095) (xy 346.235991 -272.921476) (xy 346.189717 -272.945054) (xy 346.140324 -272.961102)
			(xy 346.089029 -272.969227) (xy 346.037095 -272.969227) (xy 345.9858 -272.961102) (xy 345.936407 -272.945054)
			(xy 345.890133 -272.921476) (xy 345.848117 -272.89095) (xy 345.811394 -272.854227) (xy 345.780868 -272.812211)
			(xy 345.75729 -272.765937) (xy 345.741242 -272.716544) (xy 345.733117 -272.665249) (xy 345.453461 -272.665249)
			(xy 345.445336 -272.716544) (xy 345.429288 -272.765937) (xy 345.40571 -272.812211) (xy 345.375184 -272.854227)
			(xy 345.338461 -272.89095) (xy 345.296445 -272.921476) (xy 345.250171 -272.945054) (xy 345.200778 -272.961102)
			(xy 345.149483 -272.969227) (xy 345.097549 -272.969227) (xy 345.046254 -272.961102) (xy 344.996861 -272.945054)
			(xy 344.950587 -272.921476) (xy 344.908571 -272.89095) (xy 344.871848 -272.854227) (xy 344.841322 -272.812211)
			(xy 344.817744 -272.765937) (xy 344.801696 -272.716544) (xy 344.793571 -272.665249) (xy 344.557604 -272.665249)
			(xy 344.557604 -273.021044) (xy 344.55803 -273.034253) (xy 344.564824 -273.059784) (xy 344.577945 -273.082714)
			(xy 344.596513 -273.101507) (xy 344.619284 -273.114903) (xy 344.644731 -273.122003) (xy 344.657934 -273.122644)
			(xy 344.683679 -273.123474) (xy 344.734452 -273.132131) (xy 344.783268 -273.148561) (xy 344.828944 -273.172364)
			(xy 344.870374 -273.202966) (xy 344.906555 -273.239625) (xy 344.936611 -273.281453) (xy 344.959814 -273.327437)
			(xy 344.975601 -273.376464) (xy 344.983592 -273.427347) (xy 344.983592 -273.478853) (xy 344.983559 -273.479065)
			(xy 345.263471 -273.479065) (xy 345.263471 -273.427131) (xy 345.271596 -273.375836) (xy 345.287644 -273.326443)
			(xy 345.311222 -273.280169) (xy 345.341748 -273.238153) (xy 345.378471 -273.20143) (xy 345.420487 -273.170904)
			(xy 345.466761 -273.147326) (xy 345.516154 -273.131278) (xy 345.567449 -273.123153) (xy 345.619383 -273.123153)
			(xy 345.670678 -273.131278) (xy 345.720071 -273.147326) (xy 345.766345 -273.170904) (xy 345.808361 -273.20143)
			(xy 345.845084 -273.238153) (xy 345.87561 -273.280169) (xy 345.899188 -273.326443) (xy 345.915236 -273.375836)
			(xy 345.923361 -273.427131) (xy 345.92387 -273.453098) (xy 345.923361 -273.479065) (xy 346.203271 -273.479065)
			(xy 346.203271 -273.427131) (xy 346.211396 -273.375836) (xy 346.227444 -273.326443) (xy 346.251022 -273.280169)
			(xy 346.281548 -273.238153) (xy 346.318271 -273.20143) (xy 346.360287 -273.170904) (xy 346.406561 -273.147326)
			(xy 346.455954 -273.131278) (xy 346.507249 -273.123153) (xy 346.559183 -273.123153) (xy 346.610478 -273.131278)
			(xy 346.659871 -273.147326) (xy 346.706145 -273.170904) (xy 346.748161 -273.20143) (xy 346.784884 -273.238153)
			(xy 346.81541 -273.280169) (xy 346.838988 -273.326443) (xy 346.855036 -273.375836) (xy 346.863161 -273.427131)
			(xy 346.86367 -273.453098) (xy 346.863161 -273.479065) (xy 347.143071 -273.479065) (xy 347.143071 -273.427131)
			(xy 347.151196 -273.375836) (xy 347.167244 -273.326443) (xy 347.190822 -273.280169) (xy 347.221348 -273.238153)
			(xy 347.258071 -273.20143) (xy 347.300087 -273.170904) (xy 347.346361 -273.147326) (xy 347.395754 -273.131278)
			(xy 347.447049 -273.123153) (xy 347.498983 -273.123153) (xy 347.550278 -273.131278) (xy 347.599671 -273.147326)
			(xy 347.645945 -273.170904) (xy 347.687961 -273.20143) (xy 347.724684 -273.238153) (xy 347.75521 -273.280169)
			(xy 347.778788 -273.326443) (xy 347.794836 -273.375836) (xy 347.802961 -273.427131) (xy 347.80347 -273.453098)
			(xy 347.802961 -273.479065) (xy 348.082871 -273.479065) (xy 348.082871 -273.427131) (xy 348.090996 -273.375836)
			(xy 348.107044 -273.326443) (xy 348.130622 -273.280169) (xy 348.161148 -273.238153) (xy 348.197871 -273.20143)
			(xy 348.239887 -273.170904) (xy 348.286161 -273.147326) (xy 348.335554 -273.131278) (xy 348.386849 -273.123153)
			(xy 348.438783 -273.123153) (xy 348.490078 -273.131278) (xy 348.539471 -273.147326) (xy 348.585745 -273.170904)
			(xy 348.627761 -273.20143) (xy 348.664484 -273.238153) (xy 348.69501 -273.280169) (xy 348.718588 -273.326443)
			(xy 348.734636 -273.375836) (xy 348.742761 -273.427131) (xy 348.74327 -273.453098) (xy 348.742761 -273.479065)
			(xy 349.022417 -273.479065) (xy 349.022417 -273.427131) (xy 349.030542 -273.375836) (xy 349.04659 -273.326443)
			(xy 349.070168 -273.280169) (xy 349.100694 -273.238153) (xy 349.137417 -273.20143) (xy 349.179433 -273.170904)
			(xy 349.225707 -273.147326) (xy 349.2751 -273.131278) (xy 349.326395 -273.123153) (xy 349.378329 -273.123153)
			(xy 349.429624 -273.131278) (xy 349.479017 -273.147326) (xy 349.525291 -273.170904) (xy 349.567307 -273.20143)
			(xy 349.60403 -273.238153) (xy 349.634556 -273.280169) (xy 349.658134 -273.326443) (xy 349.674182 -273.375836)
			(xy 349.682307 -273.427131) (xy 349.682816 -273.453098) (xy 349.682307 -273.479065) (xy 349.962471 -273.479065)
			(xy 349.962471 -273.427131) (xy 349.970596 -273.375836) (xy 349.986644 -273.326443) (xy 350.010222 -273.280169)
			(xy 350.040748 -273.238153) (xy 350.077471 -273.20143) (xy 350.119487 -273.170904) (xy 350.165761 -273.147326)
			(xy 350.215154 -273.131278) (xy 350.266449 -273.123153) (xy 350.318383 -273.123153) (xy 350.369678 -273.131278)
			(xy 350.419071 -273.147326) (xy 350.465345 -273.170904) (xy 350.507361 -273.20143) (xy 350.544084 -273.238153)
			(xy 350.57461 -273.280169) (xy 350.598188 -273.326443) (xy 350.614236 -273.375836) (xy 350.622361 -273.427131)
			(xy 350.62287 -273.453098) (xy 350.622361 -273.479065) (xy 350.902017 -273.479065) (xy 350.902017 -273.427131)
			(xy 350.910142 -273.375836) (xy 350.92619 -273.326443) (xy 350.949768 -273.280169) (xy 350.980294 -273.238153)
			(xy 351.017017 -273.20143) (xy 351.059033 -273.170904) (xy 351.105307 -273.147326) (xy 351.1547 -273.131278)
			(xy 351.205995 -273.123153) (xy 351.257929 -273.123153) (xy 351.309224 -273.131278) (xy 351.358617 -273.147326)
			(xy 351.404891 -273.170904) (xy 351.446907 -273.20143) (xy 351.48363 -273.238153) (xy 351.514156 -273.280169)
			(xy 351.537734 -273.326443) (xy 351.553782 -273.375836) (xy 351.561907 -273.427131) (xy 351.562416 -273.453098)
			(xy 351.561907 -273.479065) (xy 351.842071 -273.479065) (xy 351.842071 -273.427131) (xy 351.850196 -273.375836)
			(xy 351.866244 -273.326443) (xy 351.889822 -273.280169) (xy 351.920348 -273.238153) (xy 351.957071 -273.20143)
			(xy 351.999087 -273.170904) (xy 352.045361 -273.147326) (xy 352.094754 -273.131278) (xy 352.146049 -273.123153)
			(xy 352.197983 -273.123153) (xy 352.249278 -273.131278) (xy 352.298671 -273.147326) (xy 352.344945 -273.170904)
			(xy 352.386961 -273.20143) (xy 352.423684 -273.238153) (xy 352.45421 -273.280169) (xy 352.477788 -273.326443)
			(xy 352.493836 -273.375836) (xy 352.501961 -273.427131) (xy 352.50247 -273.453098) (xy 352.501961 -273.479065)
			(xy 353.721671 -273.479065) (xy 353.721671 -273.427131) (xy 353.729796 -273.375836) (xy 353.745844 -273.326443)
			(xy 353.769422 -273.280169) (xy 353.799948 -273.238153) (xy 353.836671 -273.20143) (xy 353.878687 -273.170904)
			(xy 353.924961 -273.147326) (xy 353.974354 -273.131278) (xy 354.025649 -273.123153) (xy 354.077583 -273.123153)
			(xy 354.128878 -273.131278) (xy 354.178271 -273.147326) (xy 354.224545 -273.170904) (xy 354.266561 -273.20143)
			(xy 354.303284 -273.238153) (xy 354.33381 -273.280169) (xy 354.357388 -273.326443) (xy 354.373436 -273.375836)
			(xy 354.381561 -273.427131) (xy 354.38207 -273.453098) (xy 354.381561 -273.479065) (xy 354.661471 -273.479065)
			(xy 354.661471 -273.427131) (xy 354.669596 -273.375836) (xy 354.685644 -273.326443) (xy 354.709222 -273.280169)
			(xy 354.739748 -273.238153) (xy 354.776471 -273.20143) (xy 354.818487 -273.170904) (xy 354.864761 -273.147326)
			(xy 354.914154 -273.131278) (xy 354.965449 -273.123153) (xy 355.017383 -273.123153) (xy 355.068678 -273.131278)
			(xy 355.118071 -273.147326) (xy 355.164345 -273.170904) (xy 355.206361 -273.20143) (xy 355.243084 -273.238153)
			(xy 355.27361 -273.280169) (xy 355.297188 -273.326443) (xy 355.313236 -273.375836) (xy 355.321361 -273.427131)
			(xy 355.32187 -273.453098) (xy 355.321361 -273.479065) (xy 355.601271 -273.479065) (xy 355.601271 -273.427131)
			(xy 355.609396 -273.375836) (xy 355.625444 -273.326443) (xy 355.649022 -273.280169) (xy 355.679548 -273.238153)
			(xy 355.716271 -273.20143) (xy 355.758287 -273.170904) (xy 355.804561 -273.147326) (xy 355.853954 -273.131278)
			(xy 355.905249 -273.123153) (xy 355.957183 -273.123153) (xy 356.008478 -273.131278) (xy 356.057871 -273.147326)
			(xy 356.104145 -273.170904) (xy 356.146161 -273.20143) (xy 356.182884 -273.238153) (xy 356.21341 -273.280169)
			(xy 356.236988 -273.326443) (xy 356.253036 -273.375836) (xy 356.261161 -273.427131) (xy 356.26167 -273.453098)
			(xy 356.540308 -273.453098) (xy 356.540817 -273.427131) (xy 356.548942 -273.375836) (xy 356.56499 -273.326443)
			(xy 356.588568 -273.280169) (xy 356.619094 -273.238153) (xy 356.655817 -273.20143) (xy 356.697833 -273.170904)
			(xy 356.744107 -273.147326) (xy 356.7935 -273.131278) (xy 356.844795 -273.123153) (xy 356.896729 -273.123153)
			(xy 356.948024 -273.131278) (xy 356.997417 -273.147326) (xy 357.043691 -273.170904) (xy 357.085707 -273.20143)
			(xy 357.12243 -273.238153) (xy 357.152956 -273.280169) (xy 357.176534 -273.326443) (xy 357.192582 -273.375836)
			(xy 357.200707 -273.427131) (xy 357.201216 -273.453098) (xy 357.200623 -273.479065) (xy 357.480617 -273.479065)
			(xy 357.480617 -273.427131) (xy 357.488742 -273.375836) (xy 357.50479 -273.326443) (xy 357.528368 -273.280169)
			(xy 357.558894 -273.238153) (xy 357.595617 -273.20143) (xy 357.637633 -273.170904) (xy 357.683907 -273.147326)
			(xy 357.7333 -273.131278) (xy 357.784595 -273.123153) (xy 357.836529 -273.123153) (xy 357.887824 -273.131278)
			(xy 357.937217 -273.147326) (xy 357.983491 -273.170904) (xy 358.025507 -273.20143) (xy 358.06223 -273.238153)
			(xy 358.092756 -273.280169) (xy 358.116334 -273.326443) (xy 358.132382 -273.375836) (xy 358.140507 -273.427131)
			(xy 358.141016 -273.453098) (xy 358.140507 -273.479065) (xy 361.239817 -273.479065) (xy 361.239817 -273.427131)
			(xy 361.247942 -273.375836) (xy 361.26399 -273.326443) (xy 361.287568 -273.280169) (xy 361.318094 -273.238153)
			(xy 361.354817 -273.20143) (xy 361.396833 -273.170904) (xy 361.443107 -273.147326) (xy 361.4925 -273.131278)
			(xy 361.543795 -273.123153) (xy 361.595729 -273.123153) (xy 361.647024 -273.131278) (xy 361.696417 -273.147326)
			(xy 361.742691 -273.170904) (xy 361.784707 -273.20143) (xy 361.82143 -273.238153) (xy 361.851956 -273.280169)
			(xy 361.875534 -273.326443) (xy 361.891582 -273.375836) (xy 361.899707 -273.427131) (xy 361.900216 -273.453098)
			(xy 361.899707 -273.479065) (xy 362.179617 -273.479065) (xy 362.179617 -273.427131) (xy 362.187742 -273.375836)
			(xy 362.20379 -273.326443) (xy 362.227368 -273.280169) (xy 362.257894 -273.238153) (xy 362.294617 -273.20143)
			(xy 362.336633 -273.170904) (xy 362.382907 -273.147326) (xy 362.4323 -273.131278) (xy 362.483595 -273.123153)
			(xy 362.535529 -273.123153) (xy 362.586824 -273.131278) (xy 362.636217 -273.147326) (xy 362.682491 -273.170904)
			(xy 362.724507 -273.20143) (xy 362.76123 -273.238153) (xy 362.791756 -273.280169) (xy 362.815334 -273.326443)
			(xy 362.831382 -273.375836) (xy 362.839507 -273.427131) (xy 362.840016 -273.453098) (xy 362.839507 -273.479065)
			(xy 363.119417 -273.479065) (xy 363.119417 -273.427131) (xy 363.127542 -273.375836) (xy 363.14359 -273.326443)
			(xy 363.167168 -273.280169) (xy 363.197694 -273.238153) (xy 363.234417 -273.20143) (xy 363.276433 -273.170904)
			(xy 363.322707 -273.147326) (xy 363.3721 -273.131278) (xy 363.423395 -273.123153) (xy 363.475329 -273.123153)
			(xy 363.526624 -273.131278) (xy 363.576017 -273.147326) (xy 363.622291 -273.170904) (xy 363.664307 -273.20143)
			(xy 363.70103 -273.238153) (xy 363.731556 -273.280169) (xy 363.755134 -273.326443) (xy 363.771182 -273.375836)
			(xy 363.779307 -273.427131) (xy 363.779816 -273.453098) (xy 363.779307 -273.479065) (xy 363.771182 -273.53036)
			(xy 363.755134 -273.579753) (xy 363.731556 -273.626027) (xy 363.70103 -273.668043) (xy 363.664307 -273.704766)
			(xy 363.622291 -273.735292) (xy 363.576017 -273.75887) (xy 363.526624 -273.774918) (xy 363.475329 -273.783043)
			(xy 363.423395 -273.783043) (xy 363.3721 -273.774918) (xy 363.322707 -273.75887) (xy 363.276433 -273.735292)
			(xy 363.234417 -273.704766) (xy 363.197694 -273.668043) (xy 363.167168 -273.626027) (xy 363.14359 -273.579753)
			(xy 363.127542 -273.53036) (xy 363.119417 -273.479065) (xy 362.839507 -273.479065) (xy 362.831382 -273.53036)
			(xy 362.815334 -273.579753) (xy 362.791756 -273.626027) (xy 362.76123 -273.668043) (xy 362.724507 -273.704766)
			(xy 362.682491 -273.735292) (xy 362.636217 -273.75887) (xy 362.586824 -273.774918) (xy 362.535529 -273.783043)
			(xy 362.483595 -273.783043) (xy 362.4323 -273.774918) (xy 362.382907 -273.75887) (xy 362.336633 -273.735292)
			(xy 362.294617 -273.704766) (xy 362.257894 -273.668043) (xy 362.227368 -273.626027) (xy 362.20379 -273.579753)
			(xy 362.187742 -273.53036) (xy 362.179617 -273.479065) (xy 361.899707 -273.479065) (xy 361.891582 -273.53036)
			(xy 361.875534 -273.579753) (xy 361.851956 -273.626027) (xy 361.82143 -273.668043) (xy 361.784707 -273.704766)
			(xy 361.742691 -273.735292) (xy 361.696417 -273.75887) (xy 361.647024 -273.774918) (xy 361.595729 -273.783043)
			(xy 361.543795 -273.783043) (xy 361.4925 -273.774918) (xy 361.443107 -273.75887) (xy 361.396833 -273.735292)
			(xy 361.354817 -273.704766) (xy 361.318094 -273.668043) (xy 361.287568 -273.626027) (xy 361.26399 -273.579753)
			(xy 361.247942 -273.53036) (xy 361.239817 -273.479065) (xy 358.140507 -273.479065) (xy 358.132382 -273.53036)
			(xy 358.116334 -273.579753) (xy 358.092756 -273.626027) (xy 358.06223 -273.668043) (xy 358.025507 -273.704766)
			(xy 357.983491 -273.735292) (xy 357.937217 -273.75887) (xy 357.887824 -273.774918) (xy 357.836529 -273.783043)
			(xy 357.784595 -273.783043) (xy 357.7333 -273.774918) (xy 357.683907 -273.75887) (xy 357.637633 -273.735292)
			(xy 357.595617 -273.704766) (xy 357.558894 -273.668043) (xy 357.528368 -273.626027) (xy 357.50479 -273.579753)
			(xy 357.488742 -273.53036) (xy 357.480617 -273.479065) (xy 357.200623 -273.479065) (xy 357.200579 -273.481014)
			(xy 357.191137 -273.536044) (xy 357.18242 -273.562572) (xy 357.1748 -273.58467) (xy 357.378508 -273.93773)
			(xy 357.401622 -273.942048) (xy 357.426537 -273.947246) (xy 357.47452 -273.964207) (xy 357.519337 -273.98832)
			(xy 357.559929 -274.019016) (xy 357.595339 -274.055571) (xy 357.624728 -274.097119) (xy 357.647404 -274.142681)
			(xy 357.662829 -274.191179) (xy 357.670641 -274.241468) (xy 357.671116 -274.266914) (xy 357.670607 -274.292881)
			(xy 357.950517 -274.292881) (xy 357.950517 -274.240947) (xy 357.958642 -274.189652) (xy 357.97469 -274.140259)
			(xy 357.998268 -274.093985) (xy 358.028794 -274.051969) (xy 358.065517 -274.015246) (xy 358.107533 -273.98472)
			(xy 358.153807 -273.961142) (xy 358.2032 -273.945094) (xy 358.254495 -273.936969) (xy 358.306429 -273.936969)
			(xy 358.357724 -273.945094) (xy 358.407117 -273.961142) (xy 358.453391 -273.98472) (xy 358.495407 -274.015246)
			(xy 358.53213 -274.051969) (xy 358.562656 -274.093985) (xy 358.586234 -274.140259) (xy 358.602282 -274.189652)
			(xy 358.610407 -274.240947) (xy 358.610916 -274.266914) (xy 358.610407 -274.292881) (xy 361.709717 -274.292881)
			(xy 361.709717 -274.240947) (xy 361.717842 -274.189652) (xy 361.73389 -274.140259) (xy 361.757468 -274.093985)
			(xy 361.787994 -274.051969) (xy 361.824717 -274.015246) (xy 361.866733 -273.98472) (xy 361.913007 -273.961142)
			(xy 361.9624 -273.945094) (xy 362.013695 -273.936969) (xy 362.065629 -273.936969) (xy 362.116924 -273.945094)
			(xy 362.166317 -273.961142) (xy 362.212591 -273.98472) (xy 362.254607 -274.015246) (xy 362.29133 -274.051969)
			(xy 362.321856 -274.093985) (xy 362.345434 -274.140259) (xy 362.361482 -274.189652) (xy 362.369607 -274.240947)
			(xy 362.370116 -274.266914) (xy 362.369607 -274.292881) (xy 362.649517 -274.292881) (xy 362.649517 -274.240947)
			(xy 362.657642 -274.189652) (xy 362.67369 -274.140259) (xy 362.697268 -274.093985) (xy 362.727794 -274.051969)
			(xy 362.764517 -274.015246) (xy 362.806533 -273.98472) (xy 362.852807 -273.961142) (xy 362.9022 -273.945094)
			(xy 362.953495 -273.936969) (xy 363.005429 -273.936969) (xy 363.056724 -273.945094) (xy 363.106117 -273.961142)
			(xy 363.152391 -273.98472) (xy 363.194407 -274.015246) (xy 363.23113 -274.051969) (xy 363.261656 -274.093985)
			(xy 363.285234 -274.140259) (xy 363.301282 -274.189652) (xy 363.309407 -274.240947) (xy 363.309916 -274.266914)
			(xy 363.309407 -274.292881) (xy 363.589571 -274.292881) (xy 363.589571 -274.240947) (xy 363.597696 -274.189652)
			(xy 363.613744 -274.140259) (xy 363.637322 -274.093985) (xy 363.667848 -274.051969) (xy 363.704571 -274.015246)
			(xy 363.746587 -273.98472) (xy 363.792861 -273.961142) (xy 363.842254 -273.945094) (xy 363.893549 -273.936969)
			(xy 363.945483 -273.936969) (xy 363.996778 -273.945094) (xy 364.046171 -273.961142) (xy 364.092445 -273.98472)
			(xy 364.134461 -274.015246) (xy 364.171184 -274.051969) (xy 364.20171 -274.093985) (xy 364.225288 -274.140259)
			(xy 364.241336 -274.189652) (xy 364.249461 -274.240947) (xy 364.24997 -274.266914) (xy 364.249461 -274.292881)
			(xy 364.241336 -274.344176) (xy 364.225288 -274.393569) (xy 364.20171 -274.439843) (xy 364.171184 -274.481859)
			(xy 364.134461 -274.518582) (xy 364.092445 -274.549108) (xy 364.046171 -274.572686) (xy 363.996778 -274.588734)
			(xy 363.945483 -274.596859) (xy 363.893549 -274.596859) (xy 363.842254 -274.588734) (xy 363.792861 -274.572686)
			(xy 363.746587 -274.549108) (xy 363.704571 -274.518582) (xy 363.667848 -274.481859) (xy 363.637322 -274.439843)
			(xy 363.613744 -274.393569) (xy 363.597696 -274.344176) (xy 363.589571 -274.292881) (xy 363.309407 -274.292881)
			(xy 363.301282 -274.344176) (xy 363.285234 -274.393569) (xy 363.261656 -274.439843) (xy 363.23113 -274.481859)
			(xy 363.194407 -274.518582) (xy 363.152391 -274.549108) (xy 363.106117 -274.572686) (xy 363.056724 -274.588734)
			(xy 363.005429 -274.596859) (xy 362.953495 -274.596859) (xy 362.9022 -274.588734) (xy 362.852807 -274.572686)
			(xy 362.806533 -274.549108) (xy 362.764517 -274.518582) (xy 362.727794 -274.481859) (xy 362.697268 -274.439843)
			(xy 362.67369 -274.393569) (xy 362.657642 -274.344176) (xy 362.649517 -274.292881) (xy 362.369607 -274.292881)
			(xy 362.361482 -274.344176) (xy 362.345434 -274.393569) (xy 362.321856 -274.439843) (xy 362.29133 -274.481859)
			(xy 362.254607 -274.518582) (xy 362.212591 -274.549108) (xy 362.166317 -274.572686) (xy 362.116924 -274.588734)
			(xy 362.065629 -274.596859) (xy 362.013695 -274.596859) (xy 361.9624 -274.588734) (xy 361.913007 -274.572686)
			(xy 361.866733 -274.549108) (xy 361.824717 -274.518582) (xy 361.787994 -274.481859) (xy 361.757468 -274.439843)
			(xy 361.73389 -274.393569) (xy 361.717842 -274.344176) (xy 361.709717 -274.292881) (xy 358.610407 -274.292881)
			(xy 358.602282 -274.344176) (xy 358.586234 -274.393569) (xy 358.562656 -274.439843) (xy 358.53213 -274.481859)
			(xy 358.495407 -274.518582) (xy 358.453391 -274.549108) (xy 358.407117 -274.572686) (xy 358.357724 -274.588734)
			(xy 358.306429 -274.596859) (xy 358.254495 -274.596859) (xy 358.2032 -274.588734) (xy 358.153807 -274.572686)
			(xy 358.107533 -274.549108) (xy 358.065517 -274.518582) (xy 358.028794 -274.481859) (xy 357.998268 -274.439843)
			(xy 357.97469 -274.393569) (xy 357.958642 -274.344176) (xy 357.950517 -274.292881) (xy 357.670607 -274.292881)
			(xy 357.662482 -274.344176) (xy 357.646434 -274.393569) (xy 357.622856 -274.439843) (xy 357.59233 -274.481859)
			(xy 357.555607 -274.518582) (xy 357.513591 -274.549108) (xy 357.467317 -274.572686) (xy 357.417924 -274.588734)
			(xy 357.366629 -274.596859) (xy 357.314695 -274.596859) (xy 357.2634 -274.588734) (xy 357.214007 -274.572686)
			(xy 357.167733 -274.549108) (xy 357.125717 -274.518582) (xy 357.088994 -274.481859) (xy 357.058468 -274.439843)
			(xy 357.03489 -274.393569) (xy 357.018842 -274.344176) (xy 357.010717 -274.292881) (xy 357.010208 -274.266914)
			(xy 357.010764 -274.238928) (xy 357.020212 -274.18376) (xy 357.029004 -274.157186) (xy 357.036624 -274.135088)
			(xy 356.832916 -273.782282) (xy 356.810056 -273.777964) (xy 356.785115 -273.77282) (xy 356.737088 -273.755894)
			(xy 356.692226 -273.731801) (xy 356.65159 -273.701112) (xy 356.616142 -273.664553) (xy 356.586722 -273.62299)
			(xy 356.564025 -273.577405) (xy 356.548588 -273.528879) (xy 356.540778 -273.478559) (xy 356.540308 -273.453098)
			(xy 356.26167 -273.453098) (xy 356.261161 -273.479065) (xy 356.253036 -273.53036) (xy 356.236988 -273.579753)
			(xy 356.21341 -273.626027) (xy 356.182884 -273.668043) (xy 356.146161 -273.704766) (xy 356.104145 -273.735292)
			(xy 356.057871 -273.75887) (xy 356.008478 -273.774918) (xy 355.957183 -273.783043) (xy 355.905249 -273.783043)
			(xy 355.853954 -273.774918) (xy 355.804561 -273.75887) (xy 355.758287 -273.735292) (xy 355.716271 -273.704766)
			(xy 355.679548 -273.668043) (xy 355.649022 -273.626027) (xy 355.625444 -273.579753) (xy 355.609396 -273.53036)
			(xy 355.601271 -273.479065) (xy 355.321361 -273.479065) (xy 355.313236 -273.53036) (xy 355.297188 -273.579753)
			(xy 355.27361 -273.626027) (xy 355.243084 -273.668043) (xy 355.206361 -273.704766) (xy 355.164345 -273.735292)
			(xy 355.118071 -273.75887) (xy 355.068678 -273.774918) (xy 355.017383 -273.783043) (xy 354.965449 -273.783043)
			(xy 354.914154 -273.774918) (xy 354.864761 -273.75887) (xy 354.818487 -273.735292) (xy 354.776471 -273.704766)
			(xy 354.739748 -273.668043) (xy 354.709222 -273.626027) (xy 354.685644 -273.579753) (xy 354.669596 -273.53036)
			(xy 354.661471 -273.479065) (xy 354.381561 -273.479065) (xy 354.373436 -273.53036) (xy 354.357388 -273.579753)
			(xy 354.33381 -273.626027) (xy 354.303284 -273.668043) (xy 354.266561 -273.704766) (xy 354.224545 -273.735292)
			(xy 354.178271 -273.75887) (xy 354.128878 -273.774918) (xy 354.077583 -273.783043) (xy 354.025649 -273.783043)
			(xy 353.974354 -273.774918) (xy 353.924961 -273.75887) (xy 353.878687 -273.735292) (xy 353.836671 -273.704766)
			(xy 353.799948 -273.668043) (xy 353.769422 -273.626027) (xy 353.745844 -273.579753) (xy 353.729796 -273.53036)
			(xy 353.721671 -273.479065) (xy 352.501961 -273.479065) (xy 352.493836 -273.53036) (xy 352.477788 -273.579753)
			(xy 352.45421 -273.626027) (xy 352.423684 -273.668043) (xy 352.386961 -273.704766) (xy 352.344945 -273.735292)
			(xy 352.298671 -273.75887) (xy 352.249278 -273.774918) (xy 352.197983 -273.783043) (xy 352.146049 -273.783043)
			(xy 352.094754 -273.774918) (xy 352.045361 -273.75887) (xy 351.999087 -273.735292) (xy 351.957071 -273.704766)
			(xy 351.920348 -273.668043) (xy 351.889822 -273.626027) (xy 351.866244 -273.579753) (xy 351.850196 -273.53036)
			(xy 351.842071 -273.479065) (xy 351.561907 -273.479065) (xy 351.553782 -273.53036) (xy 351.537734 -273.579753)
			(xy 351.514156 -273.626027) (xy 351.48363 -273.668043) (xy 351.446907 -273.704766) (xy 351.404891 -273.735292)
			(xy 351.358617 -273.75887) (xy 351.309224 -273.774918) (xy 351.257929 -273.783043) (xy 351.205995 -273.783043)
			(xy 351.1547 -273.774918) (xy 351.105307 -273.75887) (xy 351.059033 -273.735292) (xy 351.017017 -273.704766)
			(xy 350.980294 -273.668043) (xy 350.949768 -273.626027) (xy 350.92619 -273.579753) (xy 350.910142 -273.53036)
			(xy 350.902017 -273.479065) (xy 350.622361 -273.479065) (xy 350.614236 -273.53036) (xy 350.598188 -273.579753)
			(xy 350.57461 -273.626027) (xy 350.544084 -273.668043) (xy 350.507361 -273.704766) (xy 350.465345 -273.735292)
			(xy 350.419071 -273.75887) (xy 350.369678 -273.774918) (xy 350.318383 -273.783043) (xy 350.266449 -273.783043)
			(xy 350.215154 -273.774918) (xy 350.165761 -273.75887) (xy 350.119487 -273.735292) (xy 350.077471 -273.704766)
			(xy 350.040748 -273.668043) (xy 350.010222 -273.626027) (xy 349.986644 -273.579753) (xy 349.970596 -273.53036)
			(xy 349.962471 -273.479065) (xy 349.682307 -273.479065) (xy 349.674182 -273.53036) (xy 349.658134 -273.579753)
			(xy 349.634556 -273.626027) (xy 349.60403 -273.668043) (xy 349.567307 -273.704766) (xy 349.525291 -273.735292)
			(xy 349.479017 -273.75887) (xy 349.429624 -273.774918) (xy 349.378329 -273.783043) (xy 349.326395 -273.783043)
			(xy 349.2751 -273.774918) (xy 349.225707 -273.75887) (xy 349.179433 -273.735292) (xy 349.137417 -273.704766)
			(xy 349.100694 -273.668043) (xy 349.070168 -273.626027) (xy 349.04659 -273.579753) (xy 349.030542 -273.53036)
			(xy 349.022417 -273.479065) (xy 348.742761 -273.479065) (xy 348.734636 -273.53036) (xy 348.718588 -273.579753)
			(xy 348.69501 -273.626027) (xy 348.664484 -273.668043) (xy 348.627761 -273.704766) (xy 348.585745 -273.735292)
			(xy 348.539471 -273.75887) (xy 348.490078 -273.774918) (xy 348.438783 -273.783043) (xy 348.386849 -273.783043)
			(xy 348.335554 -273.774918) (xy 348.286161 -273.75887) (xy 348.239887 -273.735292) (xy 348.197871 -273.704766)
			(xy 348.161148 -273.668043) (xy 348.130622 -273.626027) (xy 348.107044 -273.579753) (xy 348.090996 -273.53036)
			(xy 348.082871 -273.479065) (xy 347.802961 -273.479065) (xy 347.794836 -273.53036) (xy 347.778788 -273.579753)
			(xy 347.75521 -273.626027) (xy 347.724684 -273.668043) (xy 347.687961 -273.704766) (xy 347.645945 -273.735292)
			(xy 347.599671 -273.75887) (xy 347.550278 -273.774918) (xy 347.498983 -273.783043) (xy 347.447049 -273.783043)
			(xy 347.395754 -273.774918) (xy 347.346361 -273.75887) (xy 347.300087 -273.735292) (xy 347.258071 -273.704766)
			(xy 347.221348 -273.668043) (xy 347.190822 -273.626027) (xy 347.167244 -273.579753) (xy 347.151196 -273.53036)
			(xy 347.143071 -273.479065) (xy 346.863161 -273.479065) (xy 346.855036 -273.53036) (xy 346.838988 -273.579753)
			(xy 346.81541 -273.626027) (xy 346.784884 -273.668043) (xy 346.748161 -273.704766) (xy 346.706145 -273.735292)
			(xy 346.659871 -273.75887) (xy 346.610478 -273.774918) (xy 346.559183 -273.783043) (xy 346.507249 -273.783043)
			(xy 346.455954 -273.774918) (xy 346.406561 -273.75887) (xy 346.360287 -273.735292) (xy 346.318271 -273.704766)
			(xy 346.281548 -273.668043) (xy 346.251022 -273.626027) (xy 346.227444 -273.579753) (xy 346.211396 -273.53036)
			(xy 346.203271 -273.479065) (xy 345.923361 -273.479065) (xy 345.915236 -273.53036) (xy 345.899188 -273.579753)
			(xy 345.87561 -273.626027) (xy 345.845084 -273.668043) (xy 345.808361 -273.704766) (xy 345.766345 -273.735292)
			(xy 345.720071 -273.75887) (xy 345.670678 -273.774918) (xy 345.619383 -273.783043) (xy 345.567449 -273.783043)
			(xy 345.516154 -273.774918) (xy 345.466761 -273.75887) (xy 345.420487 -273.735292) (xy 345.378471 -273.704766)
			(xy 345.341748 -273.668043) (xy 345.311222 -273.626027) (xy 345.287644 -273.579753) (xy 345.271596 -273.53036)
			(xy 345.263471 -273.479065) (xy 344.983559 -273.479065) (xy 344.975601 -273.529736) (xy 344.959814 -273.578763)
			(xy 344.936611 -273.624747) (xy 344.906555 -273.666575) (xy 344.870374 -273.703234) (xy 344.828944 -273.733835)
			(xy 344.783268 -273.757639) (xy 344.734452 -273.774069) (xy 344.683679 -273.782726) (xy 344.657934 -273.783552)
			(xy 344.644728 -273.784138) (xy 344.619277 -273.791244) (xy 344.596506 -273.80465) (xy 344.577943 -273.823455)
			(xy 344.564834 -273.846399) (xy 344.558059 -273.87194) (xy 344.557604 -273.885152) (xy 344.557604 -274.292881)
			(xy 344.793317 -274.292881) (xy 344.793317 -274.240947) (xy 344.801442 -274.189652) (xy 344.81749 -274.140259)
			(xy 344.841068 -274.093985) (xy 344.871594 -274.051969) (xy 344.908317 -274.015246) (xy 344.950333 -273.98472)
			(xy 344.996607 -273.961142) (xy 345.046 -273.945094) (xy 345.097295 -273.936969) (xy 345.149229 -273.936969)
			(xy 345.200524 -273.945094) (xy 345.249917 -273.961142) (xy 345.296191 -273.98472) (xy 345.338207 -274.015246)
			(xy 345.37493 -274.051969) (xy 345.405456 -274.093985) (xy 345.429034 -274.140259) (xy 345.445082 -274.189652)
			(xy 345.453207 -274.240947) (xy 345.453716 -274.266914) (xy 345.453207 -274.292881) (xy 345.733117 -274.292881)
			(xy 345.733117 -274.240947) (xy 345.741242 -274.189652) (xy 345.75729 -274.140259) (xy 345.780868 -274.093985)
			(xy 345.811394 -274.051969) (xy 345.848117 -274.015246) (xy 345.890133 -273.98472) (xy 345.936407 -273.961142)
			(xy 345.9858 -273.945094) (xy 346.037095 -273.936969) (xy 346.089029 -273.936969) (xy 346.140324 -273.945094)
			(xy 346.189717 -273.961142) (xy 346.235991 -273.98472) (xy 346.278007 -274.015246) (xy 346.31473 -274.051969)
			(xy 346.345256 -274.093985) (xy 346.368834 -274.140259) (xy 346.384882 -274.189652) (xy 346.393007 -274.240947)
			(xy 346.393516 -274.266914) (xy 346.393007 -274.292881) (xy 346.672917 -274.292881) (xy 346.672917 -274.240947)
			(xy 346.681042 -274.189652) (xy 346.69709 -274.140259) (xy 346.720668 -274.093985) (xy 346.751194 -274.051969)
			(xy 346.787917 -274.015246) (xy 346.829933 -273.98472) (xy 346.876207 -273.961142) (xy 346.9256 -273.945094)
			(xy 346.976895 -273.936969) (xy 347.028829 -273.936969) (xy 347.080124 -273.945094) (xy 347.129517 -273.961142)
			(xy 347.175791 -273.98472) (xy 347.217807 -274.015246) (xy 347.25453 -274.051969) (xy 347.285056 -274.093985)
			(xy 347.308634 -274.140259) (xy 347.324682 -274.189652) (xy 347.332807 -274.240947) (xy 347.333316 -274.266914)
			(xy 347.332807 -274.292881) (xy 347.612717 -274.292881) (xy 347.612717 -274.240947) (xy 347.620842 -274.189652)
			(xy 347.63689 -274.140259) (xy 347.660468 -274.093985) (xy 347.690994 -274.051969) (xy 347.727717 -274.015246)
			(xy 347.769733 -273.98472) (xy 347.816007 -273.961142) (xy 347.8654 -273.945094) (xy 347.916695 -273.936969)
			(xy 347.968629 -273.936969) (xy 348.019924 -273.945094) (xy 348.069317 -273.961142) (xy 348.115591 -273.98472)
			(xy 348.157607 -274.015246) (xy 348.19433 -274.051969) (xy 348.224856 -274.093985) (xy 348.248434 -274.140259)
			(xy 348.264482 -274.189652) (xy 348.272607 -274.240947) (xy 348.273116 -274.266914) (xy 348.272607 -274.292881)
			(xy 348.552517 -274.292881) (xy 348.552517 -274.240947) (xy 348.560642 -274.189652) (xy 348.57669 -274.140259)
			(xy 348.600268 -274.093985) (xy 348.630794 -274.051969) (xy 348.667517 -274.015246) (xy 348.709533 -273.98472)
			(xy 348.755807 -273.961142) (xy 348.8052 -273.945094) (xy 348.856495 -273.936969) (xy 348.908429 -273.936969)
			(xy 348.959724 -273.945094) (xy 349.009117 -273.961142) (xy 349.055391 -273.98472) (xy 349.097407 -274.015246)
			(xy 349.13413 -274.051969) (xy 349.164656 -274.093985) (xy 349.188234 -274.140259) (xy 349.204282 -274.189652)
			(xy 349.212407 -274.240947) (xy 349.212916 -274.266914) (xy 349.212407 -274.292881) (xy 349.492317 -274.292881)
			(xy 349.492317 -274.240947) (xy 349.500442 -274.189652) (xy 349.51649 -274.140259) (xy 349.540068 -274.093985)
			(xy 349.570594 -274.051969) (xy 349.607317 -274.015246) (xy 349.649333 -273.98472) (xy 349.695607 -273.961142)
			(xy 349.745 -273.945094) (xy 349.796295 -273.936969) (xy 349.848229 -273.936969) (xy 349.899524 -273.945094)
			(xy 349.948917 -273.961142) (xy 349.995191 -273.98472) (xy 350.037207 -274.015246) (xy 350.07393 -274.051969)
			(xy 350.104456 -274.093985) (xy 350.128034 -274.140259) (xy 350.144082 -274.189652) (xy 350.152207 -274.240947)
			(xy 350.152716 -274.266914) (xy 350.152207 -274.292881) (xy 350.432117 -274.292881) (xy 350.432117 -274.240947)
			(xy 350.440242 -274.189652) (xy 350.45629 -274.140259) (xy 350.479868 -274.093985) (xy 350.510394 -274.051969)
			(xy 350.547117 -274.015246) (xy 350.589133 -273.98472) (xy 350.635407 -273.961142) (xy 350.6848 -273.945094)
			(xy 350.736095 -273.936969) (xy 350.788029 -273.936969) (xy 350.839324 -273.945094) (xy 350.888717 -273.961142)
			(xy 350.934991 -273.98472) (xy 350.977007 -274.015246) (xy 351.01373 -274.051969) (xy 351.044256 -274.093985)
			(xy 351.067834 -274.140259) (xy 351.083882 -274.189652) (xy 351.092007 -274.240947) (xy 351.092516 -274.266914)
			(xy 351.371408 -274.266914) (xy 351.371917 -274.240947) (xy 351.380042 -274.189652) (xy 351.39609 -274.140259)
			(xy 351.419668 -274.093985) (xy 351.450194 -274.051969) (xy 351.486917 -274.015246) (xy 351.528933 -273.98472)
			(xy 351.575207 -273.961142) (xy 351.6246 -273.945094) (xy 351.675895 -273.936969) (xy 351.727829 -273.936969)
			(xy 351.779124 -273.945094) (xy 351.828517 -273.961142) (xy 351.874791 -273.98472) (xy 351.916807 -274.015246)
			(xy 351.95353 -274.051969) (xy 351.984056 -274.093985) (xy 352.007634 -274.140259) (xy 352.023682 -274.189652)
			(xy 352.031807 -274.240947) (xy 352.032316 -274.266914) (xy 352.031784 -274.292881) (xy 352.311717 -274.292881)
			(xy 352.311717 -274.240947) (xy 352.319842 -274.189652) (xy 352.33589 -274.140259) (xy 352.359468 -274.093985)
			(xy 352.389994 -274.051969) (xy 352.426717 -274.015246) (xy 352.468733 -273.98472) (xy 352.515007 -273.961142)
			(xy 352.5644 -273.945094) (xy 352.615695 -273.936969) (xy 352.667629 -273.936969) (xy 352.718924 -273.945094)
			(xy 352.768317 -273.961142) (xy 352.814591 -273.98472) (xy 352.856607 -274.015246) (xy 352.89333 -274.051969)
			(xy 352.923856 -274.093985) (xy 352.947434 -274.140259) (xy 352.963482 -274.189652) (xy 352.971607 -274.240947)
			(xy 352.972116 -274.266914) (xy 352.971607 -274.292881) (xy 353.251517 -274.292881) (xy 353.251517 -274.240947)
			(xy 353.259642 -274.189652) (xy 353.27569 -274.140259) (xy 353.299268 -274.093985) (xy 353.329794 -274.051969)
			(xy 353.366517 -274.015246) (xy 353.408533 -273.98472) (xy 353.454807 -273.961142) (xy 353.5042 -273.945094)
			(xy 353.555495 -273.936969) (xy 353.607429 -273.936969) (xy 353.658724 -273.945094) (xy 353.708117 -273.961142)
			(xy 353.754391 -273.98472) (xy 353.796407 -274.015246) (xy 353.83313 -274.051969) (xy 353.863656 -274.093985)
			(xy 353.887234 -274.140259) (xy 353.903282 -274.189652) (xy 353.911407 -274.240947) (xy 353.911916 -274.266914)
			(xy 353.911407 -274.292881) (xy 354.191317 -274.292881) (xy 354.191317 -274.240947) (xy 354.199442 -274.189652)
			(xy 354.21549 -274.140259) (xy 354.239068 -274.093985) (xy 354.269594 -274.051969) (xy 354.306317 -274.015246)
			(xy 354.348333 -273.98472) (xy 354.394607 -273.961142) (xy 354.444 -273.945094) (xy 354.495295 -273.936969)
			(xy 354.547229 -273.936969) (xy 354.598524 -273.945094) (xy 354.647917 -273.961142) (xy 354.694191 -273.98472)
			(xy 354.736207 -274.015246) (xy 354.77293 -274.051969) (xy 354.803456 -274.093985) (xy 354.827034 -274.140259)
			(xy 354.843082 -274.189652) (xy 354.851207 -274.240947) (xy 354.851716 -274.266914) (xy 354.851207 -274.292881)
			(xy 355.131117 -274.292881) (xy 355.131117 -274.240947) (xy 355.139242 -274.189652) (xy 355.15529 -274.140259)
			(xy 355.178868 -274.093985) (xy 355.209394 -274.051969) (xy 355.246117 -274.015246) (xy 355.288133 -273.98472)
			(xy 355.334407 -273.961142) (xy 355.3838 -273.945094) (xy 355.435095 -273.936969) (xy 355.487029 -273.936969)
			(xy 355.538324 -273.945094) (xy 355.587717 -273.961142) (xy 355.633991 -273.98472) (xy 355.676007 -274.015246)
			(xy 355.71273 -274.051969) (xy 355.743256 -274.093985) (xy 355.766834 -274.140259) (xy 355.782882 -274.189652)
			(xy 355.791007 -274.240947) (xy 355.791516 -274.266914) (xy 355.791007 -274.292881) (xy 356.071171 -274.292881)
			(xy 356.071171 -274.240947) (xy 356.079296 -274.189652) (xy 356.095344 -274.140259) (xy 356.118922 -274.093985)
			(xy 356.149448 -274.051969) (xy 356.186171 -274.015246) (xy 356.228187 -273.98472) (xy 356.274461 -273.961142)
			(xy 356.323854 -273.945094) (xy 356.375149 -273.936969) (xy 356.427083 -273.936969) (xy 356.478378 -273.945094)
			(xy 356.527771 -273.961142) (xy 356.574045 -273.98472) (xy 356.616061 -274.015246) (xy 356.652784 -274.051969)
			(xy 356.68331 -274.093985) (xy 356.706888 -274.140259) (xy 356.722936 -274.189652) (xy 356.731061 -274.240947)
			(xy 356.73157 -274.266914) (xy 356.731061 -274.292881) (xy 356.722936 -274.344176) (xy 356.706888 -274.393569)
			(xy 356.68331 -274.439843) (xy 356.652784 -274.481859) (xy 356.616061 -274.518582) (xy 356.574045 -274.549108)
			(xy 356.527771 -274.572686) (xy 356.478378 -274.588734) (xy 356.427083 -274.596859) (xy 356.375149 -274.596859)
			(xy 356.323854 -274.588734) (xy 356.274461 -274.572686) (xy 356.228187 -274.549108) (xy 356.186171 -274.518582)
			(xy 356.149448 -274.481859) (xy 356.118922 -274.439843) (xy 356.095344 -274.393569) (xy 356.079296 -274.344176)
			(xy 356.071171 -274.292881) (xy 355.791007 -274.292881) (xy 355.782882 -274.344176) (xy 355.766834 -274.393569)
			(xy 355.743256 -274.439843) (xy 355.71273 -274.481859) (xy 355.676007 -274.518582) (xy 355.633991 -274.549108)
			(xy 355.587717 -274.572686) (xy 355.538324 -274.588734) (xy 355.487029 -274.596859) (xy 355.435095 -274.596859)
			(xy 355.3838 -274.588734) (xy 355.334407 -274.572686) (xy 355.288133 -274.549108) (xy 355.246117 -274.518582)
			(xy 355.209394 -274.481859) (xy 355.178868 -274.439843) (xy 355.15529 -274.393569) (xy 355.139242 -274.344176)
			(xy 355.131117 -274.292881) (xy 354.851207 -274.292881) (xy 354.843082 -274.344176) (xy 354.827034 -274.393569)
			(xy 354.803456 -274.439843) (xy 354.77293 -274.481859) (xy 354.736207 -274.518582) (xy 354.694191 -274.549108)
			(xy 354.647917 -274.572686) (xy 354.598524 -274.588734) (xy 354.547229 -274.596859) (xy 354.495295 -274.596859)
			(xy 354.444 -274.588734) (xy 354.394607 -274.572686) (xy 354.348333 -274.549108) (xy 354.306317 -274.518582)
			(xy 354.269594 -274.481859) (xy 354.239068 -274.439843) (xy 354.21549 -274.393569) (xy 354.199442 -274.344176)
			(xy 354.191317 -274.292881) (xy 353.911407 -274.292881) (xy 353.903282 -274.344176) (xy 353.887234 -274.393569)
			(xy 353.863656 -274.439843) (xy 353.83313 -274.481859) (xy 353.796407 -274.518582) (xy 353.754391 -274.549108)
			(xy 353.708117 -274.572686) (xy 353.658724 -274.588734) (xy 353.607429 -274.596859) (xy 353.555495 -274.596859)
			(xy 353.5042 -274.588734) (xy 353.454807 -274.572686) (xy 353.408533 -274.549108) (xy 353.366517 -274.518582)
			(xy 353.329794 -274.481859) (xy 353.299268 -274.439843) (xy 353.27569 -274.393569) (xy 353.259642 -274.344176)
			(xy 353.251517 -274.292881) (xy 352.971607 -274.292881) (xy 352.963482 -274.344176) (xy 352.947434 -274.393569)
			(xy 352.923856 -274.439843) (xy 352.89333 -274.481859) (xy 352.856607 -274.518582) (xy 352.814591 -274.549108)
			(xy 352.768317 -274.572686) (xy 352.718924 -274.588734) (xy 352.667629 -274.596859) (xy 352.615695 -274.596859)
			(xy 352.5644 -274.588734) (xy 352.515007 -274.572686) (xy 352.468733 -274.549108) (xy 352.426717 -274.518582)
			(xy 352.389994 -274.481859) (xy 352.359468 -274.439843) (xy 352.33589 -274.393569) (xy 352.319842 -274.344176)
			(xy 352.311717 -274.292881) (xy 352.031784 -274.292881) (xy 352.031745 -274.294759) (xy 352.022431 -274.349663)
			(xy 352.013774 -274.376134) (xy 352.0059 -274.398232) (xy 352.209862 -274.751546) (xy 352.232976 -274.755864)
			(xy 352.257903 -274.761008) (xy 352.305887 -274.777977) (xy 352.350704 -274.802099) (xy 352.391295 -274.832803)
			(xy 352.426703 -274.869364) (xy 352.456091 -274.910919) (xy 352.478764 -274.956486) (xy 352.494187 -275.004989)
			(xy 352.501996 -275.055282) (xy 352.50247 -275.08073) (xy 352.501961 -275.106697) (xy 352.493836 -275.157992)
			(xy 352.477788 -275.207385) (xy 352.45421 -275.253659) (xy 352.423684 -275.295675) (xy 352.386961 -275.332398)
			(xy 352.344945 -275.362924) (xy 352.298671 -275.386502) (xy 352.249278 -275.40255) (xy 352.197983 -275.410675)
			(xy 352.146049 -275.410675) (xy 352.094754 -275.40255) (xy 352.045361 -275.386502) (xy 351.999087 -275.362924)
			(xy 351.957071 -275.332398) (xy 351.920348 -275.295675) (xy 351.889822 -275.253659) (xy 351.866244 -275.207385)
			(xy 351.850196 -275.157992) (xy 351.842071 -275.106697) (xy 351.841562 -275.08073) (xy 351.842119 -275.052744)
			(xy 351.851566 -274.997576) (xy 351.860358 -274.971002) (xy 351.867978 -274.948904) (xy 351.66427 -274.596098)
			(xy 351.64141 -274.59178) (xy 351.616463 -274.58661) (xy 351.568399 -274.569722) (xy 351.523497 -274.545656)
			(xy 351.482822 -274.514983) (xy 351.447337 -274.478431) (xy 351.417883 -274.436864) (xy 351.395158 -274.391269)
			(xy 351.379702 -274.342726) (xy 351.37188 -274.292386) (xy 351.371408 -274.266914) (xy 351.092516 -274.266914)
			(xy 351.092007 -274.292881) (xy 351.083882 -274.344176) (xy 351.067834 -274.393569) (xy 351.044256 -274.439843)
			(xy 351.01373 -274.481859) (xy 350.977007 -274.518582) (xy 350.934991 -274.549108) (xy 350.888717 -274.572686)
			(xy 350.839324 -274.588734) (xy 350.788029 -274.596859) (xy 350.736095 -274.596859) (xy 350.6848 -274.588734)
			(xy 350.635407 -274.572686) (xy 350.589133 -274.549108) (xy 350.547117 -274.518582) (xy 350.510394 -274.481859)
			(xy 350.479868 -274.439843) (xy 350.45629 -274.393569) (xy 350.440242 -274.344176) (xy 350.432117 -274.292881)
			(xy 350.152207 -274.292881) (xy 350.144082 -274.344176) (xy 350.128034 -274.393569) (xy 350.104456 -274.439843)
			(xy 350.07393 -274.481859) (xy 350.037207 -274.518582) (xy 349.995191 -274.549108) (xy 349.948917 -274.572686)
			(xy 349.899524 -274.588734) (xy 349.848229 -274.596859) (xy 349.796295 -274.596859) (xy 349.745 -274.588734)
			(xy 349.695607 -274.572686) (xy 349.649333 -274.549108) (xy 349.607317 -274.518582) (xy 349.570594 -274.481859)
			(xy 349.540068 -274.439843) (xy 349.51649 -274.393569) (xy 349.500442 -274.344176) (xy 349.492317 -274.292881)
			(xy 349.212407 -274.292881) (xy 349.204282 -274.344176) (xy 349.188234 -274.393569) (xy 349.164656 -274.439843)
			(xy 349.13413 -274.481859) (xy 349.097407 -274.518582) (xy 349.055391 -274.549108) (xy 349.009117 -274.572686)
			(xy 348.959724 -274.588734) (xy 348.908429 -274.596859) (xy 348.856495 -274.596859) (xy 348.8052 -274.588734)
			(xy 348.755807 -274.572686) (xy 348.709533 -274.549108) (xy 348.667517 -274.518582) (xy 348.630794 -274.481859)
			(xy 348.600268 -274.439843) (xy 348.57669 -274.393569) (xy 348.560642 -274.344176) (xy 348.552517 -274.292881)
			(xy 348.272607 -274.292881) (xy 348.264482 -274.344176) (xy 348.248434 -274.393569) (xy 348.224856 -274.439843)
			(xy 348.19433 -274.481859) (xy 348.157607 -274.518582) (xy 348.115591 -274.549108) (xy 348.069317 -274.572686)
			(xy 348.019924 -274.588734) (xy 347.968629 -274.596859) (xy 347.916695 -274.596859) (xy 347.8654 -274.588734)
			(xy 347.816007 -274.572686) (xy 347.769733 -274.549108) (xy 347.727717 -274.518582) (xy 347.690994 -274.481859)
			(xy 347.660468 -274.439843) (xy 347.63689 -274.393569) (xy 347.620842 -274.344176) (xy 347.612717 -274.292881)
			(xy 347.332807 -274.292881) (xy 347.324682 -274.344176) (xy 347.308634 -274.393569) (xy 347.285056 -274.439843)
			(xy 347.25453 -274.481859) (xy 347.217807 -274.518582) (xy 347.175791 -274.549108) (xy 347.129517 -274.572686)
			(xy 347.080124 -274.588734) (xy 347.028829 -274.596859) (xy 346.976895 -274.596859) (xy 346.9256 -274.588734)
			(xy 346.876207 -274.572686) (xy 346.829933 -274.549108) (xy 346.787917 -274.518582) (xy 346.751194 -274.481859)
			(xy 346.720668 -274.439843) (xy 346.69709 -274.393569) (xy 346.681042 -274.344176) (xy 346.672917 -274.292881)
			(xy 346.393007 -274.292881) (xy 346.384882 -274.344176) (xy 346.368834 -274.393569) (xy 346.345256 -274.439843)
			(xy 346.31473 -274.481859) (xy 346.278007 -274.518582) (xy 346.235991 -274.549108) (xy 346.189717 -274.572686)
			(xy 346.140324 -274.588734) (xy 346.089029 -274.596859) (xy 346.037095 -274.596859) (xy 345.9858 -274.588734)
			(xy 345.936407 -274.572686) (xy 345.890133 -274.549108) (xy 345.848117 -274.518582) (xy 345.811394 -274.481859)
			(xy 345.780868 -274.439843) (xy 345.75729 -274.393569) (xy 345.741242 -274.344176) (xy 345.733117 -274.292881)
			(xy 345.453207 -274.292881) (xy 345.445082 -274.344176) (xy 345.429034 -274.393569) (xy 345.405456 -274.439843)
			(xy 345.37493 -274.481859) (xy 345.338207 -274.518582) (xy 345.296191 -274.549108) (xy 345.249917 -274.572686)
			(xy 345.200524 -274.588734) (xy 345.149229 -274.596859) (xy 345.097295 -274.596859) (xy 345.046 -274.588734)
			(xy 344.996607 -274.572686) (xy 344.950333 -274.549108) (xy 344.908317 -274.518582) (xy 344.871594 -274.481859)
			(xy 344.841068 -274.439843) (xy 344.81749 -274.393569) (xy 344.801442 -274.344176) (xy 344.793317 -274.292881)
			(xy 344.557604 -274.292881) (xy 344.557604 -274.648676) (xy 344.558022 -274.661891) (xy 344.564804 -274.687436)
			(xy 344.577921 -274.710382) (xy 344.596491 -274.72919) (xy 344.619268 -274.742596) (xy 344.644725 -274.749703)
			(xy 344.657934 -274.750276) (xy 344.683676 -274.751106) (xy 344.734445 -274.759762) (xy 344.783256 -274.77619)
			(xy 344.828927 -274.799992) (xy 344.870354 -274.830591) (xy 344.906531 -274.867246) (xy 344.936584 -274.90907)
			(xy 344.959784 -274.955049) (xy 344.97557 -275.004072) (xy 344.98356 -275.05495) (xy 344.98356 -275.106451)
			(xy 344.983521 -275.106697) (xy 345.263471 -275.106697) (xy 345.263471 -275.054763) (xy 345.271596 -275.003468)
			(xy 345.287644 -274.954075) (xy 345.311222 -274.907801) (xy 345.341748 -274.865785) (xy 345.378471 -274.829062)
			(xy 345.420487 -274.798536) (xy 345.466761 -274.774958) (xy 345.516154 -274.75891) (xy 345.567449 -274.750785)
			(xy 345.619383 -274.750785) (xy 345.670678 -274.75891) (xy 345.720071 -274.774958) (xy 345.766345 -274.798536)
			(xy 345.808361 -274.829062) (xy 345.845084 -274.865785) (xy 345.87561 -274.907801) (xy 345.899188 -274.954075)
			(xy 345.915236 -275.003468) (xy 345.923361 -275.054763) (xy 345.92387 -275.08073) (xy 345.923361 -275.106697)
			(xy 346.203017 -275.106697) (xy 346.203017 -275.054763) (xy 346.211142 -275.003468) (xy 346.22719 -274.954075)
			(xy 346.250768 -274.907801) (xy 346.281294 -274.865785) (xy 346.318017 -274.829062) (xy 346.360033 -274.798536)
			(xy 346.406307 -274.774958) (xy 346.4557 -274.75891) (xy 346.506995 -274.750785) (xy 346.558929 -274.750785)
			(xy 346.610224 -274.75891) (xy 346.659617 -274.774958) (xy 346.705891 -274.798536) (xy 346.747907 -274.829062)
			(xy 346.78463 -274.865785) (xy 346.815156 -274.907801) (xy 346.838734 -274.954075) (xy 346.854782 -275.003468)
			(xy 346.862907 -275.054763) (xy 346.863416 -275.08073) (xy 346.862907 -275.106697) (xy 347.143071 -275.106697)
			(xy 347.143071 -275.054763) (xy 347.151196 -275.003468) (xy 347.167244 -274.954075) (xy 347.190822 -274.907801)
			(xy 347.221348 -274.865785) (xy 347.258071 -274.829062) (xy 347.300087 -274.798536) (xy 347.346361 -274.774958)
			(xy 347.395754 -274.75891) (xy 347.447049 -274.750785) (xy 347.498983 -274.750785) (xy 347.550278 -274.75891)
			(xy 347.599671 -274.774958) (xy 347.645945 -274.798536) (xy 347.687961 -274.829062) (xy 347.724684 -274.865785)
			(xy 347.75521 -274.907801) (xy 347.778788 -274.954075) (xy 347.794836 -275.003468) (xy 347.802961 -275.054763)
			(xy 347.80347 -275.08073) (xy 347.802961 -275.106697) (xy 348.082871 -275.106697) (xy 348.082871 -275.054763)
			(xy 348.090996 -275.003468) (xy 348.107044 -274.954075) (xy 348.130622 -274.907801) (xy 348.161148 -274.865785)
			(xy 348.197871 -274.829062) (xy 348.239887 -274.798536) (xy 348.286161 -274.774958) (xy 348.335554 -274.75891)
			(xy 348.386849 -274.750785) (xy 348.438783 -274.750785) (xy 348.490078 -274.75891) (xy 348.539471 -274.774958)
			(xy 348.585745 -274.798536) (xy 348.627761 -274.829062) (xy 348.664484 -274.865785) (xy 348.69501 -274.907801)
			(xy 348.718588 -274.954075) (xy 348.734636 -275.003468) (xy 348.742761 -275.054763) (xy 348.74327 -275.08073)
			(xy 348.742761 -275.106697) (xy 349.022671 -275.106697) (xy 349.022671 -275.054763) (xy 349.030796 -275.003468)
			(xy 349.046844 -274.954075) (xy 349.070422 -274.907801) (xy 349.100948 -274.865785) (xy 349.137671 -274.829062)
			(xy 349.179687 -274.798536) (xy 349.225961 -274.774958) (xy 349.275354 -274.75891) (xy 349.326649 -274.750785)
			(xy 349.378583 -274.750785) (xy 349.429878 -274.75891) (xy 349.479271 -274.774958) (xy 349.525545 -274.798536)
			(xy 349.567561 -274.829062) (xy 349.604284 -274.865785) (xy 349.63481 -274.907801) (xy 349.658388 -274.954075)
			(xy 349.674436 -275.003468) (xy 349.682561 -275.054763) (xy 349.68307 -275.08073) (xy 349.682562 -275.106668)
			(xy 349.962459 -275.106668) (xy 349.962459 -275.054732) (xy 349.970584 -275.003436) (xy 349.986633 -274.954043)
			(xy 350.010212 -274.907768) (xy 350.04074 -274.865752) (xy 350.077464 -274.829029) (xy 350.119482 -274.798503)
			(xy 350.165758 -274.774927) (xy 350.215152 -274.75888) (xy 350.266448 -274.750758) (xy 350.292416 -274.750276)
			(xy 350.318052 -274.750756) (xy 350.368707 -274.758683) (xy 350.417529 -274.774344) (xy 350.463343 -274.797362)
			(xy 350.50505 -274.827184) (xy 350.541646 -274.863094) (xy 350.557338 -274.883372) (xy 350.967294 -274.883372)
			(xy 350.982971 -274.863082) (xy 351.019571 -274.827174) (xy 351.06128 -274.797354) (xy 351.107098 -274.774339)
			(xy 351.155922 -274.758682) (xy 351.206579 -274.750759) (xy 351.232216 -274.750276) (xy 351.258185 -274.750727)
			(xy 351.309482 -274.758854) (xy 351.358877 -274.774905) (xy 351.405153 -274.798486) (xy 351.447171 -274.829015)
			(xy 351.483895 -274.865741) (xy 351.514423 -274.90776) (xy 351.538001 -274.954037) (xy 351.55405 -275.003433)
			(xy 351.562175 -275.054731) (xy 351.562175 -275.106669) (xy 351.55405 -275.157967) (xy 351.538001 -275.207363)
			(xy 351.514423 -275.25364) (xy 351.483895 -275.295659) (xy 351.447171 -275.332385) (xy 351.405153 -275.362914)
			(xy 351.358877 -275.386495) (xy 351.309482 -275.402546) (xy 351.258185 -275.410673) (xy 351.232216 -275.411184)
			(xy 351.20658 -275.410697) (xy 351.155924 -275.402774) (xy 351.107102 -275.387116) (xy 351.061287 -275.364099)
			(xy 351.019581 -275.334277) (xy 350.982985 -275.298367) (xy 350.967294 -275.278088) (xy 350.557338 -275.278088)
			(xy 350.541631 -275.298354) (xy 350.505039 -275.334266) (xy 350.463336 -275.36409) (xy 350.417524 -275.387109)
			(xy 350.368705 -275.402771) (xy 350.318051 -275.410698) (xy 350.292416 -275.411184) (xy 350.266448 -275.410642)
			(xy 350.215152 -275.40252) (xy 350.165758 -275.386473) (xy 350.119482 -275.362897) (xy 350.077464 -275.332371)
			(xy 350.04074 -275.295648) (xy 350.010212 -275.253632) (xy 349.986633 -275.207357) (xy 349.970584 -275.157964)
			(xy 349.962459 -275.106668) (xy 349.682562 -275.106668) (xy 349.682561 -275.106697) (xy 349.674436 -275.157992)
			(xy 349.658388 -275.207385) (xy 349.63481 -275.253659) (xy 349.604284 -275.295675) (xy 349.567561 -275.332398)
			(xy 349.525545 -275.362924) (xy 349.479271 -275.386502) (xy 349.429878 -275.40255) (xy 349.378583 -275.410675)
			(xy 349.326649 -275.410675) (xy 349.275354 -275.40255) (xy 349.225961 -275.386502) (xy 349.179687 -275.362924)
			(xy 349.137671 -275.332398) (xy 349.100948 -275.295675) (xy 349.070422 -275.253659) (xy 349.046844 -275.207385)
			(xy 349.030796 -275.157992) (xy 349.022671 -275.106697) (xy 348.742761 -275.106697) (xy 348.734636 -275.157992)
			(xy 348.718588 -275.207385) (xy 348.69501 -275.253659) (xy 348.664484 -275.295675) (xy 348.627761 -275.332398)
			(xy 348.585745 -275.362924) (xy 348.539471 -275.386502) (xy 348.490078 -275.40255) (xy 348.438783 -275.410675)
			(xy 348.386849 -275.410675) (xy 348.335554 -275.40255) (xy 348.286161 -275.386502) (xy 348.239887 -275.362924)
			(xy 348.197871 -275.332398) (xy 348.161148 -275.295675) (xy 348.130622 -275.253659) (xy 348.107044 -275.207385)
			(xy 348.090996 -275.157992) (xy 348.082871 -275.106697) (xy 347.802961 -275.106697) (xy 347.794836 -275.157992)
			(xy 347.778788 -275.207385) (xy 347.75521 -275.253659) (xy 347.724684 -275.295675) (xy 347.687961 -275.332398)
			(xy 347.645945 -275.362924) (xy 347.599671 -275.386502) (xy 347.550278 -275.40255) (xy 347.498983 -275.410675)
			(xy 347.447049 -275.410675) (xy 347.395754 -275.40255) (xy 347.346361 -275.386502) (xy 347.300087 -275.362924)
			(xy 347.258071 -275.332398) (xy 347.221348 -275.295675) (xy 347.190822 -275.253659) (xy 347.167244 -275.207385)
			(xy 347.151196 -275.157992) (xy 347.143071 -275.106697) (xy 346.862907 -275.106697) (xy 346.854782 -275.157992)
			(xy 346.838734 -275.207385) (xy 346.815156 -275.253659) (xy 346.78463 -275.295675) (xy 346.747907 -275.332398)
			(xy 346.705891 -275.362924) (xy 346.659617 -275.386502) (xy 346.610224 -275.40255) (xy 346.558929 -275.410675)
			(xy 346.506995 -275.410675) (xy 346.4557 -275.40255) (xy 346.406307 -275.386502) (xy 346.360033 -275.362924)
			(xy 346.318017 -275.332398) (xy 346.281294 -275.295675) (xy 346.250768 -275.253659) (xy 346.22719 -275.207385)
			(xy 346.211142 -275.157992) (xy 346.203017 -275.106697) (xy 345.923361 -275.106697) (xy 345.915236 -275.157992)
			(xy 345.899188 -275.207385) (xy 345.87561 -275.253659) (xy 345.845084 -275.295675) (xy 345.808361 -275.332398)
			(xy 345.766345 -275.362924) (xy 345.720071 -275.386502) (xy 345.670678 -275.40255) (xy 345.619383 -275.410675)
			(xy 345.567449 -275.410675) (xy 345.516154 -275.40255) (xy 345.466761 -275.386502) (xy 345.420487 -275.362924)
			(xy 345.378471 -275.332398) (xy 345.341748 -275.295675) (xy 345.311222 -275.253659) (xy 345.287644 -275.207385)
			(xy 345.271596 -275.157992) (xy 345.263471 -275.106697) (xy 344.983521 -275.106697) (xy 344.97557 -275.157329)
			(xy 344.959784 -275.206351) (xy 344.936583 -275.252331) (xy 344.90653 -275.294155) (xy 344.870353 -275.33081)
			(xy 344.828927 -275.361409) (xy 344.783255 -275.38521) (xy 344.734444 -275.401638) (xy 344.683675 -275.410294)
			(xy 344.657934 -275.411184) (xy 344.644725 -275.411769) (xy 344.619267 -275.418874) (xy 344.596487 -275.432278)
			(xy 344.577913 -275.451082) (xy 344.56479 -275.474025) (xy 344.557999 -275.499569) (xy 344.557604 -275.512784)
			(xy 344.557604 -275.920767) (xy 344.793317 -275.920767) (xy 344.793317 -275.868833) (xy 344.801442 -275.817538)
			(xy 344.81749 -275.768145) (xy 344.841068 -275.721871) (xy 344.871594 -275.679855) (xy 344.908317 -275.643132)
			(xy 344.950333 -275.612606) (xy 344.996607 -275.589028) (xy 345.046 -275.57298) (xy 345.097295 -275.564855)
			(xy 345.149229 -275.564855) (xy 345.200524 -275.57298) (xy 345.249917 -275.589028) (xy 345.296191 -275.612606)
			(xy 345.338207 -275.643132) (xy 345.37493 -275.679855) (xy 345.405456 -275.721871) (xy 345.429034 -275.768145)
			(xy 345.445082 -275.817538) (xy 345.453207 -275.868833) (xy 345.453716 -275.8948) (xy 345.453207 -275.920767)
			(xy 345.733117 -275.920767) (xy 345.733117 -275.868833) (xy 345.741242 -275.817538) (xy 345.75729 -275.768145)
			(xy 345.780868 -275.721871) (xy 345.811394 -275.679855) (xy 345.848117 -275.643132) (xy 345.890133 -275.612606)
			(xy 345.936407 -275.589028) (xy 345.9858 -275.57298) (xy 346.037095 -275.564855) (xy 346.089029 -275.564855)
			(xy 346.140324 -275.57298) (xy 346.189717 -275.589028) (xy 346.235991 -275.612606) (xy 346.278007 -275.643132)
			(xy 346.31473 -275.679855) (xy 346.345256 -275.721871) (xy 346.368834 -275.768145) (xy 346.384882 -275.817538)
			(xy 346.393007 -275.868833) (xy 346.393516 -275.8948) (xy 346.393007 -275.920767) (xy 346.672917 -275.920767)
			(xy 346.672917 -275.868833) (xy 346.681042 -275.817538) (xy 346.69709 -275.768145) (xy 346.720668 -275.721871)
			(xy 346.751194 -275.679855) (xy 346.787917 -275.643132) (xy 346.829933 -275.612606) (xy 346.876207 -275.589028)
			(xy 346.9256 -275.57298) (xy 346.976895 -275.564855) (xy 347.028829 -275.564855) (xy 347.080124 -275.57298)
			(xy 347.129517 -275.589028) (xy 347.175791 -275.612606) (xy 347.217807 -275.643132) (xy 347.25453 -275.679855)
			(xy 347.285056 -275.721871) (xy 347.308634 -275.768145) (xy 347.324682 -275.817538) (xy 347.332807 -275.868833)
			(xy 347.333316 -275.8948) (xy 347.332807 -275.920767) (xy 347.612717 -275.920767) (xy 347.612717 -275.868833)
			(xy 347.620842 -275.817538) (xy 347.63689 -275.768145) (xy 347.660468 -275.721871) (xy 347.690994 -275.679855)
			(xy 347.727717 -275.643132) (xy 347.769733 -275.612606) (xy 347.816007 -275.589028) (xy 347.8654 -275.57298)
			(xy 347.916695 -275.564855) (xy 347.968629 -275.564855) (xy 348.019924 -275.57298) (xy 348.069317 -275.589028)
			(xy 348.115591 -275.612606) (xy 348.157607 -275.643132) (xy 348.19433 -275.679855) (xy 348.224856 -275.721871)
			(xy 348.248434 -275.768145) (xy 348.264482 -275.817538) (xy 348.272607 -275.868833) (xy 348.273116 -275.8948)
			(xy 348.272607 -275.920767) (xy 348.552771 -275.920767) (xy 348.552771 -275.868833) (xy 348.560896 -275.817538)
			(xy 348.576944 -275.768145) (xy 348.600522 -275.721871) (xy 348.631048 -275.679855) (xy 348.667771 -275.643132)
			(xy 348.709787 -275.612606) (xy 348.756061 -275.589028) (xy 348.805454 -275.57298) (xy 348.856749 -275.564855)
			(xy 348.908683 -275.564855) (xy 348.959978 -275.57298) (xy 349.009371 -275.589028) (xy 349.055645 -275.612606)
			(xy 349.097661 -275.643132) (xy 349.134384 -275.679855) (xy 349.16491 -275.721871) (xy 349.188488 -275.768145)
			(xy 349.204536 -275.817538) (xy 349.212661 -275.868833) (xy 349.21317 -275.8948) (xy 349.212661 -275.920767)
			(xy 349.492317 -275.920767) (xy 349.492317 -275.868833) (xy 349.500442 -275.817538) (xy 349.51649 -275.768145)
			(xy 349.540068 -275.721871) (xy 349.570594 -275.679855) (xy 349.607317 -275.643132) (xy 349.649333 -275.612606)
			(xy 349.695607 -275.589028) (xy 349.745 -275.57298) (xy 349.796295 -275.564855) (xy 349.848229 -275.564855)
			(xy 349.899524 -275.57298) (xy 349.948917 -275.589028) (xy 349.995191 -275.612606) (xy 350.037207 -275.643132)
			(xy 350.07393 -275.679855) (xy 350.104456 -275.721871) (xy 350.128034 -275.768145) (xy 350.144082 -275.817538)
			(xy 350.152207 -275.868833) (xy 350.152716 -275.8948) (xy 350.152207 -275.920767) (xy 350.144082 -275.972062)
			(xy 350.128034 -276.021455) (xy 350.104456 -276.067729) (xy 350.07393 -276.109745) (xy 350.037207 -276.146468)
			(xy 349.995191 -276.176994) (xy 349.948917 -276.200572) (xy 349.899524 -276.21662) (xy 349.848229 -276.224745)
			(xy 349.796295 -276.224745) (xy 349.745 -276.21662) (xy 349.695607 -276.200572) (xy 349.649333 -276.176994)
			(xy 349.607317 -276.146468) (xy 349.570594 -276.109745) (xy 349.540068 -276.067729) (xy 349.51649 -276.021455)
			(xy 349.500442 -275.972062) (xy 349.492317 -275.920767) (xy 349.212661 -275.920767) (xy 349.204536 -275.972062)
			(xy 349.188488 -276.021455) (xy 349.16491 -276.067729) (xy 349.134384 -276.109745) (xy 349.097661 -276.146468)
			(xy 349.055645 -276.176994) (xy 349.009371 -276.200572) (xy 348.959978 -276.21662) (xy 348.908683 -276.224745)
			(xy 348.856749 -276.224745) (xy 348.805454 -276.21662) (xy 348.756061 -276.200572) (xy 348.709787 -276.176994)
			(xy 348.667771 -276.146468) (xy 348.631048 -276.109745) (xy 348.600522 -276.067729) (xy 348.576944 -276.021455)
			(xy 348.560896 -275.972062) (xy 348.552771 -275.920767) (xy 348.272607 -275.920767) (xy 348.264482 -275.972062)
			(xy 348.248434 -276.021455) (xy 348.224856 -276.067729) (xy 348.19433 -276.109745) (xy 348.157607 -276.146468)
			(xy 348.115591 -276.176994) (xy 348.069317 -276.200572) (xy 348.019924 -276.21662) (xy 347.968629 -276.224745)
			(xy 347.916695 -276.224745) (xy 347.8654 -276.21662) (xy 347.816007 -276.200572) (xy 347.769733 -276.176994)
			(xy 347.727717 -276.146468) (xy 347.690994 -276.109745) (xy 347.660468 -276.067729) (xy 347.63689 -276.021455)
			(xy 347.620842 -275.972062) (xy 347.612717 -275.920767) (xy 347.332807 -275.920767) (xy 347.324682 -275.972062)
			(xy 347.308634 -276.021455) (xy 347.285056 -276.067729) (xy 347.25453 -276.109745) (xy 347.217807 -276.146468)
			(xy 347.175791 -276.176994) (xy 347.129517 -276.200572) (xy 347.080124 -276.21662) (xy 347.028829 -276.224745)
			(xy 346.976895 -276.224745) (xy 346.9256 -276.21662) (xy 346.876207 -276.200572) (xy 346.829933 -276.176994)
			(xy 346.787917 -276.146468) (xy 346.751194 -276.109745) (xy 346.720668 -276.067729) (xy 346.69709 -276.021455)
			(xy 346.681042 -275.972062) (xy 346.672917 -275.920767) (xy 346.393007 -275.920767) (xy 346.384882 -275.972062)
			(xy 346.368834 -276.021455) (xy 346.345256 -276.067729) (xy 346.31473 -276.109745) (xy 346.278007 -276.146468)
			(xy 346.235991 -276.176994) (xy 346.189717 -276.200572) (xy 346.140324 -276.21662) (xy 346.089029 -276.224745)
			(xy 346.037095 -276.224745) (xy 345.9858 -276.21662) (xy 345.936407 -276.200572) (xy 345.890133 -276.176994)
			(xy 345.848117 -276.146468) (xy 345.811394 -276.109745) (xy 345.780868 -276.067729) (xy 345.75729 -276.021455)
			(xy 345.741242 -275.972062) (xy 345.733117 -275.920767) (xy 345.453207 -275.920767) (xy 345.445082 -275.972062)
			(xy 345.429034 -276.021455) (xy 345.405456 -276.067729) (xy 345.37493 -276.109745) (xy 345.338207 -276.146468)
			(xy 345.296191 -276.176994) (xy 345.249917 -276.200572) (xy 345.200524 -276.21662) (xy 345.149229 -276.224745)
			(xy 345.097295 -276.224745) (xy 345.046 -276.21662) (xy 344.996607 -276.200572) (xy 344.950333 -276.176994)
			(xy 344.908317 -276.146468) (xy 344.871594 -276.109745) (xy 344.841068 -276.067729) (xy 344.81749 -276.021455)
			(xy 344.801442 -275.972062) (xy 344.793317 -275.920767) (xy 344.557604 -275.920767) (xy 344.557604 -276.276562)
			(xy 344.55802 -276.289778) (xy 344.5648 -276.315326) (xy 344.577916 -276.338276) (xy 344.596486 -276.357086)
			(xy 344.619265 -276.370495) (xy 344.644724 -276.377602) (xy 344.657934 -276.378162) (xy 344.683677 -276.378992)
			(xy 344.734448 -276.387649) (xy 344.783261 -276.404077) (xy 344.828935 -276.42788) (xy 344.870363 -276.45848)
			(xy 344.906542 -276.495137) (xy 344.936596 -276.536962) (xy 344.959797 -276.582944) (xy 344.975584 -276.631968)
			(xy 344.983574 -276.682848) (xy 344.983574 -276.734352) (xy 344.983538 -276.734583) (xy 345.263217 -276.734583)
			(xy 345.263217 -276.682649) (xy 345.271342 -276.631354) (xy 345.28739 -276.581961) (xy 345.310968 -276.535687)
			(xy 345.341494 -276.493671) (xy 345.378217 -276.456948) (xy 345.420233 -276.426422) (xy 345.466507 -276.402844)
			(xy 345.5159 -276.386796) (xy 345.567195 -276.378671) (xy 345.619129 -276.378671) (xy 345.670424 -276.386796)
			(xy 345.719817 -276.402844) (xy 345.766091 -276.426422) (xy 345.808107 -276.456948) (xy 345.84483 -276.493671)
			(xy 345.875356 -276.535687) (xy 345.898934 -276.581961) (xy 345.914982 -276.631354) (xy 345.923107 -276.682649)
			(xy 345.923616 -276.708616) (xy 345.923107 -276.734583) (xy 346.203271 -276.734583) (xy 346.203271 -276.682649)
			(xy 346.211396 -276.631354) (xy 346.227444 -276.581961) (xy 346.251022 -276.535687) (xy 346.281548 -276.493671)
			(xy 346.318271 -276.456948) (xy 346.360287 -276.426422) (xy 346.406561 -276.402844) (xy 346.455954 -276.386796)
			(xy 346.507249 -276.378671) (xy 346.559183 -276.378671) (xy 346.610478 -276.386796) (xy 346.659871 -276.402844)
			(xy 346.706145 -276.426422) (xy 346.748161 -276.456948) (xy 346.784884 -276.493671) (xy 346.81541 -276.535687)
			(xy 346.838988 -276.581961) (xy 346.855036 -276.631354) (xy 346.863161 -276.682649) (xy 346.86367 -276.708616)
			(xy 346.863161 -276.734583) (xy 347.143071 -276.734583) (xy 347.143071 -276.682649) (xy 347.151196 -276.631354)
			(xy 347.167244 -276.581961) (xy 347.190822 -276.535687) (xy 347.221348 -276.493671) (xy 347.258071 -276.456948)
			(xy 347.300087 -276.426422) (xy 347.346361 -276.402844) (xy 347.395754 -276.386796) (xy 347.447049 -276.378671)
			(xy 347.498983 -276.378671) (xy 347.550278 -276.386796) (xy 347.599671 -276.402844) (xy 347.645945 -276.426422)
			(xy 347.687961 -276.456948) (xy 347.724684 -276.493671) (xy 347.75521 -276.535687) (xy 347.778788 -276.581961)
			(xy 347.794836 -276.631354) (xy 347.802961 -276.682649) (xy 347.80347 -276.708616) (xy 347.802961 -276.734583)
			(xy 348.082871 -276.734583) (xy 348.082871 -276.682649) (xy 348.090996 -276.631354) (xy 348.107044 -276.581961)
			(xy 348.130622 -276.535687) (xy 348.161148 -276.493671) (xy 348.197871 -276.456948) (xy 348.239887 -276.426422)
			(xy 348.286161 -276.402844) (xy 348.335554 -276.386796) (xy 348.386849 -276.378671) (xy 348.438783 -276.378671)
			(xy 348.490078 -276.386796) (xy 348.539471 -276.402844) (xy 348.585745 -276.426422) (xy 348.627761 -276.456948)
			(xy 348.664484 -276.493671) (xy 348.69501 -276.535687) (xy 348.718588 -276.581961) (xy 348.734636 -276.631354)
			(xy 348.742761 -276.682649) (xy 348.74327 -276.708616) (xy 348.742761 -276.734583) (xy 349.022671 -276.734583)
			(xy 349.022671 -276.682649) (xy 349.030796 -276.631354) (xy 349.046844 -276.581961) (xy 349.070422 -276.535687)
			(xy 349.100948 -276.493671) (xy 349.137671 -276.456948) (xy 349.179687 -276.426422) (xy 349.225961 -276.402844)
			(xy 349.275354 -276.386796) (xy 349.326649 -276.378671) (xy 349.378583 -276.378671) (xy 349.429878 -276.386796)
			(xy 349.479271 -276.402844) (xy 349.525545 -276.426422) (xy 349.567561 -276.456948) (xy 349.604284 -276.493671)
			(xy 349.63481 -276.535687) (xy 349.658388 -276.581961) (xy 349.674436 -276.631354) (xy 349.682561 -276.682649)
			(xy 349.68307 -276.708616) (xy 349.961708 -276.708616) (xy 349.96215 -276.683164) (xy 349.969939 -276.63286)
			(xy 349.985351 -276.584346) (xy 350.008021 -276.53877) (xy 350.037413 -276.497209) (xy 350.072832 -276.460648)
			(xy 350.113438 -276.429952) (xy 350.158272 -276.405846) (xy 350.206273 -276.388902) (xy 350.231202 -276.38375)
			(xy 350.254316 -276.379432) (xy 350.458024 -276.026372) (xy 350.450404 -276.004274) (xy 350.441653 -275.977755)
			(xy 350.432207 -275.92272) (xy 350.431608 -275.8948) (xy 350.432117 -275.868833) (xy 350.440242 -275.817538)
			(xy 350.45629 -275.768145) (xy 350.479868 -275.721871) (xy 350.510394 -275.679855) (xy 350.547117 -275.643132)
			(xy 350.589133 -275.612606) (xy 350.635407 -275.589028) (xy 350.6848 -275.57298) (xy 350.736095 -275.564855)
			(xy 350.788029 -275.564855) (xy 350.839324 -275.57298) (xy 350.888717 -275.589028) (xy 350.934991 -275.612606)
			(xy 350.977007 -275.643132) (xy 351.01373 -275.679855) (xy 351.044256 -275.721871) (xy 351.067834 -275.768145)
			(xy 351.083882 -275.817538) (xy 351.092007 -275.868833) (xy 351.092516 -275.8948) (xy 351.092022 -275.920262)
			(xy 351.091944 -275.920767) (xy 351.371917 -275.920767) (xy 351.371917 -275.868833) (xy 351.380042 -275.817538)
			(xy 351.39609 -275.768145) (xy 351.419668 -275.721871) (xy 351.450194 -275.679855) (xy 351.486917 -275.643132)
			(xy 351.528933 -275.612606) (xy 351.575207 -275.589028) (xy 351.6246 -275.57298) (xy 351.675895 -275.564855)
			(xy 351.727829 -275.564855) (xy 351.779124 -275.57298) (xy 351.828517 -275.589028) (xy 351.874791 -275.612606)
			(xy 351.916807 -275.643132) (xy 351.95353 -275.679855) (xy 351.984056 -275.721871) (xy 352.007634 -275.768145)
			(xy 352.023682 -275.817538) (xy 352.031807 -275.868833) (xy 352.032316 -275.8948) (xy 352.311208 -275.8948)
			(xy 352.311726 -275.869351) (xy 352.319503 -275.81905) (xy 352.334904 -275.770538) (xy 352.357563 -275.724961)
			(xy 352.386946 -275.683401) (xy 352.422355 -275.646838) (xy 352.462954 -275.61614) (xy 352.507781 -275.592033)
			(xy 352.555776 -275.575087) (xy 352.580702 -275.569934) (xy 352.603816 -275.565616) (xy 352.807778 -275.212302)
			(xy 352.799904 -275.190204) (xy 352.791244 -275.163668) (xy 352.781924 -275.108637) (xy 352.781362 -275.08073)
			(xy 352.781871 -275.054763) (xy 352.789996 -275.003468) (xy 352.806044 -274.954075) (xy 352.829622 -274.907801)
			(xy 352.860148 -274.865785) (xy 352.896871 -274.829062) (xy 352.938887 -274.798536) (xy 352.985161 -274.774958)
			(xy 353.034554 -274.75891) (xy 353.085849 -274.750785) (xy 353.137783 -274.750785) (xy 353.189078 -274.75891)
			(xy 353.238471 -274.774958) (xy 353.284745 -274.798536) (xy 353.326761 -274.829062) (xy 353.363484 -274.865785)
			(xy 353.39401 -274.907801) (xy 353.417588 -274.954075) (xy 353.433636 -275.003468) (xy 353.441761 -275.054763)
			(xy 353.44227 -275.08073) (xy 353.44184 -275.106194) (xy 353.441762 -275.106697) (xy 353.721417 -275.106697)
			(xy 353.721417 -275.054763) (xy 353.729542 -275.003468) (xy 353.74559 -274.954075) (xy 353.769168 -274.907801)
			(xy 353.799694 -274.865785) (xy 353.836417 -274.829062) (xy 353.878433 -274.798536) (xy 353.924707 -274.774958)
			(xy 353.9741 -274.75891) (xy 354.025395 -274.750785) (xy 354.077329 -274.750785) (xy 354.128624 -274.75891)
			(xy 354.178017 -274.774958) (xy 354.224291 -274.798536) (xy 354.266307 -274.829062) (xy 354.30303 -274.865785)
			(xy 354.333556 -274.907801) (xy 354.357134 -274.954075) (xy 354.373182 -275.003468) (xy 354.381307 -275.054763)
			(xy 354.381816 -275.08073) (xy 354.381307 -275.106697) (xy 354.661471 -275.106697) (xy 354.661471 -275.054763)
			(xy 354.669596 -275.003468) (xy 354.685644 -274.954075) (xy 354.709222 -274.907801) (xy 354.739748 -274.865785)
			(xy 354.776471 -274.829062) (xy 354.818487 -274.798536) (xy 354.864761 -274.774958) (xy 354.914154 -274.75891)
			(xy 354.965449 -274.750785) (xy 355.017383 -274.750785) (xy 355.068678 -274.75891) (xy 355.118071 -274.774958)
			(xy 355.164345 -274.798536) (xy 355.206361 -274.829062) (xy 355.243084 -274.865785) (xy 355.27361 -274.907801)
			(xy 355.297188 -274.954075) (xy 355.313236 -275.003468) (xy 355.321361 -275.054763) (xy 355.32187 -275.08073)
			(xy 355.600762 -275.08073) (xy 355.601271 -275.054763) (xy 355.609396 -275.003468) (xy 355.625444 -274.954075)
			(xy 355.649022 -274.907801) (xy 355.679548 -274.865785) (xy 355.716271 -274.829062) (xy 355.758287 -274.798536)
			(xy 355.804561 -274.774958) (xy 355.853954 -274.75891) (xy 355.905249 -274.750785) (xy 355.957183 -274.750785)
			(xy 356.008478 -274.75891) (xy 356.057871 -274.774958) (xy 356.104145 -274.798536) (xy 356.146161 -274.829062)
			(xy 356.182884 -274.865785) (xy 356.21341 -274.907801) (xy 356.236988 -274.954075) (xy 356.253036 -275.003468)
			(xy 356.261161 -275.054763) (xy 356.26167 -275.08073) (xy 356.261165 -275.106697) (xy 356.540817 -275.106697)
			(xy 356.540817 -275.054763) (xy 356.548942 -275.003468) (xy 356.56499 -274.954075) (xy 356.588568 -274.907801)
			(xy 356.619094 -274.865785) (xy 356.655817 -274.829062) (xy 356.697833 -274.798536) (xy 356.744107 -274.774958)
			(xy 356.7935 -274.75891) (xy 356.844795 -274.750785) (xy 356.896729 -274.750785) (xy 356.948024 -274.75891)
			(xy 356.997417 -274.774958) (xy 357.043691 -274.798536) (xy 357.085707 -274.829062) (xy 357.12243 -274.865785)
			(xy 357.152956 -274.907801) (xy 357.176534 -274.954075) (xy 357.192582 -275.003468) (xy 357.200707 -275.054763)
			(xy 357.201216 -275.08073) (xy 357.200707 -275.106697) (xy 357.480617 -275.106697) (xy 357.480617 -275.054763)
			(xy 357.488742 -275.003468) (xy 357.50479 -274.954075) (xy 357.528368 -274.907801) (xy 357.558894 -274.865785)
			(xy 357.595617 -274.829062) (xy 357.637633 -274.798536) (xy 357.683907 -274.774958) (xy 357.7333 -274.75891)
			(xy 357.784595 -274.750785) (xy 357.836529 -274.750785) (xy 357.887824 -274.75891) (xy 357.937217 -274.774958)
			(xy 357.983491 -274.798536) (xy 358.025507 -274.829062) (xy 358.06223 -274.865785) (xy 358.092756 -274.907801)
			(xy 358.116334 -274.954075) (xy 358.132382 -275.003468) (xy 358.140507 -275.054763) (xy 358.141016 -275.08073)
			(xy 358.140507 -275.106697) (xy 361.239817 -275.106697) (xy 361.239817 -275.054763) (xy 361.247942 -275.003468)
			(xy 361.26399 -274.954075) (xy 361.287568 -274.907801) (xy 361.318094 -274.865785) (xy 361.354817 -274.829062)
			(xy 361.396833 -274.798536) (xy 361.443107 -274.774958) (xy 361.4925 -274.75891) (xy 361.543795 -274.750785)
			(xy 361.595729 -274.750785) (xy 361.647024 -274.75891) (xy 361.696417 -274.774958) (xy 361.742691 -274.798536)
			(xy 361.784707 -274.829062) (xy 361.82143 -274.865785) (xy 361.851956 -274.907801) (xy 361.875534 -274.954075)
			(xy 361.891582 -275.003468) (xy 361.899707 -275.054763) (xy 361.900216 -275.08073) (xy 361.899707 -275.106697)
			(xy 362.179363 -275.106697) (xy 362.179363 -275.054763) (xy 362.187488 -275.003468) (xy 362.203536 -274.954075)
			(xy 362.227114 -274.907801) (xy 362.25764 -274.865785) (xy 362.294363 -274.829062) (xy 362.336379 -274.798536)
			(xy 362.382653 -274.774958) (xy 362.432046 -274.75891) (xy 362.483341 -274.750785) (xy 362.535275 -274.750785)
			(xy 362.58657 -274.75891) (xy 362.635963 -274.774958) (xy 362.682237 -274.798536) (xy 362.724253 -274.829062)
			(xy 362.760976 -274.865785) (xy 362.791502 -274.907801) (xy 362.81508 -274.954075) (xy 362.831128 -275.003468)
			(xy 362.839253 -275.054763) (xy 362.839762 -275.08073) (xy 362.839253 -275.106697) (xy 363.119163 -275.106697)
			(xy 363.119163 -275.054763) (xy 363.127288 -275.003468) (xy 363.143336 -274.954075) (xy 363.166914 -274.907801)
			(xy 363.19744 -274.865785) (xy 363.234163 -274.829062) (xy 363.276179 -274.798536) (xy 363.322453 -274.774958)
			(xy 363.371846 -274.75891) (xy 363.423141 -274.750785) (xy 363.475075 -274.750785) (xy 363.52637 -274.75891)
			(xy 363.575763 -274.774958) (xy 363.622037 -274.798536) (xy 363.664053 -274.829062) (xy 363.700776 -274.865785)
			(xy 363.731302 -274.907801) (xy 363.75488 -274.954075) (xy 363.770928 -275.003468) (xy 363.779053 -275.054763)
			(xy 363.779562 -275.08073) (xy 363.779053 -275.106697) (xy 364.059217 -275.106697) (xy 364.059217 -275.054763)
			(xy 364.067342 -275.003468) (xy 364.08339 -274.954075) (xy 364.106968 -274.907801) (xy 364.137494 -274.865785)
			(xy 364.174217 -274.829062) (xy 364.216233 -274.798536) (xy 364.262507 -274.774958) (xy 364.3119 -274.75891)
			(xy 364.363195 -274.750785) (xy 364.415129 -274.750785) (xy 364.466424 -274.75891) (xy 364.515817 -274.774958)
			(xy 364.562091 -274.798536) (xy 364.604107 -274.829062) (xy 364.64083 -274.865785) (xy 364.671356 -274.907801)
			(xy 364.694934 -274.954075) (xy 364.710982 -275.003468) (xy 364.719107 -275.054763) (xy 364.719616 -275.08073)
			(xy 364.719107 -275.106697) (xy 364.710982 -275.157992) (xy 364.694934 -275.207385) (xy 364.671356 -275.253659)
			(xy 364.64083 -275.295675) (xy 364.604107 -275.332398) (xy 364.562091 -275.362924) (xy 364.515817 -275.386502)
			(xy 364.466424 -275.40255) (xy 364.415129 -275.410675) (xy 364.363195 -275.410675) (xy 364.3119 -275.40255)
			(xy 364.262507 -275.386502) (xy 364.216233 -275.362924) (xy 364.174217 -275.332398) (xy 364.137494 -275.295675)
			(xy 364.106968 -275.253659) (xy 364.08339 -275.207385) (xy 364.067342 -275.157992) (xy 364.059217 -275.106697)
			(xy 363.779053 -275.106697) (xy 363.770928 -275.157992) (xy 363.75488 -275.207385) (xy 363.731302 -275.253659)
			(xy 363.700776 -275.295675) (xy 363.664053 -275.332398) (xy 363.622037 -275.362924) (xy 363.575763 -275.386502)
			(xy 363.52637 -275.40255) (xy 363.475075 -275.410675) (xy 363.423141 -275.410675) (xy 363.371846 -275.40255)
			(xy 363.322453 -275.386502) (xy 363.276179 -275.362924) (xy 363.234163 -275.332398) (xy 363.19744 -275.295675)
			(xy 363.166914 -275.253659) (xy 363.143336 -275.207385) (xy 363.127288 -275.157992) (xy 363.119163 -275.106697)
			(xy 362.839253 -275.106697) (xy 362.831128 -275.157992) (xy 362.81508 -275.207385) (xy 362.791502 -275.253659)
			(xy 362.760976 -275.295675) (xy 362.724253 -275.332398) (xy 362.682237 -275.362924) (xy 362.635963 -275.386502)
			(xy 362.58657 -275.40255) (xy 362.535275 -275.410675) (xy 362.483341 -275.410675) (xy 362.432046 -275.40255)
			(xy 362.382653 -275.386502) (xy 362.336379 -275.362924) (xy 362.294363 -275.332398) (xy 362.25764 -275.295675)
			(xy 362.227114 -275.253659) (xy 362.203536 -275.207385) (xy 362.187488 -275.157992) (xy 362.179363 -275.106697)
			(xy 361.899707 -275.106697) (xy 361.891582 -275.157992) (xy 361.875534 -275.207385) (xy 361.851956 -275.253659)
			(xy 361.82143 -275.295675) (xy 361.784707 -275.332398) (xy 361.742691 -275.362924) (xy 361.696417 -275.386502)
			(xy 361.647024 -275.40255) (xy 361.595729 -275.410675) (xy 361.543795 -275.410675) (xy 361.4925 -275.40255)
			(xy 361.443107 -275.386502) (xy 361.396833 -275.362924) (xy 361.354817 -275.332398) (xy 361.318094 -275.295675)
			(xy 361.287568 -275.253659) (xy 361.26399 -275.207385) (xy 361.247942 -275.157992) (xy 361.239817 -275.106697)
			(xy 358.140507 -275.106697) (xy 358.132382 -275.157992) (xy 358.116334 -275.207385) (xy 358.092756 -275.253659)
			(xy 358.06223 -275.295675) (xy 358.025507 -275.332398) (xy 357.983491 -275.362924) (xy 357.937217 -275.386502)
			(xy 357.887824 -275.40255) (xy 357.836529 -275.410675) (xy 357.784595 -275.410675) (xy 357.7333 -275.40255)
			(xy 357.683907 -275.386502) (xy 357.637633 -275.362924) (xy 357.595617 -275.332398) (xy 357.558894 -275.295675)
			(xy 357.528368 -275.253659) (xy 357.50479 -275.207385) (xy 357.488742 -275.157992) (xy 357.480617 -275.106697)
			(xy 357.200707 -275.106697) (xy 357.192582 -275.157992) (xy 357.176534 -275.207385) (xy 357.152956 -275.253659)
			(xy 357.12243 -275.295675) (xy 357.085707 -275.332398) (xy 357.043691 -275.362924) (xy 356.997417 -275.386502)
			(xy 356.948024 -275.40255) (xy 356.896729 -275.410675) (xy 356.844795 -275.410675) (xy 356.7935 -275.40255)
			(xy 356.744107 -275.386502) (xy 356.697833 -275.362924) (xy 356.655817 -275.332398) (xy 356.619094 -275.295675)
			(xy 356.588568 -275.253659) (xy 356.56499 -275.207385) (xy 356.548942 -275.157992) (xy 356.540817 -275.106697)
			(xy 356.261165 -275.106697) (xy 356.261126 -275.108716) (xy 356.25167 -275.163884) (xy 356.242874 -275.190458)
			(xy 356.235254 -275.212556) (xy 356.438962 -275.565616) (xy 356.462076 -275.569934) (xy 356.486996 -275.575106)
			(xy 356.534978 -275.592073) (xy 356.579793 -275.616192) (xy 356.620384 -275.646893) (xy 356.655792 -275.68345)
			(xy 356.68518 -275.725001) (xy 356.707855 -275.770564) (xy 356.723281 -275.819063) (xy 356.731094 -275.869353)
			(xy 356.73157 -275.8948) (xy 356.731061 -275.920767) (xy 356.722936 -275.972062) (xy 356.706888 -276.021455)
			(xy 356.68331 -276.067729) (xy 356.652784 -276.109745) (xy 356.616061 -276.146468) (xy 356.574045 -276.176994)
			(xy 356.527771 -276.200572) (xy 356.478378 -276.21662) (xy 356.427083 -276.224745) (xy 356.375149 -276.224745)
			(xy 356.323854 -276.21662) (xy 356.274461 -276.200572) (xy 356.228187 -276.176994) (xy 356.186171 -276.146468)
			(xy 356.149448 -276.109745) (xy 356.118922 -276.067729) (xy 356.095344 -276.021455) (xy 356.079296 -275.972062)
			(xy 356.071171 -275.920767) (xy 356.070662 -275.8948) (xy 356.071211 -275.866814) (xy 356.080663 -275.811646)
			(xy 356.089458 -275.785072) (xy 356.097078 -275.762974) (xy 355.89337 -275.409914) (xy 355.870256 -275.405596)
			(xy 355.845325 -275.400467) (xy 355.797339 -275.383499) (xy 355.752519 -275.359378) (xy 355.711925 -275.328673)
			(xy 355.676516 -275.29211) (xy 355.647129 -275.250552) (xy 355.624458 -275.204982) (xy 355.609037 -275.156476)
			(xy 355.601233 -275.106179) (xy 355.600762 -275.08073) (xy 355.32187 -275.08073) (xy 355.321361 -275.106697)
			(xy 355.313236 -275.157992) (xy 355.297188 -275.207385) (xy 355.27361 -275.253659) (xy 355.243084 -275.295675)
			(xy 355.206361 -275.332398) (xy 355.164345 -275.362924) (xy 355.118071 -275.386502) (xy 355.068678 -275.40255)
			(xy 355.017383 -275.410675) (xy 354.965449 -275.410675) (xy 354.914154 -275.40255) (xy 354.864761 -275.386502)
			(xy 354.818487 -275.362924) (xy 354.776471 -275.332398) (xy 354.739748 -275.295675) (xy 354.709222 -275.253659)
			(xy 354.685644 -275.207385) (xy 354.669596 -275.157992) (xy 354.661471 -275.106697) (xy 354.381307 -275.106697)
			(xy 354.373182 -275.157992) (xy 354.357134 -275.207385) (xy 354.333556 -275.253659) (xy 354.30303 -275.295675)
			(xy 354.266307 -275.332398) (xy 354.224291 -275.362924) (xy 354.178017 -275.386502) (xy 354.128624 -275.40255)
			(xy 354.077329 -275.410675) (xy 354.025395 -275.410675) (xy 353.9741 -275.40255) (xy 353.924707 -275.386502)
			(xy 353.878433 -275.362924) (xy 353.836417 -275.332398) (xy 353.799694 -275.295675) (xy 353.769168 -275.253659)
			(xy 353.74559 -275.207385) (xy 353.729542 -275.157992) (xy 353.721417 -275.106697) (xy 353.441762 -275.106697)
			(xy 353.434036 -275.156521) (xy 353.418602 -275.205055) (xy 353.395903 -275.250645) (xy 353.366478 -275.292213)
			(xy 353.331023 -275.328773) (xy 353.290378 -275.35946) (xy 353.245505 -275.383546) (xy 353.197468 -275.400462)
			(xy 353.172522 -275.405596) (xy 353.149408 -275.409914) (xy 352.9457 -275.762974) (xy 352.95332 -275.785072)
			(xy 352.962052 -275.811662) (xy 352.971503 -275.86682) (xy 352.972116 -275.8948) (xy 352.971607 -275.920767)
			(xy 353.251771 -275.920767) (xy 353.251771 -275.868833) (xy 353.259896 -275.817538) (xy 353.275944 -275.768145)
			(xy 353.299522 -275.721871) (xy 353.330048 -275.679855) (xy 353.366771 -275.643132) (xy 353.408787 -275.612606)
			(xy 353.455061 -275.589028) (xy 353.504454 -275.57298) (xy 353.555749 -275.564855) (xy 353.607683 -275.564855)
			(xy 353.658978 -275.57298) (xy 353.708371 -275.589028) (xy 353.754645 -275.612606) (xy 353.796661 -275.643132)
			(xy 353.833384 -275.679855) (xy 353.86391 -275.721871) (xy 353.887488 -275.768145) (xy 353.903536 -275.817538)
			(xy 353.911661 -275.868833) (xy 353.91217 -275.8948) (xy 353.911661 -275.920765) (xy 354.191355 -275.920765)
			(xy 354.191355 -275.868835) (xy 354.199478 -275.817543) (xy 354.215525 -275.768154) (xy 354.239099 -275.721883)
			(xy 354.269621 -275.679868) (xy 354.30634 -275.643146) (xy 354.34835 -275.612619) (xy 354.394619 -275.589039)
			(xy 354.444006 -275.572987) (xy 354.495297 -275.564858) (xy 354.521262 -275.564346) (xy 354.546884 -275.564818)
			(xy 354.597512 -275.572743) (xy 354.646312 -275.588379) (xy 354.692119 -275.611352) (xy 354.733835 -275.641112)
			(xy 354.770465 -275.676948) (xy 354.786184 -275.697188) (xy 355.19614 -275.697188) (xy 355.211851 -275.67694)
			(xy 355.248471 -275.641089) (xy 355.290186 -275.611321) (xy 355.335996 -275.58835) (xy 355.384804 -275.572726)
			(xy 355.435438 -275.564824) (xy 355.461062 -275.564346) (xy 355.487033 -275.564826) (xy 355.538337 -275.572946)
			(xy 355.587739 -275.588993) (xy 355.634021 -275.61257) (xy 355.676046 -275.643098) (xy 355.712777 -275.679825)
			(xy 355.74331 -275.721846) (xy 355.766893 -275.768126) (xy 355.782945 -275.817526) (xy 355.791071 -275.868829)
			(xy 355.791071 -275.920771) (xy 355.782945 -275.972074) (xy 355.766893 -276.021474) (xy 355.74331 -276.067754)
			(xy 355.712777 -276.109775) (xy 355.676046 -276.146502) (xy 355.634021 -276.17703) (xy 355.587739 -276.200607)
			(xy 355.538337 -276.216654) (xy 355.487033 -276.224774) (xy 355.461062 -276.225254) (xy 355.435441 -276.224765)
			(xy 355.384814 -276.216843) (xy 355.336014 -276.20121) (xy 355.290207 -276.178241) (xy 355.24849 -276.148484)
			(xy 355.211859 -276.112651) (xy 355.19614 -276.092412) (xy 354.786184 -276.092412) (xy 354.770459 -276.112648)
			(xy 354.733842 -276.1485) (xy 354.69213 -276.178269) (xy 354.646322 -276.201243) (xy 354.597517 -276.216869)
			(xy 354.546885 -276.224775) (xy 354.521262 -276.225254) (xy 354.495297 -276.224742) (xy 354.444006 -276.216613)
			(xy 354.394619 -276.200561) (xy 354.34835 -276.176981) (xy 354.30634 -276.146454) (xy 354.269621 -276.109732)
			(xy 354.239099 -276.067717) (xy 354.215525 -276.021446) (xy 354.199478 -275.972057) (xy 354.191355 -275.920765)
			(xy 353.911661 -275.920765) (xy 353.911661 -275.920767) (xy 353.903536 -275.972062) (xy 353.887488 -276.021455)
			(xy 353.86391 -276.067729) (xy 353.833384 -276.109745) (xy 353.796661 -276.146468) (xy 353.754645 -276.176994)
			(xy 353.708371 -276.200572) (xy 353.658978 -276.21662) (xy 353.607683 -276.224745) (xy 353.555749 -276.224745)
			(xy 353.504454 -276.21662) (xy 353.455061 -276.200572) (xy 353.408787 -276.176994) (xy 353.366771 -276.146468)
			(xy 353.330048 -276.109745) (xy 353.299522 -276.067729) (xy 353.275944 -276.021455) (xy 353.259896 -275.972062)
			(xy 353.251771 -275.920767) (xy 352.971607 -275.920767) (xy 352.963482 -275.972062) (xy 352.947434 -276.021455)
			(xy 352.923856 -276.067729) (xy 352.89333 -276.109745) (xy 352.856607 -276.146468) (xy 352.814591 -276.176994)
			(xy 352.768317 -276.200572) (xy 352.718924 -276.21662) (xy 352.667629 -276.224745) (xy 352.615695 -276.224745)
			(xy 352.5644 -276.21662) (xy 352.515007 -276.200572) (xy 352.468733 -276.176994) (xy 352.426717 -276.146468)
			(xy 352.389994 -276.109745) (xy 352.359468 -276.067729) (xy 352.33589 -276.021455) (xy 352.319842 -275.972062)
			(xy 352.311717 -275.920767) (xy 352.311208 -275.8948) (xy 352.032316 -275.8948) (xy 352.031807 -275.920767)
			(xy 352.023682 -275.972062) (xy 352.007634 -276.021455) (xy 351.984056 -276.067729) (xy 351.95353 -276.109745)
			(xy 351.916807 -276.146468) (xy 351.874791 -276.176994) (xy 351.828517 -276.200572) (xy 351.779124 -276.21662)
			(xy 351.727829 -276.224745) (xy 351.675895 -276.224745) (xy 351.6246 -276.21662) (xy 351.575207 -276.200572)
			(xy 351.528933 -276.176994) (xy 351.486917 -276.146468) (xy 351.450194 -276.109745) (xy 351.419668 -276.067729)
			(xy 351.39609 -276.021455) (xy 351.380042 -275.972062) (xy 351.371917 -275.920767) (xy 351.091944 -275.920767)
			(xy 351.084223 -275.970584) (xy 351.068796 -276.019114) (xy 351.046105 -276.064702) (xy 351.016688 -276.106268)
			(xy 350.981241 -276.142829) (xy 350.940604 -276.173518) (xy 350.89574 -276.197608) (xy 350.84771 -276.214528)
			(xy 350.822768 -276.219666) (xy 350.799908 -276.223984) (xy 350.5962 -276.57679) (xy 350.60382 -276.598888)
			(xy 350.612555 -276.625477) (xy 350.622004 -276.680636) (xy 350.622616 -276.708616) (xy 350.901762 -276.708616)
			(xy 350.902271 -276.682649) (xy 350.910396 -276.631354) (xy 350.926444 -276.581961) (xy 350.950022 -276.535687)
			(xy 350.980548 -276.493671) (xy 351.017271 -276.456948) (xy 351.059287 -276.426422) (xy 351.105561 -276.402844)
			(xy 351.154954 -276.386796) (xy 351.206249 -276.378671) (xy 351.258183 -276.378671) (xy 351.309478 -276.386796)
			(xy 351.358871 -276.402844) (xy 351.405145 -276.426422) (xy 351.447161 -276.456948) (xy 351.483884 -276.493671)
			(xy 351.51441 -276.535687) (xy 351.537988 -276.581961) (xy 351.554036 -276.631354) (xy 351.562161 -276.682649)
			(xy 351.56267 -276.708616) (xy 351.562163 -276.734569) (xy 351.842045 -276.734569) (xy 351.842045 -276.682631)
			(xy 351.85017 -276.631333) (xy 351.86622 -276.581937) (xy 351.8898 -276.535661) (xy 351.920329 -276.493643)
			(xy 351.957055 -276.456919) (xy 351.999075 -276.426392) (xy 352.045352 -276.402814) (xy 352.094749 -276.386766)
			(xy 352.146047 -276.378644) (xy 352.172016 -276.378162) (xy 352.197635 -276.378701) (xy 352.248258 -276.386617)
			(xy 352.297056 -276.402242) (xy 352.342862 -276.425202) (xy 352.384581 -276.454949) (xy 352.421216 -276.490771)
			(xy 352.436938 -276.511004) (xy 352.846894 -276.511004) (xy 352.862636 -276.490782) (xy 352.899249 -276.454928)
			(xy 352.940957 -276.425157) (xy 352.986762 -276.402181) (xy 353.035564 -276.386551) (xy 353.086194 -276.378643)
			(xy 353.111816 -276.378162) (xy 353.137784 -276.37864) (xy 353.189079 -276.386767) (xy 353.238472 -276.402818)
			(xy 353.284746 -276.426398) (xy 353.326762 -276.456926) (xy 353.363485 -276.493651) (xy 353.394011 -276.535668)
			(xy 353.417588 -276.581943) (xy 353.433637 -276.631336) (xy 353.441761 -276.682632) (xy 353.441761 -276.734568)
			(xy 353.441759 -276.734583) (xy 353.721417 -276.734583) (xy 353.721417 -276.682649) (xy 353.729542 -276.631354)
			(xy 353.74559 -276.581961) (xy 353.769168 -276.535687) (xy 353.799694 -276.493671) (xy 353.836417 -276.456948)
			(xy 353.878433 -276.426422) (xy 353.924707 -276.402844) (xy 353.9741 -276.386796) (xy 354.025395 -276.378671)
			(xy 354.077329 -276.378671) (xy 354.128624 -276.386796) (xy 354.178017 -276.402844) (xy 354.224291 -276.426422)
			(xy 354.266307 -276.456948) (xy 354.30303 -276.493671) (xy 354.333556 -276.535687) (xy 354.357134 -276.581961)
			(xy 354.373182 -276.631354) (xy 354.381307 -276.682649) (xy 354.381816 -276.708616) (xy 354.381307 -276.734583)
			(xy 354.373182 -276.785878) (xy 354.357134 -276.835271) (xy 354.333556 -276.881545) (xy 354.30303 -276.923561)
			(xy 354.266307 -276.960284) (xy 354.224291 -276.99081) (xy 354.178017 -277.014388) (xy 354.128624 -277.030436)
			(xy 354.077329 -277.038561) (xy 354.025395 -277.038561) (xy 353.9741 -277.030436) (xy 353.924707 -277.014388)
			(xy 353.878433 -276.99081) (xy 353.836417 -276.960284) (xy 353.799694 -276.923561) (xy 353.769168 -276.881545)
			(xy 353.74559 -276.835271) (xy 353.729542 -276.785878) (xy 353.721417 -276.734583) (xy 353.441759 -276.734583)
			(xy 353.433637 -276.785864) (xy 353.417588 -276.835257) (xy 353.394011 -276.881532) (xy 353.363485 -276.923549)
			(xy 353.326762 -276.960274) (xy 353.284746 -276.990802) (xy 353.238472 -277.014382) (xy 353.189079 -277.030433)
			(xy 353.137784 -277.03856) (xy 353.111816 -277.03907) (xy 353.086194 -277.038607) (xy 353.035566 -277.030679)
			(xy 352.986766 -277.015041) (xy 352.940959 -276.992066) (xy 352.899243 -276.962305) (xy 352.862613 -276.926468)
			(xy 352.846894 -276.906228) (xy 352.436938 -276.906228) (xy 352.421244 -276.926489) (xy 352.38462 -276.962339)
			(xy 352.342902 -276.992105) (xy 352.297088 -277.015074) (xy 352.248277 -277.030695) (xy 352.197641 -277.038594)
			(xy 352.172016 -277.03907) (xy 352.146047 -277.038556) (xy 352.094749 -277.030434) (xy 352.045352 -277.014386)
			(xy 351.999075 -276.990808) (xy 351.957055 -276.960281) (xy 351.920329 -276.923557) (xy 351.8898 -276.881539)
			(xy 351.86622 -276.835263) (xy 351.85017 -276.785867) (xy 351.842045 -276.734569) (xy 351.562163 -276.734569)
			(xy 351.562123 -276.736602) (xy 351.552669 -276.79177) (xy 351.543874 -276.818344) (xy 351.536 -276.840442)
			(xy 351.739708 -277.193248) (xy 351.762822 -277.197566) (xy 351.787741 -277.202747) (xy 351.835725 -277.219709)
			(xy 351.880543 -277.243824) (xy 351.921136 -277.274522) (xy 351.956545 -277.311079) (xy 351.985934 -277.35263)
			(xy 352.008609 -277.398194) (xy 352.024033 -277.446694) (xy 352.031843 -277.496985) (xy 352.032316 -277.522432)
			(xy 352.031807 -277.548399) (xy 352.311717 -277.548399) (xy 352.311717 -277.496465) (xy 352.319842 -277.44517)
			(xy 352.33589 -277.395777) (xy 352.359468 -277.349503) (xy 352.389994 -277.307487) (xy 352.426717 -277.270764)
			(xy 352.468733 -277.240238) (xy 352.515007 -277.21666) (xy 352.5644 -277.200612) (xy 352.615695 -277.192487)
			(xy 352.667629 -277.192487) (xy 352.718924 -277.200612) (xy 352.768317 -277.21666) (xy 352.814591 -277.240238)
			(xy 352.856607 -277.270764) (xy 352.89333 -277.307487) (xy 352.923856 -277.349503) (xy 352.947434 -277.395777)
			(xy 352.963482 -277.44517) (xy 352.971607 -277.496465) (xy 352.972116 -277.522432) (xy 352.971607 -277.548399)
			(xy 353.251517 -277.548399) (xy 353.251517 -277.496465) (xy 353.259642 -277.44517) (xy 353.27569 -277.395777)
			(xy 353.299268 -277.349503) (xy 353.329794 -277.307487) (xy 353.366517 -277.270764) (xy 353.408533 -277.240238)
			(xy 353.454807 -277.21666) (xy 353.5042 -277.200612) (xy 353.555495 -277.192487) (xy 353.607429 -277.192487)
			(xy 353.658724 -277.200612) (xy 353.708117 -277.21666) (xy 353.754391 -277.240238) (xy 353.796407 -277.270764)
			(xy 353.83313 -277.307487) (xy 353.863656 -277.349503) (xy 353.887234 -277.395777) (xy 353.903282 -277.44517)
			(xy 353.911407 -277.496465) (xy 353.911916 -277.522432) (xy 354.190808 -277.522432) (xy 354.191264 -277.496981)
			(xy 354.199051 -277.446677) (xy 354.214461 -277.398163) (xy 354.237129 -277.352587) (xy 354.266519 -277.311026)
			(xy 354.301936 -277.274465) (xy 354.342541 -277.243769) (xy 354.387374 -277.219663) (xy 354.435373 -277.202718)
			(xy 354.460302 -277.197566) (xy 354.483416 -277.193248) (xy 354.687378 -276.839934) (xy 354.679504 -276.817836)
			(xy 354.670868 -276.791359) (xy 354.661542 -276.736459) (xy 354.660962 -276.708616) (xy 354.661471 -276.682649)
			(xy 354.669596 -276.631354) (xy 354.685644 -276.581961) (xy 354.709222 -276.535687) (xy 354.739748 -276.493671)
			(xy 354.776471 -276.456948) (xy 354.818487 -276.426422) (xy 354.864761 -276.402844) (xy 354.914154 -276.386796)
			(xy 354.965449 -276.378671) (xy 355.017383 -276.378671) (xy 355.068678 -276.386796) (xy 355.118071 -276.402844)
			(xy 355.164345 -276.426422) (xy 355.206361 -276.456948) (xy 355.243084 -276.493671) (xy 355.27361 -276.535687)
			(xy 355.297188 -276.581961) (xy 355.313236 -276.631354) (xy 355.321361 -276.682649) (xy 355.32187 -276.708616)
			(xy 355.321389 -276.734089) (xy 355.321312 -276.734583) (xy 355.601271 -276.734583) (xy 355.601271 -276.682649)
			(xy 355.609396 -276.631354) (xy 355.625444 -276.581961) (xy 355.649022 -276.535687) (xy 355.679548 -276.493671)
			(xy 355.716271 -276.456948) (xy 355.758287 -276.426422) (xy 355.804561 -276.402844) (xy 355.853954 -276.386796)
			(xy 355.905249 -276.378671) (xy 355.957183 -276.378671) (xy 356.008478 -276.386796) (xy 356.057871 -276.402844)
			(xy 356.104145 -276.426422) (xy 356.146161 -276.456948) (xy 356.182884 -276.493671) (xy 356.21341 -276.535687)
			(xy 356.236988 -276.581961) (xy 356.253036 -276.631354) (xy 356.261161 -276.682649) (xy 356.26167 -276.708616)
			(xy 356.540308 -276.708616) (xy 356.54075 -276.683164) (xy 356.548539 -276.63286) (xy 356.563951 -276.584346)
			(xy 356.586621 -276.53877) (xy 356.616013 -276.497209) (xy 356.651432 -276.460648) (xy 356.692038 -276.429952)
			(xy 356.736872 -276.405846) (xy 356.784873 -276.388902) (xy 356.809802 -276.38375) (xy 356.832916 -276.379432)
			(xy 357.036624 -276.026626) (xy 357.02875 -276.004528) (xy 357.020021 -275.977937) (xy 357.010567 -275.92278)
			(xy 357.009954 -275.8948) (xy 357.010463 -275.868833) (xy 357.018588 -275.817538) (xy 357.034636 -275.768145)
			(xy 357.058214 -275.721871) (xy 357.08874 -275.679855) (xy 357.125463 -275.643132) (xy 357.167479 -275.612606)
			(xy 357.213753 -275.589028) (xy 357.263146 -275.57298) (xy 357.314441 -275.564855) (xy 357.366375 -275.564855)
			(xy 357.41767 -275.57298) (xy 357.467063 -275.589028) (xy 357.513337 -275.612606) (xy 357.555353 -275.643132)
			(xy 357.592076 -275.679855) (xy 357.622602 -275.721871) (xy 357.64618 -275.768145) (xy 357.662228 -275.817538)
			(xy 357.670353 -275.868833) (xy 357.670862 -275.8948) (xy 357.670368 -275.920251) (xy 357.670288 -275.920767)
			(xy 357.950517 -275.920767) (xy 357.950517 -275.868833) (xy 357.958642 -275.817538) (xy 357.97469 -275.768145)
			(xy 357.998268 -275.721871) (xy 358.028794 -275.679855) (xy 358.065517 -275.643132) (xy 358.107533 -275.612606)
			(xy 358.153807 -275.589028) (xy 358.2032 -275.57298) (xy 358.254495 -275.564855) (xy 358.306429 -275.564855)
			(xy 358.357724 -275.57298) (xy 358.407117 -275.589028) (xy 358.453391 -275.612606) (xy 358.495407 -275.643132)
			(xy 358.53213 -275.679855) (xy 358.562656 -275.721871) (xy 358.586234 -275.768145) (xy 358.602282 -275.817538)
			(xy 358.610407 -275.868833) (xy 358.610916 -275.8948) (xy 358.610407 -275.920767) (xy 361.709971 -275.920767)
			(xy 361.709971 -275.868833) (xy 361.718096 -275.817538) (xy 361.734144 -275.768145) (xy 361.757722 -275.721871)
			(xy 361.788248 -275.679855) (xy 361.824971 -275.643132) (xy 361.866987 -275.612606) (xy 361.913261 -275.589028)
			(xy 361.962654 -275.57298) (xy 362.013949 -275.564855) (xy 362.065883 -275.564855) (xy 362.117178 -275.57298)
			(xy 362.166571 -275.589028) (xy 362.212845 -275.612606) (xy 362.254861 -275.643132) (xy 362.291584 -275.679855)
			(xy 362.32211 -275.721871) (xy 362.345688 -275.768145) (xy 362.361736 -275.817538) (xy 362.369861 -275.868833)
			(xy 362.37037 -275.8948) (xy 362.369861 -275.920767) (xy 362.649517 -275.920767) (xy 362.649517 -275.868833)
			(xy 362.657642 -275.817538) (xy 362.67369 -275.768145) (xy 362.697268 -275.721871) (xy 362.727794 -275.679855)
			(xy 362.764517 -275.643132) (xy 362.806533 -275.612606) (xy 362.852807 -275.589028) (xy 362.9022 -275.57298)
			(xy 362.953495 -275.564855) (xy 363.005429 -275.564855) (xy 363.056724 -275.57298) (xy 363.106117 -275.589028)
			(xy 363.152391 -275.612606) (xy 363.194407 -275.643132) (xy 363.23113 -275.679855) (xy 363.261656 -275.721871)
			(xy 363.285234 -275.768145) (xy 363.301282 -275.817538) (xy 363.309407 -275.868833) (xy 363.309916 -275.8948)
			(xy 363.309407 -275.920767) (xy 363.589317 -275.920767) (xy 363.589317 -275.868833) (xy 363.597442 -275.817538)
			(xy 363.61349 -275.768145) (xy 363.637068 -275.721871) (xy 363.667594 -275.679855) (xy 363.704317 -275.643132)
			(xy 363.746333 -275.612606) (xy 363.792607 -275.589028) (xy 363.842 -275.57298) (xy 363.893295 -275.564855)
			(xy 363.945229 -275.564855) (xy 363.996524 -275.57298) (xy 364.045917 -275.589028) (xy 364.092191 -275.612606)
			(xy 364.134207 -275.643132) (xy 364.17093 -275.679855) (xy 364.201456 -275.721871) (xy 364.225034 -275.768145)
			(xy 364.241082 -275.817538) (xy 364.249207 -275.868833) (xy 364.249716 -275.8948) (xy 364.249212 -275.920513)
			(xy 364.529371 -275.920513) (xy 364.529371 -275.868579) (xy 364.537496 -275.817284) (xy 364.553544 -275.767891)
			(xy 364.577122 -275.721617) (xy 364.607648 -275.679601) (xy 364.644371 -275.642878) (xy 364.686387 -275.612352)
			(xy 364.732661 -275.588774) (xy 364.782054 -275.572726) (xy 364.833349 -275.564601) (xy 364.885283 -275.564601)
			(xy 364.936578 -275.572726) (xy 364.985971 -275.588774) (xy 365.032245 -275.612352) (xy 365.074261 -275.642878)
			(xy 365.110984 -275.679601) (xy 365.14151 -275.721617) (xy 365.165088 -275.767891) (xy 365.181136 -275.817284)
			(xy 365.189261 -275.868579) (xy 365.18977 -275.894546) (xy 365.189261 -275.920513) (xy 365.181136 -275.971808)
			(xy 365.165088 -276.021201) (xy 365.14151 -276.067475) (xy 365.110984 -276.109491) (xy 365.074261 -276.146214)
			(xy 365.032245 -276.17674) (xy 364.985971 -276.200318) (xy 364.936578 -276.216366) (xy 364.885283 -276.224491)
			(xy 364.833349 -276.224491) (xy 364.782054 -276.216366) (xy 364.732661 -276.200318) (xy 364.686387 -276.17674)
			(xy 364.644371 -276.146214) (xy 364.607648 -276.109491) (xy 364.577122 -276.067475) (xy 364.553544 -276.021201)
			(xy 364.537496 -275.971808) (xy 364.529371 -275.920513) (xy 364.249212 -275.920513) (xy 364.249207 -275.920767)
			(xy 364.241082 -275.972062) (xy 364.225034 -276.021455) (xy 364.201456 -276.067729) (xy 364.17093 -276.109745)
			(xy 364.134207 -276.146468) (xy 364.092191 -276.176994) (xy 364.045917 -276.200572) (xy 363.996524 -276.21662)
			(xy 363.945229 -276.224745) (xy 363.893295 -276.224745) (xy 363.842 -276.21662) (xy 363.792607 -276.200572)
			(xy 363.746333 -276.176994) (xy 363.704317 -276.146468) (xy 363.667594 -276.109745) (xy 363.637068 -276.067729)
			(xy 363.61349 -276.021455) (xy 363.597442 -275.972062) (xy 363.589317 -275.920767) (xy 363.309407 -275.920767)
			(xy 363.301282 -275.972062) (xy 363.285234 -276.021455) (xy 363.261656 -276.067729) (xy 363.23113 -276.109745)
			(xy 363.194407 -276.146468) (xy 363.152391 -276.176994) (xy 363.106117 -276.200572) (xy 363.056724 -276.21662)
			(xy 363.005429 -276.224745) (xy 362.953495 -276.224745) (xy 362.9022 -276.21662) (xy 362.852807 -276.200572)
			(xy 362.806533 -276.176994) (xy 362.764517 -276.146468) (xy 362.727794 -276.109745) (xy 362.697268 -276.067729)
			(xy 362.67369 -276.021455) (xy 362.657642 -275.972062) (xy 362.649517 -275.920767) (xy 362.369861 -275.920767)
			(xy 362.361736 -275.972062) (xy 362.345688 -276.021455) (xy 362.32211 -276.067729) (xy 362.291584 -276.109745)
			(xy 362.254861 -276.146468) (xy 362.212845 -276.176994) (xy 362.166571 -276.200572) (xy 362.117178 -276.21662)
			(xy 362.065883 -276.224745) (xy 362.013949 -276.224745) (xy 361.962654 -276.21662) (xy 361.913261 -276.200572)
			(xy 361.866987 -276.176994) (xy 361.824971 -276.146468) (xy 361.788248 -276.109745) (xy 361.757722 -276.067729)
			(xy 361.734144 -276.021455) (xy 361.718096 -275.972062) (xy 361.709971 -275.920767) (xy 358.610407 -275.920767)
			(xy 358.602282 -275.972062) (xy 358.586234 -276.021455) (xy 358.562656 -276.067729) (xy 358.53213 -276.109745)
			(xy 358.495407 -276.146468) (xy 358.453391 -276.176994) (xy 358.407117 -276.200572) (xy 358.357724 -276.21662)
			(xy 358.306429 -276.224745) (xy 358.254495 -276.224745) (xy 358.2032 -276.21662) (xy 358.153807 -276.200572)
			(xy 358.107533 -276.176994) (xy 358.065517 -276.146468) (xy 358.028794 -276.109745) (xy 357.998268 -276.067729)
			(xy 357.97469 -276.021455) (xy 357.958642 -275.972062) (xy 357.950517 -275.920767) (xy 357.670288 -275.920767)
			(xy 357.66259 -275.970554) (xy 357.647188 -276.019068) (xy 357.624526 -276.064646) (xy 357.595141 -276.106207)
			(xy 357.559728 -276.142769) (xy 357.519125 -276.173466) (xy 357.474294 -276.197572) (xy 357.426296 -276.214514)
			(xy 357.401368 -276.219666) (xy 357.378508 -276.223984) (xy 357.1748 -276.57679) (xy 357.18242 -276.598888)
			(xy 357.191155 -276.625477) (xy 357.200604 -276.680636) (xy 357.201216 -276.708616) (xy 357.200707 -276.734583)
			(xy 357.480617 -276.734583) (xy 357.480617 -276.682649) (xy 357.488742 -276.631354) (xy 357.50479 -276.581961)
			(xy 357.528368 -276.535687) (xy 357.558894 -276.493671) (xy 357.595617 -276.456948) (xy 357.637633 -276.426422)
			(xy 357.683907 -276.402844) (xy 357.7333 -276.386796) (xy 357.784595 -276.378671) (xy 357.836529 -276.378671)
			(xy 357.887824 -276.386796) (xy 357.937217 -276.402844) (xy 357.983491 -276.426422) (xy 358.025507 -276.456948)
			(xy 358.06223 -276.493671) (xy 358.092756 -276.535687) (xy 358.116334 -276.581961) (xy 358.132382 -276.631354)
			(xy 358.140507 -276.682649) (xy 358.141016 -276.708616) (xy 358.140507 -276.734583) (xy 362.179871 -276.734583)
			(xy 362.179871 -276.682649) (xy 362.187996 -276.631354) (xy 362.204044 -276.581961) (xy 362.227622 -276.535687)
			(xy 362.258148 -276.493671) (xy 362.294871 -276.456948) (xy 362.336887 -276.426422) (xy 362.383161 -276.402844)
			(xy 362.432554 -276.386796) (xy 362.483849 -276.378671) (xy 362.535783 -276.378671) (xy 362.587078 -276.386796)
			(xy 362.636471 -276.402844) (xy 362.682745 -276.426422) (xy 362.724761 -276.456948) (xy 362.761484 -276.493671)
			(xy 362.79201 -276.535687) (xy 362.815588 -276.581961) (xy 362.831636 -276.631354) (xy 362.839761 -276.682649)
			(xy 362.84027 -276.708616) (xy 362.839766 -276.734329) (xy 363.119417 -276.734329) (xy 363.119417 -276.682395)
			(xy 363.127542 -276.6311) (xy 363.14359 -276.581707) (xy 363.167168 -276.535433) (xy 363.197694 -276.493417)
			(xy 363.234417 -276.456694) (xy 363.276433 -276.426168) (xy 363.322707 -276.40259) (xy 363.3721 -276.386542)
			(xy 363.423395 -276.378417) (xy 363.475329 -276.378417) (xy 363.526624 -276.386542) (xy 363.576017 -276.40259)
			(xy 363.622291 -276.426168) (xy 363.664307 -276.456694) (xy 363.70103 -276.493417) (xy 363.731556 -276.535433)
			(xy 363.755134 -276.581707) (xy 363.771182 -276.6311) (xy 363.779307 -276.682395) (xy 363.779816 -276.708362)
			(xy 363.779307 -276.734329) (xy 364.059217 -276.734329) (xy 364.059217 -276.682395) (xy 364.067342 -276.6311)
			(xy 364.08339 -276.581707) (xy 364.106968 -276.535433) (xy 364.137494 -276.493417) (xy 364.174217 -276.456694)
			(xy 364.216233 -276.426168) (xy 364.262507 -276.40259) (xy 364.3119 -276.386542) (xy 364.363195 -276.378417)
			(xy 364.415129 -276.378417) (xy 364.466424 -276.386542) (xy 364.515817 -276.40259) (xy 364.562091 -276.426168)
			(xy 364.604107 -276.456694) (xy 364.64083 -276.493417) (xy 364.671356 -276.535433) (xy 364.694934 -276.581707)
			(xy 364.710982 -276.6311) (xy 364.719107 -276.682395) (xy 364.719616 -276.708362) (xy 364.719107 -276.734329)
			(xy 364.999017 -276.734329) (xy 364.999017 -276.682395) (xy 365.007142 -276.6311) (xy 365.02319 -276.581707)
			(xy 365.046768 -276.535433) (xy 365.077294 -276.493417) (xy 365.114017 -276.456694) (xy 365.156033 -276.426168)
			(xy 365.202307 -276.40259) (xy 365.2517 -276.386542) (xy 365.302995 -276.378417) (xy 365.354929 -276.378417)
			(xy 365.406224 -276.386542) (xy 365.455617 -276.40259) (xy 365.501891 -276.426168) (xy 365.543907 -276.456694)
			(xy 365.58063 -276.493417) (xy 365.611156 -276.535433) (xy 365.634734 -276.581707) (xy 365.650782 -276.6311)
			(xy 365.658907 -276.682395) (xy 365.659416 -276.708362) (xy 365.658907 -276.734329) (xy 365.650782 -276.785624)
			(xy 365.634734 -276.835017) (xy 365.611156 -276.881291) (xy 365.58063 -276.923307) (xy 365.543907 -276.96003)
			(xy 365.501891 -276.990556) (xy 365.455617 -277.014134) (xy 365.406224 -277.030182) (xy 365.354929 -277.038307)
			(xy 365.302995 -277.038307) (xy 365.2517 -277.030182) (xy 365.202307 -277.014134) (xy 365.156033 -276.990556)
			(xy 365.114017 -276.96003) (xy 365.077294 -276.923307) (xy 365.046768 -276.881291) (xy 365.02319 -276.835017)
			(xy 365.007142 -276.785624) (xy 364.999017 -276.734329) (xy 364.719107 -276.734329) (xy 364.710982 -276.785624)
			(xy 364.694934 -276.835017) (xy 364.671356 -276.881291) (xy 364.64083 -276.923307) (xy 364.604107 -276.96003)
			(xy 364.562091 -276.990556) (xy 364.515817 -277.014134) (xy 364.466424 -277.030182) (xy 364.415129 -277.038307)
			(xy 364.363195 -277.038307) (xy 364.3119 -277.030182) (xy 364.262507 -277.014134) (xy 364.216233 -276.990556)
			(xy 364.174217 -276.96003) (xy 364.137494 -276.923307) (xy 364.106968 -276.881291) (xy 364.08339 -276.835017)
			(xy 364.067342 -276.785624) (xy 364.059217 -276.734329) (xy 363.779307 -276.734329) (xy 363.771182 -276.785624)
			(xy 363.755134 -276.835017) (xy 363.731556 -276.881291) (xy 363.70103 -276.923307) (xy 363.664307 -276.96003)
			(xy 363.622291 -276.990556) (xy 363.576017 -277.014134) (xy 363.526624 -277.030182) (xy 363.475329 -277.038307)
			(xy 363.423395 -277.038307) (xy 363.3721 -277.030182) (xy 363.322707 -277.014134) (xy 363.276433 -276.990556)
			(xy 363.234417 -276.96003) (xy 363.197694 -276.923307) (xy 363.167168 -276.881291) (xy 363.14359 -276.835017)
			(xy 363.127542 -276.785624) (xy 363.119417 -276.734329) (xy 362.839766 -276.734329) (xy 362.839761 -276.734583)
			(xy 362.831636 -276.785878) (xy 362.815588 -276.835271) (xy 362.79201 -276.881545) (xy 362.761484 -276.923561)
			(xy 362.724761 -276.960284) (xy 362.682745 -276.99081) (xy 362.636471 -277.014388) (xy 362.587078 -277.030436)
			(xy 362.535783 -277.038561) (xy 362.483849 -277.038561) (xy 362.432554 -277.030436) (xy 362.383161 -277.014388)
			(xy 362.336887 -276.99081) (xy 362.294871 -276.960284) (xy 362.258148 -276.923561) (xy 362.227622 -276.881545)
			(xy 362.204044 -276.835271) (xy 362.187996 -276.785878) (xy 362.179871 -276.734583) (xy 358.140507 -276.734583)
			(xy 358.132382 -276.785878) (xy 358.116334 -276.835271) (xy 358.092756 -276.881545) (xy 358.06223 -276.923561)
			(xy 358.025507 -276.960284) (xy 357.983491 -276.99081) (xy 357.937217 -277.014388) (xy 357.887824 -277.030436)
			(xy 357.836529 -277.038561) (xy 357.784595 -277.038561) (xy 357.7333 -277.030436) (xy 357.683907 -277.014388)
			(xy 357.637633 -276.99081) (xy 357.595617 -276.960284) (xy 357.558894 -276.923561) (xy 357.528368 -276.881545)
			(xy 357.50479 -276.835271) (xy 357.488742 -276.785878) (xy 357.480617 -276.734583) (xy 357.200707 -276.734583)
			(xy 357.192582 -276.785878) (xy 357.176534 -276.835271) (xy 357.152956 -276.881545) (xy 357.12243 -276.923561)
			(xy 357.085707 -276.960284) (xy 357.043691 -276.99081) (xy 356.997417 -277.014388) (xy 356.948024 -277.030436)
			(xy 356.896729 -277.038561) (xy 356.844795 -277.038561) (xy 356.7935 -277.030436) (xy 356.744107 -277.014388)
			(xy 356.697833 -276.99081) (xy 356.655817 -276.960284) (xy 356.619094 -276.923561) (xy 356.588568 -276.881545)
			(xy 356.56499 -276.835271) (xy 356.548942 -276.785878) (xy 356.540817 -276.734583) (xy 356.540308 -276.708616)
			(xy 356.26167 -276.708616) (xy 356.261161 -276.734583) (xy 356.253036 -276.785878) (xy 356.236988 -276.835271)
			(xy 356.21341 -276.881545) (xy 356.182884 -276.923561) (xy 356.146161 -276.960284) (xy 356.104145 -276.99081)
			(xy 356.057871 -277.014388) (xy 356.008478 -277.030436) (xy 355.957183 -277.038561) (xy 355.905249 -277.038561)
			(xy 355.853954 -277.030436) (xy 355.804561 -277.014388) (xy 355.758287 -276.99081) (xy 355.716271 -276.960284)
			(xy 355.679548 -276.923561) (xy 355.649022 -276.881545) (xy 355.625444 -276.835271) (xy 355.609396 -276.785878)
			(xy 355.601271 -276.734583) (xy 355.321312 -276.734583) (xy 355.313568 -276.784431) (xy 355.298113 -276.832977)
			(xy 355.275391 -276.878575) (xy 355.24594 -276.920146) (xy 355.210458 -276.956705) (xy 355.169786 -276.987385)
			(xy 355.124887 -277.01146) (xy 355.076825 -277.028358) (xy 355.051868 -277.033482) (xy 355.029008 -277.0378)
			(xy 354.8253 -277.390606) (xy 354.83292 -277.412704) (xy 354.841659 -277.439292) (xy 354.851106 -277.494451)
			(xy 354.851716 -277.522432) (xy 355.130608 -277.522432) (xy 355.131117 -277.496465) (xy 355.139242 -277.44517)
			(xy 355.15529 -277.395777) (xy 355.178868 -277.349503) (xy 355.209394 -277.307487) (xy 355.246117 -277.270764)
			(xy 355.288133 -277.240238) (xy 355.334407 -277.21666) (xy 355.3838 -277.200612) (xy 355.435095 -277.192487)
			(xy 355.487029 -277.192487) (xy 355.538324 -277.200612) (xy 355.587717 -277.21666) (xy 355.633991 -277.240238)
			(xy 355.676007 -277.270764) (xy 355.71273 -277.307487) (xy 355.743256 -277.349503) (xy 355.766834 -277.395777)
			(xy 355.782882 -277.44517) (xy 355.791007 -277.496465) (xy 355.791516 -277.522432) (xy 355.791017 -277.548363)
			(xy 356.070987 -277.548363) (xy 356.070987 -277.496437) (xy 356.079109 -277.445151) (xy 356.095154 -277.395766)
			(xy 356.118726 -277.349499) (xy 356.149245 -277.307489) (xy 356.18596 -277.27077) (xy 356.227967 -277.240246)
			(xy 356.274231 -277.216669) (xy 356.323614 -277.200618) (xy 356.374899 -277.19249) (xy 356.400862 -277.191978)
			(xy 356.426482 -277.192477) (xy 356.477108 -277.200401) (xy 356.525906 -277.216033) (xy 356.571712 -277.239001)
			(xy 356.61343 -277.268755) (xy 356.650063 -277.304584) (xy 356.665784 -277.32482) (xy 357.07574 -277.32482)
			(xy 357.091433 -277.304558) (xy 357.128058 -277.268711) (xy 357.169778 -277.238946) (xy 357.215592 -277.215978)
			(xy 357.264401 -277.200356) (xy 357.315038 -277.192455) (xy 357.340662 -277.191978) (xy 357.366636 -277.192394)
			(xy 357.417944 -277.200515) (xy 357.467351 -277.216563) (xy 357.513638 -277.240143) (xy 357.555667 -277.270674)
			(xy 357.592401 -277.307404) (xy 357.622937 -277.349429) (xy 357.646522 -277.395714) (xy 357.662576 -277.445119)
			(xy 357.670703 -277.496426) (xy 357.670703 -277.548374) (xy 357.670699 -277.548399) (xy 357.950517 -277.548399)
			(xy 357.950517 -277.496465) (xy 357.958642 -277.44517) (xy 357.97469 -277.395777) (xy 357.998268 -277.349503)
			(xy 358.028794 -277.307487) (xy 358.065517 -277.270764) (xy 358.107533 -277.240238) (xy 358.153807 -277.21666)
			(xy 358.2032 -277.200612) (xy 358.254495 -277.192487) (xy 358.306429 -277.192487) (xy 358.357724 -277.200612)
			(xy 358.407117 -277.21666) (xy 358.453391 -277.240238) (xy 358.495407 -277.270764) (xy 358.53213 -277.307487)
			(xy 358.562656 -277.349503) (xy 358.586234 -277.395777) (xy 358.602282 -277.44517) (xy 358.610407 -277.496465)
			(xy 358.610916 -277.522432) (xy 358.610407 -277.548399) (xy 362.649517 -277.548399) (xy 362.649517 -277.496465)
			(xy 362.657642 -277.44517) (xy 362.67369 -277.395777) (xy 362.697268 -277.349503) (xy 362.727794 -277.307487)
			(xy 362.764517 -277.270764) (xy 362.806533 -277.240238) (xy 362.852807 -277.21666) (xy 362.9022 -277.200612)
			(xy 362.953495 -277.192487) (xy 363.005429 -277.192487) (xy 363.056724 -277.200612) (xy 363.106117 -277.21666)
			(xy 363.152391 -277.240238) (xy 363.194407 -277.270764) (xy 363.23113 -277.307487) (xy 363.261656 -277.349503)
			(xy 363.285234 -277.395777) (xy 363.301282 -277.44517) (xy 363.309407 -277.496465) (xy 363.309916 -277.522432)
			(xy 363.309412 -277.548145) (xy 363.589571 -277.548145) (xy 363.589571 -277.496211) (xy 363.597696 -277.444916)
			(xy 363.613744 -277.395523) (xy 363.637322 -277.349249) (xy 363.667848 -277.307233) (xy 363.704571 -277.27051)
			(xy 363.746587 -277.239984) (xy 363.792861 -277.216406) (xy 363.842254 -277.200358) (xy 363.893549 -277.192233)
			(xy 363.945483 -277.192233) (xy 363.996778 -277.200358) (xy 364.046171 -277.216406) (xy 364.092445 -277.239984)
			(xy 364.134461 -277.27051) (xy 364.171184 -277.307233) (xy 364.20171 -277.349249) (xy 364.225288 -277.395523)
			(xy 364.241336 -277.444916) (xy 364.249461 -277.496211) (xy 364.24997 -277.522178) (xy 364.249461 -277.548145)
			(xy 364.249421 -277.548399) (xy 364.529117 -277.548399) (xy 364.529117 -277.496465) (xy 364.537242 -277.44517)
			(xy 364.55329 -277.395777) (xy 364.576868 -277.349503) (xy 364.607394 -277.307487) (xy 364.644117 -277.270764)
			(xy 364.686133 -277.240238) (xy 364.732407 -277.21666) (xy 364.7818 -277.200612) (xy 364.833095 -277.192487)
			(xy 364.885029 -277.192487) (xy 364.936324 -277.200612) (xy 364.985717 -277.21666) (xy 365.031991 -277.240238)
			(xy 365.074007 -277.270764) (xy 365.11073 -277.307487) (xy 365.141256 -277.349503) (xy 365.164834 -277.395777)
			(xy 365.180882 -277.44517) (xy 365.189007 -277.496465) (xy 365.189516 -277.522432) (xy 365.189012 -277.548145)
			(xy 365.469171 -277.548145) (xy 365.469171 -277.496211) (xy 365.477296 -277.444916) (xy 365.493344 -277.395523)
			(xy 365.516922 -277.349249) (xy 365.547448 -277.307233) (xy 365.584171 -277.27051) (xy 365.626187 -277.239984)
			(xy 365.672461 -277.216406) (xy 365.721854 -277.200358) (xy 365.773149 -277.192233) (xy 365.825083 -277.192233)
			(xy 365.876378 -277.200358) (xy 365.925771 -277.216406) (xy 365.972045 -277.239984) (xy 366.014061 -277.27051)
			(xy 366.050784 -277.307233) (xy 366.08131 -277.349249) (xy 366.104888 -277.395523) (xy 366.120936 -277.444916)
			(xy 366.129061 -277.496211) (xy 366.12957 -277.522178) (xy 366.129061 -277.548145) (xy 366.120936 -277.59944)
			(xy 366.104888 -277.648833) (xy 366.08131 -277.695107) (xy 366.050784 -277.737123) (xy 366.014061 -277.773846)
			(xy 365.972045 -277.804372) (xy 365.925771 -277.82795) (xy 365.876378 -277.843998) (xy 365.825083 -277.852123)
			(xy 365.773149 -277.852123) (xy 365.721854 -277.843998) (xy 365.672461 -277.82795) (xy 365.626187 -277.804372)
			(xy 365.584171 -277.773846) (xy 365.547448 -277.737123) (xy 365.516922 -277.695107) (xy 365.493344 -277.648833)
			(xy 365.477296 -277.59944) (xy 365.469171 -277.548145) (xy 365.189012 -277.548145) (xy 365.189007 -277.548399)
			(xy 365.180882 -277.599694) (xy 365.164834 -277.649087) (xy 365.141256 -277.695361) (xy 365.11073 -277.737377)
			(xy 365.074007 -277.7741) (xy 365.031991 -277.804626) (xy 364.985717 -277.828204) (xy 364.936324 -277.844252)
			(xy 364.885029 -277.852377) (xy 364.833095 -277.852377) (xy 364.7818 -277.844252) (xy 364.732407 -277.828204)
			(xy 364.686133 -277.804626) (xy 364.644117 -277.7741) (xy 364.607394 -277.737377) (xy 364.576868 -277.695361)
			(xy 364.55329 -277.649087) (xy 364.537242 -277.599694) (xy 364.529117 -277.548399) (xy 364.249421 -277.548399)
			(xy 364.241336 -277.59944) (xy 364.225288 -277.648833) (xy 364.20171 -277.695107) (xy 364.171184 -277.737123)
			(xy 364.134461 -277.773846) (xy 364.092445 -277.804372) (xy 364.046171 -277.82795) (xy 363.996778 -277.843998)
			(xy 363.945483 -277.852123) (xy 363.893549 -277.852123) (xy 363.842254 -277.843998) (xy 363.792861 -277.82795)
			(xy 363.746587 -277.804372) (xy 363.704571 -277.773846) (xy 363.667848 -277.737123) (xy 363.637322 -277.695107)
			(xy 363.613744 -277.648833) (xy 363.597696 -277.59944) (xy 363.589571 -277.548145) (xy 363.309412 -277.548145)
			(xy 363.309407 -277.548399) (xy 363.301282 -277.599694) (xy 363.285234 -277.649087) (xy 363.261656 -277.695361)
			(xy 363.23113 -277.737377) (xy 363.194407 -277.7741) (xy 363.152391 -277.804626) (xy 363.106117 -277.828204)
			(xy 363.056724 -277.844252) (xy 363.005429 -277.852377) (xy 362.953495 -277.852377) (xy 362.9022 -277.844252)
			(xy 362.852807 -277.828204) (xy 362.806533 -277.804626) (xy 362.764517 -277.7741) (xy 362.727794 -277.737377)
			(xy 362.697268 -277.695361) (xy 362.67369 -277.649087) (xy 362.657642 -277.599694) (xy 362.649517 -277.548399)
			(xy 358.610407 -277.548399) (xy 358.602282 -277.599694) (xy 358.586234 -277.649087) (xy 358.562656 -277.695361)
			(xy 358.53213 -277.737377) (xy 358.495407 -277.7741) (xy 358.453391 -277.804626) (xy 358.407117 -277.828204)
			(xy 358.357724 -277.844252) (xy 358.306429 -277.852377) (xy 358.254495 -277.852377) (xy 358.2032 -277.844252)
			(xy 358.153807 -277.828204) (xy 358.107533 -277.804626) (xy 358.065517 -277.7741) (xy 358.028794 -277.737377)
			(xy 357.998268 -277.695361) (xy 357.97469 -277.649087) (xy 357.958642 -277.599694) (xy 357.950517 -277.548399)
			(xy 357.670699 -277.548399) (xy 357.662576 -277.599681) (xy 357.646522 -277.649086) (xy 357.622937 -277.695371)
			(xy 357.592401 -277.737396) (xy 357.555667 -277.774126) (xy 357.513638 -277.804657) (xy 357.467351 -277.828237)
			(xy 357.417944 -277.844285) (xy 357.366636 -277.852406) (xy 357.340662 -277.852886) (xy 357.315041 -277.852384)
			(xy 357.264416 -277.844463) (xy 357.215616 -277.828832) (xy 357.16981 -277.805865) (xy 357.128092 -277.776111)
			(xy 357.09146 -277.740281) (xy 357.07574 -277.720044) (xy 356.665784 -277.720044) (xy 356.650067 -277.740287)
			(xy 356.613448 -277.776137) (xy 356.571734 -277.805905) (xy 356.525925 -277.828877) (xy 356.477118 -277.844502)
			(xy 356.426485 -277.852407) (xy 356.400862 -277.852886) (xy 356.374899 -277.85231) (xy 356.323614 -277.844182)
			(xy 356.274231 -277.828131) (xy 356.227967 -277.804554) (xy 356.18596 -277.77403) (xy 356.149245 -277.737311)
			(xy 356.118726 -277.695301) (xy 356.095154 -277.649034) (xy 356.079109 -277.599649) (xy 356.070987 -277.548363)
			(xy 355.791017 -277.548363) (xy 355.790979 -277.550342) (xy 355.781653 -277.605374) (xy 355.772974 -277.631906)
			(xy 355.7651 -277.654004) (xy 355.969062 -278.007318) (xy 355.992176 -278.011636) (xy 356.017097 -278.016806)
			(xy 356.065078 -278.033774) (xy 356.109894 -278.057893) (xy 356.150485 -278.088593) (xy 356.185893 -278.125151)
			(xy 356.215281 -278.166702) (xy 356.237956 -278.212265) (xy 356.253382 -278.260765) (xy 356.261194 -278.311055)
			(xy 356.26167 -278.336502) (xy 356.261161 -278.362469) (xy 356.540817 -278.362469) (xy 356.540817 -278.310535)
			(xy 356.548942 -278.25924) (xy 356.56499 -278.209847) (xy 356.588568 -278.163573) (xy 356.619094 -278.121557)
			(xy 356.655817 -278.084834) (xy 356.697833 -278.054308) (xy 356.744107 -278.03073) (xy 356.7935 -278.014682)
			(xy 356.844795 -278.006557) (xy 356.896729 -278.006557) (xy 356.948024 -278.014682) (xy 356.997417 -278.03073)
			(xy 357.043691 -278.054308) (xy 357.085707 -278.084834) (xy 357.12243 -278.121557) (xy 357.152956 -278.163573)
			(xy 357.176534 -278.209847) (xy 357.192582 -278.25924) (xy 357.200707 -278.310535) (xy 357.201216 -278.336502)
			(xy 357.200707 -278.362469) (xy 357.480617 -278.362469) (xy 357.480617 -278.310535) (xy 357.488742 -278.25924)
			(xy 357.50479 -278.209847) (xy 357.528368 -278.163573) (xy 357.558894 -278.121557) (xy 357.595617 -278.084834)
			(xy 357.637633 -278.054308) (xy 357.683907 -278.03073) (xy 357.7333 -278.014682) (xy 357.784595 -278.006557)
			(xy 357.836529 -278.006557) (xy 357.887824 -278.014682) (xy 357.937217 -278.03073) (xy 357.983491 -278.054308)
			(xy 358.025507 -278.084834) (xy 358.06223 -278.121557) (xy 358.092756 -278.163573) (xy 358.116334 -278.209847)
			(xy 358.132382 -278.25924) (xy 358.140507 -278.310535) (xy 358.141016 -278.336502) (xy 358.140512 -278.362215)
			(xy 362.179617 -278.362215) (xy 362.179617 -278.310281) (xy 362.187742 -278.258986) (xy 362.20379 -278.209593)
			(xy 362.227368 -278.163319) (xy 362.257894 -278.121303) (xy 362.294617 -278.08458) (xy 362.336633 -278.054054)
			(xy 362.382907 -278.030476) (xy 362.4323 -278.014428) (xy 362.483595 -278.006303) (xy 362.535529 -278.006303)
			(xy 362.586824 -278.014428) (xy 362.636217 -278.030476) (xy 362.682491 -278.054054) (xy 362.724507 -278.08458)
			(xy 362.76123 -278.121303) (xy 362.791756 -278.163319) (xy 362.815334 -278.209593) (xy 362.831382 -278.258986)
			(xy 362.839507 -278.310281) (xy 362.840016 -278.336248) (xy 362.839507 -278.362215) (xy 363.119417 -278.362215)
			(xy 363.119417 -278.310281) (xy 363.127542 -278.258986) (xy 363.14359 -278.209593) (xy 363.167168 -278.163319)
			(xy 363.197694 -278.121303) (xy 363.234417 -278.08458) (xy 363.276433 -278.054054) (xy 363.322707 -278.030476)
			(xy 363.3721 -278.014428) (xy 363.423395 -278.006303) (xy 363.475329 -278.006303) (xy 363.526624 -278.014428)
			(xy 363.576017 -278.030476) (xy 363.622291 -278.054054) (xy 363.664307 -278.08458) (xy 363.70103 -278.121303)
			(xy 363.731556 -278.163319) (xy 363.755134 -278.209593) (xy 363.771182 -278.258986) (xy 363.779307 -278.310281)
			(xy 363.779816 -278.336248) (xy 363.779307 -278.362215) (xy 364.059217 -278.362215) (xy 364.059217 -278.310281)
			(xy 364.067342 -278.258986) (xy 364.08339 -278.209593) (xy 364.106968 -278.163319) (xy 364.137494 -278.121303)
			(xy 364.174217 -278.08458) (xy 364.216233 -278.054054) (xy 364.262507 -278.030476) (xy 364.3119 -278.014428)
			(xy 364.363195 -278.006303) (xy 364.415129 -278.006303) (xy 364.466424 -278.014428) (xy 364.515817 -278.030476)
			(xy 364.562091 -278.054054) (xy 364.604107 -278.08458) (xy 364.64083 -278.121303) (xy 364.671356 -278.163319)
			(xy 364.694934 -278.209593) (xy 364.710982 -278.258986) (xy 364.719107 -278.310281) (xy 364.719616 -278.336248)
			(xy 364.719107 -278.362215) (xy 364.999017 -278.362215) (xy 364.999017 -278.310281) (xy 365.007142 -278.258986)
			(xy 365.02319 -278.209593) (xy 365.046768 -278.163319) (xy 365.077294 -278.121303) (xy 365.114017 -278.08458)
			(xy 365.156033 -278.054054) (xy 365.202307 -278.030476) (xy 365.2517 -278.014428) (xy 365.302995 -278.006303)
			(xy 365.354929 -278.006303) (xy 365.406224 -278.014428) (xy 365.455617 -278.030476) (xy 365.501891 -278.054054)
			(xy 365.543907 -278.08458) (xy 365.58063 -278.121303) (xy 365.611156 -278.163319) (xy 365.634734 -278.209593)
			(xy 365.650782 -278.258986) (xy 365.658907 -278.310281) (xy 365.659416 -278.336248) (xy 365.658907 -278.362215)
			(xy 365.938817 -278.362215) (xy 365.938817 -278.310281) (xy 365.946942 -278.258986) (xy 365.96299 -278.209593)
			(xy 365.986568 -278.163319) (xy 366.017094 -278.121303) (xy 366.053817 -278.08458) (xy 366.095833 -278.054054)
			(xy 366.142107 -278.030476) (xy 366.1915 -278.014428) (xy 366.242795 -278.006303) (xy 366.294729 -278.006303)
			(xy 366.346024 -278.014428) (xy 366.395417 -278.030476) (xy 366.441691 -278.054054) (xy 366.483707 -278.08458)
			(xy 366.52043 -278.121303) (xy 366.550956 -278.163319) (xy 366.574534 -278.209593) (xy 366.590582 -278.258986)
			(xy 366.598707 -278.310281) (xy 366.599216 -278.336248) (xy 366.598707 -278.362215) (xy 366.590582 -278.41351)
			(xy 366.574534 -278.462903) (xy 366.550956 -278.509177) (xy 366.52043 -278.551193) (xy 366.483707 -278.587916)
			(xy 366.441691 -278.618442) (xy 366.395417 -278.64202) (xy 366.346024 -278.658068) (xy 366.294729 -278.666193)
			(xy 366.242795 -278.666193) (xy 366.1915 -278.658068) (xy 366.142107 -278.64202) (xy 366.095833 -278.618442)
			(xy 366.053817 -278.587916) (xy 366.017094 -278.551193) (xy 365.986568 -278.509177) (xy 365.96299 -278.462903)
			(xy 365.946942 -278.41351) (xy 365.938817 -278.362215) (xy 365.658907 -278.362215) (xy 365.650782 -278.41351)
			(xy 365.634734 -278.462903) (xy 365.611156 -278.509177) (xy 365.58063 -278.551193) (xy 365.543907 -278.587916)
			(xy 365.501891 -278.618442) (xy 365.455617 -278.64202) (xy 365.406224 -278.658068) (xy 365.354929 -278.666193)
			(xy 365.302995 -278.666193) (xy 365.2517 -278.658068) (xy 365.202307 -278.64202) (xy 365.156033 -278.618442)
			(xy 365.114017 -278.587916) (xy 365.077294 -278.551193) (xy 365.046768 -278.509177) (xy 365.02319 -278.462903)
			(xy 365.007142 -278.41351) (xy 364.999017 -278.362215) (xy 364.719107 -278.362215) (xy 364.710982 -278.41351)
			(xy 364.694934 -278.462903) (xy 364.671356 -278.509177) (xy 364.64083 -278.551193) (xy 364.604107 -278.587916)
			(xy 364.562091 -278.618442) (xy 364.515817 -278.64202) (xy 364.466424 -278.658068) (xy 364.415129 -278.666193)
			(xy 364.363195 -278.666193) (xy 364.3119 -278.658068) (xy 364.262507 -278.64202) (xy 364.216233 -278.618442)
			(xy 364.174217 -278.587916) (xy 364.137494 -278.551193) (xy 364.106968 -278.509177) (xy 364.08339 -278.462903)
			(xy 364.067342 -278.41351) (xy 364.059217 -278.362215) (xy 363.779307 -278.362215) (xy 363.771182 -278.41351)
			(xy 363.755134 -278.462903) (xy 363.731556 -278.509177) (xy 363.70103 -278.551193) (xy 363.664307 -278.587916)
			(xy 363.622291 -278.618442) (xy 363.576017 -278.64202) (xy 363.526624 -278.658068) (xy 363.475329 -278.666193)
			(xy 363.423395 -278.666193) (xy 363.3721 -278.658068) (xy 363.322707 -278.64202) (xy 363.276433 -278.618442)
			(xy 363.234417 -278.587916) (xy 363.197694 -278.551193) (xy 363.167168 -278.509177) (xy 363.14359 -278.462903)
			(xy 363.127542 -278.41351) (xy 363.119417 -278.362215) (xy 362.839507 -278.362215) (xy 362.831382 -278.41351)
			(xy 362.815334 -278.462903) (xy 362.791756 -278.509177) (xy 362.76123 -278.551193) (xy 362.724507 -278.587916)
			(xy 362.682491 -278.618442) (xy 362.636217 -278.64202) (xy 362.586824 -278.658068) (xy 362.535529 -278.666193)
			(xy 362.483595 -278.666193) (xy 362.4323 -278.658068) (xy 362.382907 -278.64202) (xy 362.336633 -278.618442)
			(xy 362.294617 -278.587916) (xy 362.257894 -278.551193) (xy 362.227368 -278.509177) (xy 362.20379 -278.462903)
			(xy 362.187742 -278.41351) (xy 362.179617 -278.362215) (xy 358.140512 -278.362215) (xy 358.140507 -278.362469)
			(xy 358.132382 -278.413764) (xy 358.116334 -278.463157) (xy 358.092756 -278.509431) (xy 358.06223 -278.551447)
			(xy 358.025507 -278.58817) (xy 357.983491 -278.618696) (xy 357.937217 -278.642274) (xy 357.887824 -278.658322)
			(xy 357.836529 -278.666447) (xy 357.784595 -278.666447) (xy 357.7333 -278.658322) (xy 357.683907 -278.642274)
			(xy 357.637633 -278.618696) (xy 357.595617 -278.58817) (xy 357.558894 -278.551447) (xy 357.528368 -278.509431)
			(xy 357.50479 -278.463157) (xy 357.488742 -278.413764) (xy 357.480617 -278.362469) (xy 357.200707 -278.362469)
			(xy 357.192582 -278.413764) (xy 357.176534 -278.463157) (xy 357.152956 -278.509431) (xy 357.12243 -278.551447)
			(xy 357.085707 -278.58817) (xy 357.043691 -278.618696) (xy 356.997417 -278.642274) (xy 356.948024 -278.658322)
			(xy 356.896729 -278.666447) (xy 356.844795 -278.666447) (xy 356.7935 -278.658322) (xy 356.744107 -278.642274)
			(xy 356.697833 -278.618696) (xy 356.655817 -278.58817) (xy 356.619094 -278.551447) (xy 356.588568 -278.509431)
			(xy 356.56499 -278.463157) (xy 356.548942 -278.413764) (xy 356.540817 -278.362469) (xy 356.261161 -278.362469)
			(xy 356.253036 -278.413764) (xy 356.236988 -278.463157) (xy 356.21341 -278.509431) (xy 356.182884 -278.551447)
			(xy 356.146161 -278.58817) (xy 356.104145 -278.618696) (xy 356.057871 -278.642274) (xy 356.008478 -278.658322)
			(xy 355.957183 -278.666447) (xy 355.905249 -278.666447) (xy 355.853954 -278.658322) (xy 355.804561 -278.642274)
			(xy 355.758287 -278.618696) (xy 355.716271 -278.58817) (xy 355.679548 -278.551447) (xy 355.649022 -278.509431)
			(xy 355.625444 -278.463157) (xy 355.609396 -278.413764) (xy 355.601271 -278.362469) (xy 355.600762 -278.336502)
			(xy 355.601312 -278.308516) (xy 355.610763 -278.253348) (xy 355.619558 -278.226774) (xy 355.627178 -278.204676)
			(xy 355.42347 -277.851616) (xy 355.400356 -277.847298) (xy 355.375423 -277.842122) (xy 355.327398 -277.825198)
			(xy 355.282538 -277.801109) (xy 355.241903 -277.770423) (xy 355.206455 -277.733869) (xy 355.177034 -277.69231)
			(xy 355.154334 -277.64673) (xy 355.138895 -277.598208) (xy 355.13108 -277.547892) (xy 355.130608 -277.522432)
			(xy 354.851716 -277.522432) (xy 354.851207 -277.548399) (xy 354.843082 -277.599694) (xy 354.827034 -277.649087)
			(xy 354.803456 -277.695361) (xy 354.77293 -277.737377) (xy 354.736207 -277.7741) (xy 354.694191 -277.804626)
			(xy 354.647917 -277.828204) (xy 354.598524 -277.844252) (xy 354.547229 -277.852377) (xy 354.495295 -277.852377)
			(xy 354.444 -277.844252) (xy 354.394607 -277.828204) (xy 354.348333 -277.804626) (xy 354.306317 -277.7741)
			(xy 354.269594 -277.737377) (xy 354.239068 -277.695361) (xy 354.21549 -277.649087) (xy 354.199442 -277.599694)
			(xy 354.191317 -277.548399) (xy 354.190808 -277.522432) (xy 353.911916 -277.522432) (xy 353.911407 -277.548399)
			(xy 353.903282 -277.599694) (xy 353.887234 -277.649087) (xy 353.863656 -277.695361) (xy 353.83313 -277.737377)
			(xy 353.796407 -277.7741) (xy 353.754391 -277.804626) (xy 353.708117 -277.828204) (xy 353.658724 -277.844252)
			(xy 353.607429 -277.852377) (xy 353.555495 -277.852377) (xy 353.5042 -277.844252) (xy 353.454807 -277.828204)
			(xy 353.408533 -277.804626) (xy 353.366517 -277.7741) (xy 353.329794 -277.737377) (xy 353.299268 -277.695361)
			(xy 353.27569 -277.649087) (xy 353.259642 -277.599694) (xy 353.251517 -277.548399) (xy 352.971607 -277.548399)
			(xy 352.963482 -277.599694) (xy 352.947434 -277.649087) (xy 352.923856 -277.695361) (xy 352.89333 -277.737377)
			(xy 352.856607 -277.7741) (xy 352.814591 -277.804626) (xy 352.768317 -277.828204) (xy 352.718924 -277.844252)
			(xy 352.667629 -277.852377) (xy 352.615695 -277.852377) (xy 352.5644 -277.844252) (xy 352.515007 -277.828204)
			(xy 352.468733 -277.804626) (xy 352.426717 -277.7741) (xy 352.389994 -277.737377) (xy 352.359468 -277.695361)
			(xy 352.33589 -277.649087) (xy 352.319842 -277.599694) (xy 352.311717 -277.548399) (xy 352.031807 -277.548399)
			(xy 352.023682 -277.599694) (xy 352.007634 -277.649087) (xy 351.984056 -277.695361) (xy 351.95353 -277.737377)
			(xy 351.916807 -277.7741) (xy 351.874791 -277.804626) (xy 351.828517 -277.828204) (xy 351.779124 -277.844252)
			(xy 351.727829 -277.852377) (xy 351.675895 -277.852377) (xy 351.6246 -277.844252) (xy 351.575207 -277.828204)
			(xy 351.528933 -277.804626) (xy 351.486917 -277.7741) (xy 351.450194 -277.737377) (xy 351.419668 -277.695361)
			(xy 351.39609 -277.649087) (xy 351.380042 -277.599694) (xy 351.371917 -277.548399) (xy 351.371408 -277.522432)
			(xy 351.371968 -277.494447) (xy 351.381413 -277.439279) (xy 351.390204 -277.412704) (xy 351.397824 -277.390606)
			(xy 351.194116 -277.0378) (xy 351.171256 -277.033482) (xy 351.146322 -277.028366) (xy 351.098334 -277.011397)
			(xy 351.053514 -276.987274) (xy 351.01292 -276.956568) (xy 350.977511 -276.920003) (xy 350.948124 -276.878444)
			(xy 350.925453 -276.832872) (xy 350.910035 -276.784364) (xy 350.902232 -276.734066) (xy 350.901762 -276.708616)
			(xy 350.622616 -276.708616) (xy 350.622107 -276.734583) (xy 350.613982 -276.785878) (xy 350.597934 -276.835271)
			(xy 350.574356 -276.881545) (xy 350.54383 -276.923561) (xy 350.507107 -276.960284) (xy 350.465091 -276.99081)
			(xy 350.418817 -277.014388) (xy 350.369424 -277.030436) (xy 350.318129 -277.038561) (xy 350.266195 -277.038561)
			(xy 350.2149 -277.030436) (xy 350.165507 -277.014388) (xy 350.119233 -276.99081) (xy 350.077217 -276.960284)
			(xy 350.040494 -276.923561) (xy 350.009968 -276.881545) (xy 349.98639 -276.835271) (xy 349.970342 -276.785878)
			(xy 349.962217 -276.734583) (xy 349.961708 -276.708616) (xy 349.68307 -276.708616) (xy 349.682561 -276.734583)
			(xy 349.674436 -276.785878) (xy 349.658388 -276.835271) (xy 349.63481 -276.881545) (xy 349.604284 -276.923561)
			(xy 349.567561 -276.960284) (xy 349.525545 -276.99081) (xy 349.479271 -277.014388) (xy 349.429878 -277.030436)
			(xy 349.378583 -277.038561) (xy 349.326649 -277.038561) (xy 349.275354 -277.030436) (xy 349.225961 -277.014388)
			(xy 349.179687 -276.99081) (xy 349.137671 -276.960284) (xy 349.100948 -276.923561) (xy 349.070422 -276.881545)
			(xy 349.046844 -276.835271) (xy 349.030796 -276.785878) (xy 349.022671 -276.734583) (xy 348.742761 -276.734583)
			(xy 348.734636 -276.785878) (xy 348.718588 -276.835271) (xy 348.69501 -276.881545) (xy 348.664484 -276.923561)
			(xy 348.627761 -276.960284) (xy 348.585745 -276.99081) (xy 348.539471 -277.014388) (xy 348.490078 -277.030436)
			(xy 348.438783 -277.038561) (xy 348.386849 -277.038561) (xy 348.335554 -277.030436) (xy 348.286161 -277.014388)
			(xy 348.239887 -276.99081) (xy 348.197871 -276.960284) (xy 348.161148 -276.923561) (xy 348.130622 -276.881545)
			(xy 348.107044 -276.835271) (xy 348.090996 -276.785878) (xy 348.082871 -276.734583) (xy 347.802961 -276.734583)
			(xy 347.794836 -276.785878) (xy 347.778788 -276.835271) (xy 347.75521 -276.881545) (xy 347.724684 -276.923561)
			(xy 347.687961 -276.960284) (xy 347.645945 -276.99081) (xy 347.599671 -277.014388) (xy 347.550278 -277.030436)
			(xy 347.498983 -277.038561) (xy 347.447049 -277.038561) (xy 347.395754 -277.030436) (xy 347.346361 -277.014388)
			(xy 347.300087 -276.99081) (xy 347.258071 -276.960284) (xy 347.221348 -276.923561) (xy 347.190822 -276.881545)
			(xy 347.167244 -276.835271) (xy 347.151196 -276.785878) (xy 347.143071 -276.734583) (xy 346.863161 -276.734583)
			(xy 346.855036 -276.785878) (xy 346.838988 -276.835271) (xy 346.81541 -276.881545) (xy 346.784884 -276.923561)
			(xy 346.748161 -276.960284) (xy 346.706145 -276.99081) (xy 346.659871 -277.014388) (xy 346.610478 -277.030436)
			(xy 346.559183 -277.038561) (xy 346.507249 -277.038561) (xy 346.455954 -277.030436) (xy 346.406561 -277.014388)
			(xy 346.360287 -276.99081) (xy 346.318271 -276.960284) (xy 346.281548 -276.923561) (xy 346.251022 -276.881545)
			(xy 346.227444 -276.835271) (xy 346.211396 -276.785878) (xy 346.203271 -276.734583) (xy 345.923107 -276.734583)
			(xy 345.914982 -276.785878) (xy 345.898934 -276.835271) (xy 345.875356 -276.881545) (xy 345.84483 -276.923561)
			(xy 345.808107 -276.960284) (xy 345.766091 -276.99081) (xy 345.719817 -277.014388) (xy 345.670424 -277.030436)
			(xy 345.619129 -277.038561) (xy 345.567195 -277.038561) (xy 345.5159 -277.030436) (xy 345.466507 -277.014388)
			(xy 345.420233 -276.99081) (xy 345.378217 -276.960284) (xy 345.341494 -276.923561) (xy 345.310968 -276.881545)
			(xy 345.28739 -276.835271) (xy 345.271342 -276.785878) (xy 345.263217 -276.734583) (xy 344.983538 -276.734583)
			(xy 344.975584 -276.785232) (xy 344.959797 -276.834257) (xy 344.936595 -276.880238) (xy 344.906541 -276.922064)
			(xy 344.870362 -276.95872) (xy 344.828934 -276.98932) (xy 344.783261 -277.013123) (xy 344.734448 -277.029551)
			(xy 344.683677 -277.038208) (xy 344.657934 -277.03907) (xy 344.644724 -277.039655) (xy 344.619265 -277.04676)
			(xy 344.596483 -277.060163) (xy 344.577907 -277.078967) (xy 344.564781 -277.10191) (xy 344.557987 -277.127454)
			(xy 344.557604 -277.14067) (xy 344.557604 -277.548399) (xy 344.793317 -277.548399) (xy 344.793317 -277.496465)
			(xy 344.801442 -277.44517) (xy 344.81749 -277.395777) (xy 344.841068 -277.349503) (xy 344.871594 -277.307487)
			(xy 344.908317 -277.270764) (xy 344.950333 -277.240238) (xy 344.996607 -277.21666) (xy 345.046 -277.200612)
			(xy 345.097295 -277.192487) (xy 345.149229 -277.192487) (xy 345.200524 -277.200612) (xy 345.249917 -277.21666)
			(xy 345.296191 -277.240238) (xy 345.338207 -277.270764) (xy 345.37493 -277.307487) (xy 345.405456 -277.349503)
			(xy 345.429034 -277.395777) (xy 345.445082 -277.44517) (xy 345.453207 -277.496465) (xy 345.453716 -277.522432)
			(xy 345.453207 -277.548399) (xy 345.733117 -277.548399) (xy 345.733117 -277.496465) (xy 345.741242 -277.44517)
			(xy 345.75729 -277.395777) (xy 345.780868 -277.349503) (xy 345.811394 -277.307487) (xy 345.848117 -277.270764)
			(xy 345.890133 -277.240238) (xy 345.936407 -277.21666) (xy 345.9858 -277.200612) (xy 346.037095 -277.192487)
			(xy 346.089029 -277.192487) (xy 346.140324 -277.200612) (xy 346.189717 -277.21666) (xy 346.235991 -277.240238)
			(xy 346.278007 -277.270764) (xy 346.31473 -277.307487) (xy 346.345256 -277.349503) (xy 346.368834 -277.395777)
			(xy 346.384882 -277.44517) (xy 346.393007 -277.496465) (xy 346.393516 -277.522432) (xy 346.393007 -277.548399)
			(xy 346.672917 -277.548399) (xy 346.672917 -277.496465) (xy 346.681042 -277.44517) (xy 346.69709 -277.395777)
			(xy 346.720668 -277.349503) (xy 346.751194 -277.307487) (xy 346.787917 -277.270764) (xy 346.829933 -277.240238)
			(xy 346.876207 -277.21666) (xy 346.9256 -277.200612) (xy 346.976895 -277.192487) (xy 347.028829 -277.192487)
			(xy 347.080124 -277.200612) (xy 347.129517 -277.21666) (xy 347.175791 -277.240238) (xy 347.217807 -277.270764)
			(xy 347.25453 -277.307487) (xy 347.285056 -277.349503) (xy 347.308634 -277.395777) (xy 347.324682 -277.44517)
			(xy 347.332807 -277.496465) (xy 347.333316 -277.522432) (xy 347.332807 -277.548399) (xy 347.612717 -277.548399)
			(xy 347.612717 -277.496465) (xy 347.620842 -277.44517) (xy 347.63689 -277.395777) (xy 347.660468 -277.349503)
			(xy 347.690994 -277.307487) (xy 347.727717 -277.270764) (xy 347.769733 -277.240238) (xy 347.816007 -277.21666)
			(xy 347.8654 -277.200612) (xy 347.916695 -277.192487) (xy 347.968629 -277.192487) (xy 348.019924 -277.200612)
			(xy 348.069317 -277.21666) (xy 348.115591 -277.240238) (xy 348.157607 -277.270764) (xy 348.19433 -277.307487)
			(xy 348.224856 -277.349503) (xy 348.248434 -277.395777) (xy 348.264482 -277.44517) (xy 348.272607 -277.496465)
			(xy 348.273116 -277.522432) (xy 348.272607 -277.548399) (xy 348.552517 -277.548399) (xy 348.552517 -277.496465)
			(xy 348.560642 -277.44517) (xy 348.57669 -277.395777) (xy 348.600268 -277.349503) (xy 348.630794 -277.307487)
			(xy 348.667517 -277.270764) (xy 348.709533 -277.240238) (xy 348.755807 -277.21666) (xy 348.8052 -277.200612)
			(xy 348.856495 -277.192487) (xy 348.908429 -277.192487) (xy 348.959724 -277.200612) (xy 349.009117 -277.21666)
			(xy 349.055391 -277.240238) (xy 349.097407 -277.270764) (xy 349.13413 -277.307487) (xy 349.164656 -277.349503)
			(xy 349.188234 -277.395777) (xy 349.204282 -277.44517) (xy 349.212407 -277.496465) (xy 349.212916 -277.522432)
			(xy 349.212407 -277.548399) (xy 349.492571 -277.548399) (xy 349.492571 -277.496465) (xy 349.500696 -277.44517)
			(xy 349.516744 -277.395777) (xy 349.540322 -277.349503) (xy 349.570848 -277.307487) (xy 349.607571 -277.270764)
			(xy 349.649587 -277.240238) (xy 349.695861 -277.21666) (xy 349.745254 -277.200612) (xy 349.796549 -277.192487)
			(xy 349.848483 -277.192487) (xy 349.899778 -277.200612) (xy 349.949171 -277.21666) (xy 349.995445 -277.240238)
			(xy 350.037461 -277.270764) (xy 350.074184 -277.307487) (xy 350.10471 -277.349503) (xy 350.128288 -277.395777)
			(xy 350.144336 -277.44517) (xy 350.152461 -277.496465) (xy 350.15297 -277.522432) (xy 350.152461 -277.548399)
			(xy 350.432117 -277.548399) (xy 350.432117 -277.496465) (xy 350.440242 -277.44517) (xy 350.45629 -277.395777)
			(xy 350.479868 -277.349503) (xy 350.510394 -277.307487) (xy 350.547117 -277.270764) (xy 350.589133 -277.240238)
			(xy 350.635407 -277.21666) (xy 350.6848 -277.200612) (xy 350.736095 -277.192487) (xy 350.788029 -277.192487)
			(xy 350.839324 -277.200612) (xy 350.888717 -277.21666) (xy 350.934991 -277.240238) (xy 350.977007 -277.270764)
			(xy 351.01373 -277.307487) (xy 351.044256 -277.349503) (xy 351.067834 -277.395777) (xy 351.083882 -277.44517)
			(xy 351.092007 -277.496465) (xy 351.092516 -277.522432) (xy 351.092007 -277.548399) (xy 351.083882 -277.599694)
			(xy 351.067834 -277.649087) (xy 351.044256 -277.695361) (xy 351.01373 -277.737377) (xy 350.977007 -277.7741)
			(xy 350.934991 -277.804626) (xy 350.888717 -277.828204) (xy 350.839324 -277.844252) (xy 350.788029 -277.852377)
			(xy 350.736095 -277.852377) (xy 350.6848 -277.844252) (xy 350.635407 -277.828204) (xy 350.589133 -277.804626)
			(xy 350.547117 -277.7741) (xy 350.510394 -277.737377) (xy 350.479868 -277.695361) (xy 350.45629 -277.649087)
			(xy 350.440242 -277.599694) (xy 350.432117 -277.548399) (xy 350.152461 -277.548399) (xy 350.144336 -277.599694)
			(xy 350.128288 -277.649087) (xy 350.10471 -277.695361) (xy 350.074184 -277.737377) (xy 350.037461 -277.7741)
			(xy 349.995445 -277.804626) (xy 349.949171 -277.828204) (xy 349.899778 -277.844252) (xy 349.848483 -277.852377)
			(xy 349.796549 -277.852377) (xy 349.745254 -277.844252) (xy 349.695861 -277.828204) (xy 349.649587 -277.804626)
			(xy 349.607571 -277.7741) (xy 349.570848 -277.737377) (xy 349.540322 -277.695361) (xy 349.516744 -277.649087)
			(xy 349.500696 -277.599694) (xy 349.492571 -277.548399) (xy 349.212407 -277.548399) (xy 349.204282 -277.599694)
			(xy 349.188234 -277.649087) (xy 349.164656 -277.695361) (xy 349.13413 -277.737377) (xy 349.097407 -277.7741)
			(xy 349.055391 -277.804626) (xy 349.009117 -277.828204) (xy 348.959724 -277.844252) (xy 348.908429 -277.852377)
			(xy 348.856495 -277.852377) (xy 348.8052 -277.844252) (xy 348.755807 -277.828204) (xy 348.709533 -277.804626)
			(xy 348.667517 -277.7741) (xy 348.630794 -277.737377) (xy 348.600268 -277.695361) (xy 348.57669 -277.649087)
			(xy 348.560642 -277.599694) (xy 348.552517 -277.548399) (xy 348.272607 -277.548399) (xy 348.264482 -277.599694)
			(xy 348.248434 -277.649087) (xy 348.224856 -277.695361) (xy 348.19433 -277.737377) (xy 348.157607 -277.7741)
			(xy 348.115591 -277.804626) (xy 348.069317 -277.828204) (xy 348.019924 -277.844252) (xy 347.968629 -277.852377)
			(xy 347.916695 -277.852377) (xy 347.8654 -277.844252) (xy 347.816007 -277.828204) (xy 347.769733 -277.804626)
			(xy 347.727717 -277.7741) (xy 347.690994 -277.737377) (xy 347.660468 -277.695361) (xy 347.63689 -277.649087)
			(xy 347.620842 -277.599694) (xy 347.612717 -277.548399) (xy 347.332807 -277.548399) (xy 347.324682 -277.599694)
			(xy 347.308634 -277.649087) (xy 347.285056 -277.695361) (xy 347.25453 -277.737377) (xy 347.217807 -277.7741)
			(xy 347.175791 -277.804626) (xy 347.129517 -277.828204) (xy 347.080124 -277.844252) (xy 347.028829 -277.852377)
			(xy 346.976895 -277.852377) (xy 346.9256 -277.844252) (xy 346.876207 -277.828204) (xy 346.829933 -277.804626)
			(xy 346.787917 -277.7741) (xy 346.751194 -277.737377) (xy 346.720668 -277.695361) (xy 346.69709 -277.649087)
			(xy 346.681042 -277.599694) (xy 346.672917 -277.548399) (xy 346.393007 -277.548399) (xy 346.384882 -277.599694)
			(xy 346.368834 -277.649087) (xy 346.345256 -277.695361) (xy 346.31473 -277.737377) (xy 346.278007 -277.7741)
			(xy 346.235991 -277.804626) (xy 346.189717 -277.828204) (xy 346.140324 -277.844252) (xy 346.089029 -277.852377)
			(xy 346.037095 -277.852377) (xy 345.9858 -277.844252) (xy 345.936407 -277.828204) (xy 345.890133 -277.804626)
			(xy 345.848117 -277.7741) (xy 345.811394 -277.737377) (xy 345.780868 -277.695361) (xy 345.75729 -277.649087)
			(xy 345.741242 -277.599694) (xy 345.733117 -277.548399) (xy 345.453207 -277.548399) (xy 345.445082 -277.599694)
			(xy 345.429034 -277.649087) (xy 345.405456 -277.695361) (xy 345.37493 -277.737377) (xy 345.338207 -277.7741)
			(xy 345.296191 -277.804626) (xy 345.249917 -277.828204) (xy 345.200524 -277.844252) (xy 345.149229 -277.852377)
			(xy 345.097295 -277.852377) (xy 345.046 -277.844252) (xy 344.996607 -277.828204) (xy 344.950333 -277.804626)
			(xy 344.908317 -277.7741) (xy 344.871594 -277.737377) (xy 344.841068 -277.695361) (xy 344.81749 -277.649087)
			(xy 344.801442 -277.599694) (xy 344.793317 -277.548399) (xy 344.557604 -277.548399) (xy 344.557604 -277.904448)
			(xy 344.55803 -277.917657) (xy 344.564825 -277.943187) (xy 344.577946 -277.966116) (xy 344.596515 -277.984908)
			(xy 344.619285 -277.998303) (xy 344.644732 -278.005404) (xy 344.657934 -278.006048) (xy 344.683678 -278.006878)
			(xy 344.734451 -278.015535) (xy 344.783267 -278.031964) (xy 344.828942 -278.055768) (xy 344.870372 -278.086369)
			(xy 344.906552 -278.123027) (xy 344.936607 -278.164855) (xy 344.95981 -278.210838) (xy 344.975597 -278.259865)
			(xy 344.983588 -278.310747) (xy 344.983588 -278.362253) (xy 344.983554 -278.362469) (xy 345.263471 -278.362469)
			(xy 345.263471 -278.310535) (xy 345.271596 -278.25924) (xy 345.287644 -278.209847) (xy 345.311222 -278.163573)
			(xy 345.341748 -278.121557) (xy 345.378471 -278.084834) (xy 345.420487 -278.054308) (xy 345.466761 -278.03073)
			(xy 345.516154 -278.014682) (xy 345.567449 -278.006557) (xy 345.619383 -278.006557) (xy 345.670678 -278.014682)
			(xy 345.720071 -278.03073) (xy 345.766345 -278.054308) (xy 345.808361 -278.084834) (xy 345.845084 -278.121557)
			(xy 345.87561 -278.163573) (xy 345.899188 -278.209847) (xy 345.915236 -278.25924) (xy 345.923361 -278.310535)
			(xy 345.92387 -278.336502) (xy 345.923361 -278.362469) (xy 346.203271 -278.362469) (xy 346.203271 -278.310535)
			(xy 346.211396 -278.25924) (xy 346.227444 -278.209847) (xy 346.251022 -278.163573) (xy 346.281548 -278.121557)
			(xy 346.318271 -278.084834) (xy 346.360287 -278.054308) (xy 346.406561 -278.03073) (xy 346.455954 -278.014682)
			(xy 346.507249 -278.006557) (xy 346.559183 -278.006557) (xy 346.610478 -278.014682) (xy 346.659871 -278.03073)
			(xy 346.706145 -278.054308) (xy 346.748161 -278.084834) (xy 346.784884 -278.121557) (xy 346.81541 -278.163573)
			(xy 346.838988 -278.209847) (xy 346.855036 -278.25924) (xy 346.863161 -278.310535) (xy 346.86367 -278.336502)
			(xy 346.863161 -278.362469) (xy 347.143071 -278.362469) (xy 347.143071 -278.310535) (xy 347.151196 -278.25924)
			(xy 347.167244 -278.209847) (xy 347.190822 -278.163573) (xy 347.221348 -278.121557) (xy 347.258071 -278.084834)
			(xy 347.300087 -278.054308) (xy 347.346361 -278.03073) (xy 347.395754 -278.014682) (xy 347.447049 -278.006557)
			(xy 347.498983 -278.006557) (xy 347.550278 -278.014682) (xy 347.599671 -278.03073) (xy 347.645945 -278.054308)
			(xy 347.687961 -278.084834) (xy 347.724684 -278.121557) (xy 347.75521 -278.163573) (xy 347.778788 -278.209847)
			(xy 347.794836 -278.25924) (xy 347.802961 -278.310535) (xy 347.80347 -278.336502) (xy 347.802961 -278.362469)
			(xy 348.082871 -278.362469) (xy 348.082871 -278.310535) (xy 348.090996 -278.25924) (xy 348.107044 -278.209847)
			(xy 348.130622 -278.163573) (xy 348.161148 -278.121557) (xy 348.197871 -278.084834) (xy 348.239887 -278.054308)
			(xy 348.286161 -278.03073) (xy 348.335554 -278.014682) (xy 348.386849 -278.006557) (xy 348.438783 -278.006557)
			(xy 348.490078 -278.014682) (xy 348.539471 -278.03073) (xy 348.585745 -278.054308) (xy 348.627761 -278.084834)
			(xy 348.664484 -278.121557) (xy 348.69501 -278.163573) (xy 348.718588 -278.209847) (xy 348.734636 -278.25924)
			(xy 348.742761 -278.310535) (xy 348.74327 -278.336502) (xy 348.742761 -278.362469) (xy 349.022417 -278.362469)
			(xy 349.022417 -278.310535) (xy 349.030542 -278.25924) (xy 349.04659 -278.209847) (xy 349.070168 -278.163573)
			(xy 349.100694 -278.121557) (xy 349.137417 -278.084834) (xy 349.179433 -278.054308) (xy 349.225707 -278.03073)
			(xy 349.2751 -278.014682) (xy 349.326395 -278.006557) (xy 349.378329 -278.006557) (xy 349.429624 -278.014682)
			(xy 349.479017 -278.03073) (xy 349.525291 -278.054308) (xy 349.567307 -278.084834) (xy 349.60403 -278.121557)
			(xy 349.634556 -278.163573) (xy 349.658134 -278.209847) (xy 349.674182 -278.25924) (xy 349.682307 -278.310535)
			(xy 349.682816 -278.336502) (xy 349.682307 -278.362469) (xy 349.962471 -278.362469) (xy 349.962471 -278.310535)
			(xy 349.970596 -278.25924) (xy 349.986644 -278.209847) (xy 350.010222 -278.163573) (xy 350.040748 -278.121557)
			(xy 350.077471 -278.084834) (xy 350.119487 -278.054308) (xy 350.165761 -278.03073) (xy 350.215154 -278.014682)
			(xy 350.266449 -278.006557) (xy 350.318383 -278.006557) (xy 350.369678 -278.014682) (xy 350.419071 -278.03073)
			(xy 350.465345 -278.054308) (xy 350.507361 -278.084834) (xy 350.544084 -278.121557) (xy 350.57461 -278.163573)
			(xy 350.598188 -278.209847) (xy 350.614236 -278.25924) (xy 350.622361 -278.310535) (xy 350.62287 -278.336502)
			(xy 350.622361 -278.362469) (xy 350.902271 -278.362469) (xy 350.902271 -278.310535) (xy 350.910396 -278.25924)
			(xy 350.926444 -278.209847) (xy 350.950022 -278.163573) (xy 350.980548 -278.121557) (xy 351.017271 -278.084834)
			(xy 351.059287 -278.054308) (xy 351.105561 -278.03073) (xy 351.154954 -278.014682) (xy 351.206249 -278.006557)
			(xy 351.258183 -278.006557) (xy 351.309478 -278.014682) (xy 351.358871 -278.03073) (xy 351.405145 -278.054308)
			(xy 351.447161 -278.084834) (xy 351.483884 -278.121557) (xy 351.51441 -278.163573) (xy 351.537988 -278.209847)
			(xy 351.554036 -278.25924) (xy 351.562161 -278.310535) (xy 351.56267 -278.336502) (xy 351.562161 -278.362469)
			(xy 351.842071 -278.362469) (xy 351.842071 -278.310535) (xy 351.850196 -278.25924) (xy 351.866244 -278.209847)
			(xy 351.889822 -278.163573) (xy 351.920348 -278.121557) (xy 351.957071 -278.084834) (xy 351.999087 -278.054308)
			(xy 352.045361 -278.03073) (xy 352.094754 -278.014682) (xy 352.146049 -278.006557) (xy 352.197983 -278.006557)
			(xy 352.249278 -278.014682) (xy 352.298671 -278.03073) (xy 352.344945 -278.054308) (xy 352.386961 -278.084834)
			(xy 352.423684 -278.121557) (xy 352.45421 -278.163573) (xy 352.477788 -278.209847) (xy 352.493836 -278.25924)
			(xy 352.501961 -278.310535) (xy 352.50247 -278.336502) (xy 352.501961 -278.362469) (xy 352.781617 -278.362469)
			(xy 352.781617 -278.310535) (xy 352.789742 -278.25924) (xy 352.80579 -278.209847) (xy 352.829368 -278.163573)
			(xy 352.859894 -278.121557) (xy 352.896617 -278.084834) (xy 352.938633 -278.054308) (xy 352.984907 -278.03073)
			(xy 353.0343 -278.014682) (xy 353.085595 -278.006557) (xy 353.137529 -278.006557) (xy 353.188824 -278.014682)
			(xy 353.238217 -278.03073) (xy 353.284491 -278.054308) (xy 353.326507 -278.084834) (xy 353.36323 -278.121557)
			(xy 353.393756 -278.163573) (xy 353.417334 -278.209847) (xy 353.433382 -278.25924) (xy 353.441507 -278.310535)
			(xy 353.442016 -278.336502) (xy 353.441507 -278.362469) (xy 353.721671 -278.362469) (xy 353.721671 -278.310535)
			(xy 353.729796 -278.25924) (xy 353.745844 -278.209847) (xy 353.769422 -278.163573) (xy 353.799948 -278.121557)
			(xy 353.836671 -278.084834) (xy 353.878687 -278.054308) (xy 353.924961 -278.03073) (xy 353.974354 -278.014682)
			(xy 354.025649 -278.006557) (xy 354.077583 -278.006557) (xy 354.128878 -278.014682) (xy 354.178271 -278.03073)
			(xy 354.224545 -278.054308) (xy 354.266561 -278.084834) (xy 354.303284 -278.121557) (xy 354.33381 -278.163573)
			(xy 354.357388 -278.209847) (xy 354.373436 -278.25924) (xy 354.381561 -278.310535) (xy 354.38207 -278.336502)
			(xy 354.381561 -278.362469) (xy 354.661471 -278.362469) (xy 354.661471 -278.310535) (xy 354.669596 -278.25924)
			(xy 354.685644 -278.209847) (xy 354.709222 -278.163573) (xy 354.739748 -278.121557) (xy 354.776471 -278.084834)
			(xy 354.818487 -278.054308) (xy 354.864761 -278.03073) (xy 354.914154 -278.014682) (xy 354.965449 -278.006557)
			(xy 355.017383 -278.006557) (xy 355.068678 -278.014682) (xy 355.118071 -278.03073) (xy 355.164345 -278.054308)
			(xy 355.206361 -278.084834) (xy 355.243084 -278.121557) (xy 355.27361 -278.163573) (xy 355.297188 -278.209847)
			(xy 355.313236 -278.25924) (xy 355.321361 -278.310535) (xy 355.32187 -278.336502) (xy 355.321361 -278.362469)
			(xy 355.313236 -278.413764) (xy 355.297188 -278.463157) (xy 355.27361 -278.509431) (xy 355.243084 -278.551447)
			(xy 355.206361 -278.58817) (xy 355.164345 -278.618696) (xy 355.118071 -278.642274) (xy 355.068678 -278.658322)
			(xy 355.017383 -278.666447) (xy 354.965449 -278.666447) (xy 354.914154 -278.658322) (xy 354.864761 -278.642274)
			(xy 354.818487 -278.618696) (xy 354.776471 -278.58817) (xy 354.739748 -278.551447) (xy 354.709222 -278.509431)
			(xy 354.685644 -278.463157) (xy 354.669596 -278.413764) (xy 354.661471 -278.362469) (xy 354.381561 -278.362469)
			(xy 354.373436 -278.413764) (xy 354.357388 -278.463157) (xy 354.33381 -278.509431) (xy 354.303284 -278.551447)
			(xy 354.266561 -278.58817) (xy 354.224545 -278.618696) (xy 354.178271 -278.642274) (xy 354.128878 -278.658322)
			(xy 354.077583 -278.666447) (xy 354.025649 -278.666447) (xy 353.974354 -278.658322) (xy 353.924961 -278.642274)
			(xy 353.878687 -278.618696) (xy 353.836671 -278.58817) (xy 353.799948 -278.551447) (xy 353.769422 -278.509431)
			(xy 353.745844 -278.463157) (xy 353.729796 -278.413764) (xy 353.721671 -278.362469) (xy 353.441507 -278.362469)
			(xy 353.433382 -278.413764) (xy 353.417334 -278.463157) (xy 353.393756 -278.509431) (xy 353.36323 -278.551447)
			(xy 353.326507 -278.58817) (xy 353.284491 -278.618696) (xy 353.238217 -278.642274) (xy 353.188824 -278.658322)
			(xy 353.137529 -278.666447) (xy 353.085595 -278.666447) (xy 353.0343 -278.658322) (xy 352.984907 -278.642274)
			(xy 352.938633 -278.618696) (xy 352.896617 -278.58817) (xy 352.859894 -278.551447) (xy 352.829368 -278.509431)
			(xy 352.80579 -278.463157) (xy 352.789742 -278.413764) (xy 352.781617 -278.362469) (xy 352.501961 -278.362469)
			(xy 352.493836 -278.413764) (xy 352.477788 -278.463157) (xy 352.45421 -278.509431) (xy 352.423684 -278.551447)
			(xy 352.386961 -278.58817) (xy 352.344945 -278.618696) (xy 352.298671 -278.642274) (xy 352.249278 -278.658322)
			(xy 352.197983 -278.666447) (xy 352.146049 -278.666447) (xy 352.094754 -278.658322) (xy 352.045361 -278.642274)
			(xy 351.999087 -278.618696) (xy 351.957071 -278.58817) (xy 351.920348 -278.551447) (xy 351.889822 -278.509431)
			(xy 351.866244 -278.463157) (xy 351.850196 -278.413764) (xy 351.842071 -278.362469) (xy 351.562161 -278.362469)
			(xy 351.554036 -278.413764) (xy 351.537988 -278.463157) (xy 351.51441 -278.509431) (xy 351.483884 -278.551447)
			(xy 351.447161 -278.58817) (xy 351.405145 -278.618696) (xy 351.358871 -278.642274) (xy 351.309478 -278.658322)
			(xy 351.258183 -278.666447) (xy 351.206249 -278.666447) (xy 351.154954 -278.658322) (xy 351.105561 -278.642274)
			(xy 351.059287 -278.618696) (xy 351.017271 -278.58817) (xy 350.980548 -278.551447) (xy 350.950022 -278.509431)
			(xy 350.926444 -278.463157) (xy 350.910396 -278.413764) (xy 350.902271 -278.362469) (xy 350.622361 -278.362469)
			(xy 350.614236 -278.413764) (xy 350.598188 -278.463157) (xy 350.57461 -278.509431) (xy 350.544084 -278.551447)
			(xy 350.507361 -278.58817) (xy 350.465345 -278.618696) (xy 350.419071 -278.642274) (xy 350.369678 -278.658322)
			(xy 350.318383 -278.666447) (xy 350.266449 -278.666447) (xy 350.215154 -278.658322) (xy 350.165761 -278.642274)
			(xy 350.119487 -278.618696) (xy 350.077471 -278.58817) (xy 350.040748 -278.551447) (xy 350.010222 -278.509431)
			(xy 349.986644 -278.463157) (xy 349.970596 -278.413764) (xy 349.962471 -278.362469) (xy 349.682307 -278.362469)
			(xy 349.674182 -278.413764) (xy 349.658134 -278.463157) (xy 349.634556 -278.509431) (xy 349.60403 -278.551447)
			(xy 349.567307 -278.58817) (xy 349.525291 -278.618696) (xy 349.479017 -278.642274) (xy 349.429624 -278.658322)
			(xy 349.378329 -278.666447) (xy 349.326395 -278.666447) (xy 349.2751 -278.658322) (xy 349.225707 -278.642274)
			(xy 349.179433 -278.618696) (xy 349.137417 -278.58817) (xy 349.100694 -278.551447) (xy 349.070168 -278.509431)
			(xy 349.04659 -278.463157) (xy 349.030542 -278.413764) (xy 349.022417 -278.362469) (xy 348.742761 -278.362469)
			(xy 348.734636 -278.413764) (xy 348.718588 -278.463157) (xy 348.69501 -278.509431) (xy 348.664484 -278.551447)
			(xy 348.627761 -278.58817) (xy 348.585745 -278.618696) (xy 348.539471 -278.642274) (xy 348.490078 -278.658322)
			(xy 348.438783 -278.666447) (xy 348.386849 -278.666447) (xy 348.335554 -278.658322) (xy 348.286161 -278.642274)
			(xy 348.239887 -278.618696) (xy 348.197871 -278.58817) (xy 348.161148 -278.551447) (xy 348.130622 -278.509431)
			(xy 348.107044 -278.463157) (xy 348.090996 -278.413764) (xy 348.082871 -278.362469) (xy 347.802961 -278.362469)
			(xy 347.794836 -278.413764) (xy 347.778788 -278.463157) (xy 347.75521 -278.509431) (xy 347.724684 -278.551447)
			(xy 347.687961 -278.58817) (xy 347.645945 -278.618696) (xy 347.599671 -278.642274) (xy 347.550278 -278.658322)
			(xy 347.498983 -278.666447) (xy 347.447049 -278.666447) (xy 347.395754 -278.658322) (xy 347.346361 -278.642274)
			(xy 347.300087 -278.618696) (xy 347.258071 -278.58817) (xy 347.221348 -278.551447) (xy 347.190822 -278.509431)
			(xy 347.167244 -278.463157) (xy 347.151196 -278.413764) (xy 347.143071 -278.362469) (xy 346.863161 -278.362469)
			(xy 346.855036 -278.413764) (xy 346.838988 -278.463157) (xy 346.81541 -278.509431) (xy 346.784884 -278.551447)
			(xy 346.748161 -278.58817) (xy 346.706145 -278.618696) (xy 346.659871 -278.642274) (xy 346.610478 -278.658322)
			(xy 346.559183 -278.666447) (xy 346.507249 -278.666447) (xy 346.455954 -278.658322) (xy 346.406561 -278.642274)
			(xy 346.360287 -278.618696) (xy 346.318271 -278.58817) (xy 346.281548 -278.551447) (xy 346.251022 -278.509431)
			(xy 346.227444 -278.463157) (xy 346.211396 -278.413764) (xy 346.203271 -278.362469) (xy 345.923361 -278.362469)
			(xy 345.915236 -278.413764) (xy 345.899188 -278.463157) (xy 345.87561 -278.509431) (xy 345.845084 -278.551447)
			(xy 345.808361 -278.58817) (xy 345.766345 -278.618696) (xy 345.720071 -278.642274) (xy 345.670678 -278.658322)
			(xy 345.619383 -278.666447) (xy 345.567449 -278.666447) (xy 345.516154 -278.658322) (xy 345.466761 -278.642274)
			(xy 345.420487 -278.618696) (xy 345.378471 -278.58817) (xy 345.341748 -278.551447) (xy 345.311222 -278.509431)
			(xy 345.287644 -278.463157) (xy 345.271596 -278.413764) (xy 345.263471 -278.362469) (xy 344.983554 -278.362469)
			(xy 344.975597 -278.413135) (xy 344.95981 -278.462162) (xy 344.936607 -278.508145) (xy 344.906552 -278.549973)
			(xy 344.870372 -278.586631) (xy 344.828942 -278.617232) (xy 344.783267 -278.641036) (xy 344.734451 -278.657465)
			(xy 344.683678 -278.666122) (xy 344.657934 -278.666956) (xy 344.644728 -278.667542) (xy 344.619278 -278.674648)
			(xy 344.596507 -278.688054) (xy 344.577945 -278.70686) (xy 344.564836 -278.729803) (xy 344.558062 -278.755344)
			(xy 344.557604 -278.768556) (xy 344.557604 -279.176285) (xy 344.793317 -279.176285) (xy 344.793317 -279.124351)
			(xy 344.801442 -279.073056) (xy 344.81749 -279.023663) (xy 344.841068 -278.977389) (xy 344.871594 -278.935373)
			(xy 344.908317 -278.89865) (xy 344.950333 -278.868124) (xy 344.996607 -278.844546) (xy 345.046 -278.828498)
			(xy 345.097295 -278.820373) (xy 345.149229 -278.820373) (xy 345.200524 -278.828498) (xy 345.249917 -278.844546)
			(xy 345.296191 -278.868124) (xy 345.338207 -278.89865) (xy 345.37493 -278.935373) (xy 345.405456 -278.977389)
			(xy 345.429034 -279.023663) (xy 345.445082 -279.073056) (xy 345.453207 -279.124351) (xy 345.453716 -279.150318)
			(xy 345.453207 -279.176285) (xy 345.733371 -279.176285) (xy 345.733371 -279.124351) (xy 345.741496 -279.073056)
			(xy 345.757544 -279.023663) (xy 345.781122 -278.977389) (xy 345.811648 -278.935373) (xy 345.848371 -278.89865)
			(xy 345.890387 -278.868124) (xy 345.936661 -278.844546) (xy 345.986054 -278.828498) (xy 346.037349 -278.820373)
			(xy 346.089283 -278.820373) (xy 346.140578 -278.828498) (xy 346.189971 -278.844546) (xy 346.236245 -278.868124)
			(xy 346.278261 -278.89865) (xy 346.314984 -278.935373) (xy 346.34551 -278.977389) (xy 346.369088 -279.023663)
			(xy 346.385136 -279.073056) (xy 346.393261 -279.124351) (xy 346.39377 -279.150318) (xy 346.393261 -279.176285)
			(xy 346.672917 -279.176285) (xy 346.672917 -279.124351) (xy 346.681042 -279.073056) (xy 346.69709 -279.023663)
			(xy 346.720668 -278.977389) (xy 346.751194 -278.935373) (xy 346.787917 -278.89865) (xy 346.829933 -278.868124)
			(xy 346.876207 -278.844546) (xy 346.9256 -278.828498) (xy 346.976895 -278.820373) (xy 347.028829 -278.820373)
			(xy 347.080124 -278.828498) (xy 347.129517 -278.844546) (xy 347.175791 -278.868124) (xy 347.217807 -278.89865)
			(xy 347.25453 -278.935373) (xy 347.285056 -278.977389) (xy 347.308634 -279.023663) (xy 347.324682 -279.073056)
			(xy 347.332807 -279.124351) (xy 347.333316 -279.150318) (xy 347.332807 -279.176285) (xy 347.612717 -279.176285)
			(xy 347.612717 -279.124351) (xy 347.620842 -279.073056) (xy 347.63689 -279.023663) (xy 347.660468 -278.977389)
			(xy 347.690994 -278.935373) (xy 347.727717 -278.89865) (xy 347.769733 -278.868124) (xy 347.816007 -278.844546)
			(xy 347.8654 -278.828498) (xy 347.916695 -278.820373) (xy 347.968629 -278.820373) (xy 348.019924 -278.828498)
			(xy 348.069317 -278.844546) (xy 348.115591 -278.868124) (xy 348.157607 -278.89865) (xy 348.19433 -278.935373)
			(xy 348.224856 -278.977389) (xy 348.248434 -279.023663) (xy 348.264482 -279.073056) (xy 348.272607 -279.124351)
			(xy 348.273116 -279.150318) (xy 348.272607 -279.176285) (xy 348.552771 -279.176285) (xy 348.552771 -279.124351)
			(xy 348.560896 -279.073056) (xy 348.576944 -279.023663) (xy 348.600522 -278.977389) (xy 348.631048 -278.935373)
			(xy 348.667771 -278.89865) (xy 348.709787 -278.868124) (xy 348.756061 -278.844546) (xy 348.805454 -278.828498)
			(xy 348.856749 -278.820373) (xy 348.908683 -278.820373) (xy 348.959978 -278.828498) (xy 349.009371 -278.844546)
			(xy 349.055645 -278.868124) (xy 349.097661 -278.89865) (xy 349.134384 -278.935373) (xy 349.16491 -278.977389)
			(xy 349.188488 -279.023663) (xy 349.204536 -279.073056) (xy 349.212661 -279.124351) (xy 349.21317 -279.150318)
			(xy 349.491808 -279.150318) (xy 349.492317 -279.124351) (xy 349.500442 -279.073056) (xy 349.51649 -279.023663)
			(xy 349.540068 -278.977389) (xy 349.570594 -278.935373) (xy 349.607317 -278.89865) (xy 349.649333 -278.868124)
			(xy 349.695607 -278.844546) (xy 349.745 -278.828498) (xy 349.796295 -278.820373) (xy 349.848229 -278.820373)
			(xy 349.899524 -278.828498) (xy 349.948917 -278.844546) (xy 349.995191 -278.868124) (xy 350.037207 -278.89865)
			(xy 350.07393 -278.935373) (xy 350.104456 -278.977389) (xy 350.128034 -279.023663) (xy 350.144082 -279.073056)
			(xy 350.152207 -279.124351) (xy 350.152716 -279.150318) (xy 350.152185 -279.176264) (xy 350.432173 -279.176264)
			(xy 350.432173 -279.124336) (xy 350.440296 -279.073048) (xy 350.456341 -279.023661) (xy 350.479914 -278.977392)
			(xy 350.510435 -278.93538) (xy 350.547151 -278.89866) (xy 350.58916 -278.868134) (xy 350.635426 -278.844556)
			(xy 350.684811 -278.828505) (xy 350.736098 -278.820376) (xy 350.762062 -278.819864) (xy 350.787696 -278.820388)
			(xy 350.838349 -278.828306) (xy 350.88717 -278.843958) (xy 350.932985 -278.866968) (xy 350.974692 -278.896783)
			(xy 351.011291 -278.932685) (xy 351.026984 -278.95296) (xy 351.43694 -278.95296) (xy 351.452646 -278.932694)
			(xy 351.48924 -278.896784) (xy 351.530944 -278.866962) (xy 351.576755 -278.843943) (xy 351.625574 -278.828281)
			(xy 351.676227 -278.820351) (xy 351.701862 -278.819864) (xy 351.727835 -278.820308) (xy 351.779141 -278.828429)
			(xy 351.828545 -278.844476) (xy 351.874831 -278.868055) (xy 351.916858 -278.898585) (xy 351.95359 -278.935313)
			(xy 351.984125 -278.977337) (xy 352.007709 -279.023619) (xy 352.023762 -279.073022) (xy 352.031889 -279.124327)
			(xy 352.031889 -279.176273) (xy 352.031887 -279.176285) (xy 352.311717 -279.176285) (xy 352.311717 -279.124351)
			(xy 352.319842 -279.073056) (xy 352.33589 -279.023663) (xy 352.359468 -278.977389) (xy 352.389994 -278.935373)
			(xy 352.426717 -278.89865) (xy 352.468733 -278.868124) (xy 352.515007 -278.844546) (xy 352.5644 -278.828498)
			(xy 352.615695 -278.820373) (xy 352.667629 -278.820373) (xy 352.718924 -278.828498) (xy 352.768317 -278.844546)
			(xy 352.814591 -278.868124) (xy 352.856607 -278.89865) (xy 352.89333 -278.935373) (xy 352.923856 -278.977389)
			(xy 352.947434 -279.023663) (xy 352.963482 -279.073056) (xy 352.971607 -279.124351) (xy 352.972116 -279.150318)
			(xy 352.971607 -279.176285) (xy 353.251771 -279.176285) (xy 353.251771 -279.124351) (xy 353.259896 -279.073056)
			(xy 353.275944 -279.023663) (xy 353.299522 -278.977389) (xy 353.330048 -278.935373) (xy 353.366771 -278.89865)
			(xy 353.408787 -278.868124) (xy 353.455061 -278.844546) (xy 353.504454 -278.828498) (xy 353.555749 -278.820373)
			(xy 353.607683 -278.820373) (xy 353.658978 -278.828498) (xy 353.708371 -278.844546) (xy 353.754645 -278.868124)
			(xy 353.796661 -278.89865) (xy 353.833384 -278.935373) (xy 353.86391 -278.977389) (xy 353.887488 -279.023663)
			(xy 353.903536 -279.073056) (xy 353.911661 -279.124351) (xy 353.91217 -279.150318) (xy 353.911661 -279.176285)
			(xy 354.191571 -279.176285) (xy 354.191571 -279.124351) (xy 354.199696 -279.073056) (xy 354.215744 -279.023663)
			(xy 354.239322 -278.977389) (xy 354.269848 -278.935373) (xy 354.306571 -278.89865) (xy 354.348587 -278.868124)
			(xy 354.394861 -278.844546) (xy 354.444254 -278.828498) (xy 354.495549 -278.820373) (xy 354.547483 -278.820373)
			(xy 354.598778 -278.828498) (xy 354.648171 -278.844546) (xy 354.694445 -278.868124) (xy 354.736461 -278.89865)
			(xy 354.773184 -278.935373) (xy 354.80371 -278.977389) (xy 354.827288 -279.023663) (xy 354.843336 -279.073056)
			(xy 354.851461 -279.124351) (xy 354.85197 -279.150318) (xy 354.851461 -279.176285) (xy 355.131117 -279.176285)
			(xy 355.131117 -279.124351) (xy 355.139242 -279.073056) (xy 355.15529 -279.023663) (xy 355.178868 -278.977389)
			(xy 355.209394 -278.935373) (xy 355.246117 -278.89865) (xy 355.288133 -278.868124) (xy 355.334407 -278.844546)
			(xy 355.3838 -278.828498) (xy 355.435095 -278.820373) (xy 355.487029 -278.820373) (xy 355.538324 -278.828498)
			(xy 355.587717 -278.844546) (xy 355.633991 -278.868124) (xy 355.676007 -278.89865) (xy 355.71273 -278.935373)
			(xy 355.743256 -278.977389) (xy 355.766834 -279.023663) (xy 355.782882 -279.073056) (xy 355.791007 -279.124351)
			(xy 355.791516 -279.150318) (xy 355.791007 -279.176285) (xy 356.070917 -279.176285) (xy 356.070917 -279.124351)
			(xy 356.079042 -279.073056) (xy 356.09509 -279.023663) (xy 356.118668 -278.977389) (xy 356.149194 -278.935373)
			(xy 356.185917 -278.89865) (xy 356.227933 -278.868124) (xy 356.274207 -278.844546) (xy 356.3236 -278.828498)
			(xy 356.374895 -278.820373) (xy 356.426829 -278.820373) (xy 356.478124 -278.828498) (xy 356.527517 -278.844546)
			(xy 356.573791 -278.868124) (xy 356.615807 -278.89865) (xy 356.65253 -278.935373) (xy 356.683056 -278.977389)
			(xy 356.706634 -279.023663) (xy 356.722682 -279.073056) (xy 356.730807 -279.124351) (xy 356.731316 -279.150318)
			(xy 356.730807 -279.176285) (xy 362.649517 -279.176285) (xy 362.649517 -279.124351) (xy 362.657642 -279.073056)
			(xy 362.67369 -279.023663) (xy 362.697268 -278.977389) (xy 362.727794 -278.935373) (xy 362.764517 -278.89865)
			(xy 362.806533 -278.868124) (xy 362.852807 -278.844546) (xy 362.9022 -278.828498) (xy 362.953495 -278.820373)
			(xy 363.005429 -278.820373) (xy 363.056724 -278.828498) (xy 363.106117 -278.844546) (xy 363.152391 -278.868124)
			(xy 363.194407 -278.89865) (xy 363.23113 -278.935373) (xy 363.261656 -278.977389) (xy 363.285234 -279.023663)
			(xy 363.301282 -279.073056) (xy 363.309407 -279.124351) (xy 363.309916 -279.150318) (xy 363.309407 -279.176285)
			(xy 363.589317 -279.176285) (xy 363.589317 -279.124351) (xy 363.597442 -279.073056) (xy 363.61349 -279.023663)
			(xy 363.637068 -278.977389) (xy 363.667594 -278.935373) (xy 363.704317 -278.89865) (xy 363.746333 -278.868124)
			(xy 363.792607 -278.844546) (xy 363.842 -278.828498) (xy 363.893295 -278.820373) (xy 363.945229 -278.820373)
			(xy 363.996524 -278.828498) (xy 364.045917 -278.844546) (xy 364.092191 -278.868124) (xy 364.134207 -278.89865)
			(xy 364.17093 -278.935373) (xy 364.201456 -278.977389) (xy 364.225034 -279.023663) (xy 364.241082 -279.073056)
			(xy 364.249207 -279.124351) (xy 364.249716 -279.150318) (xy 364.249212 -279.176031) (xy 364.529371 -279.176031)
			(xy 364.529371 -279.124097) (xy 364.537496 -279.072802) (xy 364.553544 -279.023409) (xy 364.577122 -278.977135)
			(xy 364.607648 -278.935119) (xy 364.644371 -278.898396) (xy 364.686387 -278.86787) (xy 364.732661 -278.844292)
			(xy 364.782054 -278.828244) (xy 364.833349 -278.820119) (xy 364.885283 -278.820119) (xy 364.936578 -278.828244)
			(xy 364.985971 -278.844292) (xy 365.032245 -278.86787) (xy 365.074261 -278.898396) (xy 365.110984 -278.935119)
			(xy 365.14151 -278.977135) (xy 365.165088 -279.023409) (xy 365.181136 -279.072802) (xy 365.189261 -279.124097)
			(xy 365.18977 -279.150064) (xy 365.189261 -279.176031) (xy 365.189221 -279.176285) (xy 365.469171 -279.176285)
			(xy 365.469171 -279.124351) (xy 365.477296 -279.073056) (xy 365.493344 -279.023663) (xy 365.516922 -278.977389)
			(xy 365.547448 -278.935373) (xy 365.584171 -278.89865) (xy 365.626187 -278.868124) (xy 365.672461 -278.844546)
			(xy 365.721854 -278.828498) (xy 365.773149 -278.820373) (xy 365.825083 -278.820373) (xy 365.876378 -278.828498)
			(xy 365.925771 -278.844546) (xy 365.972045 -278.868124) (xy 366.014061 -278.89865) (xy 366.050784 -278.935373)
			(xy 366.08131 -278.977389) (xy 366.104888 -279.023663) (xy 366.120936 -279.073056) (xy 366.129061 -279.124351)
			(xy 366.12957 -279.150318) (xy 366.129061 -279.176285) (xy 366.408717 -279.176285) (xy 366.408717 -279.124351)
			(xy 366.416842 -279.073056) (xy 366.43289 -279.023663) (xy 366.456468 -278.977389) (xy 366.486994 -278.935373)
			(xy 366.523717 -278.89865) (xy 366.565733 -278.868124) (xy 366.612007 -278.844546) (xy 366.6614 -278.828498)
			(xy 366.712695 -278.820373) (xy 366.764629 -278.820373) (xy 366.815924 -278.828498) (xy 366.865317 -278.844546)
			(xy 366.911591 -278.868124) (xy 366.953607 -278.89865) (xy 366.99033 -278.935373) (xy 367.020856 -278.977389)
			(xy 367.044434 -279.023663) (xy 367.060482 -279.073056) (xy 367.068607 -279.124351) (xy 367.069116 -279.150318)
			(xy 367.068607 -279.176285) (xy 367.060482 -279.22758) (xy 367.044434 -279.276973) (xy 367.020856 -279.323247)
			(xy 366.99033 -279.365263) (xy 366.953607 -279.401986) (xy 366.911591 -279.432512) (xy 366.865317 -279.45609)
			(xy 366.815924 -279.472138) (xy 366.764629 -279.480263) (xy 366.712695 -279.480263) (xy 366.6614 -279.472138)
			(xy 366.612007 -279.45609) (xy 366.565733 -279.432512) (xy 366.523717 -279.401986) (xy 366.486994 -279.365263)
			(xy 366.456468 -279.323247) (xy 366.43289 -279.276973) (xy 366.416842 -279.22758) (xy 366.408717 -279.176285)
			(xy 366.129061 -279.176285) (xy 366.120936 -279.22758) (xy 366.104888 -279.276973) (xy 366.08131 -279.323247)
			(xy 366.050784 -279.365263) (xy 366.014061 -279.401986) (xy 365.972045 -279.432512) (xy 365.925771 -279.45609)
			(xy 365.876378 -279.472138) (xy 365.825083 -279.480263) (xy 365.773149 -279.480263) (xy 365.721854 -279.472138)
			(xy 365.672461 -279.45609) (xy 365.626187 -279.432512) (xy 365.584171 -279.401986) (xy 365.547448 -279.365263)
			(xy 365.516922 -279.323247) (xy 365.493344 -279.276973) (xy 365.477296 -279.22758) (xy 365.469171 -279.176285)
			(xy 365.189221 -279.176285) (xy 365.181136 -279.227326) (xy 365.165088 -279.276719) (xy 365.14151 -279.322993)
			(xy 365.110984 -279.365009) (xy 365.074261 -279.401732) (xy 365.032245 -279.432258) (xy 364.985971 -279.455836)
			(xy 364.936578 -279.471884) (xy 364.885283 -279.480009) (xy 364.833349 -279.480009) (xy 364.782054 -279.471884)
			(xy 364.732661 -279.455836) (xy 364.686387 -279.432258) (xy 364.644371 -279.401732) (xy 364.607648 -279.365009)
			(xy 364.577122 -279.322993) (xy 364.553544 -279.276719) (xy 364.537496 -279.227326) (xy 364.529371 -279.176031)
			(xy 364.249212 -279.176031) (xy 364.249207 -279.176285) (xy 364.241082 -279.22758) (xy 364.225034 -279.276973)
			(xy 364.201456 -279.323247) (xy 364.17093 -279.365263) (xy 364.134207 -279.401986) (xy 364.092191 -279.432512)
			(xy 364.045917 -279.45609) (xy 363.996524 -279.472138) (xy 363.945229 -279.480263) (xy 363.893295 -279.480263)
			(xy 363.842 -279.472138) (xy 363.792607 -279.45609) (xy 363.746333 -279.432512) (xy 363.704317 -279.401986)
			(xy 363.667594 -279.365263) (xy 363.637068 -279.323247) (xy 363.61349 -279.276973) (xy 363.597442 -279.22758)
			(xy 363.589317 -279.176285) (xy 363.309407 -279.176285) (xy 363.301282 -279.22758) (xy 363.285234 -279.276973)
			(xy 363.261656 -279.323247) (xy 363.23113 -279.365263) (xy 363.194407 -279.401986) (xy 363.152391 -279.432512)
			(xy 363.106117 -279.45609) (xy 363.056724 -279.472138) (xy 363.005429 -279.480263) (xy 362.953495 -279.480263)
			(xy 362.9022 -279.472138) (xy 362.852807 -279.45609) (xy 362.806533 -279.432512) (xy 362.764517 -279.401986)
			(xy 362.727794 -279.365263) (xy 362.697268 -279.323247) (xy 362.67369 -279.276973) (xy 362.657642 -279.22758)
			(xy 362.649517 -279.176285) (xy 356.730807 -279.176285) (xy 356.722682 -279.22758) (xy 356.706634 -279.276973)
			(xy 356.683056 -279.323247) (xy 356.65253 -279.365263) (xy 356.615807 -279.401986) (xy 356.573791 -279.432512)
			(xy 356.527517 -279.45609) (xy 356.478124 -279.472138) (xy 356.426829 -279.480263) (xy 356.374895 -279.480263)
			(xy 356.3236 -279.472138) (xy 356.274207 -279.45609) (xy 356.227933 -279.432512) (xy 356.185917 -279.401986)
			(xy 356.149194 -279.365263) (xy 356.118668 -279.323247) (xy 356.09509 -279.276973) (xy 356.079042 -279.22758)
			(xy 356.070917 -279.176285) (xy 355.791007 -279.176285) (xy 355.782882 -279.22758) (xy 355.766834 -279.276973)
			(xy 355.743256 -279.323247) (xy 355.71273 -279.365263) (xy 355.676007 -279.401986) (xy 355.633991 -279.432512)
			(xy 355.587717 -279.45609) (xy 355.538324 -279.472138) (xy 355.487029 -279.480263) (xy 355.435095 -279.480263)
			(xy 355.3838 -279.472138) (xy 355.334407 -279.45609) (xy 355.288133 -279.432512) (xy 355.246117 -279.401986)
			(xy 355.209394 -279.365263) (xy 355.178868 -279.323247) (xy 355.15529 -279.276973) (xy 355.139242 -279.22758)
			(xy 355.131117 -279.176285) (xy 354.851461 -279.176285) (xy 354.843336 -279.22758) (xy 354.827288 -279.276973)
			(xy 354.80371 -279.323247) (xy 354.773184 -279.365263) (xy 354.736461 -279.401986) (xy 354.694445 -279.432512)
			(xy 354.648171 -279.45609) (xy 354.598778 -279.472138) (xy 354.547483 -279.480263) (xy 354.495549 -279.480263)
			(xy 354.444254 -279.472138) (xy 354.394861 -279.45609) (xy 354.348587 -279.432512) (xy 354.306571 -279.401986)
			(xy 354.269848 -279.365263) (xy 354.239322 -279.323247) (xy 354.215744 -279.276973) (xy 354.199696 -279.22758)
			(xy 354.191571 -279.176285) (xy 353.911661 -279.176285) (xy 353.903536 -279.22758) (xy 353.887488 -279.276973)
			(xy 353.86391 -279.323247) (xy 353.833384 -279.365263) (xy 353.796661 -279.401986) (xy 353.754645 -279.432512)
			(xy 353.708371 -279.45609) (xy 353.658978 -279.472138) (xy 353.607683 -279.480263) (xy 353.555749 -279.480263)
			(xy 353.504454 -279.472138) (xy 353.455061 -279.45609) (xy 353.408787 -279.432512) (xy 353.366771 -279.401986)
			(xy 353.330048 -279.365263) (xy 353.299522 -279.323247) (xy 353.275944 -279.276973) (xy 353.259896 -279.22758)
			(xy 353.251771 -279.176285) (xy 352.971607 -279.176285) (xy 352.963482 -279.22758) (xy 352.947434 -279.276973)
			(xy 352.923856 -279.323247) (xy 352.89333 -279.365263) (xy 352.856607 -279.401986) (xy 352.814591 -279.432512)
			(xy 352.768317 -279.45609) (xy 352.718924 -279.472138) (xy 352.667629 -279.480263) (xy 352.615695 -279.480263)
			(xy 352.5644 -279.472138) (xy 352.515007 -279.45609) (xy 352.468733 -279.432512) (xy 352.426717 -279.401986)
			(xy 352.389994 -279.365263) (xy 352.359468 -279.323247) (xy 352.33589 -279.276973) (xy 352.319842 -279.22758)
			(xy 352.311717 -279.176285) (xy 352.031887 -279.176285) (xy 352.023762 -279.227578) (xy 352.007709 -279.276981)
			(xy 351.984125 -279.323263) (xy 351.95359 -279.365286) (xy 351.916858 -279.402015) (xy 351.874831 -279.432545)
			(xy 351.828545 -279.456124) (xy 351.779141 -279.472171) (xy 351.727835 -279.480292) (xy 351.701862 -279.480772)
			(xy 351.676224 -279.480329) (xy 351.625566 -279.472397) (xy 351.576743 -279.456731) (xy 351.530928 -279.433706)
			(xy 351.489223 -279.403876) (xy 351.45263 -279.367958) (xy 351.43694 -279.347676) (xy 351.026984 -279.347676)
			(xy 351.011305 -279.367965) (xy 350.974708 -279.403876) (xy 350.932999 -279.433698) (xy 350.887182 -279.456714)
			(xy 350.838357 -279.47237) (xy 350.787699 -279.48029) (xy 350.762062 -279.480772) (xy 350.736098 -279.480224)
			(xy 350.684811 -279.472095) (xy 350.635426 -279.456044) (xy 350.58916 -279.432466) (xy 350.547151 -279.40194)
			(xy 350.510435 -279.36522) (xy 350.479914 -279.323208) (xy 350.456341 -279.276939) (xy 350.440296 -279.227552)
			(xy 350.432173 -279.176264) (xy 350.152185 -279.176264) (xy 350.152146 -279.178163) (xy 350.142831 -279.233067)
			(xy 350.134174 -279.259538) (xy 350.1263 -279.281636) (xy 350.330262 -279.63495) (xy 350.353376 -279.639268)
			(xy 350.378304 -279.644408) (xy 350.426288 -279.661378) (xy 350.471105 -279.6855) (xy 350.511697 -279.716204)
			(xy 350.547105 -279.752766) (xy 350.576492 -279.794321) (xy 350.599165 -279.839888) (xy 350.614588 -279.888392)
			(xy 350.622397 -279.938686) (xy 350.62287 -279.964134) (xy 350.622361 -279.990101) (xy 350.902017 -279.990101)
			(xy 350.902017 -279.938167) (xy 350.910142 -279.886872) (xy 350.92619 -279.837479) (xy 350.949768 -279.791205)
			(xy 350.980294 -279.749189) (xy 351.017017 -279.712466) (xy 351.059033 -279.68194) (xy 351.105307 -279.658362)
			(xy 351.1547 -279.642314) (xy 351.205995 -279.634189) (xy 351.257929 -279.634189) (xy 351.309224 -279.642314)
			(xy 351.358617 -279.658362) (xy 351.404891 -279.68194) (xy 351.446907 -279.712466) (xy 351.48363 -279.749189)
			(xy 351.514156 -279.791205) (xy 351.537734 -279.837479) (xy 351.553782 -279.886872) (xy 351.561907 -279.938167)
			(xy 351.562416 -279.964134) (xy 351.561907 -279.990101) (xy 351.842071 -279.990101) (xy 351.842071 -279.938167)
			(xy 351.850196 -279.886872) (xy 351.866244 -279.837479) (xy 351.889822 -279.791205) (xy 351.920348 -279.749189)
			(xy 351.957071 -279.712466) (xy 351.999087 -279.68194) (xy 352.045361 -279.658362) (xy 352.094754 -279.642314)
			(xy 352.146049 -279.634189) (xy 352.197983 -279.634189) (xy 352.249278 -279.642314) (xy 352.298671 -279.658362)
			(xy 352.344945 -279.68194) (xy 352.386961 -279.712466) (xy 352.423684 -279.749189) (xy 352.45421 -279.791205)
			(xy 352.477788 -279.837479) (xy 352.493836 -279.886872) (xy 352.501961 -279.938167) (xy 352.50247 -279.964134)
			(xy 352.501961 -279.990101) (xy 352.493836 -280.041396) (xy 352.477788 -280.090789) (xy 352.45421 -280.137063)
			(xy 352.423684 -280.179079) (xy 352.386961 -280.215802) (xy 352.344945 -280.246328) (xy 352.298671 -280.269906)
			(xy 352.249278 -280.285954) (xy 352.197983 -280.294079) (xy 352.146049 -280.294079) (xy 352.094754 -280.285954)
			(xy 352.045361 -280.269906) (xy 351.999087 -280.246328) (xy 351.957071 -280.215802) (xy 351.920348 -280.179079)
			(xy 351.889822 -280.137063) (xy 351.866244 -280.090789) (xy 351.850196 -280.041396) (xy 351.842071 -279.990101)
			(xy 351.561907 -279.990101) (xy 351.553782 -280.041396) (xy 351.537734 -280.090789) (xy 351.514156 -280.137063)
			(xy 351.48363 -280.179079) (xy 351.446907 -280.215802) (xy 351.404891 -280.246328) (xy 351.358617 -280.269906)
			(xy 351.309224 -280.285954) (xy 351.257929 -280.294079) (xy 351.205995 -280.294079) (xy 351.1547 -280.285954)
			(xy 351.105307 -280.269906) (xy 351.059033 -280.246328) (xy 351.017017 -280.215802) (xy 350.980294 -280.179079)
			(xy 350.949768 -280.137063) (xy 350.92619 -280.090789) (xy 350.910142 -280.041396) (xy 350.902017 -279.990101)
			(xy 350.622361 -279.990101) (xy 350.614236 -280.041396) (xy 350.598188 -280.090789) (xy 350.57461 -280.137063)
			(xy 350.544084 -280.179079) (xy 350.507361 -280.215802) (xy 350.465345 -280.246328) (xy 350.419071 -280.269906)
			(xy 350.369678 -280.285954) (xy 350.318383 -280.294079) (xy 350.266449 -280.294079) (xy 350.215154 -280.285954)
			(xy 350.165761 -280.269906) (xy 350.119487 -280.246328) (xy 350.077471 -280.215802) (xy 350.040748 -280.179079)
			(xy 350.010222 -280.137063) (xy 349.986644 -280.090789) (xy 349.970596 -280.041396) (xy 349.962471 -279.990101)
			(xy 349.961962 -279.964134) (xy 349.96252 -279.936148) (xy 349.971966 -279.88098) (xy 349.980758 -279.854406)
			(xy 349.988378 -279.832308) (xy 349.78467 -279.479502) (xy 349.76181 -279.475184) (xy 349.736864 -279.47001)
			(xy 349.6888 -279.453122) (xy 349.643899 -279.429057) (xy 349.603223 -279.398385) (xy 349.567738 -279.361832)
			(xy 349.538284 -279.320266) (xy 349.515559 -279.274672) (xy 349.500103 -279.22613) (xy 349.49228 -279.17579)
			(xy 349.491808 -279.150318) (xy 349.21317 -279.150318) (xy 349.212661 -279.176285) (xy 349.204536 -279.22758)
			(xy 349.188488 -279.276973) (xy 349.16491 -279.323247) (xy 349.134384 -279.365263) (xy 349.097661 -279.401986)
			(xy 349.055645 -279.432512) (xy 349.009371 -279.45609) (xy 348.959978 -279.472138) (xy 348.908683 -279.480263)
			(xy 348.856749 -279.480263) (xy 348.805454 -279.472138) (xy 348.756061 -279.45609) (xy 348.709787 -279.432512)
			(xy 348.667771 -279.401986) (xy 348.631048 -279.365263) (xy 348.600522 -279.323247) (xy 348.576944 -279.276973)
			(xy 348.560896 -279.22758) (xy 348.552771 -279.176285) (xy 348.272607 -279.176285) (xy 348.264482 -279.22758)
			(xy 348.248434 -279.276973) (xy 348.224856 -279.323247) (xy 348.19433 -279.365263) (xy 348.157607 -279.401986)
			(xy 348.115591 -279.432512) (xy 348.069317 -279.45609) (xy 348.019924 -279.472138) (xy 347.968629 -279.480263)
			(xy 347.916695 -279.480263) (xy 347.8654 -279.472138) (xy 347.816007 -279.45609) (xy 347.769733 -279.432512)
			(xy 347.727717 -279.401986) (xy 347.690994 -279.365263) (xy 347.660468 -279.323247) (xy 347.63689 -279.276973)
			(xy 347.620842 -279.22758) (xy 347.612717 -279.176285) (xy 347.332807 -279.176285) (xy 347.324682 -279.22758)
			(xy 347.308634 -279.276973) (xy 347.285056 -279.323247) (xy 347.25453 -279.365263) (xy 347.217807 -279.401986)
			(xy 347.175791 -279.432512) (xy 347.129517 -279.45609) (xy 347.080124 -279.472138) (xy 347.028829 -279.480263)
			(xy 346.976895 -279.480263) (xy 346.9256 -279.472138) (xy 346.876207 -279.45609) (xy 346.829933 -279.432512)
			(xy 346.787917 -279.401986) (xy 346.751194 -279.365263) (xy 346.720668 -279.323247) (xy 346.69709 -279.276973)
			(xy 346.681042 -279.22758) (xy 346.672917 -279.176285) (xy 346.393261 -279.176285) (xy 346.385136 -279.22758)
			(xy 346.369088 -279.276973) (xy 346.34551 -279.323247) (xy 346.314984 -279.365263) (xy 346.278261 -279.401986)
			(xy 346.236245 -279.432512) (xy 346.189971 -279.45609) (xy 346.140578 -279.472138) (xy 346.089283 -279.480263)
			(xy 346.037349 -279.480263) (xy 345.986054 -279.472138) (xy 345.936661 -279.45609) (xy 345.890387 -279.432512)
			(xy 345.848371 -279.401986) (xy 345.811648 -279.365263) (xy 345.781122 -279.323247) (xy 345.757544 -279.276973)
			(xy 345.741496 -279.22758) (xy 345.733371 -279.176285) (xy 345.453207 -279.176285) (xy 345.445082 -279.22758)
			(xy 345.429034 -279.276973) (xy 345.405456 -279.323247) (xy 345.37493 -279.365263) (xy 345.338207 -279.401986)
			(xy 345.296191 -279.432512) (xy 345.249917 -279.45609) (xy 345.200524 -279.472138) (xy 345.149229 -279.480263)
			(xy 345.097295 -279.480263) (xy 345.046 -279.472138) (xy 344.996607 -279.45609) (xy 344.950333 -279.432512)
			(xy 344.908317 -279.401986) (xy 344.871594 -279.365263) (xy 344.841068 -279.323247) (xy 344.81749 -279.276973)
			(xy 344.801442 -279.22758) (xy 344.793317 -279.176285) (xy 344.557604 -279.176285) (xy 344.557604 -279.53208)
			(xy 344.558022 -279.545295) (xy 344.564805 -279.570839) (xy 344.577922 -279.593784) (xy 344.596492 -279.612591)
			(xy 344.619269 -279.625997) (xy 344.644725 -279.633103) (xy 344.657934 -279.63368) (xy 344.683677 -279.63451)
			(xy 344.734449 -279.643168) (xy 344.783262 -279.659597) (xy 344.828935 -279.683402) (xy 344.870362 -279.714004)
			(xy 344.90654 -279.750662) (xy 344.936592 -279.79249) (xy 344.95979 -279.838474) (xy 344.975573 -279.8875)
			(xy 344.983559 -279.938382) (xy 344.98407 -279.964134) (xy 344.983518 -279.990101) (xy 345.263471 -279.990101)
			(xy 345.263471 -279.938167) (xy 345.271596 -279.886872) (xy 345.287644 -279.837479) (xy 345.311222 -279.791205)
			(xy 345.341748 -279.749189) (xy 345.378471 -279.712466) (xy 345.420487 -279.68194) (xy 345.466761 -279.658362)
			(xy 345.516154 -279.642314) (xy 345.567449 -279.634189) (xy 345.619383 -279.634189) (xy 345.670678 -279.642314)
			(xy 345.720071 -279.658362) (xy 345.766345 -279.68194) (xy 345.808361 -279.712466) (xy 345.845084 -279.749189)
			(xy 345.87561 -279.791205) (xy 345.899188 -279.837479) (xy 345.915236 -279.886872) (xy 345.923361 -279.938167)
			(xy 345.92387 -279.964134) (xy 345.923361 -279.990101) (xy 346.203271 -279.990101) (xy 346.203271 -279.938167)
			(xy 346.211396 -279.886872) (xy 346.227444 -279.837479) (xy 346.251022 -279.791205) (xy 346.281548 -279.749189)
			(xy 346.318271 -279.712466) (xy 346.360287 -279.68194) (xy 346.406561 -279.658362) (xy 346.455954 -279.642314)
			(xy 346.507249 -279.634189) (xy 346.559183 -279.634189) (xy 346.610478 -279.642314) (xy 346.659871 -279.658362)
			(xy 346.706145 -279.68194) (xy 346.748161 -279.712466) (xy 346.784884 -279.749189) (xy 346.81541 -279.791205)
			(xy 346.838988 -279.837479) (xy 346.855036 -279.886872) (xy 346.863161 -279.938167) (xy 346.86367 -279.964134)
			(xy 346.863161 -279.990101) (xy 347.143071 -279.990101) (xy 347.143071 -279.938167) (xy 347.151196 -279.886872)
			(xy 347.167244 -279.837479) (xy 347.190822 -279.791205) (xy 347.221348 -279.749189) (xy 347.258071 -279.712466)
			(xy 347.300087 -279.68194) (xy 347.346361 -279.658362) (xy 347.395754 -279.642314) (xy 347.447049 -279.634189)
			(xy 347.498983 -279.634189) (xy 347.550278 -279.642314) (xy 347.599671 -279.658362) (xy 347.645945 -279.68194)
			(xy 347.687961 -279.712466) (xy 347.724684 -279.749189) (xy 347.75521 -279.791205) (xy 347.778788 -279.837479)
			(xy 347.794836 -279.886872) (xy 347.802961 -279.938167) (xy 347.80347 -279.964134) (xy 347.802961 -279.990101)
			(xy 348.082871 -279.990101) (xy 348.082871 -279.938167) (xy 348.090996 -279.886872) (xy 348.107044 -279.837479)
			(xy 348.130622 -279.791205) (xy 348.161148 -279.749189) (xy 348.197871 -279.712466) (xy 348.239887 -279.68194)
			(xy 348.286161 -279.658362) (xy 348.335554 -279.642314) (xy 348.386849 -279.634189) (xy 348.438783 -279.634189)
			(xy 348.490078 -279.642314) (xy 348.539471 -279.658362) (xy 348.585745 -279.68194) (xy 348.627761 -279.712466)
			(xy 348.664484 -279.749189) (xy 348.69501 -279.791205) (xy 348.718588 -279.837479) (xy 348.734636 -279.886872)
			(xy 348.742761 -279.938167) (xy 348.74327 -279.964134) (xy 348.742761 -279.990101) (xy 349.022671 -279.990101)
			(xy 349.022671 -279.938167) (xy 349.030796 -279.886872) (xy 349.046844 -279.837479) (xy 349.070422 -279.791205)
			(xy 349.100948 -279.749189) (xy 349.137671 -279.712466) (xy 349.179687 -279.68194) (xy 349.225961 -279.658362)
			(xy 349.275354 -279.642314) (xy 349.326649 -279.634189) (xy 349.378583 -279.634189) (xy 349.429878 -279.642314)
			(xy 349.479271 -279.658362) (xy 349.525545 -279.68194) (xy 349.567561 -279.712466) (xy 349.604284 -279.749189)
			(xy 349.63481 -279.791205) (xy 349.658388 -279.837479) (xy 349.674436 -279.886872) (xy 349.682561 -279.938167)
			(xy 349.68307 -279.964134) (xy 349.682561 -279.990101) (xy 349.674436 -280.041396) (xy 349.658388 -280.090789)
			(xy 349.63481 -280.137063) (xy 349.604284 -280.179079) (xy 349.567561 -280.215802) (xy 349.525545 -280.246328)
			(xy 349.479271 -280.269906) (xy 349.429878 -280.285954) (xy 349.378583 -280.294079) (xy 349.326649 -280.294079)
			(xy 349.275354 -280.285954) (xy 349.225961 -280.269906) (xy 349.179687 -280.246328) (xy 349.137671 -280.215802)
			(xy 349.100948 -280.179079) (xy 349.070422 -280.137063) (xy 349.046844 -280.090789) (xy 349.030796 -280.041396)
			(xy 349.022671 -279.990101) (xy 348.742761 -279.990101) (xy 348.734636 -280.041396) (xy 348.718588 -280.090789)
			(xy 348.69501 -280.137063) (xy 348.664484 -280.179079) (xy 348.627761 -280.215802) (xy 348.585745 -280.246328)
			(xy 348.539471 -280.269906) (xy 348.490078 -280.285954) (xy 348.438783 -280.294079) (xy 348.386849 -280.294079)
			(xy 348.335554 -280.285954) (xy 348.286161 -280.269906) (xy 348.239887 -280.246328) (xy 348.197871 -280.215802)
			(xy 348.161148 -280.179079) (xy 348.130622 -280.137063) (xy 348.107044 -280.090789) (xy 348.090996 -280.041396)
			(xy 348.082871 -279.990101) (xy 347.802961 -279.990101) (xy 347.794836 -280.041396) (xy 347.778788 -280.090789)
			(xy 347.75521 -280.137063) (xy 347.724684 -280.179079) (xy 347.687961 -280.215802) (xy 347.645945 -280.246328)
			(xy 347.599671 -280.269906) (xy 347.550278 -280.285954) (xy 347.498983 -280.294079) (xy 347.447049 -280.294079)
			(xy 347.395754 -280.285954) (xy 347.346361 -280.269906) (xy 347.300087 -280.246328) (xy 347.258071 -280.215802)
			(xy 347.221348 -280.179079) (xy 347.190822 -280.137063) (xy 347.167244 -280.090789) (xy 347.151196 -280.041396)
			(xy 347.143071 -279.990101) (xy 346.863161 -279.990101) (xy 346.855036 -280.041396) (xy 346.838988 -280.090789)
			(xy 346.81541 -280.137063) (xy 346.784884 -280.179079) (xy 346.748161 -280.215802) (xy 346.706145 -280.246328)
			(xy 346.659871 -280.269906) (xy 346.610478 -280.285954) (xy 346.559183 -280.294079) (xy 346.507249 -280.294079)
			(xy 346.455954 -280.285954) (xy 346.406561 -280.269906) (xy 346.360287 -280.246328) (xy 346.318271 -280.215802)
			(xy 346.281548 -280.179079) (xy 346.251022 -280.137063) (xy 346.227444 -280.090789) (xy 346.211396 -280.041396)
			(xy 346.203271 -279.990101) (xy 345.923361 -279.990101) (xy 345.915236 -280.041396) (xy 345.899188 -280.090789)
			(xy 345.87561 -280.137063) (xy 345.845084 -280.179079) (xy 345.808361 -280.215802) (xy 345.766345 -280.246328)
			(xy 345.720071 -280.269906) (xy 345.670678 -280.285954) (xy 345.619383 -280.294079) (xy 345.567449 -280.294079)
			(xy 345.516154 -280.285954) (xy 345.466761 -280.269906) (xy 345.420487 -280.246328) (xy 345.378471 -280.215802)
			(xy 345.341748 -280.179079) (xy 345.311222 -280.137063) (xy 345.287644 -280.090789) (xy 345.271596 -280.041396)
			(xy 345.263471 -279.990101) (xy 344.983518 -279.990101) (xy 344.983474 -279.992178) (xy 344.974023 -280.047465)
			(xy 344.965274 -280.074116) (xy 344.9574 -280.096214) (xy 345.161108 -280.44902) (xy 345.184222 -280.453338)
			(xy 345.209152 -280.458487) (xy 345.257156 -280.475425) (xy 345.301992 -280.499527) (xy 345.3426 -280.530223)
			(xy 345.378018 -280.566785) (xy 345.407408 -280.608348) (xy 345.430073 -280.653928) (xy 345.445477 -280.702445)
			(xy 345.453256 -280.752752) (xy 345.453716 -280.778204) (xy 345.453207 -280.804171) (xy 345.445082 -280.855466)
			(xy 345.429034 -280.904859) (xy 345.405456 -280.951133) (xy 345.37493 -280.993149) (xy 345.338207 -281.029872)
			(xy 345.296191 -281.060398) (xy 345.249917 -281.083976) (xy 345.200524 -281.100024) (xy 345.149229 -281.108149)
			(xy 345.097295 -281.108149) (xy 345.046 -281.100024) (xy 344.996607 -281.083976) (xy 344.950333 -281.060398)
			(xy 344.908317 -281.029872) (xy 344.871594 -280.993149) (xy 344.841068 -280.951133) (xy 344.81749 -280.904859)
			(xy 344.801442 -280.855466) (xy 344.793317 -280.804171) (xy 344.792808 -280.778204) (xy 344.793421 -280.750224)
			(xy 344.802872 -280.695066) (xy 344.811604 -280.668476) (xy 344.819224 -280.646378) (xy 344.747088 -280.52141)
			(xy 344.739241 -280.508863) (xy 344.717705 -280.488586) (xy 344.691261 -280.475331) (xy 344.662127 -280.47021)
			(xy 344.632748 -280.473653) (xy 344.605588 -280.485371) (xy 344.582925 -280.504381) (xy 344.56666 -280.529088)
			(xy 344.558158 -280.55742) (xy 344.557604 -280.57221) (xy 344.557604 -281.159966) (xy 344.558021 -281.173182)
			(xy 344.564801 -281.198729) (xy 344.577917 -281.221678) (xy 344.596487 -281.240487) (xy 344.619266 -281.253895)
			(xy 344.644724 -281.261002) (xy 344.657934 -281.261566) (xy 344.683677 -281.262396) (xy 344.734447 -281.271053)
			(xy 344.78326 -281.287481) (xy 344.828933 -281.311283) (xy 344.87036 -281.341883) (xy 344.906538 -281.378539)
			(xy 344.936592 -281.420364) (xy 344.959793 -281.466345) (xy 344.97558 -281.515369) (xy 344.98357 -281.566249)
			(xy 344.98357 -281.59202) (xy 345.262962 -281.59202) (xy 345.263364 -281.566566) (xy 345.271154 -281.516258)
			(xy 345.286568 -281.46774) (xy 345.309243 -281.422161) (xy 345.33864 -281.380599) (xy 345.374064 -281.344038)
			(xy 345.414677 -281.313344) (xy 345.459517 -281.289242) (xy 345.507524 -281.272303) (xy 345.532456 -281.267154)
			(xy 345.55557 -281.262836) (xy 345.759278 -280.91003) (xy 345.751404 -280.887932) (xy 345.742674 -280.861341)
			(xy 345.733222 -280.806184) (xy 345.732608 -280.778204) (xy 345.733117 -280.752237) (xy 345.741242 -280.700942)
			(xy 345.75729 -280.651549) (xy 345.780868 -280.605275) (xy 345.811394 -280.563259) (xy 345.848117 -280.526536)
			(xy 345.890133 -280.49601) (xy 345.936407 -280.472432) (xy 345.9858 -280.456384) (xy 346.037095 -280.448259)
			(xy 346.089029 -280.448259) (xy 346.140324 -280.456384) (xy 346.189717 -280.472432) (xy 346.235991 -280.49601)
			(xy 346.278007 -280.526536) (xy 346.31473 -280.563259) (xy 346.345256 -280.605275) (xy 346.368834 -280.651549)
			(xy 346.384882 -280.700942) (xy 346.393007 -280.752237) (xy 346.393516 -280.778204) (xy 346.393063 -280.803657)
			(xy 346.392984 -280.804171) (xy 346.672917 -280.804171) (xy 346.672917 -280.752237) (xy 346.681042 -280.700942)
			(xy 346.69709 -280.651549) (xy 346.720668 -280.605275) (xy 346.751194 -280.563259) (xy 346.787917 -280.526536)
			(xy 346.829933 -280.49601) (xy 346.876207 -280.472432) (xy 346.9256 -280.456384) (xy 346.976895 -280.448259)
			(xy 347.028829 -280.448259) (xy 347.080124 -280.456384) (xy 347.129517 -280.472432) (xy 347.175791 -280.49601)
			(xy 347.217807 -280.526536) (xy 347.25453 -280.563259) (xy 347.285056 -280.605275) (xy 347.308634 -280.651549)
			(xy 347.324682 -280.700942) (xy 347.332807 -280.752237) (xy 347.333316 -280.778204) (xy 347.332807 -280.804171)
			(xy 347.612717 -280.804171) (xy 347.612717 -280.752237) (xy 347.620842 -280.700942) (xy 347.63689 -280.651549)
			(xy 347.660468 -280.605275) (xy 347.690994 -280.563259) (xy 347.727717 -280.526536) (xy 347.769733 -280.49601)
			(xy 347.816007 -280.472432) (xy 347.8654 -280.456384) (xy 347.916695 -280.448259) (xy 347.968629 -280.448259)
			(xy 348.019924 -280.456384) (xy 348.069317 -280.472432) (xy 348.115591 -280.49601) (xy 348.157607 -280.526536)
			(xy 348.19433 -280.563259) (xy 348.224856 -280.605275) (xy 348.248434 -280.651549) (xy 348.264482 -280.700942)
			(xy 348.272607 -280.752237) (xy 348.273116 -280.778204) (xy 348.552008 -280.778204) (xy 348.552517 -280.752237)
			(xy 348.560642 -280.700942) (xy 348.57669 -280.651549) (xy 348.600268 -280.605275) (xy 348.630794 -280.563259)
			(xy 348.667517 -280.526536) (xy 348.709533 -280.49601) (xy 348.755807 -280.472432) (xy 348.8052 -280.456384)
			(xy 348.856495 -280.448259) (xy 348.908429 -280.448259) (xy 348.959724 -280.456384) (xy 349.009117 -280.472432)
			(xy 349.055391 -280.49601) (xy 349.097407 -280.526536) (xy 349.13413 -280.563259) (xy 349.164656 -280.605275)
			(xy 349.188234 -280.651549) (xy 349.204282 -280.700942) (xy 349.212407 -280.752237) (xy 349.212916 -280.778204)
			(xy 349.212404 -280.804171) (xy 349.492317 -280.804171) (xy 349.492317 -280.752237) (xy 349.500442 -280.700942)
			(xy 349.51649 -280.651549) (xy 349.540068 -280.605275) (xy 349.570594 -280.563259) (xy 349.607317 -280.526536)
			(xy 349.649333 -280.49601) (xy 349.695607 -280.472432) (xy 349.745 -280.456384) (xy 349.796295 -280.448259)
			(xy 349.848229 -280.448259) (xy 349.899524 -280.456384) (xy 349.948917 -280.472432) (xy 349.995191 -280.49601)
			(xy 350.037207 -280.526536) (xy 350.07393 -280.563259) (xy 350.104456 -280.605275) (xy 350.128034 -280.651549)
			(xy 350.144082 -280.700942) (xy 350.152207 -280.752237) (xy 350.152716 -280.778204) (xy 350.152207 -280.804171)
			(xy 350.432371 -280.804171) (xy 350.432371 -280.752237) (xy 350.440496 -280.700942) (xy 350.456544 -280.651549)
			(xy 350.480122 -280.605275) (xy 350.510648 -280.563259) (xy 350.547371 -280.526536) (xy 350.589387 -280.49601)
			(xy 350.635661 -280.472432) (xy 350.685054 -280.456384) (xy 350.736349 -280.448259) (xy 350.788283 -280.448259)
			(xy 350.839578 -280.456384) (xy 350.888971 -280.472432) (xy 350.935245 -280.49601) (xy 350.977261 -280.526536)
			(xy 351.013984 -280.563259) (xy 351.04451 -280.605275) (xy 351.068088 -280.651549) (xy 351.084136 -280.700942)
			(xy 351.092261 -280.752237) (xy 351.09277 -280.778204) (xy 351.371408 -280.778204) (xy 351.371917 -280.752237)
			(xy 351.380042 -280.700942) (xy 351.39609 -280.651549) (xy 351.419668 -280.605275) (xy 351.450194 -280.563259)
			(xy 351.486917 -280.526536) (xy 351.528933 -280.49601) (xy 351.575207 -280.472432) (xy 351.6246 -280.456384)
			(xy 351.675895 -280.448259) (xy 351.727829 -280.448259) (xy 351.779124 -280.456384) (xy 351.828517 -280.472432)
			(xy 351.874791 -280.49601) (xy 351.916807 -280.526536) (xy 351.95353 -280.563259) (xy 351.984056 -280.605275)
			(xy 352.007634 -280.651549) (xy 352.023682 -280.700942) (xy 352.031807 -280.752237) (xy 352.032316 -280.778204)
			(xy 352.311208 -280.778204) (xy 352.31173 -280.752755) (xy 352.319506 -280.702454) (xy 352.334906 -280.653942)
			(xy 352.357565 -280.608366) (xy 352.386947 -280.566805) (xy 352.422356 -280.530243) (xy 352.462955 -280.499545)
			(xy 352.507782 -280.475437) (xy 352.555776 -280.458491) (xy 352.580702 -280.453338) (xy 352.603816 -280.44902)
			(xy 352.807778 -280.095706) (xy 352.799904 -280.073608) (xy 352.791245 -280.047072) (xy 352.781924 -279.992041)
			(xy 352.781362 -279.964134) (xy 352.781871 -279.938167) (xy 352.789996 -279.886872) (xy 352.806044 -279.837479)
			(xy 352.829622 -279.791205) (xy 352.860148 -279.749189) (xy 352.896871 -279.712466) (xy 352.938887 -279.68194)
			(xy 352.985161 -279.658362) (xy 353.034554 -279.642314) (xy 353.085849 -279.634189) (xy 353.137783 -279.634189)
			(xy 353.189078 -279.642314) (xy 353.238471 -279.658362) (xy 353.284745 -279.68194) (xy 353.326761 -279.712466)
			(xy 353.363484 -279.749189) (xy 353.39401 -279.791205) (xy 353.417588 -279.837479) (xy 353.433636 -279.886872)
			(xy 353.441761 -279.938167) (xy 353.44227 -279.964134) (xy 353.441844 -279.989598) (xy 353.441766 -279.990101)
			(xy 353.721671 -279.990101) (xy 353.721671 -279.938167) (xy 353.729796 -279.886872) (xy 353.745844 -279.837479)
			(xy 353.769422 -279.791205) (xy 353.799948 -279.749189) (xy 353.836671 -279.712466) (xy 353.878687 -279.68194)
			(xy 353.924961 -279.658362) (xy 353.974354 -279.642314) (xy 354.025649 -279.634189) (xy 354.077583 -279.634189)
			(xy 354.128878 -279.642314) (xy 354.178271 -279.658362) (xy 354.224545 -279.68194) (xy 354.266561 -279.712466)
			(xy 354.303284 -279.749189) (xy 354.33381 -279.791205) (xy 354.357388 -279.837479) (xy 354.373436 -279.886872)
			(xy 354.381561 -279.938167) (xy 354.38207 -279.964134) (xy 354.381561 -279.990101) (xy 354.661471 -279.990101)
			(xy 354.661471 -279.938167) (xy 354.669596 -279.886872) (xy 354.685644 -279.837479) (xy 354.709222 -279.791205)
			(xy 354.739748 -279.749189) (xy 354.776471 -279.712466) (xy 354.818487 -279.68194) (xy 354.864761 -279.658362)
			(xy 354.914154 -279.642314) (xy 354.965449 -279.634189) (xy 355.017383 -279.634189) (xy 355.068678 -279.642314)
			(xy 355.118071 -279.658362) (xy 355.164345 -279.68194) (xy 355.206361 -279.712466) (xy 355.243084 -279.749189)
			(xy 355.27361 -279.791205) (xy 355.297188 -279.837479) (xy 355.313236 -279.886872) (xy 355.321361 -279.938167)
			(xy 355.32187 -279.964134) (xy 355.321361 -279.990101) (xy 355.601017 -279.990101) (xy 355.601017 -279.938167)
			(xy 355.609142 -279.886872) (xy 355.62519 -279.837479) (xy 355.648768 -279.791205) (xy 355.679294 -279.749189)
			(xy 355.716017 -279.712466) (xy 355.758033 -279.68194) (xy 355.804307 -279.658362) (xy 355.8537 -279.642314)
			(xy 355.904995 -279.634189) (xy 355.956929 -279.634189) (xy 356.008224 -279.642314) (xy 356.057617 -279.658362)
			(xy 356.103891 -279.68194) (xy 356.145907 -279.712466) (xy 356.18263 -279.749189) (xy 356.213156 -279.791205)
			(xy 356.236734 -279.837479) (xy 356.252782 -279.886872) (xy 356.260907 -279.938167) (xy 356.261416 -279.964134)
			(xy 356.260907 -279.990101) (xy 361.239817 -279.990101) (xy 361.239817 -279.938167) (xy 361.247942 -279.886872)
			(xy 361.26399 -279.837479) (xy 361.287568 -279.791205) (xy 361.318094 -279.749189) (xy 361.354817 -279.712466)
			(xy 361.396833 -279.68194) (xy 361.443107 -279.658362) (xy 361.4925 -279.642314) (xy 361.543795 -279.634189)
			(xy 361.595729 -279.634189) (xy 361.647024 -279.642314) (xy 361.696417 -279.658362) (xy 361.742691 -279.68194)
			(xy 361.784707 -279.712466) (xy 361.82143 -279.749189) (xy 361.851956 -279.791205) (xy 361.875534 -279.837479)
			(xy 361.891582 -279.886872) (xy 361.899707 -279.938167) (xy 361.900216 -279.964134) (xy 361.899707 -279.990101)
			(xy 364.059471 -279.990101) (xy 364.059471 -279.938167) (xy 364.067596 -279.886872) (xy 364.083644 -279.837479)
			(xy 364.107222 -279.791205) (xy 364.137748 -279.749189) (xy 364.174471 -279.712466) (xy 364.216487 -279.68194)
			(xy 364.262761 -279.658362) (xy 364.312154 -279.642314) (xy 364.363449 -279.634189) (xy 364.415383 -279.634189)
			(xy 364.466678 -279.642314) (xy 364.516071 -279.658362) (xy 364.562345 -279.68194) (xy 364.604361 -279.712466)
			(xy 364.641084 -279.749189) (xy 364.67161 -279.791205) (xy 364.695188 -279.837479) (xy 364.711236 -279.886872)
			(xy 364.719361 -279.938167) (xy 364.71987 -279.964134) (xy 364.719361 -279.990101) (xy 364.999271 -279.990101)
			(xy 364.999271 -279.938167) (xy 365.007396 -279.886872) (xy 365.023444 -279.837479) (xy 365.047022 -279.791205)
			(xy 365.077548 -279.749189) (xy 365.114271 -279.712466) (xy 365.156287 -279.68194) (xy 365.202561 -279.658362)
			(xy 365.251954 -279.642314) (xy 365.303249 -279.634189) (xy 365.355183 -279.634189) (xy 365.406478 -279.642314)
			(xy 365.455871 -279.658362) (xy 365.502145 -279.68194) (xy 365.544161 -279.712466) (xy 365.580884 -279.749189)
			(xy 365.61141 -279.791205) (xy 365.634988 -279.837479) (xy 365.651036 -279.886872) (xy 365.659161 -279.938167)
			(xy 365.65967 -279.964134) (xy 365.659161 -279.990101) (xy 365.938817 -279.990101) (xy 365.938817 -279.938167)
			(xy 365.946942 -279.886872) (xy 365.96299 -279.837479) (xy 365.986568 -279.791205) (xy 366.017094 -279.749189)
			(xy 366.053817 -279.712466) (xy 366.095833 -279.68194) (xy 366.142107 -279.658362) (xy 366.1915 -279.642314)
			(xy 366.242795 -279.634189) (xy 366.294729 -279.634189) (xy 366.346024 -279.642314) (xy 366.395417 -279.658362)
			(xy 366.441691 -279.68194) (xy 366.483707 -279.712466) (xy 366.52043 -279.749189) (xy 366.550956 -279.791205)
			(xy 366.574534 -279.837479) (xy 366.590582 -279.886872) (xy 366.598707 -279.938167) (xy 366.599216 -279.964134)
			(xy 366.598707 -279.990101) (xy 366.590582 -280.041396) (xy 366.574534 -280.090789) (xy 366.550956 -280.137063)
			(xy 366.52043 -280.179079) (xy 366.483707 -280.215802) (xy 366.441691 -280.246328) (xy 366.395417 -280.269906)
			(xy 366.346024 -280.285954) (xy 366.294729 -280.294079) (xy 366.242795 -280.294079) (xy 366.1915 -280.285954)
			(xy 366.142107 -280.269906) (xy 366.095833 -280.246328) (xy 366.053817 -280.215802) (xy 366.017094 -280.179079)
			(xy 365.986568 -280.137063) (xy 365.96299 -280.090789) (xy 365.946942 -280.041396) (xy 365.938817 -279.990101)
			(xy 365.659161 -279.990101) (xy 365.651036 -280.041396) (xy 365.634988 -280.090789) (xy 365.61141 -280.137063)
			(xy 365.580884 -280.179079) (xy 365.544161 -280.215802) (xy 365.502145 -280.246328) (xy 365.455871 -280.269906)
			(xy 365.406478 -280.285954) (xy 365.355183 -280.294079) (xy 365.303249 -280.294079) (xy 365.251954 -280.285954)
			(xy 365.202561 -280.269906) (xy 365.156287 -280.246328) (xy 365.114271 -280.215802) (xy 365.077548 -280.179079)
			(xy 365.047022 -280.137063) (xy 365.023444 -280.090789) (xy 365.007396 -280.041396) (xy 364.999271 -279.990101)
			(xy 364.719361 -279.990101) (xy 364.711236 -280.041396) (xy 364.695188 -280.090789) (xy 364.67161 -280.137063)
			(xy 364.641084 -280.179079) (xy 364.604361 -280.215802) (xy 364.562345 -280.246328) (xy 364.516071 -280.269906)
			(xy 364.466678 -280.285954) (xy 364.415383 -280.294079) (xy 364.363449 -280.294079) (xy 364.312154 -280.285954)
			(xy 364.262761 -280.269906) (xy 364.216487 -280.246328) (xy 364.174471 -280.215802) (xy 364.137748 -280.179079)
			(xy 364.107222 -280.137063) (xy 364.083644 -280.090789) (xy 364.067596 -280.041396) (xy 364.059471 -279.990101)
			(xy 361.899707 -279.990101) (xy 361.891582 -280.041396) (xy 361.875534 -280.090789) (xy 361.851956 -280.137063)
			(xy 361.82143 -280.179079) (xy 361.784707 -280.215802) (xy 361.742691 -280.246328) (xy 361.696417 -280.269906)
			(xy 361.647024 -280.285954) (xy 361.595729 -280.294079) (xy 361.543795 -280.294079) (xy 361.4925 -280.285954)
			(xy 361.443107 -280.269906) (xy 361.396833 -280.246328) (xy 361.354817 -280.215802) (xy 361.318094 -280.179079)
			(xy 361.287568 -280.137063) (xy 361.26399 -280.090789) (xy 361.247942 -280.041396) (xy 361.239817 -279.990101)
			(xy 356.260907 -279.990101) (xy 356.252782 -280.041396) (xy 356.236734 -280.090789) (xy 356.213156 -280.137063)
			(xy 356.18263 -280.179079) (xy 356.145907 -280.215802) (xy 356.103891 -280.246328) (xy 356.057617 -280.269906)
			(xy 356.008224 -280.285954) (xy 355.956929 -280.294079) (xy 355.904995 -280.294079) (xy 355.8537 -280.285954)
			(xy 355.804307 -280.269906) (xy 355.758033 -280.246328) (xy 355.716017 -280.215802) (xy 355.679294 -280.179079)
			(xy 355.648768 -280.137063) (xy 355.62519 -280.090789) (xy 355.609142 -280.041396) (xy 355.601017 -279.990101)
			(xy 355.321361 -279.990101) (xy 355.313236 -280.041396) (xy 355.297188 -280.090789) (xy 355.27361 -280.137063)
			(xy 355.243084 -280.179079) (xy 355.206361 -280.215802) (xy 355.164345 -280.246328) (xy 355.118071 -280.269906)
			(xy 355.068678 -280.285954) (xy 355.017383 -280.294079) (xy 354.965449 -280.294079) (xy 354.914154 -280.285954)
			(xy 354.864761 -280.269906) (xy 354.818487 -280.246328) (xy 354.776471 -280.215802) (xy 354.739748 -280.179079)
			(xy 354.709222 -280.137063) (xy 354.685644 -280.090789) (xy 354.669596 -280.041396) (xy 354.661471 -279.990101)
			(xy 354.381561 -279.990101) (xy 354.373436 -280.041396) (xy 354.357388 -280.090789) (xy 354.33381 -280.137063)
			(xy 354.303284 -280.179079) (xy 354.266561 -280.215802) (xy 354.224545 -280.246328) (xy 354.178271 -280.269906)
			(xy 354.128878 -280.285954) (xy 354.077583 -280.294079) (xy 354.025649 -280.294079) (xy 353.974354 -280.285954)
			(xy 353.924961 -280.269906) (xy 353.878687 -280.246328) (xy 353.836671 -280.215802) (xy 353.799948 -280.179079)
			(xy 353.769422 -280.137063) (xy 353.745844 -280.090789) (xy 353.729796 -280.041396) (xy 353.721671 -279.990101)
			(xy 353.441766 -279.990101) (xy 353.434039 -280.039926) (xy 353.418605 -280.088459) (xy 353.395905 -280.13405)
			(xy 353.36648 -280.175617) (xy 353.331024 -280.212177) (xy 353.290378 -280.242864) (xy 353.245505 -280.26695)
			(xy 353.197468 -280.283866) (xy 353.172522 -280.289) (xy 353.149408 -280.293318) (xy 352.9457 -280.646378)
			(xy 352.95332 -280.668476) (xy 352.962053 -280.695066) (xy 352.971503 -280.750224) (xy 352.972116 -280.778204)
			(xy 352.971607 -280.804165) (xy 353.251559 -280.804165) (xy 353.251559 -280.752235) (xy 353.259682 -280.700944)
			(xy 353.275728 -280.651555) (xy 353.299302 -280.605285) (xy 353.329824 -280.563271) (xy 353.366542 -280.526549)
			(xy 353.408552 -280.496022) (xy 353.45482 -280.472443) (xy 353.504207 -280.456391) (xy 353.555497 -280.448262)
			(xy 353.581462 -280.44775) (xy 353.607084 -280.44822) (xy 353.657712 -280.456146) (xy 353.706512 -280.471782)
			(xy 353.752319 -280.494755) (xy 353.794036 -280.524516) (xy 353.830666 -280.560352) (xy 353.846384 -280.580592)
			(xy 354.25634 -280.580592) (xy 354.272052 -280.560345) (xy 354.308671 -280.524494) (xy 354.350386 -280.494725)
			(xy 354.396196 -280.471754) (xy 354.445004 -280.45613) (xy 354.495638 -280.448228) (xy 354.521262 -280.44775)
			(xy 354.547234 -280.448222) (xy 354.598538 -280.456342) (xy 354.64794 -280.472389) (xy 354.694224 -280.495967)
			(xy 354.736248 -280.526495) (xy 354.77298 -280.563223) (xy 354.803513 -280.605244) (xy 354.827096 -280.651525)
			(xy 354.843149 -280.700925) (xy 354.851275 -280.752228) (xy 354.851275 -280.804171) (xy 355.131117 -280.804171)
			(xy 355.131117 -280.752237) (xy 355.139242 -280.700942) (xy 355.15529 -280.651549) (xy 355.178868 -280.605275)
			(xy 355.209394 -280.563259) (xy 355.246117 -280.526536) (xy 355.288133 -280.49601) (xy 355.334407 -280.472432)
			(xy 355.3838 -280.456384) (xy 355.435095 -280.448259) (xy 355.487029 -280.448259) (xy 355.538324 -280.456384)
			(xy 355.587717 -280.472432) (xy 355.633991 -280.49601) (xy 355.676007 -280.526536) (xy 355.71273 -280.563259)
			(xy 355.743256 -280.605275) (xy 355.766834 -280.651549) (xy 355.782882 -280.700942) (xy 355.791007 -280.752237)
			(xy 355.791516 -280.778204) (xy 355.791007 -280.804171) (xy 357.950517 -280.804171) (xy 357.950517 -280.752237)
			(xy 357.958642 -280.700942) (xy 357.97469 -280.651549) (xy 357.998268 -280.605275) (xy 358.028794 -280.563259)
			(xy 358.065517 -280.526536) (xy 358.107533 -280.49601) (xy 358.153807 -280.472432) (xy 358.2032 -280.456384)
			(xy 358.254495 -280.448259) (xy 358.306429 -280.448259) (xy 358.357724 -280.456384) (xy 358.407117 -280.472432)
			(xy 358.453391 -280.49601) (xy 358.495407 -280.526536) (xy 358.53213 -280.563259) (xy 358.562656 -280.605275)
			(xy 358.586234 -280.651549) (xy 358.602282 -280.700942) (xy 358.610407 -280.752237) (xy 358.610916 -280.778204)
			(xy 358.610407 -280.804171) (xy 364.529371 -280.804171) (xy 364.529371 -280.752237) (xy 364.537496 -280.700942)
			(xy 364.553544 -280.651549) (xy 364.577122 -280.605275) (xy 364.607648 -280.563259) (xy 364.644371 -280.526536)
			(xy 364.686387 -280.49601) (xy 364.732661 -280.472432) (xy 364.782054 -280.456384) (xy 364.833349 -280.448259)
			(xy 364.885283 -280.448259) (xy 364.936578 -280.456384) (xy 364.985971 -280.472432) (xy 365.032245 -280.49601)
			(xy 365.074261 -280.526536) (xy 365.110984 -280.563259) (xy 365.14151 -280.605275) (xy 365.165088 -280.651549)
			(xy 365.181136 -280.700942) (xy 365.189261 -280.752237) (xy 365.18977 -280.778204) (xy 365.189261 -280.804171)
			(xy 365.469171 -280.804171) (xy 365.469171 -280.752237) (xy 365.477296 -280.700942) (xy 365.493344 -280.651549)
			(xy 365.516922 -280.605275) (xy 365.547448 -280.563259) (xy 365.584171 -280.526536) (xy 365.626187 -280.49601)
			(xy 365.672461 -280.472432) (xy 365.721854 -280.456384) (xy 365.773149 -280.448259) (xy 365.825083 -280.448259)
			(xy 365.876378 -280.456384) (xy 365.925771 -280.472432) (xy 365.972045 -280.49601) (xy 366.014061 -280.526536)
			(xy 366.050784 -280.563259) (xy 366.08131 -280.605275) (xy 366.104888 -280.651549) (xy 366.120936 -280.700942)
			(xy 366.129061 -280.752237) (xy 366.12957 -280.778204) (xy 366.129061 -280.804171) (xy 366.408717 -280.804171)
			(xy 366.408717 -280.752237) (xy 366.416842 -280.700942) (xy 366.43289 -280.651549) (xy 366.456468 -280.605275)
			(xy 366.486994 -280.563259) (xy 366.523717 -280.526536) (xy 366.565733 -280.49601) (xy 366.612007 -280.472432)
			(xy 366.6614 -280.456384) (xy 366.712695 -280.448259) (xy 366.764629 -280.448259) (xy 366.815924 -280.456384)
			(xy 366.865317 -280.472432) (xy 366.911591 -280.49601) (xy 366.953607 -280.526536) (xy 366.99033 -280.563259)
			(xy 367.020856 -280.605275) (xy 367.044434 -280.651549) (xy 367.060482 -280.700942) (xy 367.068607 -280.752237)
			(xy 367.069116 -280.778204) (xy 367.068607 -280.804171) (xy 367.060482 -280.855466) (xy 367.044434 -280.904859)
			(xy 367.020856 -280.951133) (xy 366.99033 -280.993149) (xy 366.953607 -281.029872) (xy 366.911591 -281.060398)
			(xy 366.865317 -281.083976) (xy 366.815924 -281.100024) (xy 366.764629 -281.108149) (xy 366.712695 -281.108149)
			(xy 366.6614 -281.100024) (xy 366.612007 -281.083976) (xy 366.565733 -281.060398) (xy 366.523717 -281.029872)
			(xy 366.486994 -280.993149) (xy 366.456468 -280.951133) (xy 366.43289 -280.904859) (xy 366.416842 -280.855466)
			(xy 366.408717 -280.804171) (xy 366.129061 -280.804171) (xy 366.120936 -280.855466) (xy 366.104888 -280.904859)
			(xy 366.08131 -280.951133) (xy 366.050784 -280.993149) (xy 366.014061 -281.029872) (xy 365.972045 -281.060398)
			(xy 365.925771 -281.083976) (xy 365.876378 -281.100024) (xy 365.825083 -281.108149) (xy 365.773149 -281.108149)
			(xy 365.721854 -281.100024) (xy 365.672461 -281.083976) (xy 365.626187 -281.060398) (xy 365.584171 -281.029872)
			(xy 365.547448 -280.993149) (xy 365.516922 -280.951133) (xy 365.493344 -280.904859) (xy 365.477296 -280.855466)
			(xy 365.469171 -280.804171) (xy 365.189261 -280.804171) (xy 365.181136 -280.855466) (xy 365.165088 -280.904859)
			(xy 365.14151 -280.951133) (xy 365.110984 -280.993149) (xy 365.074261 -281.029872) (xy 365.032245 -281.060398)
			(xy 364.985971 -281.083976) (xy 364.936578 -281.100024) (xy 364.885283 -281.108149) (xy 364.833349 -281.108149)
			(xy 364.782054 -281.100024) (xy 364.732661 -281.083976) (xy 364.686387 -281.060398) (xy 364.644371 -281.029872)
			(xy 364.607648 -280.993149) (xy 364.577122 -280.951133) (xy 364.553544 -280.904859) (xy 364.537496 -280.855466)
			(xy 364.529371 -280.804171) (xy 358.610407 -280.804171) (xy 358.602282 -280.855466) (xy 358.586234 -280.904859)
			(xy 358.562656 -280.951133) (xy 358.53213 -280.993149) (xy 358.495407 -281.029872) (xy 358.453391 -281.060398)
			(xy 358.407117 -281.083976) (xy 358.357724 -281.100024) (xy 358.306429 -281.108149) (xy 358.254495 -281.108149)
			(xy 358.2032 -281.100024) (xy 358.153807 -281.083976) (xy 358.107533 -281.060398) (xy 358.065517 -281.029872)
			(xy 358.028794 -280.993149) (xy 357.998268 -280.951133) (xy 357.97469 -280.904859) (xy 357.958642 -280.855466)
			(xy 357.950517 -280.804171) (xy 355.791007 -280.804171) (xy 355.782882 -280.855466) (xy 355.766834 -280.904859)
			(xy 355.743256 -280.951133) (xy 355.71273 -280.993149) (xy 355.676007 -281.029872) (xy 355.633991 -281.060398)
			(xy 355.587717 -281.083976) (xy 355.538324 -281.100024) (xy 355.487029 -281.108149) (xy 355.435095 -281.108149)
			(xy 355.3838 -281.100024) (xy 355.334407 -281.083976) (xy 355.288133 -281.060398) (xy 355.246117 -281.029872)
			(xy 355.209394 -280.993149) (xy 355.178868 -280.951133) (xy 355.15529 -280.904859) (xy 355.139242 -280.855466)
			(xy 355.131117 -280.804171) (xy 354.851275 -280.804171) (xy 354.851275 -280.804172) (xy 354.843149 -280.855475)
			(xy 354.827096 -280.904875) (xy 354.803513 -280.951156) (xy 354.77298 -280.993177) (xy 354.736248 -281.029905)
			(xy 354.694224 -281.060433) (xy 354.64794 -281.084011) (xy 354.598538 -281.100058) (xy 354.547234 -281.108178)
			(xy 354.521262 -281.108658) (xy 354.495641 -281.108167) (xy 354.445014 -281.100245) (xy 354.396214 -281.084613)
			(xy 354.350408 -281.061644) (xy 354.30869 -281.031887) (xy 354.272059 -280.996054) (xy 354.25634 -280.975816)
			(xy 353.846384 -280.975816) (xy 353.83066 -280.996053) (xy 353.794043 -281.031905) (xy 353.75233 -281.061674)
			(xy 353.706523 -281.084647) (xy 353.657717 -281.100274) (xy 353.607085 -281.108179) (xy 353.581462 -281.108658)
			(xy 353.555497 -281.108138) (xy 353.504207 -281.100009) (xy 353.45482 -281.083957) (xy 353.408552 -281.060378)
			(xy 353.366542 -281.029851) (xy 353.329824 -280.993129) (xy 353.299302 -280.951115) (xy 353.275728 -280.904845)
			(xy 353.259682 -280.855456) (xy 353.251559 -280.804165) (xy 352.971607 -280.804165) (xy 352.971607 -280.804171)
			(xy 352.963482 -280.855466) (xy 352.947434 -280.904859) (xy 352.923856 -280.951133) (xy 352.89333 -280.993149)
			(xy 352.856607 -281.029872) (xy 352.814591 -281.060398) (xy 352.768317 -281.083976) (xy 352.718924 -281.100024)
			(xy 352.667629 -281.108149) (xy 352.615695 -281.108149) (xy 352.5644 -281.100024) (xy 352.515007 -281.083976)
			(xy 352.468733 -281.060398) (xy 352.426717 -281.029872) (xy 352.389994 -280.993149) (xy 352.359468 -280.951133)
			(xy 352.33589 -280.904859) (xy 352.319842 -280.855466) (xy 352.311717 -280.804171) (xy 352.311208 -280.778204)
			(xy 352.032316 -280.778204) (xy 352.031767 -280.80605) (xy 352.022438 -280.860954) (xy 352.013774 -280.887424)
			(xy 352.0059 -280.909522) (xy 352.209862 -281.262836) (xy 352.232976 -281.267154) (xy 352.257901 -281.272307)
			(xy 352.305884 -281.289276) (xy 352.3507 -281.313397) (xy 352.391292 -281.344099) (xy 352.426699 -281.380659)
			(xy 352.456087 -281.422213) (xy 352.478761 -281.467778) (xy 352.494185 -281.51628) (xy 352.501996 -281.566572)
			(xy 352.50247 -281.59202) (xy 352.501961 -281.617987) (xy 352.781871 -281.617987) (xy 352.781871 -281.566053)
			(xy 352.789996 -281.514758) (xy 352.806044 -281.465365) (xy 352.829622 -281.419091) (xy 352.860148 -281.377075)
			(xy 352.896871 -281.340352) (xy 352.938887 -281.309826) (xy 352.985161 -281.286248) (xy 353.034554 -281.2702)
			(xy 353.085849 -281.262075) (xy 353.137783 -281.262075) (xy 353.189078 -281.2702) (xy 353.238471 -281.286248)
			(xy 353.284745 -281.309826) (xy 353.326761 -281.340352) (xy 353.363484 -281.377075) (xy 353.39401 -281.419091)
			(xy 353.417588 -281.465365) (xy 353.433636 -281.514758) (xy 353.441761 -281.566053) (xy 353.44227 -281.59202)
			(xy 353.721162 -281.59202) (xy 353.721671 -281.566053) (xy 353.729796 -281.514758) (xy 353.745844 -281.465365)
			(xy 353.769422 -281.419091) (xy 353.799948 -281.377075) (xy 353.836671 -281.340352) (xy 353.878687 -281.309826)
			(xy 353.924961 -281.286248) (xy 353.974354 -281.2702) (xy 354.025649 -281.262075) (xy 354.077583 -281.262075)
			(xy 354.128878 -281.2702) (xy 354.178271 -281.286248) (xy 354.224545 -281.309826) (xy 354.266561 -281.340352)
			(xy 354.303284 -281.377075) (xy 354.33381 -281.419091) (xy 354.357388 -281.465365) (xy 354.373436 -281.514758)
			(xy 354.381561 -281.566053) (xy 354.38207 -281.59202) (xy 354.381563 -281.617987) (xy 354.661471 -281.617987)
			(xy 354.661471 -281.566053) (xy 354.669596 -281.514758) (xy 354.685644 -281.465365) (xy 354.709222 -281.419091)
			(xy 354.739748 -281.377075) (xy 354.776471 -281.340352) (xy 354.818487 -281.309826) (xy 354.864761 -281.286248)
			(xy 354.914154 -281.2702) (xy 354.965449 -281.262075) (xy 355.017383 -281.262075) (xy 355.068678 -281.2702)
			(xy 355.118071 -281.286248) (xy 355.164345 -281.309826) (xy 355.206361 -281.340352) (xy 355.243084 -281.377075)
			(xy 355.27361 -281.419091) (xy 355.297188 -281.465365) (xy 355.313236 -281.514758) (xy 355.321361 -281.566053)
			(xy 355.32187 -281.59202) (xy 355.321361 -281.617987) (xy 361.239817 -281.617987) (xy 361.239817 -281.566053)
			(xy 361.247942 -281.514758) (xy 361.26399 -281.465365) (xy 361.287568 -281.419091) (xy 361.318094 -281.377075)
			(xy 361.354817 -281.340352) (xy 361.396833 -281.309826) (xy 361.443107 -281.286248) (xy 361.4925 -281.2702)
			(xy 361.543795 -281.262075) (xy 361.595729 -281.262075) (xy 361.647024 -281.2702) (xy 361.696417 -281.286248)
			(xy 361.742691 -281.309826) (xy 361.784707 -281.340352) (xy 361.82143 -281.377075) (xy 361.851956 -281.419091)
			(xy 361.875534 -281.465365) (xy 361.891582 -281.514758) (xy 361.899707 -281.566053) (xy 361.900216 -281.59202)
			(xy 361.899707 -281.617987) (xy 364.999271 -281.617987) (xy 364.999271 -281.566053) (xy 365.007396 -281.514758)
			(xy 365.023444 -281.465365) (xy 365.047022 -281.419091) (xy 365.077548 -281.377075) (xy 365.114271 -281.340352)
			(xy 365.156287 -281.309826) (xy 365.202561 -281.286248) (xy 365.251954 -281.2702) (xy 365.303249 -281.262075)
			(xy 365.355183 -281.262075) (xy 365.406478 -281.2702) (xy 365.455871 -281.286248) (xy 365.502145 -281.309826)
			(xy 365.544161 -281.340352) (xy 365.580884 -281.377075) (xy 365.61141 -281.419091) (xy 365.634988 -281.465365)
			(xy 365.651036 -281.514758) (xy 365.659161 -281.566053) (xy 365.65967 -281.59202) (xy 365.659161 -281.617987)
			(xy 365.938817 -281.617987) (xy 365.938817 -281.566053) (xy 365.946942 -281.514758) (xy 365.96299 -281.465365)
			(xy 365.986568 -281.419091) (xy 366.017094 -281.377075) (xy 366.053817 -281.340352) (xy 366.095833 -281.309826)
			(xy 366.142107 -281.286248) (xy 366.1915 -281.2702) (xy 366.242795 -281.262075) (xy 366.294729 -281.262075)
			(xy 366.346024 -281.2702) (xy 366.395417 -281.286248) (xy 366.441691 -281.309826) (xy 366.483707 -281.340352)
			(xy 366.52043 -281.377075) (xy 366.550956 -281.419091) (xy 366.574534 -281.465365) (xy 366.590582 -281.514758)
			(xy 366.598707 -281.566053) (xy 366.599216 -281.59202) (xy 366.598707 -281.617987) (xy 366.590582 -281.669282)
			(xy 366.574534 -281.718675) (xy 366.550956 -281.764949) (xy 366.52043 -281.806965) (xy 366.483707 -281.843688)
			(xy 366.441691 -281.874214) (xy 366.395417 -281.897792) (xy 366.346024 -281.91384) (xy 366.294729 -281.921965)
			(xy 366.242795 -281.921965) (xy 366.1915 -281.91384) (xy 366.142107 -281.897792) (xy 366.095833 -281.874214)
			(xy 366.053817 -281.843688) (xy 366.017094 -281.806965) (xy 365.986568 -281.764949) (xy 365.96299 -281.718675)
			(xy 365.946942 -281.669282) (xy 365.938817 -281.617987) (xy 365.659161 -281.617987) (xy 365.651036 -281.669282)
			(xy 365.634988 -281.718675) (xy 365.61141 -281.764949) (xy 365.580884 -281.806965) (xy 365.544161 -281.843688)
			(xy 365.502145 -281.874214) (xy 365.455871 -281.897792) (xy 365.406478 -281.91384) (xy 365.355183 -281.921965)
			(xy 365.303249 -281.921965) (xy 365.251954 -281.91384) (xy 365.202561 -281.897792) (xy 365.156287 -281.874214)
			(xy 365.114271 -281.843688) (xy 365.077548 -281.806965) (xy 365.047022 -281.764949) (xy 365.023444 -281.718675)
			(xy 365.007396 -281.669282) (xy 364.999271 -281.617987) (xy 361.899707 -281.617987) (xy 361.891582 -281.669282)
			(xy 361.875534 -281.718675) (xy 361.851956 -281.764949) (xy 361.82143 -281.806965) (xy 361.784707 -281.843688)
			(xy 361.742691 -281.874214) (xy 361.696417 -281.897792) (xy 361.647024 -281.91384) (xy 361.595729 -281.921965)
			(xy 361.543795 -281.921965) (xy 361.4925 -281.91384) (xy 361.443107 -281.897792) (xy 361.396833 -281.874214)
			(xy 361.354817 -281.843688) (xy 361.318094 -281.806965) (xy 361.287568 -281.764949) (xy 361.26399 -281.718675)
			(xy 361.247942 -281.669282) (xy 361.239817 -281.617987) (xy 355.321361 -281.617987) (xy 355.313236 -281.669282)
			(xy 355.297188 -281.718675) (xy 355.27361 -281.764949) (xy 355.243084 -281.806965) (xy 355.206361 -281.843688)
			(xy 355.164345 -281.874214) (xy 355.118071 -281.897792) (xy 355.068678 -281.91384) (xy 355.017383 -281.921965)
			(xy 354.965449 -281.921965) (xy 354.914154 -281.91384) (xy 354.864761 -281.897792) (xy 354.818487 -281.874214)
			(xy 354.776471 -281.843688) (xy 354.739748 -281.806965) (xy 354.709222 -281.764949) (xy 354.685644 -281.718675)
			(xy 354.669596 -281.669282) (xy 354.661471 -281.617987) (xy 354.381563 -281.617987) (xy 354.381524 -281.620006)
			(xy 354.37207 -281.675174) (xy 354.363274 -281.701748) (xy 354.3554 -281.723846) (xy 354.559108 -282.076652)
			(xy 354.582222 -282.08097) (xy 354.607142 -282.086147) (xy 354.655126 -282.103109) (xy 354.699944 -282.127225)
			(xy 354.740538 -282.157924) (xy 354.775947 -282.194481) (xy 354.805336 -282.236032) (xy 354.82801 -282.281596)
			(xy 354.843434 -282.330097) (xy 354.851243 -282.380389) (xy 354.851716 -282.405836) (xy 354.851207 -282.431803)
			(xy 355.131117 -282.431803) (xy 355.131117 -282.379869) (xy 355.139242 -282.328574) (xy 355.15529 -282.279181)
			(xy 355.178868 -282.232907) (xy 355.209394 -282.190891) (xy 355.246117 -282.154168) (xy 355.288133 -282.123642)
			(xy 355.334407 -282.100064) (xy 355.3838 -282.084016) (xy 355.435095 -282.075891) (xy 355.487029 -282.075891)
			(xy 355.538324 -282.084016) (xy 355.587717 -282.100064) (xy 355.633991 -282.123642) (xy 355.676007 -282.154168)
			(xy 355.71273 -282.190891) (xy 355.743256 -282.232907) (xy 355.766834 -282.279181) (xy 355.782882 -282.328574)
			(xy 355.791007 -282.379869) (xy 355.791516 -282.405836) (xy 355.791007 -282.431803) (xy 357.950517 -282.431803)
			(xy 357.950517 -282.379869) (xy 357.958642 -282.328574) (xy 357.97469 -282.279181) (xy 357.998268 -282.232907)
			(xy 358.028794 -282.190891) (xy 358.065517 -282.154168) (xy 358.107533 -282.123642) (xy 358.153807 -282.100064)
			(xy 358.2032 -282.084016) (xy 358.254495 -282.075891) (xy 358.306429 -282.075891) (xy 358.357724 -282.084016)
			(xy 358.407117 -282.100064) (xy 358.453391 -282.123642) (xy 358.495407 -282.154168) (xy 358.53213 -282.190891)
			(xy 358.562656 -282.232907) (xy 358.586234 -282.279181) (xy 358.602282 -282.328574) (xy 358.610407 -282.379869)
			(xy 358.610916 -282.405836) (xy 358.610407 -282.431803) (xy 365.469171 -282.431803) (xy 365.469171 -282.379869)
			(xy 365.477296 -282.328574) (xy 365.493344 -282.279181) (xy 365.516922 -282.232907) (xy 365.547448 -282.190891)
			(xy 365.584171 -282.154168) (xy 365.626187 -282.123642) (xy 365.672461 -282.100064) (xy 365.721854 -282.084016)
			(xy 365.773149 -282.075891) (xy 365.825083 -282.075891) (xy 365.876378 -282.084016) (xy 365.925771 -282.100064)
			(xy 365.972045 -282.123642) (xy 366.014061 -282.154168) (xy 366.050784 -282.190891) (xy 366.08131 -282.232907)
			(xy 366.104888 -282.279181) (xy 366.120936 -282.328574) (xy 366.129061 -282.379869) (xy 366.12957 -282.405836)
			(xy 366.129061 -282.431803) (xy 366.408717 -282.431803) (xy 366.408717 -282.379869) (xy 366.416842 -282.328574)
			(xy 366.43289 -282.279181) (xy 366.456468 -282.232907) (xy 366.486994 -282.190891) (xy 366.523717 -282.154168)
			(xy 366.565733 -282.123642) (xy 366.612007 -282.100064) (xy 366.6614 -282.084016) (xy 366.712695 -282.075891)
			(xy 366.764629 -282.075891) (xy 366.815924 -282.084016) (xy 366.865317 -282.100064) (xy 366.911591 -282.123642)
			(xy 366.953607 -282.154168) (xy 366.99033 -282.190891) (xy 367.020856 -282.232907) (xy 367.044434 -282.279181)
			(xy 367.060482 -282.328574) (xy 367.068607 -282.379869) (xy 367.069116 -282.405836) (xy 367.068607 -282.431803)
			(xy 367.060482 -282.483098) (xy 367.044434 -282.532491) (xy 367.020856 -282.578765) (xy 366.99033 -282.620781)
			(xy 366.953607 -282.657504) (xy 366.911591 -282.68803) (xy 366.865317 -282.711608) (xy 366.815924 -282.727656)
			(xy 366.764629 -282.735781) (xy 366.712695 -282.735781) (xy 366.6614 -282.727656) (xy 366.612007 -282.711608)
			(xy 366.565733 -282.68803) (xy 366.523717 -282.657504) (xy 366.486994 -282.620781) (xy 366.456468 -282.578765)
			(xy 366.43289 -282.532491) (xy 366.416842 -282.483098) (xy 366.408717 -282.431803) (xy 366.129061 -282.431803)
			(xy 366.120936 -282.483098) (xy 366.104888 -282.532491) (xy 366.08131 -282.578765) (xy 366.050784 -282.620781)
			(xy 366.014061 -282.657504) (xy 365.972045 -282.68803) (xy 365.925771 -282.711608) (xy 365.876378 -282.727656)
			(xy 365.825083 -282.735781) (xy 365.773149 -282.735781) (xy 365.721854 -282.727656) (xy 365.672461 -282.711608)
			(xy 365.626187 -282.68803) (xy 365.584171 -282.657504) (xy 365.547448 -282.620781) (xy 365.516922 -282.578765)
			(xy 365.493344 -282.532491) (xy 365.477296 -282.483098) (xy 365.469171 -282.431803) (xy 358.610407 -282.431803)
			(xy 358.602282 -282.483098) (xy 358.586234 -282.532491) (xy 358.562656 -282.578765) (xy 358.53213 -282.620781)
			(xy 358.495407 -282.657504) (xy 358.453391 -282.68803) (xy 358.407117 -282.711608) (xy 358.357724 -282.727656)
			(xy 358.306429 -282.735781) (xy 358.254495 -282.735781) (xy 358.2032 -282.727656) (xy 358.153807 -282.711608)
			(xy 358.107533 -282.68803) (xy 358.065517 -282.657504) (xy 358.028794 -282.620781) (xy 357.998268 -282.578765)
			(xy 357.97469 -282.532491) (xy 357.958642 -282.483098) (xy 357.950517 -282.431803) (xy 355.791007 -282.431803)
			(xy 355.782882 -282.483098) (xy 355.766834 -282.532491) (xy 355.743256 -282.578765) (xy 355.71273 -282.620781)
			(xy 355.676007 -282.657504) (xy 355.633991 -282.68803) (xy 355.587717 -282.711608) (xy 355.538324 -282.727656)
			(xy 355.487029 -282.735781) (xy 355.435095 -282.735781) (xy 355.3838 -282.727656) (xy 355.334407 -282.711608)
			(xy 355.288133 -282.68803) (xy 355.246117 -282.657504) (xy 355.209394 -282.620781) (xy 355.178868 -282.578765)
			(xy 355.15529 -282.532491) (xy 355.139242 -282.483098) (xy 355.131117 -282.431803) (xy 354.851207 -282.431803)
			(xy 354.843082 -282.483098) (xy 354.827034 -282.532491) (xy 354.803456 -282.578765) (xy 354.77293 -282.620781)
			(xy 354.736207 -282.657504) (xy 354.694191 -282.68803) (xy 354.647917 -282.711608) (xy 354.598524 -282.727656)
			(xy 354.547229 -282.735781) (xy 354.495295 -282.735781) (xy 354.444 -282.727656) (xy 354.394607 -282.711608)
			(xy 354.348333 -282.68803) (xy 354.306317 -282.657504) (xy 354.269594 -282.620781) (xy 354.239068 -282.578765)
			(xy 354.21549 -282.532491) (xy 354.199442 -282.483098) (xy 354.191317 -282.431803) (xy 354.190808 -282.405836)
			(xy 354.191369 -282.377851) (xy 354.200814 -282.322683) (xy 354.209604 -282.296108) (xy 354.217224 -282.27401)
			(xy 354.013516 -281.921204) (xy 353.990656 -281.916886) (xy 353.965723 -281.911766) (xy 353.917736 -281.894798)
			(xy 353.872915 -281.870675) (xy 353.832321 -281.839969) (xy 353.796913 -281.803405) (xy 353.767526 -281.761846)
			(xy 353.744855 -281.716275) (xy 353.729435 -281.667767) (xy 353.721632 -281.61747) (xy 353.721162 -281.59202)
			(xy 353.44227 -281.59202) (xy 353.441761 -281.617987) (xy 353.433636 -281.669282) (xy 353.417588 -281.718675)
			(xy 353.39401 -281.764949) (xy 353.363484 -281.806965) (xy 353.326761 -281.843688) (xy 353.284745 -281.874214)
			(xy 353.238471 -281.897792) (xy 353.189078 -281.91384) (xy 353.137783 -281.921965) (xy 353.085849 -281.921965)
			(xy 353.034554 -281.91384) (xy 352.985161 -281.897792) (xy 352.938887 -281.874214) (xy 352.896871 -281.843688)
			(xy 352.860148 -281.806965) (xy 352.829622 -281.764949) (xy 352.806044 -281.718675) (xy 352.789996 -281.669282)
			(xy 352.781871 -281.617987) (xy 352.501961 -281.617987) (xy 352.493836 -281.669282) (xy 352.477788 -281.718675)
			(xy 352.45421 -281.764949) (xy 352.423684 -281.806965) (xy 352.386961 -281.843688) (xy 352.344945 -281.874214)
			(xy 352.298671 -281.897792) (xy 352.249278 -281.91384) (xy 352.197983 -281.921965) (xy 352.146049 -281.921965)
			(xy 352.094754 -281.91384) (xy 352.045361 -281.897792) (xy 351.999087 -281.874214) (xy 351.957071 -281.843688)
			(xy 351.920348 -281.806965) (xy 351.889822 -281.764949) (xy 351.866244 -281.718675) (xy 351.850196 -281.669282)
			(xy 351.842071 -281.617987) (xy 351.841562 -281.59202) (xy 351.842116 -281.564034) (xy 351.851565 -281.508866)
			(xy 351.860358 -281.482292) (xy 351.867978 -281.460194) (xy 351.66427 -281.107388) (xy 351.64141 -281.10307)
			(xy 351.61646 -281.097909) (xy 351.568396 -281.08102) (xy 351.523494 -281.056954) (xy 351.482818 -281.02628)
			(xy 351.447333 -280.989726) (xy 351.417879 -280.948158) (xy 351.395155 -280.902562) (xy 351.3797 -280.854018)
			(xy 351.371879 -280.803677) (xy 351.371408 -280.778204) (xy 351.09277 -280.778204) (xy 351.092261 -280.804171)
			(xy 351.084136 -280.855466) (xy 351.068088 -280.904859) (xy 351.04451 -280.951133) (xy 351.013984 -280.993149)
			(xy 350.977261 -281.029872) (xy 350.935245 -281.060398) (xy 350.888971 -281.083976) (xy 350.839578 -281.100024)
			(xy 350.788283 -281.108149) (xy 350.736349 -281.108149) (xy 350.685054 -281.100024) (xy 350.635661 -281.083976)
			(xy 350.589387 -281.060398) (xy 350.547371 -281.029872) (xy 350.510648 -280.993149) (xy 350.480122 -280.951133)
			(xy 350.456544 -280.904859) (xy 350.440496 -280.855466) (xy 350.432371 -280.804171) (xy 350.152207 -280.804171)
			(xy 350.144082 -280.855466) (xy 350.128034 -280.904859) (xy 350.104456 -280.951133) (xy 350.07393 -280.993149)
			(xy 350.037207 -281.029872) (xy 349.995191 -281.060398) (xy 349.948917 -281.083976) (xy 349.899524 -281.100024)
			(xy 349.848229 -281.108149) (xy 349.796295 -281.108149) (xy 349.745 -281.100024) (xy 349.695607 -281.083976)
			(xy 349.649333 -281.060398) (xy 349.607317 -281.029872) (xy 349.570594 -280.993149) (xy 349.540068 -280.951133)
			(xy 349.51649 -280.904859) (xy 349.500442 -280.855466) (xy 349.492317 -280.804171) (xy 349.212404 -280.804171)
			(xy 349.212367 -280.80605) (xy 349.203038 -280.860954) (xy 349.194374 -280.887424) (xy 349.1865 -280.909522)
			(xy 349.390462 -281.262836) (xy 349.413576 -281.267154) (xy 349.438501 -281.272307) (xy 349.486484 -281.289276)
			(xy 349.5313 -281.313397) (xy 349.571892 -281.344099) (xy 349.607299 -281.380659) (xy 349.636687 -281.422213)
			(xy 349.659361 -281.467778) (xy 349.674785 -281.51628) (xy 349.682596 -281.566572) (xy 349.68307 -281.59202)
			(xy 349.682561 -281.617987) (xy 349.674436 -281.669282) (xy 349.658388 -281.718675) (xy 349.63481 -281.764949)
			(xy 349.604284 -281.806965) (xy 349.567561 -281.843688) (xy 349.525545 -281.874214) (xy 349.479271 -281.897792)
			(xy 349.429878 -281.91384) (xy 349.378583 -281.921965) (xy 349.326649 -281.921965) (xy 349.275354 -281.91384)
			(xy 349.225961 -281.897792) (xy 349.179687 -281.874214) (xy 349.137671 -281.843688) (xy 349.100948 -281.806965)
			(xy 349.070422 -281.764949) (xy 349.046844 -281.718675) (xy 349.030796 -281.669282) (xy 349.022671 -281.617987)
			(xy 349.022162 -281.59202) (xy 349.022716 -281.564034) (xy 349.032165 -281.508866) (xy 349.040958 -281.482292)
			(xy 349.048578 -281.460194) (xy 348.84487 -281.107388) (xy 348.82201 -281.10307) (xy 348.79706 -281.097909)
			(xy 348.748996 -281.08102) (xy 348.704094 -281.056954) (xy 348.663418 -281.02628) (xy 348.627933 -280.989726)
			(xy 348.598479 -280.948158) (xy 348.575755 -280.902562) (xy 348.5603 -280.854018) (xy 348.552479 -280.803677)
			(xy 348.552008 -280.778204) (xy 348.273116 -280.778204) (xy 348.272607 -280.804171) (xy 348.264482 -280.855466)
			(xy 348.248434 -280.904859) (xy 348.224856 -280.951133) (xy 348.19433 -280.993149) (xy 348.157607 -281.029872)
			(xy 348.115591 -281.060398) (xy 348.069317 -281.083976) (xy 348.019924 -281.100024) (xy 347.968629 -281.108149)
			(xy 347.916695 -281.108149) (xy 347.8654 -281.100024) (xy 347.816007 -281.083976) (xy 347.769733 -281.060398)
			(xy 347.727717 -281.029872) (xy 347.690994 -280.993149) (xy 347.660468 -280.951133) (xy 347.63689 -280.904859)
			(xy 347.620842 -280.855466) (xy 347.612717 -280.804171) (xy 347.332807 -280.804171) (xy 347.324682 -280.855466)
			(xy 347.308634 -280.904859) (xy 347.285056 -280.951133) (xy 347.25453 -280.993149) (xy 347.217807 -281.029872)
			(xy 347.175791 -281.060398) (xy 347.129517 -281.083976) (xy 347.080124 -281.100024) (xy 347.028829 -281.108149)
			(xy 346.976895 -281.108149) (xy 346.9256 -281.100024) (xy 346.876207 -281.083976) (xy 346.829933 -281.060398)
			(xy 346.787917 -281.029872) (xy 346.751194 -280.993149) (xy 346.720668 -280.951133) (xy 346.69709 -280.904859)
			(xy 346.681042 -280.855466) (xy 346.672917 -280.804171) (xy 346.392984 -280.804171) (xy 346.385283 -280.853963)
			(xy 346.369878 -280.902481) (xy 346.347212 -280.948061) (xy 346.317821 -280.989624) (xy 346.282402 -281.026186)
			(xy 346.241794 -281.056881) (xy 346.196957 -281.080983) (xy 346.148953 -281.097921) (xy 346.124022 -281.10307)
			(xy 346.101162 -281.107388) (xy 345.897454 -281.460194) (xy 345.905074 -281.482292) (xy 345.913809 -281.508881)
			(xy 345.923258 -281.56404) (xy 345.92387 -281.59202) (xy 345.923361 -281.617987) (xy 346.203271 -281.617987)
			(xy 346.203271 -281.566053) (xy 346.211396 -281.514758) (xy 346.227444 -281.465365) (xy 346.251022 -281.419091)
			(xy 346.281548 -281.377075) (xy 346.318271 -281.340352) (xy 346.360287 -281.309826) (xy 346.406561 -281.286248)
			(xy 346.455954 -281.2702) (xy 346.507249 -281.262075) (xy 346.559183 -281.262075) (xy 346.610478 -281.2702)
			(xy 346.659871 -281.286248) (xy 346.706145 -281.309826) (xy 346.748161 -281.340352) (xy 346.784884 -281.377075)
			(xy 346.81541 -281.419091) (xy 346.838988 -281.465365) (xy 346.855036 -281.514758) (xy 346.863161 -281.566053)
			(xy 346.86367 -281.59202) (xy 346.863161 -281.617969) (xy 347.143049 -281.617969) (xy 347.143049 -281.566031)
			(xy 347.151174 -281.514734) (xy 347.167224 -281.465339) (xy 347.190803 -281.419063) (xy 347.221332 -281.377046)
			(xy 347.258058 -281.340322) (xy 347.300077 -281.309795) (xy 347.346354 -281.286218) (xy 347.395749 -281.27017)
			(xy 347.447047 -281.262048) (xy 347.473016 -281.261566) (xy 347.498635 -281.262103) (xy 347.549258 -281.270019)
			(xy 347.598056 -281.285644) (xy 347.643862 -281.308605) (xy 347.685581 -281.338352) (xy 347.722216 -281.374175)
			(xy 347.737938 -281.394408) (xy 348.147894 -281.394408) (xy 348.163638 -281.374187) (xy 348.20025 -281.338333)
			(xy 348.241958 -281.308561) (xy 348.287762 -281.285585) (xy 348.336564 -281.269955) (xy 348.387194 -281.262047)
			(xy 348.412816 -281.261566) (xy 348.438784 -281.262037) (xy 348.49008 -281.270163) (xy 348.539474 -281.286214)
			(xy 348.585748 -281.309794) (xy 348.627764 -281.340323) (xy 348.664488 -281.377048) (xy 348.695014 -281.419066)
			(xy 348.718592 -281.465341) (xy 348.73464 -281.514735) (xy 348.742765 -281.566032) (xy 348.742765 -281.617968)
			(xy 348.73464 -281.669265) (xy 348.718592 -281.718659) (xy 348.695014 -281.764934) (xy 348.664488 -281.806952)
			(xy 348.627764 -281.843677) (xy 348.585748 -281.874206) (xy 348.539474 -281.897786) (xy 348.49008 -281.913837)
			(xy 348.438784 -281.921963) (xy 348.412816 -281.922474) (xy 348.387194 -281.92201) (xy 348.336566 -281.914082)
			(xy 348.287766 -281.898444) (xy 348.24196 -281.875469) (xy 348.200243 -281.845708) (xy 348.163613 -281.809872)
			(xy 348.147894 -281.789632) (xy 347.737938 -281.789632) (xy 347.722245 -281.809894) (xy 347.685621 -281.845744)
			(xy 347.643902 -281.87551) (xy 347.598088 -281.898478) (xy 347.549278 -281.914099) (xy 347.498641 -281.921998)
			(xy 347.473016 -281.922474) (xy 347.447047 -281.921952) (xy 347.395749 -281.91383) (xy 347.346354 -281.897782)
			(xy 347.300077 -281.874205) (xy 347.258058 -281.843678) (xy 347.221332 -281.806954) (xy 347.190803 -281.764937)
			(xy 347.167224 -281.718661) (xy 347.151174 -281.669266) (xy 347.143049 -281.617969) (xy 346.863161 -281.617969)
			(xy 346.863161 -281.617987) (xy 346.855036 -281.669282) (xy 346.838988 -281.718675) (xy 346.81541 -281.764949)
			(xy 346.784884 -281.806965) (xy 346.748161 -281.843688) (xy 346.706145 -281.874214) (xy 346.659871 -281.897792)
			(xy 346.610478 -281.91384) (xy 346.559183 -281.921965) (xy 346.507249 -281.921965) (xy 346.455954 -281.91384)
			(xy 346.406561 -281.897792) (xy 346.360287 -281.874214) (xy 346.318271 -281.843688) (xy 346.281548 -281.806965)
			(xy 346.251022 -281.764949) (xy 346.227444 -281.718675) (xy 346.211396 -281.669282) (xy 346.203271 -281.617987)
			(xy 345.923361 -281.617987) (xy 345.915236 -281.669282) (xy 345.899188 -281.718675) (xy 345.87561 -281.764949)
			(xy 345.845084 -281.806965) (xy 345.808361 -281.843688) (xy 345.766345 -281.874214) (xy 345.720071 -281.897792)
			(xy 345.670678 -281.91384) (xy 345.619383 -281.921965) (xy 345.567449 -281.921965) (xy 345.516154 -281.91384)
			(xy 345.466761 -281.897792) (xy 345.420487 -281.874214) (xy 345.378471 -281.843688) (xy 345.341748 -281.806965)
			(xy 345.311222 -281.764949) (xy 345.287644 -281.718675) (xy 345.271596 -281.669282) (xy 345.263471 -281.617987)
			(xy 345.262962 -281.59202) (xy 344.98357 -281.59202) (xy 344.98357 -281.617752) (xy 344.97558 -281.668631)
			(xy 344.959793 -281.717655) (xy 344.936592 -281.763636) (xy 344.906538 -281.805461) (xy 344.87036 -281.842117)
			(xy 344.828932 -281.872717) (xy 344.783259 -281.896519) (xy 344.734447 -281.912947) (xy 344.683676 -281.921604)
			(xy 344.657934 -281.922474) (xy 344.644724 -281.923059) (xy 344.619265 -281.930164) (xy 344.596484 -281.943567)
			(xy 344.577908 -281.962371) (xy 344.564784 -281.985314) (xy 344.55799 -282.010858) (xy 344.557604 -282.024074)
			(xy 344.557604 -282.431762) (xy 344.793391 -282.431762) (xy 344.793391 -282.379838) (xy 344.801513 -282.328552)
			(xy 344.817558 -282.279168) (xy 344.84113 -282.232901) (xy 344.871648 -282.190892) (xy 344.908363 -282.154173)
			(xy 344.950369 -282.12365) (xy 344.996633 -282.100072) (xy 345.046015 -282.084022) (xy 345.0973 -282.075894)
			(xy 345.123262 -282.075382) (xy 345.148883 -282.07588) (xy 345.199508 -282.083803) (xy 345.248307 -282.099436)
			(xy 345.294113 -282.122404) (xy 345.335831 -282.152158) (xy 345.372463 -282.187987) (xy 345.388184 -282.208224)
			(xy 345.79814 -282.208224) (xy 345.813834 -282.187963) (xy 345.850459 -282.152115) (xy 345.892178 -282.122351)
			(xy 345.937992 -282.099382) (xy 345.986802 -282.08376) (xy 346.037438 -282.075859) (xy 346.063062 -282.075382)
			(xy 346.089036 -282.07579) (xy 346.140345 -282.083911) (xy 346.189752 -282.09996) (xy 346.23604 -282.12354)
			(xy 346.278069 -282.154071) (xy 346.314804 -282.190802) (xy 346.34534 -282.232827) (xy 346.368926 -282.279112)
			(xy 346.38498 -282.328518) (xy 346.393107 -282.379826) (xy 346.393107 -282.431774) (xy 346.393102 -282.431803)
			(xy 346.672917 -282.431803) (xy 346.672917 -282.379869) (xy 346.681042 -282.328574) (xy 346.69709 -282.279181)
			(xy 346.720668 -282.232907) (xy 346.751194 -282.190891) (xy 346.787917 -282.154168) (xy 346.829933 -282.123642)
			(xy 346.876207 -282.100064) (xy 346.9256 -282.084016) (xy 346.976895 -282.075891) (xy 347.028829 -282.075891)
			(xy 347.080124 -282.084016) (xy 347.129517 -282.100064) (xy 347.175791 -282.123642) (xy 347.217807 -282.154168)
			(xy 347.25453 -282.190891) (xy 347.285056 -282.232907) (xy 347.308634 -282.279181) (xy 347.324682 -282.328574)
			(xy 347.332807 -282.379869) (xy 347.333316 -282.405836) (xy 347.332807 -282.431803) (xy 347.324682 -282.483098)
			(xy 347.308634 -282.532491) (xy 347.285056 -282.578765) (xy 347.25453 -282.620781) (xy 347.217807 -282.657504)
			(xy 347.175791 -282.68803) (xy 347.129517 -282.711608) (xy 347.080124 -282.727656) (xy 347.028829 -282.735781)
			(xy 346.976895 -282.735781) (xy 346.9256 -282.727656) (xy 346.876207 -282.711608) (xy 346.829933 -282.68803)
			(xy 346.787917 -282.657504) (xy 346.751194 -282.620781) (xy 346.720668 -282.578765) (xy 346.69709 -282.532491)
			(xy 346.681042 -282.483098) (xy 346.672917 -282.431803) (xy 346.393102 -282.431803) (xy 346.38498 -282.483082)
			(xy 346.368926 -282.532488) (xy 346.34534 -282.578773) (xy 346.314804 -282.620798) (xy 346.278069 -282.657529)
			(xy 346.23604 -282.68806) (xy 346.189752 -282.71164) (xy 346.140345 -282.727689) (xy 346.089036 -282.73581)
			(xy 346.063062 -282.73629) (xy 346.037442 -282.735786) (xy 345.986816 -282.727866) (xy 345.938017 -282.712235)
			(xy 345.89221 -282.689268) (xy 345.850493 -282.659514) (xy 345.81386 -282.623685) (xy 345.79814 -282.603448)
			(xy 345.388184 -282.603448) (xy 345.372468 -282.623692) (xy 345.335849 -282.659541) (xy 345.294134 -282.689309)
			(xy 345.248325 -282.712281) (xy 345.199519 -282.727906) (xy 345.148885 -282.735811) (xy 345.123262 -282.73629)
			(xy 345.0973 -282.735706) (xy 345.046015 -282.727578) (xy 344.996633 -282.711528) (xy 344.950369 -282.68795)
			(xy 344.908363 -282.657427) (xy 344.871648 -282.620708) (xy 344.84113 -282.578699) (xy 344.817558 -282.532432)
			(xy 344.801513 -282.483048) (xy 344.793391 -282.431762) (xy 344.557604 -282.431762) (xy 344.557604 -282.65882)
			(xy 344.691462 -282.890722) (xy 344.714576 -282.89504) (xy 344.739503 -282.900192) (xy 344.7875 -282.917136)
			(xy 344.832329 -282.941242) (xy 344.872931 -282.971939) (xy 344.908342 -283.008501) (xy 344.937726 -283.050063)
			(xy 344.960387 -283.09564) (xy 344.975787 -283.144154) (xy 344.983564 -283.194456) (xy 344.98407 -283.219906)
			(xy 344.983577 -283.245658) (xy 344.983543 -283.245873) (xy 345.263217 -283.245873) (xy 345.263217 -283.193939)
			(xy 345.271342 -283.142644) (xy 345.28739 -283.093251) (xy 345.310968 -283.046977) (xy 345.341494 -283.004961)
			(xy 345.378217 -282.968238) (xy 345.420233 -282.937712) (xy 345.466507 -282.914134) (xy 345.5159 -282.898086)
			(xy 345.567195 -282.889961) (xy 345.619129 -282.889961) (xy 345.670424 -282.898086) (xy 345.719817 -282.914134)
			(xy 345.766091 -282.937712) (xy 345.808107 -282.968238) (xy 345.84483 -283.004961) (xy 345.875356 -283.046977)
			(xy 345.898934 -283.093251) (xy 345.914982 -283.142644) (xy 345.923107 -283.193939) (xy 345.923616 -283.219906)
			(xy 345.923107 -283.245873) (xy 346.203017 -283.245873) (xy 346.203017 -283.193939) (xy 346.211142 -283.142644)
			(xy 346.22719 -283.093251) (xy 346.250768 -283.046977) (xy 346.281294 -283.004961) (xy 346.318017 -282.968238)
			(xy 346.360033 -282.937712) (xy 346.406307 -282.914134) (xy 346.4557 -282.898086) (xy 346.506995 -282.889961)
			(xy 346.558929 -282.889961) (xy 346.610224 -282.898086) (xy 346.659617 -282.914134) (xy 346.705891 -282.937712)
			(xy 346.747907 -282.968238) (xy 346.78463 -283.004961) (xy 346.815156 -283.046977) (xy 346.838734 -283.093251)
			(xy 346.854782 -283.142644) (xy 346.862907 -283.193939) (xy 346.863416 -283.219906) (xy 347.142562 -283.219906)
			(xy 347.143042 -283.194455) (xy 347.15082 -283.14415) (xy 347.166222 -283.095634) (xy 347.188885 -283.050055)
			(xy 347.218272 -283.008493) (xy 347.253688 -282.971931) (xy 347.294293 -282.941234) (xy 347.339126 -282.917131)
			(xy 347.387127 -282.90019) (xy 347.412056 -282.89504) (xy 347.43517 -282.890722) (xy 347.638878 -282.537916)
			(xy 347.631004 -282.515818) (xy 347.622255 -282.489167) (xy 347.612804 -282.43388) (xy 347.612208 -282.405836)
			(xy 347.612717 -282.379869) (xy 347.620842 -282.328574) (xy 347.63689 -282.279181) (xy 347.660468 -282.232907)
			(xy 347.690994 -282.190891) (xy 347.727717 -282.154168) (xy 347.769733 -282.123642) (xy 347.816007 -282.100064)
			(xy 347.8654 -282.084016) (xy 347.916695 -282.075891) (xy 347.968629 -282.075891) (xy 348.019924 -282.084016)
			(xy 348.069317 -282.100064) (xy 348.115591 -282.123642) (xy 348.157607 -282.154168) (xy 348.19433 -282.190891)
			(xy 348.224856 -282.232907) (xy 348.248434 -282.279181) (xy 348.264482 -282.328574) (xy 348.272607 -282.379869)
			(xy 348.273116 -282.405836) (xy 348.272607 -282.431268) (xy 348.272524 -282.431803) (xy 348.552517 -282.431803)
			(xy 348.552517 -282.379869) (xy 348.560642 -282.328574) (xy 348.57669 -282.279181) (xy 348.600268 -282.232907)
			(xy 348.630794 -282.190891) (xy 348.667517 -282.154168) (xy 348.709533 -282.123642) (xy 348.755807 -282.100064)
			(xy 348.8052 -282.084016) (xy 348.856495 -282.075891) (xy 348.908429 -282.075891) (xy 348.959724 -282.084016)
			(xy 349.009117 -282.100064) (xy 349.055391 -282.123642) (xy 349.097407 -282.154168) (xy 349.13413 -282.190891)
			(xy 349.164656 -282.232907) (xy 349.188234 -282.279181) (xy 349.204282 -282.328574) (xy 349.212407 -282.379869)
			(xy 349.212916 -282.405836) (xy 349.491808 -282.405836) (xy 349.492268 -282.380385) (xy 349.500054 -282.330082)
			(xy 349.515464 -282.281568) (xy 349.538131 -282.235991) (xy 349.567521 -282.194431) (xy 349.602937 -282.15787)
			(xy 349.643542 -282.127173) (xy 349.688374 -282.103067) (xy 349.736373 -282.086122) (xy 349.761302 -282.08097)
			(xy 349.784416 -282.076652) (xy 349.988378 -281.723338) (xy 349.980504 -281.70124) (xy 349.971869 -281.674763)
			(xy 349.962543 -281.619863) (xy 349.961962 -281.59202) (xy 349.962471 -281.566053) (xy 349.970596 -281.514758)
			(xy 349.986644 -281.465365) (xy 350.010222 -281.419091) (xy 350.040748 -281.377075) (xy 350.077471 -281.340352)
			(xy 350.119487 -281.309826) (xy 350.165761 -281.286248) (xy 350.215154 -281.2702) (xy 350.266449 -281.262075)
			(xy 350.318383 -281.262075) (xy 350.369678 -281.2702) (xy 350.419071 -281.286248) (xy 350.465345 -281.309826)
			(xy 350.507361 -281.340352) (xy 350.544084 -281.377075) (xy 350.57461 -281.419091) (xy 350.598188 -281.465365)
			(xy 350.614236 -281.514758) (xy 350.622361 -281.566053) (xy 350.62287 -281.59202) (xy 350.622393 -281.617493)
			(xy 350.622316 -281.617987) (xy 350.902017 -281.617987) (xy 350.902017 -281.566053) (xy 350.910142 -281.514758)
			(xy 350.92619 -281.465365) (xy 350.949768 -281.419091) (xy 350.980294 -281.377075) (xy 351.017017 -281.340352)
			(xy 351.059033 -281.309826) (xy 351.105307 -281.286248) (xy 351.1547 -281.2702) (xy 351.205995 -281.262075)
			(xy 351.257929 -281.262075) (xy 351.309224 -281.2702) (xy 351.358617 -281.286248) (xy 351.404891 -281.309826)
			(xy 351.446907 -281.340352) (xy 351.48363 -281.377075) (xy 351.514156 -281.419091) (xy 351.537734 -281.465365)
			(xy 351.553782 -281.514758) (xy 351.561907 -281.566053) (xy 351.562416 -281.59202) (xy 351.561907 -281.617987)
			(xy 351.553782 -281.669282) (xy 351.537734 -281.718675) (xy 351.514156 -281.764949) (xy 351.48363 -281.806965)
			(xy 351.446907 -281.843688) (xy 351.404891 -281.874214) (xy 351.358617 -281.897792) (xy 351.309224 -281.91384)
			(xy 351.257929 -281.921965) (xy 351.205995 -281.921965) (xy 351.1547 -281.91384) (xy 351.105307 -281.897792)
			(xy 351.059033 -281.874214) (xy 351.017017 -281.843688) (xy 350.980294 -281.806965) (xy 350.949768 -281.764949)
			(xy 350.92619 -281.718675) (xy 350.910142 -281.669282) (xy 350.902017 -281.617987) (xy 350.622316 -281.617987)
			(xy 350.614571 -281.667836) (xy 350.599116 -281.716381) (xy 350.576393 -281.76198) (xy 350.546942 -281.803551)
			(xy 350.511459 -281.840109) (xy 350.470787 -281.870789) (xy 350.425887 -281.894864) (xy 350.377825 -281.911762)
			(xy 350.352868 -281.916886) (xy 350.330008 -281.921204) (xy 350.1263 -282.27401) (xy 350.13392 -282.296108)
			(xy 350.14266 -282.322695) (xy 350.152106 -282.377855) (xy 350.152716 -282.405836) (xy 350.152207 -282.431803)
			(xy 350.432371 -282.431803) (xy 350.432371 -282.379869) (xy 350.440496 -282.328574) (xy 350.456544 -282.279181)
			(xy 350.480122 -282.232907) (xy 350.510648 -282.190891) (xy 350.547371 -282.154168) (xy 350.589387 -282.123642)
			(xy 350.635661 -282.100064) (xy 350.685054 -282.084016) (xy 350.736349 -282.075891) (xy 350.788283 -282.075891)
			(xy 350.839578 -282.084016) (xy 350.888971 -282.100064) (xy 350.935245 -282.123642) (xy 350.977261 -282.154168)
			(xy 351.013984 -282.190891) (xy 351.04451 -282.232907) (xy 351.068088 -282.279181) (xy 351.084136 -282.328574)
			(xy 351.092261 -282.379869) (xy 351.09277 -282.405836) (xy 351.092262 -282.431762) (xy 351.371991 -282.431762)
			(xy 351.371991 -282.379838) (xy 351.380113 -282.328552) (xy 351.396158 -282.279168) (xy 351.41973 -282.232901)
			(xy 351.450248 -282.190892) (xy 351.486963 -282.154173) (xy 351.528969 -282.12365) (xy 351.575233 -282.100072)
			(xy 351.624615 -282.084022) (xy 351.6759 -282.075894) (xy 351.701862 -282.075382) (xy 351.727483 -282.07588)
			(xy 351.778108 -282.083803) (xy 351.826907 -282.099436) (xy 351.872713 -282.122404) (xy 351.914431 -282.152158)
			(xy 351.951063 -282.187987) (xy 351.966784 -282.208224) (xy 352.37674 -282.208224) (xy 352.392434 -282.187963)
			(xy 352.429059 -282.152115) (xy 352.470778 -282.122351) (xy 352.516592 -282.099382) (xy 352.565402 -282.08376)
			(xy 352.616038 -282.075859) (xy 352.641662 -282.075382) (xy 352.667636 -282.07579) (xy 352.718945 -282.083911)
			(xy 352.768352 -282.09996) (xy 352.81464 -282.12354) (xy 352.856669 -282.154071) (xy 352.893404 -282.190802)
			(xy 352.92394 -282.232827) (xy 352.947526 -282.279112) (xy 352.96358 -282.328518) (xy 352.971707 -282.379826)
			(xy 352.971707 -282.431774) (xy 352.96358 -282.483082) (xy 352.947526 -282.532488) (xy 352.92394 -282.578773)
			(xy 352.893404 -282.620798) (xy 352.856669 -282.657529) (xy 352.81464 -282.68806) (xy 352.768352 -282.71164)
			(xy 352.718945 -282.727689) (xy 352.667636 -282.73581) (xy 352.641662 -282.73629) (xy 352.616042 -282.735786)
			(xy 352.565416 -282.727866) (xy 352.516617 -282.712235) (xy 352.47081 -282.689268) (xy 352.429093 -282.659514)
			(xy 352.39246 -282.623685) (xy 352.37674 -282.603448) (xy 351.966784 -282.603448) (xy 351.951068 -282.623692)
			(xy 351.914449 -282.659541) (xy 351.872734 -282.689309) (xy 351.826925 -282.712281) (xy 351.778119 -282.727906)
			(xy 351.727485 -282.735811) (xy 351.701862 -282.73629) (xy 351.6759 -282.735706) (xy 351.624615 -282.727578)
			(xy 351.575233 -282.711528) (xy 351.528969 -282.68795) (xy 351.486963 -282.657427) (xy 351.450248 -282.620708)
			(xy 351.41973 -282.578699) (xy 351.396158 -282.532432) (xy 351.380113 -282.483048) (xy 351.371991 -282.431762)
			(xy 351.092262 -282.431762) (xy 351.092261 -282.431803) (xy 351.084136 -282.483098) (xy 351.068088 -282.532491)
			(xy 351.04451 -282.578765) (xy 351.013984 -282.620781) (xy 350.977261 -282.657504) (xy 350.935245 -282.68803)
			(xy 350.888971 -282.711608) (xy 350.839578 -282.727656) (xy 350.788283 -282.735781) (xy 350.736349 -282.735781)
			(xy 350.685054 -282.727656) (xy 350.635661 -282.711608) (xy 350.589387 -282.68803) (xy 350.547371 -282.657504)
			(xy 350.510648 -282.620781) (xy 350.480122 -282.578765) (xy 350.456544 -282.532491) (xy 350.440496 -282.483098)
			(xy 350.432371 -282.431803) (xy 350.152207 -282.431803) (xy 350.144082 -282.483098) (xy 350.128034 -282.532491)
			(xy 350.104456 -282.578765) (xy 350.07393 -282.620781) (xy 350.037207 -282.657504) (xy 349.995191 -282.68803)
			(xy 349.948917 -282.711608) (xy 349.899524 -282.727656) (xy 349.848229 -282.735781) (xy 349.796295 -282.735781)
			(xy 349.745 -282.727656) (xy 349.695607 -282.711608) (xy 349.649333 -282.68803) (xy 349.607317 -282.657504)
			(xy 349.570594 -282.620781) (xy 349.540068 -282.578765) (xy 349.51649 -282.532491) (xy 349.500442 -282.483098)
			(xy 349.492317 -282.431803) (xy 349.491808 -282.405836) (xy 349.212916 -282.405836) (xy 349.212407 -282.431803)
			(xy 349.204282 -282.483098) (xy 349.188234 -282.532491) (xy 349.164656 -282.578765) (xy 349.13413 -282.620781)
			(xy 349.097407 -282.657504) (xy 349.055391 -282.68803) (xy 349.009117 -282.711608) (xy 348.959724 -282.727656)
			(xy 348.908429 -282.735781) (xy 348.856495 -282.735781) (xy 348.8052 -282.727656) (xy 348.755807 -282.711608)
			(xy 348.709533 -282.68803) (xy 348.667517 -282.657504) (xy 348.630794 -282.620781) (xy 348.600268 -282.578765)
			(xy 348.57669 -282.532491) (xy 348.560642 -282.483098) (xy 348.552517 -282.431803) (xy 348.272524 -282.431803)
			(xy 348.2648 -282.481529) (xy 348.249392 -282.530003) (xy 348.226744 -282.575547) (xy 348.197392 -282.617088)
			(xy 348.162026 -282.653645) (xy 348.121482 -282.684358) (xy 348.076713 -282.708503) (xy 348.028777 -282.72551)
			(xy 348.003876 -282.730702) (xy 347.980762 -282.73502) (xy 347.777054 -283.08808) (xy 347.784674 -283.110178)
			(xy 347.793406 -283.136768) (xy 347.802857 -283.191926) (xy 347.80347 -283.219906) (xy 347.802961 -283.245873)
			(xy 348.082617 -283.245873) (xy 348.082617 -283.193939) (xy 348.090742 -283.142644) (xy 348.10679 -283.093251)
			(xy 348.130368 -283.046977) (xy 348.160894 -283.004961) (xy 348.197617 -282.968238) (xy 348.239633 -282.937712)
			(xy 348.285907 -282.914134) (xy 348.3353 -282.898086) (xy 348.386595 -282.889961) (xy 348.438529 -282.889961)
			(xy 348.489824 -282.898086) (xy 348.539217 -282.914134) (xy 348.585491 -282.937712) (xy 348.627507 -282.968238)
			(xy 348.66423 -283.004961) (xy 348.694756 -283.046977) (xy 348.718334 -283.093251) (xy 348.734382 -283.142644)
			(xy 348.742507 -283.193939) (xy 348.743016 -283.219906) (xy 348.742507 -283.24587) (xy 349.022635 -283.24587)
			(xy 349.022635 -283.19393) (xy 349.03076 -283.142631) (xy 349.046811 -283.093234) (xy 349.070391 -283.046956)
			(xy 349.100921 -283.004937) (xy 349.137649 -282.968211) (xy 349.179669 -282.937683) (xy 349.225948 -282.914105)
			(xy 349.275346 -282.898056) (xy 349.326646 -282.889934) (xy 349.352616 -282.889452) (xy 349.378253 -282.889902)
			(xy 349.428912 -282.897831) (xy 349.477735 -282.913495) (xy 349.523551 -282.936519) (xy 349.565256 -282.966348)
			(xy 349.601849 -283.002266) (xy 349.617538 -283.022548) (xy 350.027494 -283.022548) (xy 350.043165 -283.002253)
			(xy 350.079766 -282.966346) (xy 350.121478 -282.936527) (xy 350.167296 -282.913513) (xy 350.216121 -282.897857)
			(xy 350.266779 -282.889935) (xy 350.292416 -282.889452) (xy 350.318383 -282.88995) (xy 350.369677 -282.898077)
			(xy 350.419068 -282.914127) (xy 350.465341 -282.937706) (xy 350.507355 -282.968233) (xy 350.544077 -283.004957)
			(xy 350.574602 -283.046973) (xy 350.598179 -283.093247) (xy 350.614227 -283.142639) (xy 350.622351 -283.193933)
			(xy 350.622351 -283.245867) (xy 350.62235 -283.245873) (xy 350.902017 -283.245873) (xy 350.902017 -283.193939)
			(xy 350.910142 -283.142644) (xy 350.92619 -283.093251) (xy 350.949768 -283.046977) (xy 350.980294 -283.004961)
			(xy 351.017017 -282.968238) (xy 351.059033 -282.937712) (xy 351.105307 -282.914134) (xy 351.1547 -282.898086)
			(xy 351.205995 -282.889961) (xy 351.257929 -282.889961) (xy 351.309224 -282.898086) (xy 351.358617 -282.914134)
			(xy 351.404891 -282.937712) (xy 351.446907 -282.968238) (xy 351.48363 -283.004961) (xy 351.514156 -283.046977)
			(xy 351.537734 -283.093251) (xy 351.553782 -283.142644) (xy 351.561907 -283.193939) (xy 351.562416 -283.219906)
			(xy 351.561907 -283.245873) (xy 351.841817 -283.245873) (xy 351.841817 -283.193939) (xy 351.849942 -283.142644)
			(xy 351.86599 -283.093251) (xy 351.889568 -283.046977) (xy 351.920094 -283.004961) (xy 351.956817 -282.968238)
			(xy 351.998833 -282.937712) (xy 352.045107 -282.914134) (xy 352.0945 -282.898086) (xy 352.145795 -282.889961)
			(xy 352.197729 -282.889961) (xy 352.249024 -282.898086) (xy 352.298417 -282.914134) (xy 352.344691 -282.937712)
			(xy 352.386707 -282.968238) (xy 352.42343 -283.004961) (xy 352.453956 -283.046977) (xy 352.477534 -283.093251)
			(xy 352.493582 -283.142644) (xy 352.501707 -283.193939) (xy 352.502216 -283.219906) (xy 352.781362 -283.219906)
			(xy 352.781842 -283.194455) (xy 352.78962 -283.14415) (xy 352.805022 -283.095634) (xy 352.827685 -283.050055)
			(xy 352.857072 -283.008493) (xy 352.892488 -282.971931) (xy 352.933093 -282.941234) (xy 352.977926 -282.917131)
			(xy 353.025927 -282.90019) (xy 353.050856 -282.89504) (xy 353.07397 -282.890722) (xy 353.277678 -282.537916)
			(xy 353.269804 -282.515818) (xy 353.261055 -282.489167) (xy 353.251604 -282.43388) (xy 353.251008 -282.405836)
			(xy 353.251517 -282.379869) (xy 353.259642 -282.328574) (xy 353.27569 -282.279181) (xy 353.299268 -282.232907)
			(xy 353.329794 -282.190891) (xy 353.366517 -282.154168) (xy 353.408533 -282.123642) (xy 353.454807 -282.100064)
			(xy 353.5042 -282.084016) (xy 353.555495 -282.075891) (xy 353.607429 -282.075891) (xy 353.658724 -282.084016)
			(xy 353.708117 -282.100064) (xy 353.754391 -282.123642) (xy 353.796407 -282.154168) (xy 353.83313 -282.190891)
			(xy 353.863656 -282.232907) (xy 353.887234 -282.279181) (xy 353.903282 -282.328574) (xy 353.911407 -282.379869)
			(xy 353.911916 -282.405836) (xy 353.911407 -282.431268) (xy 353.9036 -282.481529) (xy 353.888192 -282.530003)
			(xy 353.865544 -282.575547) (xy 353.836192 -282.617088) (xy 353.800826 -282.653645) (xy 353.760282 -282.684358)
			(xy 353.715513 -282.708503) (xy 353.667577 -282.72551) (xy 353.642676 -282.730702) (xy 353.619562 -282.73502)
			(xy 353.415854 -283.08808) (xy 353.423474 -283.110178) (xy 353.432206 -283.136768) (xy 353.441657 -283.191926)
			(xy 353.44227 -283.219906) (xy 353.441761 -283.245873) (xy 353.721417 -283.245873) (xy 353.721417 -283.193939)
			(xy 353.729542 -283.142644) (xy 353.74559 -283.093251) (xy 353.769168 -283.046977) (xy 353.799694 -283.004961)
			(xy 353.836417 -282.968238) (xy 353.878433 -282.937712) (xy 353.924707 -282.914134) (xy 353.9741 -282.898086)
			(xy 354.025395 -282.889961) (xy 354.077329 -282.889961) (xy 354.128624 -282.898086) (xy 354.178017 -282.914134)
			(xy 354.224291 -282.937712) (xy 354.266307 -282.968238) (xy 354.30303 -283.004961) (xy 354.333556 -283.046977)
			(xy 354.357134 -283.093251) (xy 354.373182 -283.142644) (xy 354.381307 -283.193939) (xy 354.381816 -283.219906)
			(xy 354.381307 -283.245873) (xy 354.661471 -283.245873) (xy 354.661471 -283.193939) (xy 354.669596 -283.142644)
			(xy 354.685644 -283.093251) (xy 354.709222 -283.046977) (xy 354.739748 -283.004961) (xy 354.776471 -282.968238)
			(xy 354.818487 -282.937712) (xy 354.864761 -282.914134) (xy 354.914154 -282.898086) (xy 354.965449 -282.889961)
			(xy 355.017383 -282.889961) (xy 355.068678 -282.898086) (xy 355.118071 -282.914134) (xy 355.164345 -282.937712)
			(xy 355.206361 -282.968238) (xy 355.243084 -283.004961) (xy 355.27361 -283.046977) (xy 355.297188 -283.093251)
			(xy 355.313236 -283.142644) (xy 355.321361 -283.193939) (xy 355.32187 -283.219906) (xy 355.321361 -283.245873)
			(xy 361.239817 -283.245873) (xy 361.239817 -283.193939) (xy 361.247942 -283.142644) (xy 361.26399 -283.093251)
			(xy 361.287568 -283.046977) (xy 361.318094 -283.004961) (xy 361.354817 -282.968238) (xy 361.396833 -282.937712)
			(xy 361.443107 -282.914134) (xy 361.4925 -282.898086) (xy 361.543795 -282.889961) (xy 361.595729 -282.889961)
			(xy 361.647024 -282.898086) (xy 361.696417 -282.914134) (xy 361.742691 -282.937712) (xy 361.784707 -282.968238)
			(xy 361.82143 -283.004961) (xy 361.851956 -283.046977) (xy 361.875534 -283.093251) (xy 361.891582 -283.142644)
			(xy 361.899707 -283.193939) (xy 361.900216 -283.219906) (xy 361.899707 -283.245873) (xy 364.059471 -283.245873)
			(xy 364.059471 -283.193939) (xy 364.067596 -283.142644) (xy 364.083644 -283.093251) (xy 364.107222 -283.046977)
			(xy 364.137748 -283.004961) (xy 364.174471 -282.968238) (xy 364.216487 -282.937712) (xy 364.262761 -282.914134)
			(xy 364.312154 -282.898086) (xy 364.363449 -282.889961) (xy 364.415383 -282.889961) (xy 364.466678 -282.898086)
			(xy 364.516071 -282.914134) (xy 364.562345 -282.937712) (xy 364.604361 -282.968238) (xy 364.641084 -283.004961)
			(xy 364.67161 -283.046977) (xy 364.695188 -283.093251) (xy 364.711236 -283.142644) (xy 364.719361 -283.193939)
			(xy 364.71987 -283.219906) (xy 364.719361 -283.245873) (xy 365.939071 -283.245873) (xy 365.939071 -283.193939)
			(xy 365.947196 -283.142644) (xy 365.963244 -283.093251) (xy 365.986822 -283.046977) (xy 366.017348 -283.004961)
			(xy 366.054071 -282.968238) (xy 366.096087 -282.937712) (xy 366.142361 -282.914134) (xy 366.191754 -282.898086)
			(xy 366.243049 -282.889961) (xy 366.294983 -282.889961) (xy 366.346278 -282.898086) (xy 366.395671 -282.914134)
			(xy 366.441945 -282.937712) (xy 366.483961 -282.968238) (xy 366.520684 -283.004961) (xy 366.55121 -283.046977)
			(xy 366.574788 -283.093251) (xy 366.590836 -283.142644) (xy 366.598961 -283.193939) (xy 366.59947 -283.219906)
			(xy 366.598961 -283.245873) (xy 366.590836 -283.297168) (xy 366.574788 -283.346561) (xy 366.55121 -283.392835)
			(xy 366.520684 -283.434851) (xy 366.483961 -283.471574) (xy 366.441945 -283.5021) (xy 366.395671 -283.525678)
			(xy 366.346278 -283.541726) (xy 366.294983 -283.549851) (xy 366.243049 -283.549851) (xy 366.191754 -283.541726)
			(xy 366.142361 -283.525678) (xy 366.096087 -283.5021) (xy 366.054071 -283.471574) (xy 366.017348 -283.434851)
			(xy 365.986822 -283.392835) (xy 365.963244 -283.346561) (xy 365.947196 -283.297168) (xy 365.939071 -283.245873)
			(xy 364.719361 -283.245873) (xy 364.711236 -283.297168) (xy 364.695188 -283.346561) (xy 364.67161 -283.392835)
			(xy 364.641084 -283.434851) (xy 364.604361 -283.471574) (xy 364.562345 -283.5021) (xy 364.516071 -283.525678)
			(xy 364.466678 -283.541726) (xy 364.415383 -283.549851) (xy 364.363449 -283.549851) (xy 364.312154 -283.541726)
			(xy 364.262761 -283.525678) (xy 364.216487 -283.5021) (xy 364.174471 -283.471574) (xy 364.137748 -283.434851)
			(xy 364.107222 -283.392835) (xy 364.083644 -283.346561) (xy 364.067596 -283.297168) (xy 364.059471 -283.245873)
			(xy 361.899707 -283.245873) (xy 361.891582 -283.297168) (xy 361.875534 -283.346561) (xy 361.851956 -283.392835)
			(xy 361.82143 -283.434851) (xy 361.784707 -283.471574) (xy 361.742691 -283.5021) (xy 361.696417 -283.525678)
			(xy 361.647024 -283.541726) (xy 361.595729 -283.549851) (xy 361.543795 -283.549851) (xy 361.4925 -283.541726)
			(xy 361.443107 -283.525678) (xy 361.396833 -283.5021) (xy 361.354817 -283.471574) (xy 361.318094 -283.434851)
			(xy 361.287568 -283.392835) (xy 361.26399 -283.346561) (xy 361.247942 -283.297168) (xy 361.239817 -283.245873)
			(xy 355.321361 -283.245873) (xy 355.313236 -283.297168) (xy 355.297188 -283.346561) (xy 355.27361 -283.392835)
			(xy 355.243084 -283.434851) (xy 355.206361 -283.471574) (xy 355.164345 -283.5021) (xy 355.118071 -283.525678)
			(xy 355.068678 -283.541726) (xy 355.017383 -283.549851) (xy 354.965449 -283.549851) (xy 354.914154 -283.541726)
			(xy 354.864761 -283.525678) (xy 354.818487 -283.5021) (xy 354.776471 -283.471574) (xy 354.739748 -283.434851)
			(xy 354.709222 -283.392835) (xy 354.685644 -283.346561) (xy 354.669596 -283.297168) (xy 354.661471 -283.245873)
			(xy 354.381307 -283.245873) (xy 354.373182 -283.297168) (xy 354.357134 -283.346561) (xy 354.333556 -283.392835)
			(xy 354.30303 -283.434851) (xy 354.266307 -283.471574) (xy 354.224291 -283.5021) (xy 354.178017 -283.525678)
			(xy 354.128624 -283.541726) (xy 354.077329 -283.549851) (xy 354.025395 -283.549851) (xy 353.9741 -283.541726)
			(xy 353.924707 -283.525678) (xy 353.878433 -283.5021) (xy 353.836417 -283.471574) (xy 353.799694 -283.434851)
			(xy 353.769168 -283.392835) (xy 353.74559 -283.346561) (xy 353.729542 -283.297168) (xy 353.721417 -283.245873)
			(xy 353.441761 -283.245873) (xy 353.433636 -283.297168) (xy 353.417588 -283.346561) (xy 353.39401 -283.392835)
			(xy 353.363484 -283.434851) (xy 353.326761 -283.471574) (xy 353.284745 -283.5021) (xy 353.238471 -283.525678)
			(xy 353.189078 -283.541726) (xy 353.137783 -283.549851) (xy 353.085849 -283.549851) (xy 353.034554 -283.541726)
			(xy 352.985161 -283.525678) (xy 352.938887 -283.5021) (xy 352.896871 -283.471574) (xy 352.860148 -283.434851)
			(xy 352.829622 -283.392835) (xy 352.806044 -283.346561) (xy 352.789996 -283.297168) (xy 352.781871 -283.245873)
			(xy 352.781362 -283.219906) (xy 352.502216 -283.219906) (xy 352.501707 -283.245873) (xy 352.493582 -283.297168)
			(xy 352.477534 -283.346561) (xy 352.453956 -283.392835) (xy 352.42343 -283.434851) (xy 352.386707 -283.471574)
			(xy 352.344691 -283.5021) (xy 352.298417 -283.525678) (xy 352.249024 -283.541726) (xy 352.197729 -283.549851)
			(xy 352.145795 -283.549851) (xy 352.0945 -283.541726) (xy 352.045107 -283.525678) (xy 351.998833 -283.5021)
			(xy 351.956817 -283.471574) (xy 351.920094 -283.434851) (xy 351.889568 -283.392835) (xy 351.86599 -283.346561)
			(xy 351.849942 -283.297168) (xy 351.841817 -283.245873) (xy 351.561907 -283.245873) (xy 351.553782 -283.297168)
			(xy 351.537734 -283.346561) (xy 351.514156 -283.392835) (xy 351.48363 -283.434851) (xy 351.446907 -283.471574)
			(xy 351.404891 -283.5021) (xy 351.358617 -283.525678) (xy 351.309224 -283.541726) (xy 351.257929 -283.549851)
			(xy 351.205995 -283.549851) (xy 351.1547 -283.541726) (xy 351.105307 -283.525678) (xy 351.059033 -283.5021)
			(xy 351.017017 -283.471574) (xy 350.980294 -283.434851) (xy 350.949768 -283.392835) (xy 350.92619 -283.346561)
			(xy 350.910142 -283.297168) (xy 350.902017 -283.245873) (xy 350.62235 -283.245873) (xy 350.614227 -283.297161)
			(xy 350.598179 -283.346553) (xy 350.574602 -283.392827) (xy 350.544077 -283.434843) (xy 350.507355 -283.471567)
			(xy 350.465341 -283.502094) (xy 350.419068 -283.525673) (xy 350.369677 -283.541723) (xy 350.318383 -283.54985)
			(xy 350.292416 -283.55036) (xy 350.26678 -283.549882) (xy 350.216123 -283.541959) (xy 350.1673 -283.526299)
			(xy 350.121485 -283.503281) (xy 350.079779 -283.473457) (xy 350.043184 -283.437544) (xy 350.027494 -283.417264)
			(xy 349.617538 -283.417264) (xy 349.601852 -283.437546) (xy 349.565253 -283.473453) (xy 349.523545 -283.503273)
			(xy 349.477729 -283.526289) (xy 349.428907 -283.541948) (xy 349.378252 -283.549874) (xy 349.352616 -283.55036)
			(xy 349.326646 -283.549866) (xy 349.275346 -283.541744) (xy 349.225948 -283.525695) (xy 349.179669 -283.502117)
			(xy 349.137649 -283.471589) (xy 349.100921 -283.434863) (xy 349.070391 -283.392844) (xy 349.046811 -283.346566)
			(xy 349.03076 -283.297169) (xy 349.022635 -283.24587) (xy 348.742507 -283.24587) (xy 348.742507 -283.245873)
			(xy 348.734382 -283.297168) (xy 348.718334 -283.346561) (xy 348.694756 -283.392835) (xy 348.66423 -283.434851)
			(xy 348.627507 -283.471574) (xy 348.585491 -283.5021) (xy 348.539217 -283.525678) (xy 348.489824 -283.541726)
			(xy 348.438529 -283.549851) (xy 348.386595 -283.549851) (xy 348.3353 -283.541726) (xy 348.285907 -283.525678)
			(xy 348.239633 -283.5021) (xy 348.197617 -283.471574) (xy 348.160894 -283.434851) (xy 348.130368 -283.392835)
			(xy 348.10679 -283.346561) (xy 348.090742 -283.297168) (xy 348.082617 -283.245873) (xy 347.802961 -283.245873)
			(xy 347.794836 -283.297168) (xy 347.778788 -283.346561) (xy 347.75521 -283.392835) (xy 347.724684 -283.434851)
			(xy 347.687961 -283.471574) (xy 347.645945 -283.5021) (xy 347.599671 -283.525678) (xy 347.550278 -283.541726)
			(xy 347.498983 -283.549851) (xy 347.447049 -283.549851) (xy 347.395754 -283.541726) (xy 347.346361 -283.525678)
			(xy 347.300087 -283.5021) (xy 347.258071 -283.471574) (xy 347.221348 -283.434851) (xy 347.190822 -283.392835)
			(xy 347.167244 -283.346561) (xy 347.151196 -283.297168) (xy 347.143071 -283.245873) (xy 347.142562 -283.219906)
			(xy 346.863416 -283.219906) (xy 346.862907 -283.245873) (xy 346.854782 -283.297168) (xy 346.838734 -283.346561)
			(xy 346.815156 -283.392835) (xy 346.78463 -283.434851) (xy 346.747907 -283.471574) (xy 346.705891 -283.5021)
			(xy 346.659617 -283.525678) (xy 346.610224 -283.541726) (xy 346.558929 -283.549851) (xy 346.506995 -283.549851)
			(xy 346.4557 -283.541726) (xy 346.406307 -283.525678) (xy 346.360033 -283.5021) (xy 346.318017 -283.471574)
			(xy 346.281294 -283.434851) (xy 346.250768 -283.392835) (xy 346.22719 -283.346561) (xy 346.211142 -283.297168)
			(xy 346.203017 -283.245873) (xy 345.923107 -283.245873) (xy 345.914982 -283.297168) (xy 345.898934 -283.346561)
			(xy 345.875356 -283.392835) (xy 345.84483 -283.434851) (xy 345.808107 -283.471574) (xy 345.766091 -283.5021)
			(xy 345.719817 -283.525678) (xy 345.670424 -283.541726) (xy 345.619129 -283.549851) (xy 345.567195 -283.549851)
			(xy 345.5159 -283.541726) (xy 345.466507 -283.525678) (xy 345.420233 -283.5021) (xy 345.378217 -283.471574)
			(xy 345.341494 -283.434851) (xy 345.310968 -283.392835) (xy 345.28739 -283.346561) (xy 345.271342 -283.297168)
			(xy 345.263217 -283.245873) (xy 344.983543 -283.245873) (xy 344.975586 -283.296538) (xy 344.959798 -283.345562)
			(xy 344.936596 -283.391543) (xy 344.906542 -283.433368) (xy 344.870363 -283.470025) (xy 344.828935 -283.500624)
			(xy 344.783261 -283.524427) (xy 344.734448 -283.540855) (xy 344.683677 -283.549512) (xy 344.657934 -283.55036)
			(xy 344.644729 -283.550946) (xy 344.619279 -283.558052) (xy 344.596508 -283.571458) (xy 344.577946 -283.590264)
			(xy 344.564839 -283.613207) (xy 344.558066 -283.638748) (xy 344.557604 -283.65196) (xy 344.557604 -284.081728)
			(xy 344.686128 -284.210252) (xy 344.814144 -284.210252) (xy 344.814144 -284.150816) (xy 344.81135 -284.142688)
			(xy 344.802704 -284.11628) (xy 344.793381 -284.061504) (xy 344.792808 -284.033722) (xy 344.793317 -284.007755)
			(xy 344.801442 -283.95646) (xy 344.81749 -283.907067) (xy 344.841068 -283.860793) (xy 344.871594 -283.818777)
			(xy 344.908317 -283.782054) (xy 344.950333 -283.751528) (xy 344.996607 -283.72795) (xy 345.046 -283.711902)
			(xy 345.097295 -283.703777) (xy 345.149229 -283.703777) (xy 345.200524 -283.711902) (xy 345.249917 -283.72795)
			(xy 345.296191 -283.751528) (xy 345.338207 -283.782054) (xy 345.37493 -283.818777) (xy 345.405456 -283.860793)
			(xy 345.429034 -283.907067) (xy 345.445082 -283.95646) (xy 345.453207 -284.007755) (xy 345.453716 -284.033722)
			(xy 345.453551 -284.04815) (xy 345.451004 -284.076893) (xy 345.448636 -284.091126) (xy 345.446572 -284.105793)
			(xy 345.450026 -284.135197) (xy 345.461766 -284.162375) (xy 345.480805 -284.185047) (xy 345.505545 -284.201308)
			(xy 345.533909 -284.209793) (xy 345.548712 -284.210252) (xy 345.637612 -284.210252) (xy 345.652406 -284.209747)
			(xy 345.680752 -284.201261) (xy 345.705475 -284.185006) (xy 345.724501 -284.162346) (xy 345.736232 -284.135182)
			(xy 345.739684 -284.105796) (xy 345.737688 -284.091126) (xy 345.735328 -284.076892) (xy 345.732787 -284.048149)
			(xy 345.732608 -284.033722) (xy 345.733117 -284.007755) (xy 345.741242 -283.95646) (xy 345.75729 -283.907067)
			(xy 345.780868 -283.860793) (xy 345.811394 -283.818777) (xy 345.848117 -283.782054) (xy 345.890133 -283.751528)
			(xy 345.936407 -283.72795) (xy 345.9858 -283.711902) (xy 346.037095 -283.703777) (xy 346.089029 -283.703777)
			(xy 346.140324 -283.711902) (xy 346.189717 -283.72795) (xy 346.235991 -283.751528) (xy 346.278007 -283.782054)
			(xy 346.31473 -283.818777) (xy 346.345256 -283.860793) (xy 346.368834 -283.907067) (xy 346.384882 -283.95646)
			(xy 346.393007 -284.007755) (xy 346.393516 -284.033722) (xy 346.393351 -284.04815) (xy 346.390804 -284.076893)
			(xy 346.388436 -284.091126) (xy 346.386372 -284.105793) (xy 346.389826 -284.135197) (xy 346.401566 -284.162375)
			(xy 346.420605 -284.185047) (xy 346.445345 -284.201308) (xy 346.473709 -284.209793) (xy 346.488512 -284.210252)
			(xy 346.577412 -284.210252) (xy 346.592206 -284.209747) (xy 346.620552 -284.201261) (xy 346.645275 -284.185006)
			(xy 346.664301 -284.162346) (xy 346.676032 -284.135182) (xy 346.679484 -284.105796) (xy 346.677488 -284.091126)
			(xy 346.675128 -284.076892) (xy 346.672587 -284.048149) (xy 346.672408 -284.033722) (xy 346.672917 -284.007755)
			(xy 346.681042 -283.95646) (xy 346.69709 -283.907067) (xy 346.720668 -283.860793) (xy 346.751194 -283.818777)
			(xy 346.787917 -283.782054) (xy 346.829933 -283.751528) (xy 346.876207 -283.72795) (xy 346.9256 -283.711902)
			(xy 346.976895 -283.703777) (xy 347.028829 -283.703777) (xy 347.080124 -283.711902) (xy 347.129517 -283.72795)
			(xy 347.175791 -283.751528) (xy 347.217807 -283.782054) (xy 347.25453 -283.818777) (xy 347.285056 -283.860793)
			(xy 347.308634 -283.907067) (xy 347.324682 -283.95646) (xy 347.332807 -284.007755) (xy 347.333316 -284.033722)
			(xy 347.333151 -284.04815) (xy 347.330604 -284.076893) (xy 347.328236 -284.091126) (xy 347.326172 -284.105793)
			(xy 347.329626 -284.135197) (xy 347.341366 -284.162375) (xy 347.360405 -284.185047) (xy 347.385145 -284.201308)
			(xy 347.413509 -284.209793) (xy 347.428312 -284.210252) (xy 347.517212 -284.210252) (xy 347.532006 -284.209747)
			(xy 347.560352 -284.201261) (xy 347.585075 -284.185006) (xy 347.604101 -284.162346) (xy 347.615832 -284.135182)
			(xy 347.619284 -284.105796) (xy 347.617288 -284.091126) (xy 347.614928 -284.076892) (xy 347.612387 -284.048149)
			(xy 347.612208 -284.033722) (xy 347.612717 -284.007755) (xy 347.620842 -283.95646) (xy 347.63689 -283.907067)
			(xy 347.660468 -283.860793) (xy 347.690994 -283.818777) (xy 347.727717 -283.782054) (xy 347.769733 -283.751528)
			(xy 347.816007 -283.72795) (xy 347.8654 -283.711902) (xy 347.916695 -283.703777) (xy 347.968629 -283.703777)
			(xy 348.019924 -283.711902) (xy 348.069317 -283.72795) (xy 348.115591 -283.751528) (xy 348.157607 -283.782054)
			(xy 348.19433 -283.818777) (xy 348.224856 -283.860793) (xy 348.248434 -283.907067) (xy 348.264482 -283.95646)
			(xy 348.272607 -284.007755) (xy 348.273116 -284.033722) (xy 348.272951 -284.04815) (xy 348.270404 -284.076893)
			(xy 348.268036 -284.091126) (xy 348.265972 -284.105793) (xy 348.269426 -284.135197) (xy 348.281166 -284.162375)
			(xy 348.300205 -284.185047) (xy 348.324945 -284.201308) (xy 348.353309 -284.209793) (xy 348.368112 -284.210252)
			(xy 348.457012 -284.210252) (xy 348.471806 -284.209747) (xy 348.500152 -284.201261) (xy 348.524875 -284.185006)
			(xy 348.543901 -284.162346) (xy 348.555632 -284.135182) (xy 348.559084 -284.105796) (xy 348.557088 -284.091126)
			(xy 348.554728 -284.076892) (xy 348.552187 -284.048149) (xy 348.552008 -284.033722) (xy 348.552517 -284.007755)
			(xy 348.560642 -283.95646) (xy 348.57669 -283.907067) (xy 348.600268 -283.860793) (xy 348.630794 -283.818777)
			(xy 348.667517 -283.782054) (xy 348.709533 -283.751528) (xy 348.755807 -283.72795) (xy 348.8052 -283.711902)
			(xy 348.856495 -283.703777) (xy 348.908429 -283.703777) (xy 348.959724 -283.711902) (xy 349.009117 -283.72795)
			(xy 349.055391 -283.751528) (xy 349.097407 -283.782054) (xy 349.13413 -283.818777) (xy 349.164656 -283.860793)
			(xy 349.188234 -283.907067) (xy 349.204282 -283.95646) (xy 349.212407 -284.007755) (xy 349.212916 -284.033722)
			(xy 349.212751 -284.04815) (xy 349.210204 -284.076893) (xy 349.207836 -284.091126) (xy 349.205772 -284.105793)
			(xy 349.209226 -284.135197) (xy 349.220966 -284.162375) (xy 349.240005 -284.185047) (xy 349.264745 -284.201308)
			(xy 349.293109 -284.209793) (xy 349.307912 -284.210252) (xy 349.396812 -284.210252) (xy 349.411606 -284.209747)
			(xy 349.439952 -284.201261) (xy 349.464675 -284.185006) (xy 349.483701 -284.162346) (xy 349.495432 -284.135182)
			(xy 349.498884 -284.105796) (xy 349.496888 -284.091126) (xy 349.494528 -284.076892) (xy 349.491987 -284.048149)
			(xy 349.491808 -284.033722) (xy 349.492317 -284.007755) (xy 349.500442 -283.95646) (xy 349.51649 -283.907067)
			(xy 349.540068 -283.860793) (xy 349.570594 -283.818777) (xy 349.607317 -283.782054) (xy 349.649333 -283.751528)
			(xy 349.695607 -283.72795) (xy 349.745 -283.711902) (xy 349.796295 -283.703777) (xy 349.848229 -283.703777)
			(xy 349.899524 -283.711902) (xy 349.948917 -283.72795) (xy 349.995191 -283.751528) (xy 350.037207 -283.782054)
			(xy 350.07393 -283.818777) (xy 350.104456 -283.860793) (xy 350.128034 -283.907067) (xy 350.144082 -283.95646)
			(xy 350.152207 -284.007755) (xy 350.152716 -284.033722) (xy 350.152551 -284.04815) (xy 350.150004 -284.076893)
			(xy 350.147636 -284.091126) (xy 350.145572 -284.105793) (xy 350.149026 -284.135197) (xy 350.160766 -284.162375)
			(xy 350.179805 -284.185047) (xy 350.204545 -284.201308) (xy 350.232909 -284.209793) (xy 350.247712 -284.210252)
			(xy 350.336612 -284.210252) (xy 350.351406 -284.209747) (xy 350.379752 -284.201261) (xy 350.404475 -284.185006)
			(xy 350.423501 -284.162346) (xy 350.435232 -284.135182) (xy 350.438684 -284.105796) (xy 350.436688 -284.091126)
			(xy 350.434328 -284.076892) (xy 350.431787 -284.048149) (xy 350.431608 -284.033722) (xy 350.432117 -284.007755)
			(xy 350.440242 -283.95646) (xy 350.45629 -283.907067) (xy 350.479868 -283.860793) (xy 350.510394 -283.818777)
			(xy 350.547117 -283.782054) (xy 350.589133 -283.751528) (xy 350.635407 -283.72795) (xy 350.6848 -283.711902)
			(xy 350.736095 -283.703777) (xy 350.788029 -283.703777) (xy 350.839324 -283.711902) (xy 350.888717 -283.72795)
			(xy 350.934991 -283.751528) (xy 350.977007 -283.782054) (xy 351.01373 -283.818777) (xy 351.044256 -283.860793)
			(xy 351.067834 -283.907067) (xy 351.083882 -283.95646) (xy 351.092007 -284.007755) (xy 351.092516 -284.033722)
			(xy 351.092351 -284.04815) (xy 351.089804 -284.076893) (xy 351.087436 -284.091126) (xy 351.085372 -284.105793)
			(xy 351.088826 -284.135197) (xy 351.100566 -284.162375) (xy 351.119605 -284.185047) (xy 351.144345 -284.201308)
			(xy 351.172709 -284.209793) (xy 351.187512 -284.210252) (xy 351.276412 -284.210252) (xy 351.291206 -284.209747)
			(xy 351.319552 -284.201261) (xy 351.344275 -284.185006) (xy 351.363301 -284.162346) (xy 351.375032 -284.135182)
			(xy 351.378484 -284.105796) (xy 351.376488 -284.091126) (xy 351.374128 -284.076892) (xy 351.371587 -284.048149)
			(xy 351.371408 -284.033722) (xy 351.371917 -284.007755) (xy 351.380042 -283.95646) (xy 351.39609 -283.907067)
			(xy 351.419668 -283.860793) (xy 351.450194 -283.818777) (xy 351.486917 -283.782054) (xy 351.528933 -283.751528)
			(xy 351.575207 -283.72795) (xy 351.6246 -283.711902) (xy 351.675895 -283.703777) (xy 351.727829 -283.703777)
			(xy 351.779124 -283.711902) (xy 351.828517 -283.72795) (xy 351.874791 -283.751528) (xy 351.916807 -283.782054)
			(xy 351.95353 -283.818777) (xy 351.984056 -283.860793) (xy 352.007634 -283.907067) (xy 352.023682 -283.95646)
			(xy 352.031807 -284.007755) (xy 352.032316 -284.033722) (xy 352.031841 -284.058337) (xy 352.031637 -284.059689)
			(xy 352.311717 -284.059689) (xy 352.311717 -284.007755) (xy 352.319842 -283.95646) (xy 352.33589 -283.907067)
			(xy 352.359468 -283.860793) (xy 352.389994 -283.818777) (xy 352.426717 -283.782054) (xy 352.468733 -283.751528)
			(xy 352.515007 -283.72795) (xy 352.5644 -283.711902) (xy 352.615695 -283.703777) (xy 352.667629 -283.703777)
			(xy 352.718924 -283.711902) (xy 352.768317 -283.72795) (xy 352.814591 -283.751528) (xy 352.856607 -283.782054)
			(xy 352.89333 -283.818777) (xy 352.923856 -283.860793) (xy 352.947434 -283.907067) (xy 352.963482 -283.95646)
			(xy 352.971607 -284.007755) (xy 352.972116 -284.033722) (xy 352.971607 -284.059689) (xy 353.251517 -284.059689)
			(xy 353.251517 -284.007755) (xy 353.259642 -283.95646) (xy 353.27569 -283.907067) (xy 353.299268 -283.860793)
			(xy 353.329794 -283.818777) (xy 353.366517 -283.782054) (xy 353.408533 -283.751528) (xy 353.454807 -283.72795)
			(xy 353.5042 -283.711902) (xy 353.555495 -283.703777) (xy 353.607429 -283.703777) (xy 353.658724 -283.711902)
			(xy 353.708117 -283.72795) (xy 353.754391 -283.751528) (xy 353.796407 -283.782054) (xy 353.83313 -283.818777)
			(xy 353.863656 -283.860793) (xy 353.887234 -283.907067) (xy 353.903282 -283.95646) (xy 353.911407 -284.007755)
			(xy 353.911916 -284.033722) (xy 353.911407 -284.059689) (xy 355.131117 -284.059689) (xy 355.131117 -284.007755)
			(xy 355.139242 -283.95646) (xy 355.15529 -283.907067) (xy 355.178868 -283.860793) (xy 355.209394 -283.818777)
			(xy 355.246117 -283.782054) (xy 355.288133 -283.751528) (xy 355.334407 -283.72795) (xy 355.3838 -283.711902)
			(xy 355.435095 -283.703777) (xy 355.487029 -283.703777) (xy 355.538324 -283.711902) (xy 355.587717 -283.72795)
			(xy 355.633991 -283.751528) (xy 355.676007 -283.782054) (xy 355.71273 -283.818777) (xy 355.743256 -283.860793)
			(xy 355.766834 -283.907067) (xy 355.782882 -283.95646) (xy 355.791007 -284.007755) (xy 355.791516 -284.033722)
			(xy 355.791007 -284.059689) (xy 357.950517 -284.059689) (xy 357.950517 -284.007755) (xy 357.958642 -283.95646)
			(xy 357.97469 -283.907067) (xy 357.998268 -283.860793) (xy 358.028794 -283.818777) (xy 358.065517 -283.782054)
			(xy 358.107533 -283.751528) (xy 358.153807 -283.72795) (xy 358.2032 -283.711902) (xy 358.254495 -283.703777)
			(xy 358.306429 -283.703777) (xy 358.357724 -283.711902) (xy 358.407117 -283.72795) (xy 358.453391 -283.751528)
			(xy 358.495407 -283.782054) (xy 358.53213 -283.818777) (xy 358.562656 -283.860793) (xy 358.586234 -283.907067)
			(xy 358.602282 -283.95646) (xy 358.610407 -284.007755) (xy 358.610916 -284.033722) (xy 358.610407 -284.059689)
			(xy 366.408717 -284.059689) (xy 366.408717 -284.007755) (xy 366.416842 -283.95646) (xy 366.43289 -283.907067)
			(xy 366.456468 -283.860793) (xy 366.486994 -283.818777) (xy 366.523717 -283.782054) (xy 366.565733 -283.751528)
			(xy 366.612007 -283.72795) (xy 366.6614 -283.711902) (xy 366.712695 -283.703777) (xy 366.764629 -283.703777)
			(xy 366.815924 -283.711902) (xy 366.865317 -283.72795) (xy 366.911591 -283.751528) (xy 366.953607 -283.782054)
			(xy 366.99033 -283.818777) (xy 367.020856 -283.860793) (xy 367.044434 -283.907067) (xy 367.060482 -283.95646)
			(xy 367.068607 -284.007755) (xy 367.069116 -284.033722) (xy 367.068607 -284.059689) (xy 367.060482 -284.110984)
			(xy 367.044434 -284.160377) (xy 367.020856 -284.206651) (xy 366.99033 -284.248667) (xy 366.953607 -284.28539)
			(xy 366.911591 -284.315916) (xy 366.865317 -284.339494) (xy 366.815924 -284.355542) (xy 366.764629 -284.363667)
			(xy 366.712695 -284.363667) (xy 366.6614 -284.355542) (xy 366.612007 -284.339494) (xy 366.565733 -284.315916)
			(xy 366.523717 -284.28539) (xy 366.486994 -284.248667) (xy 366.456468 -284.206651) (xy 366.43289 -284.160377)
			(xy 366.416842 -284.110984) (xy 366.408717 -284.059689) (xy 358.610407 -284.059689) (xy 358.602282 -284.110984)
			(xy 358.586234 -284.160377) (xy 358.562656 -284.206651) (xy 358.53213 -284.248667) (xy 358.495407 -284.28539)
			(xy 358.453391 -284.315916) (xy 358.407117 -284.339494) (xy 358.357724 -284.355542) (xy 358.306429 -284.363667)
			(xy 358.254495 -284.363667) (xy 358.2032 -284.355542) (xy 358.153807 -284.339494) (xy 358.107533 -284.315916)
			(xy 358.065517 -284.28539) (xy 358.028794 -284.248667) (xy 357.998268 -284.206651) (xy 357.97469 -284.160377)
			(xy 357.958642 -284.110984) (xy 357.950517 -284.059689) (xy 355.791007 -284.059689) (xy 355.782882 -284.110984)
			(xy 355.766834 -284.160377) (xy 355.743256 -284.206651) (xy 355.71273 -284.248667) (xy 355.676007 -284.28539)
			(xy 355.633991 -284.315916) (xy 355.587717 -284.339494) (xy 355.538324 -284.355542) (xy 355.487029 -284.363667)
			(xy 355.435095 -284.363667) (xy 355.3838 -284.355542) (xy 355.334407 -284.339494) (xy 355.288133 -284.315916)
			(xy 355.246117 -284.28539) (xy 355.209394 -284.248667) (xy 355.178868 -284.206651) (xy 355.15529 -284.160377)
			(xy 355.139242 -284.110984) (xy 355.131117 -284.059689) (xy 353.911407 -284.059689) (xy 353.903282 -284.110984)
			(xy 353.887234 -284.160377) (xy 353.863656 -284.206651) (xy 353.83313 -284.248667) (xy 353.796407 -284.28539)
			(xy 353.754391 -284.315916) (xy 353.708117 -284.339494) (xy 353.658724 -284.355542) (xy 353.607429 -284.363667)
			(xy 353.555495 -284.363667) (xy 353.5042 -284.355542) (xy 353.454807 -284.339494) (xy 353.408533 -284.315916)
			(xy 353.366517 -284.28539) (xy 353.329794 -284.248667) (xy 353.299268 -284.206651) (xy 353.27569 -284.160377)
			(xy 353.259642 -284.110984) (xy 353.251517 -284.059689) (xy 352.971607 -284.059689) (xy 352.963482 -284.110984)
			(xy 352.947434 -284.160377) (xy 352.923856 -284.206651) (xy 352.89333 -284.248667) (xy 352.856607 -284.28539)
			(xy 352.814591 -284.315916) (xy 352.768317 -284.339494) (xy 352.718924 -284.355542) (xy 352.667629 -284.363667)
			(xy 352.615695 -284.363667) (xy 352.5644 -284.355542) (xy 352.515007 -284.339494) (xy 352.468733 -284.315916)
			(xy 352.426717 -284.28539) (xy 352.389994 -284.248667) (xy 352.359468 -284.206651) (xy 352.33589 -284.160377)
			(xy 352.319842 -284.110984) (xy 352.311717 -284.059689) (xy 352.031637 -284.059689) (xy 352.024502 -284.107019)
			(xy 352.010034 -284.154076) (xy 351.999804 -284.17647) (xy 351.98431 -284.208728) (xy 352.336354 -284.560772)
			(xy 352.341688 -284.564074) (xy 352.364666 -284.578468) (xy 352.406012 -284.613541) (xy 352.441075 -284.654894)
			(xy 352.45548 -284.677866) (xy 352.458782 -284.6832) (xy 352.615246 -284.839664) (xy 352.625331 -284.849061)
			(xy 352.649347 -284.862569) (xy 352.676102 -284.869158) (xy 352.703644 -284.868348) (xy 352.729966 -284.860197)
			(xy 352.753146 -284.8453) (xy 352.771495 -284.824744) (xy 352.783674 -284.800028) (xy 352.786696 -284.786578)
			(xy 352.791844 -284.761646) (xy 352.808781 -284.71364) (xy 352.832883 -284.6688) (xy 352.863578 -284.628188)
			(xy 352.900139 -284.592765) (xy 352.941702 -284.563371) (xy 352.987282 -284.5407) (xy 353.0358 -284.52529)
			(xy 353.086108 -284.517506) (xy 353.111562 -284.517084) (xy 353.13753 -284.517564) (xy 353.188828 -284.525683)
			(xy 353.238224 -284.541728) (xy 353.284502 -284.565303) (xy 353.326521 -284.595827) (xy 353.363248 -284.63255)
			(xy 353.393777 -284.674566) (xy 353.417358 -284.720841) (xy 353.433408 -284.770235) (xy 353.441533 -284.821532)
			(xy 353.441533 -284.873468) (xy 353.441527 -284.873505) (xy 361.239817 -284.873505) (xy 361.239817 -284.821571)
			(xy 361.247942 -284.770276) (xy 361.26399 -284.720883) (xy 361.287568 -284.674609) (xy 361.318094 -284.632593)
			(xy 361.354817 -284.59587) (xy 361.396833 -284.565344) (xy 361.443107 -284.541766) (xy 361.4925 -284.525718)
			(xy 361.543795 -284.517593) (xy 361.595729 -284.517593) (xy 361.647024 -284.525718) (xy 361.696417 -284.541766)
			(xy 361.742691 -284.565344) (xy 361.784707 -284.59587) (xy 361.82143 -284.632593) (xy 361.851956 -284.674609)
			(xy 361.875534 -284.720883) (xy 361.891582 -284.770276) (xy 361.899707 -284.821571) (xy 361.900216 -284.847538)
			(xy 361.899707 -284.873505) (xy 364.059471 -284.873505) (xy 364.059471 -284.821571) (xy 364.067596 -284.770276)
			(xy 364.083644 -284.720883) (xy 364.107222 -284.674609) (xy 364.137748 -284.632593) (xy 364.174471 -284.59587)
			(xy 364.216487 -284.565344) (xy 364.262761 -284.541766) (xy 364.312154 -284.525718) (xy 364.363449 -284.517593)
			(xy 364.415383 -284.517593) (xy 364.466678 -284.525718) (xy 364.516071 -284.541766) (xy 364.562345 -284.565344)
			(xy 364.604361 -284.59587) (xy 364.641084 -284.632593) (xy 364.67161 -284.674609) (xy 364.695188 -284.720883)
			(xy 364.711236 -284.770276) (xy 364.719361 -284.821571) (xy 364.71987 -284.847538) (xy 364.719361 -284.873505)
			(xy 365.939071 -284.873505) (xy 365.939071 -284.821571) (xy 365.947196 -284.770276) (xy 365.963244 -284.720883)
			(xy 365.986822 -284.674609) (xy 366.017348 -284.632593) (xy 366.054071 -284.59587) (xy 366.096087 -284.565344)
			(xy 366.142361 -284.541766) (xy 366.191754 -284.525718) (xy 366.243049 -284.517593) (xy 366.294983 -284.517593)
			(xy 366.346278 -284.525718) (xy 366.395671 -284.541766) (xy 366.441945 -284.565344) (xy 366.483961 -284.59587)
			(xy 366.520684 -284.632593) (xy 366.55121 -284.674609) (xy 366.574788 -284.720883) (xy 366.590836 -284.770276)
			(xy 366.598961 -284.821571) (xy 366.59947 -284.847538) (xy 366.598961 -284.873505) (xy 366.590836 -284.9248)
			(xy 366.574788 -284.974193) (xy 366.55121 -285.020467) (xy 366.520684 -285.062483) (xy 366.483961 -285.099206)
			(xy 366.441945 -285.129732) (xy 366.395671 -285.15331) (xy 366.346278 -285.169358) (xy 366.294983 -285.177483)
			(xy 366.243049 -285.177483) (xy 366.191754 -285.169358) (xy 366.142361 -285.15331) (xy 366.096087 -285.129732)
			(xy 366.054071 -285.099206) (xy 366.017348 -285.062483) (xy 365.986822 -285.020467) (xy 365.963244 -284.974193)
			(xy 365.947196 -284.9248) (xy 365.939071 -284.873505) (xy 364.719361 -284.873505) (xy 364.711236 -284.9248)
			(xy 364.695188 -284.974193) (xy 364.67161 -285.020467) (xy 364.641084 -285.062483) (xy 364.604361 -285.099206)
			(xy 364.562345 -285.129732) (xy 364.516071 -285.15331) (xy 364.466678 -285.169358) (xy 364.415383 -285.177483)
			(xy 364.363449 -285.177483) (xy 364.312154 -285.169358) (xy 364.262761 -285.15331) (xy 364.216487 -285.129732)
			(xy 364.174471 -285.099206) (xy 364.137748 -285.062483) (xy 364.107222 -285.020467) (xy 364.083644 -284.974193)
			(xy 364.067596 -284.9248) (xy 364.059471 -284.873505) (xy 361.899707 -284.873505) (xy 361.891582 -284.9248)
			(xy 361.875534 -284.974193) (xy 361.851956 -285.020467) (xy 361.82143 -285.062483) (xy 361.784707 -285.099206)
			(xy 361.742691 -285.129732) (xy 361.696417 -285.15331) (xy 361.647024 -285.169358) (xy 361.595729 -285.177483)
			(xy 361.543795 -285.177483) (xy 361.4925 -285.169358) (xy 361.443107 -285.15331) (xy 361.396833 -285.129732)
			(xy 361.354817 -285.099206) (xy 361.318094 -285.062483) (xy 361.287568 -285.020467) (xy 361.26399 -284.974193)
			(xy 361.247942 -284.9248) (xy 361.239817 -284.873505) (xy 353.441527 -284.873505) (xy 353.433408 -284.924765)
			(xy 353.417358 -284.974159) (xy 353.393777 -285.020434) (xy 353.363248 -285.06245) (xy 353.326521 -285.099173)
			(xy 353.284502 -285.129697) (xy 353.238224 -285.153272) (xy 353.188828 -285.169317) (xy 353.13753 -285.177436)
			(xy 353.111562 -285.177992) (xy 353.082753 -285.177339) (xy 353.026016 -285.167299) (xy 352.971876 -285.147581)
			(xy 352.921971 -285.118782) (xy 352.899472 -285.100776) (xy 352.888081 -285.09189) (xy 352.86164 -285.080282)
			(xy 352.833008 -285.076535) (xy 352.804471 -285.080949) (xy 352.778309 -285.093171) (xy 352.756611 -285.112225)
			(xy 352.74111 -285.136588) (xy 352.733046 -285.164316) (xy 352.732594 -285.178754) (xy 352.732594 -285.341822)
			(xy 352.764598 -285.354522) (xy 352.78875 -285.364759) (xy 352.833732 -285.391741) (xy 352.873891 -285.425485)
			(xy 352.908219 -285.465146) (xy 352.935855 -285.509729) (xy 352.956107 -285.558116) (xy 352.968466 -285.609094)
			(xy 352.972622 -285.661383) (xy 352.970563 -285.687321) (xy 355.131117 -285.687321) (xy 355.131117 -285.635387)
			(xy 355.139242 -285.584092) (xy 355.15529 -285.534699) (xy 355.178868 -285.488425) (xy 355.209394 -285.446409)
			(xy 355.246117 -285.409686) (xy 355.288133 -285.37916) (xy 355.334407 -285.355582) (xy 355.3838 -285.339534)
			(xy 355.435095 -285.331409) (xy 355.487029 -285.331409) (xy 355.538324 -285.339534) (xy 355.587717 -285.355582)
			(xy 355.633991 -285.37916) (xy 355.676007 -285.409686) (xy 355.71273 -285.446409) (xy 355.743256 -285.488425)
			(xy 355.766834 -285.534699) (xy 355.782882 -285.584092) (xy 355.791007 -285.635387) (xy 355.791516 -285.661354)
			(xy 355.791007 -285.687321) (xy 357.950517 -285.687321) (xy 357.950517 -285.635387) (xy 357.958642 -285.584092)
			(xy 357.97469 -285.534699) (xy 357.998268 -285.488425) (xy 358.028794 -285.446409) (xy 358.065517 -285.409686)
			(xy 358.107533 -285.37916) (xy 358.153807 -285.355582) (xy 358.2032 -285.339534) (xy 358.254495 -285.331409)
			(xy 358.306429 -285.331409) (xy 358.357724 -285.339534) (xy 358.407117 -285.355582) (xy 358.453391 -285.37916)
			(xy 358.495407 -285.409686) (xy 358.53213 -285.446409) (xy 358.562656 -285.488425) (xy 358.586234 -285.534699)
			(xy 358.602282 -285.584092) (xy 358.610407 -285.635387) (xy 358.610916 -285.661354) (xy 358.610407 -285.687321)
			(xy 366.408971 -285.687321) (xy 366.408971 -285.635387) (xy 366.417096 -285.584092) (xy 366.433144 -285.534699)
			(xy 366.456722 -285.488425) (xy 366.487248 -285.446409) (xy 366.523971 -285.409686) (xy 366.565987 -285.37916)
			(xy 366.612261 -285.355582) (xy 366.661654 -285.339534) (xy 366.712949 -285.331409) (xy 366.764883 -285.331409)
			(xy 366.816178 -285.339534) (xy 366.865571 -285.355582) (xy 366.911845 -285.37916) (xy 366.953861 -285.409686)
			(xy 366.990584 -285.446409) (xy 367.02111 -285.488425) (xy 367.044688 -285.534699) (xy 367.060736 -285.584092)
			(xy 367.068861 -285.635387) (xy 367.06937 -285.661354) (xy 367.068861 -285.687321) (xy 367.060736 -285.738616)
			(xy 367.044688 -285.788009) (xy 367.02111 -285.834283) (xy 366.990584 -285.876299) (xy 366.953861 -285.913022)
			(xy 366.911845 -285.943548) (xy 366.865571 -285.967126) (xy 366.816178 -285.983174) (xy 366.764883 -285.991299)
			(xy 366.712949 -285.991299) (xy 366.661654 -285.983174) (xy 366.612261 -285.967126) (xy 366.565987 -285.943548)
			(xy 366.523971 -285.913022) (xy 366.487248 -285.876299) (xy 366.456722 -285.834283) (xy 366.433144 -285.788009)
			(xy 366.417096 -285.738616) (xy 366.408971 -285.687321) (xy 358.610407 -285.687321) (xy 358.602282 -285.738616)
			(xy 358.586234 -285.788009) (xy 358.562656 -285.834283) (xy 358.53213 -285.876299) (xy 358.495407 -285.913022)
			(xy 358.453391 -285.943548) (xy 358.407117 -285.967126) (xy 358.357724 -285.983174) (xy 358.306429 -285.991299)
			(xy 358.254495 -285.991299) (xy 358.2032 -285.983174) (xy 358.153807 -285.967126) (xy 358.107533 -285.943548)
			(xy 358.065517 -285.913022) (xy 358.028794 -285.876299) (xy 357.998268 -285.834283) (xy 357.97469 -285.788009)
			(xy 357.958642 -285.738616) (xy 357.950517 -285.687321) (xy 355.791007 -285.687321) (xy 355.782882 -285.738616)
			(xy 355.766834 -285.788009) (xy 355.743256 -285.834283) (xy 355.71273 -285.876299) (xy 355.676007 -285.913022)
			(xy 355.633991 -285.943548) (xy 355.587717 -285.967126) (xy 355.538324 -285.983174) (xy 355.487029 -285.991299)
			(xy 355.435095 -285.991299) (xy 355.3838 -285.983174) (xy 355.334407 -285.967126) (xy 355.288133 -285.943548)
			(xy 355.246117 -285.913022) (xy 355.209394 -285.876299) (xy 355.178868 -285.834283) (xy 355.15529 -285.788009)
			(xy 355.139242 -285.738616) (xy 355.131117 -285.687321) (xy 352.970563 -285.687321) (xy 352.968471 -285.713672)
			(xy 352.956118 -285.764651) (xy 352.935871 -285.81304) (xy 352.908239 -285.857626) (xy 352.873916 -285.897291)
			(xy 352.83376 -285.93104) (xy 352.788781 -285.958026) (xy 352.764598 -285.968186) (xy 352.732594 -285.980886)
			(xy 352.732594 -286.144462) (xy 352.733092 -286.158893) (xy 352.741165 -286.186604) (xy 352.756674 -286.210945)
			(xy 352.778379 -286.229969) (xy 352.804544 -286.242153) (xy 352.833073 -286.246523) (xy 352.861685 -286.242728)
			(xy 352.888089 -286.231073) (xy 352.899472 -286.222186) (xy 352.921954 -286.204101) (xy 352.971926 -286.175264)
			(xy 353.026147 -286.155546) (xy 353.082968 -286.145545) (xy 353.111816 -286.14497) (xy 353.137781 -286.14548)
			(xy 353.18907 -286.153606) (xy 353.238457 -286.169655) (xy 353.284725 -286.193232) (xy 353.326736 -286.223756)
			(xy 353.363454 -286.260476) (xy 353.393977 -286.302489) (xy 353.417551 -286.348758) (xy 353.433598 -286.398146)
			(xy 353.441721 -286.449435) (xy 353.441721 -286.501365) (xy 353.441717 -286.501391) (xy 361.239817 -286.501391)
			(xy 361.239817 -286.449457) (xy 361.247942 -286.398162) (xy 361.26399 -286.348769) (xy 361.287568 -286.302495)
			(xy 361.318094 -286.260479) (xy 361.354817 -286.223756) (xy 361.396833 -286.19323) (xy 361.443107 -286.169652)
			(xy 361.4925 -286.153604) (xy 361.543795 -286.145479) (xy 361.595729 -286.145479) (xy 361.647024 -286.153604)
			(xy 361.696417 -286.169652) (xy 361.742691 -286.19323) (xy 361.784707 -286.223756) (xy 361.82143 -286.260479)
			(xy 361.851956 -286.302495) (xy 361.875534 -286.348769) (xy 361.891582 -286.398162) (xy 361.899707 -286.449457)
			(xy 361.900216 -286.475424) (xy 361.899707 -286.501391) (xy 364.059471 -286.501391) (xy 364.059471 -286.449457)
			(xy 364.067596 -286.398162) (xy 364.083644 -286.348769) (xy 364.107222 -286.302495) (xy 364.137748 -286.260479)
			(xy 364.174471 -286.223756) (xy 364.216487 -286.19323) (xy 364.262761 -286.169652) (xy 364.312154 -286.153604)
			(xy 364.363449 -286.145479) (xy 364.415383 -286.145479) (xy 364.466678 -286.153604) (xy 364.516071 -286.169652)
			(xy 364.562345 -286.19323) (xy 364.604361 -286.223756) (xy 364.641084 -286.260479) (xy 364.67161 -286.302495)
			(xy 364.695188 -286.348769) (xy 364.711236 -286.398162) (xy 364.719361 -286.449457) (xy 364.71987 -286.475424)
			(xy 364.719361 -286.501391) (xy 364.711236 -286.552686) (xy 364.695188 -286.602079) (xy 364.67161 -286.648353)
			(xy 364.641084 -286.690369) (xy 364.604361 -286.727092) (xy 364.562345 -286.757618) (xy 364.516071 -286.781196)
			(xy 364.466678 -286.797244) (xy 364.415383 -286.805369) (xy 364.363449 -286.805369) (xy 364.312154 -286.797244)
			(xy 364.262761 -286.781196) (xy 364.216487 -286.757618) (xy 364.174471 -286.727092) (xy 364.137748 -286.690369)
			(xy 364.107222 -286.648353) (xy 364.083644 -286.602079) (xy 364.067596 -286.552686) (xy 364.059471 -286.501391)
			(xy 361.899707 -286.501391) (xy 361.891582 -286.552686) (xy 361.875534 -286.602079) (xy 361.851956 -286.648353)
			(xy 361.82143 -286.690369) (xy 361.784707 -286.727092) (xy 361.742691 -286.757618) (xy 361.696417 -286.781196)
			(xy 361.647024 -286.797244) (xy 361.595729 -286.805369) (xy 361.543795 -286.805369) (xy 361.4925 -286.797244)
			(xy 361.443107 -286.781196) (xy 361.396833 -286.757618) (xy 361.354817 -286.727092) (xy 361.318094 -286.690369)
			(xy 361.287568 -286.648353) (xy 361.26399 -286.602079) (xy 361.247942 -286.552686) (xy 361.239817 -286.501391)
			(xy 353.441717 -286.501391) (xy 353.433598 -286.552654) (xy 353.417551 -286.602042) (xy 353.393977 -286.648311)
			(xy 353.363454 -286.690324) (xy 353.326736 -286.727044) (xy 353.284725 -286.757568) (xy 353.238457 -286.781145)
			(xy 353.18907 -286.797194) (xy 353.137781 -286.80532) (xy 353.111816 -286.805878) (xy 353.082975 -286.805244)
			(xy 353.02617 -286.795226) (xy 352.971963 -286.775506) (xy 352.921999 -286.746684) (xy 352.899472 -286.728662)
			(xy 352.888099 -286.719779) (xy 352.861697 -286.708166) (xy 352.8331 -286.7044) (xy 352.804591 -286.708781)
			(xy 352.778445 -286.720961) (xy 352.756748 -286.739966) (xy 352.741231 -286.764281) (xy 352.733134 -286.791965)
			(xy 352.732594 -286.806386) (xy 352.732594 -286.969708) (xy 352.764598 -286.982408) (xy 352.787272 -286.99196)
			(xy 352.829742 -287.016794) (xy 352.868062 -287.04765) (xy 352.901384 -287.083845) (xy 352.928974 -287.124579)
			(xy 352.950219 -287.168954) (xy 352.964653 -287.215987) (xy 352.971955 -287.264641) (xy 352.97237 -287.28924)
			(xy 352.972116 -287.30321) (xy 352.971571 -287.315207) (xy 355.131117 -287.315207) (xy 355.131117 -287.263273)
			(xy 355.139242 -287.211978) (xy 355.15529 -287.162585) (xy 355.178868 -287.116311) (xy 355.209394 -287.074295)
			(xy 355.246117 -287.037572) (xy 355.288133 -287.007046) (xy 355.334407 -286.983468) (xy 355.3838 -286.96742)
			(xy 355.435095 -286.959295) (xy 355.487029 -286.959295) (xy 355.538324 -286.96742) (xy 355.587717 -286.983468)
			(xy 355.633991 -287.007046) (xy 355.676007 -287.037572) (xy 355.71273 -287.074295) (xy 355.743256 -287.116311)
			(xy 355.766834 -287.162585) (xy 355.782882 -287.211978) (xy 355.791007 -287.263273) (xy 355.791516 -287.28924)
			(xy 355.791007 -287.315207) (xy 357.950517 -287.315207) (xy 357.950517 -287.263273) (xy 357.958642 -287.211978)
			(xy 357.97469 -287.162585) (xy 357.998268 -287.116311) (xy 358.028794 -287.074295) (xy 358.065517 -287.037572)
			(xy 358.107533 -287.007046) (xy 358.153807 -286.983468) (xy 358.2032 -286.96742) (xy 358.254495 -286.959295)
			(xy 358.306429 -286.959295) (xy 358.357724 -286.96742) (xy 358.407117 -286.983468) (xy 358.453391 -287.007046)
			(xy 358.495407 -287.037572) (xy 358.53213 -287.074295) (xy 358.562656 -287.116311) (xy 358.586234 -287.162585)
			(xy 358.602282 -287.211978) (xy 358.610407 -287.263273) (xy 358.610916 -287.28924) (xy 358.610407 -287.315207)
			(xy 358.602282 -287.366502) (xy 358.586234 -287.415895) (xy 358.562656 -287.462169) (xy 358.53213 -287.504185)
			(xy 358.495407 -287.540908) (xy 358.453391 -287.571434) (xy 358.407117 -287.595012) (xy 358.357724 -287.61106)
			(xy 358.306429 -287.619185) (xy 358.254495 -287.619185) (xy 358.2032 -287.61106) (xy 358.153807 -287.595012)
			(xy 358.107533 -287.571434) (xy 358.065517 -287.540908) (xy 358.028794 -287.504185) (xy 357.998268 -287.462169)
			(xy 357.97469 -287.415895) (xy 357.958642 -287.366502) (xy 357.950517 -287.315207) (xy 355.791007 -287.315207)
			(xy 355.782882 -287.366502) (xy 355.766834 -287.415895) (xy 355.743256 -287.462169) (xy 355.71273 -287.504185)
			(xy 355.676007 -287.540908) (xy 355.633991 -287.571434) (xy 355.587717 -287.595012) (xy 355.538324 -287.61106)
			(xy 355.487029 -287.619185) (xy 355.435095 -287.619185) (xy 355.3838 -287.61106) (xy 355.334407 -287.595012)
			(xy 355.288133 -287.571434) (xy 355.246117 -287.540908) (xy 355.209394 -287.504185) (xy 355.178868 -287.462169)
			(xy 355.15529 -287.415895) (xy 355.139242 -287.366502) (xy 355.131117 -287.315207) (xy 352.971571 -287.315207)
			(xy 352.9711 -287.325562) (xy 353.770692 -288.125154) (xy 353.770692 -288.129023) (xy 361.239817 -288.129023)
			(xy 361.239817 -288.077089) (xy 361.247942 -288.025794) (xy 361.26399 -287.976401) (xy 361.287568 -287.930127)
			(xy 361.318094 -287.888111) (xy 361.354817 -287.851388) (xy 361.396833 -287.820862) (xy 361.443107 -287.797284)
			(xy 361.4925 -287.781236) (xy 361.543795 -287.773111) (xy 361.595729 -287.773111) (xy 361.647024 -287.781236)
			(xy 361.696417 -287.797284) (xy 361.742691 -287.820862) (xy 361.784707 -287.851388) (xy 361.82143 -287.888111)
			(xy 361.851956 -287.930127) (xy 361.875534 -287.976401) (xy 361.891582 -288.025794) (xy 361.899707 -288.077089)
			(xy 361.900216 -288.103056) (xy 361.899707 -288.129023) (xy 364.059471 -288.129023) (xy 364.059471 -288.077089)
			(xy 364.067596 -288.025794) (xy 364.083644 -287.976401) (xy 364.107222 -287.930127) (xy 364.137748 -287.888111)
			(xy 364.174471 -287.851388) (xy 364.216487 -287.820862) (xy 364.262761 -287.797284) (xy 364.312154 -287.781236)
			(xy 364.363449 -287.773111) (xy 364.415383 -287.773111) (xy 364.466678 -287.781236) (xy 364.516071 -287.797284)
			(xy 364.562345 -287.820862) (xy 364.604361 -287.851388) (xy 364.641084 -287.888111) (xy 364.67161 -287.930127)
			(xy 364.695188 -287.976401) (xy 364.711236 -288.025794) (xy 364.719361 -288.077089) (xy 364.71987 -288.103056)
			(xy 364.719361 -288.129023) (xy 364.711236 -288.180318) (xy 364.695188 -288.229711) (xy 364.67161 -288.275985)
			(xy 364.641084 -288.318001) (xy 364.604361 -288.354724) (xy 364.562345 -288.38525) (xy 364.516071 -288.408828)
			(xy 364.466678 -288.424876) (xy 364.415383 -288.433001) (xy 364.363449 -288.433001) (xy 364.312154 -288.424876)
			(xy 364.262761 -288.408828) (xy 364.216487 -288.38525) (xy 364.174471 -288.354724) (xy 364.137748 -288.318001)
			(xy 364.107222 -288.275985) (xy 364.083644 -288.229711) (xy 364.067596 -288.180318) (xy 364.059471 -288.129023)
			(xy 361.899707 -288.129023) (xy 361.891582 -288.180318) (xy 361.875534 -288.229711) (xy 361.851956 -288.275985)
			(xy 361.82143 -288.318001) (xy 361.784707 -288.354724) (xy 361.742691 -288.38525) (xy 361.696417 -288.408828)
			(xy 361.647024 -288.424876) (xy 361.595729 -288.433001) (xy 361.543795 -288.433001) (xy 361.4925 -288.424876)
			(xy 361.443107 -288.408828) (xy 361.396833 -288.38525) (xy 361.354817 -288.354724) (xy 361.318094 -288.318001)
			(xy 361.287568 -288.275985) (xy 361.26399 -288.229711) (xy 361.247942 -288.180318) (xy 361.239817 -288.129023)
			(xy 353.770692 -288.129023) (xy 353.770692 -288.645854) (xy 353.792171 -288.661439) (xy 353.830329 -288.698314)
			(xy 353.862103 -288.740814) (xy 353.886677 -288.787846) (xy 353.903418 -288.8382) (xy 353.911896 -288.890583)
			(xy 353.911894 -288.943093) (xy 355.131371 -288.943093) (xy 355.131371 -288.891159) (xy 355.139496 -288.839864)
			(xy 355.155544 -288.790471) (xy 355.179122 -288.744197) (xy 355.209648 -288.702181) (xy 355.246371 -288.665458)
			(xy 355.288387 -288.634932) (xy 355.334661 -288.611354) (xy 355.384054 -288.595306) (xy 355.435349 -288.587181)
			(xy 355.487283 -288.587181) (xy 355.538578 -288.595306) (xy 355.587971 -288.611354) (xy 355.634245 -288.634932)
			(xy 355.676261 -288.665458) (xy 355.712984 -288.702181) (xy 355.74351 -288.744197) (xy 355.767088 -288.790471)
			(xy 355.783136 -288.839864) (xy 355.791261 -288.891159) (xy 355.79177 -288.917126) (xy 355.791261 -288.943093)
			(xy 355.783136 -288.994388) (xy 355.775044 -289.019293) (xy 357.950771 -289.019293) (xy 357.950771 -288.967359)
			(xy 357.958896 -288.916064) (xy 357.974944 -288.866671) (xy 357.998522 -288.820397) (xy 358.029048 -288.778381)
			(xy 358.065771 -288.741658) (xy 358.107787 -288.711132) (xy 358.154061 -288.687554) (xy 358.203454 -288.671506)
			(xy 358.254749 -288.663381) (xy 358.306683 -288.663381) (xy 358.357978 -288.671506) (xy 358.407371 -288.687554)
			(xy 358.453645 -288.711132) (xy 358.495661 -288.741658) (xy 358.532384 -288.778381) (xy 358.56291 -288.820397)
			(xy 358.586488 -288.866671) (xy 358.602536 -288.916064) (xy 358.610661 -288.967359) (xy 358.61117 -288.993326)
			(xy 358.610661 -289.019293) (xy 358.602536 -289.070588) (xy 358.586488 -289.119981) (xy 358.56291 -289.166255)
			(xy 358.532384 -289.208271) (xy 358.495661 -289.244994) (xy 358.453645 -289.27552) (xy 358.407371 -289.299098)
			(xy 358.357978 -289.315146) (xy 358.306683 -289.323271) (xy 358.254749 -289.323271) (xy 358.203454 -289.315146)
			(xy 358.154061 -289.299098) (xy 358.107787 -289.27552) (xy 358.065771 -289.244994) (xy 358.029048 -289.208271)
			(xy 357.998522 -289.166255) (xy 357.974944 -289.119981) (xy 357.958896 -289.070588) (xy 357.950771 -289.019293)
			(xy 355.775044 -289.019293) (xy 355.767088 -289.043781) (xy 355.74351 -289.090055) (xy 355.712984 -289.132071)
			(xy 355.676261 -289.168794) (xy 355.634245 -289.19932) (xy 355.587971 -289.222898) (xy 355.538578 -289.238946)
			(xy 355.487283 -289.247071) (xy 355.435349 -289.247071) (xy 355.384054 -289.238946) (xy 355.334661 -289.222898)
			(xy 355.288387 -289.19932) (xy 355.246371 -289.168794) (xy 355.209648 -289.132071) (xy 355.179122 -289.090055)
			(xy 355.155544 -289.043781) (xy 355.139496 -288.994388) (xy 355.131371 -288.943093) (xy 353.911894 -288.943093)
			(xy 353.911894 -288.943647) (xy 353.903411 -288.996029) (xy 353.886665 -289.046382) (xy 353.862087 -289.093411)
			(xy 353.830309 -289.135908) (xy 353.792148 -289.17278) (xy 353.770692 -289.188398) (xy 353.770692 -291.801804)
			(xy 352.606864 -292.965632) (xy 352.624183 -292.982951) (xy 357.228881 -292.982951) (xy 357.228881 -292.928449)
			(xy 357.236638 -292.874501) (xy 357.251993 -292.822207) (xy 357.274634 -292.77263) (xy 357.3041 -292.72678)
			(xy 357.339792 -292.68559) (xy 357.380982 -292.649899) (xy 357.426832 -292.620433) (xy 357.476409 -292.597792)
			(xy 357.528703 -292.582437) (xy 357.582651 -292.574681) (xy 357.609902 -292.574218) (xy 357.637272 -292.574679)
			(xy 357.691452 -292.582497) (xy 357.743955 -292.597987) (xy 357.793702 -292.62083) (xy 357.839669 -292.650556)
			(xy 357.8606 -292.668198) (xy 357.871928 -292.677434) (xy 357.898485 -292.68961) (xy 357.927402 -292.693783)
			(xy 357.956319 -292.68961) (xy 357.982876 -292.677434) (xy 357.994204 -292.668198) (xy 358.015123 -292.650543)
			(xy 358.0611 -292.620834) (xy 358.11085 -292.598001) (xy 358.163354 -292.582514) (xy 358.217532 -292.57469)
			(xy 358.244902 -292.574218) (xy 358.272155 -292.574652) (xy 358.326106 -292.582409) (xy 358.378404 -292.597766)
			(xy 358.427985 -292.620408) (xy 358.473838 -292.649877) (xy 358.515031 -292.685571) (xy 358.550724 -292.726764)
			(xy 358.580193 -292.772617) (xy 358.602835 -292.822198) (xy 358.618191 -292.874496) (xy 358.625948 -292.928447)
			(xy 358.625948 -292.982953) (xy 358.618191 -293.036904) (xy 358.602835 -293.089202) (xy 358.580193 -293.138783)
			(xy 358.550724 -293.184636) (xy 358.515031 -293.225829) (xy 358.473838 -293.261523) (xy 358.427985 -293.290992)
			(xy 358.378404 -293.313634) (xy 358.326106 -293.328991) (xy 358.272155 -293.336748) (xy 358.244902 -293.337234)
			(xy 358.217531 -293.336783) (xy 358.163351 -293.328964) (xy 358.110847 -293.313472) (xy 358.0611 -293.290627)
			(xy 358.015135 -293.260898) (xy 357.994204 -293.243254) (xy 357.982876 -293.234018) (xy 357.956319 -293.221842)
			(xy 357.927402 -293.217669) (xy 357.898485 -293.221842) (xy 357.871928 -293.234018) (xy 357.8606 -293.243254)
			(xy 357.839673 -293.260899) (xy 357.793699 -293.290612) (xy 357.743951 -293.313447) (xy 357.691449 -293.328937)
			(xy 357.637272 -293.336762) (xy 357.609902 -293.337234) (xy 357.582651 -293.336719) (xy 357.528703 -293.328963)
			(xy 357.476409 -293.313608) (xy 357.426832 -293.290967) (xy 357.380982 -293.261501) (xy 357.339792 -293.22581)
			(xy 357.3041 -293.18462) (xy 357.274634 -293.13877) (xy 357.251993 -293.089193) (xy 357.236638 -293.036899)
			(xy 357.228881 -292.982951) (xy 352.624183 -292.982951) (xy 352.742754 -293.101522) (xy 352.742754 -295.065751)
			(xy 357.228881 -295.065751) (xy 357.228881 -295.011249) (xy 357.236638 -294.957301) (xy 357.251993 -294.905007)
			(xy 357.274634 -294.85543) (xy 357.3041 -294.80958) (xy 357.339792 -294.76839) (xy 357.380982 -294.732699)
			(xy 357.426832 -294.703233) (xy 357.476409 -294.680592) (xy 357.528703 -294.665237) (xy 357.582651 -294.657481)
			(xy 357.609902 -294.657018) (xy 357.640025 -294.657597) (xy 357.699521 -294.667077) (xy 357.756788 -294.685787)
			(xy 357.810405 -294.713261) (xy 357.85904 -294.748816) (xy 357.880666 -294.769794) (xy 357.890388 -294.779012)
			(xy 357.91355 -294.792457) (xy 357.939411 -294.799419) (xy 357.966193 -294.799419) (xy 357.992054 -294.792457)
			(xy 358.015216 -294.779012) (xy 358.024938 -294.769794) (xy 358.046566 -294.748817) (xy 358.095194 -294.713249)
			(xy 358.14881 -294.685768) (xy 358.206079 -294.667059) (xy 358.265578 -294.657587) (xy 358.295702 -294.657018)
			(xy 358.322955 -294.657452) (xy 358.376906 -294.665209) (xy 358.429204 -294.680566) (xy 358.478785 -294.703208)
			(xy 358.524638 -294.732677) (xy 358.565831 -294.768371) (xy 358.601524 -294.809564) (xy 358.630993 -294.855417)
			(xy 358.653635 -294.904998) (xy 358.668991 -294.957296) (xy 358.676748 -295.011247) (xy 358.676748 -295.065753)
			(xy 358.668991 -295.119704) (xy 358.653635 -295.172002) (xy 358.630993 -295.221583) (xy 358.601524 -295.267436)
			(xy 358.565831 -295.308629) (xy 358.524638 -295.344323) (xy 358.478785 -295.373792) (xy 358.429204 -295.396434)
			(xy 358.376906 -295.411791) (xy 358.322955 -295.419548) (xy 358.295702 -295.420034) (xy 358.265578 -295.419467)
			(xy 358.206082 -295.409986) (xy 358.148813 -295.391274) (xy 358.095196 -295.363797) (xy 358.046562 -295.328238)
			(xy 358.024938 -295.307258) (xy 358.015216 -295.29804) (xy 357.992054 -295.284595) (xy 357.966193 -295.277633)
			(xy 357.939411 -295.277633) (xy 357.91355 -295.284595) (xy 357.890388 -295.29804) (xy 357.880666 -295.307258)
			(xy 357.859028 -295.328224) (xy 357.810404 -295.363796) (xy 357.756791 -295.39128) (xy 357.699523 -295.409991)
			(xy 357.640025 -295.419465) (xy 357.609902 -295.420034) (xy 357.582651 -295.419519) (xy 357.528703 -295.411763)
			(xy 357.476409 -295.396408) (xy 357.426832 -295.373767) (xy 357.380982 -295.344301) (xy 357.339792 -295.30861)
			(xy 357.3041 -295.26742) (xy 357.274634 -295.22157) (xy 357.251993 -295.171993) (xy 357.236638 -295.119699)
			(xy 357.228881 -295.065751) (xy 352.742754 -295.065751) (xy 352.742754 -297.224751) (xy 357.228881 -297.224751)
			(xy 357.228881 -297.170249) (xy 357.236638 -297.116301) (xy 357.251993 -297.064007) (xy 357.274634 -297.01443)
			(xy 357.3041 -296.96858) (xy 357.339792 -296.92739) (xy 357.380982 -296.891699) (xy 357.426832 -296.862233)
			(xy 357.476409 -296.839592) (xy 357.528703 -296.824237) (xy 357.582651 -296.816481) (xy 357.609902 -296.816018)
			(xy 357.640025 -296.816597) (xy 357.699521 -296.826077) (xy 357.756788 -296.844787) (xy 357.810405 -296.872261)
			(xy 357.85904 -296.907816) (xy 357.880666 -296.928794) (xy 357.890388 -296.938012) (xy 357.91355 -296.951457)
			(xy 357.939411 -296.958419) (xy 357.966193 -296.958419) (xy 357.992054 -296.951457) (xy 358.015216 -296.938012)
			(xy 358.024938 -296.928794) (xy 358.046566 -296.907817) (xy 358.095194 -296.872249) (xy 358.14881 -296.844768)
			(xy 358.206079 -296.826059) (xy 358.265578 -296.816587) (xy 358.295702 -296.816018) (xy 358.322955 -296.816452)
			(xy 358.376906 -296.824209) (xy 358.429204 -296.839566) (xy 358.478785 -296.862208) (xy 358.524638 -296.891677)
			(xy 358.565831 -296.927371) (xy 358.601524 -296.968564) (xy 358.630993 -297.014417) (xy 358.653635 -297.063998)
			(xy 358.668991 -297.116296) (xy 358.676748 -297.170247) (xy 358.676748 -297.224753) (xy 358.668991 -297.278704)
			(xy 358.653635 -297.331002) (xy 358.630993 -297.380583) (xy 358.601524 -297.426436) (xy 358.565831 -297.467629)
			(xy 358.524638 -297.503323) (xy 358.478785 -297.532792) (xy 358.429204 -297.555434) (xy 358.376906 -297.570791)
			(xy 358.322955 -297.578548) (xy 358.295702 -297.579034) (xy 358.265578 -297.578467) (xy 358.206082 -297.568986)
			(xy 358.148813 -297.550274) (xy 358.095196 -297.522797) (xy 358.046562 -297.487238) (xy 358.024938 -297.466258)
			(xy 358.015216 -297.45704) (xy 357.992054 -297.443595) (xy 357.966193 -297.436633) (xy 357.939411 -297.436633)
			(xy 357.91355 -297.443595) (xy 357.890388 -297.45704) (xy 357.880666 -297.466258) (xy 357.859028 -297.487224)
			(xy 357.810404 -297.522796) (xy 357.756791 -297.55028) (xy 357.699523 -297.568991) (xy 357.640025 -297.578465)
			(xy 357.609902 -297.579034) (xy 357.582651 -297.578519) (xy 357.528703 -297.570763) (xy 357.476409 -297.555408)
			(xy 357.426832 -297.532767) (xy 357.380982 -297.503301) (xy 357.339792 -297.46761) (xy 357.3041 -297.42642)
			(xy 357.274634 -297.38057) (xy 357.251993 -297.330993) (xy 357.236638 -297.278699) (xy 357.228881 -297.224751)
			(xy 352.742754 -297.224751) (xy 352.742754 -301.128684) (xy 350.701356 -304.939192) (xy 339.780702 -315.709738)
			(xy 345.576648 -315.709738) (xy 345.576648 -315.625042) (xy 345.584699 -315.540728) (xy 345.600728 -315.457562)
			(xy 345.624589 -315.376295) (xy 345.656068 -315.297665) (xy 345.694879 -315.222384) (xy 345.740669 -315.151132)
			(xy 345.793025 -315.084556) (xy 345.851473 -315.023258) (xy 345.915483 -314.967793) (xy 345.984475 -314.918664)
			(xy 346.057825 -314.876315) (xy 346.134868 -314.841131) (xy 346.214907 -314.813429) (xy 346.297216 -314.793461)
			(xy 346.381051 -314.781408) (xy 346.465652 -314.777378) (xy 346.550253 -314.781408) (xy 346.634088 -314.793461)
			(xy 346.716397 -314.813429) (xy 346.796436 -314.841131) (xy 346.873479 -314.876315) (xy 346.946829 -314.918664)
			(xy 347.015821 -314.967793) (xy 347.079831 -315.023258) (xy 347.138279 -315.084556) (xy 347.190635 -315.151132)
			(xy 347.236425 -315.222384) (xy 347.275236 -315.297665) (xy 347.306715 -315.376295) (xy 347.330576 -315.457562)
			(xy 347.346605 -315.540728) (xy 347.354656 -315.625042) (xy 347.35516 -315.66739) (xy 347.550237 -315.66739)
			(xy 347.554259 -315.58167) (xy 347.56629 -315.496702) (xy 347.586226 -315.413235) (xy 347.613889 -315.332001)
			(xy 347.649038 -315.253715) (xy 347.691364 -315.179064) (xy 347.740493 -315.108705) (xy 347.795996 -315.043255)
			(xy 347.857383 -314.983291) (xy 347.924116 -314.929338) (xy 347.995608 -314.881871) (xy 348.07123 -314.841307)
			(xy 348.150319 -314.808003) (xy 348.232179 -314.782251) (xy 348.31609 -314.764278) (xy 348.401316 -314.754242)
			(xy 348.487108 -314.75223) (xy 348.57271 -314.758261) (xy 348.657372 -314.772281) (xy 348.740349 -314.794167)
			(xy 348.820912 -314.823728) (xy 348.898352 -314.860702) (xy 348.971991 -314.904766) (xy 349.041179 -314.955532)
			(xy 349.10531 -315.012553) (xy 349.163819 -315.075329) (xy 349.216192 -315.143309) (xy 349.26197 -315.215894)
			(xy 349.30075 -315.292446) (xy 349.332191 -315.372294) (xy 349.356017 -315.454735) (xy 349.372018 -315.539045)
			(xy 349.380053 -315.624483) (xy 349.380556 -315.66739) (xy 349.38006 -315.709738) (xy 351.774248 -315.709738)
			(xy 351.774248 -315.625042) (xy 351.782299 -315.540728) (xy 351.798328 -315.457562) (xy 351.822189 -315.376295)
			(xy 351.853668 -315.297665) (xy 351.892479 -315.222384) (xy 351.938269 -315.151132) (xy 351.990625 -315.084556)
			(xy 352.049073 -315.023258) (xy 352.113083 -314.967793) (xy 352.182075 -314.918664) (xy 352.255425 -314.876315)
			(xy 352.332468 -314.841131) (xy 352.412507 -314.813429) (xy 352.494816 -314.793461) (xy 352.578651 -314.781408)
			(xy 352.663252 -314.777378) (xy 352.747853 -314.781408) (xy 352.831688 -314.793461) (xy 352.913997 -314.813429)
			(xy 352.994036 -314.841131) (xy 353.071079 -314.876315) (xy 353.144429 -314.918664) (xy 353.213421 -314.967793)
			(xy 353.277431 -315.023258) (xy 353.335879 -315.084556) (xy 353.388235 -315.151132) (xy 353.434025 -315.222384)
			(xy 353.472836 -315.297665) (xy 353.504315 -315.376295) (xy 353.528176 -315.457562) (xy 353.544205 -315.540728)
			(xy 353.552256 -315.625042) (xy 353.55276 -315.66739) (xy 353.747837 -315.66739) (xy 353.751859 -315.58167)
			(xy 353.76389 -315.496702) (xy 353.783826 -315.413235) (xy 353.811489 -315.332001) (xy 353.846638 -315.253715)
			(xy 353.888964 -315.179064) (xy 353.938093 -315.108705) (xy 353.993596 -315.043255) (xy 354.054983 -314.983291)
			(xy 354.121716 -314.929338) (xy 354.193208 -314.881871) (xy 354.26883 -314.841307) (xy 354.347919 -314.808003)
			(xy 354.429779 -314.782251) (xy 354.51369 -314.764278) (xy 354.598916 -314.754242) (xy 354.684708 -314.75223)
			(xy 354.77031 -314.758261) (xy 354.854972 -314.772281) (xy 354.937949 -314.794167) (xy 355.018512 -314.823728)
			(xy 355.095952 -314.860702) (xy 355.169591 -314.904766) (xy 355.238779 -314.955532) (xy 355.30291 -315.012553)
			(xy 355.361419 -315.075329) (xy 355.413792 -315.143309) (xy 355.45957 -315.215894) (xy 355.49835 -315.292446)
			(xy 355.529791 -315.372294) (xy 355.553617 -315.454735) (xy 355.569618 -315.539045) (xy 355.577653 -315.624483)
			(xy 355.578156 -315.66739) (xy 355.57766 -315.709738) (xy 357.952036 -315.709738) (xy 357.952036 -315.625042)
			(xy 357.960087 -315.540728) (xy 357.976116 -315.457562) (xy 357.999977 -315.376295) (xy 358.031456 -315.297665)
			(xy 358.070267 -315.222384) (xy 358.116057 -315.151132) (xy 358.168413 -315.084556) (xy 358.226861 -315.023258)
			(xy 358.290871 -314.967793) (xy 358.359863 -314.918664) (xy 358.433213 -314.876315) (xy 358.510256 -314.841131)
			(xy 358.590295 -314.813429) (xy 358.672604 -314.793461) (xy 358.756439 -314.781408) (xy 358.84104 -314.777378)
			(xy 358.925641 -314.781408) (xy 359.009476 -314.793461) (xy 359.091785 -314.813429) (xy 359.171824 -314.841131)
			(xy 359.248867 -314.876315) (xy 359.322217 -314.918664) (xy 359.391209 -314.967793) (xy 359.455219 -315.023258)
			(xy 359.513667 -315.084556) (xy 359.566023 -315.151132) (xy 359.611813 -315.222384) (xy 359.650624 -315.297665)
			(xy 359.682103 -315.376295) (xy 359.705964 -315.457562) (xy 359.721993 -315.540728) (xy 359.730044 -315.625042)
			(xy 359.730548 -315.66739) (xy 359.925625 -315.66739) (xy 359.929647 -315.58167) (xy 359.941678 -315.496702)
			(xy 359.961614 -315.413235) (xy 359.989277 -315.332001) (xy 360.024426 -315.253715) (xy 360.066752 -315.179064)
			(xy 360.115881 -315.108705) (xy 360.171384 -315.043255) (xy 360.232771 -314.983291) (xy 360.299504 -314.929338)
			(xy 360.370996 -314.881871) (xy 360.446618 -314.841307) (xy 360.525707 -314.808003) (xy 360.607567 -314.782251)
			(xy 360.691478 -314.764278) (xy 360.776704 -314.754242) (xy 360.862496 -314.75223) (xy 360.948098 -314.758261)
			(xy 361.03276 -314.772281) (xy 361.115737 -314.794167) (xy 361.1963 -314.823728) (xy 361.27374 -314.860702)
			(xy 361.347379 -314.904766) (xy 361.416567 -314.955532) (xy 361.480698 -315.012553) (xy 361.539207 -315.075329)
			(xy 361.59158 -315.143309) (xy 361.637358 -315.215894) (xy 361.676138 -315.292446) (xy 361.707579 -315.372294)
			(xy 361.731405 -315.454735) (xy 361.747406 -315.539045) (xy 361.755441 -315.624483) (xy 361.755944 -315.66739)
			(xy 361.755448 -315.709738) (xy 364.149636 -315.709738) (xy 364.149636 -315.625042) (xy 364.157687 -315.540728)
			(xy 364.173716 -315.457562) (xy 364.197577 -315.376295) (xy 364.229056 -315.297665) (xy 364.267867 -315.222384)
			(xy 364.313657 -315.151132) (xy 364.366013 -315.084556) (xy 364.424461 -315.023258) (xy 364.488471 -314.967793)
			(xy 364.557463 -314.918664) (xy 364.630813 -314.876315) (xy 364.707856 -314.841131) (xy 364.787895 -314.813429)
			(xy 364.870204 -314.793461) (xy 364.954039 -314.781408) (xy 365.03864 -314.777378) (xy 365.123241 -314.781408)
			(xy 365.207076 -314.793461) (xy 365.289385 -314.813429) (xy 365.369424 -314.841131) (xy 365.446467 -314.876315)
			(xy 365.519817 -314.918664) (xy 365.588809 -314.967793) (xy 365.652819 -315.023258) (xy 365.711267 -315.084556)
			(xy 365.763623 -315.151132) (xy 365.809413 -315.222384) (xy 365.848224 -315.297665) (xy 365.879703 -315.376295)
			(xy 365.903564 -315.457562) (xy 365.919593 -315.540728) (xy 365.927644 -315.625042) (xy 365.928148 -315.66739)
			(xy 366.123225 -315.66739) (xy 366.127247 -315.58167) (xy 366.139278 -315.496702) (xy 366.159214 -315.413235)
			(xy 366.186877 -315.332001) (xy 366.222026 -315.253715) (xy 366.264352 -315.179064) (xy 366.313481 -315.108705)
			(xy 366.368984 -315.043255) (xy 366.430371 -314.983291) (xy 366.497104 -314.929338) (xy 366.568596 -314.881871)
			(xy 366.644218 -314.841307) (xy 366.723307 -314.808003) (xy 366.805167 -314.782251) (xy 366.889078 -314.764278)
			(xy 366.974304 -314.754242) (xy 367.060096 -314.75223) (xy 367.145698 -314.758261) (xy 367.23036 -314.772281)
			(xy 367.313337 -314.794167) (xy 367.3939 -314.823728) (xy 367.47134 -314.860702) (xy 367.544979 -314.904766)
			(xy 367.614167 -314.955532) (xy 367.678298 -315.012553) (xy 367.736807 -315.075329) (xy 367.78918 -315.143309)
			(xy 367.834958 -315.215894) (xy 367.873738 -315.292446) (xy 367.905179 -315.372294) (xy 367.929005 -315.454735)
			(xy 367.945006 -315.539045) (xy 367.953041 -315.624483) (xy 367.953544 -315.66739) (xy 367.953048 -315.709738)
			(xy 370.347236 -315.709738) (xy 370.347236 -315.625042) (xy 370.355287 -315.540728) (xy 370.371316 -315.457562)
			(xy 370.395177 -315.376295) (xy 370.426656 -315.297665) (xy 370.465467 -315.222384) (xy 370.511257 -315.151132)
			(xy 370.563613 -315.084556) (xy 370.622061 -315.023258) (xy 370.686071 -314.967793) (xy 370.755063 -314.918664)
			(xy 370.828413 -314.876315) (xy 370.905456 -314.841131) (xy 370.985495 -314.813429) (xy 371.067804 -314.793461)
			(xy 371.151639 -314.781408) (xy 371.23624 -314.777378) (xy 371.320841 -314.781408) (xy 371.404676 -314.793461)
			(xy 371.486985 -314.813429) (xy 371.567024 -314.841131) (xy 371.644067 -314.876315) (xy 371.717417 -314.918664)
			(xy 371.786409 -314.967793) (xy 371.850419 -315.023258) (xy 371.908867 -315.084556) (xy 371.961223 -315.151132)
			(xy 372.007013 -315.222384) (xy 372.045824 -315.297665) (xy 372.077303 -315.376295) (xy 372.101164 -315.457562)
			(xy 372.117193 -315.540728) (xy 372.125244 -315.625042) (xy 372.125748 -315.66739) (xy 372.320825 -315.66739)
			(xy 372.324847 -315.58167) (xy 372.336878 -315.496702) (xy 372.356814 -315.413235) (xy 372.384477 -315.332001)
			(xy 372.419626 -315.253715) (xy 372.461952 -315.179064) (xy 372.511081 -315.108705) (xy 372.566584 -315.043255)
			(xy 372.627971 -314.983291) (xy 372.694704 -314.929338) (xy 372.766196 -314.881871) (xy 372.841818 -314.841307)
			(xy 372.920907 -314.808003) (xy 373.002767 -314.782251) (xy 373.086678 -314.764278) (xy 373.171904 -314.754242)
			(xy 373.257696 -314.75223) (xy 373.343298 -314.758261) (xy 373.42796 -314.772281) (xy 373.510937 -314.794167)
			(xy 373.5915 -314.823728) (xy 373.66894 -314.860702) (xy 373.742579 -314.904766) (xy 373.811767 -314.955532)
			(xy 373.875898 -315.012553) (xy 373.934407 -315.075329) (xy 373.98678 -315.143309) (xy 374.032558 -315.215894)
			(xy 374.071338 -315.292446) (xy 374.102779 -315.372294) (xy 374.126605 -315.454735) (xy 374.142606 -315.539045)
			(xy 374.150641 -315.624483) (xy 374.151144 -315.66739) (xy 374.150641 -315.710297) (xy 374.142606 -315.795735)
			(xy 374.126605 -315.880045) (xy 374.102779 -315.962486) (xy 374.071338 -316.042334) (xy 374.032558 -316.118886)
			(xy 373.98678 -316.191471) (xy 373.934407 -316.259451) (xy 373.875898 -316.322227) (xy 373.811767 -316.379248)
			(xy 373.742579 -316.430014) (xy 373.66894 -316.474078) (xy 373.5915 -316.511052) (xy 373.510937 -316.540613)
			(xy 373.42796 -316.562499) (xy 373.343298 -316.576519) (xy 373.257696 -316.58255) (xy 373.171904 -316.580538)
			(xy 373.086678 -316.570502) (xy 373.002767 -316.552529) (xy 372.920907 -316.526777) (xy 372.841818 -316.493473)
			(xy 372.766196 -316.452909) (xy 372.694704 -316.405442) (xy 372.627971 -316.351489) (xy 372.566584 -316.291525)
			(xy 372.511081 -316.226075) (xy 372.461952 -316.155716) (xy 372.419626 -316.081065) (xy 372.384477 -316.002779)
			(xy 372.356814 -315.921545) (xy 372.336878 -315.838078) (xy 372.324847 -315.75311) (xy 372.320825 -315.66739)
			(xy 372.125748 -315.66739) (xy 372.125244 -315.709738) (xy 372.117193 -315.794052) (xy 372.101164 -315.877218)
			(xy 372.077303 -315.958485) (xy 372.045824 -316.037115) (xy 372.007013 -316.112396) (xy 371.961223 -316.183648)
			(xy 371.908867 -316.250224) (xy 371.850419 -316.311522) (xy 371.786409 -316.366987) (xy 371.717417 -316.416116)
			(xy 371.644067 -316.458465) (xy 371.567024 -316.493649) (xy 371.486985 -316.521351) (xy 371.404676 -316.541319)
			(xy 371.320841 -316.553372) (xy 371.23624 -316.557403) (xy 371.151639 -316.553372) (xy 371.067804 -316.541319)
			(xy 370.985495 -316.521351) (xy 370.905456 -316.493649) (xy 370.828413 -316.458465) (xy 370.755063 -316.416116)
			(xy 370.686071 -316.366987) (xy 370.622061 -316.311522) (xy 370.563613 -316.250224) (xy 370.511257 -316.183648)
			(xy 370.465467 -316.112396) (xy 370.426656 -316.037115) (xy 370.395177 -315.958485) (xy 370.371316 -315.877218)
			(xy 370.355287 -315.794052) (xy 370.347236 -315.709738) (xy 367.953048 -315.709738) (xy 367.953041 -315.710297)
			(xy 367.945006 -315.795735) (xy 367.929005 -315.880045) (xy 367.905179 -315.962486) (xy 367.873738 -316.042334)
			(xy 367.834958 -316.118886) (xy 367.78918 -316.191471) (xy 367.736807 -316.259451) (xy 367.678298 -316.322227)
			(xy 367.614167 -316.379248) (xy 367.544979 -316.430014) (xy 367.47134 -316.474078) (xy 367.3939 -316.511052)
			(xy 367.313337 -316.540613) (xy 367.23036 -316.562499) (xy 367.145698 -316.576519) (xy 367.060096 -316.58255)
			(xy 366.974304 -316.580538) (xy 366.889078 -316.570502) (xy 366.805167 -316.552529) (xy 366.723307 -316.526777)
			(xy 366.644218 -316.493473) (xy 366.568596 -316.452909) (xy 366.497104 -316.405442) (xy 366.430371 -316.351489)
			(xy 366.368984 -316.291525) (xy 366.313481 -316.226075) (xy 366.264352 -316.155716) (xy 366.222026 -316.081065)
			(xy 366.186877 -316.002779) (xy 366.159214 -315.921545) (xy 366.139278 -315.838078) (xy 366.127247 -315.75311)
			(xy 366.123225 -315.66739) (xy 365.928148 -315.66739) (xy 365.927644 -315.709738) (xy 365.919593 -315.794052)
			(xy 365.903564 -315.877218) (xy 365.879703 -315.958485) (xy 365.848224 -316.037115) (xy 365.809413 -316.112396)
			(xy 365.763623 -316.183648) (xy 365.711267 -316.250224) (xy 365.652819 -316.311522) (xy 365.588809 -316.366987)
			(xy 365.519817 -316.416116) (xy 365.446467 -316.458465) (xy 365.369424 -316.493649) (xy 365.289385 -316.521351)
			(xy 365.207076 -316.541319) (xy 365.123241 -316.553372) (xy 365.03864 -316.557403) (xy 364.954039 -316.553372)
			(xy 364.870204 -316.541319) (xy 364.787895 -316.521351) (xy 364.707856 -316.493649) (xy 364.630813 -316.458465)
			(xy 364.557463 -316.416116) (xy 364.488471 -316.366987) (xy 364.424461 -316.311522) (xy 364.366013 -316.250224)
			(xy 364.313657 -316.183648) (xy 364.267867 -316.112396) (xy 364.229056 -316.037115) (xy 364.197577 -315.958485)
			(xy 364.173716 -315.877218) (xy 364.157687 -315.794052) (xy 364.149636 -315.709738) (xy 361.755448 -315.709738)
			(xy 361.755441 -315.710297) (xy 361.747406 -315.795735) (xy 361.731405 -315.880045) (xy 361.707579 -315.962486)
			(xy 361.676138 -316.042334) (xy 361.637358 -316.118886) (xy 361.59158 -316.191471) (xy 361.539207 -316.259451)
			(xy 361.480698 -316.322227) (xy 361.416567 -316.379248) (xy 361.347379 -316.430014) (xy 361.27374 -316.474078)
			(xy 361.1963 -316.511052) (xy 361.115737 -316.540613) (xy 361.03276 -316.562499) (xy 360.948098 -316.576519)
			(xy 360.862496 -316.58255) (xy 360.776704 -316.580538) (xy 360.691478 -316.570502) (xy 360.607567 -316.552529)
			(xy 360.525707 -316.526777) (xy 360.446618 -316.493473) (xy 360.370996 -316.452909) (xy 360.299504 -316.405442)
			(xy 360.232771 -316.351489) (xy 360.171384 -316.291525) (xy 360.115881 -316.226075) (xy 360.066752 -316.155716)
			(xy 360.024426 -316.081065) (xy 359.989277 -316.002779) (xy 359.961614 -315.921545) (xy 359.941678 -315.838078)
			(xy 359.929647 -315.75311) (xy 359.925625 -315.66739) (xy 359.730548 -315.66739) (xy 359.730044 -315.709738)
			(xy 359.721993 -315.794052) (xy 359.705964 -315.877218) (xy 359.682103 -315.958485) (xy 359.650624 -316.037115)
			(xy 359.611813 -316.112396) (xy 359.566023 -316.183648) (xy 359.513667 -316.250224) (xy 359.455219 -316.311522)
			(xy 359.391209 -316.366987) (xy 359.322217 -316.416116) (xy 359.248867 -316.458465) (xy 359.171824 -316.493649)
			(xy 359.091785 -316.521351) (xy 359.009476 -316.541319) (xy 358.925641 -316.553372) (xy 358.84104 -316.557403)
			(xy 358.756439 -316.553372) (xy 358.672604 -316.541319) (xy 358.590295 -316.521351) (xy 358.510256 -316.493649)
			(xy 358.433213 -316.458465) (xy 358.359863 -316.416116) (xy 358.290871 -316.366987) (xy 358.226861 -316.311522)
			(xy 358.168413 -316.250224) (xy 358.116057 -316.183648) (xy 358.070267 -316.112396) (xy 358.031456 -316.037115)
			(xy 357.999977 -315.958485) (xy 357.976116 -315.877218) (xy 357.960087 -315.794052) (xy 357.952036 -315.709738)
			(xy 355.57766 -315.709738) (xy 355.577653 -315.710297) (xy 355.569618 -315.795735) (xy 355.553617 -315.880045)
			(xy 355.529791 -315.962486) (xy 355.49835 -316.042334) (xy 355.45957 -316.118886) (xy 355.413792 -316.191471)
			(xy 355.361419 -316.259451) (xy 355.30291 -316.322227) (xy 355.238779 -316.379248) (xy 355.169591 -316.430014)
			(xy 355.095952 -316.474078) (xy 355.018512 -316.511052) (xy 354.937949 -316.540613) (xy 354.854972 -316.562499)
			(xy 354.77031 -316.576519) (xy 354.684708 -316.58255) (xy 354.598916 -316.580538) (xy 354.51369 -316.570502)
			(xy 354.429779 -316.552529) (xy 354.347919 -316.526777) (xy 354.26883 -316.493473) (xy 354.193208 -316.452909)
			(xy 354.121716 -316.405442) (xy 354.054983 -316.351489) (xy 353.993596 -316.291525) (xy 353.938093 -316.226075)
			(xy 353.888964 -316.155716) (xy 353.846638 -316.081065) (xy 353.811489 -316.002779) (xy 353.783826 -315.921545)
			(xy 353.76389 -315.838078) (xy 353.751859 -315.75311) (xy 353.747837 -315.66739) (xy 353.55276 -315.66739)
			(xy 353.552256 -315.709738) (xy 353.544205 -315.794052) (xy 353.528176 -315.877218) (xy 353.504315 -315.958485)
			(xy 353.472836 -316.037115) (xy 353.434025 -316.112396) (xy 353.388235 -316.183648) (xy 353.335879 -316.250224)
			(xy 353.277431 -316.311522) (xy 353.213421 -316.366987) (xy 353.144429 -316.416116) (xy 353.071079 -316.458465)
			(xy 352.994036 -316.493649) (xy 352.913997 -316.521351) (xy 352.831688 -316.541319) (xy 352.747853 -316.553372)
			(xy 352.663252 -316.557403) (xy 352.578651 -316.553372) (xy 352.494816 -316.541319) (xy 352.412507 -316.521351)
			(xy 352.332468 -316.493649) (xy 352.255425 -316.458465) (xy 352.182075 -316.416116) (xy 352.113083 -316.366987)
			(xy 352.049073 -316.311522) (xy 351.990625 -316.250224) (xy 351.938269 -316.183648) (xy 351.892479 -316.112396)
			(xy 351.853668 -316.037115) (xy 351.822189 -315.958485) (xy 351.798328 -315.877218) (xy 351.782299 -315.794052)
			(xy 351.774248 -315.709738) (xy 349.38006 -315.709738) (xy 349.380053 -315.710297) (xy 349.372018 -315.795735)
			(xy 349.356017 -315.880045) (xy 349.332191 -315.962486) (xy 349.30075 -316.042334) (xy 349.26197 -316.118886)
			(xy 349.216192 -316.191471) (xy 349.163819 -316.259451) (xy 349.10531 -316.322227) (xy 349.041179 -316.379248)
			(xy 348.971991 -316.430014) (xy 348.898352 -316.474078) (xy 348.820912 -316.511052) (xy 348.740349 -316.540613)
			(xy 348.657372 -316.562499) (xy 348.57271 -316.576519) (xy 348.487108 -316.58255) (xy 348.401316 -316.580538)
			(xy 348.31609 -316.570502) (xy 348.232179 -316.552529) (xy 348.150319 -316.526777) (xy 348.07123 -316.493473)
			(xy 347.995608 -316.452909) (xy 347.924116 -316.405442) (xy 347.857383 -316.351489) (xy 347.795996 -316.291525)
			(xy 347.740493 -316.226075) (xy 347.691364 -316.155716) (xy 347.649038 -316.081065) (xy 347.613889 -316.002779)
			(xy 347.586226 -315.921545) (xy 347.56629 -315.838078) (xy 347.554259 -315.75311) (xy 347.550237 -315.66739)
			(xy 347.35516 -315.66739) (xy 347.354656 -315.709738) (xy 347.346605 -315.794052) (xy 347.330576 -315.877218)
			(xy 347.306715 -315.958485) (xy 347.275236 -316.037115) (xy 347.236425 -316.112396) (xy 347.190635 -316.183648)
			(xy 347.138279 -316.250224) (xy 347.079831 -316.311522) (xy 347.015821 -316.366987) (xy 346.946829 -316.416116)
			(xy 346.873479 -316.458465) (xy 346.796436 -316.493649) (xy 346.716397 -316.521351) (xy 346.634088 -316.541319)
			(xy 346.550253 -316.553372) (xy 346.465652 -316.557403) (xy 346.381051 -316.553372) (xy 346.297216 -316.541319)
			(xy 346.214907 -316.521351) (xy 346.134868 -316.493649) (xy 346.057825 -316.458465) (xy 345.984475 -316.416116)
			(xy 345.915483 -316.366987) (xy 345.851473 -316.311522) (xy 345.793025 -316.250224) (xy 345.740669 -316.183648)
			(xy 345.694879 -316.112396) (xy 345.656068 -316.037115) (xy 345.624589 -315.958485) (xy 345.600728 -315.877218)
			(xy 345.584699 -315.794052) (xy 345.576648 -315.709738) (xy 339.780702 -315.709738) (xy 328.655934 -326.681592)
			(xy 327.795128 -327.542398) (xy 325.421752 -331.2033) (xy 325.42226 -331.219048) (xy 325.42226 -331.226668)
			(xy 325.421804 -331.252771) (xy 325.414183 -331.304418) (xy 325.399101 -331.354398) (xy 325.376879 -331.401639)
			(xy 325.347996 -331.445127) (xy 325.31307 -331.48393) (xy 325.272851 -331.517216) (xy 325.228202 -331.54427)
			(xy 325.204328 -331.554836) (xy 325.190104 -331.560932) (xy 324.61073 -332.454504) (xy 324.912228 -332.756002)
			(xy 336.148934 -332.756002)
		)
		(stroke
			(width 0)
			(type solid)
		)
		(fill yes)
		(layer "In4.Cu")
		(net "PVCCIN_CPU0")
	)
	(gr_poly
		(pts
			(xy 84.270596 -332.93177) (xy 84.278789 -332.931461) (xy 84.294335 -332.926277) (xy 84.301076 -332.92161)
			(xy 84.306664 -332.916784) (xy 84.832952 -332.390496) (xy 84.837778 -332.384908) (xy 84.842448 -332.378168)
			(xy 84.847634 -332.362622) (xy 84.847938 -332.354428) (xy 84.847938 -331.695552) (xy 84.847622 -331.687361)
			(xy 84.842432 -331.671821) (xy 84.837778 -331.665072) (xy 84.832952 -331.659484) (xy 84.830158 -331.65669)
			(xy 84.830158 -330.941172) (xy 84.830588 -330.931105) (xy 84.838316 -330.912514) (xy 84.845144 -330.905104)
			(xy 86.392512 -329.357736) (xy 86.399909 -329.350888) (xy 86.418508 -329.343152) (xy 86.42858 -329.34275)
			(xy 92.002356 -329.34275) (xy 92.010553 -329.342448) (xy 92.026109 -329.337281) (xy 92.032836 -329.33259)
			(xy 92.038424 -329.327764) (xy 95.295212 -326.070976) (xy 95.302608 -326.064123) (xy 95.321206 -326.056381)
			(xy 95.33128 -326.05599) (xy 123.505976 -326.05599) (xy 123.51604 -326.056427) (xy 123.534626 -326.064159)
			(xy 123.542044 -326.070976) (xy 127.179578 -329.708256) (xy 131.751578 -329.708256) (xy 132.869178 -330.825856)
			(xy 133.416802 -331.373734) (xy 133.42239 -331.37856) (xy 133.42913 -331.383231) (xy 133.444676 -331.38842)
			(xy 133.45287 -331.38872) (xy 140.203428 -331.38872) (xy 140.5128 -331.079348) (xy 140.5128 -326.442324)
			(xy 138.702034 -324.631558) (xy 117.521482 -298.826428) (xy 117.521482 -297.680126) (xy 117.520991 -297.666447)
			(xy 117.513639 -297.640091) (xy 117.499561 -297.616628) (xy 117.479765 -297.597738) (xy 117.45567 -297.584774)
			(xy 117.428999 -297.578662) (xy 117.41531 -297.57878) (xy 117.397784 -297.579288) (xy 117.370414 -297.578815)
			(xy 117.316238 -297.570989) (xy 117.263735 -297.5555) (xy 117.213986 -297.532666) (xy 117.168011 -297.502955)
			(xy 117.147086 -297.485308) (xy 117.135758 -297.476072) (xy 117.109201 -297.463896) (xy 117.080284 -297.459723)
			(xy 117.051367 -297.463896) (xy 117.02481 -297.476072) (xy 117.013482 -297.485308) (xy 116.992549 -297.502949)
			(xy 116.946581 -297.532673) (xy 116.896835 -297.555519) (xy 116.844333 -297.571015) (xy 116.790155 -297.578844)
			(xy 116.735413 -297.578844) (xy 116.681235 -297.571015) (xy 116.628733 -297.555519) (xy 116.578987 -297.532673)
			(xy 116.533019 -297.502949) (xy 116.512086 -297.485308) (xy 116.500758 -297.476072) (xy 116.474201 -297.463896)
			(xy 116.445284 -297.459723) (xy 116.416367 -297.463896) (xy 116.38981 -297.476072) (xy 116.378482 -297.485308)
			(xy 116.35755 -297.502949) (xy 116.311583 -297.532672) (xy 116.261836 -297.555512) (xy 116.209333 -297.571)
			(xy 116.155154 -297.578815) (xy 116.127784 -297.579288) (xy 116.100535 -297.578801) (xy 116.046592 -297.571043)
			(xy 115.994302 -297.555687) (xy 115.944729 -297.533046) (xy 115.898883 -297.503581) (xy 115.857697 -297.467891)
			(xy 115.822009 -297.426704) (xy 115.792546 -297.380857) (xy 115.769907 -297.331283) (xy 115.754554 -297.278992)
			(xy 115.746798 -297.225049) (xy 115.746798 -297.170551) (xy 115.754554 -297.116608) (xy 115.769907 -297.064317)
			(xy 115.792546 -297.014743) (xy 115.822009 -296.968896) (xy 115.857697 -296.927709) (xy 115.898883 -296.892019)
			(xy 115.944729 -296.862554) (xy 115.994302 -296.839913) (xy 116.046592 -296.824557) (xy 116.100535 -296.816799)
			(xy 116.127784 -296.816272) (xy 116.155151 -296.81675) (xy 116.209323 -296.824586) (xy 116.261818 -296.840084)
			(xy 116.311559 -296.862927) (xy 116.357523 -296.892646) (xy 116.378482 -296.910252) (xy 116.38981 -296.919488)
			(xy 116.416367 -296.931664) (xy 116.445284 -296.935837) (xy 116.474201 -296.931664) (xy 116.500758 -296.919488)
			(xy 116.512086 -296.910252) (xy 116.533019 -296.892611) (xy 116.578987 -296.862887) (xy 116.628733 -296.840041)
			(xy 116.681235 -296.824545) (xy 116.735413 -296.816716) (xy 116.790155 -296.816716) (xy 116.844333 -296.824545)
			(xy 116.896835 -296.840041) (xy 116.946581 -296.862887) (xy 116.992549 -296.892611) (xy 117.013482 -296.910252)
			(xy 117.02481 -296.919488) (xy 117.051367 -296.931664) (xy 117.080284 -296.935837) (xy 117.109201 -296.931664)
			(xy 117.135758 -296.919488) (xy 117.147086 -296.910252) (xy 117.168016 -296.892607) (xy 117.213981 -296.862875)
			(xy 117.263728 -296.840027) (xy 117.316232 -296.824533) (xy 117.370413 -296.816711) (xy 117.397784 -296.816272)
			(xy 117.41531 -296.81678) (xy 117.429008 -296.816954) (xy 117.455707 -296.810874) (xy 117.479829 -296.797913)
			(xy 117.499637 -296.779006) (xy 117.513705 -296.755513) (xy 117.521021 -296.729125) (xy 117.521482 -296.715434)
			(xy 117.521482 -295.521126) (xy 117.520991 -295.507447) (xy 117.513639 -295.481091) (xy 117.499561 -295.457628)
			(xy 117.479765 -295.438738) (xy 117.45567 -295.425774) (xy 117.428999 -295.419662) (xy 117.41531 -295.41978)
			(xy 117.397784 -295.420288) (xy 117.370414 -295.419815) (xy 117.316238 -295.411989) (xy 117.263735 -295.3965)
			(xy 117.213986 -295.373666) (xy 117.168011 -295.343955) (xy 117.147086 -295.326308) (xy 117.135758 -295.317072)
			(xy 117.109201 -295.304896) (xy 117.080284 -295.300723) (xy 117.051367 -295.304896) (xy 117.02481 -295.317072)
			(xy 117.013482 -295.326308) (xy 116.992549 -295.343949) (xy 116.946581 -295.373673) (xy 116.896835 -295.396519)
			(xy 116.844333 -295.412015) (xy 116.790155 -295.419844) (xy 116.735413 -295.419844) (xy 116.681235 -295.412015)
			(xy 116.628733 -295.396519) (xy 116.578987 -295.373673) (xy 116.533019 -295.343949) (xy 116.512086 -295.326308)
			(xy 116.500758 -295.317072) (xy 116.474201 -295.304896) (xy 116.445284 -295.300723) (xy 116.416367 -295.304896)
			(xy 116.38981 -295.317072) (xy 116.378482 -295.326308) (xy 116.35755 -295.343949) (xy 116.311583 -295.373672)
			(xy 116.261836 -295.396512) (xy 116.209333 -295.412) (xy 116.155154 -295.419815) (xy 116.127784 -295.420288)
			(xy 116.100535 -295.419801) (xy 116.046592 -295.412043) (xy 115.994302 -295.396687) (xy 115.944729 -295.374046)
			(xy 115.898883 -295.344581) (xy 115.857697 -295.308891) (xy 115.822009 -295.267704) (xy 115.792546 -295.221857)
			(xy 115.769907 -295.172283) (xy 115.754554 -295.119992) (xy 115.746798 -295.066049) (xy 115.746798 -295.011551)
			(xy 115.754554 -294.957608) (xy 115.769907 -294.905317) (xy 115.792546 -294.855743) (xy 115.822009 -294.809896)
			(xy 115.857697 -294.768709) (xy 115.898883 -294.733019) (xy 115.944729 -294.703554) (xy 115.994302 -294.680913)
			(xy 116.046592 -294.665557) (xy 116.100535 -294.657799) (xy 116.127784 -294.657272) (xy 116.155151 -294.65775)
			(xy 116.209323 -294.665586) (xy 116.261818 -294.681084) (xy 116.311559 -294.703927) (xy 116.357523 -294.733646)
			(xy 116.378482 -294.751252) (xy 116.38981 -294.760488) (xy 116.416367 -294.772664) (xy 116.445284 -294.776837)
			(xy 116.474201 -294.772664) (xy 116.500758 -294.760488) (xy 116.512086 -294.751252) (xy 116.533019 -294.733611)
			(xy 116.578987 -294.703887) (xy 116.628733 -294.681041) (xy 116.681235 -294.665545) (xy 116.735413 -294.657716)
			(xy 116.790155 -294.657716) (xy 116.844333 -294.665545) (xy 116.896835 -294.681041) (xy 116.946581 -294.703887)
			(xy 116.992549 -294.733611) (xy 117.013482 -294.751252) (xy 117.02481 -294.760488) (xy 117.051367 -294.772664)
			(xy 117.080284 -294.776837) (xy 117.109201 -294.772664) (xy 117.135758 -294.760488) (xy 117.147086 -294.751252)
			(xy 117.168016 -294.733607) (xy 117.213981 -294.703875) (xy 117.263728 -294.681027) (xy 117.316232 -294.665533)
			(xy 117.370413 -294.657711) (xy 117.397784 -294.657272) (xy 117.41531 -294.65778) (xy 117.429008 -294.657954)
			(xy 117.455707 -294.651874) (xy 117.479829 -294.638913) (xy 117.499637 -294.620006) (xy 117.513705 -294.596513)
			(xy 117.521021 -294.570125) (xy 117.521482 -294.556434) (xy 117.521482 -293.438326) (xy 117.520991 -293.424647)
			(xy 117.513639 -293.398291) (xy 117.499561 -293.374828) (xy 117.479765 -293.355938) (xy 117.45567 -293.342974)
			(xy 117.428999 -293.336862) (xy 117.41531 -293.33698) (xy 117.397784 -293.337488) (xy 117.370414 -293.337015)
			(xy 117.316238 -293.329189) (xy 117.263735 -293.3137) (xy 117.213986 -293.290866) (xy 117.168011 -293.261155)
			(xy 117.147086 -293.243508) (xy 117.135758 -293.234272) (xy 117.109201 -293.222096) (xy 117.080284 -293.217923)
			(xy 117.051367 -293.222096) (xy 117.02481 -293.234272) (xy 117.013482 -293.243508) (xy 116.992549 -293.261149)
			(xy 116.946581 -293.290873) (xy 116.896835 -293.313719) (xy 116.844333 -293.329215) (xy 116.790155 -293.337044)
			(xy 116.735413 -293.337044) (xy 116.681235 -293.329215) (xy 116.628733 -293.313719) (xy 116.578987 -293.290873)
			(xy 116.533019 -293.261149) (xy 116.512086 -293.243508) (xy 116.500758 -293.234272) (xy 116.474201 -293.222096)
			(xy 116.445284 -293.217923) (xy 116.416367 -293.222096) (xy 116.38981 -293.234272) (xy 116.378482 -293.243508)
			(xy 116.35755 -293.261149) (xy 116.311583 -293.290872) (xy 116.261836 -293.313712) (xy 116.209333 -293.3292)
			(xy 116.155154 -293.337015) (xy 116.127784 -293.337488) (xy 116.100535 -293.337001) (xy 116.046592 -293.329243)
			(xy 115.994302 -293.313887) (xy 115.944729 -293.291246) (xy 115.898883 -293.261781) (xy 115.857697 -293.226091)
			(xy 115.822009 -293.184904) (xy 115.792546 -293.139057) (xy 115.769907 -293.089483) (xy 115.754554 -293.037192)
			(xy 115.746798 -292.983249) (xy 115.746798 -292.928751) (xy 115.754554 -292.874808) (xy 115.769907 -292.822517)
			(xy 115.792546 -292.772943) (xy 115.822009 -292.727096) (xy 115.857697 -292.685909) (xy 115.898883 -292.650219)
			(xy 115.944729 -292.620754) (xy 115.994302 -292.598113) (xy 116.046592 -292.582757) (xy 116.100535 -292.574999)
			(xy 116.127784 -292.574472) (xy 116.155151 -292.57495) (xy 116.209323 -292.582786) (xy 116.261818 -292.598284)
			(xy 116.311559 -292.621127) (xy 116.357523 -292.650846) (xy 116.378482 -292.668452) (xy 116.38981 -292.677688)
			(xy 116.416367 -292.689864) (xy 116.445284 -292.694037) (xy 116.474201 -292.689864) (xy 116.500758 -292.677688)
			(xy 116.512086 -292.668452) (xy 116.533019 -292.650811) (xy 116.578987 -292.621087) (xy 116.628733 -292.598241)
			(xy 116.681235 -292.582745) (xy 116.735413 -292.574916) (xy 116.790155 -292.574916) (xy 116.844333 -292.582745)
			(xy 116.896835 -292.598241) (xy 116.946581 -292.621087) (xy 116.992549 -292.650811) (xy 117.013482 -292.668452)
			(xy 117.02481 -292.677688) (xy 117.051367 -292.689864) (xy 117.080284 -292.694037) (xy 117.109201 -292.689864)
			(xy 117.135758 -292.677688) (xy 117.147086 -292.668452) (xy 117.168016 -292.650807) (xy 117.213981 -292.621075)
			(xy 117.263728 -292.598227) (xy 117.316232 -292.582733) (xy 117.370413 -292.574911) (xy 117.397784 -292.574472)
			(xy 117.41531 -292.57498) (xy 117.429008 -292.575154) (xy 117.455707 -292.569074) (xy 117.479829 -292.556113)
			(xy 117.499637 -292.537206) (xy 117.513705 -292.513713) (xy 117.521021 -292.487325) (xy 117.521482 -292.473634)
			(xy 117.521482 -291.310822) (xy 118.946422 -289.885882) (xy 118.942358 -289.860228) (xy 118.940336 -289.84705)
			(xy 118.938177 -289.820474) (xy 118.93804 -289.807142) (xy 118.938533 -289.781339) (xy 118.946551 -289.73036)
			(xy 118.962399 -289.681248) (xy 118.98569 -289.635197) (xy 119.015858 -289.593328) (xy 119.05217 -289.55666)
			(xy 119.093742 -289.526083) (xy 119.139563 -289.502343) (xy 119.188518 -289.486017) (xy 119.213884 -289.48126)
			(xy 119.256302 -289.474148) (xy 119.256302 -288.436304) (xy 119.213884 -288.429192) (xy 119.188502 -288.424437)
			(xy 119.139518 -288.408093) (xy 119.093671 -288.384333) (xy 119.052075 -288.353734) (xy 119.015742 -288.31704)
			(xy 118.985555 -288.275144) (xy 118.962249 -288.229065) (xy 118.946389 -288.179922) (xy 118.938362 -288.128912)
			(xy 118.938364 -288.077274) (xy 118.946393 -288.026263) (xy 118.962254 -287.977122) (xy 118.985563 -287.931043)
			(xy 119.015751 -287.889149) (xy 119.052086 -287.852457) (xy 119.093683 -287.82186) (xy 119.139532 -287.798101)
			(xy 119.188516 -287.78176) (xy 119.213884 -287.77692) (xy 119.256302 -287.769808) (xy 119.256302 -286.808418)
			(xy 119.213884 -286.801306) (xy 119.188529 -286.796539) (xy 119.139603 -286.780181) (xy 119.093813 -286.75642)
			(xy 119.052271 -286.725832) (xy 119.015987 -286.68916) (xy 118.985841 -286.647296) (xy 118.962567 -286.601257)
			(xy 118.946729 -286.55216) (xy 118.938712 -286.501198) (xy 118.938712 -286.44961) (xy 118.946727 -286.398648)
			(xy 118.962564 -286.349551) (xy 118.985837 -286.30351) (xy 119.015981 -286.261646) (xy 119.052265 -286.224973)
			(xy 119.093806 -286.194385) (xy 119.139596 -286.170622) (xy 119.188522 -286.154263) (xy 119.213884 -286.149542)
			(xy 119.256302 -286.14243) (xy 119.256302 -285.220918) (xy 119.230648 -285.176722) (xy 119.207788 -285.172404)
			(xy 119.182861 -285.167251) (xy 119.134866 -285.150304) (xy 119.090037 -285.126197) (xy 119.049436 -285.095499)
			(xy 119.014024 -285.058937) (xy 118.984639 -285.017377) (xy 118.961976 -284.971801) (xy 118.946571 -284.923289)
			(xy 118.938789 -284.872988) (xy 118.938294 -284.847538) (xy 118.938786 -284.821746) (xy 118.946795 -284.770787)
			(xy 118.962623 -284.721691) (xy 118.985887 -284.67565) (xy 119.016021 -284.633783) (xy 119.052294 -284.597106)
			(xy 119.093824 -284.566509) (xy 119.139604 -284.542737) (xy 119.188522 -284.526365) (xy 119.213884 -284.521656)
			(xy 119.256302 -284.514544) (xy 119.256302 -283.5529) (xy 119.213884 -283.545788) (xy 119.18852 -283.541034)
			(xy 119.139573 -283.524698) (xy 119.09376 -283.500951) (xy 119.052195 -283.470371) (xy 119.015889 -283.433703)
			(xy 118.985724 -283.391836) (xy 118.962435 -283.345789) (xy 118.946586 -283.296681) (xy 118.938564 -283.245707)
			(xy 118.93804 -283.219906) (xy 118.938475 -283.195823) (xy 118.945464 -283.148168) (xy 118.959295 -283.102032)
			(xy 118.979676 -283.058391) (xy 119.006174 -283.01817) (xy 119.038229 -282.982221) (xy 119.056404 -282.966414)
			(xy 119.066864 -282.957024) (xy 119.082623 -282.93376) (xy 119.091452 -282.907084) (xy 119.092687 -282.879012)
			(xy 119.086232 -282.851665) (xy 119.072577 -282.827107) (xy 119.063008 -282.816808) (xy 118.948454 -282.702254)
			(xy 118.917466 -282.714192) (xy 118.888831 -282.724484) (xy 118.829015 -282.735609) (xy 118.798594 -282.73629)
			(xy 118.772626 -282.73578) (xy 118.72133 -282.727655) (xy 118.671936 -282.711607) (xy 118.62566 -282.688029)
			(xy 118.583642 -282.657504) (xy 118.546916 -282.620781) (xy 118.516386 -282.578766) (xy 118.492805 -282.532492)
			(xy 118.476752 -282.4831) (xy 118.468622 -282.431804) (xy 118.46814 -282.405836) (xy 118.468827 -282.375415)
			(xy 118.479941 -282.315597) (xy 118.490238 -282.286964) (xy 118.502176 -282.255976) (xy 117.878352 -281.632152)
			(xy 117.867228 -281.621732) (xy 117.840301 -281.60748) (xy 117.810369 -281.6018) (xy 117.780093 -281.605198)
			(xy 117.752164 -281.617372) (xy 117.729067 -281.63724) (xy 117.712855 -281.663034) (xy 117.708426 -281.677618)
			(xy 117.700874 -281.703593) (xy 117.678499 -281.752838) (xy 117.648411 -281.797788) (xy 117.611411 -281.837243)
			(xy 117.568486 -281.870154) (xy 117.520778 -281.895643) (xy 117.469558 -281.913031) (xy 117.416193 -281.921855)
			(xy 117.389148 -281.922474) (xy 117.363176 -281.921995) (xy 117.31187 -281.913876) (xy 117.262465 -281.89783)
			(xy 117.21618 -281.874254) (xy 117.174152 -281.843726) (xy 117.137418 -281.807) (xy 117.106882 -281.764978)
			(xy 117.083296 -281.718698) (xy 117.06724 -281.669297) (xy 117.059111 -281.617992) (xy 117.058694 -281.59202)
			(xy 117.059225 -281.564965) (xy 117.06802 -281.511574) (xy 117.085394 -281.460329) (xy 117.110884 -281.412598)
			(xy 117.143808 -281.369657) (xy 117.183287 -281.332653) (xy 117.228267 -281.302574) (xy 117.277545 -281.280223)
			(xy 117.30355 -281.272742) (xy 117.318085 -281.268226) (xy 117.343812 -281.251995) (xy 117.363625 -281.228913)
			(xy 117.37577 -281.201024) (xy 117.379173 -281.170795) (xy 117.373532 -281.140904) (xy 117.359346 -281.113995)
			(xy 117.349016 -281.102816) (xy 117.276626 -281.030426) (xy 117.265408 -281.019935) (xy 117.238236 -281.005644)
			(xy 117.208042 -281.000088) (xy 117.177563 -281.003773) (xy 117.149563 -281.016363) (xy 117.137688 -281.026108)
			(xy 117.119502 -281.041591) (xy 117.079509 -281.067699) (xy 117.03617 -281.087771) (xy 116.990392 -281.101387)
			(xy 116.943128 -281.108263) (xy 116.919248 -281.108658) (xy 116.893276 -281.108179) (xy 116.841971 -281.10006)
			(xy 116.792568 -281.084014) (xy 116.746283 -281.060437) (xy 116.704257 -281.029909) (xy 116.667525 -280.993183)
			(xy 116.63699 -280.951161) (xy 116.613406 -280.90488) (xy 116.597352 -280.85548) (xy 116.589225 -280.804176)
			(xy 116.588794 -280.778204) (xy 116.589215 -280.754324) (xy 116.59609 -280.707062) (xy 116.609699 -280.661283)
			(xy 116.629757 -280.61794) (xy 116.655847 -280.577936) (xy 116.671344 -280.559764) (xy 116.681077 -280.547896)
			(xy 116.69359 -280.519884) (xy 116.697243 -280.489422) (xy 116.691707 -280.459246) (xy 116.67748 -280.432064)
			(xy 116.667026 -280.420826) (xy 116.53139 -280.28519) (xy 116.505482 -280.289762) (xy 116.491559 -280.292027)
			(xy 116.463453 -280.29444) (xy 116.449348 -280.294588) (xy 116.423375 -280.294109) (xy 116.372068 -280.28599)
			(xy 116.322663 -280.269945) (xy 116.276376 -280.246368) (xy 116.234348 -280.215841) (xy 116.197612 -280.179115)
			(xy 116.167075 -280.137094) (xy 116.143487 -280.090813) (xy 116.127429 -280.041412) (xy 116.119298 -279.990107)
			(xy 116.118894 -279.964134) (xy 116.119057 -279.95003) (xy 116.121472 -279.921925) (xy 116.12372 -279.908)
			(xy 116.128292 -279.882092) (xy 115.504214 -279.258014) (xy 115.493983 -279.248396) (xy 115.469493 -279.234679)
			(xy 115.442194 -279.228147) (xy 115.414147 -279.229292) (xy 115.387472 -279.23803) (xy 115.364183 -279.253699)
			(xy 115.346039 -279.275117) (xy 115.339876 -279.287732) (xy 115.328172 -279.31203) (xy 115.298069 -279.356777)
			(xy 115.261103 -279.396044) (xy 115.218252 -279.428789) (xy 115.170654 -279.454144) (xy 115.119571 -279.471436)
			(xy 115.066359 -279.480206) (xy 115.039394 -279.480772) (xy 115.013427 -279.480262) (xy 114.962131 -279.472137)
			(xy 114.912738 -279.456088) (xy 114.866464 -279.432511) (xy 114.824447 -279.401985) (xy 114.787723 -279.365262)
			(xy 114.757196 -279.323246) (xy 114.733616 -279.276973) (xy 114.717565 -279.22758) (xy 114.709439 -279.176285)
			(xy 114.70894 -279.150318) (xy 114.709473 -279.12335) (xy 114.718232 -279.070129) (xy 114.73552 -279.019039)
			(xy 114.760877 -278.971435) (xy 114.793631 -278.928582) (xy 114.832911 -278.89162) (xy 114.877673 -278.861529)
			(xy 114.90198 -278.849836) (xy 114.914563 -278.843612) (xy 114.935971 -278.825467) (xy 114.951637 -278.802184)
			(xy 114.960382 -278.775519) (xy 114.961546 -278.74748) (xy 114.955041 -278.720182) (xy 114.941358 -278.695681)
			(xy 114.931698 -278.685498) (xy 114.812064 -278.565864) (xy 114.776504 -278.594312) (xy 114.754345 -278.611342)
			(xy 114.705496 -278.638481) (xy 114.652776 -278.657013) (xy 114.597689 -278.666408) (xy 114.569748 -278.666956)
			(xy 114.543776 -278.666477) (xy 114.492471 -278.658358) (xy 114.443068 -278.642312) (xy 114.396784 -278.618735)
			(xy 114.354758 -278.588207) (xy 114.318025 -278.55148) (xy 114.287491 -278.509459) (xy 114.263907 -278.463178)
			(xy 114.247854 -278.413778) (xy 114.239727 -278.362474) (xy 114.239294 -278.336502) (xy 114.239822 -278.309618)
			(xy 114.248533 -278.25656) (xy 114.265726 -278.205614) (xy 114.290945 -278.158126) (xy 114.323525 -278.115352)
			(xy 114.342672 -278.096472) (xy 114.342418 -278.096218) (xy 114.349585 -278.088745) (xy 114.357733 -278.069732)
			(xy 114.358166 -278.059388) (xy 114.358166 -276.98573) (xy 114.342672 -276.949154) (xy 114.34191 -276.948392)
			(xy 114.338608 -276.945344) (xy 114.33556 -276.942296) (xy 114.317592 -276.923555) (xy 114.28713 -276.881515)
			(xy 114.263603 -276.835235) (xy 114.247591 -276.785849) (xy 114.239484 -276.73457) (xy 114.239482 -276.682653)
			(xy 114.247585 -276.631373) (xy 114.263595 -276.581986) (xy 114.287118 -276.535705) (xy 114.317577 -276.493663)
			(xy 114.33556 -276.474936) (xy 114.338608 -276.471888) (xy 114.34191 -276.46884) (xy 114.342672 -276.468078)
			(xy 114.358166 -276.431502) (xy 114.358166 -276.296882) (xy 114.357414 -276.285659) (xy 114.347531 -276.265483)
			(xy 114.339116 -276.25802) (xy 114.336068 -276.255734) (xy 114.305842 -276.23516) (xy 114.264186 -276.206712)
			(xy 114.25942 -276.203986) (xy 114.249045 -276.200394) (xy 114.243612 -276.1996) (xy 114.236754 -276.198838)
			(xy 114.224308 -276.201378) (xy 114.21999 -276.202902) (xy 114.219736 -276.202902) (xy 114.219228 -276.203156)
			(xy 114.190496 -276.213602) (xy 114.130413 -276.224858) (xy 114.099848 -276.225508) (xy 114.073856 -276.225028)
			(xy 114.022512 -276.216903) (xy 113.973071 -276.200845) (xy 113.926751 -276.17725) (xy 113.884693 -276.146699)
			(xy 113.847933 -276.109944) (xy 113.817375 -276.06789) (xy 113.793773 -276.021573) (xy 113.777708 -275.972135)
			(xy 113.769575 -275.920792) (xy 113.769575 -275.868808) (xy 113.777708 -275.817465) (xy 113.793773 -275.768027)
			(xy 113.817375 -275.72171) (xy 113.847933 -275.679656) (xy 113.884693 -275.642901) (xy 113.926751 -275.61235)
			(xy 113.973071 -275.588755) (xy 114.022512 -275.572697) (xy 114.073856 -275.564572) (xy 114.099848 -275.564092)
			(xy 114.126336 -275.564619) (xy 114.178633 -275.573071) (xy 114.228914 -275.589753) (xy 114.275892 -275.614237)
			(xy 114.29746 -275.629624) (xy 114.304826 -275.634958) (xy 114.322352 -275.640038) (xy 114.330988 -275.63953)
			(xy 114.340094 -275.638556) (xy 114.356759 -275.630998) (xy 114.3635 -275.624798) (xy 114.475006 -275.513292)
			(xy 114.479832 -275.507704) (xy 114.484505 -275.500965) (xy 114.489695 -275.485419) (xy 114.489992 -275.477224)
			(xy 114.489992 -275.439124) (xy 114.489774 -275.432083) (xy 114.485916 -275.418541) (xy 114.482372 -275.412454)
			(xy 114.475514 -275.406866) (xy 114.44933 -275.398792) (xy 114.39979 -275.375389) (xy 114.354652 -275.344331)
			(xy 114.31509 -275.306426) (xy 114.28213 -275.262658) (xy 114.25663 -275.214164) (xy 114.239251 -275.162203)
			(xy 114.230445 -275.108125) (xy 114.229896 -275.08073) (xy 114.23039 -275.054062) (xy 114.23873 -275.001381)
			(xy 114.255209 -274.950654) (xy 114.279422 -274.90313) (xy 114.310772 -274.85998) (xy 114.348488 -274.822266)
			(xy 114.391639 -274.790917) (xy 114.439164 -274.766705) (xy 114.489891 -274.750227) (xy 114.542572 -274.741889)
			(xy 114.56924 -274.741386) (xy 114.597099 -274.741951) (xy 114.652069 -274.751061) (xy 114.704811 -274.769029)
			(xy 114.753909 -274.795373) (xy 114.798043 -274.829384) (xy 114.836028 -274.870149) (xy 114.851942 -274.893024)
			(xy 114.862864 -274.895818) (xy 114.942874 -274.900898) (xy 114.947446 -274.900898) (xy 114.957018 -274.900201)
			(xy 114.974633 -274.892622) (xy 114.981736 -274.886166) (xy 115.17884 -274.689062) (xy 115.183666 -274.683474)
			(xy 115.188332 -274.676733) (xy 115.19351 -274.661187) (xy 115.193826 -274.652994) (xy 115.193826 -274.634198)
			(xy 115.193338 -274.624189) (xy 115.185679 -274.605693) (xy 115.171527 -274.591534) (xy 115.153035 -274.583867)
			(xy 115.143026 -274.583398) (xy 115.135914 -274.583398) (xy 115.12931 -274.585176) (xy 115.107289 -274.590998)
			(xy 115.062169 -274.597245) (xy 115.039394 -274.597622) (xy 115.013406 -274.597112) (xy 114.96207 -274.58898)
			(xy 114.912638 -274.572918) (xy 114.866328 -274.549321) (xy 114.824279 -274.51877) (xy 114.787526 -274.482017)
			(xy 114.756976 -274.439967) (xy 114.73338 -274.393656) (xy 114.717318 -274.344224) (xy 114.709188 -274.292888)
			(xy 114.709188 -274.240912) (xy 114.717318 -274.189576) (xy 114.73338 -274.140144) (xy 114.756976 -274.093833)
			(xy 114.787526 -274.051783) (xy 114.824279 -274.01503) (xy 114.866328 -273.984479) (xy 114.912638 -273.960882)
			(xy 114.96207 -273.94482) (xy 115.013406 -273.936688) (xy 115.039394 -273.936206) (xy 115.049517 -273.936298)
			(xy 115.069725 -273.937568) (xy 115.07978 -273.938746) (xy 115.080034 -273.938746) (xy 115.090758 -273.939405)
			(xy 115.111229 -273.932964) (xy 115.119658 -273.9263) (xy 115.13439 -273.913346) (xy 115.178078 -273.874992)
			(xy 115.18392 -273.868134) (xy 115.187775 -273.862569) (xy 115.192669 -273.849951) (xy 115.193572 -273.843242)
			(xy 115.193826 -273.840702) (xy 115.193826 -273.552666) (xy 115.191794 -273.545554) (xy 115.185636 -273.522937)
			(xy 115.17901 -273.476534) (xy 115.178586 -273.453098) (xy 115.178991 -273.42966) (xy 115.185616 -273.383255)
			(xy 115.191794 -273.360642) (xy 115.193826 -273.35353) (xy 115.193826 -273.065494) (xy 115.193572 -273.062954)
			(xy 115.192647 -273.056251) (xy 115.187748 -273.043642) (xy 115.18392 -273.038062) (xy 115.178332 -273.031458)
			(xy 115.117626 -272.978372) (xy 115.111992 -272.97408) (xy 115.098971 -272.968525) (xy 115.091972 -272.96745)
			(xy 115.07978 -272.96745) (xy 115.069725 -272.968626) (xy 115.049517 -272.969899) (xy 115.039394 -272.96999)
			(xy 115.013409 -272.96948) (xy 114.962078 -272.961349) (xy 114.912651 -272.945289) (xy 114.866344 -272.921694)
			(xy 114.824299 -272.891145) (xy 114.787551 -272.854396) (xy 114.757003 -272.812351) (xy 114.733409 -272.766044)
			(xy 114.717349 -272.716617) (xy 114.709219 -272.665285) (xy 114.709219 -272.613315) (xy 114.717349 -272.561983)
			(xy 114.733409 -272.512556) (xy 114.757003 -272.466249) (xy 114.787551 -272.424204) (xy 114.824299 -272.387455)
			(xy 114.866344 -272.356906) (xy 114.912651 -272.333311) (xy 114.962078 -272.317251) (xy 115.013409 -272.30912)
			(xy 115.039394 -272.308574) (xy 115.049517 -272.308666) (xy 115.069725 -272.309936) (xy 115.07978 -272.311114)
			(xy 115.080034 -272.311114) (xy 115.090759 -272.311774) (xy 115.111234 -272.30534) (xy 115.119658 -272.298668)
			(xy 115.13439 -272.285714) (xy 115.178078 -272.24736) (xy 115.18392 -272.240502) (xy 115.187772 -272.234936)
			(xy 115.192657 -272.222317) (xy 115.193572 -272.21561) (xy 115.193826 -272.21307) (xy 115.193826 -271.924018)
			(xy 115.191794 -271.916906) (xy 115.185733 -271.894469) (xy 115.179229 -271.84845) (xy 115.179228 -271.801973)
			(xy 115.185728 -271.755954) (xy 115.191794 -271.733518) (xy 115.193826 -271.726406) (xy 115.193826 -271.437608)
			(xy 115.193572 -271.435068) (xy 115.192649 -271.428364) (xy 115.187753 -271.415753) (xy 115.18392 -271.410176)
			(xy 115.178332 -271.403572) (xy 115.117626 -271.350486) (xy 115.111989 -271.346201) (xy 115.098968 -271.340655)
			(xy 115.091972 -271.339564) (xy 115.07978 -271.339564) (xy 115.069725 -271.34074) (xy 115.049517 -271.342013)
			(xy 115.039394 -271.342104) (xy 115.013407 -271.341594) (xy 114.962074 -271.333463) (xy 114.912645 -271.317401)
			(xy 114.866337 -271.293806) (xy 114.82429 -271.263256) (xy 114.78754 -271.226505) (xy 114.756991 -271.184458)
			(xy 114.733396 -271.138149) (xy 114.717336 -271.08872) (xy 114.709206 -271.037387) (xy 114.709206 -270.985413)
			(xy 114.717336 -270.93408) (xy 114.733396 -270.884651) (xy 114.756991 -270.838342) (xy 114.78754 -270.796295)
			(xy 114.82429 -270.759544) (xy 114.866337 -270.728994) (xy 114.912645 -270.705399) (xy 114.962074 -270.689337)
			(xy 115.013407 -270.681206) (xy 115.039394 -270.680688) (xy 115.049517 -270.68078) (xy 115.069725 -270.68205)
			(xy 115.07978 -270.683228) (xy 115.080034 -270.683228) (xy 115.090758 -270.683887) (xy 115.111227 -270.677444)
			(xy 115.119658 -270.670782) (xy 115.13439 -270.657828) (xy 115.178078 -270.619474) (xy 115.18392 -270.612616)
			(xy 115.187773 -270.60705) (xy 115.192662 -270.594432) (xy 115.193572 -270.587724) (xy 115.193826 -270.585184)
			(xy 115.193826 -270.297148) (xy 115.191794 -270.290036) (xy 115.185637 -270.267419) (xy 115.179013 -270.221016)
			(xy 115.178586 -270.19758) (xy 115.178992 -270.174142) (xy 115.18562 -270.127738) (xy 115.191794 -270.105124)
			(xy 115.193826 -270.098012) (xy 115.193826 -269.809722) (xy 115.193572 -269.807182) (xy 115.19265 -269.800478)
			(xy 115.187757 -269.787865) (xy 115.18392 -269.78229) (xy 115.178332 -269.775686) (xy 115.117626 -269.7226)
			(xy 115.11199 -269.718314) (xy 115.098968 -269.712767) (xy 115.091972 -269.711678) (xy 115.07978 -269.711678)
			(xy 115.069725 -269.712854) (xy 115.049517 -269.714127) (xy 115.039394 -269.714218) (xy 115.013406 -269.713708)
			(xy 114.962071 -269.705576) (xy 114.91264 -269.689514) (xy 114.86633 -269.665918) (xy 114.824281 -269.635367)
			(xy 114.787529 -269.598614) (xy 114.756979 -269.556565) (xy 114.733383 -269.510255) (xy 114.717322 -269.460823)
			(xy 114.709192 -269.409488) (xy 114.709192 -269.357512) (xy 114.717322 -269.306177) (xy 114.733383 -269.256745)
			(xy 114.756979 -269.210435) (xy 114.787529 -269.168386) (xy 114.824281 -269.131633) (xy 114.86633 -269.101082)
			(xy 114.91264 -269.077486) (xy 114.962071 -269.061424) (xy 115.013406 -269.053292) (xy 115.039394 -269.052802)
			(xy 115.049517 -269.052894) (xy 115.069725 -269.054164) (xy 115.07978 -269.055342) (xy 115.080034 -269.055342)
			(xy 115.090758 -269.056001) (xy 115.111228 -269.04956) (xy 115.119658 -269.042896) (xy 115.13439 -269.029942)
			(xy 115.178078 -268.991588) (xy 115.18392 -268.98473) (xy 115.187775 -268.979165) (xy 115.192667 -268.966547)
			(xy 115.193572 -268.959838) (xy 115.193826 -268.957298) (xy 115.193826 -268.6685) (xy 115.191794 -268.661388)
			(xy 115.185734 -268.638951) (xy 115.179233 -268.592932) (xy 115.179234 -268.546456) (xy 115.185737 -268.500438)
			(xy 115.191794 -268.478) (xy 115.193826 -268.470888) (xy 115.193826 -268.18209) (xy 115.193572 -268.17955)
			(xy 115.192646 -268.172847) (xy 115.187747 -268.160239) (xy 115.18392 -268.154658) (xy 115.178332 -268.148054)
			(xy 115.117626 -268.094968) (xy 115.111992 -268.090677) (xy 115.098971 -268.085122) (xy 115.091972 -268.084046)
			(xy 115.07978 -268.084046) (xy 115.069725 -268.085222) (xy 115.049517 -268.086495) (xy 115.039394 -268.086586)
			(xy 115.013409 -268.086076) (xy 114.962079 -268.077945) (xy 114.912652 -268.061885) (xy 114.866346 -268.03829)
			(xy 114.824302 -268.007742) (xy 114.787554 -267.970994) (xy 114.757007 -267.928948) (xy 114.733413 -267.882642)
			(xy 114.717353 -267.833216) (xy 114.709223 -267.781885) (xy 114.709223 -267.729915) (xy 114.717353 -267.678584)
			(xy 114.733413 -267.629158) (xy 114.757007 -267.582852) (xy 114.787554 -267.540806) (xy 114.824302 -267.504058)
			(xy 114.866346 -267.47351) (xy 114.912652 -267.449915) (xy 114.962079 -267.433855) (xy 115.013409 -267.425724)
			(xy 115.039394 -267.42517) (xy 115.049517 -267.425262) (xy 115.069725 -267.426532) (xy 115.07978 -267.42771)
			(xy 115.080034 -267.42771) (xy 115.090759 -267.42837) (xy 115.111234 -267.421935) (xy 115.119658 -267.415264)
			(xy 115.13439 -267.40231) (xy 115.178078 -267.363956) (xy 115.18392 -267.357098) (xy 115.187771 -267.351531)
			(xy 115.192656 -267.338913) (xy 115.193572 -267.332206) (xy 115.193826 -267.329666) (xy 115.193826 -267.040614)
			(xy 115.191794 -267.033502) (xy 115.185733 -267.011065) (xy 115.17923 -266.965046) (xy 115.179229 -266.91857)
			(xy 115.18573 -266.87255) (xy 115.191794 -266.850114) (xy 115.193826 -266.843002) (xy 115.193826 -266.554458)
			(xy 115.193572 -266.551918) (xy 115.192655 -266.545212) (xy 115.187769 -266.532594) (xy 115.18392 -266.527026)
			(xy 115.178332 -266.520422) (xy 115.117626 -266.467336) (xy 115.111991 -266.463047) (xy 115.09897 -266.457496)
			(xy 115.091972 -266.456414) (xy 115.07978 -266.456414) (xy 115.069725 -266.45759) (xy 115.049517 -266.458863)
			(xy 115.039394 -266.458954) (xy 115.013404 -266.458444) (xy 114.962063 -266.450311) (xy 114.912626 -266.434248)
			(xy 114.866311 -266.410648) (xy 114.824258 -266.380094) (xy 114.787502 -266.343338) (xy 114.756949 -266.301284)
			(xy 114.73335 -266.254968) (xy 114.717287 -266.205532) (xy 114.709156 -266.15419) (xy 114.709156 -266.10221)
			(xy 114.717287 -266.050868) (xy 114.73335 -266.001432) (xy 114.756949 -265.955116) (xy 114.787502 -265.913062)
			(xy 114.824258 -265.876306) (xy 114.866311 -265.845752) (xy 114.912626 -265.822152) (xy 114.962063 -265.806089)
			(xy 115.013404 -265.797956) (xy 115.039394 -265.797538) (xy 115.049517 -265.79763) (xy 115.069725 -265.7989)
			(xy 115.07978 -265.800078) (xy 115.080034 -265.800078) (xy 115.090759 -265.800738) (xy 115.111231 -265.7943)
			(xy 115.119658 -265.787632) (xy 115.13439 -265.774678) (xy 115.178078 -265.736324) (xy 115.18392 -265.729466)
			(xy 115.187779 -265.723902) (xy 115.19268 -265.711286) (xy 115.193572 -265.704574) (xy 115.193826 -265.702034)
			(xy 115.193826 -265.412982) (xy 115.191794 -265.40587) (xy 115.185735 -265.383433) (xy 115.179237 -265.337414)
			(xy 115.17924 -265.290939) (xy 115.185745 -265.244922) (xy 115.191794 -265.222482) (xy 115.193826 -265.21537)
			(xy 115.193826 -264.926572) (xy 115.193572 -264.924032) (xy 115.192644 -264.91733) (xy 115.187741 -264.904725)
			(xy 115.18392 -264.89914) (xy 115.178332 -264.892536) (xy 115.117626 -264.83945) (xy 115.111991 -264.83516)
			(xy 115.098971 -264.829607) (xy 115.091972 -264.828528) (xy 115.07978 -264.828528) (xy 115.069725 -264.829704)
			(xy 115.049517 -264.830977) (xy 115.039394 -264.831068) (xy 115.01341 -264.830558) (xy 114.962083 -264.822427)
			(xy 114.912659 -264.806368) (xy 114.866356 -264.782774) (xy 114.824314 -264.752228) (xy 114.787568 -264.715481)
			(xy 114.757022 -264.673439) (xy 114.73343 -264.627135) (xy 114.717371 -264.577711) (xy 114.709242 -264.526384)
			(xy 114.709242 -264.474416) (xy 114.717371 -264.423089) (xy 114.73343 -264.373665) (xy 114.757022 -264.327361)
			(xy 114.787568 -264.285319) (xy 114.824314 -264.248572) (xy 114.866356 -264.218026) (xy 114.912659 -264.194432)
			(xy 114.962083 -264.178373) (xy 115.01341 -264.170242) (xy 115.039394 -264.169652) (xy 115.049517 -264.169744)
			(xy 115.069725 -264.171014) (xy 115.07978 -264.172192) (xy 115.080034 -264.172192) (xy 115.090759 -264.172852)
			(xy 115.111232 -264.166415) (xy 115.119658 -264.159746) (xy 115.13439 -264.146792) (xy 115.178078 -264.108438)
			(xy 115.18392 -264.10158) (xy 115.18778 -264.096016) (xy 115.192685 -264.0834) (xy 115.193572 -264.076688)
			(xy 115.193826 -264.074148) (xy 115.193826 -263.78535) (xy 115.191794 -263.778238) (xy 115.185731 -263.755801)
			(xy 115.179222 -263.709781) (xy 115.179217 -263.663303) (xy 115.185713 -263.617282) (xy 115.191794 -263.59485)
			(xy 115.193826 -263.587738) (xy 115.193826 -262.814054) (xy 115.194258 -262.803988) (xy 115.201987 -262.785398)
			(xy 115.208812 -262.777986) (xy 116.013992 -261.972806) (xy 116.017802 -261.964678) (xy 116.030551 -261.938905)
			(xy 116.063563 -261.891834) (xy 116.104216 -261.851179) (xy 116.151285 -261.818163) (xy 116.17706 -261.80542)
			(xy 116.185188 -261.80161) (xy 116.1923 -261.794498) (xy 116.199699 -261.787652) (xy 116.218296 -261.779918)
			(xy 116.228368 -261.779512) (xy 116.257832 -261.779512) (xy 116.26215 -261.77875) (xy 116.275827 -261.776593)
			(xy 116.303423 -261.774307) (xy 116.317268 -261.774178) (xy 116.331113 -261.774311) (xy 116.358709 -261.776596)
			(xy 116.372386 -261.77875) (xy 116.376704 -261.779512) (xy 118.408196 -261.779512) (xy 118.417459 -261.778556)
			(xy 118.434405 -261.770875) (xy 118.441216 -261.764526) (xy 118.511066 -261.694422) (xy 118.518078 -261.686664)
			(xy 118.525701 -261.667214) (xy 118.524943 -261.646338) (xy 118.515928 -261.627492) (xy 118.500151 -261.6138)
			(xy 118.480225 -261.607528) (xy 118.45945 -261.609715) (xy 118.450106 -261.614412) (xy 118.449598 -261.614666)
			(xy 118.424103 -261.628869) (xy 118.369346 -261.64904) (xy 118.311897 -261.659278) (xy 118.28272 -261.659878)
			(xy 118.255427 -261.65929) (xy 118.201589 -261.650276) (xy 118.149958 -261.632556) (xy 118.101931 -261.606608)
			(xy 118.05881 -261.573137) (xy 118.039896 -261.553452) (xy 118.036594 -261.55015) (xy 118.029888 -261.544581)
			(xy 118.013782 -261.537945) (xy 118.005098 -261.537196) (xy 117.925342 -261.537196) (xy 117.916492 -261.538025)
			(xy 117.900124 -261.544917) (xy 117.893338 -261.550658) (xy 117.890544 -261.553452) (xy 117.873386 -261.571374)
			(xy 117.834654 -261.60238) (xy 117.791723 -261.627249) (xy 117.745558 -261.645422) (xy 117.697194 -261.656493)
			(xy 117.64772 -261.66021) (xy 117.598246 -261.656493) (xy 117.549882 -261.645422) (xy 117.503717 -261.627249)
			(xy 117.460786 -261.60238) (xy 117.422054 -261.571374) (xy 117.404896 -261.553452) (xy 117.402102 -261.550658)
			(xy 117.39532 -261.544914) (xy 117.378946 -261.538039) (xy 117.370098 -261.537196) (xy 117.290342 -261.537196)
			(xy 117.281492 -261.538025) (xy 117.265124 -261.544917) (xy 117.258338 -261.550658) (xy 117.255544 -261.553452)
			(xy 117.238386 -261.571374) (xy 117.199654 -261.60238) (xy 117.156723 -261.627249) (xy 117.110558 -261.645422)
			(xy 117.062194 -261.656493) (xy 117.01272 -261.66021) (xy 116.963246 -261.656493) (xy 116.914882 -261.645422)
			(xy 116.868717 -261.627249) (xy 116.825786 -261.60238) (xy 116.787054 -261.571374) (xy 116.769896 -261.553452)
			(xy 116.767102 -261.550658) (xy 116.76032 -261.544914) (xy 116.743946 -261.538039) (xy 116.735098 -261.537196)
			(xy 116.655342 -261.537196) (xy 116.64667 -261.537993) (xy 116.63058 -261.544626) (xy 116.623846 -261.55015)
			(xy 116.620544 -261.553452) (xy 116.601658 -261.573173) (xy 116.558561 -261.606699) (xy 116.510532 -261.632671)
			(xy 116.458882 -261.650379) (xy 116.405021 -261.659341) (xy 116.37772 -261.659878) (xy 116.351732 -261.659396)
			(xy 116.300396 -261.651268) (xy 116.250963 -261.635209) (xy 116.204651 -261.611615) (xy 116.162601 -261.581066)
			(xy 116.125847 -261.544314) (xy 116.095296 -261.502266) (xy 116.071698 -261.455956) (xy 116.055636 -261.406524)
			(xy 116.047505 -261.355188) (xy 116.047505 -261.303212) (xy 116.055636 -261.251876) (xy 116.071698 -261.202444)
			(xy 116.095296 -261.156134) (xy 116.125847 -261.114086) (xy 116.162601 -261.077334) (xy 116.204651 -261.046785)
			(xy 116.250963 -261.023191) (xy 116.300396 -261.007132) (xy 116.351732 -260.999004) (xy 116.37772 -260.998462)
			(xy 116.405011 -260.999054) (xy 116.458845 -261.008074) (xy 116.510471 -261.0258) (xy 116.55849 -261.051753)
			(xy 116.601603 -261.08523) (xy 116.620544 -261.104888) (xy 116.623846 -261.10819) (xy 116.630556 -261.11375)
			(xy 116.646662 -261.120368) (xy 116.655342 -261.121144) (xy 116.735098 -261.121144) (xy 116.743953 -261.120326)
			(xy 116.760338 -261.113452) (xy 116.767102 -261.107682) (xy 116.769896 -261.104888) (xy 116.787054 -261.086966)
			(xy 116.825786 -261.05596) (xy 116.868717 -261.031091) (xy 116.914882 -261.012918) (xy 116.963246 -261.001847)
			(xy 117.01272 -260.99813) (xy 117.062194 -261.001847) (xy 117.110558 -261.012918) (xy 117.156723 -261.031091)
			(xy 117.199654 -261.05596) (xy 117.238386 -261.086966) (xy 117.255544 -261.104888) (xy 117.258338 -261.107682)
			(xy 117.265114 -261.11344) (xy 117.281487 -261.120342) (xy 117.290342 -261.121144) (xy 117.370098 -261.121144)
			(xy 117.378953 -261.120326) (xy 117.395338 -261.113452) (xy 117.402102 -261.107682) (xy 117.404896 -261.104888)
			(xy 117.422054 -261.086966) (xy 117.460786 -261.05596) (xy 117.503717 -261.031091) (xy 117.549882 -261.012918)
			(xy 117.598246 -261.001847) (xy 117.64772 -260.99813) (xy 117.697194 -261.001847) (xy 117.745558 -261.012918)
			(xy 117.791723 -261.031091) (xy 117.834654 -261.05596) (xy 117.873386 -261.086966) (xy 117.890544 -261.104888)
			(xy 117.893338 -261.107682) (xy 117.900114 -261.11344) (xy 117.916487 -261.120342) (xy 117.925342 -261.121144)
			(xy 118.005098 -261.121144) (xy 118.013775 -261.120358) (xy 118.029881 -261.113742) (xy 118.036594 -261.10819)
			(xy 118.039896 -261.104888) (xy 118.058783 -261.085166) (xy 118.10188 -261.051638) (xy 118.149908 -261.025663)
			(xy 118.201557 -261.007949) (xy 118.255418 -260.998979) (xy 118.28272 -260.998462) (xy 118.308707 -260.998973)
			(xy 118.360041 -261.007106) (xy 118.409471 -261.023168) (xy 118.45578 -261.046765) (xy 118.497827 -261.077314)
			(xy 118.534579 -261.114065) (xy 118.56513 -261.156112) (xy 118.588728 -261.20242) (xy 118.604792 -261.251849)
			(xy 118.612926 -261.303183) (xy 118.613428 -261.32917) (xy 118.61292 -261.349744) (xy 118.61292 -261.350252)
			(xy 118.61673 -261.365492) (xy 118.620794 -261.372096) (xy 118.625027 -261.378421) (xy 118.63653 -261.388379)
			(xy 118.6434 -261.391654) (xy 118.730268 -261.429754) (xy 118.739743 -261.433397) (xy 118.760026 -261.433684)
			(xy 118.778849 -261.426125) (xy 118.786402 -261.41934) (xy 119.86514 -260.340602) (xy 119.869966 -260.335014)
			(xy 119.874637 -260.328274) (xy 119.879827 -260.312728) (xy 119.880126 -260.304534) (xy 119.880126 -258.115308)
			(xy 119.879629 -258.105866) (xy 119.872717 -258.088284) (xy 119.866664 -258.081018) (xy 119.8626 -258.076954)
			(xy 119.814086 -258.037838) (xy 119.783116 -258.048603) (xy 119.718596 -258.060227) (xy 119.685816 -258.060952)
			(xy 119.658463 -258.060451) (xy 119.604359 -258.052347) (xy 119.552054 -258.036315) (xy 119.502702 -258.01271)
			(xy 119.457393 -257.982052) (xy 119.417127 -257.945018) (xy 119.399558 -257.924046) (xy 119.38762 -257.924046)
			(xy 119.370076 -257.94539) (xy 119.329676 -257.983075) (xy 119.284094 -258.014294) (xy 119.234356 -258.038346)
			(xy 119.18158 -258.054689) (xy 119.126954 -258.062955) (xy 119.09933 -258.063492) (xy 119.072415 -258.063019)
			(xy 119.019162 -258.055167) (xy 118.967621 -258.03964) (xy 118.918891 -258.01677) (xy 118.874013 -257.987046)
			(xy 118.833944 -257.9511) (xy 118.79954 -257.909701) (xy 118.785132 -257.886962) (xy 118.723918 -257.886454)
			(xy 118.719672 -257.886795) (xy 118.711374 -257.88871) (xy 118.707408 -257.890264) (xy 118.694454 -257.896106)
			(xy 118.687088 -257.904996) (xy 118.671288 -257.923259) (xy 118.635295 -257.955453) (xy 118.595001 -257.982069)
			(xy 118.551263 -258.002538) (xy 118.505012 -258.016425) (xy 118.457233 -258.023435) (xy 118.433088 -258.023868)
			(xy 118.407228 -258.023367) (xy 118.356139 -258.01531) (xy 118.306928 -257.999395) (xy 118.260796 -257.97601)
			(xy 118.21887 -257.945726) (xy 118.20017 -257.927856) (xy 118.199916 -257.927602) (xy 118.16842 -257.913378)
			(xy 118.164356 -257.913124) (xy 118.092728 -257.913124) (xy 118.088664 -257.913378) (xy 118.057168 -257.927602)
			(xy 118.056914 -257.927856) (xy 118.038215 -257.945725) (xy 117.99629 -257.976012) (xy 117.950159 -257.999395)
			(xy 117.900946 -258.015303) (xy 117.849856 -258.023347) (xy 117.823996 -258.023868) (xy 117.798012 -258.023358)
			(xy 117.746684 -258.015228) (xy 117.697261 -257.999168) (xy 117.650957 -257.975575) (xy 117.608915 -257.945029)
			(xy 117.572168 -257.908282) (xy 117.541623 -257.866239) (xy 117.51803 -257.819936) (xy 117.501971 -257.770512)
			(xy 117.493842 -257.719184) (xy 117.493842 -257.667216) (xy 117.501971 -257.615888) (xy 117.51803 -257.566464)
			(xy 117.541623 -257.520161) (xy 117.572168 -257.478118) (xy 117.608915 -257.441371) (xy 117.650957 -257.410825)
			(xy 117.697261 -257.387232) (xy 117.746684 -257.371172) (xy 117.798012 -257.363042) (xy 117.823996 -257.362452)
			(xy 117.849857 -257.362952) (xy 117.900949 -257.371005) (xy 117.950164 -257.386915) (xy 117.996301 -257.410295)
			(xy 118.038234 -257.440573) (xy 118.056914 -257.458464) (xy 118.057168 -257.458718) (xy 118.088664 -257.472942)
			(xy 118.092728 -257.473196) (xy 118.164356 -257.473196) (xy 118.16842 -257.472942) (xy 118.199916 -257.458718)
			(xy 118.20017 -257.458464) (xy 118.218869 -257.440593) (xy 118.260792 -257.410302) (xy 118.306923 -257.386915)
			(xy 118.356136 -257.371004) (xy 118.407227 -257.362957) (xy 118.433088 -257.362452) (xy 118.461291 -257.363023)
			(xy 118.51688 -257.372593) (xy 118.570038 -257.391458) (xy 118.619224 -257.41907) (xy 118.663011 -257.454629)
			(xy 118.682008 -257.475482) (xy 118.685056 -257.479038) (xy 118.686326 -257.480562) (xy 118.688866 -257.48361)
			(xy 118.727728 -257.501898) (xy 118.786656 -257.502152) (xy 118.80111 -257.479676) (xy 118.83549 -257.438769)
			(xy 118.875433 -257.403273) (xy 118.920097 -257.373938) (xy 118.968539 -257.351383) (xy 119.019737 -257.336083)
			(xy 119.072612 -257.328361) (xy 119.09933 -257.327908) (xy 119.126686 -257.328405) (xy 119.180794 -257.336501)
			(xy 119.233106 -257.352526) (xy 119.282465 -257.376126) (xy 119.327783 -257.406778) (xy 119.368059 -257.443808)
			(xy 119.385588 -257.464814) (xy 119.397526 -257.464814) (xy 119.41507 -257.44347) (xy 119.45547 -257.405782)
			(xy 119.501052 -257.37456) (xy 119.550789 -257.350504) (xy 119.603565 -257.334155) (xy 119.658191 -257.325881)
			(xy 119.685816 -257.325368) (xy 119.718596 -257.326089) (xy 119.783115 -257.337719) (xy 119.814086 -257.348482)
			(xy 119.829072 -257.33629) (xy 119.86133 -257.310382) (xy 119.866664 -257.305302) (xy 119.872814 -257.298097)
			(xy 119.879732 -257.280477) (xy 119.880126 -257.271012) (xy 119.880126 -247.088152) (xy 119.879618 -247.081548)
			(xy 119.877984 -247.073696) (xy 119.870625 -247.059457) (xy 119.86514 -247.053608) (xy 119.806974 -247.000776)
			(xy 119.803273 -246.997745) (xy 119.794958 -246.993017) (xy 119.790464 -246.991378) (xy 119.779288 -246.987568)
			(xy 119.76862 -246.988584) (xy 119.737124 -246.990108) (xy 119.736616 -246.990108) (xy 119.709324 -246.989519)
			(xy 119.655487 -246.980503) (xy 119.603859 -246.96278) (xy 119.555837 -246.936828) (xy 119.512721 -246.903352)
			(xy 119.493792 -246.883682) (xy 119.49049 -246.88038) (xy 119.483781 -246.874818) (xy 119.467675 -246.868192)
			(xy 119.458994 -246.867426) (xy 119.379238 -246.867426) (xy 119.37056 -246.868208) (xy 119.354452 -246.874823)
			(xy 119.347742 -246.88038) (xy 119.34444 -246.883682) (xy 119.325553 -246.903401) (xy 119.282455 -246.936924)
			(xy 119.234426 -246.962892) (xy 119.182776 -246.980598) (xy 119.128916 -246.989558) (xy 119.101616 -246.990108)
			(xy 119.077335 -246.989681) (xy 119.029296 -246.982582) (xy 118.982811 -246.968534) (xy 118.93888 -246.947839)
			(xy 118.898448 -246.920941) (xy 118.862384 -246.888421) (xy 118.8466 -246.869966) (xy 118.845838 -246.86895)
			(xy 118.843044 -246.865902) (xy 118.84279 -246.865648) (xy 118.836366 -246.85962) (xy 118.820516 -246.851961)
			(xy 118.811802 -246.850662) (xy 118.806976 -246.850408) (xy 118.727728 -246.850408) (xy 118.722902 -246.850662)
			(xy 118.714184 -246.851948) (xy 118.698329 -246.859608) (xy 118.691914 -246.865648) (xy 118.69166 -246.865902)
			(xy 118.688866 -246.86895) (xy 118.688104 -246.869966) (xy 118.672314 -246.888416) (xy 118.636252 -246.920936)
			(xy 118.595821 -246.947834) (xy 118.551891 -246.968529) (xy 118.505407 -246.982577) (xy 118.457368 -246.989677)
			(xy 118.433088 -246.990108) (xy 118.407802 -246.989628) (xy 118.357819 -246.981928) (xy 118.30959 -246.966711)
			(xy 118.264239 -246.944331) (xy 118.222823 -246.915308) (xy 118.204234 -246.89816) (xy 118.196614 -246.890794)
			(xy 118.18747 -246.887238) (xy 118.182881 -246.885612) (xy 118.173289 -246.883947) (xy 118.16842 -246.883936)
			(xy 118.096538 -246.884698) (xy 118.091497 -246.884918) (xy 118.081644 -246.887091) (xy 118.07698 -246.889016)
			(xy 118.074694 -246.890032) (xy 118.06428 -246.897144) (xy 118.060978 -246.900446) (xy 118.042175 -246.918986)
			(xy 117.999772 -246.95045) (xy 117.95291 -246.974781) (xy 117.902779 -246.991362) (xy 117.850651 -246.999771)
			(xy 117.82425 -247.000268) (xy 117.823996 -247.000268) (xy 117.798012 -246.999758) (xy 117.746684 -246.991628)
			(xy 117.697261 -246.975568) (xy 117.650957 -246.951975) (xy 117.608915 -246.921429) (xy 117.572168 -246.884682)
			(xy 117.541623 -246.842639) (xy 117.51803 -246.796336) (xy 117.501971 -246.746912) (xy 117.493842 -246.695584)
			(xy 117.493842 -246.643616) (xy 117.501971 -246.592288) (xy 117.51803 -246.542864) (xy 117.541623 -246.496561)
			(xy 117.572168 -246.454518) (xy 117.608915 -246.417771) (xy 117.650957 -246.387225) (xy 117.697261 -246.363632)
			(xy 117.746684 -246.347572) (xy 117.798012 -246.339442) (xy 117.823996 -246.338852) (xy 117.849283 -246.339331)
			(xy 117.899268 -246.347027) (xy 117.947499 -246.362241) (xy 117.992853 -246.384619) (xy 118.034273 -246.413638)
			(xy 118.05285 -246.4308) (xy 118.06047 -246.438166) (xy 118.069614 -246.441722) (xy 118.074203 -246.443348)
			(xy 118.083795 -246.445014) (xy 118.088664 -246.445024) (xy 118.160546 -246.444262) (xy 118.165587 -246.444036)
			(xy 118.17544 -246.441868) (xy 118.180104 -246.439944) (xy 118.18239 -246.438928) (xy 118.192804 -246.431816)
			(xy 118.196106 -246.428514) (xy 118.214912 -246.409981) (xy 118.257319 -246.378531) (xy 118.304182 -246.354215)
			(xy 118.354312 -246.337649) (xy 118.406436 -246.329255) (xy 118.432834 -246.328692) (xy 118.433088 -246.328692)
			(xy 118.457369 -246.329119) (xy 118.505408 -246.336219) (xy 118.551892 -246.350267) (xy 118.595823 -246.370963)
			(xy 118.636254 -246.39786) (xy 118.672317 -246.430381) (xy 118.688104 -246.448834) (xy 118.688866 -246.44985)
			(xy 118.69166 -246.452898) (xy 118.691914 -246.453152) (xy 118.698338 -246.45918) (xy 118.714189 -246.466837)
			(xy 118.722902 -246.468138) (xy 118.727728 -246.468392) (xy 118.806976 -246.468392) (xy 118.811802 -246.468138)
			(xy 118.820519 -246.466851) (xy 118.836373 -246.459191) (xy 118.84279 -246.453152) (xy 118.843044 -246.452898)
			(xy 118.845838 -246.44985) (xy 118.8466 -246.448834) (xy 118.86239 -246.430384) (xy 118.898453 -246.397864)
			(xy 118.938884 -246.370968) (xy 118.982813 -246.350273) (xy 119.029297 -246.336225) (xy 119.077336 -246.329126)
			(xy 119.101616 -246.328692) (xy 119.128907 -246.329284) (xy 119.182741 -246.338304) (xy 119.234366 -246.356031)
			(xy 119.282384 -246.381985) (xy 119.325496 -246.415464) (xy 119.34444 -246.435118) (xy 119.347742 -246.43842)
			(xy 119.354453 -246.443978) (xy 119.370559 -246.450594) (xy 119.379238 -246.451374) (xy 119.458994 -246.451374)
			(xy 119.46767 -246.450587) (xy 119.483771 -246.443965) (xy 119.49049 -246.43842) (xy 119.493792 -246.435118)
			(xy 119.512678 -246.415395) (xy 119.555773 -246.381863) (xy 119.603802 -246.355885) (xy 119.655452 -246.338168)
			(xy 119.709314 -246.329197) (xy 119.736616 -246.328692) (xy 119.737124 -246.328692) (xy 119.76862 -246.330216)
			(xy 119.779288 -246.331232) (xy 119.789194 -246.32793) (xy 119.793499 -246.326475) (xy 119.801552 -246.322263)
			(xy 119.805196 -246.319548) (xy 119.865394 -246.264938) (xy 119.870849 -246.259165) (xy 119.878119 -246.245051)
			(xy 119.879618 -246.237252) (xy 119.880126 -246.230648) (xy 119.880126 -245.34749) (xy 119.879816 -245.339297)
			(xy 119.874633 -245.323751) (xy 119.869966 -245.31701) (xy 119.86514 -245.311422) (xy 117.860572 -243.306854)
			(xy 117.853174 -243.300006) (xy 117.834576 -243.292274) (xy 117.824504 -243.291868) (xy 117.798465 -243.291421)
			(xy 117.747019 -243.283336) (xy 117.697476 -243.267287) (xy 117.651061 -243.243671) (xy 117.608922 -243.213071)
			(xy 117.5721 -243.176245) (xy 117.541506 -243.134101) (xy 117.517896 -243.087683) (xy 117.501854 -243.038139)
			(xy 117.493776 -242.986692) (xy 117.493288 -242.960652) (xy 117.492805 -242.950689) (xy 117.48522 -242.932261)
			(xy 117.478556 -242.924838) (xy 115.83289 -241.279172) (xy 115.824 -241.27206) (xy 115.820506 -241.269931)
			(xy 115.812974 -241.266739) (xy 115.809014 -241.26571) (xy 115.79606 -241.26444) (xy 115.71859 -241.268758)
			(xy 115.682014 -241.287554) (xy 115.675664 -241.295428) (xy 115.667282 -241.304826) (xy 115.660678 -241.311938)
			(xy 115.657376 -241.320574) (xy 115.65575 -241.325038) (xy 115.653963 -241.334367) (xy 115.65382 -241.339116)
			(xy 115.65382 -241.407696) (xy 115.653919 -241.412449) (xy 115.655713 -241.421784) (xy 115.657376 -241.426238)
			(xy 115.660678 -241.43462) (xy 115.667282 -241.441986) (xy 115.683538 -241.460392) (xy 115.710993 -241.501104)
			(xy 115.732129 -241.545428) (xy 115.746484 -241.592388) (xy 115.75374 -241.640954) (xy 115.75415 -241.665506)
			(xy 115.75364 -241.691493) (xy 115.74551 -241.742828) (xy 115.729449 -241.792258) (xy 115.705853 -241.838568)
			(xy 115.675303 -241.880616) (xy 115.638552 -241.917367) (xy 115.596504 -241.947917) (xy 115.550194 -241.971513)
			(xy 115.500764 -241.987574) (xy 115.449429 -241.995704) (xy 115.397455 -241.995704) (xy 115.34612 -241.987574)
			(xy 115.29669 -241.971513) (xy 115.25038 -241.947917) (xy 115.208332 -241.917367) (xy 115.171581 -241.880616)
			(xy 115.141031 -241.838568) (xy 115.117435 -241.792258) (xy 115.101374 -241.742828) (xy 115.093244 -241.691493)
			(xy 115.092734 -241.665506) (xy 115.093201 -241.640016) (xy 115.101009 -241.589636) (xy 115.11644 -241.541047)
			(xy 115.139131 -241.495394) (xy 115.168546 -241.453756) (xy 115.185952 -241.435128) (xy 115.186206 -241.434874)
			(xy 115.189508 -241.426238) (xy 115.191135 -241.421774) (xy 115.192925 -241.412445) (xy 115.193064 -241.407696)
			(xy 115.193064 -241.339116) (xy 115.192966 -241.334363) (xy 115.191174 -241.325027) (xy 115.189508 -241.320574)
			(xy 115.186206 -241.312192) (xy 115.179602 -241.304826) (xy 115.163352 -241.286418) (xy 115.135909 -241.245703)
			(xy 115.114785 -241.201379) (xy 115.100444 -241.154419) (xy 115.093201 -241.105856) (xy 115.092734 -241.081306)
			(xy 115.093217 -241.055318) (xy 115.101347 -241.003981) (xy 115.11741 -240.954548) (xy 115.141008 -240.908237)
			(xy 115.171561 -240.866188) (xy 115.208316 -240.829437) (xy 115.250368 -240.798889) (xy 115.296681 -240.775296)
			(xy 115.346116 -240.759239) (xy 115.397454 -240.751114) (xy 115.423442 -240.750598) (xy 115.42395 -240.750598)
			(xy 115.449153 -240.751092) (xy 115.498969 -240.758783) (xy 115.547039 -240.77395) (xy 115.592249 -240.796241)
			(xy 115.61318 -240.810288) (xy 115.615212 -240.811812) (xy 115.620636 -240.814976) (xy 115.632583 -240.818833)
			(xy 115.638834 -240.819432) (xy 115.645946 -240.81994) (xy 115.659408 -240.817146) (xy 115.745514 -240.772188)
			(xy 115.753566 -240.76759) (xy 115.765936 -240.753796) (xy 115.772563 -240.736494) (xy 115.772946 -240.72723)
			(xy 115.772946 -239.524794) (xy 115.772637 -239.5166) (xy 115.767457 -239.501053) (xy 115.762786 -239.494314)
			(xy 115.75796 -239.488726) (xy 115.455192 -239.185958) (xy 115.449604 -239.181132) (xy 115.442864 -239.176462)
			(xy 115.427318 -239.171276) (xy 115.419124 -239.170972) (xy 114.794538 -239.170972) (xy 114.78553 -239.171465)
			(xy 114.768711 -239.177959) (xy 114.755179 -239.189872) (xy 114.750596 -239.197642) (xy 114.738078 -239.219701)
			(xy 114.707334 -239.260039) (xy 114.670792 -239.29521) (xy 114.629309 -239.32439) (xy 114.583857 -239.346896)
			(xy 114.535503 -239.3622) (xy 114.485379 -239.369943) (xy 114.434661 -239.369943) (xy 114.384537 -239.3622)
			(xy 114.336183 -239.346896) (xy 114.290731 -239.32439) (xy 114.249248 -239.29521) (xy 114.212706 -239.260039)
			(xy 114.181962 -239.219701) (xy 114.169444 -239.197642) (xy 114.164847 -239.18988) (xy 114.151322 -239.177961)
			(xy 114.134509 -239.171457) (xy 114.125502 -239.170972) (xy 113.854484 -239.170972) (xy 113.845472 -239.171458)
			(xy 113.828641 -239.177941) (xy 113.815096 -239.189852) (xy 113.810542 -239.197642) (xy 113.798024 -239.219701)
			(xy 113.76728 -239.260039) (xy 113.730738 -239.29521) (xy 113.689255 -239.32439) (xy 113.643803 -239.346896)
			(xy 113.595449 -239.3622) (xy 113.545325 -239.369943) (xy 113.494607 -239.369943) (xy 113.444483 -239.3622)
			(xy 113.396129 -239.346896) (xy 113.350677 -239.32439) (xy 113.309194 -239.29521) (xy 113.272652 -239.260039)
			(xy 113.241908 -239.219701) (xy 113.22939 -239.197642) (xy 113.22479 -239.189886) (xy 113.211263 -239.177981)
			(xy 113.194451 -239.171495) (xy 113.185448 -239.170972) (xy 112.914938 -239.170972) (xy 112.90593 -239.171465)
			(xy 112.889111 -239.177959) (xy 112.875579 -239.189872) (xy 112.870996 -239.197642) (xy 112.858478 -239.219701)
			(xy 112.827734 -239.260039) (xy 112.791192 -239.29521) (xy 112.749709 -239.32439) (xy 112.704257 -239.346896)
			(xy 112.655903 -239.3622) (xy 112.605779 -239.369943) (xy 112.555061 -239.369943) (xy 112.504937 -239.3622)
			(xy 112.456583 -239.346896) (xy 112.411131 -239.32439) (xy 112.369648 -239.29521) (xy 112.333106 -239.260039)
			(xy 112.302362 -239.219701) (xy 112.289844 -239.197642) (xy 112.285247 -239.18988) (xy 112.271722 -239.177961)
			(xy 112.254909 -239.171457) (xy 112.245902 -239.170972) (xy 111.975138 -239.170972) (xy 111.96613 -239.171465)
			(xy 111.949311 -239.177959) (xy 111.935779 -239.189872) (xy 111.931196 -239.197642) (xy 111.918678 -239.219701)
			(xy 111.887934 -239.260039) (xy 111.851392 -239.29521) (xy 111.809909 -239.32439) (xy 111.764457 -239.346896)
			(xy 111.716103 -239.3622) (xy 111.665979 -239.369943) (xy 111.615261 -239.369943) (xy 111.565137 -239.3622)
			(xy 111.516783 -239.346896) (xy 111.471331 -239.32439) (xy 111.429848 -239.29521) (xy 111.393306 -239.260039)
			(xy 111.362562 -239.219701) (xy 111.350044 -239.197642) (xy 111.345447 -239.18988) (xy 111.331922 -239.177961)
			(xy 111.315109 -239.171457) (xy 111.306102 -239.170972) (xy 111.035338 -239.170972) (xy 111.02633 -239.171465)
			(xy 111.009511 -239.177959) (xy 110.995979 -239.189872) (xy 110.991396 -239.197642) (xy 110.978878 -239.219701)
			(xy 110.948134 -239.260039) (xy 110.911592 -239.29521) (xy 110.870109 -239.32439) (xy 110.824657 -239.346896)
			(xy 110.776303 -239.3622) (xy 110.726179 -239.369943) (xy 110.675461 -239.369943) (xy 110.625337 -239.3622)
			(xy 110.576983 -239.346896) (xy 110.531531 -239.32439) (xy 110.490048 -239.29521) (xy 110.453506 -239.260039)
			(xy 110.422762 -239.219701) (xy 110.410244 -239.197642) (xy 110.405647 -239.18988) (xy 110.392122 -239.177961)
			(xy 110.375309 -239.171457) (xy 110.366302 -239.170972) (xy 110.095538 -239.170972) (xy 110.08653 -239.171465)
			(xy 110.069711 -239.177959) (xy 110.056179 -239.189872) (xy 110.051596 -239.197642) (xy 110.039078 -239.219701)
			(xy 110.008334 -239.260039) (xy 109.971792 -239.29521) (xy 109.930309 -239.32439) (xy 109.884857 -239.346896)
			(xy 109.836503 -239.3622) (xy 109.786379 -239.369943) (xy 109.735661 -239.369943) (xy 109.685537 -239.3622)
			(xy 109.637183 -239.346896) (xy 109.591731 -239.32439) (xy 109.550248 -239.29521) (xy 109.513706 -239.260039)
			(xy 109.482962 -239.219701) (xy 109.470444 -239.197642) (xy 109.465847 -239.18988) (xy 109.452322 -239.177961)
			(xy 109.435509 -239.171457) (xy 109.426502 -239.170972) (xy 106.779822 -239.170972) (xy 106.769491 -239.171463)
			(xy 106.750496 -239.1796) (xy 106.742992 -239.18672) (xy 106.691938 -239.240314) (xy 106.685393 -239.248032)
			(xy 106.678454 -239.267024) (xy 106.678476 -239.277144) (xy 106.678476 -239.277398) (xy 106.67873 -239.292638)
			(xy 106.67873 -239.293146) (xy 106.678202 -239.319121) (xy 106.670041 -239.370427) (xy 106.653959 -239.419826)
			(xy 106.63035 -239.466103) (xy 106.599796 -239.50812) (xy 106.563049 -239.544842) (xy 106.521012 -239.575367)
			(xy 106.474719 -239.598945) (xy 106.425309 -239.614994) (xy 106.373998 -239.62312) (xy 106.348022 -239.6236)
			(xy 106.322532 -239.623133) (xy 106.272152 -239.615327) (xy 106.223563 -239.599895) (xy 106.177912 -239.577202)
			(xy 106.136276 -239.547784) (xy 106.117644 -239.530382) (xy 106.11739 -239.530128) (xy 106.108754 -239.526826)
			(xy 106.104291 -239.525197) (xy 106.094961 -239.523403) (xy 106.090212 -239.52327) (xy 106.021632 -239.52327)
			(xy 106.016878 -239.523365) (xy 106.00754 -239.525153) (xy 106.00309 -239.526826) (xy 105.994708 -239.530128)
			(xy 105.987342 -239.536732) (xy 105.968563 -239.553297) (xy 105.926956 -239.581158) (xy 105.881628 -239.602435)
			(xy 105.833612 -239.616644) (xy 105.784005 -239.62346) (xy 105.733936 -239.622729) (xy 105.684549 -239.614466)
			(xy 105.636969 -239.598861) (xy 105.592282 -239.576269) (xy 105.551506 -239.547205) (xy 105.53319 -239.530128)
			(xy 105.524554 -239.526826) (xy 105.520091 -239.525197) (xy 105.510761 -239.523403) (xy 105.506012 -239.52327)
			(xy 105.437432 -239.52327) (xy 105.432678 -239.523365) (xy 105.42334 -239.525153) (xy 105.41889 -239.526826)
			(xy 105.410508 -239.530128) (xy 105.403142 -239.536732) (xy 105.384734 -239.552981) (xy 105.344018 -239.580423)
			(xy 105.299694 -239.601547) (xy 105.252735 -239.615889) (xy 105.204172 -239.623134) (xy 105.179622 -239.6236)
			(xy 105.153647 -239.623093) (xy 105.102334 -239.614973) (xy 105.052923 -239.598929) (xy 105.006628 -239.575357)
			(xy 104.964589 -239.544835) (xy 104.927839 -239.508115) (xy 104.897284 -239.466101) (xy 104.873673 -239.419825)
			(xy 104.85759 -239.370427) (xy 104.849428 -239.319121) (xy 104.848914 -239.293146) (xy 104.848914 -239.292638)
			(xy 104.849168 -239.277398) (xy 104.849168 -239.277144) (xy 104.849181 -239.267028) (xy 104.842229 -239.248047)
			(xy 104.835706 -239.240314) (xy 104.809798 -239.213136) (xy 104.784652 -239.18672) (xy 104.777172 -239.179571)
			(xy 104.758159 -239.171458) (xy 104.747822 -239.170972) (xy 104.54259 -239.170972) (xy 104.532048 -239.171545)
			(xy 104.51275 -239.180053) (xy 104.505252 -239.187482) (xy 104.454452 -239.242854) (xy 104.448241 -239.25017)
			(xy 104.441338 -239.26806) (xy 104.44099 -239.277652) (xy 104.441244 -239.281208) (xy 104.442514 -239.309656)
			(xy 104.442034 -239.335648) (xy 104.433908 -239.386992) (xy 104.41785 -239.436433) (xy 104.394255 -239.482752)
			(xy 104.363703 -239.52481) (xy 104.326949 -239.561571) (xy 104.284895 -239.592129) (xy 104.238579 -239.615731)
			(xy 104.189141 -239.631797) (xy 104.137798 -239.63993) (xy 104.111806 -239.640364) (xy 104.086316 -239.639897)
			(xy 104.035936 -239.632089) (xy 103.987347 -239.616658) (xy 103.941695 -239.593967) (xy 103.900056 -239.564551)
			(xy 103.881428 -239.547146) (xy 103.881174 -239.546892) (xy 103.872538 -239.54359) (xy 103.868074 -239.541963)
			(xy 103.858745 -239.540174) (xy 103.853996 -239.540034) (xy 103.785416 -239.540034) (xy 103.780663 -239.540132)
			(xy 103.771327 -239.541924) (xy 103.766874 -239.54359) (xy 103.758492 -239.546892) (xy 103.751126 -239.553496)
			(xy 103.732348 -239.570062) (xy 103.690742 -239.597923) (xy 103.645415 -239.6192) (xy 103.5974 -239.633408)
			(xy 103.547793 -239.640224) (xy 103.497725 -239.63949) (xy 103.448339 -239.631225) (xy 103.400761 -239.615617)
			(xy 103.356076 -239.593021) (xy 103.315304 -239.563954) (xy 103.296974 -239.546892) (xy 103.288338 -239.54359)
			(xy 103.283874 -239.541963) (xy 103.274545 -239.540174) (xy 103.269796 -239.540034) (xy 103.201216 -239.540034)
			(xy 103.196463 -239.540132) (xy 103.187127 -239.541924) (xy 103.182674 -239.54359) (xy 103.174292 -239.546892)
			(xy 103.166926 -239.553496) (xy 103.148518 -239.569746) (xy 103.107803 -239.597189) (xy 103.063479 -239.618313)
			(xy 103.01652 -239.632654) (xy 102.967956 -239.639897) (xy 102.943406 -239.640364) (xy 102.917292 -239.639878)
			(xy 102.865711 -239.631682) (xy 102.816061 -239.615477) (xy 102.769577 -239.591666) (xy 102.727416 -239.560842)
			(xy 102.690626 -239.523772) (xy 102.660123 -239.481377) (xy 102.636665 -239.434714) (xy 102.620838 -239.384942)
			(xy 102.616508 -239.359186) (xy 102.616 -239.356646) (xy 102.613006 -239.344638) (xy 102.597429 -239.325444)
			(xy 102.586282 -239.32007) (xy 102.49916 -239.286542) (xy 102.495457 -239.285378) (xy 102.487801 -239.284097)
			(xy 102.48392 -239.284002) (xy 102.451916 -239.295432) (xy 102.44709 -239.298988) (xy 102.425072 -239.315674)
			(xy 102.376636 -239.342234) (xy 102.324456 -239.360366) (xy 102.269986 -239.369566) (xy 102.242366 -239.370108)
			(xy 102.217012 -239.369621) (xy 102.166898 -239.361877) (xy 102.118553 -239.346576) (xy 102.07311 -239.324076)
			(xy 102.031633 -239.294904) (xy 101.995093 -239.259744) (xy 101.964347 -239.21942) (xy 101.95179 -239.197388)
			(xy 101.948488 -239.191546) (xy 101.93909 -239.18164) (xy 101.933248 -239.178084) (xy 101.92728 -239.1748)
			(xy 101.914148 -239.171198) (xy 101.90734 -239.170972) (xy 101.637338 -239.170972) (xy 101.630527 -239.171185)
			(xy 101.61739 -239.174783) (xy 101.61143 -239.178084) (xy 101.605588 -239.18164) (xy 101.59619 -239.191546)
			(xy 101.592888 -239.197388) (xy 101.58037 -239.219447) (xy 101.549626 -239.259785) (xy 101.513084 -239.294956)
			(xy 101.471601 -239.324136) (xy 101.426149 -239.346642) (xy 101.377795 -239.361946) (xy 101.327671 -239.369689)
			(xy 101.276953 -239.369689) (xy 101.226829 -239.361946) (xy 101.178475 -239.346642) (xy 101.133023 -239.324136)
			(xy 101.09154 -239.294956) (xy 101.054998 -239.259785) (xy 101.024254 -239.219447) (xy 101.011736 -239.197388)
			(xy 101.008434 -239.191546) (xy 100.999036 -239.18164) (xy 100.993194 -239.178084) (xy 100.987227 -239.174795)
			(xy 100.974096 -239.171181) (xy 100.967286 -239.170972) (xy 100.697792 -239.170972) (xy 100.690983 -239.171191)
			(xy 100.677852 -239.174799) (xy 100.671884 -239.178084) (xy 100.666042 -239.18164) (xy 100.656644 -239.191546)
			(xy 100.653342 -239.197388) (xy 100.640826 -239.219446) (xy 100.610083 -239.259781) (xy 100.573541 -239.294948)
			(xy 100.532056 -239.324122) (xy 100.486603 -239.346617) (xy 100.438247 -239.361907) (xy 100.388124 -239.369632)
			(xy 100.362766 -239.370108) (xy 100.334609 -239.369519) (xy 100.279117 -239.359935) (xy 100.226052 -239.341084)
			(xy 100.17695 -239.31351) (xy 100.15474 -239.296194) (xy 100.154232 -239.296194) (xy 100.146765 -239.290737)
			(xy 100.129191 -239.285023) (xy 100.119942 -239.285018) (xy 100.110638 -239.285892) (xy 100.09356 -239.29344)
			(xy 100.086668 -239.29975) (xy 99.998784 -239.387634) (xy 99.990644 -239.396876) (xy 99.983363 -239.420361)
			(xy 99.984814 -239.432592) (xy 99.996244 -239.49533) (xy 100.000054 -239.51565) (xy 100.003356 -239.526318)
			(xy 100.028756 -239.551718) (xy 100.03663 -239.555528) (xy 100.060234 -239.567528) (xy 100.103613 -239.59789)
			(xy 100.141599 -239.634777) (xy 100.173222 -239.677244) (xy 100.197675 -239.724209) (xy 100.214331 -239.774469)
			(xy 100.222766 -239.826742) (xy 100.22332 -239.853216) (xy 100.222809 -239.879183) (xy 100.502467 -239.879183)
			(xy 100.502467 -239.827249) (xy 100.510592 -239.775954) (xy 100.52664 -239.726561) (xy 100.550218 -239.680287)
			(xy 100.580744 -239.638271) (xy 100.617467 -239.601548) (xy 100.659483 -239.571022) (xy 100.705757 -239.547444)
			(xy 100.75515 -239.531396) (xy 100.806445 -239.523271) (xy 100.858379 -239.523271) (xy 100.909674 -239.531396)
			(xy 100.959067 -239.547444) (xy 101.005341 -239.571022) (xy 101.047357 -239.601548) (xy 101.08408 -239.638271)
			(xy 101.114606 -239.680287) (xy 101.138184 -239.726561) (xy 101.154232 -239.775954) (xy 101.162357 -239.827249)
			(xy 101.162866 -239.853216) (xy 101.162357 -239.879183) (xy 101.442521 -239.879183) (xy 101.442521 -239.827249)
			(xy 101.450646 -239.775954) (xy 101.466694 -239.726561) (xy 101.490272 -239.680287) (xy 101.520798 -239.638271)
			(xy 101.557521 -239.601548) (xy 101.599537 -239.571022) (xy 101.645811 -239.547444) (xy 101.695204 -239.531396)
			(xy 101.746499 -239.523271) (xy 101.798433 -239.523271) (xy 101.849728 -239.531396) (xy 101.899121 -239.547444)
			(xy 101.945395 -239.571022) (xy 101.987411 -239.601548) (xy 102.024134 -239.638271) (xy 102.05466 -239.680287)
			(xy 102.078238 -239.726561) (xy 102.094286 -239.775954) (xy 102.102411 -239.827249) (xy 102.10292 -239.853216)
			(xy 102.102411 -239.879183) (xy 102.102371 -239.879437) (xy 109.900975 -239.879437) (xy 109.900975 -239.827503)
			(xy 109.9091 -239.776208) (xy 109.925148 -239.726815) (xy 109.948726 -239.680541) (xy 109.979252 -239.638525)
			(xy 110.015975 -239.601802) (xy 110.057991 -239.571276) (xy 110.104265 -239.547698) (xy 110.153658 -239.53165)
			(xy 110.204953 -239.523525) (xy 110.256887 -239.523525) (xy 110.308182 -239.53165) (xy 110.357575 -239.547698)
			(xy 110.403849 -239.571276) (xy 110.445865 -239.601802) (xy 110.482588 -239.638525) (xy 110.513114 -239.680541)
			(xy 110.536692 -239.726815) (xy 110.55274 -239.776208) (xy 110.560865 -239.827503) (xy 110.561374 -239.85347)
			(xy 110.560865 -239.879437) (xy 110.55274 -239.930732) (xy 110.536692 -239.980125) (xy 110.513114 -240.026399)
			(xy 110.482588 -240.068415) (xy 110.445865 -240.105138) (xy 110.403849 -240.135664) (xy 110.357575 -240.159242)
			(xy 110.308182 -240.17529) (xy 110.256887 -240.183415) (xy 110.204953 -240.183415) (xy 110.153658 -240.17529)
			(xy 110.104265 -240.159242) (xy 110.057991 -240.135664) (xy 110.015975 -240.105138) (xy 109.979252 -240.068415)
			(xy 109.948726 -240.026399) (xy 109.925148 -239.980125) (xy 109.9091 -239.930732) (xy 109.900975 -239.879437)
			(xy 102.102371 -239.879437) (xy 102.094286 -239.930478) (xy 102.078238 -239.979871) (xy 102.05466 -240.026145)
			(xy 102.024134 -240.068161) (xy 101.987411 -240.104884) (xy 101.945395 -240.13541) (xy 101.899121 -240.158988)
			(xy 101.849728 -240.175036) (xy 101.798433 -240.183161) (xy 101.746499 -240.183161) (xy 101.695204 -240.175036)
			(xy 101.645811 -240.158988) (xy 101.599537 -240.13541) (xy 101.557521 -240.104884) (xy 101.520798 -240.068161)
			(xy 101.490272 -240.026145) (xy 101.466694 -239.979871) (xy 101.450646 -239.930478) (xy 101.442521 -239.879183)
			(xy 101.162357 -239.879183) (xy 101.154232 -239.930478) (xy 101.138184 -239.979871) (xy 101.114606 -240.026145)
			(xy 101.08408 -240.068161) (xy 101.047357 -240.104884) (xy 101.005341 -240.13541) (xy 100.959067 -240.158988)
			(xy 100.909674 -240.175036) (xy 100.858379 -240.183161) (xy 100.806445 -240.183161) (xy 100.75515 -240.175036)
			(xy 100.705757 -240.158988) (xy 100.659483 -240.13541) (xy 100.617467 -240.104884) (xy 100.580744 -240.068161)
			(xy 100.550218 -240.026145) (xy 100.52664 -239.979871) (xy 100.510592 -239.930478) (xy 100.502467 -239.879183)
			(xy 100.222809 -239.879183) (xy 100.222809 -239.879203) (xy 100.214677 -239.930536) (xy 100.198615 -239.979965)
			(xy 100.175018 -240.026273) (xy 100.144468 -240.06832) (xy 100.107717 -240.105071) (xy 100.06567 -240.13562)
			(xy 100.019361 -240.159216) (xy 99.969932 -240.175278) (xy 99.918599 -240.18341) (xy 99.892612 -240.183924)
			(xy 99.866137 -240.183403) (xy 99.813863 -240.174965) (xy 99.763601 -240.158304) (xy 99.716638 -240.133845)
			(xy 99.674174 -240.102214) (xy 99.637293 -240.064219) (xy 99.60694 -240.020832) (xy 99.594924 -239.997234)
			(xy 99.591114 -239.98936) (xy 99.565714 -239.96396) (xy 99.555046 -239.960658) (xy 99.534726 -239.956848)
			(xy 99.471988 -239.945418) (xy 99.459752 -239.94391) (xy 99.436243 -239.951199) (xy 99.42703 -239.959388)
			(xy 99.192842 -240.193576) (xy 99.188016 -240.199164) (xy 99.183357 -240.205907) (xy 99.178192 -240.221453)
			(xy 99.177856 -240.229644) (xy 99.177856 -240.25987) (xy 99.178459 -240.270496) (xy 99.18712 -240.289911)
			(xy 99.19462 -240.297462) (xy 99.199192 -240.301018) (xy 99.247706 -240.335308) (xy 99.26828 -240.349786)
			(xy 99.279456 -240.355374) (xy 99.312984 -240.355374) (xy 99.320604 -240.352834) (xy 99.34551 -240.345238)
			(xy 99.396933 -240.337071) (xy 99.422966 -240.336578) (xy 99.448958 -240.337059) (xy 99.500303 -240.345186)
			(xy 99.549744 -240.361246) (xy 99.596064 -240.384843) (xy 99.638122 -240.415396) (xy 99.674882 -240.452152)
			(xy 99.705439 -240.494207) (xy 99.729041 -240.540524) (xy 99.745106 -240.589964) (xy 99.753239 -240.641308)
			(xy 99.753239 -240.693253) (xy 100.032821 -240.693253) (xy 100.032821 -240.641319) (xy 100.040946 -240.590024)
			(xy 100.056994 -240.540631) (xy 100.080572 -240.494357) (xy 100.111098 -240.452341) (xy 100.147821 -240.415618)
			(xy 100.189837 -240.385092) (xy 100.236111 -240.361514) (xy 100.285504 -240.345466) (xy 100.336799 -240.337341)
			(xy 100.388733 -240.337341) (xy 100.440028 -240.345466) (xy 100.489421 -240.361514) (xy 100.535695 -240.385092)
			(xy 100.577711 -240.415618) (xy 100.614434 -240.452341) (xy 100.64496 -240.494357) (xy 100.668538 -240.540631)
			(xy 100.684586 -240.590024) (xy 100.692711 -240.641319) (xy 100.69322 -240.667286) (xy 100.692711 -240.693253)
			(xy 100.972621 -240.693253) (xy 100.972621 -240.641319) (xy 100.980746 -240.590024) (xy 100.996794 -240.540631)
			(xy 101.020372 -240.494357) (xy 101.050898 -240.452341) (xy 101.087621 -240.415618) (xy 101.129637 -240.385092)
			(xy 101.175911 -240.361514) (xy 101.225304 -240.345466) (xy 101.276599 -240.337341) (xy 101.328533 -240.337341)
			(xy 101.379828 -240.345466) (xy 101.429221 -240.361514) (xy 101.475495 -240.385092) (xy 101.517511 -240.415618)
			(xy 101.554234 -240.452341) (xy 101.58476 -240.494357) (xy 101.608338 -240.540631) (xy 101.624386 -240.590024)
			(xy 101.632511 -240.641319) (xy 101.63302 -240.667286) (xy 101.632511 -240.693253) (xy 101.632509 -240.693267)
			(xy 101.912441 -240.693267) (xy 101.912441 -240.641333) (xy 101.920565 -240.590039) (xy 101.936612 -240.540648)
			(xy 101.960188 -240.494374) (xy 101.990712 -240.452358) (xy 102.027432 -240.415634) (xy 102.069445 -240.385106)
			(xy 102.115716 -240.361525) (xy 102.165106 -240.345473) (xy 102.216399 -240.337344) (xy 102.242366 -240.336832)
			(xy 102.266068 -240.337242) (xy 102.312988 -240.344007) (xy 102.35846 -240.357403) (xy 102.401553 -240.377155)
			(xy 102.42169 -240.389664) (xy 102.434465 -240.397377) (xy 102.46314 -240.405608) (xy 102.49297 -240.405208)
			(xy 102.521414 -240.396212) (xy 102.546049 -240.379386) (xy 102.564776 -240.356163) (xy 102.576 -240.328522)
			(xy 102.5779 -240.313718) (xy 102.58098 -240.28676) (xy 102.594811 -240.234297) (xy 102.617028 -240.184799)
			(xy 102.647035 -240.139597) (xy 102.684025 -240.099905) (xy 102.727004 -240.066792) (xy 102.774815 -240.041146)
			(xy 102.826175 -240.023658) (xy 102.879702 -240.014797) (xy 102.90683 -240.014252) (xy 102.932798 -240.014728)
			(xy 102.984095 -240.022857) (xy 103.033489 -240.03891) (xy 103.079763 -240.062492) (xy 103.121779 -240.093022)
			(xy 103.158502 -240.129749) (xy 103.189027 -240.171768) (xy 103.212604 -240.218045) (xy 103.228652 -240.26744)
			(xy 103.236775 -240.318738) (xy 103.237284 -240.344706) (xy 103.237284 -240.34496) (xy 103.236812 -240.369486)
			(xy 103.229555 -240.417998) (xy 103.215208 -240.464905) (xy 103.194088 -240.509177) (xy 103.166657 -240.549842)
			(xy 103.150416 -240.568226) (xy 103.140607 -240.579711) (xy 103.127596 -240.60695) (xy 103.123129 -240.636804)
			(xy 103.127598 -240.666659) (xy 103.140612 -240.693897) (xy 103.150416 -240.705386) (xy 103.166677 -240.723755)
			(xy 103.19412 -240.764418) (xy 103.215246 -240.808692) (xy 103.229592 -240.855605) (xy 103.23684 -240.904123)
			(xy 103.237284 -240.928652) (xy 103.237284 -240.928906) (xy 103.23675 -240.954872) (xy 103.228626 -241.006164)
			(xy 103.212578 -241.055554) (xy 103.189003 -241.101826) (xy 103.158479 -241.143841) (xy 103.129576 -241.172746)
			(xy 108.095796 -241.172746) (xy 108.095796 -241.172492) (xy 108.096244 -241.147965) (xy 108.103508 -241.099452)
			(xy 108.11786 -241.052545) (xy 108.138986 -241.008274) (xy 108.166422 -240.967609) (xy 108.182664 -240.949226)
			(xy 108.192424 -240.937702) (xy 108.205444 -240.910478) (xy 108.209922 -240.880634) (xy 108.205464 -240.850787)
			(xy 108.192462 -240.823554) (xy 108.182664 -240.812066) (xy 108.166441 -240.793665) (xy 108.13899 -240.753012)
			(xy 108.117855 -240.708746) (xy 108.103501 -240.66184) (xy 108.096244 -240.613327) (xy 108.095796 -240.5888)
			(xy 108.095796 -240.588546) (xy 108.096305 -240.562579) (xy 108.10443 -240.511284) (xy 108.120478 -240.461891)
			(xy 108.144056 -240.415617) (xy 108.174582 -240.373601) (xy 108.211305 -240.336878) (xy 108.253321 -240.306352)
			(xy 108.299595 -240.282774) (xy 108.348988 -240.266726) (xy 108.400283 -240.258601) (xy 108.452217 -240.258601)
			(xy 108.503512 -240.266726) (xy 108.552905 -240.282774) (xy 108.599179 -240.306352) (xy 108.641195 -240.336878)
			(xy 108.677918 -240.373601) (xy 108.708444 -240.415617) (xy 108.732022 -240.461891) (xy 108.74807 -240.511284)
			(xy 108.756195 -240.562579) (xy 108.756704 -240.588546) (xy 108.756704 -240.5888) (xy 108.756251 -240.613327)
			(xy 108.748988 -240.661839) (xy 108.739299 -240.693507) (xy 113.190275 -240.693507) (xy 113.190275 -240.641573)
			(xy 113.1984 -240.590278) (xy 113.214448 -240.540885) (xy 113.238026 -240.494611) (xy 113.268552 -240.452595)
			(xy 113.305275 -240.415872) (xy 113.347291 -240.385346) (xy 113.393565 -240.361768) (xy 113.442958 -240.34572)
			(xy 113.494253 -240.337595) (xy 113.546187 -240.337595) (xy 113.597482 -240.34572) (xy 113.646875 -240.361768)
			(xy 113.693149 -240.385346) (xy 113.735165 -240.415872) (xy 113.771888 -240.452595) (xy 113.802414 -240.494611)
			(xy 113.825992 -240.540885) (xy 113.84204 -240.590278) (xy 113.850165 -240.641573) (xy 113.850674 -240.66754)
			(xy 113.850165 -240.693507) (xy 113.84204 -240.744802) (xy 113.825992 -240.794195) (xy 113.802414 -240.840469)
			(xy 113.771888 -240.882485) (xy 113.735165 -240.919208) (xy 113.693149 -240.949734) (xy 113.646875 -240.973312)
			(xy 113.597482 -240.98936) (xy 113.546187 -240.997485) (xy 113.494253 -240.997485) (xy 113.442958 -240.98936)
			(xy 113.393565 -240.973312) (xy 113.347291 -240.949734) (xy 113.305275 -240.919208) (xy 113.268552 -240.882485)
			(xy 113.238026 -240.840469) (xy 113.214448 -240.794195) (xy 113.1984 -240.744802) (xy 113.190275 -240.693507)
			(xy 108.739299 -240.693507) (xy 108.734637 -240.708746) (xy 108.713512 -240.753018) (xy 108.686078 -240.793682)
			(xy 108.669836 -240.812066) (xy 108.659987 -240.823519) (xy 108.646977 -240.850769) (xy 108.642516 -240.880634)
			(xy 108.646997 -240.910496) (xy 108.660025 -240.937737) (xy 108.669836 -240.949226) (xy 108.686055 -240.96763)
			(xy 108.713507 -241.008282) (xy 108.734643 -241.052548) (xy 108.748998 -241.099453) (xy 108.756256 -241.147966)
			(xy 108.756704 -241.172492) (xy 108.756704 -241.172746) (xy 108.756195 -241.198713) (xy 108.74807 -241.250008)
			(xy 108.732022 -241.299401) (xy 108.708444 -241.345675) (xy 108.677918 -241.387691) (xy 108.641195 -241.424414)
			(xy 108.599179 -241.45494) (xy 108.552905 -241.478518) (xy 108.503512 -241.494566) (xy 108.452217 -241.502691)
			(xy 108.400283 -241.502691) (xy 108.348988 -241.494566) (xy 108.299595 -241.478518) (xy 108.253321 -241.45494)
			(xy 108.211305 -241.424414) (xy 108.174582 -241.387691) (xy 108.144056 -241.345675) (xy 108.120478 -241.299401)
			(xy 108.10443 -241.250008) (xy 108.096305 -241.198713) (xy 108.095796 -241.172746) (xy 103.129576 -241.172746)
			(xy 103.121759 -241.180563) (xy 103.079747 -241.21109) (xy 103.033477 -241.234669) (xy 102.984088 -241.25072)
			(xy 102.932796 -241.258849) (xy 102.90683 -241.25936) (xy 102.882071 -241.258943) (xy 102.833106 -241.251572)
			(xy 102.785789 -241.236977) (xy 102.74118 -241.215483) (xy 102.700279 -241.187572) (xy 102.664001 -241.153869)
			(xy 102.633159 -241.11513) (xy 102.608444 -241.072222) (xy 102.59041 -241.026106) (xy 102.584504 -241.002058)
			(xy 102.580927 -240.988358) (xy 102.567385 -240.963507) (xy 102.547539 -240.94333) (xy 102.522915 -240.929379)
			(xy 102.495406 -240.922726) (xy 102.467129 -240.923883) (xy 102.440256 -240.932761) (xy 102.428294 -240.940336)
			(xy 102.407636 -240.953885) (xy 102.363121 -240.97531) (xy 102.315914 -240.989877) (xy 102.267067 -240.997262)
			(xy 102.242366 -240.99774) (xy 102.216399 -240.997256) (xy 102.165106 -240.989127) (xy 102.115716 -240.973075)
			(xy 102.069445 -240.949494) (xy 102.027432 -240.918966) (xy 101.990712 -240.882242) (xy 101.960188 -240.840226)
			(xy 101.936612 -240.793952) (xy 101.920565 -240.744561) (xy 101.912441 -240.693267) (xy 101.632509 -240.693267)
			(xy 101.624386 -240.744548) (xy 101.608338 -240.793941) (xy 101.58476 -240.840215) (xy 101.554234 -240.882231)
			(xy 101.517511 -240.918954) (xy 101.475495 -240.94948) (xy 101.429221 -240.973058) (xy 101.379828 -240.989106)
			(xy 101.328533 -240.997231) (xy 101.276599 -240.997231) (xy 101.225304 -240.989106) (xy 101.175911 -240.973058)
			(xy 101.129637 -240.94948) (xy 101.087621 -240.918954) (xy 101.050898 -240.882231) (xy 101.020372 -240.840215)
			(xy 100.996794 -240.793941) (xy 100.980746 -240.744548) (xy 100.972621 -240.693253) (xy 100.692711 -240.693253)
			(xy 100.684586 -240.744548) (xy 100.668538 -240.793941) (xy 100.64496 -240.840215) (xy 100.614434 -240.882231)
			(xy 100.577711 -240.918954) (xy 100.535695 -240.94948) (xy 100.489421 -240.973058) (xy 100.440028 -240.989106)
			(xy 100.388733 -240.997231) (xy 100.336799 -240.997231) (xy 100.285504 -240.989106) (xy 100.236111 -240.973058)
			(xy 100.189837 -240.94948) (xy 100.147821 -240.918954) (xy 100.111098 -240.882231) (xy 100.080572 -240.840215)
			(xy 100.056994 -240.793941) (xy 100.040946 -240.744548) (xy 100.032821 -240.693253) (xy 99.753239 -240.693253)
			(xy 99.753239 -240.693292) (xy 99.745106 -240.744636) (xy 99.729041 -240.794076) (xy 99.705439 -240.840393)
			(xy 99.674882 -240.882448) (xy 99.638122 -240.919204) (xy 99.596064 -240.949757) (xy 99.549744 -240.973354)
			(xy 99.500303 -240.989414) (xy 99.448958 -240.997541) (xy 99.422966 -240.997994) (xy 99.394985 -240.997385)
			(xy 99.339827 -240.987935) (xy 99.313238 -240.979198) (xy 99.312984 -240.979198) (xy 99.306768 -240.977235)
			(xy 99.293777 -240.976204) (xy 99.28733 -240.977166) (xy 99.281813 -240.9783) (xy 99.271431 -240.98266)
			(xy 99.266756 -240.985802) (xy 99.199192 -241.033554) (xy 99.19462 -241.03711) (xy 99.187002 -241.044577)
			(xy 99.178328 -241.064045) (xy 99.177856 -241.074702) (xy 99.177856 -241.21745) (xy 99.178177 -241.225936)
			(xy 99.183625 -241.242008) (xy 99.188524 -241.248946) (xy 99.191826 -241.252756) (xy 99.208903 -241.271321)
			(xy 99.2378 -241.312663) (xy 99.260081 -241.357915) (xy 99.275229 -241.406027) (xy 99.282891 -241.455881)
			(xy 99.282891 -241.506321) (xy 99.282776 -241.507069) (xy 99.562667 -241.507069) (xy 99.562667 -241.455135)
			(xy 99.570792 -241.40384) (xy 99.58684 -241.354447) (xy 99.610418 -241.308173) (xy 99.640944 -241.266157)
			(xy 99.677667 -241.229434) (xy 99.719683 -241.198908) (xy 99.765957 -241.17533) (xy 99.81535 -241.159282)
			(xy 99.866645 -241.151157) (xy 99.918579 -241.151157) (xy 99.969874 -241.159282) (xy 100.019267 -241.17533)
			(xy 100.065541 -241.198908) (xy 100.107557 -241.229434) (xy 100.14428 -241.266157) (xy 100.174806 -241.308173)
			(xy 100.198384 -241.354447) (xy 100.214432 -241.40384) (xy 100.222557 -241.455135) (xy 100.223066 -241.481102)
			(xy 100.222557 -241.507069) (xy 100.502721 -241.507069) (xy 100.502721 -241.455135) (xy 100.510846 -241.40384)
			(xy 100.526894 -241.354447) (xy 100.550472 -241.308173) (xy 100.580998 -241.266157) (xy 100.617721 -241.229434)
			(xy 100.659737 -241.198908) (xy 100.706011 -241.17533) (xy 100.755404 -241.159282) (xy 100.806699 -241.151157)
			(xy 100.858633 -241.151157) (xy 100.909928 -241.159282) (xy 100.959321 -241.17533) (xy 101.005595 -241.198908)
			(xy 101.047611 -241.229434) (xy 101.084334 -241.266157) (xy 101.11486 -241.308173) (xy 101.138438 -241.354447)
			(xy 101.154486 -241.40384) (xy 101.162611 -241.455135) (xy 101.16312 -241.481102) (xy 101.162611 -241.507069)
			(xy 101.442775 -241.507069) (xy 101.442775 -241.455135) (xy 101.4509 -241.40384) (xy 101.466948 -241.354447)
			(xy 101.490526 -241.308173) (xy 101.521052 -241.266157) (xy 101.557775 -241.229434) (xy 101.599791 -241.198908)
			(xy 101.646065 -241.17533) (xy 101.695458 -241.159282) (xy 101.746753 -241.151157) (xy 101.798687 -241.151157)
			(xy 101.849982 -241.159282) (xy 101.899375 -241.17533) (xy 101.945649 -241.198908) (xy 101.987665 -241.229434)
			(xy 102.024388 -241.266157) (xy 102.054914 -241.308173) (xy 102.078492 -241.354447) (xy 102.09454 -241.40384)
			(xy 102.102665 -241.455135) (xy 102.103174 -241.481102) (xy 102.102665 -241.507069) (xy 102.102625 -241.507323)
			(xy 109.900975 -241.507323) (xy 109.900975 -241.455389) (xy 109.9091 -241.404094) (xy 109.925148 -241.354701)
			(xy 109.948726 -241.308427) (xy 109.979252 -241.266411) (xy 110.015975 -241.229688) (xy 110.057991 -241.199162)
			(xy 110.104265 -241.175584) (xy 110.153658 -241.159536) (xy 110.204953 -241.151411) (xy 110.256887 -241.151411)
			(xy 110.308182 -241.159536) (xy 110.357575 -241.175584) (xy 110.403849 -241.199162) (xy 110.445865 -241.229688)
			(xy 110.482588 -241.266411) (xy 110.513114 -241.308427) (xy 110.536692 -241.354701) (xy 110.55274 -241.404094)
			(xy 110.560865 -241.455389) (xy 110.561374 -241.481356) (xy 110.560865 -241.507323) (xy 110.55274 -241.558618)
			(xy 110.536692 -241.608011) (xy 110.513114 -241.654285) (xy 110.482588 -241.696301) (xy 110.445865 -241.733024)
			(xy 110.403849 -241.76355) (xy 110.357575 -241.787128) (xy 110.308182 -241.803176) (xy 110.256887 -241.811301)
			(xy 110.204953 -241.811301) (xy 110.153658 -241.803176) (xy 110.104265 -241.787128) (xy 110.057991 -241.76355)
			(xy 110.015975 -241.733024) (xy 109.979252 -241.696301) (xy 109.948726 -241.654285) (xy 109.925148 -241.608011)
			(xy 109.9091 -241.558618) (xy 109.900975 -241.507323) (xy 102.102625 -241.507323) (xy 102.09454 -241.558364)
			(xy 102.078492 -241.607757) (xy 102.054914 -241.654031) (xy 102.024388 -241.696047) (xy 101.987665 -241.73277)
			(xy 101.945649 -241.763296) (xy 101.899375 -241.786874) (xy 101.849982 -241.802922) (xy 101.798687 -241.811047)
			(xy 101.746753 -241.811047) (xy 101.695458 -241.802922) (xy 101.646065 -241.786874) (xy 101.599791 -241.763296)
			(xy 101.557775 -241.73277) (xy 101.521052 -241.696047) (xy 101.490526 -241.654031) (xy 101.466948 -241.607757)
			(xy 101.4509 -241.558364) (xy 101.442775 -241.507069) (xy 101.162611 -241.507069) (xy 101.154486 -241.558364)
			(xy 101.138438 -241.607757) (xy 101.11486 -241.654031) (xy 101.084334 -241.696047) (xy 101.047611 -241.73277)
			(xy 101.005595 -241.763296) (xy 100.959321 -241.786874) (xy 100.909928 -241.802922) (xy 100.858633 -241.811047)
			(xy 100.806699 -241.811047) (xy 100.755404 -241.802922) (xy 100.706011 -241.786874) (xy 100.659737 -241.763296)
			(xy 100.617721 -241.73277) (xy 100.580998 -241.696047) (xy 100.550472 -241.654031) (xy 100.526894 -241.607757)
			(xy 100.510846 -241.558364) (xy 100.502721 -241.507069) (xy 100.222557 -241.507069) (xy 100.214432 -241.558364)
			(xy 100.198384 -241.607757) (xy 100.174806 -241.654031) (xy 100.14428 -241.696047) (xy 100.107557 -241.73277)
			(xy 100.065541 -241.763296) (xy 100.019267 -241.786874) (xy 99.969874 -241.802922) (xy 99.918579 -241.811047)
			(xy 99.866645 -241.811047) (xy 99.81535 -241.802922) (xy 99.765957 -241.786874) (xy 99.719683 -241.763296)
			(xy 99.677667 -241.73277) (xy 99.640944 -241.696047) (xy 99.610418 -241.654031) (xy 99.58684 -241.607757)
			(xy 99.570792 -241.558364) (xy 99.562667 -241.507069) (xy 99.282776 -241.507069) (xy 99.275228 -241.556176)
			(xy 99.26008 -241.604288) (xy 99.237799 -241.64954) (xy 99.208901 -241.690882) (xy 99.191826 -241.709448)
			(xy 99.188524 -241.713258) (xy 99.183559 -241.720159) (xy 99.178123 -241.736256) (xy 99.177856 -241.744754)
			(xy 99.177856 -241.887502) (xy 99.178465 -241.898125) (xy 99.187134 -241.917531) (xy 99.19462 -241.925094)
			(xy 99.199192 -241.92865) (xy 99.247706 -241.96294) (xy 99.26828 -241.977418) (xy 99.279456 -241.983006)
			(xy 99.312984 -241.983006) (xy 99.320604 -241.980466) (xy 99.345516 -241.972898) (xy 99.396935 -241.964733)
			(xy 99.422966 -241.96421) (xy 99.448956 -241.964691) (xy 99.500295 -241.972817) (xy 99.549732 -241.988875)
			(xy 99.596047 -242.01247) (xy 99.638101 -242.04302) (xy 99.674858 -242.079773) (xy 99.705412 -242.121824)
			(xy 99.729012 -242.168137) (xy 99.745075 -242.217571) (xy 99.753207 -242.26891) (xy 99.753207 -242.320885)
			(xy 100.032821 -242.320885) (xy 100.032821 -242.268951) (xy 100.040946 -242.217656) (xy 100.056994 -242.168263)
			(xy 100.080572 -242.121989) (xy 100.111098 -242.079973) (xy 100.147821 -242.04325) (xy 100.189837 -242.012724)
			(xy 100.236111 -241.989146) (xy 100.285504 -241.973098) (xy 100.336799 -241.964973) (xy 100.388733 -241.964973)
			(xy 100.440028 -241.973098) (xy 100.489421 -241.989146) (xy 100.535695 -242.012724) (xy 100.577711 -242.04325)
			(xy 100.614434 -242.079973) (xy 100.64496 -242.121989) (xy 100.668538 -242.168263) (xy 100.684586 -242.217656)
			(xy 100.692711 -242.268951) (xy 100.69322 -242.294918) (xy 100.692711 -242.320885) (xy 100.972621 -242.320885)
			(xy 100.972621 -242.268951) (xy 100.980746 -242.217656) (xy 100.996794 -242.168263) (xy 101.020372 -242.121989)
			(xy 101.050898 -242.079973) (xy 101.087621 -242.04325) (xy 101.129637 -242.012724) (xy 101.175911 -241.989146)
			(xy 101.225304 -241.973098) (xy 101.276599 -241.964973) (xy 101.328533 -241.964973) (xy 101.379828 -241.973098)
			(xy 101.429221 -241.989146) (xy 101.475495 -242.012724) (xy 101.517511 -242.04325) (xy 101.554234 -242.079973)
			(xy 101.58476 -242.121989) (xy 101.608338 -242.168263) (xy 101.624386 -242.217656) (xy 101.632511 -242.268951)
			(xy 101.63302 -242.294918) (xy 101.632511 -242.320885) (xy 101.912421 -242.320885) (xy 101.912421 -242.268951)
			(xy 101.920546 -242.217656) (xy 101.936594 -242.168263) (xy 101.960172 -242.121989) (xy 101.990698 -242.079973)
			(xy 102.027421 -242.04325) (xy 102.069437 -242.012724) (xy 102.115711 -241.989146) (xy 102.165104 -241.973098)
			(xy 102.216399 -241.964973) (xy 102.268333 -241.964973) (xy 102.319628 -241.973098) (xy 102.369021 -241.989146)
			(xy 102.415295 -242.012724) (xy 102.457311 -242.04325) (xy 102.494034 -242.079973) (xy 102.52456 -242.121989)
			(xy 102.548138 -242.168263) (xy 102.564186 -242.217656) (xy 102.572311 -242.268951) (xy 102.57282 -242.294918)
			(xy 102.572311 -242.320885) (xy 102.572271 -242.321139) (xy 113.190275 -242.321139) (xy 113.190275 -242.269205)
			(xy 113.1984 -242.21791) (xy 113.214448 -242.168517) (xy 113.238026 -242.122243) (xy 113.268552 -242.080227)
			(xy 113.305275 -242.043504) (xy 113.347291 -242.012978) (xy 113.393565 -241.9894) (xy 113.442958 -241.973352)
			(xy 113.494253 -241.965227) (xy 113.546187 -241.965227) (xy 113.597482 -241.973352) (xy 113.646875 -241.9894)
			(xy 113.693149 -242.012978) (xy 113.735165 -242.043504) (xy 113.771888 -242.080227) (xy 113.802414 -242.122243)
			(xy 113.825992 -242.168517) (xy 113.84204 -242.21791) (xy 113.850165 -242.269205) (xy 113.850674 -242.295172)
			(xy 113.850165 -242.321139) (xy 113.84204 -242.372434) (xy 113.825992 -242.421827) (xy 113.802414 -242.468101)
			(xy 113.771888 -242.510117) (xy 113.735165 -242.54684) (xy 113.693149 -242.577366) (xy 113.646875 -242.600944)
			(xy 113.597482 -242.616992) (xy 113.546187 -242.625117) (xy 113.494253 -242.625117) (xy 113.442958 -242.616992)
			(xy 113.393565 -242.600944) (xy 113.347291 -242.577366) (xy 113.305275 -242.54684) (xy 113.268552 -242.510117)
			(xy 113.238026 -242.468101) (xy 113.214448 -242.421827) (xy 113.1984 -242.372434) (xy 113.190275 -242.321139)
			(xy 102.572271 -242.321139) (xy 102.564186 -242.37218) (xy 102.548138 -242.421573) (xy 102.52456 -242.467847)
			(xy 102.494034 -242.509863) (xy 102.457311 -242.546586) (xy 102.415295 -242.577112) (xy 102.369021 -242.60069)
			(xy 102.319628 -242.616738) (xy 102.268333 -242.624863) (xy 102.216399 -242.624863) (xy 102.165104 -242.616738)
			(xy 102.115711 -242.60069) (xy 102.069437 -242.577112) (xy 102.027421 -242.546586) (xy 101.990698 -242.509863)
			(xy 101.960172 -242.467847) (xy 101.936594 -242.421573) (xy 101.920546 -242.37218) (xy 101.912421 -242.320885)
			(xy 101.632511 -242.320885) (xy 101.624386 -242.37218) (xy 101.608338 -242.421573) (xy 101.58476 -242.467847)
			(xy 101.554234 -242.509863) (xy 101.517511 -242.546586) (xy 101.475495 -242.577112) (xy 101.429221 -242.60069)
			(xy 101.379828 -242.616738) (xy 101.328533 -242.624863) (xy 101.276599 -242.624863) (xy 101.225304 -242.616738)
			(xy 101.175911 -242.60069) (xy 101.129637 -242.577112) (xy 101.087621 -242.546586) (xy 101.050898 -242.509863)
			(xy 101.020372 -242.467847) (xy 100.996794 -242.421573) (xy 100.980746 -242.37218) (xy 100.972621 -242.320885)
			(xy 100.692711 -242.320885) (xy 100.684586 -242.37218) (xy 100.668538 -242.421573) (xy 100.64496 -242.467847)
			(xy 100.614434 -242.509863) (xy 100.577711 -242.546586) (xy 100.535695 -242.577112) (xy 100.489421 -242.60069)
			(xy 100.440028 -242.616738) (xy 100.388733 -242.624863) (xy 100.336799 -242.624863) (xy 100.285504 -242.616738)
			(xy 100.236111 -242.60069) (xy 100.189837 -242.577112) (xy 100.147821 -242.546586) (xy 100.111098 -242.509863)
			(xy 100.080572 -242.467847) (xy 100.056994 -242.421573) (xy 100.040946 -242.37218) (xy 100.032821 -242.320885)
			(xy 99.753207 -242.320885) (xy 99.753207 -242.32089) (xy 99.745075 -242.372229) (xy 99.729012 -242.421663)
			(xy 99.705412 -242.467976) (xy 99.674858 -242.510027) (xy 99.638101 -242.54678) (xy 99.596047 -242.57733)
			(xy 99.549732 -242.600925) (xy 99.500295 -242.616983) (xy 99.448956 -242.625109) (xy 99.422966 -242.625626)
			(xy 99.394985 -242.625017) (xy 99.339826 -242.615568) (xy 99.313238 -242.60683) (xy 99.312984 -242.60683)
			(xy 99.306768 -242.604866) (xy 99.293777 -242.603834) (xy 99.28733 -242.604798) (xy 99.281813 -242.605933)
			(xy 99.271433 -242.610295) (xy 99.266756 -242.613434) (xy 99.199192 -242.661186) (xy 99.19462 -242.664742)
			(xy 99.187007 -242.672211) (xy 99.178345 -242.691679) (xy 99.177856 -242.702334) (xy 99.177856 -242.845336)
			(xy 99.178175 -242.853823) (xy 99.18362 -242.869898) (xy 99.188524 -242.876832) (xy 99.191826 -242.880642)
			(xy 99.208904 -242.899207) (xy 99.237803 -242.940549) (xy 99.260086 -242.985802) (xy 99.275236 -243.033915)
			(xy 99.2829 -243.083771) (xy 99.282902 -243.134212) (xy 99.282788 -243.134955) (xy 99.562667 -243.134955)
			(xy 99.562667 -243.083021) (xy 99.570792 -243.031726) (xy 99.58684 -242.982333) (xy 99.610418 -242.936059)
			(xy 99.640944 -242.894043) (xy 99.677667 -242.85732) (xy 99.719683 -242.826794) (xy 99.765957 -242.803216)
			(xy 99.81535 -242.787168) (xy 99.866645 -242.779043) (xy 99.918579 -242.779043) (xy 99.969874 -242.787168)
			(xy 100.019267 -242.803216) (xy 100.065541 -242.826794) (xy 100.107557 -242.85732) (xy 100.14428 -242.894043)
			(xy 100.174806 -242.936059) (xy 100.198384 -242.982333) (xy 100.214432 -243.031726) (xy 100.222557 -243.083021)
			(xy 100.223066 -243.108988) (xy 100.222557 -243.134955) (xy 100.502467 -243.134955) (xy 100.502467 -243.083021)
			(xy 100.510592 -243.031726) (xy 100.52664 -242.982333) (xy 100.550218 -242.936059) (xy 100.580744 -242.894043)
			(xy 100.617467 -242.85732) (xy 100.659483 -242.826794) (xy 100.705757 -242.803216) (xy 100.75515 -242.787168)
			(xy 100.806445 -242.779043) (xy 100.858379 -242.779043) (xy 100.909674 -242.787168) (xy 100.959067 -242.803216)
			(xy 101.005341 -242.826794) (xy 101.047357 -242.85732) (xy 101.08408 -242.894043) (xy 101.114606 -242.936059)
			(xy 101.138184 -242.982333) (xy 101.154232 -243.031726) (xy 101.162357 -243.083021) (xy 101.162866 -243.108988)
			(xy 101.162357 -243.134955) (xy 101.442267 -243.134955) (xy 101.442267 -243.083021) (xy 101.450392 -243.031726)
			(xy 101.46644 -242.982333) (xy 101.490018 -242.936059) (xy 101.520544 -242.894043) (xy 101.557267 -242.85732)
			(xy 101.599283 -242.826794) (xy 101.645557 -242.803216) (xy 101.69495 -242.787168) (xy 101.746245 -242.779043)
			(xy 101.798179 -242.779043) (xy 101.849474 -242.787168) (xy 101.898867 -242.803216) (xy 101.945141 -242.826794)
			(xy 101.987157 -242.85732) (xy 102.02388 -242.894043) (xy 102.054406 -242.936059) (xy 102.077984 -242.982333)
			(xy 102.094032 -243.031726) (xy 102.102157 -243.083021) (xy 102.102666 -243.108988) (xy 102.102157 -243.134955)
			(xy 102.102117 -243.135209) (xy 109.900975 -243.135209) (xy 109.900975 -243.083275) (xy 109.9091 -243.03198)
			(xy 109.925148 -242.982587) (xy 109.948726 -242.936313) (xy 109.979252 -242.894297) (xy 110.015975 -242.857574)
			(xy 110.057991 -242.827048) (xy 110.104265 -242.80347) (xy 110.153658 -242.787422) (xy 110.204953 -242.779297)
			(xy 110.256887 -242.779297) (xy 110.308182 -242.787422) (xy 110.357575 -242.80347) (xy 110.403849 -242.827048)
			(xy 110.445865 -242.857574) (xy 110.482588 -242.894297) (xy 110.513114 -242.936313) (xy 110.536692 -242.982587)
			(xy 110.55274 -243.03198) (xy 110.560865 -243.083275) (xy 110.561374 -243.109242) (xy 110.560865 -243.135209)
			(xy 110.55274 -243.186504) (xy 110.536692 -243.235897) (xy 110.513114 -243.282171) (xy 110.482588 -243.324187)
			(xy 110.445865 -243.36091) (xy 110.403849 -243.391436) (xy 110.357575 -243.415014) (xy 110.308182 -243.431062)
			(xy 110.256887 -243.439187) (xy 110.204953 -243.439187) (xy 110.153658 -243.431062) (xy 110.104265 -243.415014)
			(xy 110.057991 -243.391436) (xy 110.015975 -243.36091) (xy 109.979252 -243.324187) (xy 109.948726 -243.282171)
			(xy 109.925148 -243.235897) (xy 109.9091 -243.186504) (xy 109.900975 -243.135209) (xy 102.102117 -243.135209)
			(xy 102.094032 -243.18625) (xy 102.077984 -243.235643) (xy 102.054406 -243.281917) (xy 102.02388 -243.323933)
			(xy 101.987157 -243.360656) (xy 101.945141 -243.391182) (xy 101.898867 -243.41476) (xy 101.849474 -243.430808)
			(xy 101.798179 -243.438933) (xy 101.746245 -243.438933) (xy 101.69495 -243.430808) (xy 101.645557 -243.41476)
			(xy 101.599283 -243.391182) (xy 101.557267 -243.360656) (xy 101.520544 -243.323933) (xy 101.490018 -243.281917)
			(xy 101.46644 -243.235643) (xy 101.450392 -243.18625) (xy 101.442267 -243.134955) (xy 101.162357 -243.134955)
			(xy 101.154232 -243.18625) (xy 101.138184 -243.235643) (xy 101.114606 -243.281917) (xy 101.08408 -243.323933)
			(xy 101.047357 -243.360656) (xy 101.005341 -243.391182) (xy 100.959067 -243.41476) (xy 100.909674 -243.430808)
			(xy 100.858379 -243.438933) (xy 100.806445 -243.438933) (xy 100.75515 -243.430808) (xy 100.705757 -243.41476)
			(xy 100.659483 -243.391182) (xy 100.617467 -243.360656) (xy 100.580744 -243.323933) (xy 100.550218 -243.281917)
			(xy 100.52664 -243.235643) (xy 100.510592 -243.18625) (xy 100.502467 -243.134955) (xy 100.222557 -243.134955)
			(xy 100.214432 -243.18625) (xy 100.198384 -243.235643) (xy 100.174806 -243.281917) (xy 100.14428 -243.323933)
			(xy 100.107557 -243.360656) (xy 100.065541 -243.391182) (xy 100.019267 -243.41476) (xy 99.969874 -243.430808)
			(xy 99.918579 -243.438933) (xy 99.866645 -243.438933) (xy 99.81535 -243.430808) (xy 99.765957 -243.41476)
			(xy 99.719683 -243.391182) (xy 99.677667 -243.360656) (xy 99.640944 -243.323933) (xy 99.610418 -243.281917)
			(xy 99.58684 -243.235643) (xy 99.570792 -243.18625) (xy 99.562667 -243.134955) (xy 99.282788 -243.134955)
			(xy 99.27524 -243.184068) (xy 99.260093 -243.232182) (xy 99.237812 -243.277436) (xy 99.208915 -243.31878)
			(xy 99.191826 -243.337334) (xy 99.188524 -243.341144) (xy 99.183557 -243.348044) (xy 99.178117 -243.364141)
			(xy 99.177856 -243.37264) (xy 99.177856 -243.515388) (xy 99.178462 -243.526012) (xy 99.187128 -243.545422)
			(xy 99.19462 -243.55298) (xy 99.199192 -243.556536) (xy 99.247706 -243.590826) (xy 99.26828 -243.605304)
			(xy 99.279456 -243.610892) (xy 99.312984 -243.610892) (xy 99.320604 -243.608352) (xy 99.345516 -243.600784)
			(xy 99.396935 -243.59262) (xy 99.422966 -243.592096) (xy 99.448957 -243.592577) (xy 99.500299 -243.600703)
			(xy 99.549737 -243.616763) (xy 99.596055 -243.640358) (xy 99.63811 -243.670909) (xy 99.674868 -243.707664)
			(xy 99.705424 -243.749716) (xy 99.729024 -243.796031) (xy 99.745089 -243.845468) (xy 99.753221 -243.896809)
			(xy 99.753221 -243.948771) (xy 100.032821 -243.948771) (xy 100.032821 -243.896837) (xy 100.040946 -243.845542)
			(xy 100.056994 -243.796149) (xy 100.080572 -243.749875) (xy 100.111098 -243.707859) (xy 100.147821 -243.671136)
			(xy 100.189837 -243.64061) (xy 100.236111 -243.617032) (xy 100.285504 -243.600984) (xy 100.336799 -243.592859)
			(xy 100.388733 -243.592859) (xy 100.440028 -243.600984) (xy 100.489421 -243.617032) (xy 100.535695 -243.64061)
			(xy 100.577711 -243.671136) (xy 100.614434 -243.707859) (xy 100.64496 -243.749875) (xy 100.668538 -243.796149)
			(xy 100.684586 -243.845542) (xy 100.692711 -243.896837) (xy 100.69322 -243.922804) (xy 100.692711 -243.948771)
			(xy 100.972367 -243.948771) (xy 100.972367 -243.896837) (xy 100.980492 -243.845542) (xy 100.99654 -243.796149)
			(xy 101.020118 -243.749875) (xy 101.050644 -243.707859) (xy 101.087367 -243.671136) (xy 101.129383 -243.64061)
			(xy 101.175657 -243.617032) (xy 101.22505 -243.600984) (xy 101.276345 -243.592859) (xy 101.328279 -243.592859)
			(xy 101.379574 -243.600984) (xy 101.428967 -243.617032) (xy 101.475241 -243.64061) (xy 101.517257 -243.671136)
			(xy 101.55398 -243.707859) (xy 101.584506 -243.749875) (xy 101.608084 -243.796149) (xy 101.624132 -243.845542)
			(xy 101.632257 -243.896837) (xy 101.632766 -243.922804) (xy 101.632257 -243.948771) (xy 101.912421 -243.948771)
			(xy 101.912421 -243.896837) (xy 101.920546 -243.845542) (xy 101.936594 -243.796149) (xy 101.960172 -243.749875)
			(xy 101.990698 -243.707859) (xy 102.027421 -243.671136) (xy 102.069437 -243.64061) (xy 102.115711 -243.617032)
			(xy 102.165104 -243.600984) (xy 102.216399 -243.592859) (xy 102.268333 -243.592859) (xy 102.319628 -243.600984)
			(xy 102.369021 -243.617032) (xy 102.415295 -243.64061) (xy 102.457311 -243.671136) (xy 102.494034 -243.707859)
			(xy 102.52456 -243.749875) (xy 102.548138 -243.796149) (xy 102.564186 -243.845542) (xy 102.572311 -243.896837)
			(xy 102.57282 -243.922804) (xy 102.572311 -243.948771) (xy 102.572271 -243.949025) (xy 113.190275 -243.949025)
			(xy 113.190275 -243.897091) (xy 113.1984 -243.845796) (xy 113.214448 -243.796403) (xy 113.238026 -243.750129)
			(xy 113.268552 -243.708113) (xy 113.305275 -243.67139) (xy 113.347291 -243.640864) (xy 113.393565 -243.617286)
			(xy 113.442958 -243.601238) (xy 113.494253 -243.593113) (xy 113.546187 -243.593113) (xy 113.597482 -243.601238)
			(xy 113.646875 -243.617286) (xy 113.693149 -243.640864) (xy 113.735165 -243.67139) (xy 113.771888 -243.708113)
			(xy 113.802414 -243.750129) (xy 113.825992 -243.796403) (xy 113.84204 -243.845796) (xy 113.850165 -243.897091)
			(xy 113.850674 -243.923058) (xy 113.850165 -243.949025) (xy 113.84204 -244.00032) (xy 113.825992 -244.049713)
			(xy 113.802414 -244.095987) (xy 113.771888 -244.138003) (xy 113.735165 -244.174726) (xy 113.693149 -244.205252)
			(xy 113.646875 -244.22883) (xy 113.597482 -244.244878) (xy 113.546187 -244.253003) (xy 113.494253 -244.253003)
			(xy 113.442958 -244.244878) (xy 113.393565 -244.22883) (xy 113.347291 -244.205252) (xy 113.305275 -244.174726)
			(xy 113.268552 -244.138003) (xy 113.238026 -244.095987) (xy 113.214448 -244.049713) (xy 113.1984 -244.00032)
			(xy 113.190275 -243.949025) (xy 102.572271 -243.949025) (xy 102.564186 -244.000066) (xy 102.548138 -244.049459)
			(xy 102.52456 -244.095733) (xy 102.494034 -244.137749) (xy 102.457311 -244.174472) (xy 102.415295 -244.204998)
			(xy 102.369021 -244.228576) (xy 102.319628 -244.244624) (xy 102.268333 -244.252749) (xy 102.216399 -244.252749)
			(xy 102.165104 -244.244624) (xy 102.115711 -244.228576) (xy 102.069437 -244.204998) (xy 102.027421 -244.174472)
			(xy 101.990698 -244.137749) (xy 101.960172 -244.095733) (xy 101.936594 -244.049459) (xy 101.920546 -244.000066)
			(xy 101.912421 -243.948771) (xy 101.632257 -243.948771) (xy 101.624132 -244.000066) (xy 101.608084 -244.049459)
			(xy 101.584506 -244.095733) (xy 101.55398 -244.137749) (xy 101.517257 -244.174472) (xy 101.475241 -244.204998)
			(xy 101.428967 -244.228576) (xy 101.379574 -244.244624) (xy 101.328279 -244.252749) (xy 101.276345 -244.252749)
			(xy 101.22505 -244.244624) (xy 101.175657 -244.228576) (xy 101.129383 -244.204998) (xy 101.087367 -244.174472)
			(xy 101.050644 -244.137749) (xy 101.020118 -244.095733) (xy 100.99654 -244.049459) (xy 100.980492 -244.000066)
			(xy 100.972367 -243.948771) (xy 100.692711 -243.948771) (xy 100.684586 -244.000066) (xy 100.668538 -244.049459)
			(xy 100.64496 -244.095733) (xy 100.614434 -244.137749) (xy 100.577711 -244.174472) (xy 100.535695 -244.204998)
			(xy 100.489421 -244.228576) (xy 100.440028 -244.244624) (xy 100.388733 -244.252749) (xy 100.336799 -244.252749)
			(xy 100.285504 -244.244624) (xy 100.236111 -244.228576) (xy 100.189837 -244.204998) (xy 100.147821 -244.174472)
			(xy 100.111098 -244.137749) (xy 100.080572 -244.095733) (xy 100.056994 -244.049459) (xy 100.040946 -244.000066)
			(xy 100.032821 -243.948771) (xy 99.753221 -243.948771) (xy 99.753221 -243.948791) (xy 99.745089 -244.000132)
			(xy 99.729024 -244.049569) (xy 99.705424 -244.095884) (xy 99.674868 -244.137936) (xy 99.63811 -244.174691)
			(xy 99.596055 -244.205242) (xy 99.549737 -244.228837) (xy 99.500299 -244.244897) (xy 99.448957 -244.253023)
			(xy 99.422966 -244.253512) (xy 99.394985 -244.252903) (xy 99.339826 -244.243454) (xy 99.313238 -244.234716)
			(xy 99.312984 -244.234716) (xy 99.306768 -244.232752) (xy 99.293777 -244.231721) (xy 99.28733 -244.232684)
			(xy 99.281813 -244.233819) (xy 99.271432 -244.23818) (xy 99.266756 -244.24132) (xy 99.199192 -244.289072)
			(xy 99.19462 -244.292628) (xy 99.187005 -244.300096) (xy 99.178337 -244.319564) (xy 99.177856 -244.33022)
			(xy 99.177856 -244.472968) (xy 99.17818 -244.481453) (xy 99.183633 -244.497522) (xy 99.188524 -244.504464)
			(xy 99.191826 -244.508274) (xy 99.208902 -244.526839) (xy 99.237796 -244.56818) (xy 99.260074 -244.613432)
			(xy 99.27522 -244.661542) (xy 99.28288 -244.711395) (xy 99.282878 -244.761834) (xy 99.282762 -244.762587)
			(xy 99.562667 -244.762587) (xy 99.562667 -244.710653) (xy 99.570792 -244.659358) (xy 99.58684 -244.609965)
			(xy 99.610418 -244.563691) (xy 99.640944 -244.521675) (xy 99.677667 -244.484952) (xy 99.719683 -244.454426)
			(xy 99.765957 -244.430848) (xy 99.81535 -244.4148) (xy 99.866645 -244.406675) (xy 99.918579 -244.406675)
			(xy 99.969874 -244.4148) (xy 100.019267 -244.430848) (xy 100.065541 -244.454426) (xy 100.107557 -244.484952)
			(xy 100.14428 -244.521675) (xy 100.174806 -244.563691) (xy 100.198384 -244.609965) (xy 100.214432 -244.659358)
			(xy 100.222557 -244.710653) (xy 100.223066 -244.73662) (xy 100.222557 -244.762587) (xy 100.502467 -244.762587)
			(xy 100.502467 -244.710653) (xy 100.510592 -244.659358) (xy 100.52664 -244.609965) (xy 100.550218 -244.563691)
			(xy 100.580744 -244.521675) (xy 100.617467 -244.484952) (xy 100.659483 -244.454426) (xy 100.705757 -244.430848)
			(xy 100.75515 -244.4148) (xy 100.806445 -244.406675) (xy 100.858379 -244.406675) (xy 100.909674 -244.4148)
			(xy 100.959067 -244.430848) (xy 101.005341 -244.454426) (xy 101.047357 -244.484952) (xy 101.08408 -244.521675)
			(xy 101.114606 -244.563691) (xy 101.138184 -244.609965) (xy 101.154232 -244.659358) (xy 101.162357 -244.710653)
			(xy 101.162866 -244.73662) (xy 101.162357 -244.762587) (xy 101.442267 -244.762587) (xy 101.442267 -244.710653)
			(xy 101.450392 -244.659358) (xy 101.46644 -244.609965) (xy 101.490018 -244.563691) (xy 101.520544 -244.521675)
			(xy 101.557267 -244.484952) (xy 101.599283 -244.454426) (xy 101.645557 -244.430848) (xy 101.69495 -244.4148)
			(xy 101.746245 -244.406675) (xy 101.798179 -244.406675) (xy 101.849474 -244.4148) (xy 101.898867 -244.430848)
			(xy 101.945141 -244.454426) (xy 101.987157 -244.484952) (xy 102.02388 -244.521675) (xy 102.054406 -244.563691)
			(xy 102.077984 -244.609965) (xy 102.094032 -244.659358) (xy 102.102157 -244.710653) (xy 102.102666 -244.73662)
			(xy 102.102157 -244.762587) (xy 102.094032 -244.813882) (xy 102.077984 -244.863275) (xy 102.054406 -244.909549)
			(xy 102.02388 -244.951565) (xy 101.987157 -244.988288) (xy 101.945141 -245.018814) (xy 101.898867 -245.042392)
			(xy 101.849474 -245.05844) (xy 101.798179 -245.066565) (xy 101.746245 -245.066565) (xy 101.69495 -245.05844)
			(xy 101.645557 -245.042392) (xy 101.599283 -245.018814) (xy 101.557267 -244.988288) (xy 101.520544 -244.951565)
			(xy 101.490018 -244.909549) (xy 101.46644 -244.863275) (xy 101.450392 -244.813882) (xy 101.442267 -244.762587)
			(xy 101.162357 -244.762587) (xy 101.154232 -244.813882) (xy 101.138184 -244.863275) (xy 101.114606 -244.909549)
			(xy 101.08408 -244.951565) (xy 101.047357 -244.988288) (xy 101.005341 -245.018814) (xy 100.959067 -245.042392)
			(xy 100.909674 -245.05844) (xy 100.858379 -245.066565) (xy 100.806445 -245.066565) (xy 100.75515 -245.05844)
			(xy 100.705757 -245.042392) (xy 100.659483 -245.018814) (xy 100.617467 -244.988288) (xy 100.580744 -244.951565)
			(xy 100.550218 -244.909549) (xy 100.52664 -244.863275) (xy 100.510592 -244.813882) (xy 100.502467 -244.762587)
			(xy 100.222557 -244.762587) (xy 100.214432 -244.813882) (xy 100.198384 -244.863275) (xy 100.174806 -244.909549)
			(xy 100.14428 -244.951565) (xy 100.107557 -244.988288) (xy 100.065541 -245.018814) (xy 100.019267 -245.042392)
			(xy 99.969874 -245.05844) (xy 99.918579 -245.066565) (xy 99.866645 -245.066565) (xy 99.81535 -245.05844)
			(xy 99.765957 -245.042392) (xy 99.719683 -245.018814) (xy 99.677667 -244.988288) (xy 99.640944 -244.951565)
			(xy 99.610418 -244.909549) (xy 99.58684 -244.863275) (xy 99.570792 -244.813882) (xy 99.562667 -244.762587)
			(xy 99.282762 -244.762587) (xy 99.275213 -244.811686) (xy 99.260064 -244.859795) (xy 99.237781 -244.905045)
			(xy 99.208884 -244.946384) (xy 99.191826 -244.964966) (xy 99.188524 -244.968776) (xy 99.183547 -244.975673)
			(xy 99.178085 -244.99177) (xy 99.177856 -245.000272) (xy 99.177856 -245.143274) (xy 99.17846 -245.153899)
			(xy 99.187122 -245.173313) (xy 99.19462 -245.180866) (xy 99.199192 -245.184422) (xy 99.247706 -245.218712)
			(xy 99.26828 -245.23319) (xy 99.279456 -245.238778) (xy 99.312984 -245.238778) (xy 99.320604 -245.236238)
			(xy 99.345516 -245.22867) (xy 99.396935 -245.220506) (xy 99.422966 -245.219982) (xy 99.448958 -245.220463)
			(xy 99.500302 -245.22859) (xy 99.549743 -245.24465) (xy 99.596062 -245.268246) (xy 99.638119 -245.298799)
			(xy 99.674879 -245.335555) (xy 99.705436 -245.377609) (xy 99.729037 -245.423926) (xy 99.745102 -245.473365)
			(xy 99.753235 -245.524708) (xy 99.753235 -245.576657) (xy 100.032821 -245.576657) (xy 100.032821 -245.524723)
			(xy 100.040946 -245.473428) (xy 100.056994 -245.424035) (xy 100.080572 -245.377761) (xy 100.111098 -245.335745)
			(xy 100.147821 -245.299022) (xy 100.189837 -245.268496) (xy 100.236111 -245.244918) (xy 100.285504 -245.22887)
			(xy 100.336799 -245.220745) (xy 100.388733 -245.220745) (xy 100.440028 -245.22887) (xy 100.489421 -245.244918)
			(xy 100.535695 -245.268496) (xy 100.577711 -245.299022) (xy 100.614434 -245.335745) (xy 100.64496 -245.377761)
			(xy 100.668538 -245.424035) (xy 100.684586 -245.473428) (xy 100.692711 -245.524723) (xy 100.69322 -245.55069)
			(xy 100.692711 -245.576657) (xy 100.972621 -245.576657) (xy 100.972621 -245.524723) (xy 100.980746 -245.473428)
			(xy 100.996794 -245.424035) (xy 101.020372 -245.377761) (xy 101.050898 -245.335745) (xy 101.087621 -245.299022)
			(xy 101.129637 -245.268496) (xy 101.175911 -245.244918) (xy 101.225304 -245.22887) (xy 101.276599 -245.220745)
			(xy 101.328533 -245.220745) (xy 101.379828 -245.22887) (xy 101.429221 -245.244918) (xy 101.475495 -245.268496)
			(xy 101.517511 -245.299022) (xy 101.554234 -245.335745) (xy 101.58476 -245.377761) (xy 101.608338 -245.424035)
			(xy 101.624386 -245.473428) (xy 101.632511 -245.524723) (xy 101.63302 -245.55069) (xy 101.632511 -245.576657)
			(xy 101.63251 -245.576666) (xy 101.912445 -245.576666) (xy 101.912445 -245.524734) (xy 101.920569 -245.47344)
			(xy 101.936616 -245.424049) (xy 101.960191 -245.377776) (xy 101.990715 -245.335761) (xy 102.027435 -245.299037)
			(xy 102.069447 -245.268509) (xy 102.115718 -245.244929) (xy 102.165107 -245.228877) (xy 102.2164 -245.220748)
			(xy 102.242366 -245.220236) (xy 102.24262 -245.220236) (xy 102.268058 -245.220694) (xy 102.318332 -245.228495)
			(xy 102.366812 -245.243926) (xy 102.412347 -245.266618) (xy 102.433374 -245.280942) (xy 102.444608 -245.288483)
			(xy 102.469993 -245.297823) (xy 102.496942 -245.30016) (xy 102.523557 -245.29533) (xy 102.547965 -245.283671)
			(xy 102.568449 -245.266006) (xy 102.583568 -245.243576) (xy 102.588314 -245.230904) (xy 102.596 -245.209441)
			(xy 102.616448 -245.168694) (xy 102.642301 -245.131143) (xy 102.657402 -245.114064) (xy 102.667219 -245.102586)
			(xy 102.680228 -245.075345) (xy 102.684692 -245.045488) (xy 102.680221 -245.015633) (xy 102.667206 -244.988394)
			(xy 102.657402 -244.976904) (xy 102.641139 -244.958537) (xy 102.613696 -244.917874) (xy 102.59257 -244.873599)
			(xy 102.578225 -244.826686) (xy 102.570977 -244.778167) (xy 102.570534 -244.753638) (xy 102.570534 -244.753384)
			(xy 102.571043 -244.727417) (xy 102.579168 -244.676122) (xy 102.595216 -244.626729) (xy 102.618794 -244.580455)
			(xy 102.64932 -244.538439) (xy 102.686043 -244.501716) (xy 102.728059 -244.47119) (xy 102.774333 -244.447612)
			(xy 102.823726 -244.431564) (xy 102.875021 -244.423439) (xy 102.926955 -244.423439) (xy 102.97825 -244.431564)
			(xy 103.027643 -244.447612) (xy 103.073917 -244.47119) (xy 103.115933 -244.501716) (xy 103.152656 -244.538439)
			(xy 103.183182 -244.580455) (xy 103.20676 -244.626729) (xy 103.222808 -244.676122) (xy 103.230933 -244.727417)
			(xy 103.231442 -244.753384) (xy 103.231442 -244.753638) (xy 103.231002 -244.778165) (xy 103.223735 -244.826678)
			(xy 103.20938 -244.873585) (xy 103.188252 -244.917856) (xy 103.160816 -244.95852) (xy 103.144574 -244.976904)
			(xy 103.134782 -244.988403) (xy 103.12176 -245.015636) (xy 103.117286 -245.045488) (xy 103.121753 -245.075341)
			(xy 103.134769 -245.102577) (xy 103.144574 -245.114064) (xy 103.160818 -245.132448) (xy 103.188264 -245.173106)
			(xy 103.209395 -245.217377) (xy 103.223744 -245.264286) (xy 103.230996 -245.312802) (xy 103.231442 -245.33733)
			(xy 103.231442 -245.337584) (xy 103.231257 -245.34749) (xy 108.103416 -245.34749) (xy 108.103416 -245.347236)
			(xy 108.103885 -245.32271) (xy 108.111143 -245.274198) (xy 108.12549 -245.227291) (xy 108.146612 -245.183019)
			(xy 108.174043 -245.142354) (xy 108.190284 -245.12397) (xy 108.200096 -245.112488) (xy 108.213108 -245.085248)
			(xy 108.217574 -245.055393) (xy 108.213104 -245.025538) (xy 108.200088 -244.9983) (xy 108.190284 -244.98681)
			(xy 108.174021 -244.968443) (xy 108.146579 -244.927779) (xy 108.125452 -244.883504) (xy 108.111108 -244.836591)
			(xy 108.10386 -244.788073) (xy 108.103416 -244.763544) (xy 108.103416 -244.76329) (xy 108.103925 -244.737323)
			(xy 108.11205 -244.686028) (xy 108.128098 -244.636635) (xy 108.151676 -244.590361) (xy 108.182202 -244.548345)
			(xy 108.218925 -244.511622) (xy 108.260941 -244.481096) (xy 108.307215 -244.457518) (xy 108.356608 -244.44147)
			(xy 108.407903 -244.433345) (xy 108.459837 -244.433345) (xy 108.511132 -244.44147) (xy 108.560525 -244.457518)
			(xy 108.606799 -244.481096) (xy 108.648815 -244.511622) (xy 108.685538 -244.548345) (xy 108.716064 -244.590361)
			(xy 108.739642 -244.636635) (xy 108.75569 -244.686028) (xy 108.763815 -244.737323) (xy 108.764315 -244.762841)
			(xy 109.900975 -244.762841) (xy 109.900975 -244.710907) (xy 109.9091 -244.659612) (xy 109.925148 -244.610219)
			(xy 109.948726 -244.563945) (xy 109.979252 -244.521929) (xy 110.015975 -244.485206) (xy 110.057991 -244.45468)
			(xy 110.104265 -244.431102) (xy 110.153658 -244.415054) (xy 110.204953 -244.406929) (xy 110.256887 -244.406929)
			(xy 110.308182 -244.415054) (xy 110.357575 -244.431102) (xy 110.403849 -244.45468) (xy 110.445865 -244.485206)
			(xy 110.482588 -244.521929) (xy 110.513114 -244.563945) (xy 110.536692 -244.610219) (xy 110.55274 -244.659612)
			(xy 110.560865 -244.710907) (xy 110.561374 -244.736874) (xy 110.560865 -244.762841) (xy 110.55274 -244.814136)
			(xy 110.536692 -244.863529) (xy 110.513114 -244.909803) (xy 110.482588 -244.951819) (xy 110.445865 -244.988542)
			(xy 110.403849 -245.019068) (xy 110.357575 -245.042646) (xy 110.308182 -245.058694) (xy 110.256887 -245.066819)
			(xy 110.204953 -245.066819) (xy 110.153658 -245.058694) (xy 110.104265 -245.042646) (xy 110.057991 -245.019068)
			(xy 110.015975 -244.988542) (xy 109.979252 -244.951819) (xy 109.948726 -244.909803) (xy 109.925148 -244.863529)
			(xy 109.9091 -244.814136) (xy 109.900975 -244.762841) (xy 108.764315 -244.762841) (xy 108.764324 -244.76329)
			(xy 108.764324 -244.763544) (xy 108.763892 -244.788071) (xy 108.756624 -244.836585) (xy 108.742267 -244.883492)
			(xy 108.721138 -244.927763) (xy 108.6937 -244.968427) (xy 108.677456 -244.98681) (xy 108.66766 -244.998306)
			(xy 108.654641 -245.02554) (xy 108.650169 -245.055393) (xy 108.654636 -245.085246) (xy 108.667651 -245.112482)
			(xy 108.677456 -245.12397) (xy 108.6937 -245.142354) (xy 108.721147 -245.183011) (xy 108.742278 -245.227282)
			(xy 108.756627 -245.274192) (xy 108.763879 -245.322708) (xy 108.764324 -245.347236) (xy 108.764324 -245.34749)
			(xy 108.763815 -245.373457) (xy 108.75569 -245.424752) (xy 108.739642 -245.474145) (xy 108.716064 -245.520419)
			(xy 108.685538 -245.562435) (xy 108.671062 -245.576911) (xy 113.190275 -245.576911) (xy 113.190275 -245.524977)
			(xy 113.1984 -245.473682) (xy 113.214448 -245.424289) (xy 113.238026 -245.378015) (xy 113.268552 -245.335999)
			(xy 113.305275 -245.299276) (xy 113.347291 -245.26875) (xy 113.393565 -245.245172) (xy 113.442958 -245.229124)
			(xy 113.494253 -245.220999) (xy 113.546187 -245.220999) (xy 113.597482 -245.229124) (xy 113.646875 -245.245172)
			(xy 113.693149 -245.26875) (xy 113.735165 -245.299276) (xy 113.771888 -245.335999) (xy 113.802414 -245.378015)
			(xy 113.811968 -245.396766) (xy 115.085368 -245.396766) (xy 115.085368 -245.396512) (xy 115.085835 -245.371986)
			(xy 115.093096 -245.323474) (xy 115.107444 -245.276568) (xy 115.128565 -245.232296) (xy 115.155996 -245.19163)
			(xy 115.172236 -245.173246) (xy 115.182076 -245.161784) (xy 115.195091 -245.134538) (xy 115.199555 -245.104675)
			(xy 115.195076 -245.074814) (xy 115.182048 -245.047574) (xy 115.172236 -245.036086) (xy 115.15597 -245.017721)
			(xy 115.128526 -244.977058) (xy 115.1074 -244.932782) (xy 115.093056 -244.885869) (xy 115.08581 -244.837349)
			(xy 115.085368 -244.81282) (xy 115.085368 -244.812566) (xy 115.085877 -244.786599) (xy 115.094002 -244.735304)
			(xy 115.11005 -244.685911) (xy 115.133628 -244.639637) (xy 115.164154 -244.597621) (xy 115.200877 -244.560898)
			(xy 115.242893 -244.530372) (xy 115.289167 -244.506794) (xy 115.33856 -244.490746) (xy 115.389855 -244.482621)
			(xy 115.441789 -244.482621) (xy 115.493084 -244.490746) (xy 115.542477 -244.506794) (xy 115.588751 -244.530372)
			(xy 115.630767 -244.560898) (xy 115.66749 -244.597621) (xy 115.698016 -244.639637) (xy 115.721594 -244.685911)
			(xy 115.737642 -244.735304) (xy 115.745767 -244.786599) (xy 115.746276 -244.812566) (xy 115.746276 -244.81282)
			(xy 115.745817 -244.837346) (xy 115.738553 -244.885858) (xy 115.724202 -244.932764) (xy 115.703079 -244.977036)
			(xy 115.675648 -245.017701) (xy 115.659408 -245.036086) (xy 115.649639 -245.047602) (xy 115.636624 -245.07483)
			(xy 115.63215 -245.104675) (xy 115.636609 -245.134522) (xy 115.649611 -245.161757) (xy 115.659408 -245.173246)
			(xy 115.675649 -245.191632) (xy 115.703095 -245.23229) (xy 115.724225 -245.27656) (xy 115.738575 -245.323469)
			(xy 115.745829 -245.371985) (xy 115.746276 -245.396512) (xy 115.746276 -245.396766) (xy 115.745767 -245.422733)
			(xy 115.737642 -245.474028) (xy 115.721594 -245.523421) (xy 115.698016 -245.569695) (xy 115.66749 -245.611711)
			(xy 115.630767 -245.648434) (xy 115.588751 -245.67896) (xy 115.542477 -245.702538) (xy 115.493084 -245.718586)
			(xy 115.441789 -245.726711) (xy 115.389855 -245.726711) (xy 115.33856 -245.718586) (xy 115.289167 -245.702538)
			(xy 115.242893 -245.67896) (xy 115.200877 -245.648434) (xy 115.164154 -245.611711) (xy 115.133628 -245.569695)
			(xy 115.11005 -245.523421) (xy 115.094002 -245.474028) (xy 115.085877 -245.422733) (xy 115.085368 -245.396766)
			(xy 113.811968 -245.396766) (xy 113.825992 -245.424289) (xy 113.84204 -245.473682) (xy 113.850165 -245.524977)
			(xy 113.850674 -245.550944) (xy 113.850165 -245.576911) (xy 113.84204 -245.628206) (xy 113.825992 -245.677599)
			(xy 113.802414 -245.723873) (xy 113.771888 -245.765889) (xy 113.735165 -245.802612) (xy 113.693149 -245.833138)
			(xy 113.646875 -245.856716) (xy 113.597482 -245.872764) (xy 113.546187 -245.880889) (xy 113.494253 -245.880889)
			(xy 113.442958 -245.872764) (xy 113.393565 -245.856716) (xy 113.347291 -245.833138) (xy 113.305275 -245.802612)
			(xy 113.268552 -245.765889) (xy 113.238026 -245.723873) (xy 113.214448 -245.677599) (xy 113.1984 -245.628206)
			(xy 113.190275 -245.576911) (xy 108.671062 -245.576911) (xy 108.648815 -245.599158) (xy 108.606799 -245.629684)
			(xy 108.560525 -245.653262) (xy 108.511132 -245.66931) (xy 108.459837 -245.677435) (xy 108.407903 -245.677435)
			(xy 108.356608 -245.66931) (xy 108.307215 -245.653262) (xy 108.260941 -245.629684) (xy 108.218925 -245.599158)
			(xy 108.182202 -245.562435) (xy 108.151676 -245.520419) (xy 108.128098 -245.474145) (xy 108.11205 -245.424752)
			(xy 108.103925 -245.373457) (xy 108.103416 -245.34749) (xy 103.231257 -245.34749) (xy 103.230956 -245.363553)
			(xy 103.222833 -245.414853) (xy 103.206785 -245.464251) (xy 103.183206 -245.510529) (xy 103.152678 -245.552549)
			(xy 103.115952 -245.589275) (xy 103.073932 -245.619804) (xy 103.027654 -245.643383) (xy 102.978257 -245.659432)
			(xy 102.926957 -245.667556) (xy 102.900988 -245.668038) (xy 102.900734 -245.668038) (xy 102.875297 -245.667558)
			(xy 102.825023 -245.659764) (xy 102.776543 -245.64434) (xy 102.731008 -245.621654) (xy 102.70998 -245.607332)
			(xy 102.698726 -245.59982) (xy 102.673346 -245.590463) (xy 102.646399 -245.588113) (xy 102.619783 -245.592937)
			(xy 102.595374 -245.604593) (xy 102.574892 -245.622262) (xy 102.559781 -245.644696) (xy 102.55504 -245.65737)
			(xy 102.54628 -245.681497) (xy 102.522417 -245.726938) (xy 102.491811 -245.768139) (xy 102.455199 -245.80411)
			(xy 102.413463 -245.833983) (xy 102.367607 -245.85704) (xy 102.318737 -245.872725) (xy 102.268029 -245.88066)
			(xy 102.242366 -245.881144) (xy 102.2164 -245.880652) (xy 102.165107 -245.872523) (xy 102.115718 -245.856471)
			(xy 102.069447 -245.832891) (xy 102.027435 -245.802363) (xy 101.990715 -245.765639) (xy 101.960191 -245.723624)
			(xy 101.936616 -245.677351) (xy 101.920569 -245.62796) (xy 101.912445 -245.576666) (xy 101.63251 -245.576666)
			(xy 101.624386 -245.627952) (xy 101.608338 -245.677345) (xy 101.58476 -245.723619) (xy 101.554234 -245.765635)
			(xy 101.517511 -245.802358) (xy 101.475495 -245.832884) (xy 101.429221 -245.856462) (xy 101.379828 -245.87251)
			(xy 101.328533 -245.880635) (xy 101.276599 -245.880635) (xy 101.225304 -245.87251) (xy 101.175911 -245.856462)
			(xy 101.129637 -245.832884) (xy 101.087621 -245.802358) (xy 101.050898 -245.765635) (xy 101.020372 -245.723619)
			(xy 100.996794 -245.677345) (xy 100.980746 -245.627952) (xy 100.972621 -245.576657) (xy 100.692711 -245.576657)
			(xy 100.684586 -245.627952) (xy 100.668538 -245.677345) (xy 100.64496 -245.723619) (xy 100.614434 -245.765635)
			(xy 100.577711 -245.802358) (xy 100.535695 -245.832884) (xy 100.489421 -245.856462) (xy 100.440028 -245.87251)
			(xy 100.388733 -245.880635) (xy 100.336799 -245.880635) (xy 100.285504 -245.87251) (xy 100.236111 -245.856462)
			(xy 100.189837 -245.832884) (xy 100.147821 -245.802358) (xy 100.111098 -245.765635) (xy 100.080572 -245.723619)
			(xy 100.056994 -245.677345) (xy 100.040946 -245.627952) (xy 100.032821 -245.576657) (xy 99.753235 -245.576657)
			(xy 99.753235 -245.576692) (xy 99.745102 -245.628035) (xy 99.729037 -245.677474) (xy 99.705436 -245.723791)
			(xy 99.674879 -245.765845) (xy 99.638119 -245.802601) (xy 99.596062 -245.833154) (xy 99.549743 -245.85675)
			(xy 99.500302 -245.87281) (xy 99.448958 -245.880937) (xy 99.422966 -245.881398) (xy 99.394985 -245.880789)
			(xy 99.339827 -245.871339) (xy 99.313238 -245.862602) (xy 99.312984 -245.862602) (xy 99.306768 -245.860639)
			(xy 99.293777 -245.859608) (xy 99.28733 -245.86057) (xy 99.281813 -245.861704) (xy 99.271431 -245.866065)
			(xy 99.266756 -245.869206) (xy 99.199192 -245.916958) (xy 99.19462 -245.920514) (xy 99.187003 -245.927981)
			(xy 99.17833 -245.947449) (xy 99.177856 -245.958106) (xy 99.177856 -246.100854) (xy 99.178178 -246.10934)
			(xy 99.183627 -246.125411) (xy 99.188524 -246.13235) (xy 99.191826 -246.13616) (xy 99.208903 -246.154725)
			(xy 99.237799 -246.196067) (xy 99.26008 -246.241319) (xy 99.275227 -246.28943) (xy 99.282889 -246.339284)
			(xy 99.282888 -246.389724) (xy 99.282773 -246.390473) (xy 99.562667 -246.390473) (xy 99.562667 -246.338539)
			(xy 99.570792 -246.287244) (xy 99.58684 -246.237851) (xy 99.610418 -246.191577) (xy 99.640944 -246.149561)
			(xy 99.677667 -246.112838) (xy 99.719683 -246.082312) (xy 99.765957 -246.058734) (xy 99.81535 -246.042686)
			(xy 99.866645 -246.034561) (xy 99.918579 -246.034561) (xy 99.969874 -246.042686) (xy 100.019267 -246.058734)
			(xy 100.065541 -246.082312) (xy 100.107557 -246.112838) (xy 100.14428 -246.149561) (xy 100.174806 -246.191577)
			(xy 100.198384 -246.237851) (xy 100.214432 -246.287244) (xy 100.222557 -246.338539) (xy 100.223066 -246.364506)
			(xy 100.222557 -246.390473) (xy 100.502721 -246.390473) (xy 100.502721 -246.338539) (xy 100.510846 -246.287244)
			(xy 100.526894 -246.237851) (xy 100.550472 -246.191577) (xy 100.580998 -246.149561) (xy 100.617721 -246.112838)
			(xy 100.659737 -246.082312) (xy 100.706011 -246.058734) (xy 100.755404 -246.042686) (xy 100.806699 -246.034561)
			(xy 100.858633 -246.034561) (xy 100.909928 -246.042686) (xy 100.959321 -246.058734) (xy 101.005595 -246.082312)
			(xy 101.047611 -246.112838) (xy 101.084334 -246.149561) (xy 101.11486 -246.191577) (xy 101.138438 -246.237851)
			(xy 101.154486 -246.287244) (xy 101.162611 -246.338539) (xy 101.16312 -246.364506) (xy 101.162611 -246.390473)
			(xy 101.442267 -246.390473) (xy 101.442267 -246.338539) (xy 101.450392 -246.287244) (xy 101.46644 -246.237851)
			(xy 101.490018 -246.191577) (xy 101.520544 -246.149561) (xy 101.557267 -246.112838) (xy 101.599283 -246.082312)
			(xy 101.645557 -246.058734) (xy 101.69495 -246.042686) (xy 101.746245 -246.034561) (xy 101.798179 -246.034561)
			(xy 101.849474 -246.042686) (xy 101.898867 -246.058734) (xy 101.945141 -246.082312) (xy 101.987157 -246.112838)
			(xy 102.02388 -246.149561) (xy 102.054406 -246.191577) (xy 102.077984 -246.237851) (xy 102.094032 -246.287244)
			(xy 102.102157 -246.338539) (xy 102.102666 -246.364506) (xy 102.102157 -246.390473) (xy 102.094032 -246.441768)
			(xy 102.077984 -246.491161) (xy 102.054406 -246.537435) (xy 102.02388 -246.579451) (xy 101.987157 -246.616174)
			(xy 101.945141 -246.6467) (xy 101.898867 -246.670278) (xy 101.852426 -246.685367) (xy 102.485455 -246.685367)
			(xy 102.485455 -246.633433) (xy 102.493579 -246.582139) (xy 102.509627 -246.532747) (xy 102.533204 -246.486474)
			(xy 102.563729 -246.444459) (xy 102.600451 -246.407736) (xy 102.642466 -246.377209) (xy 102.688738 -246.353631)
			(xy 102.738129 -246.337582) (xy 102.789423 -246.329456) (xy 102.81539 -246.328946) (xy 102.815644 -246.328946)
			(xy 102.840171 -246.329385) (xy 102.888684 -246.336653) (xy 102.93559 -246.351009) (xy 102.979862 -246.372136)
			(xy 103.020526 -246.399572) (xy 103.03891 -246.415814) (xy 103.050399 -246.425617) (xy 103.077636 -246.438631)
			(xy 103.10749 -246.443099) (xy 103.137344 -246.438631) (xy 103.164581 -246.425617) (xy 103.17607 -246.415814)
			(xy 103.194469 -246.39955) (xy 103.235175 -246.372082) (xy 103.279499 -246.350944) (xy 103.326465 -246.336603)
			(xy 103.375036 -246.329374) (xy 103.39959 -246.328946) (xy 103.424143 -246.329368) (xy 103.47271 -246.336614)
			(xy 103.519672 -246.350962) (xy 103.563996 -246.372098) (xy 103.604706 -246.399556) (xy 103.62311 -246.415814)
			(xy 103.634599 -246.425617) (xy 103.661836 -246.438631) (xy 103.69169 -246.443099) (xy 103.721544 -246.438631)
			(xy 103.748781 -246.425617) (xy 103.76027 -246.415814) (xy 103.778669 -246.39955) (xy 103.819375 -246.372082)
			(xy 103.863699 -246.350944) (xy 103.910665 -246.336603) (xy 103.959236 -246.329374) (xy 103.98379 -246.328946)
			(xy 104.008343 -246.329368) (xy 104.05691 -246.336614) (xy 104.103872 -246.350962) (xy 104.148196 -246.372098)
			(xy 104.188906 -246.399556) (xy 104.20731 -246.415814) (xy 104.218799 -246.425617) (xy 104.246036 -246.438631)
			(xy 104.27589 -246.443099) (xy 104.305744 -246.438631) (xy 104.332981 -246.425617) (xy 104.34447 -246.415814)
			(xy 104.36285 -246.399566) (xy 104.403509 -246.37212) (xy 104.447781 -246.35099) (xy 104.494691 -246.336642)
			(xy 104.543208 -246.329391) (xy 104.567736 -246.328946) (xy 104.56799 -246.328946) (xy 104.593402 -246.329377)
			(xy 104.643623 -246.337177) (xy 104.692062 -246.352564) (xy 104.737578 -246.375177) (xy 104.779102 -246.404483)
			(xy 104.815656 -246.439794) (xy 104.831388 -246.459756) (xy 104.841111 -246.471705) (xy 104.866155 -246.489618)
			(xy 104.895398 -246.499257) (xy 104.926184 -246.499748) (xy 104.955719 -246.491045) (xy 104.981321 -246.473939)
			(xy 104.991408 -246.462296) (xy 105.007209 -246.443447) (xy 105.043388 -246.410131) (xy 105.084107 -246.382546)
			(xy 105.128465 -246.361302) (xy 105.175482 -246.346869) (xy 105.224119 -246.339565) (xy 105.24871 -246.339106)
			(xy 105.274464 -246.339583) (xy 105.32535 -246.347565) (xy 105.37438 -246.363349) (xy 105.420366 -246.386552)
			(xy 105.462193 -246.416613) (xy 105.480866 -246.434356) (xy 105.490556 -246.443349) (xy 105.513488 -246.456481)
			(xy 105.539027 -246.463276) (xy 105.565453 -246.463276) (xy 105.590992 -246.456481) (xy 105.613924 -246.443349)
			(xy 105.623614 -246.434356) (xy 105.642297 -246.416625) (xy 105.684127 -246.386576) (xy 105.730112 -246.363378)
			(xy 105.779137 -246.347592) (xy 105.830018 -246.3396) (xy 105.85577 -246.339106) (xy 105.881738 -246.339666)
			(xy 105.933034 -246.347787) (xy 105.982429 -246.363832) (xy 106.028705 -246.387407) (xy 106.033275 -246.390727)
			(xy 109.900975 -246.390727) (xy 109.900975 -246.338793) (xy 109.9091 -246.287498) (xy 109.925148 -246.238105)
			(xy 109.948726 -246.191831) (xy 109.979252 -246.149815) (xy 110.015975 -246.113092) (xy 110.057991 -246.082566)
			(xy 110.104265 -246.058988) (xy 110.153658 -246.04294) (xy 110.204953 -246.034815) (xy 110.256887 -246.034815)
			(xy 110.308182 -246.04294) (xy 110.357575 -246.058988) (xy 110.403849 -246.082566) (xy 110.445865 -246.113092)
			(xy 110.482588 -246.149815) (xy 110.513114 -246.191831) (xy 110.536692 -246.238105) (xy 110.55274 -246.287498)
			(xy 110.560865 -246.338793) (xy 110.561374 -246.36476) (xy 110.560865 -246.390727) (xy 110.55274 -246.442022)
			(xy 110.536692 -246.491415) (xy 110.513114 -246.537689) (xy 110.482588 -246.579705) (xy 110.445865 -246.616428)
			(xy 110.403849 -246.646954) (xy 110.357575 -246.670532) (xy 110.308182 -246.68658) (xy 110.256887 -246.694705)
			(xy 110.204953 -246.694705) (xy 110.153658 -246.68658) (xy 110.104265 -246.670532) (xy 110.057991 -246.646954)
			(xy 110.015975 -246.616428) (xy 109.979252 -246.579705) (xy 109.948726 -246.537689) (xy 109.925148 -246.491415)
			(xy 109.9091 -246.442022) (xy 109.900975 -246.390727) (xy 106.033275 -246.390727) (xy 106.070723 -246.417932)
			(xy 106.107449 -246.454654) (xy 106.137977 -246.496669) (xy 106.161556 -246.542943) (xy 106.177606 -246.592337)
			(xy 106.185731 -246.643632) (xy 106.185731 -246.695568) (xy 106.177606 -246.746863) (xy 106.161556 -246.796257)
			(xy 106.137977 -246.842531) (xy 106.107449 -246.884546) (xy 106.070723 -246.921268) (xy 106.028705 -246.951793)
			(xy 105.982429 -246.975368) (xy 105.933034 -246.991413) (xy 105.881738 -246.999534) (xy 105.85577 -247.000014)
			(xy 105.830016 -246.999544) (xy 105.77913 -246.991559) (xy 105.7301 -246.975774) (xy 105.684114 -246.952569)
			(xy 105.642287 -246.922507) (xy 105.623614 -246.904764) (xy 105.613924 -246.895771) (xy 105.590992 -246.882639)
			(xy 105.565453 -246.875844) (xy 105.539027 -246.875844) (xy 105.513488 -246.882639) (xy 105.490556 -246.895771)
			(xy 105.480866 -246.904764) (xy 105.462195 -246.922508) (xy 105.420361 -246.952554) (xy 105.374374 -246.975749)
			(xy 105.325346 -246.991532) (xy 105.274463 -246.999521) (xy 105.24871 -247.000014) (xy 105.2233 -246.99956)
			(xy 105.17308 -246.991761) (xy 105.124643 -246.976377) (xy 105.079127 -246.953769) (xy 105.037603 -246.924468)
			(xy 105.001046 -246.889163) (xy 104.985312 -246.869204) (xy 104.975588 -246.857258) (xy 104.950542 -246.839352)
			(xy 104.921301 -246.829717) (xy 104.890517 -246.829226) (xy 104.860984 -246.837926) (xy 104.835381 -246.855025)
			(xy 104.825292 -246.866664) (xy 104.809481 -246.885505) (xy 104.773305 -246.918823) (xy 104.732589 -246.94641)
			(xy 104.688233 -246.967656) (xy 104.641217 -246.98209) (xy 104.592581 -246.989395) (xy 104.56799 -246.989854)
			(xy 104.567736 -246.989854) (xy 104.543211 -246.989367) (xy 104.4947 -246.98211) (xy 104.447794 -246.967766)
			(xy 104.403522 -246.94665) (xy 104.362855 -246.919224) (xy 104.34447 -246.902986) (xy 104.332981 -246.893183)
			(xy 104.305744 -246.880169) (xy 104.27589 -246.875701) (xy 104.246036 -246.880169) (xy 104.218799 -246.893183)
			(xy 104.20731 -246.902986) (xy 104.188919 -246.91926) (xy 104.148211 -246.946726) (xy 104.103884 -246.967862)
			(xy 104.056917 -246.982201) (xy 104.008344 -246.989427) (xy 103.98379 -246.989854) (xy 103.959239 -246.989384)
			(xy 103.910674 -246.982149) (xy 103.863713 -246.967812) (xy 103.819388 -246.946687) (xy 103.778675 -246.919239)
			(xy 103.76027 -246.902986) (xy 103.748781 -246.893183) (xy 103.721544 -246.880169) (xy 103.69169 -246.875701)
			(xy 103.661836 -246.880169) (xy 103.634599 -246.893183) (xy 103.62311 -246.902986) (xy 103.604719 -246.91926)
			(xy 103.564011 -246.946726) (xy 103.519684 -246.967862) (xy 103.472717 -246.982201) (xy 103.424144 -246.989427)
			(xy 103.39959 -246.989854) (xy 103.375039 -246.989384) (xy 103.326474 -246.982149) (xy 103.279513 -246.967812)
			(xy 103.235188 -246.946687) (xy 103.194475 -246.919239) (xy 103.17607 -246.902986) (xy 103.164581 -246.893183)
			(xy 103.137344 -246.880169) (xy 103.10749 -246.875701) (xy 103.077636 -246.880169) (xy 103.050399 -246.893183)
			(xy 103.03891 -246.902986) (xy 103.020538 -246.919244) (xy 102.979877 -246.946688) (xy 102.935603 -246.967816)
			(xy 102.888691 -246.982162) (xy 102.840172 -246.98941) (xy 102.815644 -246.989854) (xy 102.81539 -246.989854)
			(xy 102.789423 -246.989344) (xy 102.738129 -246.981218) (xy 102.688738 -246.965169) (xy 102.642466 -246.941591)
			(xy 102.600451 -246.911064) (xy 102.563729 -246.874341) (xy 102.533204 -246.832326) (xy 102.509627 -246.786053)
			(xy 102.493579 -246.736661) (xy 102.485455 -246.685367) (xy 101.852426 -246.685367) (xy 101.849474 -246.686326)
			(xy 101.798179 -246.694451) (xy 101.746245 -246.694451) (xy 101.69495 -246.686326) (xy 101.645557 -246.670278)
			(xy 101.599283 -246.6467) (xy 101.557267 -246.616174) (xy 101.520544 -246.579451) (xy 101.490018 -246.537435)
			(xy 101.46644 -246.491161) (xy 101.450392 -246.441768) (xy 101.442267 -246.390473) (xy 101.162611 -246.390473)
			(xy 101.154486 -246.441768) (xy 101.138438 -246.491161) (xy 101.11486 -246.537435) (xy 101.084334 -246.579451)
			(xy 101.047611 -246.616174) (xy 101.005595 -246.6467) (xy 100.959321 -246.670278) (xy 100.909928 -246.686326)
			(xy 100.858633 -246.694451) (xy 100.806699 -246.694451) (xy 100.755404 -246.686326) (xy 100.706011 -246.670278)
			(xy 100.659737 -246.6467) (xy 100.617721 -246.616174) (xy 100.580998 -246.579451) (xy 100.550472 -246.537435)
			(xy 100.526894 -246.491161) (xy 100.510846 -246.441768) (xy 100.502721 -246.390473) (xy 100.222557 -246.390473)
			(xy 100.214432 -246.441768) (xy 100.198384 -246.491161) (xy 100.174806 -246.537435) (xy 100.14428 -246.579451)
			(xy 100.107557 -246.616174) (xy 100.065541 -246.6467) (xy 100.019267 -246.670278) (xy 99.969874 -246.686326)
			(xy 99.918579 -246.694451) (xy 99.866645 -246.694451) (xy 99.81535 -246.686326) (xy 99.765957 -246.670278)
			(xy 99.719683 -246.6467) (xy 99.677667 -246.616174) (xy 99.640944 -246.579451) (xy 99.610418 -246.537435)
			(xy 99.58684 -246.491161) (xy 99.570792 -246.441768) (xy 99.562667 -246.390473) (xy 99.282773 -246.390473)
			(xy 99.275225 -246.439578) (xy 99.260076 -246.487689) (xy 99.237795 -246.532941) (xy 99.208897 -246.574282)
			(xy 99.191826 -246.592852) (xy 99.188524 -246.596662) (xy 99.18356 -246.603563) (xy 99.178125 -246.61966)
			(xy 99.177856 -246.628158) (xy 99.177856 -246.770906) (xy 99.178466 -246.781528) (xy 99.187136 -246.800933)
			(xy 99.19462 -246.808498) (xy 99.199192 -246.812054) (xy 99.247706 -246.846344) (xy 99.26828 -246.860822)
			(xy 99.279456 -246.86641) (xy 99.312984 -246.86641) (xy 99.320604 -246.86387) (xy 99.345516 -246.856302)
			(xy 99.396935 -246.848137) (xy 99.422966 -246.847614) (xy 99.448955 -246.848095) (xy 99.500295 -246.856221)
			(xy 99.54973 -246.872279) (xy 99.596045 -246.895874) (xy 99.638099 -246.926423) (xy 99.674855 -246.963176)
			(xy 99.705409 -247.005226) (xy 99.729008 -247.051538) (xy 99.745071 -247.100972) (xy 99.753203 -247.152311)
			(xy 99.753203 -247.204289) (xy 100.032821 -247.204289) (xy 100.032821 -247.152355) (xy 100.040946 -247.10106)
			(xy 100.056994 -247.051667) (xy 100.080572 -247.005393) (xy 100.111098 -246.963377) (xy 100.147821 -246.926654)
			(xy 100.189837 -246.896128) (xy 100.236111 -246.87255) (xy 100.285504 -246.856502) (xy 100.336799 -246.848377)
			(xy 100.388733 -246.848377) (xy 100.440028 -246.856502) (xy 100.489421 -246.87255) (xy 100.535695 -246.896128)
			(xy 100.577711 -246.926654) (xy 100.614434 -246.963377) (xy 100.64496 -247.005393) (xy 100.668538 -247.051667)
			(xy 100.684586 -247.10106) (xy 100.692711 -247.152355) (xy 100.69322 -247.178322) (xy 100.692711 -247.204289)
			(xy 100.972621 -247.204289) (xy 100.972621 -247.152355) (xy 100.980746 -247.10106) (xy 100.996794 -247.051667)
			(xy 101.020372 -247.005393) (xy 101.050898 -246.963377) (xy 101.087621 -246.926654) (xy 101.129637 -246.896128)
			(xy 101.175911 -246.87255) (xy 101.225304 -246.856502) (xy 101.276599 -246.848377) (xy 101.328533 -246.848377)
			(xy 101.379828 -246.856502) (xy 101.429221 -246.87255) (xy 101.475495 -246.896128) (xy 101.517511 -246.926654)
			(xy 101.554234 -246.963377) (xy 101.58476 -247.005393) (xy 101.608338 -247.051667) (xy 101.624386 -247.10106)
			(xy 101.632511 -247.152355) (xy 101.63302 -247.178322) (xy 101.632511 -247.204289) (xy 101.912421 -247.204289)
			(xy 101.912421 -247.152355) (xy 101.920546 -247.10106) (xy 101.936594 -247.051667) (xy 101.960172 -247.005393)
			(xy 101.990698 -246.963377) (xy 102.027421 -246.926654) (xy 102.069437 -246.896128) (xy 102.115711 -246.87255)
			(xy 102.165104 -246.856502) (xy 102.216399 -246.848377) (xy 102.268333 -246.848377) (xy 102.319628 -246.856502)
			(xy 102.369021 -246.87255) (xy 102.415295 -246.896128) (xy 102.457311 -246.926654) (xy 102.494034 -246.963377)
			(xy 102.52456 -247.005393) (xy 102.548138 -247.051667) (xy 102.564186 -247.10106) (xy 102.572311 -247.152355)
			(xy 102.57282 -247.178322) (xy 102.572311 -247.204289) (xy 102.572271 -247.204543) (xy 113.190275 -247.204543)
			(xy 113.190275 -247.152609) (xy 113.1984 -247.101314) (xy 113.214448 -247.051921) (xy 113.238026 -247.005647)
			(xy 113.268552 -246.963631) (xy 113.305275 -246.926908) (xy 113.347291 -246.896382) (xy 113.393565 -246.872804)
			(xy 113.442958 -246.856756) (xy 113.494253 -246.848631) (xy 113.546187 -246.848631) (xy 113.597482 -246.856756)
			(xy 113.646875 -246.872804) (xy 113.693149 -246.896382) (xy 113.735165 -246.926908) (xy 113.771888 -246.963631)
			(xy 113.802414 -247.005647) (xy 113.825992 -247.051921) (xy 113.84204 -247.101314) (xy 113.850165 -247.152609)
			(xy 113.850674 -247.178576) (xy 113.850165 -247.204543) (xy 113.84204 -247.255838) (xy 113.825992 -247.305231)
			(xy 113.802414 -247.351505) (xy 113.771888 -247.393521) (xy 113.735165 -247.430244) (xy 113.693149 -247.46077)
			(xy 113.646875 -247.484348) (xy 113.597482 -247.500396) (xy 113.546187 -247.508521) (xy 113.494253 -247.508521)
			(xy 113.442958 -247.500396) (xy 113.393565 -247.484348) (xy 113.347291 -247.46077) (xy 113.305275 -247.430244)
			(xy 113.268552 -247.393521) (xy 113.238026 -247.351505) (xy 113.214448 -247.305231) (xy 113.1984 -247.255838)
			(xy 113.190275 -247.204543) (xy 102.572271 -247.204543) (xy 102.564186 -247.255584) (xy 102.548138 -247.304977)
			(xy 102.52456 -247.351251) (xy 102.494034 -247.393267) (xy 102.457311 -247.42999) (xy 102.415295 -247.460516)
			(xy 102.369021 -247.484094) (xy 102.319628 -247.500142) (xy 102.268333 -247.508267) (xy 102.216399 -247.508267)
			(xy 102.165104 -247.500142) (xy 102.115711 -247.484094) (xy 102.069437 -247.460516) (xy 102.027421 -247.42999)
			(xy 101.990698 -247.393267) (xy 101.960172 -247.351251) (xy 101.936594 -247.304977) (xy 101.920546 -247.255584)
			(xy 101.912421 -247.204289) (xy 101.632511 -247.204289) (xy 101.624386 -247.255584) (xy 101.608338 -247.304977)
			(xy 101.58476 -247.351251) (xy 101.554234 -247.393267) (xy 101.517511 -247.42999) (xy 101.475495 -247.460516)
			(xy 101.429221 -247.484094) (xy 101.379828 -247.500142) (xy 101.328533 -247.508267) (xy 101.276599 -247.508267)
			(xy 101.225304 -247.500142) (xy 101.175911 -247.484094) (xy 101.129637 -247.460516) (xy 101.087621 -247.42999)
			(xy 101.050898 -247.393267) (xy 101.020372 -247.351251) (xy 100.996794 -247.304977) (xy 100.980746 -247.255584)
			(xy 100.972621 -247.204289) (xy 100.692711 -247.204289) (xy 100.684586 -247.255584) (xy 100.668538 -247.304977)
			(xy 100.64496 -247.351251) (xy 100.614434 -247.393267) (xy 100.577711 -247.42999) (xy 100.535695 -247.460516)
			(xy 100.489421 -247.484094) (xy 100.440028 -247.500142) (xy 100.388733 -247.508267) (xy 100.336799 -247.508267)
			(xy 100.285504 -247.500142) (xy 100.236111 -247.484094) (xy 100.189837 -247.460516) (xy 100.147821 -247.42999)
			(xy 100.111098 -247.393267) (xy 100.080572 -247.351251) (xy 100.056994 -247.304977) (xy 100.040946 -247.255584)
			(xy 100.032821 -247.204289) (xy 99.753203 -247.204289) (xy 99.745071 -247.255628) (xy 99.729008 -247.305062)
			(xy 99.705409 -247.351374) (xy 99.674855 -247.393424) (xy 99.638099 -247.430177) (xy 99.596045 -247.460726)
			(xy 99.54973 -247.484321) (xy 99.500295 -247.500379) (xy 99.448955 -247.508505) (xy 99.422966 -247.50903)
			(xy 99.394985 -247.508421) (xy 99.339826 -247.498972) (xy 99.313238 -247.490234) (xy 99.312984 -247.490234)
			(xy 99.306768 -247.488269) (xy 99.293777 -247.487238) (xy 99.28733 -247.488202) (xy 99.281814 -247.489337)
			(xy 99.271433 -247.4937) (xy 99.266756 -247.496838) (xy 99.199192 -247.54459) (xy 99.19462 -247.548146)
			(xy 99.187008 -247.555615) (xy 99.178347 -247.575083) (xy 99.177856 -247.585738) (xy 99.177856 -247.728232)
			(xy 99.19208 -247.763284) (xy 99.19589 -247.767602) (xy 99.212317 -247.786043) (xy 99.240079 -247.826884)
			(xy 99.261458 -247.8714) (xy 99.275979 -247.918601) (xy 99.283319 -247.967436) (xy 99.283315 -248.01682)
			(xy 99.283122 -248.018105) (xy 99.562667 -248.018105) (xy 99.562667 -247.966171) (xy 99.570792 -247.914876)
			(xy 99.58684 -247.865483) (xy 99.610418 -247.819209) (xy 99.640944 -247.777193) (xy 99.677667 -247.74047)
			(xy 99.719683 -247.709944) (xy 99.765957 -247.686366) (xy 99.81535 -247.670318) (xy 99.866645 -247.662193)
			(xy 99.918579 -247.662193) (xy 99.969874 -247.670318) (xy 100.019267 -247.686366) (xy 100.065541 -247.709944)
			(xy 100.107557 -247.74047) (xy 100.14428 -247.777193) (xy 100.174806 -247.819209) (xy 100.198384 -247.865483)
			(xy 100.214432 -247.914876) (xy 100.222557 -247.966171) (xy 100.223066 -247.992138) (xy 100.222557 -248.018105)
			(xy 100.502467 -248.018105) (xy 100.502467 -247.966171) (xy 100.510592 -247.914876) (xy 100.52664 -247.865483)
			(xy 100.550218 -247.819209) (xy 100.580744 -247.777193) (xy 100.617467 -247.74047) (xy 100.659483 -247.709944)
			(xy 100.705757 -247.686366) (xy 100.75515 -247.670318) (xy 100.806445 -247.662193) (xy 100.858379 -247.662193)
			(xy 100.909674 -247.670318) (xy 100.959067 -247.686366) (xy 101.005341 -247.709944) (xy 101.047357 -247.74047)
			(xy 101.08408 -247.777193) (xy 101.114606 -247.819209) (xy 101.138184 -247.865483) (xy 101.154232 -247.914876)
			(xy 101.162357 -247.966171) (xy 101.162866 -247.992138) (xy 101.162357 -248.018105) (xy 101.442267 -248.018105)
			(xy 101.442267 -247.966171) (xy 101.450392 -247.914876) (xy 101.46644 -247.865483) (xy 101.490018 -247.819209)
			(xy 101.520544 -247.777193) (xy 101.557267 -247.74047) (xy 101.599283 -247.709944) (xy 101.645557 -247.686366)
			(xy 101.69495 -247.670318) (xy 101.746245 -247.662193) (xy 101.798179 -247.662193) (xy 101.849474 -247.670318)
			(xy 101.898867 -247.686366) (xy 101.945141 -247.709944) (xy 101.987157 -247.74047) (xy 102.02388 -247.777193)
			(xy 102.054406 -247.819209) (xy 102.077984 -247.865483) (xy 102.094032 -247.914876) (xy 102.102157 -247.966171)
			(xy 102.102666 -247.992138) (xy 102.102157 -248.018105) (xy 102.102117 -248.018359) (xy 109.900975 -248.018359)
			(xy 109.900975 -247.966425) (xy 109.9091 -247.91513) (xy 109.925148 -247.865737) (xy 109.948726 -247.819463)
			(xy 109.979252 -247.777447) (xy 110.015975 -247.740724) (xy 110.057991 -247.710198) (xy 110.104265 -247.68662)
			(xy 110.153658 -247.670572) (xy 110.204953 -247.662447) (xy 110.256887 -247.662447) (xy 110.308182 -247.670572)
			(xy 110.357575 -247.68662) (xy 110.403849 -247.710198) (xy 110.445865 -247.740724) (xy 110.482588 -247.777447)
			(xy 110.513114 -247.819463) (xy 110.536692 -247.865737) (xy 110.55274 -247.91513) (xy 110.560865 -247.966425)
			(xy 110.561374 -247.992392) (xy 110.560865 -248.018359) (xy 110.55274 -248.069654) (xy 110.536692 -248.119047)
			(xy 110.513114 -248.165321) (xy 110.482588 -248.207337) (xy 110.445865 -248.24406) (xy 110.403849 -248.274586)
			(xy 110.357575 -248.298164) (xy 110.308182 -248.314212) (xy 110.256887 -248.322337) (xy 110.204953 -248.322337)
			(xy 110.153658 -248.314212) (xy 110.104265 -248.298164) (xy 110.057991 -248.274586) (xy 110.015975 -248.24406)
			(xy 109.979252 -248.207337) (xy 109.948726 -248.165321) (xy 109.925148 -248.119047) (xy 109.9091 -248.069654)
			(xy 109.900975 -248.018359) (xy 102.102117 -248.018359) (xy 102.094032 -248.0694) (xy 102.077984 -248.118793)
			(xy 102.054406 -248.165067) (xy 102.02388 -248.207083) (xy 101.987157 -248.243806) (xy 101.945141 -248.274332)
			(xy 101.898867 -248.29791) (xy 101.849474 -248.313958) (xy 101.798179 -248.322083) (xy 101.746245 -248.322083)
			(xy 101.69495 -248.313958) (xy 101.645557 -248.29791) (xy 101.599283 -248.274332) (xy 101.557267 -248.243806)
			(xy 101.520544 -248.207083) (xy 101.490018 -248.165067) (xy 101.46644 -248.118793) (xy 101.450392 -248.0694)
			(xy 101.442267 -248.018105) (xy 101.162357 -248.018105) (xy 101.154232 -248.0694) (xy 101.138184 -248.118793)
			(xy 101.114606 -248.165067) (xy 101.08408 -248.207083) (xy 101.047357 -248.243806) (xy 101.005341 -248.274332)
			(xy 100.959067 -248.29791) (xy 100.909674 -248.313958) (xy 100.858379 -248.322083) (xy 100.806445 -248.322083)
			(xy 100.75515 -248.313958) (xy 100.705757 -248.29791) (xy 100.659483 -248.274332) (xy 100.617467 -248.243806)
			(xy 100.580744 -248.207083) (xy 100.550218 -248.165067) (xy 100.52664 -248.118793) (xy 100.510592 -248.0694)
			(xy 100.502467 -248.018105) (xy 100.222557 -248.018105) (xy 100.214432 -248.0694) (xy 100.198384 -248.118793)
			(xy 100.174806 -248.165067) (xy 100.14428 -248.207083) (xy 100.107557 -248.243806) (xy 100.065541 -248.274332)
			(xy 100.019267 -248.29791) (xy 99.969874 -248.313958) (xy 99.918579 -248.322083) (xy 99.866645 -248.322083)
			(xy 99.81535 -248.313958) (xy 99.765957 -248.29791) (xy 99.719683 -248.274332) (xy 99.677667 -248.243806)
			(xy 99.640944 -248.207083) (xy 99.610418 -248.165067) (xy 99.58684 -248.118793) (xy 99.570792 -248.0694)
			(xy 99.562667 -248.018105) (xy 99.283122 -248.018105) (xy 99.275967 -248.065654) (xy 99.261438 -248.112852)
			(xy 99.240051 -248.157364) (xy 99.212282 -248.198201) (xy 99.19589 -248.216674) (xy 99.19208 -248.220992)
			(xy 99.177856 -248.256044) (xy 99.177856 -248.398792) (xy 99.178463 -248.409416) (xy 99.187129 -248.428825)
			(xy 99.19462 -248.436384) (xy 99.199192 -248.43994) (xy 99.247706 -248.47423) (xy 99.26828 -248.488708)
			(xy 99.279456 -248.494296) (xy 99.312984 -248.494296) (xy 99.320604 -248.491756) (xy 99.345516 -248.484188)
			(xy 99.396935 -248.476024) (xy 99.422966 -248.4755) (xy 99.448956 -248.475981) (xy 99.500298 -248.484107)
			(xy 99.549736 -248.500166) (xy 99.596053 -248.523762) (xy 99.638108 -248.554312) (xy 99.674865 -248.591066)
			(xy 99.705421 -248.633118) (xy 99.729021 -248.679433) (xy 99.745085 -248.728869) (xy 99.753217 -248.78021)
			(xy 99.753217 -248.832175) (xy 100.032821 -248.832175) (xy 100.032821 -248.780241) (xy 100.040946 -248.728946)
			(xy 100.056994 -248.679553) (xy 100.080572 -248.633279) (xy 100.111098 -248.591263) (xy 100.147821 -248.55454)
			(xy 100.189837 -248.524014) (xy 100.236111 -248.500436) (xy 100.285504 -248.484388) (xy 100.336799 -248.476263)
			(xy 100.388733 -248.476263) (xy 100.440028 -248.484388) (xy 100.489421 -248.500436) (xy 100.535695 -248.524014)
			(xy 100.577711 -248.55454) (xy 100.614434 -248.591263) (xy 100.64496 -248.633279) (xy 100.668538 -248.679553)
			(xy 100.684586 -248.728946) (xy 100.692711 -248.780241) (xy 100.69322 -248.806208) (xy 100.692711 -248.832175)
			(xy 100.972367 -248.832175) (xy 100.972367 -248.780241) (xy 100.980492 -248.728946) (xy 100.99654 -248.679553)
			(xy 101.020118 -248.633279) (xy 101.050644 -248.591263) (xy 101.087367 -248.55454) (xy 101.129383 -248.524014)
			(xy 101.175657 -248.500436) (xy 101.22505 -248.484388) (xy 101.276345 -248.476263) (xy 101.328279 -248.476263)
			(xy 101.379574 -248.484388) (xy 101.428967 -248.500436) (xy 101.475241 -248.524014) (xy 101.517257 -248.55454)
			(xy 101.55398 -248.591263) (xy 101.584506 -248.633279) (xy 101.608084 -248.679553) (xy 101.624132 -248.728946)
			(xy 101.632257 -248.780241) (xy 101.632766 -248.806208) (xy 101.632257 -248.832165) (xy 101.912463 -248.832165)
			(xy 101.912463 -248.780235) (xy 101.920586 -248.728945) (xy 101.936632 -248.679556) (xy 101.960207 -248.633286)
			(xy 101.990728 -248.591272) (xy 102.027446 -248.55455) (xy 102.069457 -248.524024) (xy 102.115725 -248.500445)
			(xy 102.165111 -248.484394) (xy 102.216401 -248.476266) (xy 102.242366 -248.475754) (xy 102.272133 -248.476387)
			(xy 102.330707 -248.487034) (xy 102.38643 -248.507991) (xy 102.412292 -248.522744) (xy 102.423902 -248.529256)
			(xy 102.449486 -248.536581) (xy 102.476094 -248.537032) (xy 102.501911 -248.530577) (xy 102.525176 -248.517658)
			(xy 102.544303 -248.499155) (xy 102.551484 -248.487946) (xy 102.564356 -248.46731) (xy 102.595233 -248.429733)
			(xy 102.631289 -248.397092) (xy 102.671741 -248.370092) (xy 102.715717 -248.349317) (xy 102.762264 -248.335217)
			(xy 102.810376 -248.328097) (xy 102.834694 -248.327672) (xy 102.860664 -248.328134) (xy 102.911966 -248.336259)
			(xy 102.961365 -248.35231) (xy 103.007644 -248.375891) (xy 103.049664 -248.406422) (xy 103.086391 -248.443151)
			(xy 103.116919 -248.485173) (xy 103.140498 -248.531454) (xy 103.156545 -248.580854) (xy 103.164667 -248.632156)
			(xy 103.165148 -248.658126) (xy 103.165148 -248.65838) (xy 103.164672 -248.682906) (xy 103.157413 -248.731417)
			(xy 103.143066 -248.778323) (xy 103.121947 -248.822595) (xy 103.094519 -248.863261) (xy 103.07828 -248.881646)
			(xy 103.068455 -248.893117) (xy 103.05545 -248.920361) (xy 103.050988 -248.950219) (xy 103.055461 -248.980076)
			(xy 103.067534 -249.005344) (xy 108.103416 -249.005344) (xy 108.103416 -249.00509) (xy 108.103858 -248.980563)
			(xy 108.111122 -248.932049) (xy 108.125476 -248.885142) (xy 108.146603 -248.840871) (xy 108.174041 -248.800207)
			(xy 108.190284 -248.781824) (xy 108.200044 -248.770301) (xy 108.213061 -248.743076) (xy 108.217538 -248.713233)
			(xy 108.21308 -248.683386) (xy 108.20008 -248.656153) (xy 108.190284 -248.644664) (xy 108.174047 -248.626275)
			(xy 108.146601 -248.585618) (xy 108.12547 -248.541348) (xy 108.111119 -248.49444) (xy 108.103864 -248.445925)
			(xy 108.103416 -248.421398) (xy 108.103416 -248.421144) (xy 108.103925 -248.395177) (xy 108.11205 -248.343882)
			(xy 108.128098 -248.294489) (xy 108.151676 -248.248215) (xy 108.182202 -248.206199) (xy 108.218925 -248.169476)
			(xy 108.260941 -248.13895) (xy 108.307215 -248.115372) (xy 108.356608 -248.099324) (xy 108.407903 -248.091199)
			(xy 108.459837 -248.091199) (xy 108.511132 -248.099324) (xy 108.560525 -248.115372) (xy 108.606799 -248.13895)
			(xy 108.648815 -248.169476) (xy 108.685538 -248.206199) (xy 108.716064 -248.248215) (xy 108.739642 -248.294489)
			(xy 108.75569 -248.343882) (xy 108.763815 -248.395177) (xy 108.764324 -248.421144) (xy 108.764324 -248.421398)
			(xy 108.763865 -248.445924) (xy 108.756603 -248.494437) (xy 108.742253 -248.541343) (xy 108.72113 -248.585615)
			(xy 108.693697 -248.62628) (xy 108.677456 -248.644664) (xy 108.667607 -248.656118) (xy 108.654594 -248.683367)
			(xy 108.650132 -248.713233) (xy 108.654613 -248.743095) (xy 108.667643 -248.770336) (xy 108.677456 -248.781824)
			(xy 108.693678 -248.800226) (xy 108.715422 -248.832429) (xy 113.190275 -248.832429) (xy 113.190275 -248.780495)
			(xy 113.1984 -248.7292) (xy 113.214448 -248.679807) (xy 113.238026 -248.633533) (xy 113.268552 -248.591517)
			(xy 113.305275 -248.554794) (xy 113.347291 -248.524268) (xy 113.393565 -248.50069) (xy 113.442958 -248.484642)
			(xy 113.494253 -248.476517) (xy 113.546187 -248.476517) (xy 113.597482 -248.484642) (xy 113.646875 -248.50069)
			(xy 113.693149 -248.524268) (xy 113.735165 -248.554794) (xy 113.771888 -248.591517) (xy 113.802414 -248.633533)
			(xy 113.825992 -248.679807) (xy 113.84204 -248.7292) (xy 113.850165 -248.780495) (xy 113.850674 -248.806462)
			(xy 113.850165 -248.832429) (xy 113.84204 -248.883724) (xy 113.825992 -248.933117) (xy 113.802414 -248.979391)
			(xy 113.771888 -249.021407) (xy 113.735165 -249.05813) (xy 113.693149 -249.088656) (xy 113.646875 -249.112234)
			(xy 113.597482 -249.128282) (xy 113.546187 -249.136407) (xy 113.494253 -249.136407) (xy 113.442958 -249.128282)
			(xy 113.393565 -249.112234) (xy 113.347291 -249.088656) (xy 113.305275 -249.05813) (xy 113.268552 -249.021407)
			(xy 113.238026 -248.979391) (xy 113.214448 -248.933117) (xy 113.1984 -248.883724) (xy 113.190275 -248.832429)
			(xy 108.715422 -248.832429) (xy 108.721128 -248.840879) (xy 108.742263 -248.885145) (xy 108.756618 -248.932051)
			(xy 108.763875 -248.980564) (xy 108.764324 -249.00509) (xy 108.764324 -249.005344) (xy 108.763815 -249.031311)
			(xy 108.75569 -249.082606) (xy 108.739642 -249.131999) (xy 108.716064 -249.178273) (xy 108.685538 -249.220289)
			(xy 108.678741 -249.227086) (xy 115.052348 -249.227086) (xy 115.052348 -249.226832) (xy 115.052832 -249.202307)
			(xy 115.060089 -249.153796) (xy 115.074434 -249.10689) (xy 115.095551 -249.062618) (xy 115.122978 -249.021951)
			(xy 115.139216 -249.003566) (xy 115.14903 -248.992086) (xy 115.162037 -248.964845) (xy 115.166501 -248.93499)
			(xy 115.162031 -248.905135) (xy 115.149018 -248.877896) (xy 115.139216 -248.866406) (xy 115.122957 -248.848036)
			(xy 115.095512 -248.807374) (xy 115.074385 -248.7631) (xy 115.060039 -248.716187) (xy 115.052791 -248.667669)
			(xy 115.052348 -248.64314) (xy 115.052348 -248.642886) (xy 115.052857 -248.616919) (xy 115.060982 -248.565624)
			(xy 115.07703 -248.516231) (xy 115.100608 -248.469957) (xy 115.131134 -248.427941) (xy 115.167857 -248.391218)
			(xy 115.209873 -248.360692) (xy 115.256147 -248.337114) (xy 115.30554 -248.321066) (xy 115.356835 -248.312941)
			(xy 115.408769 -248.312941) (xy 115.460064 -248.321066) (xy 115.509457 -248.337114) (xy 115.555731 -248.360692)
			(xy 115.597747 -248.391218) (xy 115.63447 -248.427941) (xy 115.664996 -248.469957) (xy 115.688574 -248.516231)
			(xy 115.704622 -248.565624) (xy 115.712747 -248.616919) (xy 115.713256 -248.642886) (xy 115.713256 -248.64314)
			(xy 115.712814 -248.667667) (xy 115.705546 -248.716179) (xy 115.691192 -248.763086) (xy 115.670065 -248.807357)
			(xy 115.64263 -248.848022) (xy 115.626388 -248.866406) (xy 115.616601 -248.877907) (xy 115.603591 -248.905141)
			(xy 115.599121 -248.93499) (xy 115.603585 -248.964839) (xy 115.61659 -248.992076) (xy 115.626388 -249.003566)
			(xy 115.642635 -249.021947) (xy 115.670081 -249.062606) (xy 115.69121 -249.106878) (xy 115.705559 -249.153788)
			(xy 115.712811 -249.202304) (xy 115.713256 -249.226832) (xy 115.713256 -249.227086) (xy 115.712747 -249.253053)
			(xy 115.704622 -249.304348) (xy 115.688574 -249.353741) (xy 115.664996 -249.400015) (xy 115.63447 -249.442031)
			(xy 115.597747 -249.478754) (xy 115.555731 -249.50928) (xy 115.509457 -249.532858) (xy 115.460064 -249.548906)
			(xy 115.408769 -249.557031) (xy 115.356835 -249.557031) (xy 115.30554 -249.548906) (xy 115.256147 -249.532858)
			(xy 115.209873 -249.50928) (xy 115.167857 -249.478754) (xy 115.131134 -249.442031) (xy 115.100608 -249.400015)
			(xy 115.07703 -249.353741) (xy 115.060982 -249.304348) (xy 115.052857 -249.253053) (xy 115.052348 -249.227086)
			(xy 108.678741 -249.227086) (xy 108.648815 -249.257012) (xy 108.606799 -249.287538) (xy 108.560525 -249.311116)
			(xy 108.511132 -249.327164) (xy 108.459837 -249.335289) (xy 108.407903 -249.335289) (xy 108.356608 -249.327164)
			(xy 108.307215 -249.311116) (xy 108.260941 -249.287538) (xy 108.218925 -249.257012) (xy 108.182202 -249.220289)
			(xy 108.151676 -249.178273) (xy 108.128098 -249.131999) (xy 108.11205 -249.082606) (xy 108.103925 -249.031311)
			(xy 108.103416 -249.005344) (xy 103.067534 -249.005344) (xy 103.068476 -249.007315) (xy 103.07828 -249.018806)
			(xy 103.094544 -249.037172) (xy 103.121988 -249.077835) (xy 103.143115 -249.12211) (xy 103.157459 -249.169024)
			(xy 103.164705 -249.217543) (xy 103.165148 -249.242072) (xy 103.165148 -249.242326) (xy 103.164639 -249.268293)
			(xy 103.156514 -249.319588) (xy 103.140466 -249.368981) (xy 103.116888 -249.415255) (xy 103.086362 -249.457271)
			(xy 103.049639 -249.493994) (xy 103.007623 -249.52452) (xy 102.961349 -249.548098) (xy 102.911956 -249.564146)
			(xy 102.860661 -249.572271) (xy 102.808727 -249.572271) (xy 102.757432 -249.564146) (xy 102.708039 -249.548098)
			(xy 102.661765 -249.52452) (xy 102.619749 -249.493994) (xy 102.583026 -249.457271) (xy 102.5525 -249.415255)
			(xy 102.528922 -249.368981) (xy 102.512874 -249.319588) (xy 102.504749 -249.268293) (xy 102.50424 -249.242326)
			(xy 102.505256 -249.215148) (xy 102.505935 -249.200357) (xy 102.499786 -249.171408) (xy 102.485604 -249.145432)
			(xy 102.464577 -249.124606) (xy 102.438466 -249.110676) (xy 102.409459 -249.104807) (xy 102.379986 -249.107492)
			(xy 102.366064 -249.112532) (xy 102.336378 -249.123758) (xy 102.274095 -249.135912) (xy 102.242366 -249.136662)
			(xy 102.216401 -249.136134) (xy 102.165111 -249.128006) (xy 102.115725 -249.111955) (xy 102.069457 -249.088376)
			(xy 102.027446 -249.05785) (xy 101.990728 -249.021128) (xy 101.960207 -248.979114) (xy 101.936632 -248.932844)
			(xy 101.920586 -248.883455) (xy 101.912463 -248.832165) (xy 101.632257 -248.832165) (xy 101.632257 -248.832175)
			(xy 101.624132 -248.88347) (xy 101.608084 -248.932863) (xy 101.584506 -248.979137) (xy 101.55398 -249.021153)
			(xy 101.517257 -249.057876) (xy 101.475241 -249.088402) (xy 101.428967 -249.11198) (xy 101.379574 -249.128028)
			(xy 101.328279 -249.136153) (xy 101.276345 -249.136153) (xy 101.22505 -249.128028) (xy 101.175657 -249.11198)
			(xy 101.129383 -249.088402) (xy 101.087367 -249.057876) (xy 101.050644 -249.021153) (xy 101.020118 -248.979137)
			(xy 100.99654 -248.932863) (xy 100.980492 -248.88347) (xy 100.972367 -248.832175) (xy 100.692711 -248.832175)
			(xy 100.684586 -248.88347) (xy 100.668538 -248.932863) (xy 100.64496 -248.979137) (xy 100.614434 -249.021153)
			(xy 100.577711 -249.057876) (xy 100.535695 -249.088402) (xy 100.489421 -249.11198) (xy 100.440028 -249.128028)
			(xy 100.388733 -249.136153) (xy 100.336799 -249.136153) (xy 100.285504 -249.128028) (xy 100.236111 -249.11198)
			(xy 100.189837 -249.088402) (xy 100.147821 -249.057876) (xy 100.111098 -249.021153) (xy 100.080572 -248.979137)
			(xy 100.056994 -248.932863) (xy 100.040946 -248.88347) (xy 100.032821 -248.832175) (xy 99.753217 -248.832175)
			(xy 99.753217 -248.83219) (xy 99.745085 -248.883531) (xy 99.729021 -248.932967) (xy 99.705421 -248.979282)
			(xy 99.674865 -249.021334) (xy 99.638108 -249.058088) (xy 99.596053 -249.088638) (xy 99.549736 -249.112234)
			(xy 99.500298 -249.128293) (xy 99.448956 -249.136419) (xy 99.422966 -249.136916) (xy 99.394985 -249.136307)
			(xy 99.339826 -249.126858) (xy 99.313238 -249.11812) (xy 99.312984 -249.11812) (xy 99.306768 -249.116156)
			(xy 99.293777 -249.115125) (xy 99.28733 -249.116088) (xy 99.281813 -249.117223) (xy 99.271432 -249.121584)
			(xy 99.266756 -249.124724) (xy 99.199192 -249.172476) (xy 99.19462 -249.176032) (xy 99.187005 -249.1835)
			(xy 99.17834 -249.202968) (xy 99.177856 -249.213624) (xy 99.177856 -249.356372) (xy 99.178181 -249.364857)
			(xy 99.183634 -249.380925) (xy 99.188524 -249.387868) (xy 99.191826 -249.391678) (xy 99.208902 -249.410243)
			(xy 99.237795 -249.451584) (xy 99.260073 -249.496835) (xy 99.275218 -249.544946) (xy 99.282877 -249.594798)
			(xy 99.282875 -249.645236) (xy 99.282759 -249.645991) (xy 99.562667 -249.645991) (xy 99.562667 -249.594057)
			(xy 99.570792 -249.542762) (xy 99.58684 -249.493369) (xy 99.610418 -249.447095) (xy 99.640944 -249.405079)
			(xy 99.677667 -249.368356) (xy 99.719683 -249.33783) (xy 99.765957 -249.314252) (xy 99.81535 -249.298204)
			(xy 99.866645 -249.290079) (xy 99.918579 -249.290079) (xy 99.969874 -249.298204) (xy 100.019267 -249.314252)
			(xy 100.065541 -249.33783) (xy 100.107557 -249.368356) (xy 100.14428 -249.405079) (xy 100.174806 -249.447095)
			(xy 100.198384 -249.493369) (xy 100.214432 -249.542762) (xy 100.222557 -249.594057) (xy 100.223066 -249.620024)
			(xy 100.222557 -249.645991) (xy 100.502467 -249.645991) (xy 100.502467 -249.594057) (xy 100.510592 -249.542762)
			(xy 100.52664 -249.493369) (xy 100.550218 -249.447095) (xy 100.580744 -249.405079) (xy 100.617467 -249.368356)
			(xy 100.659483 -249.33783) (xy 100.705757 -249.314252) (xy 100.75515 -249.298204) (xy 100.806445 -249.290079)
			(xy 100.858379 -249.290079) (xy 100.909674 -249.298204) (xy 100.959067 -249.314252) (xy 101.005341 -249.33783)
			(xy 101.047357 -249.368356) (xy 101.08408 -249.405079) (xy 101.114606 -249.447095) (xy 101.138184 -249.493369)
			(xy 101.154232 -249.542762) (xy 101.162357 -249.594057) (xy 101.162866 -249.620024) (xy 101.162357 -249.645991)
			(xy 101.442267 -249.645991) (xy 101.442267 -249.594057) (xy 101.450392 -249.542762) (xy 101.46644 -249.493369)
			(xy 101.490018 -249.447095) (xy 101.520544 -249.405079) (xy 101.557267 -249.368356) (xy 101.599283 -249.33783)
			(xy 101.645557 -249.314252) (xy 101.69495 -249.298204) (xy 101.746245 -249.290079) (xy 101.798179 -249.290079)
			(xy 101.849474 -249.298204) (xy 101.898867 -249.314252) (xy 101.945141 -249.33783) (xy 101.987157 -249.368356)
			(xy 102.02388 -249.405079) (xy 102.054406 -249.447095) (xy 102.077984 -249.493369) (xy 102.094032 -249.542762)
			(xy 102.102157 -249.594057) (xy 102.102666 -249.620024) (xy 102.102157 -249.645991) (xy 102.102117 -249.646245)
			(xy 109.900975 -249.646245) (xy 109.900975 -249.594311) (xy 109.9091 -249.543016) (xy 109.925148 -249.493623)
			(xy 109.948726 -249.447349) (xy 109.979252 -249.405333) (xy 110.015975 -249.36861) (xy 110.057991 -249.338084)
			(xy 110.104265 -249.314506) (xy 110.153658 -249.298458) (xy 110.204953 -249.290333) (xy 110.256887 -249.290333)
			(xy 110.308182 -249.298458) (xy 110.357575 -249.314506) (xy 110.403849 -249.338084) (xy 110.445865 -249.36861)
			(xy 110.482588 -249.405333) (xy 110.513114 -249.447349) (xy 110.536692 -249.493623) (xy 110.55274 -249.543016)
			(xy 110.560865 -249.594311) (xy 110.561374 -249.620278) (xy 110.560865 -249.646245) (xy 110.55274 -249.69754)
			(xy 110.536692 -249.746933) (xy 110.513114 -249.793207) (xy 110.482588 -249.835223) (xy 110.445865 -249.871946)
			(xy 110.403849 -249.902472) (xy 110.357575 -249.92605) (xy 110.308182 -249.942098) (xy 110.256887 -249.950223)
			(xy 110.204953 -249.950223) (xy 110.153658 -249.942098) (xy 110.104265 -249.92605) (xy 110.057991 -249.902472)
			(xy 110.015975 -249.871946) (xy 109.979252 -249.835223) (xy 109.948726 -249.793207) (xy 109.925148 -249.746933)
			(xy 109.9091 -249.69754) (xy 109.900975 -249.646245) (xy 102.102117 -249.646245) (xy 102.094032 -249.697286)
			(xy 102.077984 -249.746679) (xy 102.054406 -249.792953) (xy 102.02388 -249.834969) (xy 101.987157 -249.871692)
			(xy 101.945141 -249.902218) (xy 101.898867 -249.925796) (xy 101.849474 -249.941844) (xy 101.798179 -249.949969)
			(xy 101.746245 -249.949969) (xy 101.69495 -249.941844) (xy 101.645557 -249.925796) (xy 101.599283 -249.902218)
			(xy 101.557267 -249.871692) (xy 101.520544 -249.834969) (xy 101.490018 -249.792953) (xy 101.46644 -249.746679)
			(xy 101.450392 -249.697286) (xy 101.442267 -249.645991) (xy 101.162357 -249.645991) (xy 101.154232 -249.697286)
			(xy 101.138184 -249.746679) (xy 101.114606 -249.792953) (xy 101.08408 -249.834969) (xy 101.047357 -249.871692)
			(xy 101.005341 -249.902218) (xy 100.959067 -249.925796) (xy 100.909674 -249.941844) (xy 100.858379 -249.949969)
			(xy 100.806445 -249.949969) (xy 100.75515 -249.941844) (xy 100.705757 -249.925796) (xy 100.659483 -249.902218)
			(xy 100.617467 -249.871692) (xy 100.580744 -249.834969) (xy 100.550218 -249.792953) (xy 100.52664 -249.746679)
			(xy 100.510592 -249.697286) (xy 100.502467 -249.645991) (xy 100.222557 -249.645991) (xy 100.214432 -249.697286)
			(xy 100.198384 -249.746679) (xy 100.174806 -249.792953) (xy 100.14428 -249.834969) (xy 100.107557 -249.871692)
			(xy 100.065541 -249.902218) (xy 100.019267 -249.925796) (xy 99.969874 -249.941844) (xy 99.918579 -249.949969)
			(xy 99.866645 -249.949969) (xy 99.81535 -249.941844) (xy 99.765957 -249.925796) (xy 99.719683 -249.902218)
			(xy 99.677667 -249.871692) (xy 99.640944 -249.834969) (xy 99.610418 -249.792953) (xy 99.58684 -249.746679)
			(xy 99.570792 -249.697286) (xy 99.562667 -249.645991) (xy 99.282759 -249.645991) (xy 99.27521 -249.695088)
			(xy 99.26006 -249.743197) (xy 99.237778 -249.788446) (xy 99.20888 -249.829784) (xy 99.191826 -249.84837)
			(xy 99.188524 -249.85218) (xy 99.183548 -249.859078) (xy 99.178087 -249.875174) (xy 99.177856 -249.883676)
			(xy 99.177856 -251.135134) (xy 102.50424 -251.135134) (xy 102.50424 -251.13488) (xy 102.504695 -251.110354)
			(xy 102.51196 -251.061842) (xy 102.526311 -251.014935) (xy 102.547435 -250.970664) (xy 102.574867 -250.929998)
			(xy 102.591108 -250.911614) (xy 102.600876 -250.900098) (xy 102.613889 -250.87287) (xy 102.618362 -250.843025)
			(xy 102.613904 -250.813178) (xy 102.600904 -250.785944) (xy 102.591108 -250.774454) (xy 102.57487 -250.756066)
			(xy 102.547423 -250.715409) (xy 102.526292 -250.671139) (xy 102.511941 -250.62423) (xy 102.504687 -250.575715)
			(xy 102.50424 -250.551188) (xy 102.50424 -250.550934) (xy 102.504749 -250.524967) (xy 102.512874 -250.473672)
			(xy 102.528922 -250.424279) (xy 102.5525 -250.378005) (xy 102.583026 -250.335989) (xy 102.619749 -250.299266)
			(xy 102.661765 -250.26874) (xy 102.708039 -250.245162) (xy 102.757432 -250.229114) (xy 102.808727 -250.220989)
			(xy 102.860661 -250.220989) (xy 102.911956 -250.229114) (xy 102.961349 -250.245162) (xy 103.007623 -250.26874)
			(xy 103.049639 -250.299266) (xy 103.086362 -250.335989) (xy 103.106179 -250.363265) (xy 105.127075 -250.363265)
			(xy 105.127075 -250.311335) (xy 105.135199 -250.260044) (xy 105.151246 -250.210655) (xy 105.174821 -250.164385)
			(xy 105.205345 -250.122372) (xy 105.242064 -250.085651) (xy 105.284076 -250.055126) (xy 105.330346 -250.03155)
			(xy 105.379734 -250.015501) (xy 105.431025 -250.007376) (xy 105.45699 -250.006866) (xy 105.482743 -250.007367)
			(xy 105.533628 -250.015345) (xy 105.582657 -250.031124) (xy 105.628643 -250.054321) (xy 105.670471 -250.084376)
			(xy 105.689146 -250.102116) (xy 105.698836 -250.111109) (xy 105.721768 -250.124241) (xy 105.747307 -250.131036)
			(xy 105.773733 -250.131036) (xy 105.799272 -250.124241) (xy 105.822204 -250.111109) (xy 105.831894 -250.102116)
			(xy 105.850579 -250.084388) (xy 105.89241 -250.05434) (xy 105.938394 -250.031143) (xy 105.987418 -250.015356)
			(xy 106.038298 -250.007362) (xy 106.06405 -250.006866) (xy 106.090023 -250.007305) (xy 106.141332 -250.015424)
			(xy 106.190738 -250.031471) (xy 106.237025 -250.055049) (xy 106.279054 -250.085579) (xy 106.315788 -250.122308)
			(xy 106.346325 -250.164332) (xy 106.36991 -250.210616) (xy 106.385964 -250.26002) (xy 106.394091 -250.311327)
			(xy 106.394091 -250.363265) (xy 117.494075 -250.363265) (xy 117.494075 -250.311335) (xy 117.502199 -250.260043)
			(xy 117.518246 -250.210654) (xy 117.541822 -250.164383) (xy 117.572346 -250.12237) (xy 117.609067 -250.085649)
			(xy 117.651079 -250.055124) (xy 117.69735 -250.031548) (xy 117.746739 -250.0155) (xy 117.798031 -250.007375)
			(xy 117.823996 -250.006866) (xy 117.849856 -250.007377) (xy 117.900948 -250.015422) (xy 117.95016 -250.031332)
			(xy 117.996292 -250.054717) (xy 118.038215 -250.085007) (xy 118.056914 -250.102878) (xy 118.066629 -250.111923)
			(xy 118.089638 -250.125135) (xy 118.115275 -250.131972) (xy 118.141809 -250.131972) (xy 118.167446 -250.125135)
			(xy 118.190455 -250.111923) (xy 118.20017 -250.102878) (xy 118.218859 -250.084997) (xy 118.26079 -250.054717)
			(xy 118.306925 -250.031335) (xy 118.356137 -250.015423) (xy 118.407227 -250.007367) (xy 118.433088 -250.006866)
			(xy 118.459059 -250.007308) (xy 118.510363 -250.015432) (xy 118.559764 -250.031482) (xy 118.606046 -250.055062)
			(xy 118.64807 -250.085593) (xy 118.6848 -250.122321) (xy 118.715332 -250.164343) (xy 118.738914 -250.210625)
			(xy 118.754965 -250.260025) (xy 118.763091 -250.311329) (xy 118.763091 -250.363271) (xy 118.754965 -250.414575)
			(xy 118.738914 -250.463975) (xy 118.715332 -250.510257) (xy 118.6848 -250.552279) (xy 118.64807 -250.589007)
			(xy 118.606046 -250.619538) (xy 118.559764 -250.643118) (xy 118.510363 -250.659168) (xy 118.459059 -250.667292)
			(xy 118.433088 -250.667774) (xy 118.407228 -250.667262) (xy 118.356137 -250.659216) (xy 118.306925 -250.643306)
			(xy 118.260793 -250.619921) (xy 118.218869 -250.589632) (xy 118.20017 -250.571762) (xy 118.190455 -250.562717)
			(xy 118.167446 -250.549505) (xy 118.141809 -250.542668) (xy 118.115275 -250.542668) (xy 118.089638 -250.549505)
			(xy 118.066629 -250.562717) (xy 118.056914 -250.571762) (xy 118.038222 -250.58964) (xy 117.996293 -250.619923)
			(xy 117.95016 -250.643306) (xy 117.900947 -250.659219) (xy 117.849857 -250.667274) (xy 117.823996 -250.667774)
			(xy 117.798031 -250.667225) (xy 117.746739 -250.6591) (xy 117.69735 -250.643052) (xy 117.651079 -250.619476)
			(xy 117.609067 -250.588951) (xy 117.572346 -250.55223) (xy 117.541822 -250.510217) (xy 117.518246 -250.463946)
			(xy 117.502199 -250.414557) (xy 117.494075 -250.363265) (xy 106.394091 -250.363265) (xy 106.394091 -250.363273)
			(xy 106.385964 -250.41458) (xy 106.36991 -250.463984) (xy 106.346325 -250.510268) (xy 106.315788 -250.552292)
			(xy 106.279054 -250.589021) (xy 106.237025 -250.619551) (xy 106.190738 -250.643129) (xy 106.141332 -250.659176)
			(xy 106.090023 -250.667295) (xy 106.06405 -250.667774) (xy 106.038295 -250.667328) (xy 105.987407 -250.659339)
			(xy 105.938376 -250.643548) (xy 105.892391 -250.620338) (xy 105.850566 -250.590271) (xy 105.831894 -250.572524)
			(xy 105.822204 -250.563531) (xy 105.799272 -250.550399) (xy 105.773733 -250.543604) (xy 105.747307 -250.543604)
			(xy 105.721768 -250.550399) (xy 105.698836 -250.563531) (xy 105.689146 -250.572524) (xy 105.670494 -250.590288)
			(xy 105.628654 -250.620329) (xy 105.582661 -250.64352) (xy 105.533629 -250.659298) (xy 105.482744 -250.667283)
			(xy 105.45699 -250.667774) (xy 105.431025 -250.667224) (xy 105.379734 -250.659099) (xy 105.330346 -250.64305)
			(xy 105.284076 -250.619474) (xy 105.242064 -250.588949) (xy 105.205345 -250.552228) (xy 105.174821 -250.510215)
			(xy 105.151246 -250.463945) (xy 105.135199 -250.414556) (xy 105.127075 -250.363265) (xy 103.106179 -250.363265)
			(xy 103.116888 -250.378005) (xy 103.140466 -250.424279) (xy 103.156514 -250.473672) (xy 103.164639 -250.524967)
			(xy 103.165148 -250.550934) (xy 103.165148 -250.551188) (xy 103.164677 -250.575714) (xy 103.157417 -250.624225)
			(xy 103.143069 -250.671132) (xy 103.121949 -250.715404) (xy 103.094519 -250.756069) (xy 103.07828 -250.774454)
			(xy 103.068447 -250.785919) (xy 103.055443 -250.813165) (xy 103.050983 -250.843025) (xy 103.055457 -250.872883)
			(xy 103.068475 -250.900123) (xy 103.07828 -250.911614) (xy 103.094548 -250.929977) (xy 103.121991 -250.970641)
			(xy 103.143117 -251.014917) (xy 103.157461 -251.061831) (xy 103.164706 -251.110351) (xy 103.165148 -251.13488)
			(xy 103.165148 -251.135134) (xy 103.164639 -251.161101) (xy 103.156514 -251.212396) (xy 103.140466 -251.261789)
			(xy 103.116888 -251.308063) (xy 103.086362 -251.350079) (xy 103.049639 -251.386802) (xy 103.007623 -251.417328)
			(xy 102.961349 -251.440906) (xy 102.911956 -251.456954) (xy 102.860661 -251.465079) (xy 102.808727 -251.465079)
			(xy 102.757432 -251.456954) (xy 102.708039 -251.440906) (xy 102.661765 -251.417328) (xy 102.619749 -251.386802)
			(xy 102.583026 -251.350079) (xy 102.5525 -251.308063) (xy 102.528922 -251.261789) (xy 102.512874 -251.212396)
			(xy 102.504749 -251.161101) (xy 102.50424 -251.135134) (xy 99.177856 -251.135134) (xy 99.177856 -252.798834)
			(xy 102.5652 -252.798834) (xy 102.5652 -252.79858) (xy 102.56564 -252.774053) (xy 102.572906 -252.72554)
			(xy 102.58726 -252.678632) (xy 102.608388 -252.634361) (xy 102.635825 -252.593697) (xy 102.652068 -252.575314)
			(xy 102.661839 -252.563799) (xy 102.674857 -252.536571) (xy 102.679333 -252.506725) (xy 102.674872 -252.476877)
			(xy 102.661867 -252.449643) (xy 102.652068 -252.438154) (xy 102.63584 -252.419757) (xy 102.608389 -252.379104)
			(xy 102.587255 -252.334836) (xy 102.572902 -252.287929) (xy 102.565647 -252.239415) (xy 102.5652 -252.214888)
			(xy 102.5652 -252.214634) (xy 102.565709 -252.188667) (xy 102.573834 -252.137372) (xy 102.589882 -252.087979)
			(xy 102.61346 -252.041705) (xy 102.643986 -251.999689) (xy 102.680709 -251.962966) (xy 102.722725 -251.93244)
			(xy 102.768999 -251.908862) (xy 102.818392 -251.892814) (xy 102.869687 -251.884689) (xy 102.921621 -251.884689)
			(xy 102.972916 -251.892814) (xy 103.022309 -251.908862) (xy 103.068583 -251.93244) (xy 103.110599 -251.962966)
			(xy 103.147322 -251.999689) (xy 103.177848 -252.041705) (xy 103.201426 -252.087979) (xy 103.217474 -252.137372)
			(xy 103.225599 -252.188667) (xy 103.226108 -252.214634) (xy 103.226108 -252.214888) (xy 103.225647 -252.239414)
			(xy 103.218386 -252.287927) (xy 103.204037 -252.334834) (xy 103.182914 -252.379105) (xy 103.155481 -252.41977)
			(xy 103.13924 -252.438154) (xy 103.129402 -252.449617) (xy 103.11639 -252.476863) (xy 103.111927 -252.506725)
			(xy 103.116405 -252.536585) (xy 103.12943 -252.563825) (xy 103.13924 -252.575314) (xy 103.155502 -252.593682)
			(xy 103.182947 -252.634344) (xy 103.194898 -252.659388) (xy 108.103416 -252.659388) (xy 108.103416 -252.659134)
			(xy 108.103884 -252.634608) (xy 108.111142 -252.586096) (xy 108.12549 -252.539189) (xy 108.146611 -252.494917)
			(xy 108.174043 -252.454252) (xy 108.190284 -252.435868) (xy 108.200098 -252.424388) (xy 108.21311 -252.397147)
			(xy 108.217575 -252.367291) (xy 108.213104 -252.337436) (xy 108.200088 -252.310198) (xy 108.190284 -252.298708)
			(xy 108.17402 -252.280342) (xy 108.146578 -252.239678) (xy 108.125452 -252.195403) (xy 108.111107 -252.14849)
			(xy 108.103859 -252.099971) (xy 108.103416 -252.075442) (xy 108.103416 -252.075188) (xy 108.103925 -252.049221)
			(xy 108.11205 -251.997926) (xy 108.128098 -251.948533) (xy 108.151676 -251.902259) (xy 108.182202 -251.860243)
			(xy 108.218925 -251.82352) (xy 108.260941 -251.792994) (xy 108.307215 -251.769416) (xy 108.356608 -251.753368)
			(xy 108.407903 -251.745243) (xy 108.459837 -251.745243) (xy 108.511132 -251.753368) (xy 108.560525 -251.769416)
			(xy 108.606799 -251.792994) (xy 108.648815 -251.82352) (xy 108.685538 -251.860243) (xy 108.716064 -251.902259)
			(xy 108.739642 -251.948533) (xy 108.75569 -251.997926) (xy 108.763815 -252.049221) (xy 108.764324 -252.075188)
			(xy 108.764324 -252.075442) (xy 108.763891 -252.099969) (xy 108.756623 -252.148483) (xy 108.742267 -252.19539)
			(xy 108.721137 -252.239661) (xy 108.693699 -252.280325) (xy 108.677456 -252.298708) (xy 108.667662 -252.310205)
			(xy 108.654642 -252.337439) (xy 108.65017 -252.367291) (xy 108.654637 -252.397144) (xy 108.667652 -252.42438)
			(xy 108.677456 -252.435868) (xy 108.693699 -252.454253) (xy 108.721146 -252.49491) (xy 108.742277 -252.539181)
			(xy 108.756627 -252.58609) (xy 108.763879 -252.634606) (xy 108.764324 -252.659134) (xy 108.764324 -252.659388)
			(xy 108.763815 -252.685355) (xy 108.75569 -252.73665) (xy 108.739642 -252.786043) (xy 108.729501 -252.805946)
			(xy 115.103148 -252.805946) (xy 115.103148 -252.805692) (xy 115.103608 -252.781166) (xy 115.110871 -252.732654)
			(xy 115.125221 -252.685747) (xy 115.146344 -252.641476) (xy 115.173776 -252.600811) (xy 115.190016 -252.582426)
			(xy 115.199771 -252.5709) (xy 115.212785 -252.543675) (xy 115.21726 -252.513834) (xy 115.212805 -252.48399)
			(xy 115.199809 -252.456756) (xy 115.190016 -252.445266) (xy 115.173785 -252.426872) (xy 115.146337 -252.386216)
			(xy 115.125204 -252.341948) (xy 115.110852 -252.295041) (xy 115.103596 -252.246527) (xy 115.103148 -252.222)
			(xy 115.103148 -252.221746) (xy 115.103657 -252.195779) (xy 115.111782 -252.144484) (xy 115.12783 -252.095091)
			(xy 115.151408 -252.048817) (xy 115.181934 -252.006801) (xy 115.218657 -251.970078) (xy 115.260673 -251.939552)
			(xy 115.306947 -251.915974) (xy 115.35634 -251.899926) (xy 115.407635 -251.891801) (xy 115.459569 -251.891801)
			(xy 115.510864 -251.899926) (xy 115.560257 -251.915974) (xy 115.606531 -251.939552) (xy 115.648547 -251.970078)
			(xy 115.68527 -252.006801) (xy 115.715796 -252.048817) (xy 115.739374 -252.095091) (xy 115.755422 -252.144484)
			(xy 115.763547 -252.195779) (xy 115.764056 -252.221746) (xy 115.764056 -252.222) (xy 115.76359 -252.246526)
			(xy 115.756328 -252.295037) (xy 115.741979 -252.341944) (xy 115.720858 -252.386216) (xy 115.693428 -252.426881)
			(xy 115.677188 -252.445266) (xy 115.667342 -252.456721) (xy 115.654339 -252.483971) (xy 115.64988 -252.513834)
			(xy 115.654358 -252.543694) (xy 115.667381 -252.570935) (xy 115.677188 -252.582426) (xy 115.693416 -252.600823)
			(xy 115.720865 -252.641478) (xy 115.741998 -252.685745) (xy 115.756351 -252.732652) (xy 115.763608 -252.781165)
			(xy 115.764056 -252.805692) (xy 115.764056 -252.805946) (xy 115.763547 -252.831913) (xy 115.755422 -252.883208)
			(xy 115.739374 -252.932601) (xy 115.715796 -252.978875) (xy 115.68527 -253.020891) (xy 115.648547 -253.057614)
			(xy 115.606531 -253.08814) (xy 115.560257 -253.111718) (xy 115.510864 -253.127766) (xy 115.459569 -253.135891)
			(xy 115.407635 -253.135891) (xy 115.35634 -253.127766) (xy 115.306947 -253.111718) (xy 115.260673 -253.08814)
			(xy 115.218657 -253.057614) (xy 115.181934 -253.020891) (xy 115.151408 -252.978875) (xy 115.12783 -252.932601)
			(xy 115.111782 -252.883208) (xy 115.103657 -252.831913) (xy 115.103148 -252.805946) (xy 108.729501 -252.805946)
			(xy 108.716064 -252.832317) (xy 108.685538 -252.874333) (xy 108.648815 -252.911056) (xy 108.606799 -252.941582)
			(xy 108.560525 -252.96516) (xy 108.511132 -252.981208) (xy 108.459837 -252.989333) (xy 108.407903 -252.989333)
			(xy 108.356608 -252.981208) (xy 108.307215 -252.96516) (xy 108.260941 -252.941582) (xy 108.218925 -252.911056)
			(xy 108.182202 -252.874333) (xy 108.151676 -252.832317) (xy 108.128098 -252.786043) (xy 108.11205 -252.73665)
			(xy 108.103925 -252.685355) (xy 108.103416 -252.659388) (xy 103.194898 -252.659388) (xy 103.204075 -252.678619)
			(xy 103.21842 -252.725532) (xy 103.225666 -252.774051) (xy 103.226108 -252.79858) (xy 103.226108 -252.798834)
			(xy 103.225599 -252.824801) (xy 103.217474 -252.876096) (xy 103.201426 -252.925489) (xy 103.177848 -252.971763)
			(xy 103.147322 -253.013779) (xy 103.110599 -253.050502) (xy 103.068583 -253.081028) (xy 103.022309 -253.104606)
			(xy 102.972916 -253.120654) (xy 102.921621 -253.128779) (xy 102.869687 -253.128779) (xy 102.818392 -253.120654)
			(xy 102.768999 -253.104606) (xy 102.722725 -253.081028) (xy 102.680709 -253.050502) (xy 102.643986 -253.013779)
			(xy 102.61346 -252.971763) (xy 102.589882 -252.925489) (xy 102.573834 -252.876096) (xy 102.565709 -252.824801)
			(xy 102.5652 -252.798834) (xy 99.177856 -252.798834) (xy 99.177856 -253.571502) (xy 99.178508 -253.580166)
			(xy 99.184909 -253.596306) (xy 99.196374 -253.609345) (xy 99.203764 -253.61392) (xy 99.229418 -253.627128)
			(xy 99.28606 -253.656084) (xy 99.287838 -253.656846) (xy 99.291236 -253.658392) (xy 99.298379 -253.660556)
			(xy 99.302062 -253.661164) (xy 99.321217 -253.644658) (xy 99.363413 -253.616799) (xy 99.409212 -253.595372)
			(xy 99.457639 -253.580831) (xy 99.507666 -253.573486) (xy 99.532948 -253.573026) (xy 99.558889 -253.573514)
			(xy 99.610191 -253.581253) (xy 99.659766 -253.596551) (xy 99.706508 -253.619067) (xy 99.749372 -253.648297)
			(xy 99.787402 -253.683588) (xy 99.819747 -253.724153) (xy 99.845686 -253.769085) (xy 99.864639 -253.817382)
			(xy 99.876183 -253.867963) (xy 99.88006 -253.9197) (xy 99.878111 -253.945703) (xy 100.142803 -253.945703)
			(xy 100.142803 -253.893769) (xy 100.150928 -253.842474) (xy 100.166976 -253.793081) (xy 100.190554 -253.746807)
			(xy 100.22108 -253.704791) (xy 100.257803 -253.668068) (xy 100.299819 -253.637542) (xy 100.346093 -253.613964)
			(xy 100.395486 -253.597916) (xy 100.446781 -253.589791) (xy 100.498715 -253.589791) (xy 100.55001 -253.597916)
			(xy 100.599403 -253.613964) (xy 100.645677 -253.637542) (xy 100.687693 -253.668068) (xy 100.724416 -253.704791)
			(xy 100.754942 -253.746807) (xy 100.77852 -253.793081) (xy 100.794568 -253.842474) (xy 100.802693 -253.893769)
			(xy 100.803202 -253.919736) (xy 100.802693 -253.945703) (xy 101.082603 -253.945703) (xy 101.082603 -253.893769)
			(xy 101.090728 -253.842474) (xy 101.106776 -253.793081) (xy 101.130354 -253.746807) (xy 101.16088 -253.704791)
			(xy 101.197603 -253.668068) (xy 101.239619 -253.637542) (xy 101.285893 -253.613964) (xy 101.335286 -253.597916)
			(xy 101.386581 -253.589791) (xy 101.438515 -253.589791) (xy 101.48981 -253.597916) (xy 101.539203 -253.613964)
			(xy 101.585477 -253.637542) (xy 101.627493 -253.668068) (xy 101.664216 -253.704791) (xy 101.694742 -253.746807)
			(xy 101.71832 -253.793081) (xy 101.734368 -253.842474) (xy 101.742493 -253.893769) (xy 101.743002 -253.919736)
			(xy 101.742493 -253.945703) (xy 102.022403 -253.945703) (xy 102.022403 -253.893769) (xy 102.030528 -253.842474)
			(xy 102.046576 -253.793081) (xy 102.070154 -253.746807) (xy 102.10068 -253.704791) (xy 102.137403 -253.668068)
			(xy 102.179419 -253.637542) (xy 102.225693 -253.613964) (xy 102.275086 -253.597916) (xy 102.326381 -253.589791)
			(xy 102.378315 -253.589791) (xy 102.42961 -253.597916) (xy 102.479003 -253.613964) (xy 102.525277 -253.637542)
			(xy 102.567293 -253.668068) (xy 102.604016 -253.704791) (xy 102.634542 -253.746807) (xy 102.65812 -253.793081)
			(xy 102.674168 -253.842474) (xy 102.682293 -253.893769) (xy 102.682802 -253.919736) (xy 102.682293 -253.945703)
			(xy 102.674168 -253.996998) (xy 102.659818 -254.041164) (xy 105.127095 -254.041164) (xy 105.127095 -253.989236)
			(xy 105.135218 -253.937949) (xy 105.151264 -253.888563) (xy 105.174838 -253.842295) (xy 105.20536 -253.800285)
			(xy 105.242077 -253.763566) (xy 105.284087 -253.733043) (xy 105.330354 -253.709468) (xy 105.379739 -253.69342)
			(xy 105.431026 -253.685296) (xy 105.45699 -253.684786) (xy 105.482743 -253.685281) (xy 105.533628 -253.693259)
			(xy 105.582658 -253.709039) (xy 105.628644 -253.732239) (xy 105.670472 -253.762295) (xy 105.689146 -253.780036)
			(xy 105.698836 -253.789029) (xy 105.721768 -253.802161) (xy 105.747307 -253.808956) (xy 105.773733 -253.808956)
			(xy 105.799272 -253.802161) (xy 105.822204 -253.789029) (xy 105.831894 -253.780036) (xy 105.850582 -253.762311)
			(xy 105.892412 -253.732263) (xy 105.938395 -253.709064) (xy 105.987419 -253.693276) (xy 106.038298 -253.685282)
			(xy 106.06405 -253.684786) (xy 106.090025 -253.685185) (xy 106.141336 -253.693305) (xy 106.190746 -253.709352)
			(xy 106.237036 -253.732932) (xy 106.279067 -253.763464) (xy 106.315804 -253.800195) (xy 106.346342 -253.842222)
			(xy 106.369928 -253.888508) (xy 106.385983 -253.937915) (xy 106.387257 -253.945957) (xy 113.300003 -253.945957)
			(xy 113.300003 -253.894023) (xy 113.308128 -253.842728) (xy 113.324176 -253.793335) (xy 113.347754 -253.747061)
			(xy 113.37828 -253.705045) (xy 113.415003 -253.668322) (xy 113.457019 -253.637796) (xy 113.503293 -253.614218)
			(xy 113.552686 -253.59817) (xy 113.603981 -253.590045) (xy 113.655915 -253.590045) (xy 113.70721 -253.59817)
			(xy 113.756603 -253.614218) (xy 113.802877 -253.637796) (xy 113.844893 -253.668322) (xy 113.881616 -253.705045)
			(xy 113.912142 -253.747061) (xy 113.93572 -253.793335) (xy 113.951768 -253.842728) (xy 113.959893 -253.894023)
			(xy 113.960402 -253.91999) (xy 113.959893 -253.945957) (xy 113.951768 -253.997252) (xy 113.937501 -254.041164)
			(xy 117.494095 -254.041164) (xy 117.494095 -253.989236) (xy 117.502218 -253.937948) (xy 117.518265 -253.888561)
			(xy 117.541839 -253.842293) (xy 117.572361 -253.800283) (xy 117.60908 -253.763564) (xy 117.65109 -253.733041)
			(xy 117.697358 -253.709466) (xy 117.746744 -253.693419) (xy 117.798032 -253.685295) (xy 117.823996 -253.684786)
			(xy 117.849857 -253.685291) (xy 117.900948 -253.693337) (xy 117.950162 -253.709247) (xy 117.996293 -253.732635)
			(xy 118.038216 -253.762926) (xy 118.056914 -253.780798) (xy 118.066629 -253.789843) (xy 118.089638 -253.803055)
			(xy 118.115275 -253.809892) (xy 118.141809 -253.809892) (xy 118.167446 -253.803055) (xy 118.190455 -253.789843)
			(xy 118.20017 -253.780798) (xy 118.218862 -253.762921) (xy 118.260792 -253.732639) (xy 118.306926 -253.709257)
			(xy 118.356138 -253.693343) (xy 118.407228 -253.685287) (xy 118.433088 -253.684786) (xy 118.459061 -253.685188)
			(xy 118.510368 -253.693313) (xy 118.559772 -253.709363) (xy 118.606057 -253.732945) (xy 118.648083 -253.763477)
			(xy 118.684815 -253.800208) (xy 118.715349 -253.842233) (xy 118.738932 -253.888517) (xy 118.754985 -253.93792)
			(xy 118.763111 -253.989227) (xy 118.763111 -254.041173) (xy 118.754985 -254.09248) (xy 118.738932 -254.141883)
			(xy 118.715349 -254.188167) (xy 118.684815 -254.230192) (xy 118.648083 -254.266923) (xy 118.606057 -254.297455)
			(xy 118.559772 -254.321037) (xy 118.510368 -254.337087) (xy 118.459061 -254.345212) (xy 118.433088 -254.345694)
			(xy 118.407227 -254.345205) (xy 118.356134 -254.337156) (xy 118.30692 -254.321242) (xy 118.260789 -254.297851)
			(xy 118.218867 -254.267556) (xy 118.20017 -254.249682) (xy 118.190455 -254.240637) (xy 118.167446 -254.227425)
			(xy 118.141809 -254.220588) (xy 118.115275 -254.220588) (xy 118.089638 -254.227425) (xy 118.066629 -254.240637)
			(xy 118.056914 -254.249682) (xy 118.038226 -254.267564) (xy 117.996295 -254.297845) (xy 117.950161 -254.321227)
			(xy 117.900948 -254.33714) (xy 117.849857 -254.345194) (xy 117.823996 -254.345694) (xy 117.798032 -254.345105)
			(xy 117.746744 -254.336981) (xy 117.697358 -254.320934) (xy 117.65109 -254.297359) (xy 117.60908 -254.266836)
			(xy 117.572361 -254.230117) (xy 117.541839 -254.188107) (xy 117.518265 -254.141839) (xy 117.502218 -254.092452)
			(xy 117.494095 -254.041164) (xy 113.937501 -254.041164) (xy 113.93572 -254.046645) (xy 113.912142 -254.092919)
			(xy 113.881616 -254.134935) (xy 113.844893 -254.171658) (xy 113.802877 -254.202184) (xy 113.756603 -254.225762)
			(xy 113.70721 -254.24181) (xy 113.655915 -254.249935) (xy 113.603981 -254.249935) (xy 113.552686 -254.24181)
			(xy 113.503293 -254.225762) (xy 113.457019 -254.202184) (xy 113.415003 -254.171658) (xy 113.37828 -254.134935)
			(xy 113.347754 -254.092919) (xy 113.324176 -254.046645) (xy 113.308128 -253.997252) (xy 113.300003 -253.945957)
			(xy 106.387257 -253.945957) (xy 106.394111 -253.989225) (xy 106.394111 -254.041175) (xy 106.385983 -254.092485)
			(xy 106.369928 -254.141892) (xy 106.346342 -254.188178) (xy 106.315804 -254.230205) (xy 106.279067 -254.266936)
			(xy 106.237036 -254.297468) (xy 106.190746 -254.321048) (xy 106.141336 -254.337095) (xy 106.090025 -254.345215)
			(xy 106.06405 -254.345694) (xy 106.038295 -254.345242) (xy 105.987408 -254.337254) (xy 105.938377 -254.321464)
			(xy 105.892392 -254.298255) (xy 105.850567 -254.26819) (xy 105.831894 -254.250444) (xy 105.822204 -254.241451)
			(xy 105.799272 -254.228319) (xy 105.773733 -254.221524) (xy 105.747307 -254.221524) (xy 105.721768 -254.228319)
			(xy 105.698836 -254.241451) (xy 105.689146 -254.250444) (xy 105.670481 -254.268194) (xy 105.628645 -254.29824)
			(xy 105.582657 -254.321435) (xy 105.533627 -254.337216) (xy 105.482743 -254.345203) (xy 105.45699 -254.345694)
			(xy 105.431026 -254.345104) (xy 105.379739 -254.33698) (xy 105.330354 -254.320932) (xy 105.284087 -254.297357)
			(xy 105.242077 -254.266834) (xy 105.20536 -254.230115) (xy 105.174838 -254.188105) (xy 105.151264 -254.141837)
			(xy 105.135218 -254.092451) (xy 105.127095 -254.041164) (xy 102.659818 -254.041164) (xy 102.65812 -254.046391)
			(xy 102.634542 -254.092665) (xy 102.604016 -254.134681) (xy 102.567293 -254.171404) (xy 102.525277 -254.20193)
			(xy 102.479003 -254.225508) (xy 102.42961 -254.241556) (xy 102.378315 -254.249681) (xy 102.326381 -254.249681)
			(xy 102.275086 -254.241556) (xy 102.225693 -254.225508) (xy 102.179419 -254.20193) (xy 102.137403 -254.171404)
			(xy 102.10068 -254.134681) (xy 102.070154 -254.092665) (xy 102.046576 -254.046391) (xy 102.030528 -253.996998)
			(xy 102.022403 -253.945703) (xy 101.742493 -253.945703) (xy 101.734368 -253.996998) (xy 101.71832 -254.046391)
			(xy 101.694742 -254.092665) (xy 101.664216 -254.134681) (xy 101.627493 -254.171404) (xy 101.585477 -254.20193)
			(xy 101.539203 -254.225508) (xy 101.48981 -254.241556) (xy 101.438515 -254.249681) (xy 101.386581 -254.249681)
			(xy 101.335286 -254.241556) (xy 101.285893 -254.225508) (xy 101.239619 -254.20193) (xy 101.197603 -254.171404)
			(xy 101.16088 -254.134681) (xy 101.130354 -254.092665) (xy 101.106776 -254.046391) (xy 101.090728 -253.996998)
			(xy 101.082603 -253.945703) (xy 100.802693 -253.945703) (xy 100.794568 -253.996998) (xy 100.77852 -254.046391)
			(xy 100.754942 -254.092665) (xy 100.724416 -254.134681) (xy 100.687693 -254.171404) (xy 100.645677 -254.20193)
			(xy 100.599403 -254.225508) (xy 100.55001 -254.241556) (xy 100.498715 -254.249681) (xy 100.446781 -254.249681)
			(xy 100.395486 -254.241556) (xy 100.346093 -254.225508) (xy 100.299819 -254.20193) (xy 100.257803 -254.171404)
			(xy 100.22108 -254.134681) (xy 100.190554 -254.092665) (xy 100.166976 -254.046391) (xy 100.150928 -253.996998)
			(xy 100.142803 -253.945703) (xy 99.878111 -253.945703) (xy 99.876183 -253.971437) (xy 99.864639 -254.022018)
			(xy 99.845686 -254.070315) (xy 99.819747 -254.115247) (xy 99.787402 -254.155812) (xy 99.749372 -254.191103)
			(xy 99.706508 -254.220333) (xy 99.659766 -254.242849) (xy 99.610191 -254.258147) (xy 99.558889 -254.265886)
			(xy 99.532948 -254.266446) (xy 99.507668 -254.265984) (xy 99.457644 -254.258629) (xy 99.409221 -254.244083)
			(xy 99.363425 -254.222654) (xy 99.32123 -254.194798) (xy 99.302062 -254.178308) (xy 99.298384 -254.178938)
			(xy 99.291244 -254.181103) (xy 99.287838 -254.182626) (xy 99.28606 -254.183388) (xy 99.229418 -254.212344)
			(xy 99.203764 -254.225552) (xy 99.196383 -254.230124) (xy 99.184974 -254.243198) (xy 99.178545 -254.259315)
			(xy 99.177856 -254.26797) (xy 99.177856 -254.38989) (xy 99.1781 -254.397072) (xy 99.182095 -254.410869)
			(xy 99.18573 -254.417068) (xy 99.18954 -254.42291) (xy 99.1997 -254.432308) (xy 99.206558 -254.43561)
			(xy 99.230192 -254.447616) (xy 99.273628 -254.477998) (xy 99.311667 -254.514915) (xy 99.343336 -254.557422)
			(xy 99.367825 -254.604433) (xy 99.384509 -254.654746) (xy 99.39296 -254.707075) (xy 99.392964 -254.759519)
			(xy 99.672649 -254.759519) (xy 99.672649 -254.707585) (xy 99.680774 -254.65629) (xy 99.696822 -254.606897)
			(xy 99.7204 -254.560623) (xy 99.750926 -254.518607) (xy 99.787649 -254.481884) (xy 99.829665 -254.451358)
			(xy 99.875939 -254.42778) (xy 99.925332 -254.411732) (xy 99.976627 -254.403607) (xy 100.028561 -254.403607)
			(xy 100.079856 -254.411732) (xy 100.129249 -254.42778) (xy 100.175523 -254.451358) (xy 100.217539 -254.481884)
			(xy 100.254262 -254.518607) (xy 100.284788 -254.560623) (xy 100.308366 -254.606897) (xy 100.324414 -254.65629)
			(xy 100.332539 -254.707585) (xy 100.333048 -254.733552) (xy 100.332539 -254.759519) (xy 100.324414 -254.810814)
			(xy 100.308366 -254.860207) (xy 100.284788 -254.906481) (xy 100.254262 -254.948497) (xy 100.217539 -254.98522)
			(xy 100.175523 -255.015746) (xy 100.129249 -255.039324) (xy 100.079856 -255.055372) (xy 100.028561 -255.063497)
			(xy 99.976627 -255.063497) (xy 99.925332 -255.055372) (xy 99.875939 -255.039324) (xy 99.829665 -255.015746)
			(xy 99.787649 -254.98522) (xy 99.750926 -254.948497) (xy 99.7204 -254.906481) (xy 99.696822 -254.860207)
			(xy 99.680774 -254.810814) (xy 99.672649 -254.759519) (xy 99.392964 -254.759519) (xy 99.392964 -254.760083)
			(xy 99.384519 -254.812413) (xy 99.367841 -254.862728) (xy 99.343358 -254.909743) (xy 99.311695 -254.952254)
			(xy 99.273661 -254.989175) (xy 99.230228 -255.019563) (xy 99.206558 -255.031494) (xy 99.20605 -255.031748)
			(xy 99.199839 -255.035046) (xy 99.189389 -255.044448) (xy 99.185476 -255.05029) (xy 99.181666 -255.056132)
			(xy 99.177856 -255.069848) (xy 99.177856 -255.199388) (xy 99.178506 -255.208054) (xy 99.184904 -255.224197)
			(xy 99.196368 -255.23724) (xy 99.203764 -255.241806) (xy 99.229418 -255.255014) (xy 99.28606 -255.28397)
			(xy 99.287838 -255.284732) (xy 99.291235 -255.286278) (xy 99.298379 -255.288443) (xy 99.302062 -255.28905)
			(xy 99.321217 -255.272544) (xy 99.363414 -255.244686) (xy 99.409212 -255.22326) (xy 99.45764 -255.20872)
			(xy 99.507666 -255.201375) (xy 99.532948 -255.200912) (xy 99.55889 -255.2014) (xy 99.610194 -255.20914)
			(xy 99.659771 -255.224438) (xy 99.706515 -255.246955) (xy 99.749381 -255.276186) (xy 99.787412 -255.311478)
			(xy 99.819759 -255.352045) (xy 99.845699 -255.396979) (xy 99.864653 -255.445277) (xy 99.876197 -255.495861)
			(xy 99.880074 -255.5476) (xy 99.876197 -255.599339) (xy 99.864653 -255.649923) (xy 99.845699 -255.698221)
			(xy 99.819759 -255.743155) (xy 99.787412 -255.783722) (xy 99.749381 -255.819014) (xy 99.706515 -255.848245)
			(xy 99.659771 -255.870762) (xy 99.610194 -255.88606) (xy 99.55889 -255.8938) (xy 99.532948 -255.894332)
			(xy 99.507668 -255.89387) (xy 99.457645 -255.886514) (xy 99.409222 -255.871968) (xy 99.363427 -255.850539)
			(xy 99.321232 -255.822682) (xy 99.302062 -255.806194) (xy 99.298384 -255.806824) (xy 99.291244 -255.808989)
			(xy 99.287838 -255.810512) (xy 99.28606 -255.811274) (xy 99.229418 -255.84023) (xy 99.203764 -255.853438)
			(xy 99.196391 -255.858014) (xy 99.185005 -255.871093) (xy 99.178602 -255.887208) (xy 99.177856 -255.895856)
			(xy 99.177856 -256.017776) (xy 99.178098 -256.024959) (xy 99.18209 -256.038758) (xy 99.18573 -256.044954)
			(xy 99.18954 -256.050796) (xy 99.1997 -256.060194) (xy 99.206558 -256.063496) (xy 99.230185 -256.075502)
			(xy 99.273608 -256.105882) (xy 99.311634 -256.142794) (xy 99.34329 -256.185295) (xy 99.367768 -256.232298)
			(xy 99.384442 -256.282601) (xy 99.392886 -256.334919) (xy 99.392883 -256.387914) (xy 99.384435 -256.440231)
			(xy 99.367755 -256.490533) (xy 99.343273 -256.537533) (xy 99.311612 -256.580031) (xy 99.273582 -256.616939)
			(xy 99.230157 -256.647315) (xy 99.206558 -256.65938) (xy 99.20605 -256.659634) (xy 99.199839 -256.662932)
			(xy 99.189387 -256.672332) (xy 99.185476 -256.678176) (xy 99.181666 -256.684018) (xy 99.177856 -256.697734)
			(xy 99.177856 -256.826766) (xy 99.179005 -256.83949) (xy 99.191934 -256.861486) (xy 99.202494 -256.868676)
			(xy 99.289362 -256.912872) (xy 99.295966 -256.915158) (xy 99.304998 -256.917134) (xy 99.323366 -256.91518)
			(xy 99.33178 -256.911348) (xy 99.338892 -256.907284) (xy 99.35816 -256.893885) (xy 99.39972 -256.872086)
			(xy 99.421696 -256.86385) (xy 99.432441 -256.85945) (xy 99.448705 -256.842912) (xy 99.452938 -256.8321)
			(xy 99.467035 -256.791583) (xy 99.500825 -256.712721) (xy 99.54079 -256.636803) (xy 99.586677 -256.56431)
			(xy 99.638193 -256.495703) (xy 99.666298 -256.463292) (xy 99.671759 -256.456298) (xy 99.677864 -256.439647)
			(xy 99.678236 -256.43078) (xy 99.67722 -256.421128) (xy 99.676458 -256.41681) (xy 99.674298 -256.403133)
			(xy 99.672007 -256.375538) (xy 99.671886 -256.361692) (xy 99.671886 -256.361438) (xy 99.672353 -256.336671)
			(xy 99.679744 -256.287692) (xy 99.69435 -256.240361) (xy 99.715847 -256.195734) (xy 99.743754 -256.15481)
			(xy 99.777447 -256.118501) (xy 99.816175 -256.087618) (xy 99.859072 -256.062851) (xy 99.881944 -256.053336)
			(xy 99.892104 -256.049526) (xy 99.923092 -256.01803) (xy 99.926648 -256.007362) (xy 99.944276 -255.958703)
			(xy 99.987599 -255.864705) (xy 100.03975 -255.775303) (xy 100.100246 -255.691324) (xy 100.133912 -255.652016)
			(xy 100.148136 -255.61671) (xy 100.147374 -255.607312) (xy 100.146612 -255.602994) (xy 100.144464 -255.58938)
			(xy 100.142173 -255.561912) (xy 100.14204 -255.54813) (xy 100.14204 -255.547622) (xy 100.142522 -255.521633)
			(xy 100.15065 -255.470295) (xy 100.166711 -255.42086) (xy 100.190309 -255.374547) (xy 100.220861 -255.332497)
			(xy 100.257617 -255.295744) (xy 100.29967 -255.265195) (xy 100.345984 -255.241601) (xy 100.39542 -255.225544)
			(xy 100.446759 -255.217419) (xy 100.472748 -255.216914) (xy 100.501576 -255.217564) (xy 100.558355 -255.227589)
			(xy 100.612547 -255.247277) (xy 100.637848 -255.26111) (xy 100.641658 -255.263142) (xy 100.66782 -255.270254)
			(xy 100.673689 -255.270106) (xy 100.685113 -255.267417) (xy 100.690426 -255.26492) (xy 100.795836 -255.20396)
			(xy 100.807133 -255.196626) (xy 100.82571 -255.177135) (xy 100.83855 -255.153468) (xy 100.844762 -255.127269)
			(xy 100.843915 -255.100357) (xy 100.836067 -255.0746) (xy 100.821764 -255.051788) (xy 100.801998 -255.033504)
			(xy 100.790248 -255.026922) (xy 100.767571 -255.014607) (xy 100.726008 -254.984026) (xy 100.689705 -254.947355)
			(xy 100.659544 -254.905486) (xy 100.63626 -254.859437) (xy 100.620417 -254.810328) (xy 100.612403 -254.759353)
			(xy 100.61194 -254.733552) (xy 100.612449 -254.707585) (xy 100.620574 -254.65629) (xy 100.636622 -254.606897)
			(xy 100.6602 -254.560623) (xy 100.690726 -254.518607) (xy 100.727449 -254.481884) (xy 100.769465 -254.451358)
			(xy 100.815739 -254.42778) (xy 100.865132 -254.411732) (xy 100.916427 -254.403607) (xy 100.968361 -254.403607)
			(xy 101.019656 -254.411732) (xy 101.069049 -254.42778) (xy 101.115323 -254.451358) (xy 101.157339 -254.481884)
			(xy 101.194062 -254.518607) (xy 101.224588 -254.560623) (xy 101.248166 -254.606897) (xy 101.264214 -254.65629)
			(xy 101.272339 -254.707585) (xy 101.272848 -254.733552) (xy 101.272506 -254.754551) (xy 101.267158 -254.796207)
			(xy 101.26218 -254.81661) (xy 101.259177 -254.830083) (xy 101.259689 -254.85767) (xy 101.267567 -254.884113)
			(xy 101.282237 -254.907481) (xy 101.302627 -254.92607) (xy 101.32725 -254.938521) (xy 101.354307 -254.943926)
			(xy 101.368098 -254.943356) (xy 101.411786 -254.941832) (xy 101.412548 -254.941832) (xy 101.456744 -254.943356)
			(xy 101.470529 -254.943911) (xy 101.49757 -254.938495) (xy 101.522171 -254.926034) (xy 101.542536 -254.907438)
			(xy 101.557175 -254.884067) (xy 101.565019 -254.857628) (xy 101.565494 -254.830055) (xy 101.562408 -254.81661)
			(xy 101.557431 -254.796207) (xy 101.552084 -254.754551) (xy 101.55174 -254.733552) (xy 101.552249 -254.707585)
			(xy 101.560374 -254.65629) (xy 101.576422 -254.606897) (xy 101.6 -254.560623) (xy 101.630526 -254.518607)
			(xy 101.667249 -254.481884) (xy 101.709265 -254.451358) (xy 101.755539 -254.42778) (xy 101.804932 -254.411732)
			(xy 101.856227 -254.403607) (xy 101.908161 -254.403607) (xy 101.959456 -254.411732) (xy 102.008849 -254.42778)
			(xy 102.055123 -254.451358) (xy 102.097139 -254.481884) (xy 102.133862 -254.518607) (xy 102.164388 -254.560623)
			(xy 102.187966 -254.606897) (xy 102.204014 -254.65629) (xy 102.212139 -254.707585) (xy 102.212648 -254.733552)
			(xy 102.212139 -254.759773) (xy 110.010703 -254.759773) (xy 110.010703 -254.707839) (xy 110.018828 -254.656544)
			(xy 110.034876 -254.607151) (xy 110.058454 -254.560877) (xy 110.08898 -254.518861) (xy 110.125703 -254.482138)
			(xy 110.167719 -254.451612) (xy 110.213993 -254.428034) (xy 110.263386 -254.411986) (xy 110.314681 -254.403861)
			(xy 110.366615 -254.403861) (xy 110.41791 -254.411986) (xy 110.467303 -254.428034) (xy 110.513577 -254.451612)
			(xy 110.555593 -254.482138) (xy 110.592316 -254.518861) (xy 110.622842 -254.560877) (xy 110.64642 -254.607151)
			(xy 110.662468 -254.656544) (xy 110.670593 -254.707839) (xy 110.671102 -254.733806) (xy 110.670593 -254.759773)
			(xy 110.662468 -254.811068) (xy 110.64642 -254.860461) (xy 110.622842 -254.906735) (xy 110.592316 -254.948751)
			(xy 110.555593 -254.985474) (xy 110.513577 -255.016) (xy 110.467303 -255.039578) (xy 110.41791 -255.055626)
			(xy 110.366615 -255.063751) (xy 110.314681 -255.063751) (xy 110.263386 -255.055626) (xy 110.213993 -255.039578)
			(xy 110.167719 -255.016) (xy 110.125703 -254.985474) (xy 110.08898 -254.948751) (xy 110.058454 -254.906735)
			(xy 110.034876 -254.860461) (xy 110.018828 -254.811068) (xy 110.010703 -254.759773) (xy 102.212139 -254.759773)
			(xy 102.212126 -254.760422) (xy 102.203438 -254.813455) (xy 102.186283 -254.864383) (xy 102.161113 -254.911864)
			(xy 102.128592 -254.954646) (xy 102.089577 -254.991603) (xy 102.045096 -255.021759) (xy 101.996321 -255.04432)
			(xy 101.970586 -255.052068) (xy 101.957438 -255.056208) (xy 101.933843 -255.070434) (xy 101.914907 -255.090449)
			(xy 101.90201 -255.114797) (xy 101.89609 -255.141706) (xy 101.897576 -255.169218) (xy 101.906362 -255.195332)
			(xy 101.91369 -255.207008) (xy 101.926014 -255.225458) (xy 101.948257 -255.263852) (xy 101.95814 -255.283716)
			(xy 101.964546 -255.295926) (xy 101.982742 -255.316628) (xy 102.00582 -255.331697) (xy 102.032091 -255.340033)
			(xy 102.059635 -255.341026) (xy 102.086438 -255.334603) (xy 102.11054 -255.321233) (xy 102.1207 -255.31191)
			(xy 102.139357 -255.294254) (xy 102.181119 -255.264351) (xy 102.227009 -255.241275) (xy 102.275917 -255.225583)
			(xy 102.326666 -255.217653) (xy 102.352348 -255.217168) (xy 102.382364 -255.217847) (xy 102.441406 -255.228705)
			(xy 102.469696 -255.238758) (xy 102.483581 -255.243464) (xy 102.51281 -255.245578) (xy 102.541439 -255.239321)
			(xy 102.567122 -255.225207) (xy 102.587752 -255.204393) (xy 102.601637 -255.178586) (xy 102.605078 -255.164336)
			(xy 102.61063 -255.139855) (xy 102.628136 -255.092811) (xy 102.652557 -255.048957) (xy 102.68333 -255.009301)
			(xy 102.719748 -254.974756) (xy 102.760972 -254.946117) (xy 102.806054 -254.924044) (xy 102.853956 -254.909043)
			(xy 102.903576 -254.901462) (xy 102.928674 -254.900938) (xy 102.954645 -254.901419) (xy 103.005948 -254.909541)
			(xy 103.055348 -254.925588) (xy 103.10163 -254.949166) (xy 103.143653 -254.979694) (xy 103.180384 -255.016421)
			(xy 103.210916 -255.058441) (xy 103.234499 -255.10472) (xy 103.250551 -255.154119) (xy 103.258678 -255.205421)
			(xy 103.259128 -255.231392) (xy 103.258641 -255.256092) (xy 103.251239 -255.304935) (xy 103.236659 -255.352135)
			(xy 103.215225 -255.396643) (xy 103.187412 -255.43747) (xy 103.17099 -255.455928) (xy 103.161069 -255.467442)
			(xy 103.147868 -255.4948) (xy 103.143299 -255.524831) (xy 103.147768 -255.554877) (xy 103.16088 -255.582279)
			(xy 103.170736 -255.59385) (xy 103.187075 -255.612245) (xy 103.214683 -255.652968) (xy 103.235941 -255.697337)
			(xy 103.250379 -255.74437) (xy 103.257677 -255.793024) (xy 103.258112 -255.817624) (xy 103.257627 -255.843591)
			(xy 103.249499 -255.894885) (xy 103.233447 -255.944275) (xy 103.209865 -255.990547) (xy 103.179335 -256.032559)
			(xy 103.142609 -256.069278) (xy 103.10059 -256.0998) (xy 103.054314 -256.123372) (xy 103.00492 -256.139415)
			(xy 102.953625 -256.147533) (xy 102.927658 -256.148078) (xy 102.901504 -256.147578) (xy 102.849849 -256.139333)
			(xy 102.800138 -256.123057) (xy 102.753609 -256.099156) (xy 102.711426 -256.068225) (xy 102.67464 -256.031037)
			(xy 102.644169 -255.98852) (xy 102.620775 -255.941735) (xy 102.612444 -255.916938) (xy 102.607793 -255.903728)
			(xy 102.592398 -255.880345) (xy 102.571226 -255.862027) (xy 102.545872 -255.850155) (xy 102.518245 -255.845623)
			(xy 102.490427 -255.848772) (xy 102.477316 -255.853692) (xy 102.447525 -255.865037) (xy 102.384979 -255.877313)
			(xy 102.35311 -255.878076) (xy 102.352348 -255.878076) (xy 102.326668 -255.877586) (xy 102.275925 -255.869637)
			(xy 102.227022 -255.853938) (xy 102.181135 -255.830867) (xy 102.139366 -255.800978) (xy 102.1207 -255.783334)
			(xy 102.110549 -255.774001) (xy 102.086435 -255.760649) (xy 102.059628 -255.754235) (xy 102.032083 -255.755228)
			(xy 102.005807 -255.763556) (xy 101.982718 -255.778611) (xy 101.964499 -255.799295) (xy 101.95814 -255.811528)
			(xy 101.950832 -255.826316) (xy 101.934819 -255.855161) (xy 101.926136 -255.869186) (xy 101.912928 -255.889506)
			(xy 101.905768 -255.901173) (xy 101.897319 -255.927199) (xy 101.896092 -255.954534) (xy 101.902175 -255.981213)
			(xy 101.91513 -256.005315) (xy 101.934025 -256.025106) (xy 101.957501 -256.039164) (xy 101.970586 -256.043176)
			(xy 101.996334 -256.05085) (xy 102.045108 -256.073375) (xy 102.089593 -256.1035) (xy 102.128613 -256.140429)
			(xy 102.16114 -256.183188) (xy 102.186315 -256.230648) (xy 102.203475 -256.281559) (xy 102.211491 -256.33045)
			(xy 108.103416 -256.33045) (xy 108.103416 -256.330196) (xy 108.103861 -256.305669) (xy 108.111125 -256.257156)
			(xy 108.125478 -256.210248) (xy 108.146604 -256.165977) (xy 108.174041 -256.125313) (xy 108.190284 -256.10693)
			(xy 108.200038 -256.095402) (xy 108.213056 -256.068179) (xy 108.217534 -256.038337) (xy 108.213078 -256.008492)
			(xy 108.200079 -255.981259) (xy 108.190284 -255.96977) (xy 108.17405 -255.951379) (xy 108.146603 -255.910722)
			(xy 108.125471 -255.866453) (xy 108.11112 -255.819545) (xy 108.103864 -255.771031) (xy 108.103416 -255.746504)
			(xy 108.103416 -255.74625) (xy 108.103925 -255.720283) (xy 108.11205 -255.668988) (xy 108.128098 -255.619595)
			(xy 108.151676 -255.573321) (xy 108.182202 -255.531305) (xy 108.218925 -255.494582) (xy 108.260941 -255.464056)
			(xy 108.307215 -255.440478) (xy 108.356608 -255.42443) (xy 108.407903 -255.416305) (xy 108.459837 -255.416305)
			(xy 108.511132 -255.42443) (xy 108.560525 -255.440478) (xy 108.606799 -255.464056) (xy 108.648815 -255.494582)
			(xy 108.685538 -255.531305) (xy 108.716064 -255.573321) (xy 108.71633 -255.573843) (xy 113.300003 -255.573843)
			(xy 113.300003 -255.521909) (xy 113.308128 -255.470614) (xy 113.324176 -255.421221) (xy 113.347754 -255.374947)
			(xy 113.37828 -255.332931) (xy 113.415003 -255.296208) (xy 113.457019 -255.265682) (xy 113.503293 -255.242104)
			(xy 113.552686 -255.226056) (xy 113.603981 -255.217931) (xy 113.655915 -255.217931) (xy 113.70721 -255.226056)
			(xy 113.756603 -255.242104) (xy 113.802877 -255.265682) (xy 113.844893 -255.296208) (xy 113.881616 -255.332931)
			(xy 113.912142 -255.374947) (xy 113.93572 -255.421221) (xy 113.951768 -255.470614) (xy 113.959893 -255.521909)
			(xy 113.960402 -255.547876) (xy 113.959893 -255.573843) (xy 113.951768 -255.625138) (xy 113.93572 -255.674531)
			(xy 113.912142 -255.720805) (xy 113.881616 -255.762821) (xy 113.844893 -255.799544) (xy 113.802877 -255.83007)
			(xy 113.756603 -255.853648) (xy 113.70721 -255.869696) (xy 113.655915 -255.877821) (xy 113.603981 -255.877821)
			(xy 113.552686 -255.869696) (xy 113.503293 -255.853648) (xy 113.457019 -255.83007) (xy 113.415003 -255.799544)
			(xy 113.37828 -255.762821) (xy 113.347754 -255.720805) (xy 113.324176 -255.674531) (xy 113.308128 -255.625138)
			(xy 113.300003 -255.573843) (xy 108.71633 -255.573843) (xy 108.739642 -255.619595) (xy 108.75569 -255.668988)
			(xy 108.763815 -255.720283) (xy 108.764324 -255.74625) (xy 108.764324 -255.746504) (xy 108.763868 -255.77103)
			(xy 108.756606 -255.819543) (xy 108.742255 -255.86645) (xy 108.721131 -255.910721) (xy 108.693697 -255.951386)
			(xy 108.677456 -255.96977) (xy 108.667601 -255.98122) (xy 108.654589 -256.00847) (xy 108.650128 -256.038337)
			(xy 108.654611 -256.068201) (xy 108.667643 -256.095442) (xy 108.677456 -256.10693) (xy 108.693681 -256.12533)
			(xy 108.721131 -256.165983) (xy 108.742265 -256.21025) (xy 108.756619 -256.257156) (xy 108.763876 -256.305669)
			(xy 108.764324 -256.330196) (xy 108.764324 -256.33045) (xy 108.763815 -256.356417) (xy 108.758866 -256.387659)
			(xy 110.010449 -256.387659) (xy 110.010449 -256.335725) (xy 110.018574 -256.28443) (xy 110.034622 -256.235037)
			(xy 110.0582 -256.188763) (xy 110.088726 -256.146747) (xy 110.125449 -256.110024) (xy 110.167465 -256.079498)
			(xy 110.213739 -256.05592) (xy 110.263132 -256.039872) (xy 110.314427 -256.031747) (xy 110.366361 -256.031747)
			(xy 110.417656 -256.039872) (xy 110.467049 -256.05592) (xy 110.513323 -256.079498) (xy 110.555339 -256.110024)
			(xy 110.592062 -256.146747) (xy 110.622588 -256.188763) (xy 110.646166 -256.235037) (xy 110.662214 -256.28443)
			(xy 110.670339 -256.335725) (xy 110.670848 -256.361692) (xy 110.670339 -256.387659) (xy 110.669986 -256.389886)
			(xy 115.098068 -256.389886) (xy 115.098068 -256.389632) (xy 115.098547 -256.365107) (xy 115.105805 -256.316595)
			(xy 115.12015 -256.269689) (xy 115.141269 -256.225417) (xy 115.168697 -256.184751) (xy 115.184936 -256.166366)
			(xy 115.194756 -256.154889) (xy 115.207774 -256.127648) (xy 115.212241 -256.09779) (xy 115.207768 -256.067932)
			(xy 115.194745 -256.040694) (xy 115.184936 -256.029206) (xy 115.16868 -256.010833) (xy 115.141234 -255.970172)
			(xy 115.120106 -255.925899) (xy 115.10576 -255.878987) (xy 115.098511 -255.830468) (xy 115.098068 -255.80594)
			(xy 115.098068 -255.805686) (xy 115.098577 -255.779719) (xy 115.106702 -255.728424) (xy 115.12275 -255.679031)
			(xy 115.146328 -255.632757) (xy 115.176854 -255.590741) (xy 115.213577 -255.554018) (xy 115.255593 -255.523492)
			(xy 115.301867 -255.499914) (xy 115.35126 -255.483866) (xy 115.402555 -255.475741) (xy 115.454489 -255.475741)
			(xy 115.505784 -255.483866) (xy 115.555177 -255.499914) (xy 115.601451 -255.523492) (xy 115.643467 -255.554018)
			(xy 115.68019 -255.590741) (xy 115.710716 -255.632757) (xy 115.734294 -255.679031) (xy 115.750342 -255.728424)
			(xy 115.758467 -255.779719) (xy 115.758976 -255.805686) (xy 115.758976 -255.80594) (xy 115.758529 -255.830467)
			(xy 115.751262 -255.878979) (xy 115.736908 -255.925885) (xy 115.715783 -255.970157) (xy 115.688349 -256.010822)
			(xy 115.672108 -256.029206) (xy 115.66232 -256.040706) (xy 115.649307 -256.06794) (xy 115.644836 -256.09779)
			(xy 115.6493 -256.12764) (xy 115.662308 -256.154876) (xy 115.672108 -256.166366) (xy 115.688358 -256.184744)
			(xy 115.715803 -256.225404) (xy 115.736932 -256.269677) (xy 115.751279 -256.316587) (xy 115.758531 -256.365104)
			(xy 115.758976 -256.389632) (xy 115.758976 -256.389886) (xy 115.758467 -256.415853) (xy 115.750342 -256.467148)
			(xy 115.734294 -256.516541) (xy 115.710716 -256.562815) (xy 115.68019 -256.604831) (xy 115.643467 -256.641554)
			(xy 115.601451 -256.67208) (xy 115.555177 -256.695658) (xy 115.505784 -256.711706) (xy 115.454489 -256.719831)
			(xy 115.402555 -256.719831) (xy 115.35126 -256.711706) (xy 115.301867 -256.695658) (xy 115.255593 -256.67208)
			(xy 115.213577 -256.641554) (xy 115.176854 -256.604831) (xy 115.146328 -256.562815) (xy 115.12275 -256.516541)
			(xy 115.106702 -256.467148) (xy 115.098577 -256.415853) (xy 115.098068 -256.389886) (xy 110.669986 -256.389886)
			(xy 110.662214 -256.438954) (xy 110.646166 -256.488347) (xy 110.622588 -256.534621) (xy 110.592062 -256.576637)
			(xy 110.555339 -256.61336) (xy 110.513323 -256.643886) (xy 110.467049 -256.667464) (xy 110.417656 -256.683512)
			(xy 110.366361 -256.691637) (xy 110.314427 -256.691637) (xy 110.263132 -256.683512) (xy 110.213739 -256.667464)
			(xy 110.167465 -256.643886) (xy 110.125449 -256.61336) (xy 110.088726 -256.576637) (xy 110.0582 -256.534621)
			(xy 110.034622 -256.488347) (xy 110.018574 -256.438954) (xy 110.010449 -256.387659) (xy 108.758866 -256.387659)
			(xy 108.75569 -256.407712) (xy 108.739642 -256.457105) (xy 108.716064 -256.503379) (xy 108.685538 -256.545395)
			(xy 108.648815 -256.582118) (xy 108.606799 -256.612644) (xy 108.560525 -256.636222) (xy 108.511132 -256.65227)
			(xy 108.459837 -256.660395) (xy 108.407903 -256.660395) (xy 108.356608 -256.65227) (xy 108.307215 -256.636222)
			(xy 108.260941 -256.612644) (xy 108.218925 -256.582118) (xy 108.182202 -256.545395) (xy 108.151676 -256.503379)
			(xy 108.128098 -256.457105) (xy 108.11205 -256.407712) (xy 108.103925 -256.356417) (xy 108.103416 -256.33045)
			(xy 102.211491 -256.33045) (xy 102.212167 -256.334576) (xy 102.212648 -256.361438) (xy 102.212139 -256.387405)
			(xy 102.204014 -256.4387) (xy 102.187966 -256.488093) (xy 102.164388 -256.534367) (xy 102.133862 -256.576383)
			(xy 102.097139 -256.613106) (xy 102.055123 -256.643632) (xy 102.008849 -256.66721) (xy 101.959456 -256.683258)
			(xy 101.908161 -256.691383) (xy 101.856227 -256.691383) (xy 101.804932 -256.683258) (xy 101.755539 -256.66721)
			(xy 101.709265 -256.643632) (xy 101.667249 -256.613106) (xy 101.630526 -256.576383) (xy 101.6 -256.534367)
			(xy 101.576422 -256.488093) (xy 101.560374 -256.4387) (xy 101.552249 -256.387405) (xy 101.55174 -256.361438)
			(xy 101.551994 -256.34696) (xy 101.552136 -256.331686) (xy 101.54438 -256.302157) (xy 101.528248 -256.276235)
			(xy 101.50518 -256.256234) (xy 101.477234 -256.243937) (xy 101.446904 -256.240443) (xy 101.416894 -256.246062)
			(xy 101.40315 -256.252726) (xy 101.333808 -256.292858) (xy 101.296978 -256.31394) (xy 101.289985 -256.318725)
			(xy 101.279397 -256.331944) (xy 101.273701 -256.347893) (xy 101.273356 -256.356358) (xy 101.273356 -256.361438)
			(xy 101.272888 -256.38684) (xy 101.265112 -256.437044) (xy 101.249748 -256.485469) (xy 101.227158 -256.530974)
			(xy 101.197874 -256.572488) (xy 101.162584 -256.609034) (xy 101.12212 -256.639752) (xy 101.077433 -256.66392)
			(xy 101.053646 -256.672842) (xy 101.042895 -256.677236) (xy 101.026615 -256.693768) (xy 101.022404 -256.704592)
			(xy 101.008366 -256.744919) (xy 100.974756 -256.823423) (xy 100.935024 -256.899013) (xy 100.889421 -256.971213)
			(xy 100.838233 -257.039568) (xy 100.810314 -257.071876) (xy 100.809298 -257.072892) (xy 100.804726 -257.079496)
			(xy 100.800115 -257.087715) (xy 100.79673 -257.106242) (xy 100.798122 -257.115564) (xy 100.798884 -257.119882)
			(xy 100.801033 -257.133496) (xy 100.803326 -257.160964) (xy 100.803456 -257.174746) (xy 100.803456 -257.175254)
			(xy 100.802987 -257.200655) (xy 100.802899 -257.201221) (xy 101.082603 -257.201221) (xy 101.082603 -257.149287)
			(xy 101.090728 -257.097992) (xy 101.106776 -257.048599) (xy 101.130354 -257.002325) (xy 101.16088 -256.960309)
			(xy 101.197603 -256.923586) (xy 101.239619 -256.89306) (xy 101.285893 -256.869482) (xy 101.335286 -256.853434)
			(xy 101.386581 -256.845309) (xy 101.438515 -256.845309) (xy 101.48981 -256.853434) (xy 101.539203 -256.869482)
			(xy 101.585477 -256.89306) (xy 101.627493 -256.923586) (xy 101.664216 -256.960309) (xy 101.694742 -257.002325)
			(xy 101.71832 -257.048599) (xy 101.734368 -257.097992) (xy 101.742493 -257.149287) (xy 101.743002 -257.175254)
			(xy 101.742493 -257.201221) (xy 102.022403 -257.201221) (xy 102.022403 -257.149287) (xy 102.030528 -257.097992)
			(xy 102.046576 -257.048599) (xy 102.070154 -257.002325) (xy 102.10068 -256.960309) (xy 102.137403 -256.923586)
			(xy 102.179419 -256.89306) (xy 102.225693 -256.869482) (xy 102.275086 -256.853434) (xy 102.326381 -256.845309)
			(xy 102.378315 -256.845309) (xy 102.42961 -256.853434) (xy 102.479003 -256.869482) (xy 102.525277 -256.89306)
			(xy 102.567293 -256.923586) (xy 102.604016 -256.960309) (xy 102.634542 -257.002325) (xy 102.65812 -257.048599)
			(xy 102.674168 -257.097992) (xy 102.682293 -257.149287) (xy 102.682802 -257.175254) (xy 102.682293 -257.201221)
			(xy 102.682253 -257.201475) (xy 113.300003 -257.201475) (xy 113.300003 -257.149541) (xy 113.308128 -257.098246)
			(xy 113.324176 -257.048853) (xy 113.347754 -257.002579) (xy 113.37828 -256.960563) (xy 113.415003 -256.92384)
			(xy 113.457019 -256.893314) (xy 113.503293 -256.869736) (xy 113.552686 -256.853688) (xy 113.603981 -256.845563)
			(xy 113.655915 -256.845563) (xy 113.70721 -256.853688) (xy 113.756603 -256.869736) (xy 113.802877 -256.893314)
			(xy 113.844893 -256.92384) (xy 113.881616 -256.960563) (xy 113.912142 -257.002579) (xy 113.93572 -257.048853)
			(xy 113.951768 -257.098246) (xy 113.959893 -257.149541) (xy 113.960402 -257.175508) (xy 113.959893 -257.201475)
			(xy 113.951768 -257.25277) (xy 113.93572 -257.302163) (xy 113.912142 -257.348437) (xy 113.881616 -257.390453)
			(xy 113.844893 -257.427176) (xy 113.802877 -257.457702) (xy 113.756603 -257.48128) (xy 113.70721 -257.497328)
			(xy 113.655915 -257.505453) (xy 113.603981 -257.505453) (xy 113.552686 -257.497328) (xy 113.503293 -257.48128)
			(xy 113.457019 -257.457702) (xy 113.415003 -257.427176) (xy 113.37828 -257.390453) (xy 113.347754 -257.348437)
			(xy 113.324176 -257.302163) (xy 113.308128 -257.25277) (xy 113.300003 -257.201475) (xy 102.682253 -257.201475)
			(xy 102.674168 -257.252516) (xy 102.65812 -257.301909) (xy 102.634542 -257.348183) (xy 102.604016 -257.390199)
			(xy 102.567293 -257.426922) (xy 102.525277 -257.457448) (xy 102.479003 -257.481026) (xy 102.42961 -257.497074)
			(xy 102.378315 -257.505199) (xy 102.326381 -257.505199) (xy 102.275086 -257.497074) (xy 102.225693 -257.481026)
			(xy 102.179419 -257.457448) (xy 102.137403 -257.426922) (xy 102.10068 -257.390199) (xy 102.070154 -257.348183)
			(xy 102.046576 -257.301909) (xy 102.030528 -257.252516) (xy 102.022403 -257.201221) (xy 101.742493 -257.201221)
			(xy 101.734368 -257.252516) (xy 101.71832 -257.301909) (xy 101.694742 -257.348183) (xy 101.664216 -257.390199)
			(xy 101.627493 -257.426922) (xy 101.585477 -257.457448) (xy 101.539203 -257.481026) (xy 101.48981 -257.497074)
			(xy 101.438515 -257.505199) (xy 101.386581 -257.505199) (xy 101.335286 -257.497074) (xy 101.285893 -257.481026)
			(xy 101.239619 -257.457448) (xy 101.197603 -257.426922) (xy 101.16088 -257.390199) (xy 101.130354 -257.348183)
			(xy 101.106776 -257.301909) (xy 101.090728 -257.252516) (xy 101.082603 -257.201221) (xy 100.802899 -257.201221)
			(xy 100.795209 -257.250858) (xy 100.779843 -257.299281) (xy 100.757252 -257.344783) (xy 100.727967 -257.386295)
			(xy 100.692678 -257.42284) (xy 100.652214 -257.453556) (xy 100.607528 -257.477723) (xy 100.583746 -257.486658)
			(xy 100.572996 -257.491053) (xy 100.556721 -257.507587) (xy 100.552504 -257.518408) (xy 100.538441 -257.558847)
			(xy 100.504762 -257.637571) (xy 100.464937 -257.713371) (xy 100.419218 -257.785769) (xy 100.367894 -257.854308)
			(xy 100.339906 -257.886708) (xy 100.336858 -257.890264) (xy 100.334318 -257.89382) (xy 100.329929 -257.90191)
			(xy 100.326683 -257.920011) (xy 100.327968 -257.929126) (xy 100.327968 -257.929634) (xy 100.32873 -257.933952)
			(xy 100.330868 -257.947503) (xy 100.333158 -257.974844) (xy 100.333302 -257.988562) (xy 100.333302 -257.98907)
			(xy 100.332841 -258.014459) (xy 100.332752 -258.015037) (xy 100.612449 -258.015037) (xy 100.612449 -257.963103)
			(xy 100.620574 -257.911808) (xy 100.636622 -257.862415) (xy 100.6602 -257.816141) (xy 100.690726 -257.774125)
			(xy 100.727449 -257.737402) (xy 100.769465 -257.706876) (xy 100.815739 -257.683298) (xy 100.865132 -257.66725)
			(xy 100.916427 -257.659125) (xy 100.968361 -257.659125) (xy 101.019656 -257.66725) (xy 101.069049 -257.683298)
			(xy 101.115323 -257.706876) (xy 101.157339 -257.737402) (xy 101.194062 -257.774125) (xy 101.224588 -257.816141)
			(xy 101.248166 -257.862415) (xy 101.264214 -257.911808) (xy 101.272339 -257.963103) (xy 101.272848 -257.98907)
			(xy 101.272339 -258.015037) (xy 101.552249 -258.015037) (xy 101.552249 -257.963103) (xy 101.560374 -257.911808)
			(xy 101.576422 -257.862415) (xy 101.6 -257.816141) (xy 101.630526 -257.774125) (xy 101.667249 -257.737402)
			(xy 101.709265 -257.706876) (xy 101.755539 -257.683298) (xy 101.804932 -257.66725) (xy 101.856227 -257.659125)
			(xy 101.908161 -257.659125) (xy 101.959456 -257.66725) (xy 102.008849 -257.683298) (xy 102.055123 -257.706876)
			(xy 102.072044 -257.71917) (xy 103.069615 -257.71917) (xy 103.069615 -257.66723) (xy 103.07774 -257.61593)
			(xy 103.09379 -257.566532) (xy 103.11737 -257.520253) (xy 103.147899 -257.478233) (xy 103.184625 -257.441505)
			(xy 103.226645 -257.410975) (xy 103.272923 -257.387394) (xy 103.32232 -257.371343) (xy 103.37362 -257.363216)
			(xy 103.39959 -257.362706) (xy 103.399844 -257.362706) (xy 103.424372 -257.36313) (xy 103.472886 -257.370399)
			(xy 103.519793 -257.384757) (xy 103.564064 -257.405888) (xy 103.604727 -257.433329) (xy 103.62311 -257.449574)
			(xy 103.634599 -257.459377) (xy 103.661836 -257.472391) (xy 103.69169 -257.476859) (xy 103.721544 -257.472391)
			(xy 103.748781 -257.459377) (xy 103.76027 -257.449574) (xy 103.778664 -257.433303) (xy 103.819372 -257.405838)
			(xy 103.863697 -257.384702) (xy 103.910664 -257.370362) (xy 103.959236 -257.363134) (xy 103.98379 -257.362706)
			(xy 104.008343 -257.363113) (xy 104.056912 -257.37036) (xy 104.103875 -257.384711) (xy 104.148198 -257.405851)
			(xy 104.188907 -257.433313) (xy 104.20731 -257.449574) (xy 104.218799 -257.459377) (xy 104.246036 -257.472391)
			(xy 104.27589 -257.476859) (xy 104.305744 -257.472391) (xy 104.332981 -257.459377) (xy 104.34447 -257.449574)
			(xy 104.362844 -257.433319) (xy 104.403506 -257.405876) (xy 104.447779 -257.384748) (xy 104.49469 -257.370401)
			(xy 104.543208 -257.363151) (xy 104.567736 -257.362706) (xy 104.56799 -257.362706) (xy 104.593957 -257.363268)
			(xy 104.645251 -257.371391) (xy 104.694643 -257.387438) (xy 104.740916 -257.411014) (xy 104.782932 -257.441539)
			(xy 104.819655 -257.478261) (xy 104.850181 -257.520275) (xy 104.873758 -257.566548) (xy 104.889807 -257.615939)
			(xy 104.897931 -257.667233) (xy 104.897931 -257.719167) (xy 104.897931 -257.71917) (xy 105.127015 -257.71917)
			(xy 105.127015 -257.66723) (xy 105.13514 -257.61593) (xy 105.15119 -257.566532) (xy 105.17477 -257.520253)
			(xy 105.205299 -257.478233) (xy 105.242025 -257.441505) (xy 105.284045 -257.410975) (xy 105.330323 -257.387394)
			(xy 105.37972 -257.371343) (xy 105.43102 -257.363216) (xy 105.45699 -257.362706) (xy 105.482744 -257.363196)
			(xy 105.533629 -257.371174) (xy 105.582659 -257.386955) (xy 105.628645 -257.410156) (xy 105.670472 -257.440214)
			(xy 105.689146 -257.457956) (xy 105.698836 -257.466949) (xy 105.721768 -257.480081) (xy 105.747307 -257.486876)
			(xy 105.773733 -257.486876) (xy 105.799272 -257.480081) (xy 105.822204 -257.466949) (xy 105.831894 -257.457956)
			(xy 105.850585 -257.440235) (xy 105.892413 -257.410185) (xy 105.938396 -257.386985) (xy 105.987419 -257.371197)
			(xy 106.038298 -257.363202) (xy 106.06405 -257.362706) (xy 106.090019 -257.363265) (xy 106.141318 -257.371383)
			(xy 106.190715 -257.387426) (xy 106.236994 -257.411) (xy 106.279015 -257.441525) (xy 106.315743 -257.478247)
			(xy 106.346273 -257.520263) (xy 106.369855 -257.566539) (xy 106.385906 -257.615934) (xy 106.394031 -257.667231)
			(xy 106.394031 -257.719169) (xy 106.385906 -257.770466) (xy 106.369855 -257.819861) (xy 106.346273 -257.866137)
			(xy 106.315743 -257.908153) (xy 106.279015 -257.944875) (xy 106.236994 -257.9754) (xy 106.190715 -257.998974)
			(xy 106.141318 -258.015017) (xy 106.139587 -258.015291) (xy 110.010703 -258.015291) (xy 110.010703 -257.963357)
			(xy 110.018828 -257.912062) (xy 110.034876 -257.862669) (xy 110.058454 -257.816395) (xy 110.08898 -257.774379)
			(xy 110.125703 -257.737656) (xy 110.167719 -257.70713) (xy 110.213993 -257.683552) (xy 110.263386 -257.667504)
			(xy 110.314681 -257.659379) (xy 110.366615 -257.659379) (xy 110.41791 -257.667504) (xy 110.467303 -257.683552)
			(xy 110.513577 -257.70713) (xy 110.555593 -257.737656) (xy 110.592316 -257.774379) (xy 110.622842 -257.816395)
			(xy 110.64642 -257.862669) (xy 110.662468 -257.912062) (xy 110.670593 -257.963357) (xy 110.671102 -257.989324)
			(xy 110.670593 -258.015291) (xy 110.662468 -258.066586) (xy 110.64642 -258.115979) (xy 110.622842 -258.162253)
			(xy 110.592316 -258.204269) (xy 110.555593 -258.240992) (xy 110.513577 -258.271518) (xy 110.467303 -258.295096)
			(xy 110.41791 -258.311144) (xy 110.366615 -258.319269) (xy 110.314681 -258.319269) (xy 110.263386 -258.311144)
			(xy 110.213993 -258.295096) (xy 110.167719 -258.271518) (xy 110.125703 -258.240992) (xy 110.08898 -258.204269)
			(xy 110.058454 -258.162253) (xy 110.034876 -258.115979) (xy 110.018828 -258.066586) (xy 110.010703 -258.015291)
			(xy 106.139587 -258.015291) (xy 106.090019 -258.023135) (xy 106.06405 -258.023614) (xy 106.038295 -258.023156)
			(xy 105.987408 -258.015169) (xy 105.938378 -257.99938) (xy 105.892393 -257.976172) (xy 105.850567 -257.946109)
			(xy 105.831894 -257.928364) (xy 105.822204 -257.919371) (xy 105.799272 -257.906239) (xy 105.773733 -257.899444)
			(xy 105.747307 -257.899444) (xy 105.721768 -257.906239) (xy 105.698836 -257.919371) (xy 105.689146 -257.928364)
			(xy 105.670484 -257.946117) (xy 105.628647 -257.976162) (xy 105.582658 -257.999356) (xy 105.533628 -258.015137)
			(xy 105.482744 -258.023123) (xy 105.45699 -258.023614) (xy 105.43102 -258.023184) (xy 105.37972 -258.015057)
			(xy 105.330323 -257.999006) (xy 105.284045 -257.975425) (xy 105.242025 -257.944895) (xy 105.205299 -257.908167)
			(xy 105.17477 -257.866147) (xy 105.15119 -257.819868) (xy 105.13514 -257.77047) (xy 105.127015 -257.71917)
			(xy 104.897931 -257.71917) (xy 104.889807 -257.770461) (xy 104.873758 -257.819852) (xy 104.850181 -257.866125)
			(xy 104.819655 -257.908139) (xy 104.782932 -257.944861) (xy 104.740916 -257.975386) (xy 104.694643 -257.998962)
			(xy 104.645251 -258.015009) (xy 104.593957 -258.023132) (xy 104.56799 -258.023614) (xy 104.567736 -258.023614)
			(xy 104.54321 -258.023137) (xy 104.494699 -258.01588) (xy 104.447792 -258.001534) (xy 104.40352 -257.980415)
			(xy 104.362855 -257.952985) (xy 104.34447 -257.936746) (xy 104.332981 -257.926943) (xy 104.305744 -257.913929)
			(xy 104.27589 -257.909461) (xy 104.246036 -257.913929) (xy 104.218799 -257.926943) (xy 104.20731 -257.936746)
			(xy 104.188913 -257.953013) (xy 104.148207 -257.980482) (xy 104.103883 -258.00162) (xy 104.056916 -258.01596)
			(xy 104.008344 -258.023187) (xy 103.98379 -258.023614) (xy 103.959239 -258.023154) (xy 103.910672 -258.015919)
			(xy 103.863711 -258.00158) (xy 103.819386 -257.980452) (xy 103.778674 -257.953001) (xy 103.76027 -257.936746)
			(xy 103.748781 -257.926943) (xy 103.721544 -257.913929) (xy 103.69169 -257.909461) (xy 103.661836 -257.913929)
			(xy 103.634599 -257.926943) (xy 103.62311 -257.936746) (xy 103.604733 -257.952997) (xy 103.564073 -257.980444)
			(xy 103.519801 -258.001574) (xy 103.47289 -258.015921) (xy 103.424372 -258.02317) (xy 103.399844 -258.023614)
			(xy 103.39959 -258.023614) (xy 103.37362 -258.023184) (xy 103.32232 -258.015057) (xy 103.272923 -257.999006)
			(xy 103.226645 -257.975425) (xy 103.184625 -257.944895) (xy 103.147899 -257.908167) (xy 103.11737 -257.866147)
			(xy 103.09379 -257.819868) (xy 103.07774 -257.77047) (xy 103.069615 -257.71917) (xy 102.072044 -257.71917)
			(xy 102.097139 -257.737402) (xy 102.133862 -257.774125) (xy 102.164388 -257.816141) (xy 102.187966 -257.862415)
			(xy 102.204014 -257.911808) (xy 102.212139 -257.963103) (xy 102.212648 -257.98907) (xy 102.212139 -258.015037)
			(xy 102.204014 -258.066332) (xy 102.187966 -258.115725) (xy 102.164388 -258.161999) (xy 102.133862 -258.204015)
			(xy 102.097139 -258.240738) (xy 102.055123 -258.271264) (xy 102.008849 -258.294842) (xy 101.959456 -258.31089)
			(xy 101.908161 -258.319015) (xy 101.856227 -258.319015) (xy 101.804932 -258.31089) (xy 101.755539 -258.294842)
			(xy 101.709265 -258.271264) (xy 101.667249 -258.240738) (xy 101.630526 -258.204015) (xy 101.6 -258.161999)
			(xy 101.576422 -258.115725) (xy 101.560374 -258.066332) (xy 101.552249 -258.015037) (xy 101.272339 -258.015037)
			(xy 101.264214 -258.066332) (xy 101.248166 -258.115725) (xy 101.224588 -258.161999) (xy 101.194062 -258.204015)
			(xy 101.157339 -258.240738) (xy 101.115323 -258.271264) (xy 101.069049 -258.294842) (xy 101.019656 -258.31089)
			(xy 100.968361 -258.319015) (xy 100.916427 -258.319015) (xy 100.865132 -258.31089) (xy 100.815739 -258.294842)
			(xy 100.769465 -258.271264) (xy 100.727449 -258.240738) (xy 100.690726 -258.204015) (xy 100.6602 -258.161999)
			(xy 100.636622 -258.115725) (xy 100.620574 -258.066332) (xy 100.612449 -258.015037) (xy 100.332752 -258.015037)
			(xy 100.325081 -258.06464) (xy 100.30974 -258.113044) (xy 100.287179 -258.158534) (xy 100.257927 -258.200039)
			(xy 100.222673 -258.236583) (xy 100.182246 -258.267307) (xy 100.137596 -258.291489) (xy 100.113846 -258.300474)
			(xy 100.105718 -258.304284) (xy 100.105464 -258.304284) (xy 100.098288 -258.308852) (xy 100.087134 -258.321683)
			(xy 100.08362 -258.32943) (xy 100.082604 -258.332478) (xy 100.068547 -258.372773) (xy 100.034911 -258.451215)
			(xy 99.99517 -258.526747) (xy 99.949572 -258.598895) (xy 99.898403 -258.667205) (xy 99.870514 -258.699508)
			(xy 99.869498 -258.700524) (xy 99.864926 -258.707128) (xy 99.860862 -258.715256) (xy 99.866314 -258.736817)
			(xy 99.872172 -258.780903) (xy 99.872546 -258.80314) (xy 99.872034 -258.829107) (xy 100.142803 -258.829107)
			(xy 100.142803 -258.777173) (xy 100.150928 -258.725878) (xy 100.166976 -258.676485) (xy 100.190554 -258.630211)
			(xy 100.22108 -258.588195) (xy 100.257803 -258.551472) (xy 100.299819 -258.520946) (xy 100.346093 -258.497368)
			(xy 100.395486 -258.48132) (xy 100.446781 -258.473195) (xy 100.498715 -258.473195) (xy 100.55001 -258.48132)
			(xy 100.599403 -258.497368) (xy 100.645677 -258.520946) (xy 100.687693 -258.551472) (xy 100.724416 -258.588195)
			(xy 100.754942 -258.630211) (xy 100.77852 -258.676485) (xy 100.794568 -258.725878) (xy 100.802693 -258.777173)
			(xy 100.803202 -258.80314) (xy 100.802693 -258.829107) (xy 101.082349 -258.829107) (xy 101.082349 -258.777173)
			(xy 101.090474 -258.725878) (xy 101.106522 -258.676485) (xy 101.1301 -258.630211) (xy 101.160626 -258.588195)
			(xy 101.197349 -258.551472) (xy 101.239365 -258.520946) (xy 101.285639 -258.497368) (xy 101.335032 -258.48132)
			(xy 101.386327 -258.473195) (xy 101.438261 -258.473195) (xy 101.489556 -258.48132) (xy 101.538949 -258.497368)
			(xy 101.585223 -258.520946) (xy 101.627239 -258.551472) (xy 101.663962 -258.588195) (xy 101.694488 -258.630211)
			(xy 101.718066 -258.676485) (xy 101.734114 -258.725878) (xy 101.742239 -258.777173) (xy 101.742748 -258.80314)
			(xy 101.742239 -258.829107) (xy 102.021895 -258.829107) (xy 102.021895 -258.777173) (xy 102.03002 -258.725878)
			(xy 102.046068 -258.676485) (xy 102.069646 -258.630211) (xy 102.100172 -258.588195) (xy 102.136895 -258.551472)
			(xy 102.178911 -258.520946) (xy 102.225185 -258.497368) (xy 102.274578 -258.48132) (xy 102.325873 -258.473195)
			(xy 102.377807 -258.473195) (xy 102.429102 -258.48132) (xy 102.478495 -258.497368) (xy 102.524769 -258.520946)
			(xy 102.566785 -258.551472) (xy 102.603508 -258.588195) (xy 102.634034 -258.630211) (xy 102.657612 -258.676485)
			(xy 102.67366 -258.725878) (xy 102.681785 -258.777173) (xy 102.682294 -258.80314) (xy 102.681785 -258.829107)
			(xy 102.67366 -258.880402) (xy 102.657612 -258.929795) (xy 102.634034 -258.976069) (xy 102.603508 -259.018085)
			(xy 102.566785 -259.054808) (xy 102.524769 -259.085334) (xy 102.478495 -259.108912) (xy 102.429102 -259.12496)
			(xy 102.377807 -259.133085) (xy 102.325873 -259.133085) (xy 102.274578 -259.12496) (xy 102.225185 -259.108912)
			(xy 102.178911 -259.085334) (xy 102.136895 -259.054808) (xy 102.100172 -259.018085) (xy 102.069646 -258.976069)
			(xy 102.046068 -258.929795) (xy 102.03002 -258.880402) (xy 102.021895 -258.829107) (xy 101.742239 -258.829107)
			(xy 101.734114 -258.880402) (xy 101.718066 -258.929795) (xy 101.694488 -258.976069) (xy 101.663962 -259.018085)
			(xy 101.627239 -259.054808) (xy 101.585223 -259.085334) (xy 101.538949 -259.108912) (xy 101.489556 -259.12496)
			(xy 101.438261 -259.133085) (xy 101.386327 -259.133085) (xy 101.335032 -259.12496) (xy 101.285639 -259.108912)
			(xy 101.239365 -259.085334) (xy 101.197349 -259.054808) (xy 101.160626 -259.018085) (xy 101.1301 -258.976069)
			(xy 101.106522 -258.929795) (xy 101.090474 -258.880402) (xy 101.082349 -258.829107) (xy 100.802693 -258.829107)
			(xy 100.794568 -258.880402) (xy 100.77852 -258.929795) (xy 100.754942 -258.976069) (xy 100.724416 -259.018085)
			(xy 100.687693 -259.054808) (xy 100.645677 -259.085334) (xy 100.599403 -259.108912) (xy 100.55001 -259.12496)
			(xy 100.498715 -259.133085) (xy 100.446781 -259.133085) (xy 100.395486 -259.12496) (xy 100.346093 -259.108912)
			(xy 100.299819 -259.085334) (xy 100.257803 -259.054808) (xy 100.22108 -259.018085) (xy 100.190554 -258.976069)
			(xy 100.166976 -258.929795) (xy 100.150928 -258.880402) (xy 100.142803 -258.829107) (xy 99.872034 -258.829107)
			(xy 99.87202 -258.829825) (xy 99.863666 -258.882537) (xy 99.84717 -258.933294) (xy 99.822939 -258.980847)
			(xy 99.791568 -259.024024) (xy 99.75383 -259.061763) (xy 99.710654 -259.093134) (xy 99.663102 -259.117367)
			(xy 99.612345 -259.133864) (xy 99.559633 -259.142219) (xy 99.532948 -259.142738) (xy 99.508945 -259.14232)
			(xy 99.461417 -259.135555) (xy 99.415315 -259.122166) (xy 99.371557 -259.102421) (xy 99.331014 -259.076713)
			(xy 99.312476 -259.061458) (xy 99.306139 -259.061241) (xy 99.293677 -259.063557) (xy 99.287838 -259.06603)
			(xy 99.28733 -259.066284) (xy 99.203002 -259.10921) (xy 99.195766 -259.113808) (xy 99.184645 -259.126843)
			(xy 99.178461 -259.142822) (xy 99.177856 -259.151374) (xy 99.177856 -259.273294) (xy 99.178101 -259.280476)
			(xy 99.182096 -259.294273) (xy 99.18573 -259.300472) (xy 99.18954 -259.306314) (xy 99.1997 -259.315712)
			(xy 99.206558 -259.319014) (xy 99.230192 -259.33102) (xy 99.273627 -259.361402) (xy 99.311665 -259.398318)
			(xy 99.343334 -259.440825) (xy 99.367822 -259.487836) (xy 99.384506 -259.538149) (xy 99.392957 -259.590478)
			(xy 99.39296 -259.642923) (xy 99.672649 -259.642923) (xy 99.672649 -259.590989) (xy 99.680774 -259.539694)
			(xy 99.696822 -259.490301) (xy 99.7204 -259.444027) (xy 99.750926 -259.402011) (xy 99.787649 -259.365288)
			(xy 99.829665 -259.334762) (xy 99.875939 -259.311184) (xy 99.925332 -259.295136) (xy 99.976627 -259.287011)
			(xy 100.028561 -259.287011) (xy 100.079856 -259.295136) (xy 100.129249 -259.311184) (xy 100.175523 -259.334762)
			(xy 100.217539 -259.365288) (xy 100.254262 -259.402011) (xy 100.284788 -259.444027) (xy 100.308366 -259.490301)
			(xy 100.324414 -259.539694) (xy 100.332539 -259.590989) (xy 100.333048 -259.616956) (xy 100.332539 -259.642923)
			(xy 100.612449 -259.642923) (xy 100.612449 -259.590989) (xy 100.620574 -259.539694) (xy 100.636622 -259.490301)
			(xy 100.6602 -259.444027) (xy 100.690726 -259.402011) (xy 100.727449 -259.365288) (xy 100.769465 -259.334762)
			(xy 100.815739 -259.311184) (xy 100.865132 -259.295136) (xy 100.916427 -259.287011) (xy 100.968361 -259.287011)
			(xy 101.019656 -259.295136) (xy 101.069049 -259.311184) (xy 101.115323 -259.334762) (xy 101.157339 -259.365288)
			(xy 101.194062 -259.402011) (xy 101.224588 -259.444027) (xy 101.248166 -259.490301) (xy 101.264214 -259.539694)
			(xy 101.272339 -259.590989) (xy 101.272848 -259.616956) (xy 101.272339 -259.642923) (xy 101.552249 -259.642923)
			(xy 101.552249 -259.590989) (xy 101.560374 -259.539694) (xy 101.576422 -259.490301) (xy 101.6 -259.444027)
			(xy 101.630526 -259.402011) (xy 101.667249 -259.365288) (xy 101.709265 -259.334762) (xy 101.755539 -259.311184)
			(xy 101.804932 -259.295136) (xy 101.856227 -259.287011) (xy 101.908161 -259.287011) (xy 101.959456 -259.295136)
			(xy 102.008849 -259.311184) (xy 102.055123 -259.334762) (xy 102.097139 -259.365288) (xy 102.133862 -259.402011)
			(xy 102.164388 -259.444027) (xy 102.187966 -259.490301) (xy 102.204014 -259.539694) (xy 102.212139 -259.590989)
			(xy 102.212648 -259.616956) (xy 102.212139 -259.642923) (xy 102.204014 -259.694218) (xy 102.194849 -259.722425)
			(xy 102.536499 -259.722425) (xy 102.536499 -259.670491) (xy 102.544624 -259.619196) (xy 102.560672 -259.569803)
			(xy 102.58425 -259.523529) (xy 102.614776 -259.481513) (xy 102.651499 -259.44479) (xy 102.693515 -259.414264)
			(xy 102.739789 -259.390686) (xy 102.789182 -259.374638) (xy 102.840477 -259.366513) (xy 102.892411 -259.366513)
			(xy 102.943706 -259.374638) (xy 102.993099 -259.390686) (xy 103.039373 -259.414264) (xy 103.081389 -259.44479)
			(xy 103.118112 -259.481513) (xy 103.148638 -259.523529) (xy 103.172216 -259.569803) (xy 103.175075 -259.578602)
			(xy 108.103416 -259.578602) (xy 108.103416 -259.578348) (xy 108.103832 -259.55382) (xy 108.111103 -259.505305)
			(xy 108.125463 -259.458398) (xy 108.146596 -259.414127) (xy 108.174038 -259.373464) (xy 108.190284 -259.355082)
			(xy 108.200085 -259.343591) (xy 108.213098 -259.316354) (xy 108.217566 -259.286501) (xy 108.213098 -259.256648)
			(xy 108.200086 -259.229411) (xy 108.190284 -259.217922) (xy 108.174027 -259.19955) (xy 108.146583 -259.158888)
			(xy 108.125456 -259.114614) (xy 108.11111 -259.067702) (xy 108.10386 -259.019184) (xy 108.103416 -258.994656)
			(xy 108.103416 -258.994402) (xy 108.103925 -258.968435) (xy 108.11205 -258.91714) (xy 108.128098 -258.867747)
			(xy 108.151676 -258.821473) (xy 108.182202 -258.779457) (xy 108.218925 -258.742734) (xy 108.260941 -258.712208)
			(xy 108.307215 -258.68863) (xy 108.356608 -258.672582) (xy 108.407903 -258.664457) (xy 108.459837 -258.664457)
			(xy 108.511132 -258.672582) (xy 108.560525 -258.68863) (xy 108.606799 -258.712208) (xy 108.648815 -258.742734)
			(xy 108.685538 -258.779457) (xy 108.716064 -258.821473) (xy 108.720083 -258.829361) (xy 113.300003 -258.829361)
			(xy 113.300003 -258.777427) (xy 113.308128 -258.726132) (xy 113.324176 -258.676739) (xy 113.347754 -258.630465)
			(xy 113.37828 -258.588449) (xy 113.415003 -258.551726) (xy 113.457019 -258.5212) (xy 113.503293 -258.497622)
			(xy 113.552686 -258.481574) (xy 113.603981 -258.473449) (xy 113.655915 -258.473449) (xy 113.70721 -258.481574)
			(xy 113.756603 -258.497622) (xy 113.802877 -258.5212) (xy 113.844893 -258.551726) (xy 113.881616 -258.588449)
			(xy 113.912142 -258.630465) (xy 113.93572 -258.676739) (xy 113.951768 -258.726132) (xy 113.959893 -258.777427)
			(xy 113.960402 -258.803394) (xy 113.959893 -258.829361) (xy 113.951768 -258.880656) (xy 113.93572 -258.930049)
			(xy 113.912142 -258.976323) (xy 113.881616 -259.018339) (xy 113.844893 -259.055062) (xy 113.802877 -259.085588)
			(xy 113.756603 -259.109166) (xy 113.70721 -259.125214) (xy 113.655915 -259.133339) (xy 113.603981 -259.133339)
			(xy 113.552686 -259.125214) (xy 113.503293 -259.109166) (xy 113.457019 -259.085588) (xy 113.415003 -259.055062)
			(xy 113.37828 -259.018339) (xy 113.347754 -258.976323) (xy 113.324176 -258.930049) (xy 113.308128 -258.880656)
			(xy 113.300003 -258.829361) (xy 108.720083 -258.829361) (xy 108.739642 -258.867747) (xy 108.75569 -258.91714)
			(xy 108.763815 -258.968435) (xy 108.764324 -258.994402) (xy 108.764324 -258.994656) (xy 108.7639 -259.019184)
			(xy 108.756629 -259.067697) (xy 108.742271 -259.114605) (xy 108.72114 -259.158876) (xy 108.6937 -259.199539)
			(xy 108.677456 -259.217922) (xy 108.667648 -259.229408) (xy 108.65463 -259.256646) (xy 108.650161 -259.286501)
			(xy 108.654631 -259.316357) (xy 108.66765 -259.343594) (xy 108.677456 -259.355082) (xy 108.693705 -259.373461)
			(xy 108.721152 -259.41412) (xy 108.742282 -259.458392) (xy 108.75663 -259.505303) (xy 108.76388 -259.55382)
			(xy 108.764324 -259.578348) (xy 108.764324 -259.578602) (xy 108.763815 -259.604569) (xy 108.7577 -259.643177)
			(xy 110.010449 -259.643177) (xy 110.010449 -259.591243) (xy 110.018574 -259.539948) (xy 110.034622 -259.490555)
			(xy 110.0582 -259.444281) (xy 110.088726 -259.402265) (xy 110.125449 -259.365542) (xy 110.167465 -259.335016)
			(xy 110.213739 -259.311438) (xy 110.263132 -259.29539) (xy 110.314427 -259.287265) (xy 110.366361 -259.287265)
			(xy 110.417656 -259.29539) (xy 110.467049 -259.311438) (xy 110.513323 -259.335016) (xy 110.555339 -259.365542)
			(xy 110.592062 -259.402265) (xy 110.622588 -259.444281) (xy 110.646166 -259.490555) (xy 110.662214 -259.539948)
			(xy 110.670339 -259.591243) (xy 110.670848 -259.61721) (xy 110.670495 -259.635244) (xy 115.095782 -259.635244)
			(xy 115.095782 -259.63499) (xy 115.096232 -259.610463) (xy 115.103496 -259.561951) (xy 115.117848 -259.515044)
			(xy 115.138974 -259.470772) (xy 115.166408 -259.430108) (xy 115.18265 -259.411724) (xy 115.192413 -259.400202)
			(xy 115.205435 -259.372977) (xy 115.209913 -259.343133) (xy 115.205454 -259.313285) (xy 115.192449 -259.286052)
			(xy 115.18265 -259.274564) (xy 115.166424 -259.256166) (xy 115.138973 -259.215512) (xy 115.117839 -259.171245)
			(xy 115.103486 -259.124338) (xy 115.09623 -259.075825) (xy 115.095782 -259.051298) (xy 115.095782 -259.051044)
			(xy 115.096291 -259.025077) (xy 115.104416 -258.973782) (xy 115.120464 -258.924389) (xy 115.144042 -258.878115)
			(xy 115.174568 -258.836099) (xy 115.211291 -258.799376) (xy 115.253307 -258.76885) (xy 115.299581 -258.745272)
			(xy 115.348974 -258.729224) (xy 115.400269 -258.721099) (xy 115.452203 -258.721099) (xy 115.503498 -258.729224)
			(xy 115.552891 -258.745272) (xy 115.599165 -258.76885) (xy 115.641181 -258.799376) (xy 115.677904 -258.836099)
			(xy 115.70843 -258.878115) (xy 115.732008 -258.924389) (xy 115.748056 -258.973782) (xy 115.756181 -259.025077)
			(xy 115.75669 -259.051044) (xy 115.75669 -259.051298) (xy 115.75624 -259.075825) (xy 115.748977 -259.124338)
			(xy 115.734625 -259.171245) (xy 115.7135 -259.215517) (xy 115.686064 -259.256181) (xy 115.669822 -259.274564)
			(xy 115.659975 -259.286019) (xy 115.646967 -259.313269) (xy 115.642507 -259.343133) (xy 115.646986 -259.372994)
			(xy 115.660012 -259.400235) (xy 115.669822 -259.411724) (xy 115.686054 -259.430117) (xy 115.713501 -259.470773)
			(xy 115.734633 -259.515042) (xy 115.748985 -259.561949) (xy 115.756242 -259.610463) (xy 115.75669 -259.63499)
			(xy 115.75669 -259.635244) (xy 115.756181 -259.661211) (xy 115.748056 -259.712506) (xy 115.732008 -259.761899)
			(xy 115.70843 -259.808173) (xy 115.677904 -259.850189) (xy 115.641181 -259.886912) (xy 115.599165 -259.917438)
			(xy 115.552891 -259.941016) (xy 115.503498 -259.957064) (xy 115.452203 -259.965189) (xy 115.400269 -259.965189)
			(xy 115.348974 -259.957064) (xy 115.299581 -259.941016) (xy 115.253307 -259.917438) (xy 115.211291 -259.886912)
			(xy 115.174568 -259.850189) (xy 115.144042 -259.808173) (xy 115.120464 -259.761899) (xy 115.104416 -259.712506)
			(xy 115.096291 -259.661211) (xy 115.095782 -259.635244) (xy 110.670495 -259.635244) (xy 110.670339 -259.643177)
			(xy 110.662214 -259.694472) (xy 110.646166 -259.743865) (xy 110.622588 -259.790139) (xy 110.592062 -259.832155)
			(xy 110.555339 -259.868878) (xy 110.513323 -259.899404) (xy 110.467049 -259.922982) (xy 110.417656 -259.93903)
			(xy 110.366361 -259.947155) (xy 110.314427 -259.947155) (xy 110.263132 -259.93903) (xy 110.213739 -259.922982)
			(xy 110.167465 -259.899404) (xy 110.125449 -259.868878) (xy 110.088726 -259.832155) (xy 110.0582 -259.790139)
			(xy 110.034622 -259.743865) (xy 110.018574 -259.694472) (xy 110.010449 -259.643177) (xy 108.7577 -259.643177)
			(xy 108.75569 -259.655864) (xy 108.739642 -259.705257) (xy 108.716064 -259.751531) (xy 108.685538 -259.793547)
			(xy 108.648815 -259.83027) (xy 108.606799 -259.860796) (xy 108.560525 -259.884374) (xy 108.511132 -259.900422)
			(xy 108.459837 -259.908547) (xy 108.407903 -259.908547) (xy 108.356608 -259.900422) (xy 108.307215 -259.884374)
			(xy 108.260941 -259.860796) (xy 108.218925 -259.83027) (xy 108.182202 -259.793547) (xy 108.151676 -259.751531)
			(xy 108.128098 -259.705257) (xy 108.11205 -259.655864) (xy 108.103925 -259.604569) (xy 108.103416 -259.578602)
			(xy 103.175075 -259.578602) (xy 103.188264 -259.619196) (xy 103.196389 -259.670491) (xy 103.196898 -259.696458)
			(xy 103.196389 -259.722425) (xy 103.188264 -259.77372) (xy 103.172216 -259.823113) (xy 103.148638 -259.869387)
			(xy 103.118112 -259.911403) (xy 103.081389 -259.948126) (xy 103.039373 -259.978652) (xy 102.993099 -260.00223)
			(xy 102.943706 -260.018278) (xy 102.892411 -260.026403) (xy 102.840477 -260.026403) (xy 102.789182 -260.018278)
			(xy 102.739789 -260.00223) (xy 102.693515 -259.978652) (xy 102.651499 -259.948126) (xy 102.614776 -259.911403)
			(xy 102.58425 -259.869387) (xy 102.560672 -259.823113) (xy 102.544624 -259.77372) (xy 102.536499 -259.722425)
			(xy 102.194849 -259.722425) (xy 102.187966 -259.743611) (xy 102.164388 -259.789885) (xy 102.133862 -259.831901)
			(xy 102.097139 -259.868624) (xy 102.055123 -259.89915) (xy 102.008849 -259.922728) (xy 101.959456 -259.938776)
			(xy 101.908161 -259.946901) (xy 101.856227 -259.946901) (xy 101.804932 -259.938776) (xy 101.755539 -259.922728)
			(xy 101.709265 -259.89915) (xy 101.667249 -259.868624) (xy 101.630526 -259.831901) (xy 101.6 -259.789885)
			(xy 101.576422 -259.743611) (xy 101.560374 -259.694218) (xy 101.552249 -259.642923) (xy 101.272339 -259.642923)
			(xy 101.264214 -259.694218) (xy 101.248166 -259.743611) (xy 101.224588 -259.789885) (xy 101.194062 -259.831901)
			(xy 101.157339 -259.868624) (xy 101.115323 -259.89915) (xy 101.069049 -259.922728) (xy 101.019656 -259.938776)
			(xy 100.968361 -259.946901) (xy 100.916427 -259.946901) (xy 100.865132 -259.938776) (xy 100.815739 -259.922728)
			(xy 100.769465 -259.89915) (xy 100.727449 -259.868624) (xy 100.690726 -259.831901) (xy 100.6602 -259.789885)
			(xy 100.636622 -259.743611) (xy 100.620574 -259.694218) (xy 100.612449 -259.642923) (xy 100.332539 -259.642923)
			(xy 100.324414 -259.694218) (xy 100.308366 -259.743611) (xy 100.284788 -259.789885) (xy 100.254262 -259.831901)
			(xy 100.217539 -259.868624) (xy 100.175523 -259.89915) (xy 100.129249 -259.922728) (xy 100.079856 -259.938776)
			(xy 100.028561 -259.946901) (xy 99.976627 -259.946901) (xy 99.925332 -259.938776) (xy 99.875939 -259.922728)
			(xy 99.829665 -259.89915) (xy 99.787649 -259.868624) (xy 99.750926 -259.831901) (xy 99.7204 -259.789885)
			(xy 99.696822 -259.743611) (xy 99.680774 -259.694218) (xy 99.672649 -259.642923) (xy 99.39296 -259.642923)
			(xy 99.39296 -259.643484) (xy 99.384515 -259.695814) (xy 99.367837 -259.746129) (xy 99.343354 -259.793142)
			(xy 99.311691 -259.835653) (xy 99.273657 -259.872574) (xy 99.230225 -259.902961) (xy 99.206558 -259.914898)
			(xy 99.20605 -259.915152) (xy 99.19984 -259.918451) (xy 99.18939 -259.927853) (xy 99.185476 -259.933694)
			(xy 99.181666 -259.939536) (xy 99.177856 -259.953252) (xy 99.177856 -260.082538) (xy 99.178499 -260.091208)
			(xy 99.184886 -260.107364) (xy 99.196347 -260.12042) (xy 99.203764 -260.124956) (xy 99.229418 -260.138164)
			(xy 99.28606 -260.16712) (xy 99.287838 -260.167882) (xy 99.291235 -260.16943) (xy 99.298378 -260.171597)
			(xy 99.302062 -260.1722) (xy 99.321218 -260.155696) (xy 99.363416 -260.127842) (xy 99.409215 -260.106419)
			(xy 99.457641 -260.091881) (xy 99.507667 -260.084538) (xy 99.532948 -260.084062) (xy 99.558894 -260.08455)
			(xy 99.610205 -260.092291) (xy 99.659789 -260.107592) (xy 99.70654 -260.130111) (xy 99.749412 -260.159346)
			(xy 99.787449 -260.194644) (xy 99.8198 -260.235217) (xy 99.845744 -260.280158) (xy 99.864701 -260.328463)
			(xy 99.876246 -260.379053) (xy 99.880124 -260.4308) (xy 99.87818 -260.456739) (xy 100.142803 -260.456739)
			(xy 100.142803 -260.404805) (xy 100.150928 -260.35351) (xy 100.166976 -260.304117) (xy 100.190554 -260.257843)
			(xy 100.22108 -260.215827) (xy 100.257803 -260.179104) (xy 100.299819 -260.148578) (xy 100.346093 -260.125)
			(xy 100.395486 -260.108952) (xy 100.446781 -260.100827) (xy 100.498715 -260.100827) (xy 100.55001 -260.108952)
			(xy 100.599403 -260.125) (xy 100.645677 -260.148578) (xy 100.687693 -260.179104) (xy 100.724416 -260.215827)
			(xy 100.754942 -260.257843) (xy 100.77852 -260.304117) (xy 100.794568 -260.35351) (xy 100.802693 -260.404805)
			(xy 100.803202 -260.430772) (xy 100.802693 -260.456739) (xy 101.082603 -260.456739) (xy 101.082603 -260.404805)
			(xy 101.090728 -260.35351) (xy 101.106776 -260.304117) (xy 101.130354 -260.257843) (xy 101.16088 -260.215827)
			(xy 101.197603 -260.179104) (xy 101.239619 -260.148578) (xy 101.285893 -260.125) (xy 101.335286 -260.108952)
			(xy 101.386581 -260.100827) (xy 101.438515 -260.100827) (xy 101.48981 -260.108952) (xy 101.539203 -260.125)
			(xy 101.585477 -260.148578) (xy 101.627493 -260.179104) (xy 101.664216 -260.215827) (xy 101.694742 -260.257843)
			(xy 101.71832 -260.304117) (xy 101.734368 -260.35351) (xy 101.742493 -260.404805) (xy 101.743002 -260.430772)
			(xy 101.742493 -260.456739) (xy 101.742487 -260.456774) (xy 102.022301 -260.456774) (xy 102.022301 -260.404826)
			(xy 102.030428 -260.353518) (xy 102.046482 -260.304113) (xy 102.070068 -260.257828) (xy 102.100605 -260.215804)
			(xy 102.13734 -260.179074) (xy 102.179369 -260.148543) (xy 102.225658 -260.124964) (xy 102.275065 -260.108917)
			(xy 102.326374 -260.100797) (xy 102.352348 -260.100318) (xy 102.379433 -260.10093) (xy 102.432877 -260.109757)
			(xy 102.484166 -260.127184) (xy 102.531926 -260.152744) (xy 102.574877 -260.185751) (xy 102.611869 -260.225323)
			(xy 102.64191 -260.270398) (xy 102.664197 -260.31977) (xy 102.678132 -260.372115) (xy 102.681278 -260.399022)
			(xy 102.683079 -260.413169) (xy 102.693479 -260.439712) (xy 102.706723 -260.456993) (xy 113.300003 -260.456993)
			(xy 113.300003 -260.405059) (xy 113.308128 -260.353764) (xy 113.324176 -260.304371) (xy 113.347754 -260.258097)
			(xy 113.37828 -260.216081) (xy 113.415003 -260.179358) (xy 113.457019 -260.148832) (xy 113.503293 -260.125254)
			(xy 113.552686 -260.109206) (xy 113.603981 -260.101081) (xy 113.655915 -260.101081) (xy 113.70721 -260.109206)
			(xy 113.756603 -260.125254) (xy 113.802877 -260.148832) (xy 113.844893 -260.179358) (xy 113.881616 -260.216081)
			(xy 113.912142 -260.258097) (xy 113.93572 -260.304371) (xy 113.951768 -260.353764) (xy 113.959893 -260.405059)
			(xy 113.960402 -260.431026) (xy 113.959893 -260.456993) (xy 113.951768 -260.508288) (xy 113.93572 -260.557681)
			(xy 113.912142 -260.603955) (xy 113.881616 -260.645971) (xy 113.844893 -260.682694) (xy 113.802877 -260.71322)
			(xy 113.756603 -260.736798) (xy 113.70721 -260.752846) (xy 113.655915 -260.760971) (xy 113.603981 -260.760971)
			(xy 113.552686 -260.752846) (xy 113.503293 -260.736798) (xy 113.457019 -260.71322) (xy 113.415003 -260.682694)
			(xy 113.37828 -260.645971) (xy 113.347754 -260.603955) (xy 113.324176 -260.557681) (xy 113.308128 -260.508288)
			(xy 113.300003 -260.456993) (xy 102.706723 -260.456993) (xy 102.71082 -260.462338) (xy 102.733745 -260.479281)
			(xy 102.760465 -260.489217) (xy 102.788891 -260.491369) (xy 102.802944 -260.488938) (xy 102.819398 -260.485756)
			(xy 102.852735 -260.48232) (xy 102.869492 -260.48208) (xy 102.895464 -260.482494) (xy 102.94677 -260.490619)
			(xy 102.996172 -260.50667) (xy 103.042456 -260.530252) (xy 103.084481 -260.560783) (xy 103.121211 -260.597513)
			(xy 103.151744 -260.639537) (xy 103.175327 -260.68582) (xy 103.191379 -260.735222) (xy 103.199505 -260.786528)
			(xy 103.199505 -260.838472) (xy 103.191379 -260.889778) (xy 103.175327 -260.93918) (xy 103.151744 -260.985463)
			(xy 103.121211 -261.027487) (xy 103.084481 -261.064217) (xy 103.042456 -261.094748) (xy 102.996172 -261.11833)
			(xy 102.94677 -261.134381) (xy 102.895464 -261.142506) (xy 102.869492 -261.142988) (xy 102.842406 -261.142426)
			(xy 102.788959 -261.133589) (xy 102.73767 -261.116154) (xy 102.68991 -261.090587) (xy 102.64696 -261.057574)
			(xy 102.609969 -261.017997) (xy 102.579929 -260.972917) (xy 102.557643 -260.923542) (xy 102.543708 -260.871192)
			(xy 102.540562 -260.844284) (xy 102.53871 -260.830146) (xy 102.528317 -260.80361) (xy 102.510986 -260.780987)
			(xy 102.488071 -260.764043) (xy 102.461362 -260.754103) (xy 102.432946 -260.751943) (xy 102.418896 -260.754368)
			(xy 102.402444 -260.757559) (xy 102.369105 -260.760989) (xy 102.352348 -260.761226) (xy 102.326374 -260.760803)
			(xy 102.275065 -260.752683) (xy 102.225658 -260.736636) (xy 102.179369 -260.713057) (xy 102.13734 -260.682526)
			(xy 102.100605 -260.645796) (xy 102.070068 -260.603772) (xy 102.046482 -260.557487) (xy 102.030428 -260.508082)
			(xy 102.022301 -260.456774) (xy 101.742487 -260.456774) (xy 101.734368 -260.508034) (xy 101.71832 -260.557427)
			(xy 101.694742 -260.603701) (xy 101.664216 -260.645717) (xy 101.627493 -260.68244) (xy 101.585477 -260.712966)
			(xy 101.539203 -260.736544) (xy 101.48981 -260.752592) (xy 101.438515 -260.760717) (xy 101.386581 -260.760717)
			(xy 101.335286 -260.752592) (xy 101.285893 -260.736544) (xy 101.239619 -260.712966) (xy 101.197603 -260.68244)
			(xy 101.16088 -260.645717) (xy 101.130354 -260.603701) (xy 101.106776 -260.557427) (xy 101.090728 -260.508034)
			(xy 101.082603 -260.456739) (xy 100.802693 -260.456739) (xy 100.794568 -260.508034) (xy 100.77852 -260.557427)
			(xy 100.754942 -260.603701) (xy 100.724416 -260.645717) (xy 100.687693 -260.68244) (xy 100.645677 -260.712966)
			(xy 100.599403 -260.736544) (xy 100.55001 -260.752592) (xy 100.498715 -260.760717) (xy 100.446781 -260.760717)
			(xy 100.395486 -260.752592) (xy 100.346093 -260.736544) (xy 100.299819 -260.712966) (xy 100.257803 -260.68244)
			(xy 100.22108 -260.645717) (xy 100.190554 -260.603701) (xy 100.166976 -260.557427) (xy 100.150928 -260.508034)
			(xy 100.142803 -260.456739) (xy 99.87818 -260.456739) (xy 99.876246 -260.482547) (xy 99.864701 -260.533137)
			(xy 99.845744 -260.581442) (xy 99.8198 -260.626383) (xy 99.787449 -260.666956) (xy 99.749412 -260.702254)
			(xy 99.70654 -260.731489) (xy 99.659789 -260.754008) (xy 99.610205 -260.769309) (xy 99.558894 -260.77705)
			(xy 99.532948 -260.777482) (xy 99.507668 -260.777019) (xy 99.457646 -260.769663) (xy 99.409224 -260.755115)
			(xy 99.363431 -260.733684) (xy 99.321238 -260.705824) (xy 99.302062 -260.689344) (xy 99.298384 -260.689973)
			(xy 99.291243 -260.692136) (xy 99.287838 -260.693662) (xy 99.28606 -260.694424) (xy 99.229418 -260.72338)
			(xy 99.203764 -260.736588) (xy 99.196386 -260.741162) (xy 99.184987 -260.754238) (xy 99.17857 -260.770354)
			(xy 99.177856 -260.779006) (xy 99.177856 -260.90118) (xy 99.178099 -260.908362) (xy 99.182091 -260.922161)
			(xy 99.18573 -260.928358) (xy 99.18954 -260.9342) (xy 99.1997 -260.943598) (xy 99.206558 -260.9469)
			(xy 99.230185 -260.958906) (xy 99.273607 -260.989286) (xy 99.311632 -261.026198) (xy 99.343288 -261.068698)
			(xy 99.367766 -261.115701) (xy 99.384439 -261.166004) (xy 99.392883 -261.218321) (xy 99.39288 -261.270809)
			(xy 99.672649 -261.270809) (xy 99.672649 -261.218875) (xy 99.680774 -261.16758) (xy 99.696822 -261.118187)
			(xy 99.7204 -261.071913) (xy 99.750926 -261.029897) (xy 99.787649 -260.993174) (xy 99.829665 -260.962648)
			(xy 99.875939 -260.93907) (xy 99.925332 -260.923022) (xy 99.976627 -260.914897) (xy 100.028561 -260.914897)
			(xy 100.079856 -260.923022) (xy 100.129249 -260.93907) (xy 100.175523 -260.962648) (xy 100.217539 -260.993174)
			(xy 100.254262 -261.029897) (xy 100.284788 -261.071913) (xy 100.308366 -261.118187) (xy 100.324414 -261.16758)
			(xy 100.332539 -261.218875) (xy 100.333048 -261.244842) (xy 100.332539 -261.270809) (xy 100.612449 -261.270809)
			(xy 100.612449 -261.218875) (xy 100.620574 -261.16758) (xy 100.636622 -261.118187) (xy 100.6602 -261.071913)
			(xy 100.690726 -261.029897) (xy 100.727449 -260.993174) (xy 100.769465 -260.962648) (xy 100.815739 -260.93907)
			(xy 100.865132 -260.923022) (xy 100.916427 -260.914897) (xy 100.968361 -260.914897) (xy 101.019656 -260.923022)
			(xy 101.069049 -260.93907) (xy 101.115323 -260.962648) (xy 101.157339 -260.993174) (xy 101.194062 -261.029897)
			(xy 101.224588 -261.071913) (xy 101.248166 -261.118187) (xy 101.264214 -261.16758) (xy 101.272339 -261.218875)
			(xy 101.272848 -261.244842) (xy 101.272339 -261.270809) (xy 101.552249 -261.270809) (xy 101.552249 -261.218875)
			(xy 101.560374 -261.16758) (xy 101.576422 -261.118187) (xy 101.6 -261.071913) (xy 101.630526 -261.029897)
			(xy 101.667249 -260.993174) (xy 101.709265 -260.962648) (xy 101.755539 -260.93907) (xy 101.804932 -260.923022)
			(xy 101.856227 -260.914897) (xy 101.908161 -260.914897) (xy 101.959456 -260.923022) (xy 102.008849 -260.93907)
			(xy 102.055123 -260.962648) (xy 102.097139 -260.993174) (xy 102.133862 -261.029897) (xy 102.164388 -261.071913)
			(xy 102.187966 -261.118187) (xy 102.204014 -261.16758) (xy 102.212139 -261.218875) (xy 102.212648 -261.244842)
			(xy 102.212139 -261.270809) (xy 102.204014 -261.322104) (xy 102.193271 -261.355169) (xy 104.308125 -261.355169)
			(xy 104.308125 -261.303231) (xy 104.31625 -261.251932) (xy 104.3323 -261.202535) (xy 104.355879 -261.156257)
			(xy 104.386408 -261.114238) (xy 104.423133 -261.077512) (xy 104.465152 -261.046982) (xy 104.51143 -261.023402)
			(xy 104.560826 -261.007352) (xy 104.612125 -260.999226) (xy 104.638094 -260.998716) (xy 104.665392 -260.999268)
			(xy 104.719244 -261.008248) (xy 104.770885 -261.025964) (xy 104.818909 -261.051933) (xy 104.862006 -261.085449)
			(xy 104.880918 -261.105142) (xy 104.890751 -261.115122) (xy 104.914635 -261.129748) (xy 104.941591 -261.137347)
			(xy 104.969597 -261.137347) (xy 104.996553 -261.129748) (xy 105.020437 -261.115122) (xy 105.03027 -261.105142)
			(xy 105.047415 -261.087197) (xy 105.086131 -261.056145) (xy 105.129058 -261.031237) (xy 105.175229 -261.013034)
			(xy 105.223604 -261.001945) (xy 105.273094 -260.998221) (xy 105.322584 -261.001945) (xy 105.370959 -261.013034)
			(xy 105.41713 -261.031237) (xy 105.460057 -261.056145) (xy 105.498773 -261.087197) (xy 105.515918 -261.105142)
			(xy 105.525751 -261.115122) (xy 105.549635 -261.129748) (xy 105.576591 -261.137347) (xy 105.604597 -261.137347)
			(xy 105.631553 -261.129748) (xy 105.655437 -261.115122) (xy 105.66527 -261.105142) (xy 105.682415 -261.087197)
			(xy 105.721131 -261.056145) (xy 105.764058 -261.031237) (xy 105.810229 -261.013034) (xy 105.858604 -261.001945)
			(xy 105.908094 -260.998221) (xy 105.957584 -261.001945) (xy 106.005959 -261.013034) (xy 106.05213 -261.031237)
			(xy 106.095057 -261.056145) (xy 106.133773 -261.087197) (xy 106.150918 -261.105142) (xy 106.160751 -261.115122)
			(xy 106.184635 -261.129748) (xy 106.211591 -261.137347) (xy 106.239597 -261.137347) (xy 106.266553 -261.129748)
			(xy 106.290437 -261.115122) (xy 106.30027 -261.105142) (xy 106.317415 -261.087197) (xy 106.356131 -261.056145)
			(xy 106.399058 -261.031237) (xy 106.445229 -261.013034) (xy 106.493604 -261.001945) (xy 106.543094 -260.998221)
			(xy 106.592584 -261.001945) (xy 106.640959 -261.013034) (xy 106.68713 -261.031237) (xy 106.730057 -261.056145)
			(xy 106.768773 -261.087197) (xy 106.785918 -261.105142) (xy 106.795751 -261.115122) (xy 106.819635 -261.129748)
			(xy 106.846591 -261.137347) (xy 106.874597 -261.137347) (xy 106.901553 -261.129748) (xy 106.925437 -261.115122)
			(xy 106.93527 -261.105142) (xy 106.954176 -261.085444) (xy 106.997278 -261.051935) (xy 107.045303 -261.025971)
			(xy 107.096945 -261.008258) (xy 107.150797 -260.999279) (xy 107.178094 -260.998716) (xy 107.204061 -260.999258)
			(xy 107.255356 -261.007382) (xy 107.304749 -261.02343) (xy 107.351024 -261.047007) (xy 107.39304 -261.077533)
			(xy 107.429763 -261.114256) (xy 107.46029 -261.156271) (xy 107.483868 -261.202545) (xy 107.499917 -261.251938)
			(xy 107.502946 -261.271063) (xy 110.010449 -261.271063) (xy 110.010449 -261.219129) (xy 110.018574 -261.167834)
			(xy 110.034622 -261.118441) (xy 110.0582 -261.072167) (xy 110.088726 -261.030151) (xy 110.125449 -260.993428)
			(xy 110.167465 -260.962902) (xy 110.213739 -260.939324) (xy 110.263132 -260.923276) (xy 110.314427 -260.915151)
			(xy 110.366361 -260.915151) (xy 110.417656 -260.923276) (xy 110.467049 -260.939324) (xy 110.513323 -260.962902)
			(xy 110.555339 -260.993428) (xy 110.592062 -261.030151) (xy 110.622588 -261.072167) (xy 110.646166 -261.118441)
			(xy 110.662214 -261.167834) (xy 110.670339 -261.219129) (xy 110.670848 -261.245096) (xy 110.670339 -261.271063)
			(xy 110.662214 -261.322358) (xy 110.646166 -261.371751) (xy 110.622588 -261.418025) (xy 110.592062 -261.460041)
			(xy 110.555339 -261.496764) (xy 110.513323 -261.52729) (xy 110.467049 -261.550868) (xy 110.417656 -261.566916)
			(xy 110.366361 -261.575041) (xy 110.314427 -261.575041) (xy 110.263132 -261.566916) (xy 110.213739 -261.550868)
			(xy 110.167465 -261.52729) (xy 110.125449 -261.496764) (xy 110.088726 -261.460041) (xy 110.0582 -261.418025)
			(xy 110.034622 -261.371751) (xy 110.018574 -261.322358) (xy 110.010449 -261.271063) (xy 107.502946 -261.271063)
			(xy 107.508041 -261.303233) (xy 107.508041 -261.355167) (xy 107.499917 -261.406462) (xy 107.483868 -261.455855)
			(xy 107.46029 -261.502129) (xy 107.429763 -261.544144) (xy 107.39304 -261.580867) (xy 107.351024 -261.611393)
			(xy 107.304749 -261.63497) (xy 107.255356 -261.651018) (xy 107.204061 -261.659142) (xy 107.178094 -261.659624)
			(xy 107.150795 -261.659099) (xy 107.096941 -261.650116) (xy 107.045298 -261.632394) (xy 106.997275 -261.606418)
			(xy 106.95418 -261.572895) (xy 106.93527 -261.553198) (xy 106.925437 -261.543218) (xy 106.901553 -261.528592)
			(xy 106.874597 -261.520993) (xy 106.846591 -261.520993) (xy 106.819635 -261.528592) (xy 106.795751 -261.543218)
			(xy 106.785918 -261.553198) (xy 106.768773 -261.571143) (xy 106.730057 -261.602195) (xy 106.68713 -261.627103)
			(xy 106.640959 -261.645306) (xy 106.592584 -261.656395) (xy 106.543094 -261.660119) (xy 106.493604 -261.656395)
			(xy 106.445229 -261.645306) (xy 106.399058 -261.627103) (xy 106.356131 -261.602195) (xy 106.317415 -261.571143)
			(xy 106.30027 -261.553198) (xy 106.290437 -261.543218) (xy 106.266553 -261.528592) (xy 106.239597 -261.520993)
			(xy 106.211591 -261.520993) (xy 106.184635 -261.528592) (xy 106.160751 -261.543218) (xy 106.150918 -261.553198)
			(xy 106.133773 -261.571143) (xy 106.095057 -261.602195) (xy 106.05213 -261.627103) (xy 106.005959 -261.645306)
			(xy 105.957584 -261.656395) (xy 105.908094 -261.660119) (xy 105.858604 -261.656395) (xy 105.810229 -261.645306)
			(xy 105.764058 -261.627103) (xy 105.721131 -261.602195) (xy 105.682415 -261.571143) (xy 105.66527 -261.553198)
			(xy 105.655437 -261.543218) (xy 105.631553 -261.528592) (xy 105.604597 -261.520993) (xy 105.576591 -261.520993)
			(xy 105.549635 -261.528592) (xy 105.525751 -261.543218) (xy 105.515918 -261.553198) (xy 105.498773 -261.571143)
			(xy 105.460057 -261.602195) (xy 105.41713 -261.627103) (xy 105.370959 -261.645306) (xy 105.322584 -261.656395)
			(xy 105.273094 -261.660119) (xy 105.223604 -261.656395) (xy 105.175229 -261.645306) (xy 105.129058 -261.627103)
			(xy 105.086131 -261.602195) (xy 105.047415 -261.571143) (xy 105.03027 -261.553198) (xy 105.020437 -261.543218)
			(xy 104.996553 -261.528592) (xy 104.969597 -261.520993) (xy 104.941591 -261.520993) (xy 104.914635 -261.528592)
			(xy 104.890751 -261.543218) (xy 104.880918 -261.553198) (xy 104.862007 -261.572891) (xy 104.818908 -261.606403)
			(xy 104.770884 -261.63237) (xy 104.719243 -261.650084) (xy 104.665391 -261.659062) (xy 104.638094 -261.659624)
			(xy 104.612125 -261.659174) (xy 104.560826 -261.651048) (xy 104.51143 -261.634998) (xy 104.465152 -261.611418)
			(xy 104.423133 -261.580888) (xy 104.386408 -261.544162) (xy 104.355879 -261.502143) (xy 104.3323 -261.455865)
			(xy 104.31625 -261.406468) (xy 104.308125 -261.355169) (xy 102.193271 -261.355169) (xy 102.187966 -261.371497)
			(xy 102.164388 -261.417771) (xy 102.133862 -261.459787) (xy 102.097139 -261.49651) (xy 102.055123 -261.527036)
			(xy 102.008849 -261.550614) (xy 101.959456 -261.566662) (xy 101.908161 -261.574787) (xy 101.856227 -261.574787)
			(xy 101.804932 -261.566662) (xy 101.755539 -261.550614) (xy 101.709265 -261.527036) (xy 101.667249 -261.49651)
			(xy 101.630526 -261.459787) (xy 101.6 -261.417771) (xy 101.576422 -261.371497) (xy 101.560374 -261.322104)
			(xy 101.552249 -261.270809) (xy 101.272339 -261.270809) (xy 101.264214 -261.322104) (xy 101.248166 -261.371497)
			(xy 101.224588 -261.417771) (xy 101.194062 -261.459787) (xy 101.157339 -261.49651) (xy 101.115323 -261.527036)
			(xy 101.069049 -261.550614) (xy 101.019656 -261.566662) (xy 100.968361 -261.574787) (xy 100.916427 -261.574787)
			(xy 100.865132 -261.566662) (xy 100.815739 -261.550614) (xy 100.769465 -261.527036) (xy 100.727449 -261.49651)
			(xy 100.690726 -261.459787) (xy 100.6602 -261.417771) (xy 100.636622 -261.371497) (xy 100.620574 -261.322104)
			(xy 100.612449 -261.270809) (xy 100.332539 -261.270809) (xy 100.324414 -261.322104) (xy 100.308366 -261.371497)
			(xy 100.284788 -261.417771) (xy 100.254262 -261.459787) (xy 100.217539 -261.49651) (xy 100.175523 -261.527036)
			(xy 100.129249 -261.550614) (xy 100.079856 -261.566662) (xy 100.028561 -261.574787) (xy 99.976627 -261.574787)
			(xy 99.925332 -261.566662) (xy 99.875939 -261.550614) (xy 99.829665 -261.527036) (xy 99.787649 -261.49651)
			(xy 99.750926 -261.459787) (xy 99.7204 -261.417771) (xy 99.696822 -261.371497) (xy 99.680774 -261.322104)
			(xy 99.672649 -261.270809) (xy 99.39288 -261.270809) (xy 99.39288 -261.271315) (xy 99.384431 -261.323632)
			(xy 99.367751 -261.373933) (xy 99.343269 -261.420933) (xy 99.311608 -261.46343) (xy 99.273579 -261.500338)
			(xy 99.230153 -261.530713) (xy 99.206558 -261.542784) (xy 99.20605 -261.543038) (xy 99.199839 -261.546336)
			(xy 99.189387 -261.555737) (xy 99.185476 -261.56158) (xy 99.181666 -261.567422) (xy 99.177856 -261.581138)
			(xy 99.177856 -261.710424) (xy 99.178496 -261.719095) (xy 99.184881 -261.735255) (xy 99.196341 -261.748315)
			(xy 99.203764 -261.752842) (xy 99.229418 -261.76605) (xy 99.28606 -261.795006) (xy 99.287838 -261.795768)
			(xy 99.291236 -261.797313) (xy 99.298379 -261.799476) (xy 99.302062 -261.800086) (xy 99.321218 -261.783583)
			(xy 99.363417 -261.75573) (xy 99.409215 -261.734308) (xy 99.457642 -261.719771) (xy 99.507667 -261.712428)
			(xy 99.532948 -261.711948) (xy 99.558895 -261.712436) (xy 99.610208 -261.720177) (xy 99.659794 -261.735479)
			(xy 99.706547 -261.757999) (xy 99.749421 -261.787236) (xy 99.787459 -261.822535) (xy 99.819812 -261.863109)
			(xy 99.845757 -261.908051) (xy 99.864714 -261.956359) (xy 99.87626 -262.006951) (xy 99.880138 -262.0587)
			(xy 99.878195 -262.084625) (xy 100.142803 -262.084625) (xy 100.142803 -262.032691) (xy 100.150928 -261.981396)
			(xy 100.166976 -261.932003) (xy 100.190554 -261.885729) (xy 100.22108 -261.843713) (xy 100.257803 -261.80699)
			(xy 100.299819 -261.776464) (xy 100.346093 -261.752886) (xy 100.395486 -261.736838) (xy 100.446781 -261.728713)
			(xy 100.498715 -261.728713) (xy 100.55001 -261.736838) (xy 100.599403 -261.752886) (xy 100.645677 -261.776464)
			(xy 100.687693 -261.80699) (xy 100.724416 -261.843713) (xy 100.754942 -261.885729) (xy 100.77852 -261.932003)
			(xy 100.794568 -261.981396) (xy 100.802693 -262.032691) (xy 100.803202 -262.058658) (xy 100.802693 -262.084625)
			(xy 101.082603 -262.084625) (xy 101.082603 -262.032691) (xy 101.090728 -261.981396) (xy 101.106776 -261.932003)
			(xy 101.130354 -261.885729) (xy 101.16088 -261.843713) (xy 101.197603 -261.80699) (xy 101.239619 -261.776464)
			(xy 101.285893 -261.752886) (xy 101.335286 -261.736838) (xy 101.386581 -261.728713) (xy 101.438515 -261.728713)
			(xy 101.48981 -261.736838) (xy 101.539203 -261.752886) (xy 101.585477 -261.776464) (xy 101.627493 -261.80699)
			(xy 101.664216 -261.843713) (xy 101.694742 -261.885729) (xy 101.71832 -261.932003) (xy 101.734368 -261.981396)
			(xy 101.742493 -262.032691) (xy 101.743002 -262.058658) (xy 101.742493 -262.084625) (xy 102.022403 -262.084625)
			(xy 102.022403 -262.032691) (xy 102.030528 -261.981396) (xy 102.046576 -261.932003) (xy 102.070154 -261.885729)
			(xy 102.10068 -261.843713) (xy 102.137403 -261.80699) (xy 102.179419 -261.776464) (xy 102.225693 -261.752886)
			(xy 102.275086 -261.736838) (xy 102.326381 -261.728713) (xy 102.378315 -261.728713) (xy 102.42961 -261.736838)
			(xy 102.479003 -261.752886) (xy 102.525277 -261.776464) (xy 102.567293 -261.80699) (xy 102.604016 -261.843713)
			(xy 102.634542 -261.885729) (xy 102.65812 -261.932003) (xy 102.674168 -261.981396) (xy 102.682293 -262.032691)
			(xy 102.682802 -262.058658) (xy 102.682293 -262.084625) (xy 102.674168 -262.13592) (xy 102.65812 -262.185313)
			(xy 102.634542 -262.231587) (xy 102.604016 -262.273603) (xy 102.567293 -262.310326) (xy 102.525277 -262.340852)
			(xy 102.479003 -262.36443) (xy 102.42961 -262.380478) (xy 102.378315 -262.388603) (xy 102.326381 -262.388603)
			(xy 102.275086 -262.380478) (xy 102.225693 -262.36443) (xy 102.179419 -262.340852) (xy 102.137403 -262.310326)
			(xy 102.10068 -262.273603) (xy 102.070154 -262.231587) (xy 102.046576 -262.185313) (xy 102.030528 -262.13592)
			(xy 102.022403 -262.084625) (xy 101.742493 -262.084625) (xy 101.734368 -262.13592) (xy 101.71832 -262.185313)
			(xy 101.694742 -262.231587) (xy 101.664216 -262.273603) (xy 101.627493 -262.310326) (xy 101.585477 -262.340852)
			(xy 101.539203 -262.36443) (xy 101.48981 -262.380478) (xy 101.438515 -262.388603) (xy 101.386581 -262.388603)
			(xy 101.335286 -262.380478) (xy 101.285893 -262.36443) (xy 101.239619 -262.340852) (xy 101.197603 -262.310326)
			(xy 101.16088 -262.273603) (xy 101.130354 -262.231587) (xy 101.106776 -262.185313) (xy 101.090728 -262.13592)
			(xy 101.082603 -262.084625) (xy 100.802693 -262.084625) (xy 100.794568 -262.13592) (xy 100.77852 -262.185313)
			(xy 100.754942 -262.231587) (xy 100.724416 -262.273603) (xy 100.687693 -262.310326) (xy 100.645677 -262.340852)
			(xy 100.599403 -262.36443) (xy 100.55001 -262.380478) (xy 100.498715 -262.388603) (xy 100.446781 -262.388603)
			(xy 100.395486 -262.380478) (xy 100.346093 -262.36443) (xy 100.299819 -262.340852) (xy 100.257803 -262.310326)
			(xy 100.22108 -262.273603) (xy 100.190554 -262.231587) (xy 100.166976 -262.185313) (xy 100.150928 -262.13592)
			(xy 100.142803 -262.084625) (xy 99.878195 -262.084625) (xy 99.87626 -262.110449) (xy 99.864714 -262.161041)
			(xy 99.845757 -262.209349) (xy 99.819812 -262.254291) (xy 99.787459 -262.294865) (xy 99.749421 -262.330164)
			(xy 99.706547 -262.359401) (xy 99.659794 -262.381921) (xy 99.610208 -262.397223) (xy 99.558895 -262.404964)
			(xy 99.532948 -262.405368) (xy 99.507668 -262.404905) (xy 99.457646 -262.397549) (xy 99.409224 -262.383)
			(xy 99.363432 -262.361568) (xy 99.32124 -262.333708) (xy 99.302062 -262.31723) (xy 99.298384 -262.317859)
			(xy 99.291243 -262.320021) (xy 99.287838 -262.321548) (xy 99.28606 -262.32231) (xy 99.229418 -262.351266)
			(xy 99.203764 -262.364474) (xy 99.196385 -262.369047) (xy 99.184982 -262.382122) (xy 99.17856 -262.398239)
			(xy 99.177856 -262.406892) (xy 99.177856 -262.528812) (xy 99.178103 -262.535993) (xy 99.182103 -262.549787)
			(xy 99.18573 -262.55599) (xy 99.18954 -262.561832) (xy 99.1997 -262.57123) (xy 99.206558 -262.574532)
			(xy 99.230194 -262.586536) (xy 99.273635 -262.616913) (xy 99.311681 -262.653824) (xy 99.343358 -262.696325)
			(xy 99.367859 -262.743332) (xy 99.384555 -262.793642) (xy 99.393022 -262.84597) (xy 99.393502 -262.872474)
			(xy 99.393021 -262.898441) (xy 99.672649 -262.898441) (xy 99.672649 -262.846507) (xy 99.680774 -262.795212)
			(xy 99.696822 -262.745819) (xy 99.7204 -262.699545) (xy 99.750926 -262.657529) (xy 99.787649 -262.620806)
			(xy 99.829665 -262.59028) (xy 99.875939 -262.566702) (xy 99.925332 -262.550654) (xy 99.976627 -262.542529)
			(xy 100.028561 -262.542529) (xy 100.079856 -262.550654) (xy 100.129249 -262.566702) (xy 100.175523 -262.59028)
			(xy 100.217539 -262.620806) (xy 100.254262 -262.657529) (xy 100.284788 -262.699545) (xy 100.308366 -262.745819)
			(xy 100.324414 -262.795212) (xy 100.332539 -262.846507) (xy 100.333048 -262.872474) (xy 100.332539 -262.898441)
			(xy 100.612449 -262.898441) (xy 100.612449 -262.846507) (xy 100.620574 -262.795212) (xy 100.636622 -262.745819)
			(xy 100.6602 -262.699545) (xy 100.690726 -262.657529) (xy 100.727449 -262.620806) (xy 100.769465 -262.59028)
			(xy 100.815739 -262.566702) (xy 100.865132 -262.550654) (xy 100.916427 -262.542529) (xy 100.968361 -262.542529)
			(xy 101.019656 -262.550654) (xy 101.069049 -262.566702) (xy 101.115323 -262.59028) (xy 101.157339 -262.620806)
			(xy 101.194062 -262.657529) (xy 101.224588 -262.699545) (xy 101.227283 -262.704834) (xy 103.384096 -262.704834)
			(xy 103.384096 -262.70458) (xy 103.384537 -262.680053) (xy 103.391802 -262.63154) (xy 103.406157 -262.584632)
			(xy 103.427284 -262.540361) (xy 103.454721 -262.499697) (xy 103.470964 -262.481314) (xy 103.480735 -262.469799)
			(xy 103.493754 -262.442572) (xy 103.49823 -262.412725) (xy 103.493769 -262.382877) (xy 103.480763 -262.355642)
			(xy 103.470964 -262.344154) (xy 103.454735 -262.325758) (xy 103.427285 -262.285104) (xy 103.406151 -262.240836)
			(xy 103.391798 -262.193929) (xy 103.384543 -262.145415) (xy 103.384096 -262.120888) (xy 103.384096 -262.120634)
			(xy 103.384605 -262.094667) (xy 103.39273 -262.043372) (xy 103.408778 -261.993979) (xy 103.432356 -261.947705)
			(xy 103.462882 -261.905689) (xy 103.499605 -261.868966) (xy 103.541621 -261.83844) (xy 103.587895 -261.814862)
			(xy 103.637288 -261.798814) (xy 103.688583 -261.790689) (xy 103.740517 -261.790689) (xy 103.791812 -261.798814)
			(xy 103.841205 -261.814862) (xy 103.887479 -261.83844) (xy 103.929495 -261.868966) (xy 103.966218 -261.905689)
			(xy 103.996744 -261.947705) (xy 104.020322 -261.993979) (xy 104.03637 -262.043372) (xy 104.042945 -262.084879)
			(xy 113.300003 -262.084879) (xy 113.300003 -262.032945) (xy 113.308128 -261.98165) (xy 113.324176 -261.932257)
			(xy 113.347754 -261.885983) (xy 113.37828 -261.843967) (xy 113.415003 -261.807244) (xy 113.457019 -261.776718)
			(xy 113.503293 -261.75314) (xy 113.552686 -261.737092) (xy 113.603981 -261.728967) (xy 113.655915 -261.728967)
			(xy 113.70721 -261.737092) (xy 113.756603 -261.75314) (xy 113.802877 -261.776718) (xy 113.844893 -261.807244)
			(xy 113.881616 -261.843967) (xy 113.912142 -261.885983) (xy 113.93572 -261.932257) (xy 113.951768 -261.98165)
			(xy 113.959893 -262.032945) (xy 113.960402 -262.058912) (xy 113.959893 -262.084879) (xy 113.951768 -262.136174)
			(xy 113.93572 -262.185567) (xy 113.912142 -262.231841) (xy 113.881616 -262.273857) (xy 113.844893 -262.31058)
			(xy 113.802877 -262.341106) (xy 113.756603 -262.364684) (xy 113.70721 -262.380732) (xy 113.655915 -262.388857)
			(xy 113.603981 -262.388857) (xy 113.552686 -262.380732) (xy 113.503293 -262.364684) (xy 113.457019 -262.341106)
			(xy 113.415003 -262.31058) (xy 113.37828 -262.273857) (xy 113.347754 -262.231841) (xy 113.324176 -262.185567)
			(xy 113.308128 -262.136174) (xy 113.300003 -262.084879) (xy 104.042945 -262.084879) (xy 104.044495 -262.094667)
			(xy 104.045004 -262.120634) (xy 104.045004 -262.120888) (xy 104.044544 -262.145414) (xy 104.037283 -262.193927)
			(xy 104.022933 -262.240834) (xy 104.00181 -262.285106) (xy 103.974377 -262.32577) (xy 103.958136 -262.344154)
			(xy 103.948298 -262.355617) (xy 103.935287 -262.382863) (xy 103.930824 -262.412725) (xy 103.935302 -262.442585)
			(xy 103.948327 -262.469825) (xy 103.958136 -262.481314) (xy 103.974397 -262.499683) (xy 104.001843 -262.540344)
			(xy 104.022971 -262.584619) (xy 104.037316 -262.631532) (xy 104.044562 -262.680051) (xy 104.045004 -262.70458)
			(xy 104.045004 -262.704834) (xy 104.044495 -262.730801) (xy 104.03637 -262.782096) (xy 104.020322 -262.831489)
			(xy 103.996744 -262.877763) (xy 103.981536 -262.898695) (xy 110.010703 -262.898695) (xy 110.010703 -262.846761)
			(xy 110.018828 -262.795466) (xy 110.034876 -262.746073) (xy 110.058454 -262.699799) (xy 110.08898 -262.657783)
			(xy 110.125703 -262.62106) (xy 110.167719 -262.590534) (xy 110.213993 -262.566956) (xy 110.263386 -262.550908)
			(xy 110.314681 -262.542783) (xy 110.366615 -262.542783) (xy 110.41791 -262.550908) (xy 110.467303 -262.566956)
			(xy 110.513577 -262.590534) (xy 110.555593 -262.62106) (xy 110.592316 -262.657783) (xy 110.622842 -262.699799)
			(xy 110.64642 -262.746073) (xy 110.662468 -262.795466) (xy 110.670593 -262.846761) (xy 110.671102 -262.872728)
			(xy 110.670593 -262.898695) (xy 110.662468 -262.94999) (xy 110.64642 -262.999383) (xy 110.622842 -263.045657)
			(xy 110.592316 -263.087673) (xy 110.555593 -263.124396) (xy 110.513577 -263.154922) (xy 110.467303 -263.1785)
			(xy 110.41791 -263.194548) (xy 110.366615 -263.202673) (xy 110.314681 -263.202673) (xy 110.263386 -263.194548)
			(xy 110.213993 -263.1785) (xy 110.167719 -263.154922) (xy 110.125703 -263.124396) (xy 110.08898 -263.087673)
			(xy 110.058454 -263.045657) (xy 110.034876 -262.999383) (xy 110.018828 -262.94999) (xy 110.010703 -262.898695)
			(xy 103.981536 -262.898695) (xy 103.966218 -262.919779) (xy 103.929495 -262.956502) (xy 103.887479 -262.987028)
			(xy 103.841205 -263.010606) (xy 103.791812 -263.026654) (xy 103.740517 -263.034779) (xy 103.688583 -263.034779)
			(xy 103.637288 -263.026654) (xy 103.587895 -263.010606) (xy 103.541621 -262.987028) (xy 103.499605 -262.956502)
			(xy 103.462882 -262.919779) (xy 103.432356 -262.877763) (xy 103.408778 -262.831489) (xy 103.39273 -262.782096)
			(xy 103.384605 -262.730801) (xy 103.384096 -262.704834) (xy 101.227283 -262.704834) (xy 101.248166 -262.745819)
			(xy 101.264214 -262.795212) (xy 101.272339 -262.846507) (xy 101.272848 -262.872474) (xy 101.272339 -262.898441)
			(xy 101.264214 -262.949736) (xy 101.248166 -262.999129) (xy 101.224588 -263.045403) (xy 101.194062 -263.087419)
			(xy 101.157339 -263.124142) (xy 101.115323 -263.154668) (xy 101.069049 -263.178246) (xy 101.019656 -263.194294)
			(xy 100.968361 -263.202419) (xy 100.916427 -263.202419) (xy 100.865132 -263.194294) (xy 100.815739 -263.178246)
			(xy 100.769465 -263.154668) (xy 100.727449 -263.124142) (xy 100.690726 -263.087419) (xy 100.6602 -263.045403)
			(xy 100.636622 -262.999129) (xy 100.620574 -262.949736) (xy 100.612449 -262.898441) (xy 100.332539 -262.898441)
			(xy 100.324414 -262.949736) (xy 100.308366 -262.999129) (xy 100.284788 -263.045403) (xy 100.254262 -263.087419)
			(xy 100.217539 -263.124142) (xy 100.175523 -263.154668) (xy 100.129249 -263.178246) (xy 100.079856 -263.194294)
			(xy 100.028561 -263.202419) (xy 99.976627 -263.202419) (xy 99.925332 -263.194294) (xy 99.875939 -263.178246)
			(xy 99.829665 -263.154668) (xy 99.787649 -263.124142) (xy 99.750926 -263.087419) (xy 99.7204 -263.045403)
			(xy 99.696822 -262.999129) (xy 99.680774 -262.949736) (xy 99.672649 -262.898441) (xy 99.393021 -262.898441)
			(xy 99.393021 -262.898464) (xy 99.384893 -262.949806) (xy 99.368833 -262.999243) (xy 99.345236 -263.04556)
			(xy 99.314684 -263.087614) (xy 99.27793 -263.124371) (xy 99.235877 -263.154926) (xy 99.189562 -263.178525)
			(xy 99.140125 -263.194588) (xy 99.088784 -263.202719) (xy 99.062794 -263.203182) (xy 99.035882 -263.202617)
			(xy 98.982781 -263.193816) (xy 98.95713 -263.185656) (xy 98.956622 -263.185656) (xy 98.947598 -263.183104)
			(xy 98.928881 -263.183982) (xy 98.91173 -263.191525) (xy 98.904806 -263.197848) (xy 98.80981 -263.292844)
			(xy 98.80441 -263.298729) (xy 98.797172 -263.312956) (xy 98.795586 -263.320784) (xy 98.794824 -263.330436)
			(xy 98.796348 -263.381744) (xy 98.79711 -263.405874) (xy 98.797529 -263.410475) (xy 98.799825 -263.419424)
			(xy 98.801682 -263.423654) (xy 98.806254 -263.433306) (xy 98.813874 -263.440164) (xy 98.834192 -263.459156)
			(xy 98.8688 -263.50269) (xy 98.895644 -263.551396) (xy 98.913969 -263.603905) (xy 98.923258 -263.658737)
			(xy 98.923856 -263.686544) (xy 98.923343 -263.712511) (xy 99.203003 -263.712511) (xy 99.203003 -263.660577)
			(xy 99.211128 -263.609282) (xy 99.227176 -263.559889) (xy 99.250754 -263.513615) (xy 99.28128 -263.471599)
			(xy 99.318003 -263.434876) (xy 99.360019 -263.40435) (xy 99.406293 -263.380772) (xy 99.455686 -263.364724)
			(xy 99.506981 -263.356599) (xy 99.558915 -263.356599) (xy 99.61021 -263.364724) (xy 99.659603 -263.380772)
			(xy 99.705877 -263.40435) (xy 99.747893 -263.434876) (xy 99.784616 -263.471599) (xy 99.815142 -263.513615)
			(xy 99.83872 -263.559889) (xy 99.854768 -263.609282) (xy 99.862893 -263.660577) (xy 99.863402 -263.686544)
			(xy 99.862893 -263.712511) (xy 100.142803 -263.712511) (xy 100.142803 -263.660577) (xy 100.150928 -263.609282)
			(xy 100.166976 -263.559889) (xy 100.190554 -263.513615) (xy 100.22108 -263.471599) (xy 100.257803 -263.434876)
			(xy 100.299819 -263.40435) (xy 100.346093 -263.380772) (xy 100.395486 -263.364724) (xy 100.446781 -263.356599)
			(xy 100.498715 -263.356599) (xy 100.55001 -263.364724) (xy 100.599403 -263.380772) (xy 100.645677 -263.40435)
			(xy 100.687693 -263.434876) (xy 100.724416 -263.471599) (xy 100.754942 -263.513615) (xy 100.77852 -263.559889)
			(xy 100.794568 -263.609282) (xy 100.802693 -263.660577) (xy 100.803202 -263.686544) (xy 100.802693 -263.712511)
			(xy 101.082349 -263.712511) (xy 101.082349 -263.660577) (xy 101.090474 -263.609282) (xy 101.106522 -263.559889)
			(xy 101.1301 -263.513615) (xy 101.160626 -263.471599) (xy 101.197349 -263.434876) (xy 101.239365 -263.40435)
			(xy 101.285639 -263.380772) (xy 101.335032 -263.364724) (xy 101.386327 -263.356599) (xy 101.438261 -263.356599)
			(xy 101.489556 -263.364724) (xy 101.538949 -263.380772) (xy 101.585223 -263.40435) (xy 101.627239 -263.434876)
			(xy 101.663962 -263.471599) (xy 101.694488 -263.513615) (xy 101.718066 -263.559889) (xy 101.734114 -263.609282)
			(xy 101.742239 -263.660577) (xy 101.742748 -263.686544) (xy 101.742239 -263.712511) (xy 102.022403 -263.712511)
			(xy 102.022403 -263.660577) (xy 102.030528 -263.609282) (xy 102.046576 -263.559889) (xy 102.070154 -263.513615)
			(xy 102.10068 -263.471599) (xy 102.137403 -263.434876) (xy 102.179419 -263.40435) (xy 102.225693 -263.380772)
			(xy 102.275086 -263.364724) (xy 102.326381 -263.356599) (xy 102.378315 -263.356599) (xy 102.42961 -263.364724)
			(xy 102.479003 -263.380772) (xy 102.525277 -263.40435) (xy 102.567293 -263.434876) (xy 102.604016 -263.471599)
			(xy 102.634542 -263.513615) (xy 102.65812 -263.559889) (xy 102.674168 -263.609282) (xy 102.682293 -263.660577)
			(xy 102.682802 -263.686544) (xy 102.682293 -263.712511) (xy 113.299495 -263.712511) (xy 113.299495 -263.660577)
			(xy 113.30762 -263.609282) (xy 113.323668 -263.559889) (xy 113.347246 -263.513615) (xy 113.377772 -263.471599)
			(xy 113.414495 -263.434876) (xy 113.456511 -263.40435) (xy 113.502785 -263.380772) (xy 113.552178 -263.364724)
			(xy 113.603473 -263.356599) (xy 113.655407 -263.356599) (xy 113.706702 -263.364724) (xy 113.756095 -263.380772)
			(xy 113.802369 -263.40435) (xy 113.844385 -263.434876) (xy 113.881108 -263.471599) (xy 113.911634 -263.513615)
			(xy 113.935212 -263.559889) (xy 113.95126 -263.609282) (xy 113.959385 -263.660577) (xy 113.959894 -263.686544)
			(xy 113.959385 -263.712511) (xy 113.95126 -263.763806) (xy 113.935212 -263.813199) (xy 113.911634 -263.859473)
			(xy 113.881108 -263.901489) (xy 113.844385 -263.938212) (xy 113.802369 -263.968738) (xy 113.756095 -263.992316)
			(xy 113.706702 -264.008364) (xy 113.655407 -264.016489) (xy 113.603473 -264.016489) (xy 113.552178 -264.008364)
			(xy 113.502785 -263.992316) (xy 113.456511 -263.968738) (xy 113.414495 -263.938212) (xy 113.377772 -263.901489)
			(xy 113.347246 -263.859473) (xy 113.323668 -263.813199) (xy 113.30762 -263.763806) (xy 113.299495 -263.712511)
			(xy 102.682293 -263.712511) (xy 102.674168 -263.763806) (xy 102.65812 -263.813199) (xy 102.634542 -263.859473)
			(xy 102.604016 -263.901489) (xy 102.567293 -263.938212) (xy 102.525277 -263.968738) (xy 102.479003 -263.992316)
			(xy 102.42961 -264.008364) (xy 102.378315 -264.016489) (xy 102.326381 -264.016489) (xy 102.275086 -264.008364)
			(xy 102.225693 -263.992316) (xy 102.179419 -263.968738) (xy 102.137403 -263.938212) (xy 102.10068 -263.901489)
			(xy 102.070154 -263.859473) (xy 102.046576 -263.813199) (xy 102.030528 -263.763806) (xy 102.022403 -263.712511)
			(xy 101.742239 -263.712511) (xy 101.734114 -263.763806) (xy 101.718066 -263.813199) (xy 101.694488 -263.859473)
			(xy 101.663962 -263.901489) (xy 101.627239 -263.938212) (xy 101.585223 -263.968738) (xy 101.538949 -263.992316)
			(xy 101.489556 -264.008364) (xy 101.438261 -264.016489) (xy 101.386327 -264.016489) (xy 101.335032 -264.008364)
			(xy 101.285639 -263.992316) (xy 101.239365 -263.968738) (xy 101.197349 -263.938212) (xy 101.160626 -263.901489)
			(xy 101.1301 -263.859473) (xy 101.106522 -263.813199) (xy 101.090474 -263.763806) (xy 101.082349 -263.712511)
			(xy 100.802693 -263.712511) (xy 100.794568 -263.763806) (xy 100.77852 -263.813199) (xy 100.754942 -263.859473)
			(xy 100.724416 -263.901489) (xy 100.687693 -263.938212) (xy 100.645677 -263.968738) (xy 100.599403 -263.992316)
			(xy 100.55001 -264.008364) (xy 100.498715 -264.016489) (xy 100.446781 -264.016489) (xy 100.395486 -264.008364)
			(xy 100.346093 -263.992316) (xy 100.299819 -263.968738) (xy 100.257803 -263.938212) (xy 100.22108 -263.901489)
			(xy 100.190554 -263.859473) (xy 100.166976 -263.813199) (xy 100.150928 -263.763806) (xy 100.142803 -263.712511)
			(xy 99.862893 -263.712511) (xy 99.854768 -263.763806) (xy 99.83872 -263.813199) (xy 99.815142 -263.859473)
			(xy 99.784616 -263.901489) (xy 99.747893 -263.938212) (xy 99.705877 -263.968738) (xy 99.659603 -263.992316)
			(xy 99.61021 -264.008364) (xy 99.558915 -264.016489) (xy 99.506981 -264.016489) (xy 99.455686 -264.008364)
			(xy 99.406293 -263.992316) (xy 99.360019 -263.968738) (xy 99.318003 -263.938212) (xy 99.28128 -263.901489)
			(xy 99.250754 -263.859473) (xy 99.227176 -263.813199) (xy 99.211128 -263.763806) (xy 99.203003 -263.712511)
			(xy 98.923343 -263.712511) (xy 98.923343 -263.71253) (xy 98.915207 -263.763862) (xy 98.899143 -263.81329)
			(xy 98.875546 -263.859597) (xy 98.844996 -263.901643) (xy 98.808246 -263.938393) (xy 98.7662 -263.968944)
			(xy 98.719894 -263.992542) (xy 98.670466 -264.008607) (xy 98.619134 -264.016743) (xy 98.593148 -264.017252)
			(xy 98.565338 -264.016686) (xy 98.5105 -264.007397) (xy 98.457987 -263.989071) (xy 98.409275 -263.962224)
			(xy 98.365737 -263.927613) (xy 98.346768 -263.90727) (xy 98.33991 -263.89965) (xy 98.330258 -263.895078)
			(xy 98.326023 -263.893233) (xy 98.317078 -263.89093) (xy 98.312478 -263.890506) (xy 98.288348 -263.889744)
			(xy 98.23704 -263.88822) (xy 98.227388 -263.888982) (xy 98.219531 -263.890484) (xy 98.205284 -263.897736)
			(xy 98.199448 -263.903206) (xy 98.103182 -263.999472) (xy 98.096781 -264.006455) (xy 98.089225 -264.023813)
			(xy 98.088499 -264.04273) (xy 98.091244 -264.051796) (xy 98.120962 -264.138156) (xy 98.123525 -264.144859)
			(xy 98.131773 -264.156596) (xy 98.137218 -264.16127) (xy 98.142806 -264.165842) (xy 98.155506 -264.170922)
			(xy 98.162872 -264.171938) (xy 98.163126 -264.171938) (xy 98.189516 -264.175708) (xy 98.240705 -264.190581)
			(xy 98.288849 -264.213466) (xy 98.332703 -264.24377) (xy 98.371134 -264.28071) (xy 98.403149 -264.323332)
			(xy 98.427919 -264.370533) (xy 98.444805 -264.421094) (xy 98.453369 -264.473707) (xy 98.453956 -264.50036)
			(xy 98.453449 -264.526327) (xy 98.732849 -264.526327) (xy 98.732849 -264.474393) (xy 98.740974 -264.423098)
			(xy 98.757022 -264.373705) (xy 98.7806 -264.327431) (xy 98.811126 -264.285415) (xy 98.847849 -264.248692)
			(xy 98.889865 -264.218166) (xy 98.936139 -264.194588) (xy 98.985532 -264.17854) (xy 99.036827 -264.170415)
			(xy 99.088761 -264.170415) (xy 99.140056 -264.17854) (xy 99.189449 -264.194588) (xy 99.235723 -264.218166)
			(xy 99.277739 -264.248692) (xy 99.314462 -264.285415) (xy 99.344988 -264.327431) (xy 99.368566 -264.373705)
			(xy 99.384614 -264.423098) (xy 99.392739 -264.474393) (xy 99.393248 -264.50036) (xy 99.392739 -264.526327)
			(xy 99.672649 -264.526327) (xy 99.672649 -264.474393) (xy 99.680774 -264.423098) (xy 99.696822 -264.373705)
			(xy 99.7204 -264.327431) (xy 99.750926 -264.285415) (xy 99.787649 -264.248692) (xy 99.829665 -264.218166)
			(xy 99.875939 -264.194588) (xy 99.925332 -264.17854) (xy 99.976627 -264.170415) (xy 100.028561 -264.170415)
			(xy 100.079856 -264.17854) (xy 100.129249 -264.194588) (xy 100.175523 -264.218166) (xy 100.217539 -264.248692)
			(xy 100.254262 -264.285415) (xy 100.284788 -264.327431) (xy 100.308366 -264.373705) (xy 100.324414 -264.423098)
			(xy 100.332539 -264.474393) (xy 100.333048 -264.50036) (xy 100.332539 -264.526327) (xy 100.612449 -264.526327)
			(xy 100.612449 -264.474393) (xy 100.620574 -264.423098) (xy 100.636622 -264.373705) (xy 100.6602 -264.327431)
			(xy 100.690726 -264.285415) (xy 100.727449 -264.248692) (xy 100.769465 -264.218166) (xy 100.815739 -264.194588)
			(xy 100.865132 -264.17854) (xy 100.916427 -264.170415) (xy 100.968361 -264.170415) (xy 101.019656 -264.17854)
			(xy 101.069049 -264.194588) (xy 101.115323 -264.218166) (xy 101.157339 -264.248692) (xy 101.194062 -264.285415)
			(xy 101.224588 -264.327431) (xy 101.248166 -264.373705) (xy 101.264214 -264.423098) (xy 101.272339 -264.474393)
			(xy 101.272848 -264.50036) (xy 101.272339 -264.526327) (xy 101.552249 -264.526327) (xy 101.552249 -264.474393)
			(xy 101.560374 -264.423098) (xy 101.576422 -264.373705) (xy 101.6 -264.327431) (xy 101.630526 -264.285415)
			(xy 101.667249 -264.248692) (xy 101.709265 -264.218166) (xy 101.755539 -264.194588) (xy 101.804932 -264.17854)
			(xy 101.856227 -264.170415) (xy 101.908161 -264.170415) (xy 101.959456 -264.17854) (xy 102.008849 -264.194588)
			(xy 102.055123 -264.218166) (xy 102.097139 -264.248692) (xy 102.133862 -264.285415) (xy 102.164388 -264.327431)
			(xy 102.187966 -264.373705) (xy 102.204014 -264.423098) (xy 102.212139 -264.474393) (xy 102.212648 -264.50036)
			(xy 102.212139 -264.526327) (xy 102.492049 -264.526327) (xy 102.492049 -264.474393) (xy 102.500174 -264.423098)
			(xy 102.516222 -264.373705) (xy 102.5398 -264.327431) (xy 102.570326 -264.285415) (xy 102.607049 -264.248692)
			(xy 102.649065 -264.218166) (xy 102.695339 -264.194588) (xy 102.744732 -264.17854) (xy 102.796027 -264.170415)
			(xy 102.847961 -264.170415) (xy 102.899256 -264.17854) (xy 102.948649 -264.194588) (xy 102.994923 -264.218166)
			(xy 103.036939 -264.248692) (xy 103.073662 -264.285415) (xy 103.104188 -264.327431) (xy 103.127766 -264.373705)
			(xy 103.143814 -264.423098) (xy 103.151939 -264.474393) (xy 103.152448 -264.50036) (xy 103.151939 -264.526327)
			(xy 103.431849 -264.526327) (xy 103.431849 -264.474393) (xy 103.439974 -264.423098) (xy 103.456022 -264.373705)
			(xy 103.4796 -264.327431) (xy 103.510126 -264.285415) (xy 103.546849 -264.248692) (xy 103.588865 -264.218166)
			(xy 103.635139 -264.194588) (xy 103.684532 -264.17854) (xy 103.735827 -264.170415) (xy 103.787761 -264.170415)
			(xy 103.839056 -264.17854) (xy 103.888449 -264.194588) (xy 103.934723 -264.218166) (xy 103.976739 -264.248692)
			(xy 104.013462 -264.285415) (xy 104.043988 -264.327431) (xy 104.067566 -264.373705) (xy 104.083614 -264.423098)
			(xy 104.091739 -264.474393) (xy 104.092248 -264.50036) (xy 104.091739 -264.526327) (xy 104.371649 -264.526327)
			(xy 104.371649 -264.474393) (xy 104.379774 -264.423098) (xy 104.395822 -264.373705) (xy 104.4194 -264.327431)
			(xy 104.449926 -264.285415) (xy 104.486649 -264.248692) (xy 104.528665 -264.218166) (xy 104.574939 -264.194588)
			(xy 104.624332 -264.17854) (xy 104.675627 -264.170415) (xy 104.727561 -264.170415) (xy 104.778856 -264.17854)
			(xy 104.828249 -264.194588) (xy 104.874523 -264.218166) (xy 104.916539 -264.248692) (xy 104.953262 -264.285415)
			(xy 104.983788 -264.327431) (xy 105.007366 -264.373705) (xy 105.023414 -264.423098) (xy 105.031539 -264.474393)
			(xy 105.032048 -264.50036) (xy 105.031539 -264.526327) (xy 105.311449 -264.526327) (xy 105.311449 -264.474393)
			(xy 105.319574 -264.423098) (xy 105.335622 -264.373705) (xy 105.3592 -264.327431) (xy 105.389726 -264.285415)
			(xy 105.426449 -264.248692) (xy 105.468465 -264.218166) (xy 105.514739 -264.194588) (xy 105.564132 -264.17854)
			(xy 105.615427 -264.170415) (xy 105.667361 -264.170415) (xy 105.718656 -264.17854) (xy 105.768049 -264.194588)
			(xy 105.814323 -264.218166) (xy 105.856339 -264.248692) (xy 105.893062 -264.285415) (xy 105.923588 -264.327431)
			(xy 105.947166 -264.373705) (xy 105.963214 -264.423098) (xy 105.971339 -264.474393) (xy 105.971848 -264.50036)
			(xy 105.971339 -264.526327) (xy 106.251249 -264.526327) (xy 106.251249 -264.474393) (xy 106.259374 -264.423098)
			(xy 106.275422 -264.373705) (xy 106.299 -264.327431) (xy 106.329526 -264.285415) (xy 106.366249 -264.248692)
			(xy 106.408265 -264.218166) (xy 106.454539 -264.194588) (xy 106.503932 -264.17854) (xy 106.555227 -264.170415)
			(xy 106.607161 -264.170415) (xy 106.658456 -264.17854) (xy 106.707849 -264.194588) (xy 106.754123 -264.218166)
			(xy 106.796139 -264.248692) (xy 106.832862 -264.285415) (xy 106.863388 -264.327431) (xy 106.886966 -264.373705)
			(xy 106.903014 -264.423098) (xy 106.911139 -264.474393) (xy 106.911648 -264.50036) (xy 106.911139 -264.526327)
			(xy 107.191303 -264.526327) (xy 107.191303 -264.474393) (xy 107.199428 -264.423098) (xy 107.215476 -264.373705)
			(xy 107.239054 -264.327431) (xy 107.26958 -264.285415) (xy 107.306303 -264.248692) (xy 107.348319 -264.218166)
			(xy 107.394593 -264.194588) (xy 107.443986 -264.17854) (xy 107.495281 -264.170415) (xy 107.547215 -264.170415)
			(xy 107.59851 -264.17854) (xy 107.647903 -264.194588) (xy 107.694177 -264.218166) (xy 107.736193 -264.248692)
			(xy 107.772916 -264.285415) (xy 107.803442 -264.327431) (xy 107.82702 -264.373705) (xy 107.843068 -264.423098)
			(xy 107.851193 -264.474393) (xy 107.851702 -264.50036) (xy 107.851193 -264.526327) (xy 108.131103 -264.526327)
			(xy 108.131103 -264.474393) (xy 108.139228 -264.423098) (xy 108.155276 -264.373705) (xy 108.178854 -264.327431)
			(xy 108.20938 -264.285415) (xy 108.246103 -264.248692) (xy 108.288119 -264.218166) (xy 108.334393 -264.194588)
			(xy 108.383786 -264.17854) (xy 108.435081 -264.170415) (xy 108.487015 -264.170415) (xy 108.53831 -264.17854)
			(xy 108.587703 -264.194588) (xy 108.633977 -264.218166) (xy 108.675993 -264.248692) (xy 108.712716 -264.285415)
			(xy 108.743242 -264.327431) (xy 108.76682 -264.373705) (xy 108.782868 -264.423098) (xy 108.790993 -264.474393)
			(xy 108.791502 -264.50036) (xy 108.790993 -264.526327) (xy 108.782868 -264.577622) (xy 108.76682 -264.627015)
			(xy 108.743242 -264.673289) (xy 108.712716 -264.715305) (xy 108.675993 -264.752028) (xy 108.633977 -264.782554)
			(xy 108.587703 -264.806132) (xy 108.53831 -264.82218) (xy 108.487015 -264.830305) (xy 108.435081 -264.830305)
			(xy 108.383786 -264.82218) (xy 108.334393 -264.806132) (xy 108.288119 -264.782554) (xy 108.246103 -264.752028)
			(xy 108.20938 -264.715305) (xy 108.178854 -264.673289) (xy 108.155276 -264.627015) (xy 108.139228 -264.577622)
			(xy 108.131103 -264.526327) (xy 107.851193 -264.526327) (xy 107.843068 -264.577622) (xy 107.82702 -264.627015)
			(xy 107.803442 -264.673289) (xy 107.772916 -264.715305) (xy 107.736193 -264.752028) (xy 107.694177 -264.782554)
			(xy 107.647903 -264.806132) (xy 107.59851 -264.82218) (xy 107.547215 -264.830305) (xy 107.495281 -264.830305)
			(xy 107.443986 -264.82218) (xy 107.394593 -264.806132) (xy 107.348319 -264.782554) (xy 107.306303 -264.752028)
			(xy 107.26958 -264.715305) (xy 107.239054 -264.673289) (xy 107.215476 -264.627015) (xy 107.199428 -264.577622)
			(xy 107.191303 -264.526327) (xy 106.911139 -264.526327) (xy 106.903014 -264.577622) (xy 106.886966 -264.627015)
			(xy 106.863388 -264.673289) (xy 106.832862 -264.715305) (xy 106.796139 -264.752028) (xy 106.754123 -264.782554)
			(xy 106.707849 -264.806132) (xy 106.658456 -264.82218) (xy 106.607161 -264.830305) (xy 106.555227 -264.830305)
			(xy 106.503932 -264.82218) (xy 106.454539 -264.806132) (xy 106.408265 -264.782554) (xy 106.366249 -264.752028)
			(xy 106.329526 -264.715305) (xy 106.299 -264.673289) (xy 106.275422 -264.627015) (xy 106.259374 -264.577622)
			(xy 106.251249 -264.526327) (xy 105.971339 -264.526327) (xy 105.963214 -264.577622) (xy 105.947166 -264.627015)
			(xy 105.923588 -264.673289) (xy 105.893062 -264.715305) (xy 105.856339 -264.752028) (xy 105.814323 -264.782554)
			(xy 105.768049 -264.806132) (xy 105.718656 -264.82218) (xy 105.667361 -264.830305) (xy 105.615427 -264.830305)
			(xy 105.564132 -264.82218) (xy 105.514739 -264.806132) (xy 105.468465 -264.782554) (xy 105.426449 -264.752028)
			(xy 105.389726 -264.715305) (xy 105.3592 -264.673289) (xy 105.335622 -264.627015) (xy 105.319574 -264.577622)
			(xy 105.311449 -264.526327) (xy 105.031539 -264.526327) (xy 105.023414 -264.577622) (xy 105.007366 -264.627015)
			(xy 104.983788 -264.673289) (xy 104.953262 -264.715305) (xy 104.916539 -264.752028) (xy 104.874523 -264.782554)
			(xy 104.828249 -264.806132) (xy 104.778856 -264.82218) (xy 104.727561 -264.830305) (xy 104.675627 -264.830305)
			(xy 104.624332 -264.82218) (xy 104.574939 -264.806132) (xy 104.528665 -264.782554) (xy 104.486649 -264.752028)
			(xy 104.449926 -264.715305) (xy 104.4194 -264.673289) (xy 104.395822 -264.627015) (xy 104.379774 -264.577622)
			(xy 104.371649 -264.526327) (xy 104.091739 -264.526327) (xy 104.083614 -264.577622) (xy 104.067566 -264.627015)
			(xy 104.043988 -264.673289) (xy 104.013462 -264.715305) (xy 103.976739 -264.752028) (xy 103.934723 -264.782554)
			(xy 103.888449 -264.806132) (xy 103.839056 -264.82218) (xy 103.787761 -264.830305) (xy 103.735827 -264.830305)
			(xy 103.684532 -264.82218) (xy 103.635139 -264.806132) (xy 103.588865 -264.782554) (xy 103.546849 -264.752028)
			(xy 103.510126 -264.715305) (xy 103.4796 -264.673289) (xy 103.456022 -264.627015) (xy 103.439974 -264.577622)
			(xy 103.431849 -264.526327) (xy 103.151939 -264.526327) (xy 103.143814 -264.577622) (xy 103.127766 -264.627015)
			(xy 103.104188 -264.673289) (xy 103.073662 -264.715305) (xy 103.036939 -264.752028) (xy 102.994923 -264.782554)
			(xy 102.948649 -264.806132) (xy 102.899256 -264.82218) (xy 102.847961 -264.830305) (xy 102.796027 -264.830305)
			(xy 102.744732 -264.82218) (xy 102.695339 -264.806132) (xy 102.649065 -264.782554) (xy 102.607049 -264.752028)
			(xy 102.570326 -264.715305) (xy 102.5398 -264.673289) (xy 102.516222 -264.627015) (xy 102.500174 -264.577622)
			(xy 102.492049 -264.526327) (xy 102.212139 -264.526327) (xy 102.204014 -264.577622) (xy 102.187966 -264.627015)
			(xy 102.164388 -264.673289) (xy 102.133862 -264.715305) (xy 102.097139 -264.752028) (xy 102.055123 -264.782554)
			(xy 102.008849 -264.806132) (xy 101.959456 -264.82218) (xy 101.908161 -264.830305) (xy 101.856227 -264.830305)
			(xy 101.804932 -264.82218) (xy 101.755539 -264.806132) (xy 101.709265 -264.782554) (xy 101.667249 -264.752028)
			(xy 101.630526 -264.715305) (xy 101.6 -264.673289) (xy 101.576422 -264.627015) (xy 101.560374 -264.577622)
			(xy 101.552249 -264.526327) (xy 101.272339 -264.526327) (xy 101.264214 -264.577622) (xy 101.248166 -264.627015)
			(xy 101.224588 -264.673289) (xy 101.194062 -264.715305) (xy 101.157339 -264.752028) (xy 101.115323 -264.782554)
			(xy 101.069049 -264.806132) (xy 101.019656 -264.82218) (xy 100.968361 -264.830305) (xy 100.916427 -264.830305)
			(xy 100.865132 -264.82218) (xy 100.815739 -264.806132) (xy 100.769465 -264.782554) (xy 100.727449 -264.752028)
			(xy 100.690726 -264.715305) (xy 100.6602 -264.673289) (xy 100.636622 -264.627015) (xy 100.620574 -264.577622)
			(xy 100.612449 -264.526327) (xy 100.332539 -264.526327) (xy 100.324414 -264.577622) (xy 100.308366 -264.627015)
			(xy 100.284788 -264.673289) (xy 100.254262 -264.715305) (xy 100.217539 -264.752028) (xy 100.175523 -264.782554)
			(xy 100.129249 -264.806132) (xy 100.079856 -264.82218) (xy 100.028561 -264.830305) (xy 99.976627 -264.830305)
			(xy 99.925332 -264.82218) (xy 99.875939 -264.806132) (xy 99.829665 -264.782554) (xy 99.787649 -264.752028)
			(xy 99.750926 -264.715305) (xy 99.7204 -264.673289) (xy 99.696822 -264.627015) (xy 99.680774 -264.577622)
			(xy 99.672649 -264.526327) (xy 99.392739 -264.526327) (xy 99.384614 -264.577622) (xy 99.368566 -264.627015)
			(xy 99.344988 -264.673289) (xy 99.314462 -264.715305) (xy 99.277739 -264.752028) (xy 99.235723 -264.782554)
			(xy 99.189449 -264.806132) (xy 99.140056 -264.82218) (xy 99.088761 -264.830305) (xy 99.036827 -264.830305)
			(xy 98.985532 -264.82218) (xy 98.936139 -264.806132) (xy 98.889865 -264.782554) (xy 98.847849 -264.752028)
			(xy 98.811126 -264.715305) (xy 98.7806 -264.673289) (xy 98.757022 -264.627015) (xy 98.740974 -264.577622)
			(xy 98.732849 -264.526327) (xy 98.453449 -264.526327) (xy 98.453449 -264.526351) (xy 98.445324 -264.577693)
			(xy 98.429267 -264.627132) (xy 98.405674 -264.67345) (xy 98.375126 -264.715508) (xy 98.338375 -264.752269)
			(xy 98.296325 -264.782828) (xy 98.250013 -264.806434) (xy 98.200578 -264.822504) (xy 98.149238 -264.830643)
			(xy 98.123248 -264.831068) (xy 98.096576 -264.830556) (xy 98.043924 -264.82199) (xy 97.993329 -264.805088)
			(xy 97.9461 -264.780288) (xy 97.903461 -264.748232) (xy 97.866518 -264.709752) (xy 97.836226 -264.665843)
			(xy 97.81337 -264.617643) (xy 97.798544 -264.566401) (xy 97.794826 -264.539984) (xy 97.794572 -264.538206)
			(xy 97.793402 -264.531707) (xy 97.788128 -264.519606) (xy 97.784158 -264.51433) (xy 97.779586 -264.508742)
			(xy 97.768156 -264.500614) (xy 97.674684 -264.468356) (xy 97.665607 -264.465712) (xy 97.646735 -264.466471)
			(xy 97.629409 -264.473992) (xy 97.62236 -264.480294) (xy 97.496884 -264.60577) (xy 97.493074 -264.616184)
			(xy 97.482619 -264.642509) (xy 97.45405 -264.691414) (xy 97.417572 -264.734741) (xy 97.37425 -264.771225)
			(xy 97.325348 -264.7998) (xy 97.299018 -264.81024) (xy 97.288604 -264.81405) (xy 97.010474 -265.09218)
			(xy 97.003388 -265.099932) (xy 96.995682 -265.119445) (xy 96.996493 -265.140409) (xy 97.000568 -265.150092)
			(xy 97.002092 -265.152886) (xy 97.015301 -265.177701) (xy 97.03408 -265.230681) (xy 97.043643 -265.286072)
			(xy 97.044256 -265.314176) (xy 97.043748 -265.340143) (xy 97.323403 -265.340143) (xy 97.323403 -265.288209)
			(xy 97.331528 -265.236914) (xy 97.347576 -265.187521) (xy 97.371154 -265.141247) (xy 97.40168 -265.099231)
			(xy 97.438403 -265.062508) (xy 97.480419 -265.031982) (xy 97.526693 -265.008404) (xy 97.576086 -264.992356)
			(xy 97.627381 -264.984231) (xy 97.679315 -264.984231) (xy 97.73061 -264.992356) (xy 97.780003 -265.008404)
			(xy 97.826277 -265.031982) (xy 97.868293 -265.062508) (xy 97.905016 -265.099231) (xy 97.935542 -265.141247)
			(xy 97.95912 -265.187521) (xy 97.975168 -265.236914) (xy 97.983293 -265.288209) (xy 97.983802 -265.314176)
			(xy 97.983293 -265.340143) (xy 98.262949 -265.340143) (xy 98.262949 -265.288209) (xy 98.271074 -265.236914)
			(xy 98.287122 -265.187521) (xy 98.3107 -265.141247) (xy 98.341226 -265.099231) (xy 98.377949 -265.062508)
			(xy 98.419965 -265.031982) (xy 98.466239 -265.008404) (xy 98.515632 -264.992356) (xy 98.566927 -264.984231)
			(xy 98.618861 -264.984231) (xy 98.670156 -264.992356) (xy 98.719549 -265.008404) (xy 98.765823 -265.031982)
			(xy 98.807839 -265.062508) (xy 98.844562 -265.099231) (xy 98.875088 -265.141247) (xy 98.898666 -265.187521)
			(xy 98.914714 -265.236914) (xy 98.922839 -265.288209) (xy 98.923348 -265.314176) (xy 98.922839 -265.340143)
			(xy 99.203003 -265.340143) (xy 99.203003 -265.288209) (xy 99.211128 -265.236914) (xy 99.227176 -265.187521)
			(xy 99.250754 -265.141247) (xy 99.28128 -265.099231) (xy 99.318003 -265.062508) (xy 99.360019 -265.031982)
			(xy 99.406293 -265.008404) (xy 99.455686 -264.992356) (xy 99.506981 -264.984231) (xy 99.558915 -264.984231)
			(xy 99.61021 -264.992356) (xy 99.659603 -265.008404) (xy 99.705877 -265.031982) (xy 99.747893 -265.062508)
			(xy 99.784616 -265.099231) (xy 99.815142 -265.141247) (xy 99.83872 -265.187521) (xy 99.854768 -265.236914)
			(xy 99.862893 -265.288209) (xy 99.863402 -265.314176) (xy 99.862893 -265.340143) (xy 100.142803 -265.340143)
			(xy 100.142803 -265.288209) (xy 100.150928 -265.236914) (xy 100.166976 -265.187521) (xy 100.190554 -265.141247)
			(xy 100.22108 -265.099231) (xy 100.257803 -265.062508) (xy 100.299819 -265.031982) (xy 100.346093 -265.008404)
			(xy 100.395486 -264.992356) (xy 100.446781 -264.984231) (xy 100.498715 -264.984231) (xy 100.55001 -264.992356)
			(xy 100.599403 -265.008404) (xy 100.645677 -265.031982) (xy 100.687693 -265.062508) (xy 100.724416 -265.099231)
			(xy 100.754942 -265.141247) (xy 100.77852 -265.187521) (xy 100.794568 -265.236914) (xy 100.802693 -265.288209)
			(xy 100.803202 -265.314176) (xy 100.802693 -265.340143) (xy 101.082603 -265.340143) (xy 101.082603 -265.288209)
			(xy 101.090728 -265.236914) (xy 101.106776 -265.187521) (xy 101.130354 -265.141247) (xy 101.16088 -265.099231)
			(xy 101.197603 -265.062508) (xy 101.239619 -265.031982) (xy 101.285893 -265.008404) (xy 101.335286 -264.992356)
			(xy 101.386581 -264.984231) (xy 101.438515 -264.984231) (xy 101.48981 -264.992356) (xy 101.539203 -265.008404)
			(xy 101.585477 -265.031982) (xy 101.627493 -265.062508) (xy 101.664216 -265.099231) (xy 101.694742 -265.141247)
			(xy 101.71832 -265.187521) (xy 101.734368 -265.236914) (xy 101.742493 -265.288209) (xy 101.743002 -265.314176)
			(xy 101.742493 -265.340143) (xy 102.022403 -265.340143) (xy 102.022403 -265.288209) (xy 102.030528 -265.236914)
			(xy 102.046576 -265.187521) (xy 102.070154 -265.141247) (xy 102.10068 -265.099231) (xy 102.137403 -265.062508)
			(xy 102.179419 -265.031982) (xy 102.225693 -265.008404) (xy 102.275086 -264.992356) (xy 102.326381 -264.984231)
			(xy 102.378315 -264.984231) (xy 102.42961 -264.992356) (xy 102.479003 -265.008404) (xy 102.525277 -265.031982)
			(xy 102.567293 -265.062508) (xy 102.604016 -265.099231) (xy 102.634542 -265.141247) (xy 102.65812 -265.187521)
			(xy 102.674168 -265.236914) (xy 102.682293 -265.288209) (xy 102.682802 -265.314176) (xy 102.682293 -265.340143)
			(xy 102.962203 -265.340143) (xy 102.962203 -265.288209) (xy 102.970328 -265.236914) (xy 102.986376 -265.187521)
			(xy 103.009954 -265.141247) (xy 103.04048 -265.099231) (xy 103.077203 -265.062508) (xy 103.119219 -265.031982)
			(xy 103.165493 -265.008404) (xy 103.214886 -264.992356) (xy 103.266181 -264.984231) (xy 103.318115 -264.984231)
			(xy 103.36941 -264.992356) (xy 103.418803 -265.008404) (xy 103.465077 -265.031982) (xy 103.507093 -265.062508)
			(xy 103.543816 -265.099231) (xy 103.574342 -265.141247) (xy 103.59792 -265.187521) (xy 103.613968 -265.236914)
			(xy 103.622093 -265.288209) (xy 103.622602 -265.314176) (xy 103.622093 -265.340143) (xy 103.902003 -265.340143)
			(xy 103.902003 -265.288209) (xy 103.910128 -265.236914) (xy 103.926176 -265.187521) (xy 103.949754 -265.141247)
			(xy 103.98028 -265.099231) (xy 104.017003 -265.062508) (xy 104.059019 -265.031982) (xy 104.105293 -265.008404)
			(xy 104.154686 -264.992356) (xy 104.205981 -264.984231) (xy 104.257915 -264.984231) (xy 104.30921 -264.992356)
			(xy 104.358603 -265.008404) (xy 104.404877 -265.031982) (xy 104.446893 -265.062508) (xy 104.483616 -265.099231)
			(xy 104.514142 -265.141247) (xy 104.53772 -265.187521) (xy 104.553768 -265.236914) (xy 104.561893 -265.288209)
			(xy 104.562402 -265.314176) (xy 104.561893 -265.340143) (xy 104.841803 -265.340143) (xy 104.841803 -265.288209)
			(xy 104.849928 -265.236914) (xy 104.865976 -265.187521) (xy 104.889554 -265.141247) (xy 104.92008 -265.099231)
			(xy 104.956803 -265.062508) (xy 104.998819 -265.031982) (xy 105.045093 -265.008404) (xy 105.094486 -264.992356)
			(xy 105.145781 -264.984231) (xy 105.197715 -264.984231) (xy 105.24901 -264.992356) (xy 105.298403 -265.008404)
			(xy 105.344677 -265.031982) (xy 105.386693 -265.062508) (xy 105.423416 -265.099231) (xy 105.453942 -265.141247)
			(xy 105.47752 -265.187521) (xy 105.493568 -265.236914) (xy 105.501693 -265.288209) (xy 105.502202 -265.314176)
			(xy 105.501693 -265.340143) (xy 105.781603 -265.340143) (xy 105.781603 -265.288209) (xy 105.789728 -265.236914)
			(xy 105.805776 -265.187521) (xy 105.829354 -265.141247) (xy 105.85988 -265.099231) (xy 105.896603 -265.062508)
			(xy 105.938619 -265.031982) (xy 105.984893 -265.008404) (xy 106.034286 -264.992356) (xy 106.085581 -264.984231)
			(xy 106.137515 -264.984231) (xy 106.18881 -264.992356) (xy 106.238203 -265.008404) (xy 106.284477 -265.031982)
			(xy 106.326493 -265.062508) (xy 106.363216 -265.099231) (xy 106.393742 -265.141247) (xy 106.41732 -265.187521)
			(xy 106.433368 -265.236914) (xy 106.441493 -265.288209) (xy 106.442002 -265.314176) (xy 106.441493 -265.340143)
			(xy 106.721403 -265.340143) (xy 106.721403 -265.288209) (xy 106.729528 -265.236914) (xy 106.745576 -265.187521)
			(xy 106.769154 -265.141247) (xy 106.79968 -265.099231) (xy 106.836403 -265.062508) (xy 106.878419 -265.031982)
			(xy 106.924693 -265.008404) (xy 106.974086 -264.992356) (xy 107.025381 -264.984231) (xy 107.077315 -264.984231)
			(xy 107.12861 -264.992356) (xy 107.178003 -265.008404) (xy 107.224277 -265.031982) (xy 107.266293 -265.062508)
			(xy 107.303016 -265.099231) (xy 107.333542 -265.141247) (xy 107.35712 -265.187521) (xy 107.373168 -265.236914)
			(xy 107.381293 -265.288209) (xy 107.381802 -265.314176) (xy 107.381293 -265.340143) (xy 107.661203 -265.340143)
			(xy 107.661203 -265.288209) (xy 107.669328 -265.236914) (xy 107.685376 -265.187521) (xy 107.708954 -265.141247)
			(xy 107.73948 -265.099231) (xy 107.776203 -265.062508) (xy 107.818219 -265.031982) (xy 107.864493 -265.008404)
			(xy 107.913886 -264.992356) (xy 107.965181 -264.984231) (xy 108.017115 -264.984231) (xy 108.06841 -264.992356)
			(xy 108.117803 -265.008404) (xy 108.164077 -265.031982) (xy 108.206093 -265.062508) (xy 108.242816 -265.099231)
			(xy 108.273342 -265.141247) (xy 108.29692 -265.187521) (xy 108.312968 -265.236914) (xy 108.321093 -265.288209)
			(xy 108.321602 -265.314176) (xy 108.321093 -265.340143) (xy 108.601003 -265.340143) (xy 108.601003 -265.288209)
			(xy 108.609128 -265.236914) (xy 108.625176 -265.187521) (xy 108.648754 -265.141247) (xy 108.67928 -265.099231)
			(xy 108.716003 -265.062508) (xy 108.758019 -265.031982) (xy 108.804293 -265.008404) (xy 108.853686 -264.992356)
			(xy 108.904981 -264.984231) (xy 108.956915 -264.984231) (xy 109.00821 -264.992356) (xy 109.057603 -265.008404)
			(xy 109.103877 -265.031982) (xy 109.145893 -265.062508) (xy 109.182616 -265.099231) (xy 109.213142 -265.141247)
			(xy 109.23672 -265.187521) (xy 109.252768 -265.236914) (xy 109.260893 -265.288209) (xy 109.261402 -265.314176)
			(xy 109.260893 -265.340143) (xy 114.239549 -265.340143) (xy 114.239549 -265.288209) (xy 114.247674 -265.236914)
			(xy 114.263722 -265.187521) (xy 114.2873 -265.141247) (xy 114.317826 -265.099231) (xy 114.354549 -265.062508)
			(xy 114.396565 -265.031982) (xy 114.442839 -265.008404) (xy 114.492232 -264.992356) (xy 114.543527 -264.984231)
			(xy 114.595461 -264.984231) (xy 114.646756 -264.992356) (xy 114.696149 -265.008404) (xy 114.742423 -265.031982)
			(xy 114.784439 -265.062508) (xy 114.821162 -265.099231) (xy 114.851688 -265.141247) (xy 114.875266 -265.187521)
			(xy 114.891314 -265.236914) (xy 114.899439 -265.288209) (xy 114.899948 -265.314176) (xy 114.899439 -265.340143)
			(xy 114.891314 -265.391438) (xy 114.875266 -265.440831) (xy 114.851688 -265.487105) (xy 114.821162 -265.529121)
			(xy 114.784439 -265.565844) (xy 114.742423 -265.59637) (xy 114.696149 -265.619948) (xy 114.646756 -265.635996)
			(xy 114.595461 -265.644121) (xy 114.543527 -265.644121) (xy 114.492232 -265.635996) (xy 114.442839 -265.619948)
			(xy 114.396565 -265.59637) (xy 114.354549 -265.565844) (xy 114.317826 -265.529121) (xy 114.2873 -265.487105)
			(xy 114.263722 -265.440831) (xy 114.247674 -265.391438) (xy 114.239549 -265.340143) (xy 109.260893 -265.340143)
			(xy 109.252768 -265.391438) (xy 109.23672 -265.440831) (xy 109.213142 -265.487105) (xy 109.182616 -265.529121)
			(xy 109.145893 -265.565844) (xy 109.103877 -265.59637) (xy 109.057603 -265.619948) (xy 109.00821 -265.635996)
			(xy 108.956915 -265.644121) (xy 108.904981 -265.644121) (xy 108.853686 -265.635996) (xy 108.804293 -265.619948)
			(xy 108.758019 -265.59637) (xy 108.716003 -265.565844) (xy 108.67928 -265.529121) (xy 108.648754 -265.487105)
			(xy 108.625176 -265.440831) (xy 108.609128 -265.391438) (xy 108.601003 -265.340143) (xy 108.321093 -265.340143)
			(xy 108.312968 -265.391438) (xy 108.29692 -265.440831) (xy 108.273342 -265.487105) (xy 108.242816 -265.529121)
			(xy 108.206093 -265.565844) (xy 108.164077 -265.59637) (xy 108.117803 -265.619948) (xy 108.06841 -265.635996)
			(xy 108.017115 -265.644121) (xy 107.965181 -265.644121) (xy 107.913886 -265.635996) (xy 107.864493 -265.619948)
			(xy 107.818219 -265.59637) (xy 107.776203 -265.565844) (xy 107.73948 -265.529121) (xy 107.708954 -265.487105)
			(xy 107.685376 -265.440831) (xy 107.669328 -265.391438) (xy 107.661203 -265.340143) (xy 107.381293 -265.340143)
			(xy 107.373168 -265.391438) (xy 107.35712 -265.440831) (xy 107.333542 -265.487105) (xy 107.303016 -265.529121)
			(xy 107.266293 -265.565844) (xy 107.224277 -265.59637) (xy 107.178003 -265.619948) (xy 107.12861 -265.635996)
			(xy 107.077315 -265.644121) (xy 107.025381 -265.644121) (xy 106.974086 -265.635996) (xy 106.924693 -265.619948)
			(xy 106.878419 -265.59637) (xy 106.836403 -265.565844) (xy 106.79968 -265.529121) (xy 106.769154 -265.487105)
			(xy 106.745576 -265.440831) (xy 106.729528 -265.391438) (xy 106.721403 -265.340143) (xy 106.441493 -265.340143)
			(xy 106.433368 -265.391438) (xy 106.41732 -265.440831) (xy 106.393742 -265.487105) (xy 106.363216 -265.529121)
			(xy 106.326493 -265.565844) (xy 106.284477 -265.59637) (xy 106.238203 -265.619948) (xy 106.18881 -265.635996)
			(xy 106.137515 -265.644121) (xy 106.085581 -265.644121) (xy 106.034286 -265.635996) (xy 105.984893 -265.619948)
			(xy 105.938619 -265.59637) (xy 105.896603 -265.565844) (xy 105.85988 -265.529121) (xy 105.829354 -265.487105)
			(xy 105.805776 -265.440831) (xy 105.789728 -265.391438) (xy 105.781603 -265.340143) (xy 105.501693 -265.340143)
			(xy 105.493568 -265.391438) (xy 105.47752 -265.440831) (xy 105.453942 -265.487105) (xy 105.423416 -265.529121)
			(xy 105.386693 -265.565844) (xy 105.344677 -265.59637) (xy 105.298403 -265.619948) (xy 105.24901 -265.635996)
			(xy 105.197715 -265.644121) (xy 105.145781 -265.644121) (xy 105.094486 -265.635996) (xy 105.045093 -265.619948)
			(xy 104.998819 -265.59637) (xy 104.956803 -265.565844) (xy 104.92008 -265.529121) (xy 104.889554 -265.487105)
			(xy 104.865976 -265.440831) (xy 104.849928 -265.391438) (xy 104.841803 -265.340143) (xy 104.561893 -265.340143)
			(xy 104.553768 -265.391438) (xy 104.53772 -265.440831) (xy 104.514142 -265.487105) (xy 104.483616 -265.529121)
			(xy 104.446893 -265.565844) (xy 104.404877 -265.59637) (xy 104.358603 -265.619948) (xy 104.30921 -265.635996)
			(xy 104.257915 -265.644121) (xy 104.205981 -265.644121) (xy 104.154686 -265.635996) (xy 104.105293 -265.619948)
			(xy 104.059019 -265.59637) (xy 104.017003 -265.565844) (xy 103.98028 -265.529121) (xy 103.949754 -265.487105)
			(xy 103.926176 -265.440831) (xy 103.910128 -265.391438) (xy 103.902003 -265.340143) (xy 103.622093 -265.340143)
			(xy 103.613968 -265.391438) (xy 103.59792 -265.440831) (xy 103.574342 -265.487105) (xy 103.543816 -265.529121)
			(xy 103.507093 -265.565844) (xy 103.465077 -265.59637) (xy 103.418803 -265.619948) (xy 103.36941 -265.635996)
			(xy 103.318115 -265.644121) (xy 103.266181 -265.644121) (xy 103.214886 -265.635996) (xy 103.165493 -265.619948)
			(xy 103.119219 -265.59637) (xy 103.077203 -265.565844) (xy 103.04048 -265.529121) (xy 103.009954 -265.487105)
			(xy 102.986376 -265.440831) (xy 102.970328 -265.391438) (xy 102.962203 -265.340143) (xy 102.682293 -265.340143)
			(xy 102.674168 -265.391438) (xy 102.65812 -265.440831) (xy 102.634542 -265.487105) (xy 102.604016 -265.529121)
			(xy 102.567293 -265.565844) (xy 102.525277 -265.59637) (xy 102.479003 -265.619948) (xy 102.42961 -265.635996)
			(xy 102.378315 -265.644121) (xy 102.326381 -265.644121) (xy 102.275086 -265.635996) (xy 102.225693 -265.619948)
			(xy 102.179419 -265.59637) (xy 102.137403 -265.565844) (xy 102.10068 -265.529121) (xy 102.070154 -265.487105)
			(xy 102.046576 -265.440831) (xy 102.030528 -265.391438) (xy 102.022403 -265.340143) (xy 101.742493 -265.340143)
			(xy 101.734368 -265.391438) (xy 101.71832 -265.440831) (xy 101.694742 -265.487105) (xy 101.664216 -265.529121)
			(xy 101.627493 -265.565844) (xy 101.585477 -265.59637) (xy 101.539203 -265.619948) (xy 101.48981 -265.635996)
			(xy 101.438515 -265.644121) (xy 101.386581 -265.644121) (xy 101.335286 -265.635996) (xy 101.285893 -265.619948)
			(xy 101.239619 -265.59637) (xy 101.197603 -265.565844) (xy 101.16088 -265.529121) (xy 101.130354 -265.487105)
			(xy 101.106776 -265.440831) (xy 101.090728 -265.391438) (xy 101.082603 -265.340143) (xy 100.802693 -265.340143)
			(xy 100.794568 -265.391438) (xy 100.77852 -265.440831) (xy 100.754942 -265.487105) (xy 100.724416 -265.529121)
			(xy 100.687693 -265.565844) (xy 100.645677 -265.59637) (xy 100.599403 -265.619948) (xy 100.55001 -265.635996)
			(xy 100.498715 -265.644121) (xy 100.446781 -265.644121) (xy 100.395486 -265.635996) (xy 100.346093 -265.619948)
			(xy 100.299819 -265.59637) (xy 100.257803 -265.565844) (xy 100.22108 -265.529121) (xy 100.190554 -265.487105)
			(xy 100.166976 -265.440831) (xy 100.150928 -265.391438) (xy 100.142803 -265.340143) (xy 99.862893 -265.340143)
			(xy 99.854768 -265.391438) (xy 99.83872 -265.440831) (xy 99.815142 -265.487105) (xy 99.784616 -265.529121)
			(xy 99.747893 -265.565844) (xy 99.705877 -265.59637) (xy 99.659603 -265.619948) (xy 99.61021 -265.635996)
			(xy 99.558915 -265.644121) (xy 99.506981 -265.644121) (xy 99.455686 -265.635996) (xy 99.406293 -265.619948)
			(xy 99.360019 -265.59637) (xy 99.318003 -265.565844) (xy 99.28128 -265.529121) (xy 99.250754 -265.487105)
			(xy 99.227176 -265.440831) (xy 99.211128 -265.391438) (xy 99.203003 -265.340143) (xy 98.922839 -265.340143)
			(xy 98.914714 -265.391438) (xy 98.898666 -265.440831) (xy 98.875088 -265.487105) (xy 98.844562 -265.529121)
			(xy 98.807839 -265.565844) (xy 98.765823 -265.59637) (xy 98.719549 -265.619948) (xy 98.670156 -265.635996)
			(xy 98.618861 -265.644121) (xy 98.566927 -265.644121) (xy 98.515632 -265.635996) (xy 98.466239 -265.619948)
			(xy 98.419965 -265.59637) (xy 98.377949 -265.565844) (xy 98.341226 -265.529121) (xy 98.3107 -265.487105)
			(xy 98.287122 -265.440831) (xy 98.271074 -265.391438) (xy 98.262949 -265.340143) (xy 97.983293 -265.340143)
			(xy 97.975168 -265.391438) (xy 97.95912 -265.440831) (xy 97.935542 -265.487105) (xy 97.905016 -265.529121)
			(xy 97.868293 -265.565844) (xy 97.826277 -265.59637) (xy 97.780003 -265.619948) (xy 97.73061 -265.635996)
			(xy 97.679315 -265.644121) (xy 97.627381 -265.644121) (xy 97.576086 -265.635996) (xy 97.526693 -265.619948)
			(xy 97.480419 -265.59637) (xy 97.438403 -265.565844) (xy 97.40168 -265.529121) (xy 97.371154 -265.487105)
			(xy 97.347576 -265.440831) (xy 97.331528 -265.391438) (xy 97.323403 -265.340143) (xy 97.043748 -265.340143)
			(xy 97.043748 -265.340166) (xy 97.035621 -265.391506) (xy 97.019563 -265.440943) (xy 96.995969 -265.487259)
			(xy 96.96542 -265.529315) (xy 96.928669 -265.566074) (xy 96.886621 -265.596631) (xy 96.840309 -265.620235)
			(xy 96.790876 -265.636304) (xy 96.739538 -265.644443) (xy 96.713548 -265.644884) (xy 96.687036 -265.64434)
			(xy 96.634695 -265.635843) (xy 96.58438 -265.619108) (xy 96.56064 -265.607292) (xy 96.55556 -265.604498)
			(xy 96.552512 -265.60272) (xy 96.552004 -265.60272) (xy 96.552004 -265.602466) (xy 96.542128 -265.597681)
			(xy 96.520261 -265.596122) (xy 96.499713 -265.603763) (xy 96.491552 -265.611102) (xy 96.407986 -265.694668)
			(xy 96.400429 -265.703127) (xy 96.392896 -265.724491) (xy 96.393508 -265.735816) (xy 96.395286 -265.752834)
			(xy 96.40189 -265.816842) (xy 96.402808 -265.821734) (xy 96.40627 -265.831066) (xy 96.408748 -265.835384)
			(xy 96.411796 -265.84021) (xy 96.419162 -265.848084) (xy 96.424242 -265.851386) (xy 96.446835 -265.866823)
			(xy 96.487088 -265.90388) (xy 96.520695 -265.947057) (xy 96.546738 -265.995175) (xy 96.564508 -266.046923)
			(xy 96.57352 -266.100889) (xy 96.574102 -266.128246) (xy 96.573589 -266.154213) (xy 96.853249 -266.154213)
			(xy 96.853249 -266.102279) (xy 96.861374 -266.050984) (xy 96.877422 -266.001591) (xy 96.901 -265.955317)
			(xy 96.931526 -265.913301) (xy 96.968249 -265.876578) (xy 97.010265 -265.846052) (xy 97.056539 -265.822474)
			(xy 97.105932 -265.806426) (xy 97.157227 -265.798301) (xy 97.209161 -265.798301) (xy 97.260456 -265.806426)
			(xy 97.309849 -265.822474) (xy 97.356123 -265.846052) (xy 97.398139 -265.876578) (xy 97.434862 -265.913301)
			(xy 97.465388 -265.955317) (xy 97.488966 -266.001591) (xy 97.505014 -266.050984) (xy 97.513139 -266.102279)
			(xy 97.513648 -266.128246) (xy 97.513139 -266.154213) (xy 97.793049 -266.154213) (xy 97.793049 -266.102279)
			(xy 97.801174 -266.050984) (xy 97.817222 -266.001591) (xy 97.8408 -265.955317) (xy 97.871326 -265.913301)
			(xy 97.908049 -265.876578) (xy 97.950065 -265.846052) (xy 97.996339 -265.822474) (xy 98.045732 -265.806426)
			(xy 98.097027 -265.798301) (xy 98.148961 -265.798301) (xy 98.200256 -265.806426) (xy 98.249649 -265.822474)
			(xy 98.295923 -265.846052) (xy 98.337939 -265.876578) (xy 98.374662 -265.913301) (xy 98.405188 -265.955317)
			(xy 98.428766 -266.001591) (xy 98.444814 -266.050984) (xy 98.452939 -266.102279) (xy 98.453448 -266.128246)
			(xy 98.452939 -266.154213) (xy 98.732849 -266.154213) (xy 98.732849 -266.102279) (xy 98.740974 -266.050984)
			(xy 98.757022 -266.001591) (xy 98.7806 -265.955317) (xy 98.811126 -265.913301) (xy 98.847849 -265.876578)
			(xy 98.889865 -265.846052) (xy 98.936139 -265.822474) (xy 98.985532 -265.806426) (xy 99.036827 -265.798301)
			(xy 99.088761 -265.798301) (xy 99.140056 -265.806426) (xy 99.189449 -265.822474) (xy 99.235723 -265.846052)
			(xy 99.277739 -265.876578) (xy 99.314462 -265.913301) (xy 99.344988 -265.955317) (xy 99.368566 -266.001591)
			(xy 99.384614 -266.050984) (xy 99.392739 -266.102279) (xy 99.393248 -266.128246) (xy 99.392739 -266.154213)
			(xy 99.672649 -266.154213) (xy 99.672649 -266.102279) (xy 99.680774 -266.050984) (xy 99.696822 -266.001591)
			(xy 99.7204 -265.955317) (xy 99.750926 -265.913301) (xy 99.787649 -265.876578) (xy 99.829665 -265.846052)
			(xy 99.875939 -265.822474) (xy 99.925332 -265.806426) (xy 99.976627 -265.798301) (xy 100.028561 -265.798301)
			(xy 100.079856 -265.806426) (xy 100.129249 -265.822474) (xy 100.175523 -265.846052) (xy 100.217539 -265.876578)
			(xy 100.254262 -265.913301) (xy 100.284788 -265.955317) (xy 100.308366 -266.001591) (xy 100.324414 -266.050984)
			(xy 100.332539 -266.102279) (xy 100.333048 -266.128246) (xy 100.332539 -266.154213) (xy 100.612449 -266.154213)
			(xy 100.612449 -266.102279) (xy 100.620574 -266.050984) (xy 100.636622 -266.001591) (xy 100.6602 -265.955317)
			(xy 100.690726 -265.913301) (xy 100.727449 -265.876578) (xy 100.769465 -265.846052) (xy 100.815739 -265.822474)
			(xy 100.865132 -265.806426) (xy 100.916427 -265.798301) (xy 100.968361 -265.798301) (xy 101.019656 -265.806426)
			(xy 101.069049 -265.822474) (xy 101.115323 -265.846052) (xy 101.157339 -265.876578) (xy 101.194062 -265.913301)
			(xy 101.224588 -265.955317) (xy 101.248166 -266.001591) (xy 101.264214 -266.050984) (xy 101.272339 -266.102279)
			(xy 101.272848 -266.128246) (xy 101.272339 -266.154213) (xy 101.552249 -266.154213) (xy 101.552249 -266.102279)
			(xy 101.560374 -266.050984) (xy 101.576422 -266.001591) (xy 101.6 -265.955317) (xy 101.630526 -265.913301)
			(xy 101.667249 -265.876578) (xy 101.709265 -265.846052) (xy 101.755539 -265.822474) (xy 101.804932 -265.806426)
			(xy 101.856227 -265.798301) (xy 101.908161 -265.798301) (xy 101.959456 -265.806426) (xy 102.008849 -265.822474)
			(xy 102.055123 -265.846052) (xy 102.097139 -265.876578) (xy 102.133862 -265.913301) (xy 102.164388 -265.955317)
			(xy 102.187966 -266.001591) (xy 102.204014 -266.050984) (xy 102.212139 -266.102279) (xy 102.212648 -266.128246)
			(xy 102.212139 -266.154213) (xy 102.492049 -266.154213) (xy 102.492049 -266.102279) (xy 102.500174 -266.050984)
			(xy 102.516222 -266.001591) (xy 102.5398 -265.955317) (xy 102.570326 -265.913301) (xy 102.607049 -265.876578)
			(xy 102.649065 -265.846052) (xy 102.695339 -265.822474) (xy 102.744732 -265.806426) (xy 102.796027 -265.798301)
			(xy 102.847961 -265.798301) (xy 102.899256 -265.806426) (xy 102.948649 -265.822474) (xy 102.994923 -265.846052)
			(xy 103.036939 -265.876578) (xy 103.073662 -265.913301) (xy 103.104188 -265.955317) (xy 103.127766 -266.001591)
			(xy 103.143814 -266.050984) (xy 103.151939 -266.102279) (xy 103.152448 -266.128246) (xy 103.151939 -266.154213)
			(xy 103.431849 -266.154213) (xy 103.431849 -266.102279) (xy 103.439974 -266.050984) (xy 103.456022 -266.001591)
			(xy 103.4796 -265.955317) (xy 103.510126 -265.913301) (xy 103.546849 -265.876578) (xy 103.588865 -265.846052)
			(xy 103.635139 -265.822474) (xy 103.684532 -265.806426) (xy 103.735827 -265.798301) (xy 103.787761 -265.798301)
			(xy 103.839056 -265.806426) (xy 103.888449 -265.822474) (xy 103.934723 -265.846052) (xy 103.976739 -265.876578)
			(xy 104.013462 -265.913301) (xy 104.043988 -265.955317) (xy 104.067566 -266.001591) (xy 104.083614 -266.050984)
			(xy 104.091739 -266.102279) (xy 104.092248 -266.128246) (xy 104.091739 -266.154213) (xy 104.371649 -266.154213)
			(xy 104.371649 -266.102279) (xy 104.379774 -266.050984) (xy 104.395822 -266.001591) (xy 104.4194 -265.955317)
			(xy 104.449926 -265.913301) (xy 104.486649 -265.876578) (xy 104.528665 -265.846052) (xy 104.574939 -265.822474)
			(xy 104.624332 -265.806426) (xy 104.675627 -265.798301) (xy 104.727561 -265.798301) (xy 104.778856 -265.806426)
			(xy 104.828249 -265.822474) (xy 104.874523 -265.846052) (xy 104.916539 -265.876578) (xy 104.953262 -265.913301)
			(xy 104.983788 -265.955317) (xy 105.007366 -266.001591) (xy 105.023414 -266.050984) (xy 105.031539 -266.102279)
			(xy 105.032048 -266.128246) (xy 105.031539 -266.154213) (xy 105.311449 -266.154213) (xy 105.311449 -266.102279)
			(xy 105.319574 -266.050984) (xy 105.335622 -266.001591) (xy 105.3592 -265.955317) (xy 105.389726 -265.913301)
			(xy 105.426449 -265.876578) (xy 105.468465 -265.846052) (xy 105.514739 -265.822474) (xy 105.564132 -265.806426)
			(xy 105.615427 -265.798301) (xy 105.667361 -265.798301) (xy 105.718656 -265.806426) (xy 105.768049 -265.822474)
			(xy 105.814323 -265.846052) (xy 105.856339 -265.876578) (xy 105.893062 -265.913301) (xy 105.923588 -265.955317)
			(xy 105.947166 -266.001591) (xy 105.963214 -266.050984) (xy 105.971339 -266.102279) (xy 105.971848 -266.128246)
			(xy 105.971339 -266.154213) (xy 106.251249 -266.154213) (xy 106.251249 -266.102279) (xy 106.259374 -266.050984)
			(xy 106.275422 -266.001591) (xy 106.299 -265.955317) (xy 106.329526 -265.913301) (xy 106.366249 -265.876578)
			(xy 106.408265 -265.846052) (xy 106.454539 -265.822474) (xy 106.503932 -265.806426) (xy 106.555227 -265.798301)
			(xy 106.607161 -265.798301) (xy 106.658456 -265.806426) (xy 106.707849 -265.822474) (xy 106.754123 -265.846052)
			(xy 106.796139 -265.876578) (xy 106.832862 -265.913301) (xy 106.863388 -265.955317) (xy 106.886966 -266.001591)
			(xy 106.903014 -266.050984) (xy 106.911139 -266.102279) (xy 106.911648 -266.128246) (xy 106.911139 -266.154213)
			(xy 107.191049 -266.154213) (xy 107.191049 -266.102279) (xy 107.199174 -266.050984) (xy 107.215222 -266.001591)
			(xy 107.2388 -265.955317) (xy 107.269326 -265.913301) (xy 107.306049 -265.876578) (xy 107.348065 -265.846052)
			(xy 107.394339 -265.822474) (xy 107.443732 -265.806426) (xy 107.495027 -265.798301) (xy 107.546961 -265.798301)
			(xy 107.598256 -265.806426) (xy 107.647649 -265.822474) (xy 107.693923 -265.846052) (xy 107.735939 -265.876578)
			(xy 107.772662 -265.913301) (xy 107.803188 -265.955317) (xy 107.826766 -266.001591) (xy 107.842814 -266.050984)
			(xy 107.850939 -266.102279) (xy 107.851448 -266.128246) (xy 107.850939 -266.154213) (xy 108.130849 -266.154213)
			(xy 108.130849 -266.102279) (xy 108.138974 -266.050984) (xy 108.155022 -266.001591) (xy 108.1786 -265.955317)
			(xy 108.209126 -265.913301) (xy 108.245849 -265.876578) (xy 108.287865 -265.846052) (xy 108.334139 -265.822474)
			(xy 108.383532 -265.806426) (xy 108.434827 -265.798301) (xy 108.486761 -265.798301) (xy 108.538056 -265.806426)
			(xy 108.587449 -265.822474) (xy 108.633723 -265.846052) (xy 108.675739 -265.876578) (xy 108.712462 -265.913301)
			(xy 108.742988 -265.955317) (xy 108.766566 -266.001591) (xy 108.782614 -266.050984) (xy 108.790739 -266.102279)
			(xy 108.791248 -266.128246) (xy 108.790739 -266.154213) (xy 109.070903 -266.154213) (xy 109.070903 -266.102279)
			(xy 109.079028 -266.050984) (xy 109.095076 -266.001591) (xy 109.118654 -265.955317) (xy 109.14918 -265.913301)
			(xy 109.185903 -265.876578) (xy 109.227919 -265.846052) (xy 109.274193 -265.822474) (xy 109.323586 -265.806426)
			(xy 109.374881 -265.798301) (xy 109.426815 -265.798301) (xy 109.47811 -265.806426) (xy 109.527503 -265.822474)
			(xy 109.573777 -265.846052) (xy 109.615793 -265.876578) (xy 109.652516 -265.913301) (xy 109.683042 -265.955317)
			(xy 109.70662 -266.001591) (xy 109.722668 -266.050984) (xy 109.730793 -266.102279) (xy 109.731302 -266.128246)
			(xy 109.730793 -266.154213) (xy 113.769649 -266.154213) (xy 113.769649 -266.102279) (xy 113.777774 -266.050984)
			(xy 113.793822 -266.001591) (xy 113.8174 -265.955317) (xy 113.847926 -265.913301) (xy 113.884649 -265.876578)
			(xy 113.926665 -265.846052) (xy 113.972939 -265.822474) (xy 114.022332 -265.806426) (xy 114.073627 -265.798301)
			(xy 114.125561 -265.798301) (xy 114.176856 -265.806426) (xy 114.226249 -265.822474) (xy 114.272523 -265.846052)
			(xy 114.314539 -265.876578) (xy 114.351262 -265.913301) (xy 114.381788 -265.955317) (xy 114.405366 -266.001591)
			(xy 114.421414 -266.050984) (xy 114.429539 -266.102279) (xy 114.430048 -266.128246) (xy 114.429539 -266.154213)
			(xy 114.421414 -266.205508) (xy 114.405366 -266.254901) (xy 114.381788 -266.301175) (xy 114.351262 -266.343191)
			(xy 114.314539 -266.379914) (xy 114.272523 -266.41044) (xy 114.226249 -266.434018) (xy 114.176856 -266.450066)
			(xy 114.125561 -266.458191) (xy 114.073627 -266.458191) (xy 114.022332 -266.450066) (xy 113.972939 -266.434018)
			(xy 113.926665 -266.41044) (xy 113.884649 -266.379914) (xy 113.847926 -266.343191) (xy 113.8174 -266.301175)
			(xy 113.793822 -266.254901) (xy 113.777774 -266.205508) (xy 113.769649 -266.154213) (xy 109.730793 -266.154213)
			(xy 109.722668 -266.205508) (xy 109.70662 -266.254901) (xy 109.683042 -266.301175) (xy 109.652516 -266.343191)
			(xy 109.615793 -266.379914) (xy 109.573777 -266.41044) (xy 109.527503 -266.434018) (xy 109.47811 -266.450066)
			(xy 109.426815 -266.458191) (xy 109.374881 -266.458191) (xy 109.323586 -266.450066) (xy 109.274193 -266.434018)
			(xy 109.227919 -266.41044) (xy 109.185903 -266.379914) (xy 109.14918 -266.343191) (xy 109.118654 -266.301175)
			(xy 109.095076 -266.254901) (xy 109.079028 -266.205508) (xy 109.070903 -266.154213) (xy 108.790739 -266.154213)
			(xy 108.782614 -266.205508) (xy 108.766566 -266.254901) (xy 108.742988 -266.301175) (xy 108.712462 -266.343191)
			(xy 108.675739 -266.379914) (xy 108.633723 -266.41044) (xy 108.587449 -266.434018) (xy 108.538056 -266.450066)
			(xy 108.486761 -266.458191) (xy 108.434827 -266.458191) (xy 108.383532 -266.450066) (xy 108.334139 -266.434018)
			(xy 108.287865 -266.41044) (xy 108.245849 -266.379914) (xy 108.209126 -266.343191) (xy 108.1786 -266.301175)
			(xy 108.155022 -266.254901) (xy 108.138974 -266.205508) (xy 108.130849 -266.154213) (xy 107.850939 -266.154213)
			(xy 107.842814 -266.205508) (xy 107.826766 -266.254901) (xy 107.803188 -266.301175) (xy 107.772662 -266.343191)
			(xy 107.735939 -266.379914) (xy 107.693923 -266.41044) (xy 107.647649 -266.434018) (xy 107.598256 -266.450066)
			(xy 107.546961 -266.458191) (xy 107.495027 -266.458191) (xy 107.443732 -266.450066) (xy 107.394339 -266.434018)
			(xy 107.348065 -266.41044) (xy 107.306049 -266.379914) (xy 107.269326 -266.343191) (xy 107.2388 -266.301175)
			(xy 107.215222 -266.254901) (xy 107.199174 -266.205508) (xy 107.191049 -266.154213) (xy 106.911139 -266.154213)
			(xy 106.903014 -266.205508) (xy 106.886966 -266.254901) (xy 106.863388 -266.301175) (xy 106.832862 -266.343191)
			(xy 106.796139 -266.379914) (xy 106.754123 -266.41044) (xy 106.707849 -266.434018) (xy 106.658456 -266.450066)
			(xy 106.607161 -266.458191) (xy 106.555227 -266.458191) (xy 106.503932 -266.450066) (xy 106.454539 -266.434018)
			(xy 106.408265 -266.41044) (xy 106.366249 -266.379914) (xy 106.329526 -266.343191) (xy 106.299 -266.301175)
			(xy 106.275422 -266.254901) (xy 106.259374 -266.205508) (xy 106.251249 -266.154213) (xy 105.971339 -266.154213)
			(xy 105.963214 -266.205508) (xy 105.947166 -266.254901) (xy 105.923588 -266.301175) (xy 105.893062 -266.343191)
			(xy 105.856339 -266.379914) (xy 105.814323 -266.41044) (xy 105.768049 -266.434018) (xy 105.718656 -266.450066)
			(xy 105.667361 -266.458191) (xy 105.615427 -266.458191) (xy 105.564132 -266.450066) (xy 105.514739 -266.434018)
			(xy 105.468465 -266.41044) (xy 105.426449 -266.379914) (xy 105.389726 -266.343191) (xy 105.3592 -266.301175)
			(xy 105.335622 -266.254901) (xy 105.319574 -266.205508) (xy 105.311449 -266.154213) (xy 105.031539 -266.154213)
			(xy 105.023414 -266.205508) (xy 105.007366 -266.254901) (xy 104.983788 -266.301175) (xy 104.953262 -266.343191)
			(xy 104.916539 -266.379914) (xy 104.874523 -266.41044) (xy 104.828249 -266.434018) (xy 104.778856 -266.450066)
			(xy 104.727561 -266.458191) (xy 104.675627 -266.458191) (xy 104.624332 -266.450066) (xy 104.574939 -266.434018)
			(xy 104.528665 -266.41044) (xy 104.486649 -266.379914) (xy 104.449926 -266.343191) (xy 104.4194 -266.301175)
			(xy 104.395822 -266.254901) (xy 104.379774 -266.205508) (xy 104.371649 -266.154213) (xy 104.091739 -266.154213)
			(xy 104.083614 -266.205508) (xy 104.067566 -266.254901) (xy 104.043988 -266.301175) (xy 104.013462 -266.343191)
			(xy 103.976739 -266.379914) (xy 103.934723 -266.41044) (xy 103.888449 -266.434018) (xy 103.839056 -266.450066)
			(xy 103.787761 -266.458191) (xy 103.735827 -266.458191) (xy 103.684532 -266.450066) (xy 103.635139 -266.434018)
			(xy 103.588865 -266.41044) (xy 103.546849 -266.379914) (xy 103.510126 -266.343191) (xy 103.4796 -266.301175)
			(xy 103.456022 -266.254901) (xy 103.439974 -266.205508) (xy 103.431849 -266.154213) (xy 103.151939 -266.154213)
			(xy 103.143814 -266.205508) (xy 103.127766 -266.254901) (xy 103.104188 -266.301175) (xy 103.073662 -266.343191)
			(xy 103.036939 -266.379914) (xy 102.994923 -266.41044) (xy 102.948649 -266.434018) (xy 102.899256 -266.450066)
			(xy 102.847961 -266.458191) (xy 102.796027 -266.458191) (xy 102.744732 -266.450066) (xy 102.695339 -266.434018)
			(xy 102.649065 -266.41044) (xy 102.607049 -266.379914) (xy 102.570326 -266.343191) (xy 102.5398 -266.301175)
			(xy 102.516222 -266.254901) (xy 102.500174 -266.205508) (xy 102.492049 -266.154213) (xy 102.212139 -266.154213)
			(xy 102.204014 -266.205508) (xy 102.187966 -266.254901) (xy 102.164388 -266.301175) (xy 102.133862 -266.343191)
			(xy 102.097139 -266.379914) (xy 102.055123 -266.41044) (xy 102.008849 -266.434018) (xy 101.959456 -266.450066)
			(xy 101.908161 -266.458191) (xy 101.856227 -266.458191) (xy 101.804932 -266.450066) (xy 101.755539 -266.434018)
			(xy 101.709265 -266.41044) (xy 101.667249 -266.379914) (xy 101.630526 -266.343191) (xy 101.6 -266.301175)
			(xy 101.576422 -266.254901) (xy 101.560374 -266.205508) (xy 101.552249 -266.154213) (xy 101.272339 -266.154213)
			(xy 101.264214 -266.205508) (xy 101.248166 -266.254901) (xy 101.224588 -266.301175) (xy 101.194062 -266.343191)
			(xy 101.157339 -266.379914) (xy 101.115323 -266.41044) (xy 101.069049 -266.434018) (xy 101.019656 -266.450066)
			(xy 100.968361 -266.458191) (xy 100.916427 -266.458191) (xy 100.865132 -266.450066) (xy 100.815739 -266.434018)
			(xy 100.769465 -266.41044) (xy 100.727449 -266.379914) (xy 100.690726 -266.343191) (xy 100.6602 -266.301175)
			(xy 100.636622 -266.254901) (xy 100.620574 -266.205508) (xy 100.612449 -266.154213) (xy 100.332539 -266.154213)
			(xy 100.324414 -266.205508) (xy 100.308366 -266.254901) (xy 100.284788 -266.301175) (xy 100.254262 -266.343191)
			(xy 100.217539 -266.379914) (xy 100.175523 -266.41044) (xy 100.129249 -266.434018) (xy 100.079856 -266.450066)
			(xy 100.028561 -266.458191) (xy 99.976627 -266.458191) (xy 99.925332 -266.450066) (xy 99.875939 -266.434018)
			(xy 99.829665 -266.41044) (xy 99.787649 -266.379914) (xy 99.750926 -266.343191) (xy 99.7204 -266.301175)
			(xy 99.696822 -266.254901) (xy 99.680774 -266.205508) (xy 99.672649 -266.154213) (xy 99.392739 -266.154213)
			(xy 99.384614 -266.205508) (xy 99.368566 -266.254901) (xy 99.344988 -266.301175) (xy 99.314462 -266.343191)
			(xy 99.277739 -266.379914) (xy 99.235723 -266.41044) (xy 99.189449 -266.434018) (xy 99.140056 -266.450066)
			(xy 99.088761 -266.458191) (xy 99.036827 -266.458191) (xy 98.985532 -266.450066) (xy 98.936139 -266.434018)
			(xy 98.889865 -266.41044) (xy 98.847849 -266.379914) (xy 98.811126 -266.343191) (xy 98.7806 -266.301175)
			(xy 98.757022 -266.254901) (xy 98.740974 -266.205508) (xy 98.732849 -266.154213) (xy 98.452939 -266.154213)
			(xy 98.444814 -266.205508) (xy 98.428766 -266.254901) (xy 98.405188 -266.301175) (xy 98.374662 -266.343191)
			(xy 98.337939 -266.379914) (xy 98.295923 -266.41044) (xy 98.249649 -266.434018) (xy 98.200256 -266.450066)
			(xy 98.148961 -266.458191) (xy 98.097027 -266.458191) (xy 98.045732 -266.450066) (xy 97.996339 -266.434018)
			(xy 97.950065 -266.41044) (xy 97.908049 -266.379914) (xy 97.871326 -266.343191) (xy 97.8408 -266.301175)
			(xy 97.817222 -266.254901) (xy 97.801174 -266.205508) (xy 97.793049 -266.154213) (xy 97.513139 -266.154213)
			(xy 97.505014 -266.205508) (xy 97.488966 -266.254901) (xy 97.465388 -266.301175) (xy 97.434862 -266.343191)
			(xy 97.398139 -266.379914) (xy 97.356123 -266.41044) (xy 97.309849 -266.434018) (xy 97.260456 -266.450066)
			(xy 97.209161 -266.458191) (xy 97.157227 -266.458191) (xy 97.105932 -266.450066) (xy 97.056539 -266.434018)
			(xy 97.010265 -266.41044) (xy 96.968249 -266.379914) (xy 96.931526 -266.343191) (xy 96.901 -266.301175)
			(xy 96.877422 -266.254901) (xy 96.861374 -266.205508) (xy 96.853249 -266.154213) (xy 96.573589 -266.154213)
			(xy 96.573589 -266.154231) (xy 96.565453 -266.205559) (xy 96.549388 -266.254983) (xy 96.525789 -266.301286)
			(xy 96.495239 -266.343327) (xy 96.458488 -266.380072) (xy 96.416442 -266.410616) (xy 96.370135 -266.434208)
			(xy 96.320709 -266.450265) (xy 96.269379 -266.458393) (xy 96.243394 -266.458954) (xy 96.242632 -266.458954)
			(xy 96.227171 -266.458751) (xy 96.196386 -266.45583) (xy 96.181164 -266.453112) (xy 96.169734 -266.450826)
			(xy 96.159066 -266.45362) (xy 96.153663 -266.455167) (xy 96.143667 -266.4603) (xy 96.139254 -266.46378)
			(xy 96.079056 -266.513564) (xy 96.070771 -266.521164) (xy 96.061149 -266.541455) (xy 96.060514 -266.55268)
			(xy 96.060514 -266.764008) (xy 96.065594 -266.786106) (xy 96.066102 -266.786868) (xy 96.066356 -266.78763)
			(xy 96.078361 -266.811537) (xy 96.095342 -266.862263) (xy 96.103945 -266.91506) (xy 96.103943 -266.967775)
			(xy 96.383603 -266.967775) (xy 96.383603 -266.915841) (xy 96.391728 -266.864546) (xy 96.407776 -266.815153)
			(xy 96.431354 -266.768879) (xy 96.46188 -266.726863) (xy 96.498603 -266.69014) (xy 96.540619 -266.659614)
			(xy 96.586893 -266.636036) (xy 96.636286 -266.619988) (xy 96.687581 -266.611863) (xy 96.739515 -266.611863)
			(xy 96.79081 -266.619988) (xy 96.840203 -266.636036) (xy 96.886477 -266.659614) (xy 96.928493 -266.69014)
			(xy 96.965216 -266.726863) (xy 96.995742 -266.768879) (xy 97.01932 -266.815153) (xy 97.035368 -266.864546)
			(xy 97.043493 -266.915841) (xy 97.044002 -266.941808) (xy 97.043493 -266.967775) (xy 97.323149 -266.967775)
			(xy 97.323149 -266.915841) (xy 97.331274 -266.864546) (xy 97.347322 -266.815153) (xy 97.3709 -266.768879)
			(xy 97.401426 -266.726863) (xy 97.438149 -266.69014) (xy 97.480165 -266.659614) (xy 97.526439 -266.636036)
			(xy 97.575832 -266.619988) (xy 97.627127 -266.611863) (xy 97.679061 -266.611863) (xy 97.730356 -266.619988)
			(xy 97.779749 -266.636036) (xy 97.826023 -266.659614) (xy 97.868039 -266.69014) (xy 97.904762 -266.726863)
			(xy 97.935288 -266.768879) (xy 97.958866 -266.815153) (xy 97.974914 -266.864546) (xy 97.983039 -266.915841)
			(xy 97.983548 -266.941808) (xy 97.983039 -266.967775) (xy 98.263203 -266.967775) (xy 98.263203 -266.915841)
			(xy 98.271328 -266.864546) (xy 98.287376 -266.815153) (xy 98.310954 -266.768879) (xy 98.34148 -266.726863)
			(xy 98.378203 -266.69014) (xy 98.420219 -266.659614) (xy 98.466493 -266.636036) (xy 98.515886 -266.619988)
			(xy 98.567181 -266.611863) (xy 98.619115 -266.611863) (xy 98.67041 -266.619988) (xy 98.719803 -266.636036)
			(xy 98.766077 -266.659614) (xy 98.808093 -266.69014) (xy 98.844816 -266.726863) (xy 98.875342 -266.768879)
			(xy 98.89892 -266.815153) (xy 98.914968 -266.864546) (xy 98.923093 -266.915841) (xy 98.923602 -266.941808)
			(xy 98.923093 -266.967775) (xy 99.203003 -266.967775) (xy 99.203003 -266.915841) (xy 99.211128 -266.864546)
			(xy 99.227176 -266.815153) (xy 99.250754 -266.768879) (xy 99.28128 -266.726863) (xy 99.318003 -266.69014)
			(xy 99.360019 -266.659614) (xy 99.406293 -266.636036) (xy 99.455686 -266.619988) (xy 99.506981 -266.611863)
			(xy 99.558915 -266.611863) (xy 99.61021 -266.619988) (xy 99.659603 -266.636036) (xy 99.705877 -266.659614)
			(xy 99.747893 -266.69014) (xy 99.784616 -266.726863) (xy 99.815142 -266.768879) (xy 99.83872 -266.815153)
			(xy 99.854768 -266.864546) (xy 99.862893 -266.915841) (xy 99.863402 -266.941808) (xy 99.862893 -266.967775)
			(xy 100.142803 -266.967775) (xy 100.142803 -266.915841) (xy 100.150928 -266.864546) (xy 100.166976 -266.815153)
			(xy 100.190554 -266.768879) (xy 100.22108 -266.726863) (xy 100.257803 -266.69014) (xy 100.299819 -266.659614)
			(xy 100.346093 -266.636036) (xy 100.395486 -266.619988) (xy 100.446781 -266.611863) (xy 100.498715 -266.611863)
			(xy 100.55001 -266.619988) (xy 100.599403 -266.636036) (xy 100.645677 -266.659614) (xy 100.687693 -266.69014)
			(xy 100.724416 -266.726863) (xy 100.754942 -266.768879) (xy 100.77852 -266.815153) (xy 100.794568 -266.864546)
			(xy 100.802693 -266.915841) (xy 100.803202 -266.941808) (xy 100.802693 -266.967775) (xy 101.082603 -266.967775)
			(xy 101.082603 -266.915841) (xy 101.090728 -266.864546) (xy 101.106776 -266.815153) (xy 101.130354 -266.768879)
			(xy 101.16088 -266.726863) (xy 101.197603 -266.69014) (xy 101.239619 -266.659614) (xy 101.285893 -266.636036)
			(xy 101.335286 -266.619988) (xy 101.386581 -266.611863) (xy 101.438515 -266.611863) (xy 101.48981 -266.619988)
			(xy 101.539203 -266.636036) (xy 101.585477 -266.659614) (xy 101.627493 -266.69014) (xy 101.664216 -266.726863)
			(xy 101.694742 -266.768879) (xy 101.71832 -266.815153) (xy 101.734368 -266.864546) (xy 101.742493 -266.915841)
			(xy 101.743002 -266.941808) (xy 101.742493 -266.967775) (xy 102.022403 -266.967775) (xy 102.022403 -266.915841)
			(xy 102.030528 -266.864546) (xy 102.046576 -266.815153) (xy 102.070154 -266.768879) (xy 102.10068 -266.726863)
			(xy 102.137403 -266.69014) (xy 102.179419 -266.659614) (xy 102.225693 -266.636036) (xy 102.275086 -266.619988)
			(xy 102.326381 -266.611863) (xy 102.378315 -266.611863) (xy 102.42961 -266.619988) (xy 102.479003 -266.636036)
			(xy 102.525277 -266.659614) (xy 102.567293 -266.69014) (xy 102.604016 -266.726863) (xy 102.634542 -266.768879)
			(xy 102.65812 -266.815153) (xy 102.674168 -266.864546) (xy 102.682293 -266.915841) (xy 102.682802 -266.941808)
			(xy 102.682293 -266.967775) (xy 102.962203 -266.967775) (xy 102.962203 -266.915841) (xy 102.970328 -266.864546)
			(xy 102.986376 -266.815153) (xy 103.009954 -266.768879) (xy 103.04048 -266.726863) (xy 103.077203 -266.69014)
			(xy 103.119219 -266.659614) (xy 103.165493 -266.636036) (xy 103.214886 -266.619988) (xy 103.266181 -266.611863)
			(xy 103.318115 -266.611863) (xy 103.36941 -266.619988) (xy 103.418803 -266.636036) (xy 103.465077 -266.659614)
			(xy 103.507093 -266.69014) (xy 103.543816 -266.726863) (xy 103.574342 -266.768879) (xy 103.59792 -266.815153)
			(xy 103.613968 -266.864546) (xy 103.622093 -266.915841) (xy 103.622602 -266.941808) (xy 103.622093 -266.967775)
			(xy 103.901749 -266.967775) (xy 103.901749 -266.915841) (xy 103.909874 -266.864546) (xy 103.925922 -266.815153)
			(xy 103.9495 -266.768879) (xy 103.980026 -266.726863) (xy 104.016749 -266.69014) (xy 104.058765 -266.659614)
			(xy 104.105039 -266.636036) (xy 104.154432 -266.619988) (xy 104.205727 -266.611863) (xy 104.257661 -266.611863)
			(xy 104.308956 -266.619988) (xy 104.358349 -266.636036) (xy 104.404623 -266.659614) (xy 104.446639 -266.69014)
			(xy 104.483362 -266.726863) (xy 104.513888 -266.768879) (xy 104.537466 -266.815153) (xy 104.553514 -266.864546)
			(xy 104.561639 -266.915841) (xy 104.562148 -266.941808) (xy 104.561639 -266.967775) (xy 104.841295 -266.967775)
			(xy 104.841295 -266.915841) (xy 104.84942 -266.864546) (xy 104.865468 -266.815153) (xy 104.889046 -266.768879)
			(xy 104.919572 -266.726863) (xy 104.956295 -266.69014) (xy 104.998311 -266.659614) (xy 105.044585 -266.636036)
			(xy 105.093978 -266.619988) (xy 105.145273 -266.611863) (xy 105.197207 -266.611863) (xy 105.248502 -266.619988)
			(xy 105.297895 -266.636036) (xy 105.344169 -266.659614) (xy 105.386185 -266.69014) (xy 105.422908 -266.726863)
			(xy 105.453434 -266.768879) (xy 105.477012 -266.815153) (xy 105.49306 -266.864546) (xy 105.501185 -266.915841)
			(xy 105.501694 -266.941808) (xy 105.501185 -266.967775) (xy 105.781349 -266.967775) (xy 105.781349 -266.915841)
			(xy 105.789474 -266.864546) (xy 105.805522 -266.815153) (xy 105.8291 -266.768879) (xy 105.859626 -266.726863)
			(xy 105.896349 -266.69014) (xy 105.938365 -266.659614) (xy 105.984639 -266.636036) (xy 106.034032 -266.619988)
			(xy 106.085327 -266.611863) (xy 106.137261 -266.611863) (xy 106.188556 -266.619988) (xy 106.237949 -266.636036)
			(xy 106.284223 -266.659614) (xy 106.326239 -266.69014) (xy 106.362962 -266.726863) (xy 106.393488 -266.768879)
			(xy 106.417066 -266.815153) (xy 106.433114 -266.864546) (xy 106.441239 -266.915841) (xy 106.441748 -266.941808)
			(xy 106.441239 -266.967775) (xy 106.721403 -266.967775) (xy 106.721403 -266.915841) (xy 106.729528 -266.864546)
			(xy 106.745576 -266.815153) (xy 106.769154 -266.768879) (xy 106.79968 -266.726863) (xy 106.836403 -266.69014)
			(xy 106.878419 -266.659614) (xy 106.924693 -266.636036) (xy 106.974086 -266.619988) (xy 107.025381 -266.611863)
			(xy 107.077315 -266.611863) (xy 107.12861 -266.619988) (xy 107.178003 -266.636036) (xy 107.224277 -266.659614)
			(xy 107.266293 -266.69014) (xy 107.303016 -266.726863) (xy 107.333542 -266.768879) (xy 107.35712 -266.815153)
			(xy 107.373168 -266.864546) (xy 107.381293 -266.915841) (xy 107.381802 -266.941808) (xy 107.381293 -266.967775)
			(xy 107.661203 -266.967775) (xy 107.661203 -266.915841) (xy 107.669328 -266.864546) (xy 107.685376 -266.815153)
			(xy 107.708954 -266.768879) (xy 107.73948 -266.726863) (xy 107.776203 -266.69014) (xy 107.818219 -266.659614)
			(xy 107.864493 -266.636036) (xy 107.913886 -266.619988) (xy 107.965181 -266.611863) (xy 108.017115 -266.611863)
			(xy 108.06841 -266.619988) (xy 108.117803 -266.636036) (xy 108.164077 -266.659614) (xy 108.206093 -266.69014)
			(xy 108.242816 -266.726863) (xy 108.273342 -266.768879) (xy 108.29692 -266.815153) (xy 108.312968 -266.864546)
			(xy 108.321093 -266.915841) (xy 108.321602 -266.941808) (xy 108.321093 -266.967775) (xy 108.601003 -266.967775)
			(xy 108.601003 -266.915841) (xy 108.609128 -266.864546) (xy 108.625176 -266.815153) (xy 108.648754 -266.768879)
			(xy 108.67928 -266.726863) (xy 108.716003 -266.69014) (xy 108.758019 -266.659614) (xy 108.804293 -266.636036)
			(xy 108.853686 -266.619988) (xy 108.904981 -266.611863) (xy 108.956915 -266.611863) (xy 109.00821 -266.619988)
			(xy 109.057603 -266.636036) (xy 109.103877 -266.659614) (xy 109.145893 -266.69014) (xy 109.182616 -266.726863)
			(xy 109.213142 -266.768879) (xy 109.23672 -266.815153) (xy 109.252768 -266.864546) (xy 109.260893 -266.915841)
			(xy 109.261402 -266.941808) (xy 109.260893 -266.967775) (xy 109.540549 -266.967775) (xy 109.540549 -266.915841)
			(xy 109.548674 -266.864546) (xy 109.564722 -266.815153) (xy 109.5883 -266.768879) (xy 109.618826 -266.726863)
			(xy 109.655549 -266.69014) (xy 109.697565 -266.659614) (xy 109.743839 -266.636036) (xy 109.793232 -266.619988)
			(xy 109.844527 -266.611863) (xy 109.896461 -266.611863) (xy 109.947756 -266.619988) (xy 109.997149 -266.636036)
			(xy 110.043423 -266.659614) (xy 110.085439 -266.69014) (xy 110.122162 -266.726863) (xy 110.152688 -266.768879)
			(xy 110.176266 -266.815153) (xy 110.192314 -266.864546) (xy 110.200439 -266.915841) (xy 110.200948 -266.941808)
			(xy 110.200439 -266.967775) (xy 113.299749 -266.967775) (xy 113.299749 -266.915841) (xy 113.307874 -266.864546)
			(xy 113.323922 -266.815153) (xy 113.3475 -266.768879) (xy 113.378026 -266.726863) (xy 113.414749 -266.69014)
			(xy 113.456765 -266.659614) (xy 113.503039 -266.636036) (xy 113.552432 -266.619988) (xy 113.603727 -266.611863)
			(xy 113.655661 -266.611863) (xy 113.706956 -266.619988) (xy 113.756349 -266.636036) (xy 113.802623 -266.659614)
			(xy 113.844639 -266.69014) (xy 113.881362 -266.726863) (xy 113.911888 -266.768879) (xy 113.935466 -266.815153)
			(xy 113.951514 -266.864546) (xy 113.959639 -266.915841) (xy 113.960148 -266.941808) (xy 113.959639 -266.967775)
			(xy 114.239803 -266.967775) (xy 114.239803 -266.915841) (xy 114.247928 -266.864546) (xy 114.263976 -266.815153)
			(xy 114.287554 -266.768879) (xy 114.31808 -266.726863) (xy 114.354803 -266.69014) (xy 114.396819 -266.659614)
			(xy 114.443093 -266.636036) (xy 114.492486 -266.619988) (xy 114.543781 -266.611863) (xy 114.595715 -266.611863)
			(xy 114.64701 -266.619988) (xy 114.696403 -266.636036) (xy 114.742677 -266.659614) (xy 114.784693 -266.69014)
			(xy 114.821416 -266.726863) (xy 114.851942 -266.768879) (xy 114.87552 -266.815153) (xy 114.891568 -266.864546)
			(xy 114.899693 -266.915841) (xy 114.900202 -266.941808) (xy 114.899693 -266.967775) (xy 114.891568 -267.01907)
			(xy 114.87552 -267.068463) (xy 114.851942 -267.114737) (xy 114.821416 -267.156753) (xy 114.784693 -267.193476)
			(xy 114.742677 -267.224002) (xy 114.696403 -267.24758) (xy 114.64701 -267.263628) (xy 114.595715 -267.271753)
			(xy 114.543781 -267.271753) (xy 114.492486 -267.263628) (xy 114.443093 -267.24758) (xy 114.396819 -267.224002)
			(xy 114.354803 -267.193476) (xy 114.31808 -267.156753) (xy 114.287554 -267.114737) (xy 114.263976 -267.068463)
			(xy 114.247928 -267.01907) (xy 114.239803 -266.967775) (xy 113.959639 -266.967775) (xy 113.951514 -267.01907)
			(xy 113.935466 -267.068463) (xy 113.911888 -267.114737) (xy 113.881362 -267.156753) (xy 113.844639 -267.193476)
			(xy 113.802623 -267.224002) (xy 113.756349 -267.24758) (xy 113.706956 -267.263628) (xy 113.655661 -267.271753)
			(xy 113.603727 -267.271753) (xy 113.552432 -267.263628) (xy 113.503039 -267.24758) (xy 113.456765 -267.224002)
			(xy 113.414749 -267.193476) (xy 113.378026 -267.156753) (xy 113.3475 -267.114737) (xy 113.323922 -267.068463)
			(xy 113.307874 -267.01907) (xy 113.299749 -266.967775) (xy 110.200439 -266.967775) (xy 110.192314 -267.01907)
			(xy 110.176266 -267.068463) (xy 110.152688 -267.114737) (xy 110.122162 -267.156753) (xy 110.085439 -267.193476)
			(xy 110.043423 -267.224002) (xy 109.997149 -267.24758) (xy 109.947756 -267.263628) (xy 109.896461 -267.271753)
			(xy 109.844527 -267.271753) (xy 109.793232 -267.263628) (xy 109.743839 -267.24758) (xy 109.697565 -267.224002)
			(xy 109.655549 -267.193476) (xy 109.618826 -267.156753) (xy 109.5883 -267.114737) (xy 109.564722 -267.068463)
			(xy 109.548674 -267.01907) (xy 109.540549 -266.967775) (xy 109.260893 -266.967775) (xy 109.252768 -267.01907)
			(xy 109.23672 -267.068463) (xy 109.213142 -267.114737) (xy 109.182616 -267.156753) (xy 109.145893 -267.193476)
			(xy 109.103877 -267.224002) (xy 109.057603 -267.24758) (xy 109.00821 -267.263628) (xy 108.956915 -267.271753)
			(xy 108.904981 -267.271753) (xy 108.853686 -267.263628) (xy 108.804293 -267.24758) (xy 108.758019 -267.224002)
			(xy 108.716003 -267.193476) (xy 108.67928 -267.156753) (xy 108.648754 -267.114737) (xy 108.625176 -267.068463)
			(xy 108.609128 -267.01907) (xy 108.601003 -266.967775) (xy 108.321093 -266.967775) (xy 108.312968 -267.01907)
			(xy 108.29692 -267.068463) (xy 108.273342 -267.114737) (xy 108.242816 -267.156753) (xy 108.206093 -267.193476)
			(xy 108.164077 -267.224002) (xy 108.117803 -267.24758) (xy 108.06841 -267.263628) (xy 108.017115 -267.271753)
			(xy 107.965181 -267.271753) (xy 107.913886 -267.263628) (xy 107.864493 -267.24758) (xy 107.818219 -267.224002)
			(xy 107.776203 -267.193476) (xy 107.73948 -267.156753) (xy 107.708954 -267.114737) (xy 107.685376 -267.068463)
			(xy 107.669328 -267.01907) (xy 107.661203 -266.967775) (xy 107.381293 -266.967775) (xy 107.373168 -267.01907)
			(xy 107.35712 -267.068463) (xy 107.333542 -267.114737) (xy 107.303016 -267.156753) (xy 107.266293 -267.193476)
			(xy 107.224277 -267.224002) (xy 107.178003 -267.24758) (xy 107.12861 -267.263628) (xy 107.077315 -267.271753)
			(xy 107.025381 -267.271753) (xy 106.974086 -267.263628) (xy 106.924693 -267.24758) (xy 106.878419 -267.224002)
			(xy 106.836403 -267.193476) (xy 106.79968 -267.156753) (xy 106.769154 -267.114737) (xy 106.745576 -267.068463)
			(xy 106.729528 -267.01907) (xy 106.721403 -266.967775) (xy 106.441239 -266.967775) (xy 106.433114 -267.01907)
			(xy 106.417066 -267.068463) (xy 106.393488 -267.114737) (xy 106.362962 -267.156753) (xy 106.326239 -267.193476)
			(xy 106.284223 -267.224002) (xy 106.237949 -267.24758) (xy 106.188556 -267.263628) (xy 106.137261 -267.271753)
			(xy 106.085327 -267.271753) (xy 106.034032 -267.263628) (xy 105.984639 -267.24758) (xy 105.938365 -267.224002)
			(xy 105.896349 -267.193476) (xy 105.859626 -267.156753) (xy 105.8291 -267.114737) (xy 105.805522 -267.068463)
			(xy 105.789474 -267.01907) (xy 105.781349 -266.967775) (xy 105.501185 -266.967775) (xy 105.49306 -267.01907)
			(xy 105.477012 -267.068463) (xy 105.453434 -267.114737) (xy 105.422908 -267.156753) (xy 105.386185 -267.193476)
			(xy 105.344169 -267.224002) (xy 105.297895 -267.24758) (xy 105.248502 -267.263628) (xy 105.197207 -267.271753)
			(xy 105.145273 -267.271753) (xy 105.093978 -267.263628) (xy 105.044585 -267.24758) (xy 104.998311 -267.224002)
			(xy 104.956295 -267.193476) (xy 104.919572 -267.156753) (xy 104.889046 -267.114737) (xy 104.865468 -267.068463)
			(xy 104.84942 -267.01907) (xy 104.841295 -266.967775) (xy 104.561639 -266.967775) (xy 104.553514 -267.01907)
			(xy 104.537466 -267.068463) (xy 104.513888 -267.114737) (xy 104.483362 -267.156753) (xy 104.446639 -267.193476)
			(xy 104.404623 -267.224002) (xy 104.358349 -267.24758) (xy 104.308956 -267.263628) (xy 104.257661 -267.271753)
			(xy 104.205727 -267.271753) (xy 104.154432 -267.263628) (xy 104.105039 -267.24758) (xy 104.058765 -267.224002)
			(xy 104.016749 -267.193476) (xy 103.980026 -267.156753) (xy 103.9495 -267.114737) (xy 103.925922 -267.068463)
			(xy 103.909874 -267.01907) (xy 103.901749 -266.967775) (xy 103.622093 -266.967775) (xy 103.613968 -267.01907)
			(xy 103.59792 -267.068463) (xy 103.574342 -267.114737) (xy 103.543816 -267.156753) (xy 103.507093 -267.193476)
			(xy 103.465077 -267.224002) (xy 103.418803 -267.24758) (xy 103.36941 -267.263628) (xy 103.318115 -267.271753)
			(xy 103.266181 -267.271753) (xy 103.214886 -267.263628) (xy 103.165493 -267.24758) (xy 103.119219 -267.224002)
			(xy 103.077203 -267.193476) (xy 103.04048 -267.156753) (xy 103.009954 -267.114737) (xy 102.986376 -267.068463)
			(xy 102.970328 -267.01907) (xy 102.962203 -266.967775) (xy 102.682293 -266.967775) (xy 102.674168 -267.01907)
			(xy 102.65812 -267.068463) (xy 102.634542 -267.114737) (xy 102.604016 -267.156753) (xy 102.567293 -267.193476)
			(xy 102.525277 -267.224002) (xy 102.479003 -267.24758) (xy 102.42961 -267.263628) (xy 102.378315 -267.271753)
			(xy 102.326381 -267.271753) (xy 102.275086 -267.263628) (xy 102.225693 -267.24758) (xy 102.179419 -267.224002)
			(xy 102.137403 -267.193476) (xy 102.10068 -267.156753) (xy 102.070154 -267.114737) (xy 102.046576 -267.068463)
			(xy 102.030528 -267.01907) (xy 102.022403 -266.967775) (xy 101.742493 -266.967775) (xy 101.734368 -267.01907)
			(xy 101.71832 -267.068463) (xy 101.694742 -267.114737) (xy 101.664216 -267.156753) (xy 101.627493 -267.193476)
			(xy 101.585477 -267.224002) (xy 101.539203 -267.24758) (xy 101.48981 -267.263628) (xy 101.438515 -267.271753)
			(xy 101.386581 -267.271753) (xy 101.335286 -267.263628) (xy 101.285893 -267.24758) (xy 101.239619 -267.224002)
			(xy 101.197603 -267.193476) (xy 101.16088 -267.156753) (xy 101.130354 -267.114737) (xy 101.106776 -267.068463)
			(xy 101.090728 -267.01907) (xy 101.082603 -266.967775) (xy 100.802693 -266.967775) (xy 100.794568 -267.01907)
			(xy 100.77852 -267.068463) (xy 100.754942 -267.114737) (xy 100.724416 -267.156753) (xy 100.687693 -267.193476)
			(xy 100.645677 -267.224002) (xy 100.599403 -267.24758) (xy 100.55001 -267.263628) (xy 100.498715 -267.271753)
			(xy 100.446781 -267.271753) (xy 100.395486 -267.263628) (xy 100.346093 -267.24758) (xy 100.299819 -267.224002)
			(xy 100.257803 -267.193476) (xy 100.22108 -267.156753) (xy 100.190554 -267.114737) (xy 100.166976 -267.068463)
			(xy 100.150928 -267.01907) (xy 100.142803 -266.967775) (xy 99.862893 -266.967775) (xy 99.854768 -267.01907)
			(xy 99.83872 -267.068463) (xy 99.815142 -267.114737) (xy 99.784616 -267.156753) (xy 99.747893 -267.193476)
			(xy 99.705877 -267.224002) (xy 99.659603 -267.24758) (xy 99.61021 -267.263628) (xy 99.558915 -267.271753)
			(xy 99.506981 -267.271753) (xy 99.455686 -267.263628) (xy 99.406293 -267.24758) (xy 99.360019 -267.224002)
			(xy 99.318003 -267.193476) (xy 99.28128 -267.156753) (xy 99.250754 -267.114737) (xy 99.227176 -267.068463)
			(xy 99.211128 -267.01907) (xy 99.203003 -266.967775) (xy 98.923093 -266.967775) (xy 98.914968 -267.01907)
			(xy 98.89892 -267.068463) (xy 98.875342 -267.114737) (xy 98.844816 -267.156753) (xy 98.808093 -267.193476)
			(xy 98.766077 -267.224002) (xy 98.719803 -267.24758) (xy 98.67041 -267.263628) (xy 98.619115 -267.271753)
			(xy 98.567181 -267.271753) (xy 98.515886 -267.263628) (xy 98.466493 -267.24758) (xy 98.420219 -267.224002)
			(xy 98.378203 -267.193476) (xy 98.34148 -267.156753) (xy 98.310954 -267.114737) (xy 98.287376 -267.068463)
			(xy 98.271328 -267.01907) (xy 98.263203 -266.967775) (xy 97.983039 -266.967775) (xy 97.974914 -267.01907)
			(xy 97.958866 -267.068463) (xy 97.935288 -267.114737) (xy 97.904762 -267.156753) (xy 97.868039 -267.193476)
			(xy 97.826023 -267.224002) (xy 97.779749 -267.24758) (xy 97.730356 -267.263628) (xy 97.679061 -267.271753)
			(xy 97.627127 -267.271753) (xy 97.575832 -267.263628) (xy 97.526439 -267.24758) (xy 97.480165 -267.224002)
			(xy 97.438149 -267.193476) (xy 97.401426 -267.156753) (xy 97.3709 -267.114737) (xy 97.347322 -267.068463)
			(xy 97.331274 -267.01907) (xy 97.323149 -266.967775) (xy 97.043493 -266.967775) (xy 97.035368 -267.01907)
			(xy 97.01932 -267.068463) (xy 96.995742 -267.114737) (xy 96.965216 -267.156753) (xy 96.928493 -267.193476)
			(xy 96.886477 -267.224002) (xy 96.840203 -267.24758) (xy 96.79081 -267.263628) (xy 96.739515 -267.271753)
			(xy 96.687581 -267.271753) (xy 96.636286 -267.263628) (xy 96.586893 -267.24758) (xy 96.540619 -267.224002)
			(xy 96.498603 -267.193476) (xy 96.46188 -267.156753) (xy 96.431354 -267.114737) (xy 96.407776 -267.068463)
			(xy 96.391728 -267.01907) (xy 96.383603 -266.967775) (xy 96.103943 -266.967775) (xy 96.103943 -266.968554)
			(xy 96.095339 -267.021351) (xy 96.078355 -267.072076) (xy 96.066356 -267.095986) (xy 96.066102 -267.096748)
			(xy 96.063308 -267.102336) (xy 96.060514 -267.113258) (xy 96.060514 -267.331444) (xy 96.061089 -267.342688)
			(xy 96.070706 -267.363011) (xy 96.079056 -267.37056) (xy 96.139254 -267.420344) (xy 96.143672 -267.423815)
			(xy 96.153671 -267.428933) (xy 96.159066 -267.430504) (xy 96.169734 -267.433298) (xy 96.181164 -267.431012)
			(xy 96.196384 -267.428283) (xy 96.22717 -267.425355) (xy 96.242632 -267.42517) (xy 96.243394 -267.42517)
			(xy 96.269385 -267.425653) (xy 96.320728 -267.433784) (xy 96.370167 -267.449847) (xy 96.416484 -267.473446)
			(xy 96.458539 -267.504) (xy 96.495296 -267.540757) (xy 96.525851 -267.582811) (xy 96.549451 -267.629128)
			(xy 96.565515 -267.678566) (xy 96.573647 -267.729909) (xy 96.573647 -267.781845) (xy 96.853503 -267.781845)
			(xy 96.853503 -267.729911) (xy 96.861628 -267.678616) (xy 96.877676 -267.629223) (xy 96.901254 -267.582949)
			(xy 96.93178 -267.540933) (xy 96.968503 -267.50421) (xy 97.010519 -267.473684) (xy 97.056793 -267.450106)
			(xy 97.106186 -267.434058) (xy 97.157481 -267.425933) (xy 97.209415 -267.425933) (xy 97.26071 -267.434058)
			(xy 97.310103 -267.450106) (xy 97.356377 -267.473684) (xy 97.398393 -267.50421) (xy 97.435116 -267.540933)
			(xy 97.465642 -267.582949) (xy 97.48922 -267.629223) (xy 97.505268 -267.678616) (xy 97.513393 -267.729911)
			(xy 97.513902 -267.755878) (xy 97.513393 -267.781845) (xy 97.793049 -267.781845) (xy 97.793049 -267.729911)
			(xy 97.801174 -267.678616) (xy 97.817222 -267.629223) (xy 97.8408 -267.582949) (xy 97.871326 -267.540933)
			(xy 97.908049 -267.50421) (xy 97.950065 -267.473684) (xy 97.996339 -267.450106) (xy 98.045732 -267.434058)
			(xy 98.097027 -267.425933) (xy 98.148961 -267.425933) (xy 98.200256 -267.434058) (xy 98.249649 -267.450106)
			(xy 98.295923 -267.473684) (xy 98.337939 -267.50421) (xy 98.374662 -267.540933) (xy 98.405188 -267.582949)
			(xy 98.428766 -267.629223) (xy 98.444814 -267.678616) (xy 98.452939 -267.729911) (xy 98.453448 -267.755878)
			(xy 98.452939 -267.781845) (xy 98.732849 -267.781845) (xy 98.732849 -267.729911) (xy 98.740974 -267.678616)
			(xy 98.757022 -267.629223) (xy 98.7806 -267.582949) (xy 98.811126 -267.540933) (xy 98.847849 -267.50421)
			(xy 98.889865 -267.473684) (xy 98.936139 -267.450106) (xy 98.985532 -267.434058) (xy 99.036827 -267.425933)
			(xy 99.088761 -267.425933) (xy 99.140056 -267.434058) (xy 99.189449 -267.450106) (xy 99.235723 -267.473684)
			(xy 99.277739 -267.50421) (xy 99.314462 -267.540933) (xy 99.344988 -267.582949) (xy 99.368566 -267.629223)
			(xy 99.384614 -267.678616) (xy 99.392739 -267.729911) (xy 99.393248 -267.755878) (xy 99.392739 -267.781845)
			(xy 99.672649 -267.781845) (xy 99.672649 -267.729911) (xy 99.680774 -267.678616) (xy 99.696822 -267.629223)
			(xy 99.7204 -267.582949) (xy 99.750926 -267.540933) (xy 99.787649 -267.50421) (xy 99.829665 -267.473684)
			(xy 99.875939 -267.450106) (xy 99.925332 -267.434058) (xy 99.976627 -267.425933) (xy 100.028561 -267.425933)
			(xy 100.079856 -267.434058) (xy 100.129249 -267.450106) (xy 100.175523 -267.473684) (xy 100.217539 -267.50421)
			(xy 100.254262 -267.540933) (xy 100.284788 -267.582949) (xy 100.308366 -267.629223) (xy 100.324414 -267.678616)
			(xy 100.332539 -267.729911) (xy 100.333048 -267.755878) (xy 100.332539 -267.781845) (xy 100.612449 -267.781845)
			(xy 100.612449 -267.729911) (xy 100.620574 -267.678616) (xy 100.636622 -267.629223) (xy 100.6602 -267.582949)
			(xy 100.690726 -267.540933) (xy 100.727449 -267.50421) (xy 100.769465 -267.473684) (xy 100.815739 -267.450106)
			(xy 100.865132 -267.434058) (xy 100.916427 -267.425933) (xy 100.968361 -267.425933) (xy 101.019656 -267.434058)
			(xy 101.069049 -267.450106) (xy 101.115323 -267.473684) (xy 101.157339 -267.50421) (xy 101.194062 -267.540933)
			(xy 101.224588 -267.582949) (xy 101.248166 -267.629223) (xy 101.264214 -267.678616) (xy 101.272339 -267.729911)
			(xy 101.272848 -267.755878) (xy 101.272339 -267.781845) (xy 101.552249 -267.781845) (xy 101.552249 -267.729911)
			(xy 101.560374 -267.678616) (xy 101.576422 -267.629223) (xy 101.6 -267.582949) (xy 101.630526 -267.540933)
			(xy 101.667249 -267.50421) (xy 101.709265 -267.473684) (xy 101.755539 -267.450106) (xy 101.804932 -267.434058)
			(xy 101.856227 -267.425933) (xy 101.908161 -267.425933) (xy 101.959456 -267.434058) (xy 102.008849 -267.450106)
			(xy 102.055123 -267.473684) (xy 102.097139 -267.50421) (xy 102.133862 -267.540933) (xy 102.164388 -267.582949)
			(xy 102.187966 -267.629223) (xy 102.204014 -267.678616) (xy 102.212139 -267.729911) (xy 102.212648 -267.755878)
			(xy 102.212139 -267.781845) (xy 102.492049 -267.781845) (xy 102.492049 -267.729911) (xy 102.500174 -267.678616)
			(xy 102.516222 -267.629223) (xy 102.5398 -267.582949) (xy 102.570326 -267.540933) (xy 102.607049 -267.50421)
			(xy 102.649065 -267.473684) (xy 102.695339 -267.450106) (xy 102.744732 -267.434058) (xy 102.796027 -267.425933)
			(xy 102.847961 -267.425933) (xy 102.899256 -267.434058) (xy 102.948649 -267.450106) (xy 102.994923 -267.473684)
			(xy 103.036939 -267.50421) (xy 103.073662 -267.540933) (xy 103.104188 -267.582949) (xy 103.127766 -267.629223)
			(xy 103.143814 -267.678616) (xy 103.151939 -267.729911) (xy 103.152448 -267.755878) (xy 103.151939 -267.781845)
			(xy 103.431849 -267.781845) (xy 103.431849 -267.729911) (xy 103.439974 -267.678616) (xy 103.456022 -267.629223)
			(xy 103.4796 -267.582949) (xy 103.510126 -267.540933) (xy 103.546849 -267.50421) (xy 103.588865 -267.473684)
			(xy 103.635139 -267.450106) (xy 103.684532 -267.434058) (xy 103.735827 -267.425933) (xy 103.787761 -267.425933)
			(xy 103.839056 -267.434058) (xy 103.888449 -267.450106) (xy 103.934723 -267.473684) (xy 103.976739 -267.50421)
			(xy 104.013462 -267.540933) (xy 104.043988 -267.582949) (xy 104.067566 -267.629223) (xy 104.083614 -267.678616)
			(xy 104.091739 -267.729911) (xy 104.092248 -267.755878) (xy 104.091739 -267.781845) (xy 104.371649 -267.781845)
			(xy 104.371649 -267.729911) (xy 104.379774 -267.678616) (xy 104.395822 -267.629223) (xy 104.4194 -267.582949)
			(xy 104.449926 -267.540933) (xy 104.486649 -267.50421) (xy 104.528665 -267.473684) (xy 104.574939 -267.450106)
			(xy 104.624332 -267.434058) (xy 104.675627 -267.425933) (xy 104.727561 -267.425933) (xy 104.778856 -267.434058)
			(xy 104.828249 -267.450106) (xy 104.874523 -267.473684) (xy 104.916539 -267.50421) (xy 104.953262 -267.540933)
			(xy 104.983788 -267.582949) (xy 105.007366 -267.629223) (xy 105.023414 -267.678616) (xy 105.031539 -267.729911)
			(xy 105.032048 -267.755878) (xy 105.031539 -267.781845) (xy 105.311449 -267.781845) (xy 105.311449 -267.729911)
			(xy 105.319574 -267.678616) (xy 105.335622 -267.629223) (xy 105.3592 -267.582949) (xy 105.389726 -267.540933)
			(xy 105.426449 -267.50421) (xy 105.468465 -267.473684) (xy 105.514739 -267.450106) (xy 105.564132 -267.434058)
			(xy 105.615427 -267.425933) (xy 105.667361 -267.425933) (xy 105.718656 -267.434058) (xy 105.768049 -267.450106)
			(xy 105.814323 -267.473684) (xy 105.856339 -267.50421) (xy 105.893062 -267.540933) (xy 105.923588 -267.582949)
			(xy 105.947166 -267.629223) (xy 105.963214 -267.678616) (xy 105.971339 -267.729911) (xy 105.971848 -267.755878)
			(xy 105.971339 -267.781845) (xy 106.251249 -267.781845) (xy 106.251249 -267.729911) (xy 106.259374 -267.678616)
			(xy 106.275422 -267.629223) (xy 106.299 -267.582949) (xy 106.329526 -267.540933) (xy 106.366249 -267.50421)
			(xy 106.408265 -267.473684) (xy 106.454539 -267.450106) (xy 106.503932 -267.434058) (xy 106.555227 -267.425933)
			(xy 106.607161 -267.425933) (xy 106.658456 -267.434058) (xy 106.707849 -267.450106) (xy 106.754123 -267.473684)
			(xy 106.796139 -267.50421) (xy 106.832862 -267.540933) (xy 106.863388 -267.582949) (xy 106.886966 -267.629223)
			(xy 106.903014 -267.678616) (xy 106.911139 -267.729911) (xy 106.911648 -267.755878) (xy 106.911139 -267.781845)
			(xy 107.191049 -267.781845) (xy 107.191049 -267.729911) (xy 107.199174 -267.678616) (xy 107.215222 -267.629223)
			(xy 107.2388 -267.582949) (xy 107.269326 -267.540933) (xy 107.306049 -267.50421) (xy 107.348065 -267.473684)
			(xy 107.394339 -267.450106) (xy 107.443732 -267.434058) (xy 107.495027 -267.425933) (xy 107.546961 -267.425933)
			(xy 107.598256 -267.434058) (xy 107.647649 -267.450106) (xy 107.693923 -267.473684) (xy 107.735939 -267.50421)
			(xy 107.772662 -267.540933) (xy 107.803188 -267.582949) (xy 107.826766 -267.629223) (xy 107.842814 -267.678616)
			(xy 107.850939 -267.729911) (xy 107.851448 -267.755878) (xy 107.850939 -267.781845) (xy 108.130849 -267.781845)
			(xy 108.130849 -267.729911) (xy 108.138974 -267.678616) (xy 108.155022 -267.629223) (xy 108.1786 -267.582949)
			(xy 108.209126 -267.540933) (xy 108.245849 -267.50421) (xy 108.287865 -267.473684) (xy 108.334139 -267.450106)
			(xy 108.383532 -267.434058) (xy 108.434827 -267.425933) (xy 108.486761 -267.425933) (xy 108.538056 -267.434058)
			(xy 108.587449 -267.450106) (xy 108.633723 -267.473684) (xy 108.675739 -267.50421) (xy 108.712462 -267.540933)
			(xy 108.742988 -267.582949) (xy 108.766566 -267.629223) (xy 108.782614 -267.678616) (xy 108.790739 -267.729911)
			(xy 108.791248 -267.755878) (xy 108.790739 -267.781845) (xy 109.070649 -267.781845) (xy 109.070649 -267.729911)
			(xy 109.078774 -267.678616) (xy 109.094822 -267.629223) (xy 109.1184 -267.582949) (xy 109.148926 -267.540933)
			(xy 109.185649 -267.50421) (xy 109.227665 -267.473684) (xy 109.273939 -267.450106) (xy 109.323332 -267.434058)
			(xy 109.374627 -267.425933) (xy 109.426561 -267.425933) (xy 109.477856 -267.434058) (xy 109.527249 -267.450106)
			(xy 109.573523 -267.473684) (xy 109.615539 -267.50421) (xy 109.652262 -267.540933) (xy 109.682788 -267.582949)
			(xy 109.706366 -267.629223) (xy 109.722414 -267.678616) (xy 109.730539 -267.729911) (xy 109.731048 -267.755878)
			(xy 109.730539 -267.781845) (xy 110.010449 -267.781845) (xy 110.010449 -267.729911) (xy 110.018574 -267.678616)
			(xy 110.034622 -267.629223) (xy 110.0582 -267.582949) (xy 110.088726 -267.540933) (xy 110.125449 -267.50421)
			(xy 110.167465 -267.473684) (xy 110.213739 -267.450106) (xy 110.263132 -267.434058) (xy 110.314427 -267.425933)
			(xy 110.366361 -267.425933) (xy 110.417656 -267.434058) (xy 110.467049 -267.450106) (xy 110.513323 -267.473684)
			(xy 110.555339 -267.50421) (xy 110.592062 -267.540933) (xy 110.622588 -267.582949) (xy 110.646166 -267.629223)
			(xy 110.662214 -267.678616) (xy 110.670339 -267.729911) (xy 110.670848 -267.755878) (xy 110.670339 -267.781845)
			(xy 113.769649 -267.781845) (xy 113.769649 -267.729911) (xy 113.777774 -267.678616) (xy 113.793822 -267.629223)
			(xy 113.8174 -267.582949) (xy 113.847926 -267.540933) (xy 113.884649 -267.50421) (xy 113.926665 -267.473684)
			(xy 113.972939 -267.450106) (xy 114.022332 -267.434058) (xy 114.073627 -267.425933) (xy 114.125561 -267.425933)
			(xy 114.176856 -267.434058) (xy 114.226249 -267.450106) (xy 114.272523 -267.473684) (xy 114.314539 -267.50421)
			(xy 114.351262 -267.540933) (xy 114.381788 -267.582949) (xy 114.405366 -267.629223) (xy 114.421414 -267.678616)
			(xy 114.429539 -267.729911) (xy 114.430048 -267.755878) (xy 114.429539 -267.781845) (xy 114.421414 -267.83314)
			(xy 114.405366 -267.882533) (xy 114.381788 -267.928807) (xy 114.351262 -267.970823) (xy 114.314539 -268.007546)
			(xy 114.272523 -268.038072) (xy 114.226249 -268.06165) (xy 114.176856 -268.077698) (xy 114.125561 -268.085823)
			(xy 114.073627 -268.085823) (xy 114.022332 -268.077698) (xy 113.972939 -268.06165) (xy 113.926665 -268.038072)
			(xy 113.884649 -268.007546) (xy 113.847926 -267.970823) (xy 113.8174 -267.928807) (xy 113.793822 -267.882533)
			(xy 113.777774 -267.83314) (xy 113.769649 -267.781845) (xy 110.670339 -267.781845) (xy 110.662214 -267.83314)
			(xy 110.646166 -267.882533) (xy 110.622588 -267.928807) (xy 110.592062 -267.970823) (xy 110.555339 -268.007546)
			(xy 110.513323 -268.038072) (xy 110.467049 -268.06165) (xy 110.417656 -268.077698) (xy 110.366361 -268.085823)
			(xy 110.314427 -268.085823) (xy 110.263132 -268.077698) (xy 110.213739 -268.06165) (xy 110.167465 -268.038072)
			(xy 110.125449 -268.007546) (xy 110.088726 -267.970823) (xy 110.0582 -267.928807) (xy 110.034622 -267.882533)
			(xy 110.018574 -267.83314) (xy 110.010449 -267.781845) (xy 109.730539 -267.781845) (xy 109.722414 -267.83314)
			(xy 109.706366 -267.882533) (xy 109.682788 -267.928807) (xy 109.652262 -267.970823) (xy 109.615539 -268.007546)
			(xy 109.573523 -268.038072) (xy 109.527249 -268.06165) (xy 109.477856 -268.077698) (xy 109.426561 -268.085823)
			(xy 109.374627 -268.085823) (xy 109.323332 -268.077698) (xy 109.273939 -268.06165) (xy 109.227665 -268.038072)
			(xy 109.185649 -268.007546) (xy 109.148926 -267.970823) (xy 109.1184 -267.928807) (xy 109.094822 -267.882533)
			(xy 109.078774 -267.83314) (xy 109.070649 -267.781845) (xy 108.790739 -267.781845) (xy 108.782614 -267.83314)
			(xy 108.766566 -267.882533) (xy 108.742988 -267.928807) (xy 108.712462 -267.970823) (xy 108.675739 -268.007546)
			(xy 108.633723 -268.038072) (xy 108.587449 -268.06165) (xy 108.538056 -268.077698) (xy 108.486761 -268.085823)
			(xy 108.434827 -268.085823) (xy 108.383532 -268.077698) (xy 108.334139 -268.06165) (xy 108.287865 -268.038072)
			(xy 108.245849 -268.007546) (xy 108.209126 -267.970823) (xy 108.1786 -267.928807) (xy 108.155022 -267.882533)
			(xy 108.138974 -267.83314) (xy 108.130849 -267.781845) (xy 107.850939 -267.781845) (xy 107.842814 -267.83314)
			(xy 107.826766 -267.882533) (xy 107.803188 -267.928807) (xy 107.772662 -267.970823) (xy 107.735939 -268.007546)
			(xy 107.693923 -268.038072) (xy 107.647649 -268.06165) (xy 107.598256 -268.077698) (xy 107.546961 -268.085823)
			(xy 107.495027 -268.085823) (xy 107.443732 -268.077698) (xy 107.394339 -268.06165) (xy 107.348065 -268.038072)
			(xy 107.306049 -268.007546) (xy 107.269326 -267.970823) (xy 107.2388 -267.928807) (xy 107.215222 -267.882533)
			(xy 107.199174 -267.83314) (xy 107.191049 -267.781845) (xy 106.911139 -267.781845) (xy 106.903014 -267.83314)
			(xy 106.886966 -267.882533) (xy 106.863388 -267.928807) (xy 106.832862 -267.970823) (xy 106.796139 -268.007546)
			(xy 106.754123 -268.038072) (xy 106.707849 -268.06165) (xy 106.658456 -268.077698) (xy 106.607161 -268.085823)
			(xy 106.555227 -268.085823) (xy 106.503932 -268.077698) (xy 106.454539 -268.06165) (xy 106.408265 -268.038072)
			(xy 106.366249 -268.007546) (xy 106.329526 -267.970823) (xy 106.299 -267.928807) (xy 106.275422 -267.882533)
			(xy 106.259374 -267.83314) (xy 106.251249 -267.781845) (xy 105.971339 -267.781845) (xy 105.963214 -267.83314)
			(xy 105.947166 -267.882533) (xy 105.923588 -267.928807) (xy 105.893062 -267.970823) (xy 105.856339 -268.007546)
			(xy 105.814323 -268.038072) (xy 105.768049 -268.06165) (xy 105.718656 -268.077698) (xy 105.667361 -268.085823)
			(xy 105.615427 -268.085823) (xy 105.564132 -268.077698) (xy 105.514739 -268.06165) (xy 105.468465 -268.038072)
			(xy 105.426449 -268.007546) (xy 105.389726 -267.970823) (xy 105.3592 -267.928807) (xy 105.335622 -267.882533)
			(xy 105.319574 -267.83314) (xy 105.311449 -267.781845) (xy 105.031539 -267.781845) (xy 105.023414 -267.83314)
			(xy 105.007366 -267.882533) (xy 104.983788 -267.928807) (xy 104.953262 -267.970823) (xy 104.916539 -268.007546)
			(xy 104.874523 -268.038072) (xy 104.828249 -268.06165) (xy 104.778856 -268.077698) (xy 104.727561 -268.085823)
			(xy 104.675627 -268.085823) (xy 104.624332 -268.077698) (xy 104.574939 -268.06165) (xy 104.528665 -268.038072)
			(xy 104.486649 -268.007546) (xy 104.449926 -267.970823) (xy 104.4194 -267.928807) (xy 104.395822 -267.882533)
			(xy 104.379774 -267.83314) (xy 104.371649 -267.781845) (xy 104.091739 -267.781845) (xy 104.083614 -267.83314)
			(xy 104.067566 -267.882533) (xy 104.043988 -267.928807) (xy 104.013462 -267.970823) (xy 103.976739 -268.007546)
			(xy 103.934723 -268.038072) (xy 103.888449 -268.06165) (xy 103.839056 -268.077698) (xy 103.787761 -268.085823)
			(xy 103.735827 -268.085823) (xy 103.684532 -268.077698) (xy 103.635139 -268.06165) (xy 103.588865 -268.038072)
			(xy 103.546849 -268.007546) (xy 103.510126 -267.970823) (xy 103.4796 -267.928807) (xy 103.456022 -267.882533)
			(xy 103.439974 -267.83314) (xy 103.431849 -267.781845) (xy 103.151939 -267.781845) (xy 103.143814 -267.83314)
			(xy 103.127766 -267.882533) (xy 103.104188 -267.928807) (xy 103.073662 -267.970823) (xy 103.036939 -268.007546)
			(xy 102.994923 -268.038072) (xy 102.948649 -268.06165) (xy 102.899256 -268.077698) (xy 102.847961 -268.085823)
			(xy 102.796027 -268.085823) (xy 102.744732 -268.077698) (xy 102.695339 -268.06165) (xy 102.649065 -268.038072)
			(xy 102.607049 -268.007546) (xy 102.570326 -267.970823) (xy 102.5398 -267.928807) (xy 102.516222 -267.882533)
			(xy 102.500174 -267.83314) (xy 102.492049 -267.781845) (xy 102.212139 -267.781845) (xy 102.204014 -267.83314)
			(xy 102.187966 -267.882533) (xy 102.164388 -267.928807) (xy 102.133862 -267.970823) (xy 102.097139 -268.007546)
			(xy 102.055123 -268.038072) (xy 102.008849 -268.06165) (xy 101.959456 -268.077698) (xy 101.908161 -268.085823)
			(xy 101.856227 -268.085823) (xy 101.804932 -268.077698) (xy 101.755539 -268.06165) (xy 101.709265 -268.038072)
			(xy 101.667249 -268.007546) (xy 101.630526 -267.970823) (xy 101.6 -267.928807) (xy 101.576422 -267.882533)
			(xy 101.560374 -267.83314) (xy 101.552249 -267.781845) (xy 101.272339 -267.781845) (xy 101.264214 -267.83314)
			(xy 101.248166 -267.882533) (xy 101.224588 -267.928807) (xy 101.194062 -267.970823) (xy 101.157339 -268.007546)
			(xy 101.115323 -268.038072) (xy 101.069049 -268.06165) (xy 101.019656 -268.077698) (xy 100.968361 -268.085823)
			(xy 100.916427 -268.085823) (xy 100.865132 -268.077698) (xy 100.815739 -268.06165) (xy 100.769465 -268.038072)
			(xy 100.727449 -268.007546) (xy 100.690726 -267.970823) (xy 100.6602 -267.928807) (xy 100.636622 -267.882533)
			(xy 100.620574 -267.83314) (xy 100.612449 -267.781845) (xy 100.332539 -267.781845) (xy 100.324414 -267.83314)
			(xy 100.308366 -267.882533) (xy 100.284788 -267.928807) (xy 100.254262 -267.970823) (xy 100.217539 -268.007546)
			(xy 100.175523 -268.038072) (xy 100.129249 -268.06165) (xy 100.079856 -268.077698) (xy 100.028561 -268.085823)
			(xy 99.976627 -268.085823) (xy 99.925332 -268.077698) (xy 99.875939 -268.06165) (xy 99.829665 -268.038072)
			(xy 99.787649 -268.007546) (xy 99.750926 -267.970823) (xy 99.7204 -267.928807) (xy 99.696822 -267.882533)
			(xy 99.680774 -267.83314) (xy 99.672649 -267.781845) (xy 99.392739 -267.781845) (xy 99.384614 -267.83314)
			(xy 99.368566 -267.882533) (xy 99.344988 -267.928807) (xy 99.314462 -267.970823) (xy 99.277739 -268.007546)
			(xy 99.235723 -268.038072) (xy 99.189449 -268.06165) (xy 99.140056 -268.077698) (xy 99.088761 -268.085823)
			(xy 99.036827 -268.085823) (xy 98.985532 -268.077698) (xy 98.936139 -268.06165) (xy 98.889865 -268.038072)
			(xy 98.847849 -268.007546) (xy 98.811126 -267.970823) (xy 98.7806 -267.928807) (xy 98.757022 -267.882533)
			(xy 98.740974 -267.83314) (xy 98.732849 -267.781845) (xy 98.452939 -267.781845) (xy 98.444814 -267.83314)
			(xy 98.428766 -267.882533) (xy 98.405188 -267.928807) (xy 98.374662 -267.970823) (xy 98.337939 -268.007546)
			(xy 98.295923 -268.038072) (xy 98.249649 -268.06165) (xy 98.200256 -268.077698) (xy 98.148961 -268.085823)
			(xy 98.097027 -268.085823) (xy 98.045732 -268.077698) (xy 97.996339 -268.06165) (xy 97.950065 -268.038072)
			(xy 97.908049 -268.007546) (xy 97.871326 -267.970823) (xy 97.8408 -267.928807) (xy 97.817222 -267.882533)
			(xy 97.801174 -267.83314) (xy 97.793049 -267.781845) (xy 97.513393 -267.781845) (xy 97.505268 -267.83314)
			(xy 97.48922 -267.882533) (xy 97.465642 -267.928807) (xy 97.435116 -267.970823) (xy 97.398393 -268.007546)
			(xy 97.356377 -268.038072) (xy 97.310103 -268.06165) (xy 97.26071 -268.077698) (xy 97.209415 -268.085823)
			(xy 97.157481 -268.085823) (xy 97.106186 -268.077698) (xy 97.056793 -268.06165) (xy 97.010519 -268.038072)
			(xy 96.968503 -268.007546) (xy 96.93178 -267.970823) (xy 96.901254 -267.928807) (xy 96.877676 -267.882533)
			(xy 96.861628 -267.83314) (xy 96.853503 -267.781845) (xy 96.573647 -267.781845) (xy 96.573647 -267.781891)
			(xy 96.565515 -267.833234) (xy 96.549451 -267.882672) (xy 96.525851 -267.928989) (xy 96.495296 -267.971043)
			(xy 96.458539 -268.0078) (xy 96.416484 -268.038354) (xy 96.370167 -268.061953) (xy 96.320728 -268.078016)
			(xy 96.269385 -268.086147) (xy 96.243394 -268.086586) (xy 96.242632 -268.086586) (xy 96.227171 -268.086383)
			(xy 96.196386 -268.083461) (xy 96.181164 -268.080744) (xy 96.169734 -268.078458) (xy 96.159066 -268.081252)
			(xy 96.153662 -268.082797) (xy 96.143662 -268.087924) (xy 96.139254 -268.091412) (xy 96.079056 -268.141196)
			(xy 96.070776 -268.148798) (xy 96.061167 -268.16909) (xy 96.060514 -268.180312) (xy 96.060514 -268.391894)
			(xy 96.065594 -268.413992) (xy 96.066102 -268.414754) (xy 96.066356 -268.415516) (xy 96.078362 -268.439423)
			(xy 96.095346 -268.49015) (xy 96.10395 -268.542947) (xy 96.103951 -268.595661) (xy 96.383603 -268.595661)
			(xy 96.383603 -268.543727) (xy 96.391728 -268.492432) (xy 96.407776 -268.443039) (xy 96.431354 -268.396765)
			(xy 96.46188 -268.354749) (xy 96.498603 -268.318026) (xy 96.540619 -268.2875) (xy 96.586893 -268.263922)
			(xy 96.636286 -268.247874) (xy 96.687581 -268.239749) (xy 96.739515 -268.239749) (xy 96.79081 -268.247874)
			(xy 96.840203 -268.263922) (xy 96.886477 -268.2875) (xy 96.928493 -268.318026) (xy 96.965216 -268.354749)
			(xy 96.995742 -268.396765) (xy 97.01932 -268.443039) (xy 97.035368 -268.492432) (xy 97.043493 -268.543727)
			(xy 97.044002 -268.569694) (xy 97.043493 -268.595661) (xy 97.323403 -268.595661) (xy 97.323403 -268.543727)
			(xy 97.331528 -268.492432) (xy 97.347576 -268.443039) (xy 97.371154 -268.396765) (xy 97.40168 -268.354749)
			(xy 97.438403 -268.318026) (xy 97.480419 -268.2875) (xy 97.526693 -268.263922) (xy 97.576086 -268.247874)
			(xy 97.627381 -268.239749) (xy 97.679315 -268.239749) (xy 97.73061 -268.247874) (xy 97.780003 -268.263922)
			(xy 97.826277 -268.2875) (xy 97.868293 -268.318026) (xy 97.905016 -268.354749) (xy 97.935542 -268.396765)
			(xy 97.95912 -268.443039) (xy 97.975168 -268.492432) (xy 97.983293 -268.543727) (xy 97.983802 -268.569694)
			(xy 97.983293 -268.595661) (xy 98.263203 -268.595661) (xy 98.263203 -268.543727) (xy 98.271328 -268.492432)
			(xy 98.287376 -268.443039) (xy 98.310954 -268.396765) (xy 98.34148 -268.354749) (xy 98.378203 -268.318026)
			(xy 98.420219 -268.2875) (xy 98.466493 -268.263922) (xy 98.515886 -268.247874) (xy 98.567181 -268.239749)
			(xy 98.619115 -268.239749) (xy 98.67041 -268.247874) (xy 98.719803 -268.263922) (xy 98.766077 -268.2875)
			(xy 98.808093 -268.318026) (xy 98.844816 -268.354749) (xy 98.875342 -268.396765) (xy 98.89892 -268.443039)
			(xy 98.914968 -268.492432) (xy 98.923093 -268.543727) (xy 98.923602 -268.569694) (xy 98.923093 -268.595661)
			(xy 99.203003 -268.595661) (xy 99.203003 -268.543727) (xy 99.211128 -268.492432) (xy 99.227176 -268.443039)
			(xy 99.250754 -268.396765) (xy 99.28128 -268.354749) (xy 99.318003 -268.318026) (xy 99.360019 -268.2875)
			(xy 99.406293 -268.263922) (xy 99.455686 -268.247874) (xy 99.506981 -268.239749) (xy 99.558915 -268.239749)
			(xy 99.61021 -268.247874) (xy 99.659603 -268.263922) (xy 99.705877 -268.2875) (xy 99.747893 -268.318026)
			(xy 99.784616 -268.354749) (xy 99.815142 -268.396765) (xy 99.83872 -268.443039) (xy 99.854768 -268.492432)
			(xy 99.862893 -268.543727) (xy 99.863402 -268.569694) (xy 99.862893 -268.595661) (xy 100.142803 -268.595661)
			(xy 100.142803 -268.543727) (xy 100.150928 -268.492432) (xy 100.166976 -268.443039) (xy 100.190554 -268.396765)
			(xy 100.22108 -268.354749) (xy 100.257803 -268.318026) (xy 100.299819 -268.2875) (xy 100.346093 -268.263922)
			(xy 100.395486 -268.247874) (xy 100.446781 -268.239749) (xy 100.498715 -268.239749) (xy 100.55001 -268.247874)
			(xy 100.599403 -268.263922) (xy 100.645677 -268.2875) (xy 100.687693 -268.318026) (xy 100.724416 -268.354749)
			(xy 100.754942 -268.396765) (xy 100.77852 -268.443039) (xy 100.794568 -268.492432) (xy 100.802693 -268.543727)
			(xy 100.803202 -268.569694) (xy 100.802693 -268.595661) (xy 101.082349 -268.595661) (xy 101.082349 -268.543727)
			(xy 101.090474 -268.492432) (xy 101.106522 -268.443039) (xy 101.1301 -268.396765) (xy 101.160626 -268.354749)
			(xy 101.197349 -268.318026) (xy 101.239365 -268.2875) (xy 101.285639 -268.263922) (xy 101.335032 -268.247874)
			(xy 101.386327 -268.239749) (xy 101.438261 -268.239749) (xy 101.489556 -268.247874) (xy 101.538949 -268.263922)
			(xy 101.585223 -268.2875) (xy 101.627239 -268.318026) (xy 101.663962 -268.354749) (xy 101.694488 -268.396765)
			(xy 101.718066 -268.443039) (xy 101.734114 -268.492432) (xy 101.742239 -268.543727) (xy 101.742748 -268.569694)
			(xy 101.742239 -268.595661) (xy 102.022403 -268.595661) (xy 102.022403 -268.543727) (xy 102.030528 -268.492432)
			(xy 102.046576 -268.443039) (xy 102.070154 -268.396765) (xy 102.10068 -268.354749) (xy 102.137403 -268.318026)
			(xy 102.179419 -268.2875) (xy 102.225693 -268.263922) (xy 102.275086 -268.247874) (xy 102.326381 -268.239749)
			(xy 102.378315 -268.239749) (xy 102.42961 -268.247874) (xy 102.479003 -268.263922) (xy 102.525277 -268.2875)
			(xy 102.567293 -268.318026) (xy 102.604016 -268.354749) (xy 102.634542 -268.396765) (xy 102.65812 -268.443039)
			(xy 102.674168 -268.492432) (xy 102.682293 -268.543727) (xy 102.682802 -268.569694) (xy 102.682293 -268.595661)
			(xy 102.962203 -268.595661) (xy 102.962203 -268.543727) (xy 102.970328 -268.492432) (xy 102.986376 -268.443039)
			(xy 103.009954 -268.396765) (xy 103.04048 -268.354749) (xy 103.077203 -268.318026) (xy 103.119219 -268.2875)
			(xy 103.165493 -268.263922) (xy 103.214886 -268.247874) (xy 103.266181 -268.239749) (xy 103.318115 -268.239749)
			(xy 103.36941 -268.247874) (xy 103.418803 -268.263922) (xy 103.465077 -268.2875) (xy 103.507093 -268.318026)
			(xy 103.543816 -268.354749) (xy 103.574342 -268.396765) (xy 103.59792 -268.443039) (xy 103.613968 -268.492432)
			(xy 103.622093 -268.543727) (xy 103.622602 -268.569694) (xy 103.622093 -268.595661) (xy 103.902003 -268.595661)
			(xy 103.902003 -268.543727) (xy 103.910128 -268.492432) (xy 103.926176 -268.443039) (xy 103.949754 -268.396765)
			(xy 103.98028 -268.354749) (xy 104.017003 -268.318026) (xy 104.059019 -268.2875) (xy 104.105293 -268.263922)
			(xy 104.154686 -268.247874) (xy 104.205981 -268.239749) (xy 104.257915 -268.239749) (xy 104.30921 -268.247874)
			(xy 104.358603 -268.263922) (xy 104.404877 -268.2875) (xy 104.446893 -268.318026) (xy 104.483616 -268.354749)
			(xy 104.514142 -268.396765) (xy 104.53772 -268.443039) (xy 104.553768 -268.492432) (xy 104.561893 -268.543727)
			(xy 104.562402 -268.569694) (xy 104.561893 -268.595661) (xy 104.841803 -268.595661) (xy 104.841803 -268.543727)
			(xy 104.849928 -268.492432) (xy 104.865976 -268.443039) (xy 104.889554 -268.396765) (xy 104.92008 -268.354749)
			(xy 104.956803 -268.318026) (xy 104.998819 -268.2875) (xy 105.045093 -268.263922) (xy 105.094486 -268.247874)
			(xy 105.145781 -268.239749) (xy 105.197715 -268.239749) (xy 105.24901 -268.247874) (xy 105.298403 -268.263922)
			(xy 105.344677 -268.2875) (xy 105.386693 -268.318026) (xy 105.423416 -268.354749) (xy 105.453942 -268.396765)
			(xy 105.47752 -268.443039) (xy 105.493568 -268.492432) (xy 105.501693 -268.543727) (xy 105.502202 -268.569694)
			(xy 105.501693 -268.595661) (xy 105.781603 -268.595661) (xy 105.781603 -268.543727) (xy 105.789728 -268.492432)
			(xy 105.805776 -268.443039) (xy 105.829354 -268.396765) (xy 105.85988 -268.354749) (xy 105.896603 -268.318026)
			(xy 105.938619 -268.2875) (xy 105.984893 -268.263922) (xy 106.034286 -268.247874) (xy 106.085581 -268.239749)
			(xy 106.137515 -268.239749) (xy 106.18881 -268.247874) (xy 106.238203 -268.263922) (xy 106.284477 -268.2875)
			(xy 106.326493 -268.318026) (xy 106.363216 -268.354749) (xy 106.393742 -268.396765) (xy 106.41732 -268.443039)
			(xy 106.433368 -268.492432) (xy 106.441493 -268.543727) (xy 106.442002 -268.569694) (xy 106.441493 -268.595661)
			(xy 106.721403 -268.595661) (xy 106.721403 -268.543727) (xy 106.729528 -268.492432) (xy 106.745576 -268.443039)
			(xy 106.769154 -268.396765) (xy 106.79968 -268.354749) (xy 106.836403 -268.318026) (xy 106.878419 -268.2875)
			(xy 106.924693 -268.263922) (xy 106.974086 -268.247874) (xy 107.025381 -268.239749) (xy 107.077315 -268.239749)
			(xy 107.12861 -268.247874) (xy 107.178003 -268.263922) (xy 107.224277 -268.2875) (xy 107.266293 -268.318026)
			(xy 107.303016 -268.354749) (xy 107.333542 -268.396765) (xy 107.35712 -268.443039) (xy 107.373168 -268.492432)
			(xy 107.381293 -268.543727) (xy 107.381802 -268.569694) (xy 107.381293 -268.595661) (xy 107.661203 -268.595661)
			(xy 107.661203 -268.543727) (xy 107.669328 -268.492432) (xy 107.685376 -268.443039) (xy 107.708954 -268.396765)
			(xy 107.73948 -268.354749) (xy 107.776203 -268.318026) (xy 107.818219 -268.2875) (xy 107.864493 -268.263922)
			(xy 107.913886 -268.247874) (xy 107.965181 -268.239749) (xy 108.017115 -268.239749) (xy 108.06841 -268.247874)
			(xy 108.117803 -268.263922) (xy 108.164077 -268.2875) (xy 108.206093 -268.318026) (xy 108.242816 -268.354749)
			(xy 108.273342 -268.396765) (xy 108.29692 -268.443039) (xy 108.312968 -268.492432) (xy 108.321093 -268.543727)
			(xy 108.321602 -268.569694) (xy 108.321093 -268.595661) (xy 108.600749 -268.595661) (xy 108.600749 -268.543727)
			(xy 108.608874 -268.492432) (xy 108.624922 -268.443039) (xy 108.6485 -268.396765) (xy 108.679026 -268.354749)
			(xy 108.715749 -268.318026) (xy 108.757765 -268.2875) (xy 108.804039 -268.263922) (xy 108.853432 -268.247874)
			(xy 108.904727 -268.239749) (xy 108.956661 -268.239749) (xy 109.007956 -268.247874) (xy 109.057349 -268.263922)
			(xy 109.103623 -268.2875) (xy 109.145639 -268.318026) (xy 109.182362 -268.354749) (xy 109.212888 -268.396765)
			(xy 109.236466 -268.443039) (xy 109.252514 -268.492432) (xy 109.260639 -268.543727) (xy 109.261148 -268.569694)
			(xy 109.260639 -268.595661) (xy 109.540549 -268.595661) (xy 109.540549 -268.543727) (xy 109.548674 -268.492432)
			(xy 109.564722 -268.443039) (xy 109.5883 -268.396765) (xy 109.618826 -268.354749) (xy 109.655549 -268.318026)
			(xy 109.697565 -268.2875) (xy 109.743839 -268.263922) (xy 109.793232 -268.247874) (xy 109.844527 -268.239749)
			(xy 109.896461 -268.239749) (xy 109.947756 -268.247874) (xy 109.997149 -268.263922) (xy 110.043423 -268.2875)
			(xy 110.085439 -268.318026) (xy 110.122162 -268.354749) (xy 110.152688 -268.396765) (xy 110.176266 -268.443039)
			(xy 110.192314 -268.492432) (xy 110.200439 -268.543727) (xy 110.200948 -268.569694) (xy 110.200439 -268.595661)
			(xy 113.299749 -268.595661) (xy 113.299749 -268.543727) (xy 113.307874 -268.492432) (xy 113.323922 -268.443039)
			(xy 113.3475 -268.396765) (xy 113.378026 -268.354749) (xy 113.414749 -268.318026) (xy 113.456765 -268.2875)
			(xy 113.503039 -268.263922) (xy 113.552432 -268.247874) (xy 113.603727 -268.239749) (xy 113.655661 -268.239749)
			(xy 113.706956 -268.247874) (xy 113.756349 -268.263922) (xy 113.802623 -268.2875) (xy 113.844639 -268.318026)
			(xy 113.881362 -268.354749) (xy 113.911888 -268.396765) (xy 113.935466 -268.443039) (xy 113.951514 -268.492432)
			(xy 113.959639 -268.543727) (xy 113.960148 -268.569694) (xy 113.959639 -268.595661) (xy 114.239803 -268.595661)
			(xy 114.239803 -268.543727) (xy 114.247928 -268.492432) (xy 114.263976 -268.443039) (xy 114.287554 -268.396765)
			(xy 114.31808 -268.354749) (xy 114.354803 -268.318026) (xy 114.396819 -268.2875) (xy 114.443093 -268.263922)
			(xy 114.492486 -268.247874) (xy 114.543781 -268.239749) (xy 114.595715 -268.239749) (xy 114.64701 -268.247874)
			(xy 114.696403 -268.263922) (xy 114.742677 -268.2875) (xy 114.784693 -268.318026) (xy 114.821416 -268.354749)
			(xy 114.851942 -268.396765) (xy 114.87552 -268.443039) (xy 114.891568 -268.492432) (xy 114.899693 -268.543727)
			(xy 114.900202 -268.569694) (xy 114.899693 -268.595661) (xy 114.891568 -268.646956) (xy 114.87552 -268.696349)
			(xy 114.851942 -268.742623) (xy 114.821416 -268.784639) (xy 114.784693 -268.821362) (xy 114.742677 -268.851888)
			(xy 114.696403 -268.875466) (xy 114.64701 -268.891514) (xy 114.595715 -268.899639) (xy 114.543781 -268.899639)
			(xy 114.492486 -268.891514) (xy 114.443093 -268.875466) (xy 114.396819 -268.851888) (xy 114.354803 -268.821362)
			(xy 114.31808 -268.784639) (xy 114.287554 -268.742623) (xy 114.263976 -268.696349) (xy 114.247928 -268.646956)
			(xy 114.239803 -268.595661) (xy 113.959639 -268.595661) (xy 113.951514 -268.646956) (xy 113.935466 -268.696349)
			(xy 113.911888 -268.742623) (xy 113.881362 -268.784639) (xy 113.844639 -268.821362) (xy 113.802623 -268.851888)
			(xy 113.756349 -268.875466) (xy 113.706956 -268.891514) (xy 113.655661 -268.899639) (xy 113.603727 -268.899639)
			(xy 113.552432 -268.891514) (xy 113.503039 -268.875466) (xy 113.456765 -268.851888) (xy 113.414749 -268.821362)
			(xy 113.378026 -268.784639) (xy 113.3475 -268.742623) (xy 113.323922 -268.696349) (xy 113.307874 -268.646956)
			(xy 113.299749 -268.595661) (xy 110.200439 -268.595661) (xy 110.192314 -268.646956) (xy 110.176266 -268.696349)
			(xy 110.152688 -268.742623) (xy 110.122162 -268.784639) (xy 110.085439 -268.821362) (xy 110.043423 -268.851888)
			(xy 109.997149 -268.875466) (xy 109.947756 -268.891514) (xy 109.896461 -268.899639) (xy 109.844527 -268.899639)
			(xy 109.793232 -268.891514) (xy 109.743839 -268.875466) (xy 109.697565 -268.851888) (xy 109.655549 -268.821362)
			(xy 109.618826 -268.784639) (xy 109.5883 -268.742623) (xy 109.564722 -268.696349) (xy 109.548674 -268.646956)
			(xy 109.540549 -268.595661) (xy 109.260639 -268.595661) (xy 109.252514 -268.646956) (xy 109.236466 -268.696349)
			(xy 109.212888 -268.742623) (xy 109.182362 -268.784639) (xy 109.145639 -268.821362) (xy 109.103623 -268.851888)
			(xy 109.057349 -268.875466) (xy 109.007956 -268.891514) (xy 108.956661 -268.899639) (xy 108.904727 -268.899639)
			(xy 108.853432 -268.891514) (xy 108.804039 -268.875466) (xy 108.757765 -268.851888) (xy 108.715749 -268.821362)
			(xy 108.679026 -268.784639) (xy 108.6485 -268.742623) (xy 108.624922 -268.696349) (xy 108.608874 -268.646956)
			(xy 108.600749 -268.595661) (xy 108.321093 -268.595661) (xy 108.312968 -268.646956) (xy 108.29692 -268.696349)
			(xy 108.273342 -268.742623) (xy 108.242816 -268.784639) (xy 108.206093 -268.821362) (xy 108.164077 -268.851888)
			(xy 108.117803 -268.875466) (xy 108.06841 -268.891514) (xy 108.017115 -268.899639) (xy 107.965181 -268.899639)
			(xy 107.913886 -268.891514) (xy 107.864493 -268.875466) (xy 107.818219 -268.851888) (xy 107.776203 -268.821362)
			(xy 107.73948 -268.784639) (xy 107.708954 -268.742623) (xy 107.685376 -268.696349) (xy 107.669328 -268.646956)
			(xy 107.661203 -268.595661) (xy 107.381293 -268.595661) (xy 107.373168 -268.646956) (xy 107.35712 -268.696349)
			(xy 107.333542 -268.742623) (xy 107.303016 -268.784639) (xy 107.266293 -268.821362) (xy 107.224277 -268.851888)
			(xy 107.178003 -268.875466) (xy 107.12861 -268.891514) (xy 107.077315 -268.899639) (xy 107.025381 -268.899639)
			(xy 106.974086 -268.891514) (xy 106.924693 -268.875466) (xy 106.878419 -268.851888) (xy 106.836403 -268.821362)
			(xy 106.79968 -268.784639) (xy 106.769154 -268.742623) (xy 106.745576 -268.696349) (xy 106.729528 -268.646956)
			(xy 106.721403 -268.595661) (xy 106.441493 -268.595661) (xy 106.433368 -268.646956) (xy 106.41732 -268.696349)
			(xy 106.393742 -268.742623) (xy 106.363216 -268.784639) (xy 106.326493 -268.821362) (xy 106.284477 -268.851888)
			(xy 106.238203 -268.875466) (xy 106.18881 -268.891514) (xy 106.137515 -268.899639) (xy 106.085581 -268.899639)
			(xy 106.034286 -268.891514) (xy 105.984893 -268.875466) (xy 105.938619 -268.851888) (xy 105.896603 -268.821362)
			(xy 105.85988 -268.784639) (xy 105.829354 -268.742623) (xy 105.805776 -268.696349) (xy 105.789728 -268.646956)
			(xy 105.781603 -268.595661) (xy 105.501693 -268.595661) (xy 105.493568 -268.646956) (xy 105.47752 -268.696349)
			(xy 105.453942 -268.742623) (xy 105.423416 -268.784639) (xy 105.386693 -268.821362) (xy 105.344677 -268.851888)
			(xy 105.298403 -268.875466) (xy 105.24901 -268.891514) (xy 105.197715 -268.899639) (xy 105.145781 -268.899639)
			(xy 105.094486 -268.891514) (xy 105.045093 -268.875466) (xy 104.998819 -268.851888) (xy 104.956803 -268.821362)
			(xy 104.92008 -268.784639) (xy 104.889554 -268.742623) (xy 104.865976 -268.696349) (xy 104.849928 -268.646956)
			(xy 104.841803 -268.595661) (xy 104.561893 -268.595661) (xy 104.553768 -268.646956) (xy 104.53772 -268.696349)
			(xy 104.514142 -268.742623) (xy 104.483616 -268.784639) (xy 104.446893 -268.821362) (xy 104.404877 -268.851888)
			(xy 104.358603 -268.875466) (xy 104.30921 -268.891514) (xy 104.257915 -268.899639) (xy 104.205981 -268.899639)
			(xy 104.154686 -268.891514) (xy 104.105293 -268.875466) (xy 104.059019 -268.851888) (xy 104.017003 -268.821362)
			(xy 103.98028 -268.784639) (xy 103.949754 -268.742623) (xy 103.926176 -268.696349) (xy 103.910128 -268.646956)
			(xy 103.902003 -268.595661) (xy 103.622093 -268.595661) (xy 103.613968 -268.646956) (xy 103.59792 -268.696349)
			(xy 103.574342 -268.742623) (xy 103.543816 -268.784639) (xy 103.507093 -268.821362) (xy 103.465077 -268.851888)
			(xy 103.418803 -268.875466) (xy 103.36941 -268.891514) (xy 103.318115 -268.899639) (xy 103.266181 -268.899639)
			(xy 103.214886 -268.891514) (xy 103.165493 -268.875466) (xy 103.119219 -268.851888) (xy 103.077203 -268.821362)
			(xy 103.04048 -268.784639) (xy 103.009954 -268.742623) (xy 102.986376 -268.696349) (xy 102.970328 -268.646956)
			(xy 102.962203 -268.595661) (xy 102.682293 -268.595661) (xy 102.674168 -268.646956) (xy 102.65812 -268.696349)
			(xy 102.634542 -268.742623) (xy 102.604016 -268.784639) (xy 102.567293 -268.821362) (xy 102.525277 -268.851888)
			(xy 102.479003 -268.875466) (xy 102.42961 -268.891514) (xy 102.378315 -268.899639) (xy 102.326381 -268.899639)
			(xy 102.275086 -268.891514) (xy 102.225693 -268.875466) (xy 102.179419 -268.851888) (xy 102.137403 -268.821362)
			(xy 102.10068 -268.784639) (xy 102.070154 -268.742623) (xy 102.046576 -268.696349) (xy 102.030528 -268.646956)
			(xy 102.022403 -268.595661) (xy 101.742239 -268.595661) (xy 101.734114 -268.646956) (xy 101.718066 -268.696349)
			(xy 101.694488 -268.742623) (xy 101.663962 -268.784639) (xy 101.627239 -268.821362) (xy 101.585223 -268.851888)
			(xy 101.538949 -268.875466) (xy 101.489556 -268.891514) (xy 101.438261 -268.899639) (xy 101.386327 -268.899639)
			(xy 101.335032 -268.891514) (xy 101.285639 -268.875466) (xy 101.239365 -268.851888) (xy 101.197349 -268.821362)
			(xy 101.160626 -268.784639) (xy 101.1301 -268.742623) (xy 101.106522 -268.696349) (xy 101.090474 -268.646956)
			(xy 101.082349 -268.595661) (xy 100.802693 -268.595661) (xy 100.794568 -268.646956) (xy 100.77852 -268.696349)
			(xy 100.754942 -268.742623) (xy 100.724416 -268.784639) (xy 100.687693 -268.821362) (xy 100.645677 -268.851888)
			(xy 100.599403 -268.875466) (xy 100.55001 -268.891514) (xy 100.498715 -268.899639) (xy 100.446781 -268.899639)
			(xy 100.395486 -268.891514) (xy 100.346093 -268.875466) (xy 100.299819 -268.851888) (xy 100.257803 -268.821362)
			(xy 100.22108 -268.784639) (xy 100.190554 -268.742623) (xy 100.166976 -268.696349) (xy 100.150928 -268.646956)
			(xy 100.142803 -268.595661) (xy 99.862893 -268.595661) (xy 99.854768 -268.646956) (xy 99.83872 -268.696349)
			(xy 99.815142 -268.742623) (xy 99.784616 -268.784639) (xy 99.747893 -268.821362) (xy 99.705877 -268.851888)
			(xy 99.659603 -268.875466) (xy 99.61021 -268.891514) (xy 99.558915 -268.899639) (xy 99.506981 -268.899639)
			(xy 99.455686 -268.891514) (xy 99.406293 -268.875466) (xy 99.360019 -268.851888) (xy 99.318003 -268.821362)
			(xy 99.28128 -268.784639) (xy 99.250754 -268.742623) (xy 99.227176 -268.696349) (xy 99.211128 -268.646956)
			(xy 99.203003 -268.595661) (xy 98.923093 -268.595661) (xy 98.914968 -268.646956) (xy 98.89892 -268.696349)
			(xy 98.875342 -268.742623) (xy 98.844816 -268.784639) (xy 98.808093 -268.821362) (xy 98.766077 -268.851888)
			(xy 98.719803 -268.875466) (xy 98.67041 -268.891514) (xy 98.619115 -268.899639) (xy 98.567181 -268.899639)
			(xy 98.515886 -268.891514) (xy 98.466493 -268.875466) (xy 98.420219 -268.851888) (xy 98.378203 -268.821362)
			(xy 98.34148 -268.784639) (xy 98.310954 -268.742623) (xy 98.287376 -268.696349) (xy 98.271328 -268.646956)
			(xy 98.263203 -268.595661) (xy 97.983293 -268.595661) (xy 97.975168 -268.646956) (xy 97.95912 -268.696349)
			(xy 97.935542 -268.742623) (xy 97.905016 -268.784639) (xy 97.868293 -268.821362) (xy 97.826277 -268.851888)
			(xy 97.780003 -268.875466) (xy 97.73061 -268.891514) (xy 97.679315 -268.899639) (xy 97.627381 -268.899639)
			(xy 97.576086 -268.891514) (xy 97.526693 -268.875466) (xy 97.480419 -268.851888) (xy 97.438403 -268.821362)
			(xy 97.40168 -268.784639) (xy 97.371154 -268.742623) (xy 97.347576 -268.696349) (xy 97.331528 -268.646956)
			(xy 97.323403 -268.595661) (xy 97.043493 -268.595661) (xy 97.035368 -268.646956) (xy 97.01932 -268.696349)
			(xy 96.995742 -268.742623) (xy 96.965216 -268.784639) (xy 96.928493 -268.821362) (xy 96.886477 -268.851888)
			(xy 96.840203 -268.875466) (xy 96.79081 -268.891514) (xy 96.739515 -268.899639) (xy 96.687581 -268.899639)
			(xy 96.636286 -268.891514) (xy 96.586893 -268.875466) (xy 96.540619 -268.851888) (xy 96.498603 -268.821362)
			(xy 96.46188 -268.784639) (xy 96.431354 -268.742623) (xy 96.407776 -268.696349) (xy 96.391728 -268.646956)
			(xy 96.383603 -268.595661) (xy 96.103951 -268.595661) (xy 96.103951 -268.596442) (xy 96.095348 -268.64924)
			(xy 96.078366 -268.699967) (xy 96.066356 -268.723872) (xy 96.066102 -268.724634) (xy 96.063308 -268.730222)
			(xy 96.060514 -268.741144) (xy 96.060514 -268.959076) (xy 96.061095 -268.970316) (xy 96.070721 -268.990629)
			(xy 96.079056 -268.998192) (xy 96.139254 -269.047976) (xy 96.14367 -269.051451) (xy 96.153668 -269.056576)
			(xy 96.159066 -269.058136) (xy 96.169734 -269.06093) (xy 96.181164 -269.058644) (xy 96.196384 -269.055915)
			(xy 96.22717 -269.052986) (xy 96.242632 -269.052802) (xy 96.243394 -269.052802) (xy 96.269383 -269.053285)
			(xy 96.320721 -269.061415) (xy 96.370154 -269.077476) (xy 96.416467 -269.101073) (xy 96.458518 -269.131624)
			(xy 96.495272 -269.168377) (xy 96.525824 -269.210428) (xy 96.549422 -269.25674) (xy 96.565484 -269.306174)
			(xy 96.573615 -269.357511) (xy 96.573615 -269.409477) (xy 96.853249 -269.409477) (xy 96.853249 -269.357543)
			(xy 96.861374 -269.306248) (xy 96.877422 -269.256855) (xy 96.901 -269.210581) (xy 96.931526 -269.168565)
			(xy 96.968249 -269.131842) (xy 97.010265 -269.101316) (xy 97.056539 -269.077738) (xy 97.105932 -269.06169)
			(xy 97.157227 -269.053565) (xy 97.209161 -269.053565) (xy 97.260456 -269.06169) (xy 97.309849 -269.077738)
			(xy 97.356123 -269.101316) (xy 97.398139 -269.131842) (xy 97.434862 -269.168565) (xy 97.465388 -269.210581)
			(xy 97.488966 -269.256855) (xy 97.505014 -269.306248) (xy 97.513139 -269.357543) (xy 97.513648 -269.38351)
			(xy 97.513139 -269.409477) (xy 97.793303 -269.409477) (xy 97.793303 -269.357543) (xy 97.801428 -269.306248)
			(xy 97.817476 -269.256855) (xy 97.841054 -269.210581) (xy 97.87158 -269.168565) (xy 97.908303 -269.131842)
			(xy 97.950319 -269.101316) (xy 97.996593 -269.077738) (xy 98.045986 -269.06169) (xy 98.097281 -269.053565)
			(xy 98.149215 -269.053565) (xy 98.20051 -269.06169) (xy 98.249903 -269.077738) (xy 98.296177 -269.101316)
			(xy 98.338193 -269.131842) (xy 98.374916 -269.168565) (xy 98.405442 -269.210581) (xy 98.42902 -269.256855)
			(xy 98.445068 -269.306248) (xy 98.453193 -269.357543) (xy 98.453702 -269.38351) (xy 98.453193 -269.409477)
			(xy 98.732849 -269.409477) (xy 98.732849 -269.357543) (xy 98.740974 -269.306248) (xy 98.757022 -269.256855)
			(xy 98.7806 -269.210581) (xy 98.811126 -269.168565) (xy 98.847849 -269.131842) (xy 98.889865 -269.101316)
			(xy 98.936139 -269.077738) (xy 98.985532 -269.06169) (xy 99.036827 -269.053565) (xy 99.088761 -269.053565)
			(xy 99.140056 -269.06169) (xy 99.189449 -269.077738) (xy 99.235723 -269.101316) (xy 99.277739 -269.131842)
			(xy 99.314462 -269.168565) (xy 99.344988 -269.210581) (xy 99.368566 -269.256855) (xy 99.384614 -269.306248)
			(xy 99.392739 -269.357543) (xy 99.393248 -269.38351) (xy 99.392739 -269.409477) (xy 99.672649 -269.409477)
			(xy 99.672649 -269.357543) (xy 99.680774 -269.306248) (xy 99.696822 -269.256855) (xy 99.7204 -269.210581)
			(xy 99.750926 -269.168565) (xy 99.787649 -269.131842) (xy 99.829665 -269.101316) (xy 99.875939 -269.077738)
			(xy 99.925332 -269.06169) (xy 99.976627 -269.053565) (xy 100.028561 -269.053565) (xy 100.079856 -269.06169)
			(xy 100.129249 -269.077738) (xy 100.175523 -269.101316) (xy 100.217539 -269.131842) (xy 100.254262 -269.168565)
			(xy 100.284788 -269.210581) (xy 100.308366 -269.256855) (xy 100.324414 -269.306248) (xy 100.332539 -269.357543)
			(xy 100.333048 -269.38351) (xy 100.332539 -269.409477) (xy 100.612449 -269.409477) (xy 100.612449 -269.357543)
			(xy 100.620574 -269.306248) (xy 100.636622 -269.256855) (xy 100.6602 -269.210581) (xy 100.690726 -269.168565)
			(xy 100.727449 -269.131842) (xy 100.769465 -269.101316) (xy 100.815739 -269.077738) (xy 100.865132 -269.06169)
			(xy 100.916427 -269.053565) (xy 100.968361 -269.053565) (xy 101.019656 -269.06169) (xy 101.069049 -269.077738)
			(xy 101.115323 -269.101316) (xy 101.157339 -269.131842) (xy 101.194062 -269.168565) (xy 101.224588 -269.210581)
			(xy 101.248166 -269.256855) (xy 101.264214 -269.306248) (xy 101.272339 -269.357543) (xy 101.272848 -269.38351)
			(xy 101.272339 -269.409477) (xy 101.552757 -269.409477) (xy 101.552757 -269.357543) (xy 101.560882 -269.306248)
			(xy 101.57693 -269.256855) (xy 101.600508 -269.210581) (xy 101.631034 -269.168565) (xy 101.667757 -269.131842)
			(xy 101.709773 -269.101316) (xy 101.756047 -269.077738) (xy 101.80544 -269.06169) (xy 101.856735 -269.053565)
			(xy 101.908669 -269.053565) (xy 101.959964 -269.06169) (xy 102.009357 -269.077738) (xy 102.055631 -269.101316)
			(xy 102.097647 -269.131842) (xy 102.13437 -269.168565) (xy 102.164896 -269.210581) (xy 102.188474 -269.256855)
			(xy 102.204522 -269.306248) (xy 102.212647 -269.357543) (xy 102.213156 -269.38351) (xy 102.212647 -269.409477)
			(xy 102.492049 -269.409477) (xy 102.492049 -269.357543) (xy 102.500174 -269.306248) (xy 102.516222 -269.256855)
			(xy 102.5398 -269.210581) (xy 102.570326 -269.168565) (xy 102.607049 -269.131842) (xy 102.649065 -269.101316)
			(xy 102.695339 -269.077738) (xy 102.744732 -269.06169) (xy 102.796027 -269.053565) (xy 102.847961 -269.053565)
			(xy 102.899256 -269.06169) (xy 102.948649 -269.077738) (xy 102.994923 -269.101316) (xy 103.036939 -269.131842)
			(xy 103.073662 -269.168565) (xy 103.104188 -269.210581) (xy 103.127766 -269.256855) (xy 103.143814 -269.306248)
			(xy 103.151939 -269.357543) (xy 103.152448 -269.38351) (xy 103.151939 -269.409477) (xy 103.431849 -269.409477)
			(xy 103.431849 -269.357543) (xy 103.439974 -269.306248) (xy 103.456022 -269.256855) (xy 103.4796 -269.210581)
			(xy 103.510126 -269.168565) (xy 103.546849 -269.131842) (xy 103.588865 -269.101316) (xy 103.635139 -269.077738)
			(xy 103.684532 -269.06169) (xy 103.735827 -269.053565) (xy 103.787761 -269.053565) (xy 103.839056 -269.06169)
			(xy 103.888449 -269.077738) (xy 103.934723 -269.101316) (xy 103.976739 -269.131842) (xy 104.013462 -269.168565)
			(xy 104.043988 -269.210581) (xy 104.067566 -269.256855) (xy 104.083614 -269.306248) (xy 104.091739 -269.357543)
			(xy 104.092248 -269.38351) (xy 104.091739 -269.409477) (xy 104.371649 -269.409477) (xy 104.371649 -269.357543)
			(xy 104.379774 -269.306248) (xy 104.395822 -269.256855) (xy 104.4194 -269.210581) (xy 104.449926 -269.168565)
			(xy 104.486649 -269.131842) (xy 104.528665 -269.101316) (xy 104.574939 -269.077738) (xy 104.624332 -269.06169)
			(xy 104.675627 -269.053565) (xy 104.727561 -269.053565) (xy 104.778856 -269.06169) (xy 104.828249 -269.077738)
			(xy 104.874523 -269.101316) (xy 104.916539 -269.131842) (xy 104.953262 -269.168565) (xy 104.983788 -269.210581)
			(xy 105.007366 -269.256855) (xy 105.023414 -269.306248) (xy 105.031539 -269.357543) (xy 105.032048 -269.38351)
			(xy 105.031539 -269.409477) (xy 105.311449 -269.409477) (xy 105.311449 -269.357543) (xy 105.319574 -269.306248)
			(xy 105.335622 -269.256855) (xy 105.3592 -269.210581) (xy 105.389726 -269.168565) (xy 105.426449 -269.131842)
			(xy 105.468465 -269.101316) (xy 105.514739 -269.077738) (xy 105.564132 -269.06169) (xy 105.615427 -269.053565)
			(xy 105.667361 -269.053565) (xy 105.718656 -269.06169) (xy 105.768049 -269.077738) (xy 105.814323 -269.101316)
			(xy 105.856339 -269.131842) (xy 105.893062 -269.168565) (xy 105.923588 -269.210581) (xy 105.947166 -269.256855)
			(xy 105.963214 -269.306248) (xy 105.971339 -269.357543) (xy 105.971848 -269.38351) (xy 105.971339 -269.409477)
			(xy 106.251249 -269.409477) (xy 106.251249 -269.357543) (xy 106.259374 -269.306248) (xy 106.275422 -269.256855)
			(xy 106.299 -269.210581) (xy 106.329526 -269.168565) (xy 106.366249 -269.131842) (xy 106.408265 -269.101316)
			(xy 106.454539 -269.077738) (xy 106.503932 -269.06169) (xy 106.555227 -269.053565) (xy 106.607161 -269.053565)
			(xy 106.658456 -269.06169) (xy 106.707849 -269.077738) (xy 106.754123 -269.101316) (xy 106.796139 -269.131842)
			(xy 106.832862 -269.168565) (xy 106.863388 -269.210581) (xy 106.886966 -269.256855) (xy 106.903014 -269.306248)
			(xy 106.911139 -269.357543) (xy 106.911648 -269.38351) (xy 106.911139 -269.409477) (xy 107.191049 -269.409477)
			(xy 107.191049 -269.357543) (xy 107.199174 -269.306248) (xy 107.215222 -269.256855) (xy 107.2388 -269.210581)
			(xy 107.269326 -269.168565) (xy 107.306049 -269.131842) (xy 107.348065 -269.101316) (xy 107.394339 -269.077738)
			(xy 107.443732 -269.06169) (xy 107.495027 -269.053565) (xy 107.546961 -269.053565) (xy 107.598256 -269.06169)
			(xy 107.647649 -269.077738) (xy 107.693923 -269.101316) (xy 107.735939 -269.131842) (xy 107.772662 -269.168565)
			(xy 107.803188 -269.210581) (xy 107.826766 -269.256855) (xy 107.842814 -269.306248) (xy 107.850939 -269.357543)
			(xy 107.851448 -269.38351) (xy 107.850939 -269.409477) (xy 108.130849 -269.409477) (xy 108.130849 -269.357543)
			(xy 108.138974 -269.306248) (xy 108.155022 -269.256855) (xy 108.1786 -269.210581) (xy 108.209126 -269.168565)
			(xy 108.245849 -269.131842) (xy 108.287865 -269.101316) (xy 108.334139 -269.077738) (xy 108.383532 -269.06169)
			(xy 108.434827 -269.053565) (xy 108.486761 -269.053565) (xy 108.538056 -269.06169) (xy 108.587449 -269.077738)
			(xy 108.633723 -269.101316) (xy 108.675739 -269.131842) (xy 108.712462 -269.168565) (xy 108.742988 -269.210581)
			(xy 108.766566 -269.256855) (xy 108.782614 -269.306248) (xy 108.790739 -269.357543) (xy 108.791248 -269.38351)
			(xy 108.790739 -269.409477) (xy 109.070649 -269.409477) (xy 109.070649 -269.357543) (xy 109.078774 -269.306248)
			(xy 109.094822 -269.256855) (xy 109.1184 -269.210581) (xy 109.148926 -269.168565) (xy 109.185649 -269.131842)
			(xy 109.227665 -269.101316) (xy 109.273939 -269.077738) (xy 109.323332 -269.06169) (xy 109.374627 -269.053565)
			(xy 109.426561 -269.053565) (xy 109.477856 -269.06169) (xy 109.527249 -269.077738) (xy 109.573523 -269.101316)
			(xy 109.615539 -269.131842) (xy 109.652262 -269.168565) (xy 109.682788 -269.210581) (xy 109.706366 -269.256855)
			(xy 109.722414 -269.306248) (xy 109.730539 -269.357543) (xy 109.731048 -269.38351) (xy 109.730539 -269.409477)
			(xy 110.010449 -269.409477) (xy 110.010449 -269.357543) (xy 110.018574 -269.306248) (xy 110.034622 -269.256855)
			(xy 110.0582 -269.210581) (xy 110.088726 -269.168565) (xy 110.125449 -269.131842) (xy 110.167465 -269.101316)
			(xy 110.213739 -269.077738) (xy 110.263132 -269.06169) (xy 110.314427 -269.053565) (xy 110.366361 -269.053565)
			(xy 110.417656 -269.06169) (xy 110.467049 -269.077738) (xy 110.513323 -269.101316) (xy 110.555339 -269.131842)
			(xy 110.592062 -269.168565) (xy 110.622588 -269.210581) (xy 110.646166 -269.256855) (xy 110.662214 -269.306248)
			(xy 110.670339 -269.357543) (xy 110.670848 -269.38351) (xy 110.670339 -269.409477) (xy 113.770157 -269.409477)
			(xy 113.770157 -269.357543) (xy 113.778282 -269.306248) (xy 113.79433 -269.256855) (xy 113.817908 -269.210581)
			(xy 113.848434 -269.168565) (xy 113.885157 -269.131842) (xy 113.927173 -269.101316) (xy 113.973447 -269.077738)
			(xy 114.02284 -269.06169) (xy 114.074135 -269.053565) (xy 114.126069 -269.053565) (xy 114.177364 -269.06169)
			(xy 114.226757 -269.077738) (xy 114.273031 -269.101316) (xy 114.315047 -269.131842) (xy 114.35177 -269.168565)
			(xy 114.382296 -269.210581) (xy 114.405874 -269.256855) (xy 114.421922 -269.306248) (xy 114.430047 -269.357543)
			(xy 114.430556 -269.38351) (xy 114.430047 -269.409477) (xy 114.421922 -269.460772) (xy 114.405874 -269.510165)
			(xy 114.382296 -269.556439) (xy 114.35177 -269.598455) (xy 114.315047 -269.635178) (xy 114.273031 -269.665704)
			(xy 114.226757 -269.689282) (xy 114.177364 -269.70533) (xy 114.126069 -269.713455) (xy 114.074135 -269.713455)
			(xy 114.02284 -269.70533) (xy 113.973447 -269.689282) (xy 113.927173 -269.665704) (xy 113.885157 -269.635178)
			(xy 113.848434 -269.598455) (xy 113.817908 -269.556439) (xy 113.79433 -269.510165) (xy 113.778282 -269.460772)
			(xy 113.770157 -269.409477) (xy 110.670339 -269.409477) (xy 110.662214 -269.460772) (xy 110.646166 -269.510165)
			(xy 110.622588 -269.556439) (xy 110.592062 -269.598455) (xy 110.555339 -269.635178) (xy 110.513323 -269.665704)
			(xy 110.467049 -269.689282) (xy 110.417656 -269.70533) (xy 110.366361 -269.713455) (xy 110.314427 -269.713455)
			(xy 110.263132 -269.70533) (xy 110.213739 -269.689282) (xy 110.167465 -269.665704) (xy 110.125449 -269.635178)
			(xy 110.088726 -269.598455) (xy 110.0582 -269.556439) (xy 110.034622 -269.510165) (xy 110.018574 -269.460772)
			(xy 110.010449 -269.409477) (xy 109.730539 -269.409477) (xy 109.722414 -269.460772) (xy 109.706366 -269.510165)
			(xy 109.682788 -269.556439) (xy 109.652262 -269.598455) (xy 109.615539 -269.635178) (xy 109.573523 -269.665704)
			(xy 109.527249 -269.689282) (xy 109.477856 -269.70533) (xy 109.426561 -269.713455) (xy 109.374627 -269.713455)
			(xy 109.323332 -269.70533) (xy 109.273939 -269.689282) (xy 109.227665 -269.665704) (xy 109.185649 -269.635178)
			(xy 109.148926 -269.598455) (xy 109.1184 -269.556439) (xy 109.094822 -269.510165) (xy 109.078774 -269.460772)
			(xy 109.070649 -269.409477) (xy 108.790739 -269.409477) (xy 108.782614 -269.460772) (xy 108.766566 -269.510165)
			(xy 108.742988 -269.556439) (xy 108.712462 -269.598455) (xy 108.675739 -269.635178) (xy 108.633723 -269.665704)
			(xy 108.587449 -269.689282) (xy 108.538056 -269.70533) (xy 108.486761 -269.713455) (xy 108.434827 -269.713455)
			(xy 108.383532 -269.70533) (xy 108.334139 -269.689282) (xy 108.287865 -269.665704) (xy 108.245849 -269.635178)
			(xy 108.209126 -269.598455) (xy 108.1786 -269.556439) (xy 108.155022 -269.510165) (xy 108.138974 -269.460772)
			(xy 108.130849 -269.409477) (xy 107.850939 -269.409477) (xy 107.842814 -269.460772) (xy 107.826766 -269.510165)
			(xy 107.803188 -269.556439) (xy 107.772662 -269.598455) (xy 107.735939 -269.635178) (xy 107.693923 -269.665704)
			(xy 107.647649 -269.689282) (xy 107.598256 -269.70533) (xy 107.546961 -269.713455) (xy 107.495027 -269.713455)
			(xy 107.443732 -269.70533) (xy 107.394339 -269.689282) (xy 107.348065 -269.665704) (xy 107.306049 -269.635178)
			(xy 107.269326 -269.598455) (xy 107.2388 -269.556439) (xy 107.215222 -269.510165) (xy 107.199174 -269.460772)
			(xy 107.191049 -269.409477) (xy 106.911139 -269.409477) (xy 106.903014 -269.460772) (xy 106.886966 -269.510165)
			(xy 106.863388 -269.556439) (xy 106.832862 -269.598455) (xy 106.796139 -269.635178) (xy 106.754123 -269.665704)
			(xy 106.707849 -269.689282) (xy 106.658456 -269.70533) (xy 106.607161 -269.713455) (xy 106.555227 -269.713455)
			(xy 106.503932 -269.70533) (xy 106.454539 -269.689282) (xy 106.408265 -269.665704) (xy 106.366249 -269.635178)
			(xy 106.329526 -269.598455) (xy 106.299 -269.556439) (xy 106.275422 -269.510165) (xy 106.259374 -269.460772)
			(xy 106.251249 -269.409477) (xy 105.971339 -269.409477) (xy 105.963214 -269.460772) (xy 105.947166 -269.510165)
			(xy 105.923588 -269.556439) (xy 105.893062 -269.598455) (xy 105.856339 -269.635178) (xy 105.814323 -269.665704)
			(xy 105.768049 -269.689282) (xy 105.718656 -269.70533) (xy 105.667361 -269.713455) (xy 105.615427 -269.713455)
			(xy 105.564132 -269.70533) (xy 105.514739 -269.689282) (xy 105.468465 -269.665704) (xy 105.426449 -269.635178)
			(xy 105.389726 -269.598455) (xy 105.3592 -269.556439) (xy 105.335622 -269.510165) (xy 105.319574 -269.460772)
			(xy 105.311449 -269.409477) (xy 105.031539 -269.409477) (xy 105.023414 -269.460772) (xy 105.007366 -269.510165)
			(xy 104.983788 -269.556439) (xy 104.953262 -269.598455) (xy 104.916539 -269.635178) (xy 104.874523 -269.665704)
			(xy 104.828249 -269.689282) (xy 104.778856 -269.70533) (xy 104.727561 -269.713455) (xy 104.675627 -269.713455)
			(xy 104.624332 -269.70533) (xy 104.574939 -269.689282) (xy 104.528665 -269.665704) (xy 104.486649 -269.635178)
			(xy 104.449926 -269.598455) (xy 104.4194 -269.556439) (xy 104.395822 -269.510165) (xy 104.379774 -269.460772)
			(xy 104.371649 -269.409477) (xy 104.091739 -269.409477) (xy 104.083614 -269.460772) (xy 104.067566 -269.510165)
			(xy 104.043988 -269.556439) (xy 104.013462 -269.598455) (xy 103.976739 -269.635178) (xy 103.934723 -269.665704)
			(xy 103.888449 -269.689282) (xy 103.839056 -269.70533) (xy 103.787761 -269.713455) (xy 103.735827 -269.713455)
			(xy 103.684532 -269.70533) (xy 103.635139 -269.689282) (xy 103.588865 -269.665704) (xy 103.546849 -269.635178)
			(xy 103.510126 -269.598455) (xy 103.4796 -269.556439) (xy 103.456022 -269.510165) (xy 103.439974 -269.460772)
			(xy 103.431849 -269.409477) (xy 103.151939 -269.409477) (xy 103.143814 -269.460772) (xy 103.127766 -269.510165)
			(xy 103.104188 -269.556439) (xy 103.073662 -269.598455) (xy 103.036939 -269.635178) (xy 102.994923 -269.665704)
			(xy 102.948649 -269.689282) (xy 102.899256 -269.70533) (xy 102.847961 -269.713455) (xy 102.796027 -269.713455)
			(xy 102.744732 -269.70533) (xy 102.695339 -269.689282) (xy 102.649065 -269.665704) (xy 102.607049 -269.635178)
			(xy 102.570326 -269.598455) (xy 102.5398 -269.556439) (xy 102.516222 -269.510165) (xy 102.500174 -269.460772)
			(xy 102.492049 -269.409477) (xy 102.212647 -269.409477) (xy 102.204522 -269.460772) (xy 102.188474 -269.510165)
			(xy 102.164896 -269.556439) (xy 102.13437 -269.598455) (xy 102.097647 -269.635178) (xy 102.055631 -269.665704)
			(xy 102.009357 -269.689282) (xy 101.959964 -269.70533) (xy 101.908669 -269.713455) (xy 101.856735 -269.713455)
			(xy 101.80544 -269.70533) (xy 101.756047 -269.689282) (xy 101.709773 -269.665704) (xy 101.667757 -269.635178)
			(xy 101.631034 -269.598455) (xy 101.600508 -269.556439) (xy 101.57693 -269.510165) (xy 101.560882 -269.460772)
			(xy 101.552757 -269.409477) (xy 101.272339 -269.409477) (xy 101.264214 -269.460772) (xy 101.248166 -269.510165)
			(xy 101.224588 -269.556439) (xy 101.194062 -269.598455) (xy 101.157339 -269.635178) (xy 101.115323 -269.665704)
			(xy 101.069049 -269.689282) (xy 101.019656 -269.70533) (xy 100.968361 -269.713455) (xy 100.916427 -269.713455)
			(xy 100.865132 -269.70533) (xy 100.815739 -269.689282) (xy 100.769465 -269.665704) (xy 100.727449 -269.635178)
			(xy 100.690726 -269.598455) (xy 100.6602 -269.556439) (xy 100.636622 -269.510165) (xy 100.620574 -269.460772)
			(xy 100.612449 -269.409477) (xy 100.332539 -269.409477) (xy 100.324414 -269.460772) (xy 100.308366 -269.510165)
			(xy 100.284788 -269.556439) (xy 100.254262 -269.598455) (xy 100.217539 -269.635178) (xy 100.175523 -269.665704)
			(xy 100.129249 -269.689282) (xy 100.079856 -269.70533) (xy 100.028561 -269.713455) (xy 99.976627 -269.713455)
			(xy 99.925332 -269.70533) (xy 99.875939 -269.689282) (xy 99.829665 -269.665704) (xy 99.787649 -269.635178)
			(xy 99.750926 -269.598455) (xy 99.7204 -269.556439) (xy 99.696822 -269.510165) (xy 99.680774 -269.460772)
			(xy 99.672649 -269.409477) (xy 99.392739 -269.409477) (xy 99.384614 -269.460772) (xy 99.368566 -269.510165)
			(xy 99.344988 -269.556439) (xy 99.314462 -269.598455) (xy 99.277739 -269.635178) (xy 99.235723 -269.665704)
			(xy 99.189449 -269.689282) (xy 99.140056 -269.70533) (xy 99.088761 -269.713455) (xy 99.036827 -269.713455)
			(xy 98.985532 -269.70533) (xy 98.936139 -269.689282) (xy 98.889865 -269.665704) (xy 98.847849 -269.635178)
			(xy 98.811126 -269.598455) (xy 98.7806 -269.556439) (xy 98.757022 -269.510165) (xy 98.740974 -269.460772)
			(xy 98.732849 -269.409477) (xy 98.453193 -269.409477) (xy 98.445068 -269.460772) (xy 98.42902 -269.510165)
			(xy 98.405442 -269.556439) (xy 98.374916 -269.598455) (xy 98.338193 -269.635178) (xy 98.296177 -269.665704)
			(xy 98.249903 -269.689282) (xy 98.20051 -269.70533) (xy 98.149215 -269.713455) (xy 98.097281 -269.713455)
			(xy 98.045986 -269.70533) (xy 97.996593 -269.689282) (xy 97.950319 -269.665704) (xy 97.908303 -269.635178)
			(xy 97.87158 -269.598455) (xy 97.841054 -269.556439) (xy 97.817476 -269.510165) (xy 97.801428 -269.460772)
			(xy 97.793303 -269.409477) (xy 97.513139 -269.409477) (xy 97.505014 -269.460772) (xy 97.488966 -269.510165)
			(xy 97.465388 -269.556439) (xy 97.434862 -269.598455) (xy 97.398139 -269.635178) (xy 97.356123 -269.665704)
			(xy 97.309849 -269.689282) (xy 97.260456 -269.70533) (xy 97.209161 -269.713455) (xy 97.157227 -269.713455)
			(xy 97.105932 -269.70533) (xy 97.056539 -269.689282) (xy 97.010265 -269.665704) (xy 96.968249 -269.635178)
			(xy 96.931526 -269.598455) (xy 96.901 -269.556439) (xy 96.877422 -269.510165) (xy 96.861374 -269.460772)
			(xy 96.853249 -269.409477) (xy 96.573615 -269.409477) (xy 96.573615 -269.409489) (xy 96.565484 -269.460826)
			(xy 96.549422 -269.51026) (xy 96.525824 -269.556572) (xy 96.495272 -269.598623) (xy 96.458518 -269.635376)
			(xy 96.416467 -269.665927) (xy 96.370154 -269.689524) (xy 96.320721 -269.705585) (xy 96.269383 -269.713715)
			(xy 96.243394 -269.714218) (xy 96.242632 -269.714218) (xy 96.227171 -269.714015) (xy 96.196386 -269.711093)
			(xy 96.181164 -269.708376) (xy 96.169734 -269.70609) (xy 96.159066 -269.708884) (xy 96.153662 -269.71043)
			(xy 96.143664 -269.71556) (xy 96.139254 -269.719044) (xy 96.079056 -269.768828) (xy 96.070766 -269.776426)
			(xy 96.061129 -269.796717) (xy 96.060514 -269.807944) (xy 96.060514 -270.01978) (xy 96.065594 -270.041878)
			(xy 96.066102 -270.04264) (xy 96.066356 -270.043402) (xy 96.078363 -270.067309) (xy 96.095349 -270.118036)
			(xy 96.103956 -270.170835) (xy 96.103958 -270.223547) (xy 96.383603 -270.223547) (xy 96.383603 -270.171613)
			(xy 96.391728 -270.120318) (xy 96.407776 -270.070925) (xy 96.431354 -270.024651) (xy 96.46188 -269.982635)
			(xy 96.498603 -269.945912) (xy 96.540619 -269.915386) (xy 96.586893 -269.891808) (xy 96.636286 -269.87576)
			(xy 96.687581 -269.867635) (xy 96.739515 -269.867635) (xy 96.79081 -269.87576) (xy 96.840203 -269.891808)
			(xy 96.886477 -269.915386) (xy 96.928493 -269.945912) (xy 96.965216 -269.982635) (xy 96.995742 -270.024651)
			(xy 97.01932 -270.070925) (xy 97.035368 -270.120318) (xy 97.043493 -270.171613) (xy 97.044002 -270.19758)
			(xy 97.043493 -270.223547) (xy 97.323403 -270.223547) (xy 97.323403 -270.171613) (xy 97.331528 -270.120318)
			(xy 97.347576 -270.070925) (xy 97.371154 -270.024651) (xy 97.40168 -269.982635) (xy 97.438403 -269.945912)
			(xy 97.480419 -269.915386) (xy 97.526693 -269.891808) (xy 97.576086 -269.87576) (xy 97.627381 -269.867635)
			(xy 97.679315 -269.867635) (xy 97.73061 -269.87576) (xy 97.780003 -269.891808) (xy 97.826277 -269.915386)
			(xy 97.868293 -269.945912) (xy 97.905016 -269.982635) (xy 97.935542 -270.024651) (xy 97.95912 -270.070925)
			(xy 97.975168 -270.120318) (xy 97.983293 -270.171613) (xy 97.983802 -270.19758) (xy 97.983293 -270.223547)
			(xy 98.262949 -270.223547) (xy 98.262949 -270.171613) (xy 98.271074 -270.120318) (xy 98.287122 -270.070925)
			(xy 98.3107 -270.024651) (xy 98.341226 -269.982635) (xy 98.377949 -269.945912) (xy 98.419965 -269.915386)
			(xy 98.466239 -269.891808) (xy 98.515632 -269.87576) (xy 98.566927 -269.867635) (xy 98.618861 -269.867635)
			(xy 98.670156 -269.87576) (xy 98.719549 -269.891808) (xy 98.765823 -269.915386) (xy 98.807839 -269.945912)
			(xy 98.844562 -269.982635) (xy 98.875088 -270.024651) (xy 98.898666 -270.070925) (xy 98.914714 -270.120318)
			(xy 98.922839 -270.171613) (xy 98.923348 -270.19758) (xy 98.922839 -270.223547) (xy 99.203003 -270.223547)
			(xy 99.203003 -270.171613) (xy 99.211128 -270.120318) (xy 99.227176 -270.070925) (xy 99.250754 -270.024651)
			(xy 99.28128 -269.982635) (xy 99.318003 -269.945912) (xy 99.360019 -269.915386) (xy 99.406293 -269.891808)
			(xy 99.455686 -269.87576) (xy 99.506981 -269.867635) (xy 99.558915 -269.867635) (xy 99.61021 -269.87576)
			(xy 99.659603 -269.891808) (xy 99.705877 -269.915386) (xy 99.747893 -269.945912) (xy 99.784616 -269.982635)
			(xy 99.815142 -270.024651) (xy 99.83872 -270.070925) (xy 99.854768 -270.120318) (xy 99.862893 -270.171613)
			(xy 99.863402 -270.19758) (xy 99.862893 -270.223547) (xy 100.142803 -270.223547) (xy 100.142803 -270.171613)
			(xy 100.150928 -270.120318) (xy 100.166976 -270.070925) (xy 100.190554 -270.024651) (xy 100.22108 -269.982635)
			(xy 100.257803 -269.945912) (xy 100.299819 -269.915386) (xy 100.346093 -269.891808) (xy 100.395486 -269.87576)
			(xy 100.446781 -269.867635) (xy 100.498715 -269.867635) (xy 100.55001 -269.87576) (xy 100.599403 -269.891808)
			(xy 100.645677 -269.915386) (xy 100.687693 -269.945912) (xy 100.724416 -269.982635) (xy 100.754942 -270.024651)
			(xy 100.77852 -270.070925) (xy 100.794568 -270.120318) (xy 100.802693 -270.171613) (xy 100.803202 -270.19758)
			(xy 100.802693 -270.223547) (xy 101.082603 -270.223547) (xy 101.082603 -270.171613) (xy 101.090728 -270.120318)
			(xy 101.106776 -270.070925) (xy 101.130354 -270.024651) (xy 101.16088 -269.982635) (xy 101.197603 -269.945912)
			(xy 101.239619 -269.915386) (xy 101.285893 -269.891808) (xy 101.335286 -269.87576) (xy 101.386581 -269.867635)
			(xy 101.438515 -269.867635) (xy 101.48981 -269.87576) (xy 101.539203 -269.891808) (xy 101.585477 -269.915386)
			(xy 101.627493 -269.945912) (xy 101.664216 -269.982635) (xy 101.694742 -270.024651) (xy 101.71832 -270.070925)
			(xy 101.734368 -270.120318) (xy 101.742493 -270.171613) (xy 101.743002 -270.19758) (xy 101.742493 -270.223547)
			(xy 102.022403 -270.223547) (xy 102.022403 -270.171613) (xy 102.030528 -270.120318) (xy 102.046576 -270.070925)
			(xy 102.070154 -270.024651) (xy 102.10068 -269.982635) (xy 102.137403 -269.945912) (xy 102.179419 -269.915386)
			(xy 102.225693 -269.891808) (xy 102.275086 -269.87576) (xy 102.326381 -269.867635) (xy 102.378315 -269.867635)
			(xy 102.42961 -269.87576) (xy 102.479003 -269.891808) (xy 102.525277 -269.915386) (xy 102.567293 -269.945912)
			(xy 102.604016 -269.982635) (xy 102.634542 -270.024651) (xy 102.65812 -270.070925) (xy 102.674168 -270.120318)
			(xy 102.682293 -270.171613) (xy 102.682802 -270.19758) (xy 102.682293 -270.223547) (xy 102.962203 -270.223547)
			(xy 102.962203 -270.171613) (xy 102.970328 -270.120318) (xy 102.986376 -270.070925) (xy 103.009954 -270.024651)
			(xy 103.04048 -269.982635) (xy 103.077203 -269.945912) (xy 103.119219 -269.915386) (xy 103.165493 -269.891808)
			(xy 103.214886 -269.87576) (xy 103.266181 -269.867635) (xy 103.318115 -269.867635) (xy 103.36941 -269.87576)
			(xy 103.418803 -269.891808) (xy 103.465077 -269.915386) (xy 103.507093 -269.945912) (xy 103.543816 -269.982635)
			(xy 103.574342 -270.024651) (xy 103.59792 -270.070925) (xy 103.613968 -270.120318) (xy 103.622093 -270.171613)
			(xy 103.622602 -270.19758) (xy 103.622093 -270.223547) (xy 103.902003 -270.223547) (xy 103.902003 -270.171613)
			(xy 103.910128 -270.120318) (xy 103.926176 -270.070925) (xy 103.949754 -270.024651) (xy 103.98028 -269.982635)
			(xy 104.017003 -269.945912) (xy 104.059019 -269.915386) (xy 104.105293 -269.891808) (xy 104.154686 -269.87576)
			(xy 104.205981 -269.867635) (xy 104.257915 -269.867635) (xy 104.30921 -269.87576) (xy 104.358603 -269.891808)
			(xy 104.404877 -269.915386) (xy 104.446893 -269.945912) (xy 104.483616 -269.982635) (xy 104.514142 -270.024651)
			(xy 104.53772 -270.070925) (xy 104.553768 -270.120318) (xy 104.561893 -270.171613) (xy 104.562402 -270.19758)
			(xy 104.561893 -270.223547) (xy 104.841803 -270.223547) (xy 104.841803 -270.171613) (xy 104.849928 -270.120318)
			(xy 104.865976 -270.070925) (xy 104.889554 -270.024651) (xy 104.92008 -269.982635) (xy 104.956803 -269.945912)
			(xy 104.998819 -269.915386) (xy 105.045093 -269.891808) (xy 105.094486 -269.87576) (xy 105.145781 -269.867635)
			(xy 105.197715 -269.867635) (xy 105.24901 -269.87576) (xy 105.298403 -269.891808) (xy 105.344677 -269.915386)
			(xy 105.386693 -269.945912) (xy 105.423416 -269.982635) (xy 105.453942 -270.024651) (xy 105.47752 -270.070925)
			(xy 105.493568 -270.120318) (xy 105.501693 -270.171613) (xy 105.502202 -270.19758) (xy 105.501693 -270.223547)
			(xy 105.781603 -270.223547) (xy 105.781603 -270.171613) (xy 105.789728 -270.120318) (xy 105.805776 -270.070925)
			(xy 105.829354 -270.024651) (xy 105.85988 -269.982635) (xy 105.896603 -269.945912) (xy 105.938619 -269.915386)
			(xy 105.984893 -269.891808) (xy 106.034286 -269.87576) (xy 106.085581 -269.867635) (xy 106.137515 -269.867635)
			(xy 106.18881 -269.87576) (xy 106.238203 -269.891808) (xy 106.284477 -269.915386) (xy 106.326493 -269.945912)
			(xy 106.363216 -269.982635) (xy 106.393742 -270.024651) (xy 106.41732 -270.070925) (xy 106.433368 -270.120318)
			(xy 106.441493 -270.171613) (xy 106.442002 -270.19758) (xy 106.441493 -270.223547) (xy 106.721403 -270.223547)
			(xy 106.721403 -270.171613) (xy 106.729528 -270.120318) (xy 106.745576 -270.070925) (xy 106.769154 -270.024651)
			(xy 106.79968 -269.982635) (xy 106.836403 -269.945912) (xy 106.878419 -269.915386) (xy 106.924693 -269.891808)
			(xy 106.974086 -269.87576) (xy 107.025381 -269.867635) (xy 107.077315 -269.867635) (xy 107.12861 -269.87576)
			(xy 107.178003 -269.891808) (xy 107.224277 -269.915386) (xy 107.266293 -269.945912) (xy 107.303016 -269.982635)
			(xy 107.333542 -270.024651) (xy 107.35712 -270.070925) (xy 107.373168 -270.120318) (xy 107.381293 -270.171613)
			(xy 107.381802 -270.19758) (xy 107.381293 -270.223547) (xy 107.661203 -270.223547) (xy 107.661203 -270.171613)
			(xy 107.669328 -270.120318) (xy 107.685376 -270.070925) (xy 107.708954 -270.024651) (xy 107.73948 -269.982635)
			(xy 107.776203 -269.945912) (xy 107.818219 -269.915386) (xy 107.864493 -269.891808) (xy 107.913886 -269.87576)
			(xy 107.965181 -269.867635) (xy 108.017115 -269.867635) (xy 108.06841 -269.87576) (xy 108.117803 -269.891808)
			(xy 108.164077 -269.915386) (xy 108.206093 -269.945912) (xy 108.242816 -269.982635) (xy 108.273342 -270.024651)
			(xy 108.29692 -270.070925) (xy 108.312968 -270.120318) (xy 108.321093 -270.171613) (xy 108.321602 -270.19758)
			(xy 108.321093 -270.223547) (xy 108.600749 -270.223547) (xy 108.600749 -270.171613) (xy 108.608874 -270.120318)
			(xy 108.624922 -270.070925) (xy 108.6485 -270.024651) (xy 108.679026 -269.982635) (xy 108.715749 -269.945912)
			(xy 108.757765 -269.915386) (xy 108.804039 -269.891808) (xy 108.853432 -269.87576) (xy 108.904727 -269.867635)
			(xy 108.956661 -269.867635) (xy 109.007956 -269.87576) (xy 109.057349 -269.891808) (xy 109.103623 -269.915386)
			(xy 109.145639 -269.945912) (xy 109.182362 -269.982635) (xy 109.212888 -270.024651) (xy 109.236466 -270.070925)
			(xy 109.252514 -270.120318) (xy 109.260639 -270.171613) (xy 109.261148 -270.19758) (xy 109.260639 -270.223547)
			(xy 113.299749 -270.223547) (xy 113.299749 -270.171613) (xy 113.307874 -270.120318) (xy 113.323922 -270.070925)
			(xy 113.3475 -270.024651) (xy 113.378026 -269.982635) (xy 113.414749 -269.945912) (xy 113.456765 -269.915386)
			(xy 113.503039 -269.891808) (xy 113.552432 -269.87576) (xy 113.603727 -269.867635) (xy 113.655661 -269.867635)
			(xy 113.706956 -269.87576) (xy 113.756349 -269.891808) (xy 113.802623 -269.915386) (xy 113.844639 -269.945912)
			(xy 113.881362 -269.982635) (xy 113.911888 -270.024651) (xy 113.935466 -270.070925) (xy 113.951514 -270.120318)
			(xy 113.959639 -270.171613) (xy 113.960148 -270.19758) (xy 113.959639 -270.223547) (xy 114.239549 -270.223547)
			(xy 114.239549 -270.171613) (xy 114.247674 -270.120318) (xy 114.263722 -270.070925) (xy 114.2873 -270.024651)
			(xy 114.317826 -269.982635) (xy 114.354549 -269.945912) (xy 114.396565 -269.915386) (xy 114.442839 -269.891808)
			(xy 114.492232 -269.87576) (xy 114.543527 -269.867635) (xy 114.595461 -269.867635) (xy 114.646756 -269.87576)
			(xy 114.696149 -269.891808) (xy 114.742423 -269.915386) (xy 114.784439 -269.945912) (xy 114.821162 -269.982635)
			(xy 114.851688 -270.024651) (xy 114.875266 -270.070925) (xy 114.891314 -270.120318) (xy 114.899439 -270.171613)
			(xy 114.899948 -270.19758) (xy 114.899439 -270.223547) (xy 114.891314 -270.274842) (xy 114.875266 -270.324235)
			(xy 114.851688 -270.370509) (xy 114.821162 -270.412525) (xy 114.784439 -270.449248) (xy 114.742423 -270.479774)
			(xy 114.696149 -270.503352) (xy 114.646756 -270.5194) (xy 114.595461 -270.527525) (xy 114.543527 -270.527525)
			(xy 114.492232 -270.5194) (xy 114.442839 -270.503352) (xy 114.396565 -270.479774) (xy 114.354549 -270.449248)
			(xy 114.317826 -270.412525) (xy 114.2873 -270.370509) (xy 114.263722 -270.324235) (xy 114.247674 -270.274842)
			(xy 114.239549 -270.223547) (xy 113.959639 -270.223547) (xy 113.951514 -270.274842) (xy 113.935466 -270.324235)
			(xy 113.911888 -270.370509) (xy 113.881362 -270.412525) (xy 113.844639 -270.449248) (xy 113.802623 -270.479774)
			(xy 113.756349 -270.503352) (xy 113.706956 -270.5194) (xy 113.655661 -270.527525) (xy 113.603727 -270.527525)
			(xy 113.552432 -270.5194) (xy 113.503039 -270.503352) (xy 113.456765 -270.479774) (xy 113.414749 -270.449248)
			(xy 113.378026 -270.412525) (xy 113.3475 -270.370509) (xy 113.323922 -270.324235) (xy 113.307874 -270.274842)
			(xy 113.299749 -270.223547) (xy 109.260639 -270.223547) (xy 109.252514 -270.274842) (xy 109.236466 -270.324235)
			(xy 109.212888 -270.370509) (xy 109.182362 -270.412525) (xy 109.145639 -270.449248) (xy 109.103623 -270.479774)
			(xy 109.057349 -270.503352) (xy 109.007956 -270.5194) (xy 108.956661 -270.527525) (xy 108.904727 -270.527525)
			(xy 108.853432 -270.5194) (xy 108.804039 -270.503352) (xy 108.757765 -270.479774) (xy 108.715749 -270.449248)
			(xy 108.679026 -270.412525) (xy 108.6485 -270.370509) (xy 108.624922 -270.324235) (xy 108.608874 -270.274842)
			(xy 108.600749 -270.223547) (xy 108.321093 -270.223547) (xy 108.312968 -270.274842) (xy 108.29692 -270.324235)
			(xy 108.273342 -270.370509) (xy 108.242816 -270.412525) (xy 108.206093 -270.449248) (xy 108.164077 -270.479774)
			(xy 108.117803 -270.503352) (xy 108.06841 -270.5194) (xy 108.017115 -270.527525) (xy 107.965181 -270.527525)
			(xy 107.913886 -270.5194) (xy 107.864493 -270.503352) (xy 107.818219 -270.479774) (xy 107.776203 -270.449248)
			(xy 107.73948 -270.412525) (xy 107.708954 -270.370509) (xy 107.685376 -270.324235) (xy 107.669328 -270.274842)
			(xy 107.661203 -270.223547) (xy 107.381293 -270.223547) (xy 107.373168 -270.274842) (xy 107.35712 -270.324235)
			(xy 107.333542 -270.370509) (xy 107.303016 -270.412525) (xy 107.266293 -270.449248) (xy 107.224277 -270.479774)
			(xy 107.178003 -270.503352) (xy 107.12861 -270.5194) (xy 107.077315 -270.527525) (xy 107.025381 -270.527525)
			(xy 106.974086 -270.5194) (xy 106.924693 -270.503352) (xy 106.878419 -270.479774) (xy 106.836403 -270.449248)
			(xy 106.79968 -270.412525) (xy 106.769154 -270.370509) (xy 106.745576 -270.324235) (xy 106.729528 -270.274842)
			(xy 106.721403 -270.223547) (xy 106.441493 -270.223547) (xy 106.433368 -270.274842) (xy 106.41732 -270.324235)
			(xy 106.393742 -270.370509) (xy 106.363216 -270.412525) (xy 106.326493 -270.449248) (xy 106.284477 -270.479774)
			(xy 106.238203 -270.503352) (xy 106.18881 -270.5194) (xy 106.137515 -270.527525) (xy 106.085581 -270.527525)
			(xy 106.034286 -270.5194) (xy 105.984893 -270.503352) (xy 105.938619 -270.479774) (xy 105.896603 -270.449248)
			(xy 105.85988 -270.412525) (xy 105.829354 -270.370509) (xy 105.805776 -270.324235) (xy 105.789728 -270.274842)
			(xy 105.781603 -270.223547) (xy 105.501693 -270.223547) (xy 105.493568 -270.274842) (xy 105.47752 -270.324235)
			(xy 105.453942 -270.370509) (xy 105.423416 -270.412525) (xy 105.386693 -270.449248) (xy 105.344677 -270.479774)
			(xy 105.298403 -270.503352) (xy 105.24901 -270.5194) (xy 105.197715 -270.527525) (xy 105.145781 -270.527525)
			(xy 105.094486 -270.5194) (xy 105.045093 -270.503352) (xy 104.998819 -270.479774) (xy 104.956803 -270.449248)
			(xy 104.92008 -270.412525) (xy 104.889554 -270.370509) (xy 104.865976 -270.324235) (xy 104.849928 -270.274842)
			(xy 104.841803 -270.223547) (xy 104.561893 -270.223547) (xy 104.553768 -270.274842) (xy 104.53772 -270.324235)
			(xy 104.514142 -270.370509) (xy 104.483616 -270.412525) (xy 104.446893 -270.449248) (xy 104.404877 -270.479774)
			(xy 104.358603 -270.503352) (xy 104.30921 -270.5194) (xy 104.257915 -270.527525) (xy 104.205981 -270.527525)
			(xy 104.154686 -270.5194) (xy 104.105293 -270.503352) (xy 104.059019 -270.479774) (xy 104.017003 -270.449248)
			(xy 103.98028 -270.412525) (xy 103.949754 -270.370509) (xy 103.926176 -270.324235) (xy 103.910128 -270.274842)
			(xy 103.902003 -270.223547) (xy 103.622093 -270.223547) (xy 103.613968 -270.274842) (xy 103.59792 -270.324235)
			(xy 103.574342 -270.370509) (xy 103.543816 -270.412525) (xy 103.507093 -270.449248) (xy 103.465077 -270.479774)
			(xy 103.418803 -270.503352) (xy 103.36941 -270.5194) (xy 103.318115 -270.527525) (xy 103.266181 -270.527525)
			(xy 103.214886 -270.5194) (xy 103.165493 -270.503352) (xy 103.119219 -270.479774) (xy 103.077203 -270.449248)
			(xy 103.04048 -270.412525) (xy 103.009954 -270.370509) (xy 102.986376 -270.324235) (xy 102.970328 -270.274842)
			(xy 102.962203 -270.223547) (xy 102.682293 -270.223547) (xy 102.674168 -270.274842) (xy 102.65812 -270.324235)
			(xy 102.634542 -270.370509) (xy 102.604016 -270.412525) (xy 102.567293 -270.449248) (xy 102.525277 -270.479774)
			(xy 102.479003 -270.503352) (xy 102.42961 -270.5194) (xy 102.378315 -270.527525) (xy 102.326381 -270.527525)
			(xy 102.275086 -270.5194) (xy 102.225693 -270.503352) (xy 102.179419 -270.479774) (xy 102.137403 -270.449248)
			(xy 102.10068 -270.412525) (xy 102.070154 -270.370509) (xy 102.046576 -270.324235) (xy 102.030528 -270.274842)
			(xy 102.022403 -270.223547) (xy 101.742493 -270.223547) (xy 101.734368 -270.274842) (xy 101.71832 -270.324235)
			(xy 101.694742 -270.370509) (xy 101.664216 -270.412525) (xy 101.627493 -270.449248) (xy 101.585477 -270.479774)
			(xy 101.539203 -270.503352) (xy 101.48981 -270.5194) (xy 101.438515 -270.527525) (xy 101.386581 -270.527525)
			(xy 101.335286 -270.5194) (xy 101.285893 -270.503352) (xy 101.239619 -270.479774) (xy 101.197603 -270.449248)
			(xy 101.16088 -270.412525) (xy 101.130354 -270.370509) (xy 101.106776 -270.324235) (xy 101.090728 -270.274842)
			(xy 101.082603 -270.223547) (xy 100.802693 -270.223547) (xy 100.794568 -270.274842) (xy 100.77852 -270.324235)
			(xy 100.754942 -270.370509) (xy 100.724416 -270.412525) (xy 100.687693 -270.449248) (xy 100.645677 -270.479774)
			(xy 100.599403 -270.503352) (xy 100.55001 -270.5194) (xy 100.498715 -270.527525) (xy 100.446781 -270.527525)
			(xy 100.395486 -270.5194) (xy 100.346093 -270.503352) (xy 100.299819 -270.479774) (xy 100.257803 -270.449248)
			(xy 100.22108 -270.412525) (xy 100.190554 -270.370509) (xy 100.166976 -270.324235) (xy 100.150928 -270.274842)
			(xy 100.142803 -270.223547) (xy 99.862893 -270.223547) (xy 99.854768 -270.274842) (xy 99.83872 -270.324235)
			(xy 99.815142 -270.370509) (xy 99.784616 -270.412525) (xy 99.747893 -270.449248) (xy 99.705877 -270.479774)
			(xy 99.659603 -270.503352) (xy 99.61021 -270.5194) (xy 99.558915 -270.527525) (xy 99.506981 -270.527525)
			(xy 99.455686 -270.5194) (xy 99.406293 -270.503352) (xy 99.360019 -270.479774) (xy 99.318003 -270.449248)
			(xy 99.28128 -270.412525) (xy 99.250754 -270.370509) (xy 99.227176 -270.324235) (xy 99.211128 -270.274842)
			(xy 99.203003 -270.223547) (xy 98.922839 -270.223547) (xy 98.914714 -270.274842) (xy 98.898666 -270.324235)
			(xy 98.875088 -270.370509) (xy 98.844562 -270.412525) (xy 98.807839 -270.449248) (xy 98.765823 -270.479774)
			(xy 98.719549 -270.503352) (xy 98.670156 -270.5194) (xy 98.618861 -270.527525) (xy 98.566927 -270.527525)
			(xy 98.515632 -270.5194) (xy 98.466239 -270.503352) (xy 98.419965 -270.479774) (xy 98.377949 -270.449248)
			(xy 98.341226 -270.412525) (xy 98.3107 -270.370509) (xy 98.287122 -270.324235) (xy 98.271074 -270.274842)
			(xy 98.262949 -270.223547) (xy 97.983293 -270.223547) (xy 97.975168 -270.274842) (xy 97.95912 -270.324235)
			(xy 97.935542 -270.370509) (xy 97.905016 -270.412525) (xy 97.868293 -270.449248) (xy 97.826277 -270.479774)
			(xy 97.780003 -270.503352) (xy 97.73061 -270.5194) (xy 97.679315 -270.527525) (xy 97.627381 -270.527525)
			(xy 97.576086 -270.5194) (xy 97.526693 -270.503352) (xy 97.480419 -270.479774) (xy 97.438403 -270.449248)
			(xy 97.40168 -270.412525) (xy 97.371154 -270.370509) (xy 97.347576 -270.324235) (xy 97.331528 -270.274842)
			(xy 97.323403 -270.223547) (xy 97.043493 -270.223547) (xy 97.035368 -270.274842) (xy 97.01932 -270.324235)
			(xy 96.995742 -270.370509) (xy 96.965216 -270.412525) (xy 96.928493 -270.449248) (xy 96.886477 -270.479774)
			(xy 96.840203 -270.503352) (xy 96.79081 -270.5194) (xy 96.739515 -270.527525) (xy 96.687581 -270.527525)
			(xy 96.636286 -270.5194) (xy 96.586893 -270.503352) (xy 96.540619 -270.479774) (xy 96.498603 -270.449248)
			(xy 96.46188 -270.412525) (xy 96.431354 -270.370509) (xy 96.407776 -270.324235) (xy 96.391728 -270.274842)
			(xy 96.383603 -270.223547) (xy 96.103958 -270.223547) (xy 96.103958 -270.22433) (xy 96.095358 -270.27713)
			(xy 96.078377 -270.327859) (xy 96.066356 -270.351758) (xy 96.066102 -270.35252) (xy 96.063308 -270.358108)
			(xy 96.060514 -270.36903) (xy 96.060514 -270.586962) (xy 96.061092 -270.598204) (xy 96.070714 -270.618521)
			(xy 96.079056 -270.626078) (xy 96.139254 -270.675862) (xy 96.143673 -270.679332) (xy 96.153672 -270.684448)
			(xy 96.159066 -270.686022) (xy 96.169734 -270.688816) (xy 96.181164 -270.68653) (xy 96.196384 -270.683801)
			(xy 96.22717 -270.680872) (xy 96.242632 -270.680688) (xy 96.243394 -270.680688) (xy 96.269384 -270.681171)
			(xy 96.320724 -270.689301) (xy 96.37016 -270.705363) (xy 96.416474 -270.728961) (xy 96.458527 -270.759513)
			(xy 96.495283 -270.796268) (xy 96.525836 -270.838321) (xy 96.549435 -270.884635) (xy 96.565497 -270.93407)
			(xy 96.573629 -270.98541) (xy 96.573629 -271.037363) (xy 96.853249 -271.037363) (xy 96.853249 -270.985429)
			(xy 96.861374 -270.934134) (xy 96.877422 -270.884741) (xy 96.901 -270.838467) (xy 96.931526 -270.796451)
			(xy 96.968249 -270.759728) (xy 97.010265 -270.729202) (xy 97.056539 -270.705624) (xy 97.105932 -270.689576)
			(xy 97.157227 -270.681451) (xy 97.209161 -270.681451) (xy 97.260456 -270.689576) (xy 97.309849 -270.705624)
			(xy 97.356123 -270.729202) (xy 97.398139 -270.759728) (xy 97.434862 -270.796451) (xy 97.465388 -270.838467)
			(xy 97.488966 -270.884741) (xy 97.505014 -270.934134) (xy 97.513139 -270.985429) (xy 97.513648 -271.011396)
			(xy 97.513139 -271.037363) (xy 97.793049 -271.037363) (xy 97.793049 -270.985429) (xy 97.801174 -270.934134)
			(xy 97.817222 -270.884741) (xy 97.8408 -270.838467) (xy 97.871326 -270.796451) (xy 97.908049 -270.759728)
			(xy 97.950065 -270.729202) (xy 97.996339 -270.705624) (xy 98.045732 -270.689576) (xy 98.097027 -270.681451)
			(xy 98.148961 -270.681451) (xy 98.200256 -270.689576) (xy 98.249649 -270.705624) (xy 98.295923 -270.729202)
			(xy 98.337939 -270.759728) (xy 98.374662 -270.796451) (xy 98.405188 -270.838467) (xy 98.428766 -270.884741)
			(xy 98.444814 -270.934134) (xy 98.452939 -270.985429) (xy 98.453448 -271.011396) (xy 98.452939 -271.037363)
			(xy 98.732849 -271.037363) (xy 98.732849 -270.985429) (xy 98.740974 -270.934134) (xy 98.757022 -270.884741)
			(xy 98.7806 -270.838467) (xy 98.811126 -270.796451) (xy 98.847849 -270.759728) (xy 98.889865 -270.729202)
			(xy 98.936139 -270.705624) (xy 98.985532 -270.689576) (xy 99.036827 -270.681451) (xy 99.088761 -270.681451)
			(xy 99.140056 -270.689576) (xy 99.189449 -270.705624) (xy 99.235723 -270.729202) (xy 99.277739 -270.759728)
			(xy 99.314462 -270.796451) (xy 99.344988 -270.838467) (xy 99.368566 -270.884741) (xy 99.384614 -270.934134)
			(xy 99.392739 -270.985429) (xy 99.393248 -271.011396) (xy 99.392739 -271.037363) (xy 99.672649 -271.037363)
			(xy 99.672649 -270.985429) (xy 99.680774 -270.934134) (xy 99.696822 -270.884741) (xy 99.7204 -270.838467)
			(xy 99.750926 -270.796451) (xy 99.787649 -270.759728) (xy 99.829665 -270.729202) (xy 99.875939 -270.705624)
			(xy 99.925332 -270.689576) (xy 99.976627 -270.681451) (xy 100.028561 -270.681451) (xy 100.079856 -270.689576)
			(xy 100.129249 -270.705624) (xy 100.175523 -270.729202) (xy 100.217539 -270.759728) (xy 100.254262 -270.796451)
			(xy 100.284788 -270.838467) (xy 100.308366 -270.884741) (xy 100.324414 -270.934134) (xy 100.332539 -270.985429)
			(xy 100.333048 -271.011396) (xy 100.332539 -271.037363) (xy 100.612703 -271.037363) (xy 100.612703 -270.985429)
			(xy 100.620828 -270.934134) (xy 100.636876 -270.884741) (xy 100.660454 -270.838467) (xy 100.69098 -270.796451)
			(xy 100.727703 -270.759728) (xy 100.769719 -270.729202) (xy 100.815993 -270.705624) (xy 100.865386 -270.689576)
			(xy 100.916681 -270.681451) (xy 100.968615 -270.681451) (xy 101.01991 -270.689576) (xy 101.069303 -270.705624)
			(xy 101.115577 -270.729202) (xy 101.157593 -270.759728) (xy 101.194316 -270.796451) (xy 101.224842 -270.838467)
			(xy 101.24842 -270.884741) (xy 101.264468 -270.934134) (xy 101.272593 -270.985429) (xy 101.273102 -271.011396)
			(xy 101.272593 -271.037363) (xy 101.552503 -271.037363) (xy 101.552503 -270.985429) (xy 101.560628 -270.934134)
			(xy 101.576676 -270.884741) (xy 101.600254 -270.838467) (xy 101.63078 -270.796451) (xy 101.667503 -270.759728)
			(xy 101.709519 -270.729202) (xy 101.755793 -270.705624) (xy 101.805186 -270.689576) (xy 101.856481 -270.681451)
			(xy 101.908415 -270.681451) (xy 101.95971 -270.689576) (xy 102.009103 -270.705624) (xy 102.055377 -270.729202)
			(xy 102.097393 -270.759728) (xy 102.134116 -270.796451) (xy 102.164642 -270.838467) (xy 102.18822 -270.884741)
			(xy 102.204268 -270.934134) (xy 102.212393 -270.985429) (xy 102.212902 -271.011396) (xy 102.212393 -271.037363)
			(xy 102.492049 -271.037363) (xy 102.492049 -270.985429) (xy 102.500174 -270.934134) (xy 102.516222 -270.884741)
			(xy 102.5398 -270.838467) (xy 102.570326 -270.796451) (xy 102.607049 -270.759728) (xy 102.649065 -270.729202)
			(xy 102.695339 -270.705624) (xy 102.744732 -270.689576) (xy 102.796027 -270.681451) (xy 102.847961 -270.681451)
			(xy 102.899256 -270.689576) (xy 102.948649 -270.705624) (xy 102.994923 -270.729202) (xy 103.036939 -270.759728)
			(xy 103.073662 -270.796451) (xy 103.104188 -270.838467) (xy 103.127766 -270.884741) (xy 103.143814 -270.934134)
			(xy 103.151939 -270.985429) (xy 103.152448 -271.011396) (xy 103.151939 -271.037363) (xy 103.431849 -271.037363)
			(xy 103.431849 -270.985429) (xy 103.439974 -270.934134) (xy 103.456022 -270.884741) (xy 103.4796 -270.838467)
			(xy 103.510126 -270.796451) (xy 103.546849 -270.759728) (xy 103.588865 -270.729202) (xy 103.635139 -270.705624)
			(xy 103.684532 -270.689576) (xy 103.735827 -270.681451) (xy 103.787761 -270.681451) (xy 103.839056 -270.689576)
			(xy 103.888449 -270.705624) (xy 103.934723 -270.729202) (xy 103.976739 -270.759728) (xy 104.013462 -270.796451)
			(xy 104.043988 -270.838467) (xy 104.067566 -270.884741) (xy 104.083614 -270.934134) (xy 104.091739 -270.985429)
			(xy 104.092248 -271.011396) (xy 104.091739 -271.037363) (xy 104.371649 -271.037363) (xy 104.371649 -270.985429)
			(xy 104.379774 -270.934134) (xy 104.395822 -270.884741) (xy 104.4194 -270.838467) (xy 104.449926 -270.796451)
			(xy 104.486649 -270.759728) (xy 104.528665 -270.729202) (xy 104.574939 -270.705624) (xy 104.624332 -270.689576)
			(xy 104.675627 -270.681451) (xy 104.727561 -270.681451) (xy 104.778856 -270.689576) (xy 104.828249 -270.705624)
			(xy 104.874523 -270.729202) (xy 104.916539 -270.759728) (xy 104.953262 -270.796451) (xy 104.983788 -270.838467)
			(xy 105.007366 -270.884741) (xy 105.023414 -270.934134) (xy 105.031539 -270.985429) (xy 105.032048 -271.011396)
			(xy 105.031539 -271.037363) (xy 105.311449 -271.037363) (xy 105.311449 -270.985429) (xy 105.319574 -270.934134)
			(xy 105.335622 -270.884741) (xy 105.3592 -270.838467) (xy 105.389726 -270.796451) (xy 105.426449 -270.759728)
			(xy 105.468465 -270.729202) (xy 105.514739 -270.705624) (xy 105.564132 -270.689576) (xy 105.615427 -270.681451)
			(xy 105.667361 -270.681451) (xy 105.718656 -270.689576) (xy 105.768049 -270.705624) (xy 105.814323 -270.729202)
			(xy 105.856339 -270.759728) (xy 105.893062 -270.796451) (xy 105.923588 -270.838467) (xy 105.947166 -270.884741)
			(xy 105.963214 -270.934134) (xy 105.971339 -270.985429) (xy 105.971848 -271.011396) (xy 105.971339 -271.037363)
			(xy 106.251249 -271.037363) (xy 106.251249 -270.985429) (xy 106.259374 -270.934134) (xy 106.275422 -270.884741)
			(xy 106.299 -270.838467) (xy 106.329526 -270.796451) (xy 106.366249 -270.759728) (xy 106.408265 -270.729202)
			(xy 106.454539 -270.705624) (xy 106.503932 -270.689576) (xy 106.555227 -270.681451) (xy 106.607161 -270.681451)
			(xy 106.658456 -270.689576) (xy 106.707849 -270.705624) (xy 106.754123 -270.729202) (xy 106.796139 -270.759728)
			(xy 106.832862 -270.796451) (xy 106.863388 -270.838467) (xy 106.886966 -270.884741) (xy 106.903014 -270.934134)
			(xy 106.911139 -270.985429) (xy 106.911648 -271.011396) (xy 106.911139 -271.037363) (xy 107.191049 -271.037363)
			(xy 107.191049 -270.985429) (xy 107.199174 -270.934134) (xy 107.215222 -270.884741) (xy 107.2388 -270.838467)
			(xy 107.269326 -270.796451) (xy 107.306049 -270.759728) (xy 107.348065 -270.729202) (xy 107.394339 -270.705624)
			(xy 107.443732 -270.689576) (xy 107.495027 -270.681451) (xy 107.546961 -270.681451) (xy 107.598256 -270.689576)
			(xy 107.647649 -270.705624) (xy 107.693923 -270.729202) (xy 107.735939 -270.759728) (xy 107.772662 -270.796451)
			(xy 107.803188 -270.838467) (xy 107.826766 -270.884741) (xy 107.842814 -270.934134) (xy 107.850939 -270.985429)
			(xy 107.851448 -271.011396) (xy 107.850939 -271.037363) (xy 108.130849 -271.037363) (xy 108.130849 -270.985429)
			(xy 108.138974 -270.934134) (xy 108.155022 -270.884741) (xy 108.1786 -270.838467) (xy 108.209126 -270.796451)
			(xy 108.245849 -270.759728) (xy 108.287865 -270.729202) (xy 108.334139 -270.705624) (xy 108.383532 -270.689576)
			(xy 108.434827 -270.681451) (xy 108.486761 -270.681451) (xy 108.538056 -270.689576) (xy 108.587449 -270.705624)
			(xy 108.633723 -270.729202) (xy 108.675739 -270.759728) (xy 108.712462 -270.796451) (xy 108.742988 -270.838467)
			(xy 108.766566 -270.884741) (xy 108.782614 -270.934134) (xy 108.790739 -270.985429) (xy 108.791248 -271.011396)
			(xy 108.790739 -271.037363) (xy 109.070649 -271.037363) (xy 109.070649 -270.985429) (xy 109.078774 -270.934134)
			(xy 109.094822 -270.884741) (xy 109.1184 -270.838467) (xy 109.148926 -270.796451) (xy 109.185649 -270.759728)
			(xy 109.227665 -270.729202) (xy 109.273939 -270.705624) (xy 109.323332 -270.689576) (xy 109.374627 -270.681451)
			(xy 109.426561 -270.681451) (xy 109.477856 -270.689576) (xy 109.527249 -270.705624) (xy 109.573523 -270.729202)
			(xy 109.615539 -270.759728) (xy 109.652262 -270.796451) (xy 109.682788 -270.838467) (xy 109.706366 -270.884741)
			(xy 109.722414 -270.934134) (xy 109.730539 -270.985429) (xy 109.731048 -271.011396) (xy 109.730539 -271.037363)
			(xy 110.010449 -271.037363) (xy 110.010449 -270.985429) (xy 110.018574 -270.934134) (xy 110.034622 -270.884741)
			(xy 110.0582 -270.838467) (xy 110.088726 -270.796451) (xy 110.125449 -270.759728) (xy 110.167465 -270.729202)
			(xy 110.213739 -270.705624) (xy 110.263132 -270.689576) (xy 110.314427 -270.681451) (xy 110.366361 -270.681451)
			(xy 110.417656 -270.689576) (xy 110.467049 -270.705624) (xy 110.513323 -270.729202) (xy 110.555339 -270.759728)
			(xy 110.592062 -270.796451) (xy 110.622588 -270.838467) (xy 110.646166 -270.884741) (xy 110.662214 -270.934134)
			(xy 110.670339 -270.985429) (xy 110.670848 -271.011396) (xy 110.670339 -271.037363) (xy 113.769649 -271.037363)
			(xy 113.769649 -270.985429) (xy 113.777774 -270.934134) (xy 113.793822 -270.884741) (xy 113.8174 -270.838467)
			(xy 113.847926 -270.796451) (xy 113.884649 -270.759728) (xy 113.926665 -270.729202) (xy 113.972939 -270.705624)
			(xy 114.022332 -270.689576) (xy 114.073627 -270.681451) (xy 114.125561 -270.681451) (xy 114.176856 -270.689576)
			(xy 114.226249 -270.705624) (xy 114.272523 -270.729202) (xy 114.314539 -270.759728) (xy 114.351262 -270.796451)
			(xy 114.381788 -270.838467) (xy 114.405366 -270.884741) (xy 114.421414 -270.934134) (xy 114.429539 -270.985429)
			(xy 114.430048 -271.011396) (xy 114.429539 -271.037363) (xy 114.421414 -271.088658) (xy 114.405366 -271.138051)
			(xy 114.381788 -271.184325) (xy 114.351262 -271.226341) (xy 114.314539 -271.263064) (xy 114.272523 -271.29359)
			(xy 114.226249 -271.317168) (xy 114.176856 -271.333216) (xy 114.125561 -271.341341) (xy 114.073627 -271.341341)
			(xy 114.022332 -271.333216) (xy 113.972939 -271.317168) (xy 113.926665 -271.29359) (xy 113.884649 -271.263064)
			(xy 113.847926 -271.226341) (xy 113.8174 -271.184325) (xy 113.793822 -271.138051) (xy 113.777774 -271.088658)
			(xy 113.769649 -271.037363) (xy 110.670339 -271.037363) (xy 110.662214 -271.088658) (xy 110.646166 -271.138051)
			(xy 110.622588 -271.184325) (xy 110.592062 -271.226341) (xy 110.555339 -271.263064) (xy 110.513323 -271.29359)
			(xy 110.467049 -271.317168) (xy 110.417656 -271.333216) (xy 110.366361 -271.341341) (xy 110.314427 -271.341341)
			(xy 110.263132 -271.333216) (xy 110.213739 -271.317168) (xy 110.167465 -271.29359) (xy 110.125449 -271.263064)
			(xy 110.088726 -271.226341) (xy 110.0582 -271.184325) (xy 110.034622 -271.138051) (xy 110.018574 -271.088658)
			(xy 110.010449 -271.037363) (xy 109.730539 -271.037363) (xy 109.722414 -271.088658) (xy 109.706366 -271.138051)
			(xy 109.682788 -271.184325) (xy 109.652262 -271.226341) (xy 109.615539 -271.263064) (xy 109.573523 -271.29359)
			(xy 109.527249 -271.317168) (xy 109.477856 -271.333216) (xy 109.426561 -271.341341) (xy 109.374627 -271.341341)
			(xy 109.323332 -271.333216) (xy 109.273939 -271.317168) (xy 109.227665 -271.29359) (xy 109.185649 -271.263064)
			(xy 109.148926 -271.226341) (xy 109.1184 -271.184325) (xy 109.094822 -271.138051) (xy 109.078774 -271.088658)
			(xy 109.070649 -271.037363) (xy 108.790739 -271.037363) (xy 108.782614 -271.088658) (xy 108.766566 -271.138051)
			(xy 108.742988 -271.184325) (xy 108.712462 -271.226341) (xy 108.675739 -271.263064) (xy 108.633723 -271.29359)
			(xy 108.587449 -271.317168) (xy 108.538056 -271.333216) (xy 108.486761 -271.341341) (xy 108.434827 -271.341341)
			(xy 108.383532 -271.333216) (xy 108.334139 -271.317168) (xy 108.287865 -271.29359) (xy 108.245849 -271.263064)
			(xy 108.209126 -271.226341) (xy 108.1786 -271.184325) (xy 108.155022 -271.138051) (xy 108.138974 -271.088658)
			(xy 108.130849 -271.037363) (xy 107.850939 -271.037363) (xy 107.842814 -271.088658) (xy 107.826766 -271.138051)
			(xy 107.803188 -271.184325) (xy 107.772662 -271.226341) (xy 107.735939 -271.263064) (xy 107.693923 -271.29359)
			(xy 107.647649 -271.317168) (xy 107.598256 -271.333216) (xy 107.546961 -271.341341) (xy 107.495027 -271.341341)
			(xy 107.443732 -271.333216) (xy 107.394339 -271.317168) (xy 107.348065 -271.29359) (xy 107.306049 -271.263064)
			(xy 107.269326 -271.226341) (xy 107.2388 -271.184325) (xy 107.215222 -271.138051) (xy 107.199174 -271.088658)
			(xy 107.191049 -271.037363) (xy 106.911139 -271.037363) (xy 106.903014 -271.088658) (xy 106.886966 -271.138051)
			(xy 106.863388 -271.184325) (xy 106.832862 -271.226341) (xy 106.796139 -271.263064) (xy 106.754123 -271.29359)
			(xy 106.707849 -271.317168) (xy 106.658456 -271.333216) (xy 106.607161 -271.341341) (xy 106.555227 -271.341341)
			(xy 106.503932 -271.333216) (xy 106.454539 -271.317168) (xy 106.408265 -271.29359) (xy 106.366249 -271.263064)
			(xy 106.329526 -271.226341) (xy 106.299 -271.184325) (xy 106.275422 -271.138051) (xy 106.259374 -271.088658)
			(xy 106.251249 -271.037363) (xy 105.971339 -271.037363) (xy 105.963214 -271.088658) (xy 105.947166 -271.138051)
			(xy 105.923588 -271.184325) (xy 105.893062 -271.226341) (xy 105.856339 -271.263064) (xy 105.814323 -271.29359)
			(xy 105.768049 -271.317168) (xy 105.718656 -271.333216) (xy 105.667361 -271.341341) (xy 105.615427 -271.341341)
			(xy 105.564132 -271.333216) (xy 105.514739 -271.317168) (xy 105.468465 -271.29359) (xy 105.426449 -271.263064)
			(xy 105.389726 -271.226341) (xy 105.3592 -271.184325) (xy 105.335622 -271.138051) (xy 105.319574 -271.088658)
			(xy 105.311449 -271.037363) (xy 105.031539 -271.037363) (xy 105.023414 -271.088658) (xy 105.007366 -271.138051)
			(xy 104.983788 -271.184325) (xy 104.953262 -271.226341) (xy 104.916539 -271.263064) (xy 104.874523 -271.29359)
			(xy 104.828249 -271.317168) (xy 104.778856 -271.333216) (xy 104.727561 -271.341341) (xy 104.675627 -271.341341)
			(xy 104.624332 -271.333216) (xy 104.574939 -271.317168) (xy 104.528665 -271.29359) (xy 104.486649 -271.263064)
			(xy 104.449926 -271.226341) (xy 104.4194 -271.184325) (xy 104.395822 -271.138051) (xy 104.379774 -271.088658)
			(xy 104.371649 -271.037363) (xy 104.091739 -271.037363) (xy 104.083614 -271.088658) (xy 104.067566 -271.138051)
			(xy 104.043988 -271.184325) (xy 104.013462 -271.226341) (xy 103.976739 -271.263064) (xy 103.934723 -271.29359)
			(xy 103.888449 -271.317168) (xy 103.839056 -271.333216) (xy 103.787761 -271.341341) (xy 103.735827 -271.341341)
			(xy 103.684532 -271.333216) (xy 103.635139 -271.317168) (xy 103.588865 -271.29359) (xy 103.546849 -271.263064)
			(xy 103.510126 -271.226341) (xy 103.4796 -271.184325) (xy 103.456022 -271.138051) (xy 103.439974 -271.088658)
			(xy 103.431849 -271.037363) (xy 103.151939 -271.037363) (xy 103.143814 -271.088658) (xy 103.127766 -271.138051)
			(xy 103.104188 -271.184325) (xy 103.073662 -271.226341) (xy 103.036939 -271.263064) (xy 102.994923 -271.29359)
			(xy 102.948649 -271.317168) (xy 102.899256 -271.333216) (xy 102.847961 -271.341341) (xy 102.796027 -271.341341)
			(xy 102.744732 -271.333216) (xy 102.695339 -271.317168) (xy 102.649065 -271.29359) (xy 102.607049 -271.263064)
			(xy 102.570326 -271.226341) (xy 102.5398 -271.184325) (xy 102.516222 -271.138051) (xy 102.500174 -271.088658)
			(xy 102.492049 -271.037363) (xy 102.212393 -271.037363) (xy 102.204268 -271.088658) (xy 102.18822 -271.138051)
			(xy 102.164642 -271.184325) (xy 102.134116 -271.226341) (xy 102.097393 -271.263064) (xy 102.055377 -271.29359)
			(xy 102.009103 -271.317168) (xy 101.95971 -271.333216) (xy 101.908415 -271.341341) (xy 101.856481 -271.341341)
			(xy 101.805186 -271.333216) (xy 101.755793 -271.317168) (xy 101.709519 -271.29359) (xy 101.667503 -271.263064)
			(xy 101.63078 -271.226341) (xy 101.600254 -271.184325) (xy 101.576676 -271.138051) (xy 101.560628 -271.088658)
			(xy 101.552503 -271.037363) (xy 101.272593 -271.037363) (xy 101.264468 -271.088658) (xy 101.24842 -271.138051)
			(xy 101.224842 -271.184325) (xy 101.194316 -271.226341) (xy 101.157593 -271.263064) (xy 101.115577 -271.29359)
			(xy 101.069303 -271.317168) (xy 101.01991 -271.333216) (xy 100.968615 -271.341341) (xy 100.916681 -271.341341)
			(xy 100.865386 -271.333216) (xy 100.815993 -271.317168) (xy 100.769719 -271.29359) (xy 100.727703 -271.263064)
			(xy 100.69098 -271.226341) (xy 100.660454 -271.184325) (xy 100.636876 -271.138051) (xy 100.620828 -271.088658)
			(xy 100.612703 -271.037363) (xy 100.332539 -271.037363) (xy 100.324414 -271.088658) (xy 100.308366 -271.138051)
			(xy 100.284788 -271.184325) (xy 100.254262 -271.226341) (xy 100.217539 -271.263064) (xy 100.175523 -271.29359)
			(xy 100.129249 -271.317168) (xy 100.079856 -271.333216) (xy 100.028561 -271.341341) (xy 99.976627 -271.341341)
			(xy 99.925332 -271.333216) (xy 99.875939 -271.317168) (xy 99.829665 -271.29359) (xy 99.787649 -271.263064)
			(xy 99.750926 -271.226341) (xy 99.7204 -271.184325) (xy 99.696822 -271.138051) (xy 99.680774 -271.088658)
			(xy 99.672649 -271.037363) (xy 99.392739 -271.037363) (xy 99.384614 -271.088658) (xy 99.368566 -271.138051)
			(xy 99.344988 -271.184325) (xy 99.314462 -271.226341) (xy 99.277739 -271.263064) (xy 99.235723 -271.29359)
			(xy 99.189449 -271.317168) (xy 99.140056 -271.333216) (xy 99.088761 -271.341341) (xy 99.036827 -271.341341)
			(xy 98.985532 -271.333216) (xy 98.936139 -271.317168) (xy 98.889865 -271.29359) (xy 98.847849 -271.263064)
			(xy 98.811126 -271.226341) (xy 98.7806 -271.184325) (xy 98.757022 -271.138051) (xy 98.740974 -271.088658)
			(xy 98.732849 -271.037363) (xy 98.452939 -271.037363) (xy 98.444814 -271.088658) (xy 98.428766 -271.138051)
			(xy 98.405188 -271.184325) (xy 98.374662 -271.226341) (xy 98.337939 -271.263064) (xy 98.295923 -271.29359)
			(xy 98.249649 -271.317168) (xy 98.200256 -271.333216) (xy 98.148961 -271.341341) (xy 98.097027 -271.341341)
			(xy 98.045732 -271.333216) (xy 97.996339 -271.317168) (xy 97.950065 -271.29359) (xy 97.908049 -271.263064)
			(xy 97.871326 -271.226341) (xy 97.8408 -271.184325) (xy 97.817222 -271.138051) (xy 97.801174 -271.088658)
			(xy 97.793049 -271.037363) (xy 97.513139 -271.037363) (xy 97.505014 -271.088658) (xy 97.488966 -271.138051)
			(xy 97.465388 -271.184325) (xy 97.434862 -271.226341) (xy 97.398139 -271.263064) (xy 97.356123 -271.29359)
			(xy 97.309849 -271.317168) (xy 97.260456 -271.333216) (xy 97.209161 -271.341341) (xy 97.157227 -271.341341)
			(xy 97.105932 -271.333216) (xy 97.056539 -271.317168) (xy 97.010265 -271.29359) (xy 96.968249 -271.263064)
			(xy 96.931526 -271.226341) (xy 96.901 -271.184325) (xy 96.877422 -271.138051) (xy 96.861374 -271.088658)
			(xy 96.853249 -271.037363) (xy 96.573629 -271.037363) (xy 96.573629 -271.03739) (xy 96.565497 -271.08873)
			(xy 96.549435 -271.138165) (xy 96.525836 -271.184479) (xy 96.495283 -271.226532) (xy 96.458527 -271.263287)
			(xy 96.416474 -271.293839) (xy 96.37016 -271.317437) (xy 96.320724 -271.333499) (xy 96.269384 -271.341629)
			(xy 96.243394 -271.342104) (xy 96.242632 -271.342104) (xy 96.227171 -271.341901) (xy 96.196386 -271.338979)
			(xy 96.181164 -271.336262) (xy 96.169734 -271.333976) (xy 96.159066 -271.33677) (xy 96.153662 -271.338316)
			(xy 96.143663 -271.343444) (xy 96.139254 -271.34693) (xy 96.079056 -271.396714) (xy 96.070763 -271.404311)
			(xy 96.061121 -271.424602) (xy 96.060514 -271.43583) (xy 96.060514 -271.647412) (xy 96.065594 -271.66951)
			(xy 96.066102 -271.670272) (xy 96.066356 -271.671034) (xy 96.078361 -271.694941) (xy 96.095341 -271.745667)
			(xy 96.103943 -271.798464) (xy 96.103941 -271.851179) (xy 96.383603 -271.851179) (xy 96.383603 -271.799245)
			(xy 96.391728 -271.74795) (xy 96.407776 -271.698557) (xy 96.431354 -271.652283) (xy 96.46188 -271.610267)
			(xy 96.498603 -271.573544) (xy 96.540619 -271.543018) (xy 96.586893 -271.51944) (xy 96.636286 -271.503392)
			(xy 96.687581 -271.495267) (xy 96.739515 -271.495267) (xy 96.79081 -271.503392) (xy 96.840203 -271.51944)
			(xy 96.886477 -271.543018) (xy 96.928493 -271.573544) (xy 96.965216 -271.610267) (xy 96.995742 -271.652283)
			(xy 97.01932 -271.698557) (xy 97.035368 -271.74795) (xy 97.043493 -271.799245) (xy 97.044002 -271.825212)
			(xy 97.043493 -271.851179) (xy 97.323149 -271.851179) (xy 97.323149 -271.799245) (xy 97.331274 -271.74795)
			(xy 97.347322 -271.698557) (xy 97.3709 -271.652283) (xy 97.401426 -271.610267) (xy 97.438149 -271.573544)
			(xy 97.480165 -271.543018) (xy 97.526439 -271.51944) (xy 97.575832 -271.503392) (xy 97.627127 -271.495267)
			(xy 97.679061 -271.495267) (xy 97.730356 -271.503392) (xy 97.779749 -271.51944) (xy 97.826023 -271.543018)
			(xy 97.868039 -271.573544) (xy 97.904762 -271.610267) (xy 97.935288 -271.652283) (xy 97.958866 -271.698557)
			(xy 97.974914 -271.74795) (xy 97.983039 -271.799245) (xy 97.983548 -271.825212) (xy 97.983039 -271.851179)
			(xy 98.263203 -271.851179) (xy 98.263203 -271.799245) (xy 98.271328 -271.74795) (xy 98.287376 -271.698557)
			(xy 98.310954 -271.652283) (xy 98.34148 -271.610267) (xy 98.378203 -271.573544) (xy 98.420219 -271.543018)
			(xy 98.466493 -271.51944) (xy 98.515886 -271.503392) (xy 98.567181 -271.495267) (xy 98.619115 -271.495267)
			(xy 98.67041 -271.503392) (xy 98.719803 -271.51944) (xy 98.766077 -271.543018) (xy 98.808093 -271.573544)
			(xy 98.844816 -271.610267) (xy 98.875342 -271.652283) (xy 98.89892 -271.698557) (xy 98.914968 -271.74795)
			(xy 98.923093 -271.799245) (xy 98.923602 -271.825212) (xy 98.923093 -271.851179) (xy 99.203003 -271.851179)
			(xy 99.203003 -271.799245) (xy 99.211128 -271.74795) (xy 99.227176 -271.698557) (xy 99.250754 -271.652283)
			(xy 99.28128 -271.610267) (xy 99.318003 -271.573544) (xy 99.360019 -271.543018) (xy 99.406293 -271.51944)
			(xy 99.455686 -271.503392) (xy 99.506981 -271.495267) (xy 99.558915 -271.495267) (xy 99.61021 -271.503392)
			(xy 99.659603 -271.51944) (xy 99.705877 -271.543018) (xy 99.747893 -271.573544) (xy 99.784616 -271.610267)
			(xy 99.815142 -271.652283) (xy 99.83872 -271.698557) (xy 99.854768 -271.74795) (xy 99.862893 -271.799245)
			(xy 99.863402 -271.825212) (xy 99.862893 -271.851179) (xy 100.142803 -271.851179) (xy 100.142803 -271.799245)
			(xy 100.150928 -271.74795) (xy 100.166976 -271.698557) (xy 100.190554 -271.652283) (xy 100.22108 -271.610267)
			(xy 100.257803 -271.573544) (xy 100.299819 -271.543018) (xy 100.346093 -271.51944) (xy 100.395486 -271.503392)
			(xy 100.446781 -271.495267) (xy 100.498715 -271.495267) (xy 100.55001 -271.503392) (xy 100.599403 -271.51944)
			(xy 100.645677 -271.543018) (xy 100.687693 -271.573544) (xy 100.724416 -271.610267) (xy 100.754942 -271.652283)
			(xy 100.77852 -271.698557) (xy 100.794568 -271.74795) (xy 100.802693 -271.799245) (xy 100.803202 -271.825212)
			(xy 100.802693 -271.851179) (xy 101.082603 -271.851179) (xy 101.082603 -271.799245) (xy 101.090728 -271.74795)
			(xy 101.106776 -271.698557) (xy 101.130354 -271.652283) (xy 101.16088 -271.610267) (xy 101.197603 -271.573544)
			(xy 101.239619 -271.543018) (xy 101.285893 -271.51944) (xy 101.335286 -271.503392) (xy 101.386581 -271.495267)
			(xy 101.438515 -271.495267) (xy 101.48981 -271.503392) (xy 101.539203 -271.51944) (xy 101.585477 -271.543018)
			(xy 101.627493 -271.573544) (xy 101.664216 -271.610267) (xy 101.694742 -271.652283) (xy 101.71832 -271.698557)
			(xy 101.734368 -271.74795) (xy 101.742493 -271.799245) (xy 101.743002 -271.825212) (xy 101.742493 -271.851179)
			(xy 102.022403 -271.851179) (xy 102.022403 -271.799245) (xy 102.030528 -271.74795) (xy 102.046576 -271.698557)
			(xy 102.070154 -271.652283) (xy 102.10068 -271.610267) (xy 102.137403 -271.573544) (xy 102.179419 -271.543018)
			(xy 102.225693 -271.51944) (xy 102.275086 -271.503392) (xy 102.326381 -271.495267) (xy 102.378315 -271.495267)
			(xy 102.42961 -271.503392) (xy 102.479003 -271.51944) (xy 102.525277 -271.543018) (xy 102.567293 -271.573544)
			(xy 102.604016 -271.610267) (xy 102.634542 -271.652283) (xy 102.65812 -271.698557) (xy 102.674168 -271.74795)
			(xy 102.682293 -271.799245) (xy 102.682802 -271.825212) (xy 102.682293 -271.851179) (xy 102.962203 -271.851179)
			(xy 102.962203 -271.799245) (xy 102.970328 -271.74795) (xy 102.986376 -271.698557) (xy 103.009954 -271.652283)
			(xy 103.04048 -271.610267) (xy 103.077203 -271.573544) (xy 103.119219 -271.543018) (xy 103.165493 -271.51944)
			(xy 103.214886 -271.503392) (xy 103.266181 -271.495267) (xy 103.318115 -271.495267) (xy 103.36941 -271.503392)
			(xy 103.418803 -271.51944) (xy 103.465077 -271.543018) (xy 103.507093 -271.573544) (xy 103.543816 -271.610267)
			(xy 103.574342 -271.652283) (xy 103.59792 -271.698557) (xy 103.613968 -271.74795) (xy 103.622093 -271.799245)
			(xy 103.622602 -271.825212) (xy 103.622093 -271.851179) (xy 103.902003 -271.851179) (xy 103.902003 -271.799245)
			(xy 103.910128 -271.74795) (xy 103.926176 -271.698557) (xy 103.949754 -271.652283) (xy 103.98028 -271.610267)
			(xy 104.017003 -271.573544) (xy 104.059019 -271.543018) (xy 104.105293 -271.51944) (xy 104.154686 -271.503392)
			(xy 104.205981 -271.495267) (xy 104.257915 -271.495267) (xy 104.30921 -271.503392) (xy 104.358603 -271.51944)
			(xy 104.404877 -271.543018) (xy 104.446893 -271.573544) (xy 104.483616 -271.610267) (xy 104.514142 -271.652283)
			(xy 104.53772 -271.698557) (xy 104.553768 -271.74795) (xy 104.561893 -271.799245) (xy 104.562402 -271.825212)
			(xy 104.561893 -271.851179) (xy 104.841803 -271.851179) (xy 104.841803 -271.799245) (xy 104.849928 -271.74795)
			(xy 104.865976 -271.698557) (xy 104.889554 -271.652283) (xy 104.92008 -271.610267) (xy 104.956803 -271.573544)
			(xy 104.998819 -271.543018) (xy 105.045093 -271.51944) (xy 105.094486 -271.503392) (xy 105.145781 -271.495267)
			(xy 105.197715 -271.495267) (xy 105.24901 -271.503392) (xy 105.298403 -271.51944) (xy 105.344677 -271.543018)
			(xy 105.386693 -271.573544) (xy 105.423416 -271.610267) (xy 105.453942 -271.652283) (xy 105.47752 -271.698557)
			(xy 105.493568 -271.74795) (xy 105.501693 -271.799245) (xy 105.502202 -271.825212) (xy 105.501693 -271.851179)
			(xy 105.781603 -271.851179) (xy 105.781603 -271.799245) (xy 105.789728 -271.74795) (xy 105.805776 -271.698557)
			(xy 105.829354 -271.652283) (xy 105.85988 -271.610267) (xy 105.896603 -271.573544) (xy 105.938619 -271.543018)
			(xy 105.984893 -271.51944) (xy 106.034286 -271.503392) (xy 106.085581 -271.495267) (xy 106.137515 -271.495267)
			(xy 106.18881 -271.503392) (xy 106.238203 -271.51944) (xy 106.284477 -271.543018) (xy 106.326493 -271.573544)
			(xy 106.363216 -271.610267) (xy 106.393742 -271.652283) (xy 106.41732 -271.698557) (xy 106.433368 -271.74795)
			(xy 106.441493 -271.799245) (xy 106.442002 -271.825212) (xy 106.441493 -271.851179) (xy 106.721403 -271.851179)
			(xy 106.721403 -271.799245) (xy 106.729528 -271.74795) (xy 106.745576 -271.698557) (xy 106.769154 -271.652283)
			(xy 106.79968 -271.610267) (xy 106.836403 -271.573544) (xy 106.878419 -271.543018) (xy 106.924693 -271.51944)
			(xy 106.974086 -271.503392) (xy 107.025381 -271.495267) (xy 107.077315 -271.495267) (xy 107.12861 -271.503392)
			(xy 107.178003 -271.51944) (xy 107.224277 -271.543018) (xy 107.266293 -271.573544) (xy 107.303016 -271.610267)
			(xy 107.333542 -271.652283) (xy 107.35712 -271.698557) (xy 107.373168 -271.74795) (xy 107.381293 -271.799245)
			(xy 107.381802 -271.825212) (xy 107.381293 -271.851179) (xy 107.661203 -271.851179) (xy 107.661203 -271.799245)
			(xy 107.669328 -271.74795) (xy 107.685376 -271.698557) (xy 107.708954 -271.652283) (xy 107.73948 -271.610267)
			(xy 107.776203 -271.573544) (xy 107.818219 -271.543018) (xy 107.864493 -271.51944) (xy 107.913886 -271.503392)
			(xy 107.965181 -271.495267) (xy 108.017115 -271.495267) (xy 108.06841 -271.503392) (xy 108.117803 -271.51944)
			(xy 108.164077 -271.543018) (xy 108.206093 -271.573544) (xy 108.242816 -271.610267) (xy 108.273342 -271.652283)
			(xy 108.29692 -271.698557) (xy 108.312968 -271.74795) (xy 108.321093 -271.799245) (xy 108.321602 -271.825212)
			(xy 108.321093 -271.851179) (xy 108.601003 -271.851179) (xy 108.601003 -271.799245) (xy 108.609128 -271.74795)
			(xy 108.625176 -271.698557) (xy 108.648754 -271.652283) (xy 108.67928 -271.610267) (xy 108.716003 -271.573544)
			(xy 108.758019 -271.543018) (xy 108.804293 -271.51944) (xy 108.853686 -271.503392) (xy 108.904981 -271.495267)
			(xy 108.956915 -271.495267) (xy 109.00821 -271.503392) (xy 109.057603 -271.51944) (xy 109.103877 -271.543018)
			(xy 109.145893 -271.573544) (xy 109.182616 -271.610267) (xy 109.213142 -271.652283) (xy 109.23672 -271.698557)
			(xy 109.252768 -271.74795) (xy 109.260893 -271.799245) (xy 109.261402 -271.825212) (xy 109.260893 -271.851179)
			(xy 109.540295 -271.851179) (xy 109.540295 -271.799245) (xy 109.54842 -271.74795) (xy 109.564468 -271.698557)
			(xy 109.588046 -271.652283) (xy 109.618572 -271.610267) (xy 109.655295 -271.573544) (xy 109.697311 -271.543018)
			(xy 109.743585 -271.51944) (xy 109.792978 -271.503392) (xy 109.844273 -271.495267) (xy 109.896207 -271.495267)
			(xy 109.947502 -271.503392) (xy 109.996895 -271.51944) (xy 110.043169 -271.543018) (xy 110.085185 -271.573544)
			(xy 110.121908 -271.610267) (xy 110.152434 -271.652283) (xy 110.176012 -271.698557) (xy 110.19206 -271.74795)
			(xy 110.200185 -271.799245) (xy 110.200694 -271.825212) (xy 110.200185 -271.851179) (xy 113.299749 -271.851179)
			(xy 113.299749 -271.799245) (xy 113.307874 -271.74795) (xy 113.323922 -271.698557) (xy 113.3475 -271.652283)
			(xy 113.378026 -271.610267) (xy 113.414749 -271.573544) (xy 113.456765 -271.543018) (xy 113.503039 -271.51944)
			(xy 113.552432 -271.503392) (xy 113.603727 -271.495267) (xy 113.655661 -271.495267) (xy 113.706956 -271.503392)
			(xy 113.756349 -271.51944) (xy 113.802623 -271.543018) (xy 113.844639 -271.573544) (xy 113.881362 -271.610267)
			(xy 113.911888 -271.652283) (xy 113.935466 -271.698557) (xy 113.951514 -271.74795) (xy 113.959639 -271.799245)
			(xy 113.960148 -271.825212) (xy 113.959639 -271.851179) (xy 114.239803 -271.851179) (xy 114.239803 -271.799245)
			(xy 114.247928 -271.74795) (xy 114.263976 -271.698557) (xy 114.287554 -271.652283) (xy 114.31808 -271.610267)
			(xy 114.354803 -271.573544) (xy 114.396819 -271.543018) (xy 114.443093 -271.51944) (xy 114.492486 -271.503392)
			(xy 114.543781 -271.495267) (xy 114.595715 -271.495267) (xy 114.64701 -271.503392) (xy 114.696403 -271.51944)
			(xy 114.742677 -271.543018) (xy 114.784693 -271.573544) (xy 114.821416 -271.610267) (xy 114.851942 -271.652283)
			(xy 114.87552 -271.698557) (xy 114.891568 -271.74795) (xy 114.899693 -271.799245) (xy 114.900202 -271.825212)
			(xy 114.899693 -271.851179) (xy 114.891568 -271.902474) (xy 114.87552 -271.951867) (xy 114.851942 -271.998141)
			(xy 114.821416 -272.040157) (xy 114.784693 -272.07688) (xy 114.742677 -272.107406) (xy 114.696403 -272.130984)
			(xy 114.64701 -272.147032) (xy 114.595715 -272.155157) (xy 114.543781 -272.155157) (xy 114.492486 -272.147032)
			(xy 114.443093 -272.130984) (xy 114.396819 -272.107406) (xy 114.354803 -272.07688) (xy 114.31808 -272.040157)
			(xy 114.287554 -271.998141) (xy 114.263976 -271.951867) (xy 114.247928 -271.902474) (xy 114.239803 -271.851179)
			(xy 113.959639 -271.851179) (xy 113.951514 -271.902474) (xy 113.935466 -271.951867) (xy 113.911888 -271.998141)
			(xy 113.881362 -272.040157) (xy 113.844639 -272.07688) (xy 113.802623 -272.107406) (xy 113.756349 -272.130984)
			(xy 113.706956 -272.147032) (xy 113.655661 -272.155157) (xy 113.603727 -272.155157) (xy 113.552432 -272.147032)
			(xy 113.503039 -272.130984) (xy 113.456765 -272.107406) (xy 113.414749 -272.07688) (xy 113.378026 -272.040157)
			(xy 113.3475 -271.998141) (xy 113.323922 -271.951867) (xy 113.307874 -271.902474) (xy 113.299749 -271.851179)
			(xy 110.200185 -271.851179) (xy 110.19206 -271.902474) (xy 110.176012 -271.951867) (xy 110.152434 -271.998141)
			(xy 110.121908 -272.040157) (xy 110.085185 -272.07688) (xy 110.043169 -272.107406) (xy 109.996895 -272.130984)
			(xy 109.947502 -272.147032) (xy 109.896207 -272.155157) (xy 109.844273 -272.155157) (xy 109.792978 -272.147032)
			(xy 109.743585 -272.130984) (xy 109.697311 -272.107406) (xy 109.655295 -272.07688) (xy 109.618572 -272.040157)
			(xy 109.588046 -271.998141) (xy 109.564468 -271.951867) (xy 109.54842 -271.902474) (xy 109.540295 -271.851179)
			(xy 109.260893 -271.851179) (xy 109.252768 -271.902474) (xy 109.23672 -271.951867) (xy 109.213142 -271.998141)
			(xy 109.182616 -272.040157) (xy 109.145893 -272.07688) (xy 109.103877 -272.107406) (xy 109.057603 -272.130984)
			(xy 109.00821 -272.147032) (xy 108.956915 -272.155157) (xy 108.904981 -272.155157) (xy 108.853686 -272.147032)
			(xy 108.804293 -272.130984) (xy 108.758019 -272.107406) (xy 108.716003 -272.07688) (xy 108.67928 -272.040157)
			(xy 108.648754 -271.998141) (xy 108.625176 -271.951867) (xy 108.609128 -271.902474) (xy 108.601003 -271.851179)
			(xy 108.321093 -271.851179) (xy 108.312968 -271.902474) (xy 108.29692 -271.951867) (xy 108.273342 -271.998141)
			(xy 108.242816 -272.040157) (xy 108.206093 -272.07688) (xy 108.164077 -272.107406) (xy 108.117803 -272.130984)
			(xy 108.06841 -272.147032) (xy 108.017115 -272.155157) (xy 107.965181 -272.155157) (xy 107.913886 -272.147032)
			(xy 107.864493 -272.130984) (xy 107.818219 -272.107406) (xy 107.776203 -272.07688) (xy 107.73948 -272.040157)
			(xy 107.708954 -271.998141) (xy 107.685376 -271.951867) (xy 107.669328 -271.902474) (xy 107.661203 -271.851179)
			(xy 107.381293 -271.851179) (xy 107.373168 -271.902474) (xy 107.35712 -271.951867) (xy 107.333542 -271.998141)
			(xy 107.303016 -272.040157) (xy 107.266293 -272.07688) (xy 107.224277 -272.107406) (xy 107.178003 -272.130984)
			(xy 107.12861 -272.147032) (xy 107.077315 -272.155157) (xy 107.025381 -272.155157) (xy 106.974086 -272.147032)
			(xy 106.924693 -272.130984) (xy 106.878419 -272.107406) (xy 106.836403 -272.07688) (xy 106.79968 -272.040157)
			(xy 106.769154 -271.998141) (xy 106.745576 -271.951867) (xy 106.729528 -271.902474) (xy 106.721403 -271.851179)
			(xy 106.441493 -271.851179) (xy 106.433368 -271.902474) (xy 106.41732 -271.951867) (xy 106.393742 -271.998141)
			(xy 106.363216 -272.040157) (xy 106.326493 -272.07688) (xy 106.284477 -272.107406) (xy 106.238203 -272.130984)
			(xy 106.18881 -272.147032) (xy 106.137515 -272.155157) (xy 106.085581 -272.155157) (xy 106.034286 -272.147032)
			(xy 105.984893 -272.130984) (xy 105.938619 -272.107406) (xy 105.896603 -272.07688) (xy 105.85988 -272.040157)
			(xy 105.829354 -271.998141) (xy 105.805776 -271.951867) (xy 105.789728 -271.902474) (xy 105.781603 -271.851179)
			(xy 105.501693 -271.851179) (xy 105.493568 -271.902474) (xy 105.47752 -271.951867) (xy 105.453942 -271.998141)
			(xy 105.423416 -272.040157) (xy 105.386693 -272.07688) (xy 105.344677 -272.107406) (xy 105.298403 -272.130984)
			(xy 105.24901 -272.147032) (xy 105.197715 -272.155157) (xy 105.145781 -272.155157) (xy 105.094486 -272.147032)
			(xy 105.045093 -272.130984) (xy 104.998819 -272.107406) (xy 104.956803 -272.07688) (xy 104.92008 -272.040157)
			(xy 104.889554 -271.998141) (xy 104.865976 -271.951867) (xy 104.849928 -271.902474) (xy 104.841803 -271.851179)
			(xy 104.561893 -271.851179) (xy 104.553768 -271.902474) (xy 104.53772 -271.951867) (xy 104.514142 -271.998141)
			(xy 104.483616 -272.040157) (xy 104.446893 -272.07688) (xy 104.404877 -272.107406) (xy 104.358603 -272.130984)
			(xy 104.30921 -272.147032) (xy 104.257915 -272.155157) (xy 104.205981 -272.155157) (xy 104.154686 -272.147032)
			(xy 104.105293 -272.130984) (xy 104.059019 -272.107406) (xy 104.017003 -272.07688) (xy 103.98028 -272.040157)
			(xy 103.949754 -271.998141) (xy 103.926176 -271.951867) (xy 103.910128 -271.902474) (xy 103.902003 -271.851179)
			(xy 103.622093 -271.851179) (xy 103.613968 -271.902474) (xy 103.59792 -271.951867) (xy 103.574342 -271.998141)
			(xy 103.543816 -272.040157) (xy 103.507093 -272.07688) (xy 103.465077 -272.107406) (xy 103.418803 -272.130984)
			(xy 103.36941 -272.147032) (xy 103.318115 -272.155157) (xy 103.266181 -272.155157) (xy 103.214886 -272.147032)
			(xy 103.165493 -272.130984) (xy 103.119219 -272.107406) (xy 103.077203 -272.07688) (xy 103.04048 -272.040157)
			(xy 103.009954 -271.998141) (xy 102.986376 -271.951867) (xy 102.970328 -271.902474) (xy 102.962203 -271.851179)
			(xy 102.682293 -271.851179) (xy 102.674168 -271.902474) (xy 102.65812 -271.951867) (xy 102.634542 -271.998141)
			(xy 102.604016 -272.040157) (xy 102.567293 -272.07688) (xy 102.525277 -272.107406) (xy 102.479003 -272.130984)
			(xy 102.42961 -272.147032) (xy 102.378315 -272.155157) (xy 102.326381 -272.155157) (xy 102.275086 -272.147032)
			(xy 102.225693 -272.130984) (xy 102.179419 -272.107406) (xy 102.137403 -272.07688) (xy 102.10068 -272.040157)
			(xy 102.070154 -271.998141) (xy 102.046576 -271.951867) (xy 102.030528 -271.902474) (xy 102.022403 -271.851179)
			(xy 101.742493 -271.851179) (xy 101.734368 -271.902474) (xy 101.71832 -271.951867) (xy 101.694742 -271.998141)
			(xy 101.664216 -272.040157) (xy 101.627493 -272.07688) (xy 101.585477 -272.107406) (xy 101.539203 -272.130984)
			(xy 101.48981 -272.147032) (xy 101.438515 -272.155157) (xy 101.386581 -272.155157) (xy 101.335286 -272.147032)
			(xy 101.285893 -272.130984) (xy 101.239619 -272.107406) (xy 101.197603 -272.07688) (xy 101.16088 -272.040157)
			(xy 101.130354 -271.998141) (xy 101.106776 -271.951867) (xy 101.090728 -271.902474) (xy 101.082603 -271.851179)
			(xy 100.802693 -271.851179) (xy 100.794568 -271.902474) (xy 100.77852 -271.951867) (xy 100.754942 -271.998141)
			(xy 100.724416 -272.040157) (xy 100.687693 -272.07688) (xy 100.645677 -272.107406) (xy 100.599403 -272.130984)
			(xy 100.55001 -272.147032) (xy 100.498715 -272.155157) (xy 100.446781 -272.155157) (xy 100.395486 -272.147032)
			(xy 100.346093 -272.130984) (xy 100.299819 -272.107406) (xy 100.257803 -272.07688) (xy 100.22108 -272.040157)
			(xy 100.190554 -271.998141) (xy 100.166976 -271.951867) (xy 100.150928 -271.902474) (xy 100.142803 -271.851179)
			(xy 99.862893 -271.851179) (xy 99.854768 -271.902474) (xy 99.83872 -271.951867) (xy 99.815142 -271.998141)
			(xy 99.784616 -272.040157) (xy 99.747893 -272.07688) (xy 99.705877 -272.107406) (xy 99.659603 -272.130984)
			(xy 99.61021 -272.147032) (xy 99.558915 -272.155157) (xy 99.506981 -272.155157) (xy 99.455686 -272.147032)
			(xy 99.406293 -272.130984) (xy 99.360019 -272.107406) (xy 99.318003 -272.07688) (xy 99.28128 -272.040157)
			(xy 99.250754 -271.998141) (xy 99.227176 -271.951867) (xy 99.211128 -271.902474) (xy 99.203003 -271.851179)
			(xy 98.923093 -271.851179) (xy 98.914968 -271.902474) (xy 98.89892 -271.951867) (xy 98.875342 -271.998141)
			(xy 98.844816 -272.040157) (xy 98.808093 -272.07688) (xy 98.766077 -272.107406) (xy 98.719803 -272.130984)
			(xy 98.67041 -272.147032) (xy 98.619115 -272.155157) (xy 98.567181 -272.155157) (xy 98.515886 -272.147032)
			(xy 98.466493 -272.130984) (xy 98.420219 -272.107406) (xy 98.378203 -272.07688) (xy 98.34148 -272.040157)
			(xy 98.310954 -271.998141) (xy 98.287376 -271.951867) (xy 98.271328 -271.902474) (xy 98.263203 -271.851179)
			(xy 97.983039 -271.851179) (xy 97.974914 -271.902474) (xy 97.958866 -271.951867) (xy 97.935288 -271.998141)
			(xy 97.904762 -272.040157) (xy 97.868039 -272.07688) (xy 97.826023 -272.107406) (xy 97.779749 -272.130984)
			(xy 97.730356 -272.147032) (xy 97.679061 -272.155157) (xy 97.627127 -272.155157) (xy 97.575832 -272.147032)
			(xy 97.526439 -272.130984) (xy 97.480165 -272.107406) (xy 97.438149 -272.07688) (xy 97.401426 -272.040157)
			(xy 97.3709 -271.998141) (xy 97.347322 -271.951867) (xy 97.331274 -271.902474) (xy 97.323149 -271.851179)
			(xy 97.043493 -271.851179) (xy 97.035368 -271.902474) (xy 97.01932 -271.951867) (xy 96.995742 -271.998141)
			(xy 96.965216 -272.040157) (xy 96.928493 -272.07688) (xy 96.886477 -272.107406) (xy 96.840203 -272.130984)
			(xy 96.79081 -272.147032) (xy 96.739515 -272.155157) (xy 96.687581 -272.155157) (xy 96.636286 -272.147032)
			(xy 96.586893 -272.130984) (xy 96.540619 -272.107406) (xy 96.498603 -272.07688) (xy 96.46188 -272.040157)
			(xy 96.431354 -271.998141) (xy 96.407776 -271.951867) (xy 96.391728 -271.902474) (xy 96.383603 -271.851179)
			(xy 96.103941 -271.851179) (xy 96.103941 -271.851957) (xy 96.095336 -271.904754) (xy 96.078352 -271.955479)
			(xy 96.066356 -271.97939) (xy 96.066102 -271.980152) (xy 96.063308 -271.98574) (xy 96.060514 -271.996662)
			(xy 96.060514 -272.214848) (xy 96.06109 -272.226091) (xy 96.070708 -272.246413) (xy 96.079056 -272.253964)
			(xy 96.139254 -272.303748) (xy 96.143672 -272.307219) (xy 96.153671 -272.312336) (xy 96.159066 -272.313908)
			(xy 96.169734 -272.316702) (xy 96.181164 -272.314416) (xy 96.196384 -272.311687) (xy 96.22717 -272.308758)
			(xy 96.242632 -272.308574) (xy 96.243394 -272.308574) (xy 96.269385 -272.309057) (xy 96.320727 -272.317188)
			(xy 96.370165 -272.33325) (xy 96.416482 -272.356849) (xy 96.458536 -272.387403) (xy 96.495293 -272.424159)
			(xy 96.525848 -272.466213) (xy 96.549447 -272.512529) (xy 96.565511 -272.561967) (xy 96.573643 -272.613309)
			(xy 96.573643 -272.665249) (xy 96.853503 -272.665249) (xy 96.853503 -272.613315) (xy 96.861628 -272.56202)
			(xy 96.877676 -272.512627) (xy 96.901254 -272.466353) (xy 96.93178 -272.424337) (xy 96.968503 -272.387614)
			(xy 97.010519 -272.357088) (xy 97.056793 -272.33351) (xy 97.106186 -272.317462) (xy 97.157481 -272.309337)
			(xy 97.209415 -272.309337) (xy 97.26071 -272.317462) (xy 97.310103 -272.33351) (xy 97.356377 -272.357088)
			(xy 97.398393 -272.387614) (xy 97.435116 -272.424337) (xy 97.465642 -272.466353) (xy 97.48922 -272.512627)
			(xy 97.505268 -272.56202) (xy 97.513393 -272.613315) (xy 97.513902 -272.639282) (xy 97.513393 -272.665249)
			(xy 97.793049 -272.665249) (xy 97.793049 -272.613315) (xy 97.801174 -272.56202) (xy 97.817222 -272.512627)
			(xy 97.8408 -272.466353) (xy 97.871326 -272.424337) (xy 97.908049 -272.387614) (xy 97.950065 -272.357088)
			(xy 97.996339 -272.33351) (xy 98.045732 -272.317462) (xy 98.097027 -272.309337) (xy 98.148961 -272.309337)
			(xy 98.200256 -272.317462) (xy 98.249649 -272.33351) (xy 98.295923 -272.357088) (xy 98.337939 -272.387614)
			(xy 98.374662 -272.424337) (xy 98.405188 -272.466353) (xy 98.428766 -272.512627) (xy 98.444814 -272.56202)
			(xy 98.452939 -272.613315) (xy 98.453448 -272.639282) (xy 98.452939 -272.665249) (xy 98.732849 -272.665249)
			(xy 98.732849 -272.613315) (xy 98.740974 -272.56202) (xy 98.757022 -272.512627) (xy 98.7806 -272.466353)
			(xy 98.811126 -272.424337) (xy 98.847849 -272.387614) (xy 98.889865 -272.357088) (xy 98.936139 -272.33351)
			(xy 98.985532 -272.317462) (xy 99.036827 -272.309337) (xy 99.088761 -272.309337) (xy 99.140056 -272.317462)
			(xy 99.189449 -272.33351) (xy 99.235723 -272.357088) (xy 99.277739 -272.387614) (xy 99.314462 -272.424337)
			(xy 99.344988 -272.466353) (xy 99.368566 -272.512627) (xy 99.384614 -272.56202) (xy 99.392739 -272.613315)
			(xy 99.393248 -272.639282) (xy 99.392739 -272.665249) (xy 99.672649 -272.665249) (xy 99.672649 -272.613315)
			(xy 99.680774 -272.56202) (xy 99.696822 -272.512627) (xy 99.7204 -272.466353) (xy 99.750926 -272.424337)
			(xy 99.787649 -272.387614) (xy 99.829665 -272.357088) (xy 99.875939 -272.33351) (xy 99.925332 -272.317462)
			(xy 99.976627 -272.309337) (xy 100.028561 -272.309337) (xy 100.079856 -272.317462) (xy 100.129249 -272.33351)
			(xy 100.175523 -272.357088) (xy 100.217539 -272.387614) (xy 100.254262 -272.424337) (xy 100.284788 -272.466353)
			(xy 100.308366 -272.512627) (xy 100.324414 -272.56202) (xy 100.332539 -272.613315) (xy 100.333048 -272.639282)
			(xy 100.332539 -272.665249) (xy 100.612449 -272.665249) (xy 100.612449 -272.613315) (xy 100.620574 -272.56202)
			(xy 100.636622 -272.512627) (xy 100.6602 -272.466353) (xy 100.690726 -272.424337) (xy 100.727449 -272.387614)
			(xy 100.769465 -272.357088) (xy 100.815739 -272.33351) (xy 100.865132 -272.317462) (xy 100.916427 -272.309337)
			(xy 100.968361 -272.309337) (xy 101.019656 -272.317462) (xy 101.069049 -272.33351) (xy 101.115323 -272.357088)
			(xy 101.157339 -272.387614) (xy 101.194062 -272.424337) (xy 101.224588 -272.466353) (xy 101.248166 -272.512627)
			(xy 101.264214 -272.56202) (xy 101.272339 -272.613315) (xy 101.272848 -272.639282) (xy 101.272339 -272.665249)
			(xy 101.552249 -272.665249) (xy 101.552249 -272.613315) (xy 101.560374 -272.56202) (xy 101.576422 -272.512627)
			(xy 101.6 -272.466353) (xy 101.630526 -272.424337) (xy 101.667249 -272.387614) (xy 101.709265 -272.357088)
			(xy 101.755539 -272.33351) (xy 101.804932 -272.317462) (xy 101.856227 -272.309337) (xy 101.908161 -272.309337)
			(xy 101.959456 -272.317462) (xy 102.008849 -272.33351) (xy 102.055123 -272.357088) (xy 102.097139 -272.387614)
			(xy 102.133862 -272.424337) (xy 102.164388 -272.466353) (xy 102.187966 -272.512627) (xy 102.204014 -272.56202)
			(xy 102.212139 -272.613315) (xy 102.212648 -272.639282) (xy 102.212139 -272.665249) (xy 102.492049 -272.665249)
			(xy 102.492049 -272.613315) (xy 102.500174 -272.56202) (xy 102.516222 -272.512627) (xy 102.5398 -272.466353)
			(xy 102.570326 -272.424337) (xy 102.607049 -272.387614) (xy 102.649065 -272.357088) (xy 102.695339 -272.33351)
			(xy 102.744732 -272.317462) (xy 102.796027 -272.309337) (xy 102.847961 -272.309337) (xy 102.899256 -272.317462)
			(xy 102.948649 -272.33351) (xy 102.994923 -272.357088) (xy 103.036939 -272.387614) (xy 103.073662 -272.424337)
			(xy 103.104188 -272.466353) (xy 103.127766 -272.512627) (xy 103.143814 -272.56202) (xy 103.151939 -272.613315)
			(xy 103.152448 -272.639282) (xy 103.151939 -272.665249) (xy 103.431849 -272.665249) (xy 103.431849 -272.613315)
			(xy 103.439974 -272.56202) (xy 103.456022 -272.512627) (xy 103.4796 -272.466353) (xy 103.510126 -272.424337)
			(xy 103.546849 -272.387614) (xy 103.588865 -272.357088) (xy 103.635139 -272.33351) (xy 103.684532 -272.317462)
			(xy 103.735827 -272.309337) (xy 103.787761 -272.309337) (xy 103.839056 -272.317462) (xy 103.888449 -272.33351)
			(xy 103.934723 -272.357088) (xy 103.976739 -272.387614) (xy 104.013462 -272.424337) (xy 104.043988 -272.466353)
			(xy 104.067566 -272.512627) (xy 104.083614 -272.56202) (xy 104.091739 -272.613315) (xy 104.092248 -272.639282)
			(xy 104.091739 -272.665249) (xy 104.371649 -272.665249) (xy 104.371649 -272.613315) (xy 104.379774 -272.56202)
			(xy 104.395822 -272.512627) (xy 104.4194 -272.466353) (xy 104.449926 -272.424337) (xy 104.486649 -272.387614)
			(xy 104.528665 -272.357088) (xy 104.574939 -272.33351) (xy 104.624332 -272.317462) (xy 104.675627 -272.309337)
			(xy 104.727561 -272.309337) (xy 104.778856 -272.317462) (xy 104.828249 -272.33351) (xy 104.874523 -272.357088)
			(xy 104.916539 -272.387614) (xy 104.953262 -272.424337) (xy 104.983788 -272.466353) (xy 105.007366 -272.512627)
			(xy 105.023414 -272.56202) (xy 105.031539 -272.613315) (xy 105.032048 -272.639282) (xy 105.031539 -272.665249)
			(xy 105.311449 -272.665249) (xy 105.311449 -272.613315) (xy 105.319574 -272.56202) (xy 105.335622 -272.512627)
			(xy 105.3592 -272.466353) (xy 105.389726 -272.424337) (xy 105.426449 -272.387614) (xy 105.468465 -272.357088)
			(xy 105.514739 -272.33351) (xy 105.564132 -272.317462) (xy 105.615427 -272.309337) (xy 105.667361 -272.309337)
			(xy 105.718656 -272.317462) (xy 105.768049 -272.33351) (xy 105.814323 -272.357088) (xy 105.856339 -272.387614)
			(xy 105.893062 -272.424337) (xy 105.923588 -272.466353) (xy 105.947166 -272.512627) (xy 105.963214 -272.56202)
			(xy 105.971339 -272.613315) (xy 105.971848 -272.639282) (xy 105.971339 -272.665249) (xy 106.251249 -272.665249)
			(xy 106.251249 -272.613315) (xy 106.259374 -272.56202) (xy 106.275422 -272.512627) (xy 106.299 -272.466353)
			(xy 106.329526 -272.424337) (xy 106.366249 -272.387614) (xy 106.408265 -272.357088) (xy 106.454539 -272.33351)
			(xy 106.503932 -272.317462) (xy 106.555227 -272.309337) (xy 106.607161 -272.309337) (xy 106.658456 -272.317462)
			(xy 106.707849 -272.33351) (xy 106.754123 -272.357088) (xy 106.796139 -272.387614) (xy 106.832862 -272.424337)
			(xy 106.863388 -272.466353) (xy 106.886966 -272.512627) (xy 106.903014 -272.56202) (xy 106.911139 -272.613315)
			(xy 106.911648 -272.639282) (xy 106.911139 -272.665249) (xy 107.191049 -272.665249) (xy 107.191049 -272.613315)
			(xy 107.199174 -272.56202) (xy 107.215222 -272.512627) (xy 107.2388 -272.466353) (xy 107.269326 -272.424337)
			(xy 107.306049 -272.387614) (xy 107.348065 -272.357088) (xy 107.394339 -272.33351) (xy 107.443732 -272.317462)
			(xy 107.495027 -272.309337) (xy 107.546961 -272.309337) (xy 107.598256 -272.317462) (xy 107.647649 -272.33351)
			(xy 107.693923 -272.357088) (xy 107.735939 -272.387614) (xy 107.772662 -272.424337) (xy 107.803188 -272.466353)
			(xy 107.826766 -272.512627) (xy 107.842814 -272.56202) (xy 107.850939 -272.613315) (xy 107.851448 -272.639282)
			(xy 107.850939 -272.665249) (xy 108.130849 -272.665249) (xy 108.130849 -272.613315) (xy 108.138974 -272.56202)
			(xy 108.155022 -272.512627) (xy 108.1786 -272.466353) (xy 108.209126 -272.424337) (xy 108.245849 -272.387614)
			(xy 108.287865 -272.357088) (xy 108.334139 -272.33351) (xy 108.383532 -272.317462) (xy 108.434827 -272.309337)
			(xy 108.486761 -272.309337) (xy 108.538056 -272.317462) (xy 108.587449 -272.33351) (xy 108.633723 -272.357088)
			(xy 108.675739 -272.387614) (xy 108.712462 -272.424337) (xy 108.742988 -272.466353) (xy 108.766566 -272.512627)
			(xy 108.782614 -272.56202) (xy 108.790739 -272.613315) (xy 108.791248 -272.639282) (xy 108.790739 -272.665249)
			(xy 109.070649 -272.665249) (xy 109.070649 -272.613315) (xy 109.078774 -272.56202) (xy 109.094822 -272.512627)
			(xy 109.1184 -272.466353) (xy 109.148926 -272.424337) (xy 109.185649 -272.387614) (xy 109.227665 -272.357088)
			(xy 109.273939 -272.33351) (xy 109.323332 -272.317462) (xy 109.374627 -272.309337) (xy 109.426561 -272.309337)
			(xy 109.477856 -272.317462) (xy 109.527249 -272.33351) (xy 109.573523 -272.357088) (xy 109.615539 -272.387614)
			(xy 109.652262 -272.424337) (xy 109.682788 -272.466353) (xy 109.706366 -272.512627) (xy 109.722414 -272.56202)
			(xy 109.730539 -272.613315) (xy 109.731048 -272.639282) (xy 109.730539 -272.665249) (xy 110.010449 -272.665249)
			(xy 110.010449 -272.613315) (xy 110.018574 -272.56202) (xy 110.034622 -272.512627) (xy 110.0582 -272.466353)
			(xy 110.088726 -272.424337) (xy 110.125449 -272.387614) (xy 110.167465 -272.357088) (xy 110.213739 -272.33351)
			(xy 110.263132 -272.317462) (xy 110.314427 -272.309337) (xy 110.366361 -272.309337) (xy 110.417656 -272.317462)
			(xy 110.467049 -272.33351) (xy 110.513323 -272.357088) (xy 110.555339 -272.387614) (xy 110.592062 -272.424337)
			(xy 110.622588 -272.466353) (xy 110.646166 -272.512627) (xy 110.662214 -272.56202) (xy 110.670339 -272.613315)
			(xy 110.670848 -272.639282) (xy 110.670339 -272.665249) (xy 113.769649 -272.665249) (xy 113.769649 -272.613315)
			(xy 113.777774 -272.56202) (xy 113.793822 -272.512627) (xy 113.8174 -272.466353) (xy 113.847926 -272.424337)
			(xy 113.884649 -272.387614) (xy 113.926665 -272.357088) (xy 113.972939 -272.33351) (xy 114.022332 -272.317462)
			(xy 114.073627 -272.309337) (xy 114.125561 -272.309337) (xy 114.176856 -272.317462) (xy 114.226249 -272.33351)
			(xy 114.272523 -272.357088) (xy 114.314539 -272.387614) (xy 114.351262 -272.424337) (xy 114.381788 -272.466353)
			(xy 114.405366 -272.512627) (xy 114.421414 -272.56202) (xy 114.429539 -272.613315) (xy 114.430048 -272.639282)
			(xy 114.429539 -272.665249) (xy 114.421414 -272.716544) (xy 114.405366 -272.765937) (xy 114.381788 -272.812211)
			(xy 114.351262 -272.854227) (xy 114.314539 -272.89095) (xy 114.272523 -272.921476) (xy 114.226249 -272.945054)
			(xy 114.176856 -272.961102) (xy 114.125561 -272.969227) (xy 114.073627 -272.969227) (xy 114.022332 -272.961102)
			(xy 113.972939 -272.945054) (xy 113.926665 -272.921476) (xy 113.884649 -272.89095) (xy 113.847926 -272.854227)
			(xy 113.8174 -272.812211) (xy 113.793822 -272.765937) (xy 113.777774 -272.716544) (xy 113.769649 -272.665249)
			(xy 110.670339 -272.665249) (xy 110.662214 -272.716544) (xy 110.646166 -272.765937) (xy 110.622588 -272.812211)
			(xy 110.592062 -272.854227) (xy 110.555339 -272.89095) (xy 110.513323 -272.921476) (xy 110.467049 -272.945054)
			(xy 110.417656 -272.961102) (xy 110.366361 -272.969227) (xy 110.314427 -272.969227) (xy 110.263132 -272.961102)
			(xy 110.213739 -272.945054) (xy 110.167465 -272.921476) (xy 110.125449 -272.89095) (xy 110.088726 -272.854227)
			(xy 110.0582 -272.812211) (xy 110.034622 -272.765937) (xy 110.018574 -272.716544) (xy 110.010449 -272.665249)
			(xy 109.730539 -272.665249) (xy 109.722414 -272.716544) (xy 109.706366 -272.765937) (xy 109.682788 -272.812211)
			(xy 109.652262 -272.854227) (xy 109.615539 -272.89095) (xy 109.573523 -272.921476) (xy 109.527249 -272.945054)
			(xy 109.477856 -272.961102) (xy 109.426561 -272.969227) (xy 109.374627 -272.969227) (xy 109.323332 -272.961102)
			(xy 109.273939 -272.945054) (xy 109.227665 -272.921476) (xy 109.185649 -272.89095) (xy 109.148926 -272.854227)
			(xy 109.1184 -272.812211) (xy 109.094822 -272.765937) (xy 109.078774 -272.716544) (xy 109.070649 -272.665249)
			(xy 108.790739 -272.665249) (xy 108.782614 -272.716544) (xy 108.766566 -272.765937) (xy 108.742988 -272.812211)
			(xy 108.712462 -272.854227) (xy 108.675739 -272.89095) (xy 108.633723 -272.921476) (xy 108.587449 -272.945054)
			(xy 108.538056 -272.961102) (xy 108.486761 -272.969227) (xy 108.434827 -272.969227) (xy 108.383532 -272.961102)
			(xy 108.334139 -272.945054) (xy 108.287865 -272.921476) (xy 108.245849 -272.89095) (xy 108.209126 -272.854227)
			(xy 108.1786 -272.812211) (xy 108.155022 -272.765937) (xy 108.138974 -272.716544) (xy 108.130849 -272.665249)
			(xy 107.850939 -272.665249) (xy 107.842814 -272.716544) (xy 107.826766 -272.765937) (xy 107.803188 -272.812211)
			(xy 107.772662 -272.854227) (xy 107.735939 -272.89095) (xy 107.693923 -272.921476) (xy 107.647649 -272.945054)
			(xy 107.598256 -272.961102) (xy 107.546961 -272.969227) (xy 107.495027 -272.969227) (xy 107.443732 -272.961102)
			(xy 107.394339 -272.945054) (xy 107.348065 -272.921476) (xy 107.306049 -272.89095) (xy 107.269326 -272.854227)
			(xy 107.2388 -272.812211) (xy 107.215222 -272.765937) (xy 107.199174 -272.716544) (xy 107.191049 -272.665249)
			(xy 106.911139 -272.665249) (xy 106.903014 -272.716544) (xy 106.886966 -272.765937) (xy 106.863388 -272.812211)
			(xy 106.832862 -272.854227) (xy 106.796139 -272.89095) (xy 106.754123 -272.921476) (xy 106.707849 -272.945054)
			(xy 106.658456 -272.961102) (xy 106.607161 -272.969227) (xy 106.555227 -272.969227) (xy 106.503932 -272.961102)
			(xy 106.454539 -272.945054) (xy 106.408265 -272.921476) (xy 106.366249 -272.89095) (xy 106.329526 -272.854227)
			(xy 106.299 -272.812211) (xy 106.275422 -272.765937) (xy 106.259374 -272.716544) (xy 106.251249 -272.665249)
			(xy 105.971339 -272.665249) (xy 105.963214 -272.716544) (xy 105.947166 -272.765937) (xy 105.923588 -272.812211)
			(xy 105.893062 -272.854227) (xy 105.856339 -272.89095) (xy 105.814323 -272.921476) (xy 105.768049 -272.945054)
			(xy 105.718656 -272.961102) (xy 105.667361 -272.969227) (xy 105.615427 -272.969227) (xy 105.564132 -272.961102)
			(xy 105.514739 -272.945054) (xy 105.468465 -272.921476) (xy 105.426449 -272.89095) (xy 105.389726 -272.854227)
			(xy 105.3592 -272.812211) (xy 105.335622 -272.765937) (xy 105.319574 -272.716544) (xy 105.311449 -272.665249)
			(xy 105.031539 -272.665249) (xy 105.023414 -272.716544) (xy 105.007366 -272.765937) (xy 104.983788 -272.812211)
			(xy 104.953262 -272.854227) (xy 104.916539 -272.89095) (xy 104.874523 -272.921476) (xy 104.828249 -272.945054)
			(xy 104.778856 -272.961102) (xy 104.727561 -272.969227) (xy 104.675627 -272.969227) (xy 104.624332 -272.961102)
			(xy 104.574939 -272.945054) (xy 104.528665 -272.921476) (xy 104.486649 -272.89095) (xy 104.449926 -272.854227)
			(xy 104.4194 -272.812211) (xy 104.395822 -272.765937) (xy 104.379774 -272.716544) (xy 104.371649 -272.665249)
			(xy 104.091739 -272.665249) (xy 104.083614 -272.716544) (xy 104.067566 -272.765937) (xy 104.043988 -272.812211)
			(xy 104.013462 -272.854227) (xy 103.976739 -272.89095) (xy 103.934723 -272.921476) (xy 103.888449 -272.945054)
			(xy 103.839056 -272.961102) (xy 103.787761 -272.969227) (xy 103.735827 -272.969227) (xy 103.684532 -272.961102)
			(xy 103.635139 -272.945054) (xy 103.588865 -272.921476) (xy 103.546849 -272.89095) (xy 103.510126 -272.854227)
			(xy 103.4796 -272.812211) (xy 103.456022 -272.765937) (xy 103.439974 -272.716544) (xy 103.431849 -272.665249)
			(xy 103.151939 -272.665249) (xy 103.143814 -272.716544) (xy 103.127766 -272.765937) (xy 103.104188 -272.812211)
			(xy 103.073662 -272.854227) (xy 103.036939 -272.89095) (xy 102.994923 -272.921476) (xy 102.948649 -272.945054)
			(xy 102.899256 -272.961102) (xy 102.847961 -272.969227) (xy 102.796027 -272.969227) (xy 102.744732 -272.961102)
			(xy 102.695339 -272.945054) (xy 102.649065 -272.921476) (xy 102.607049 -272.89095) (xy 102.570326 -272.854227)
			(xy 102.5398 -272.812211) (xy 102.516222 -272.765937) (xy 102.500174 -272.716544) (xy 102.492049 -272.665249)
			(xy 102.212139 -272.665249) (xy 102.204014 -272.716544) (xy 102.187966 -272.765937) (xy 102.164388 -272.812211)
			(xy 102.133862 -272.854227) (xy 102.097139 -272.89095) (xy 102.055123 -272.921476) (xy 102.008849 -272.945054)
			(xy 101.959456 -272.961102) (xy 101.908161 -272.969227) (xy 101.856227 -272.969227) (xy 101.804932 -272.961102)
			(xy 101.755539 -272.945054) (xy 101.709265 -272.921476) (xy 101.667249 -272.89095) (xy 101.630526 -272.854227)
			(xy 101.6 -272.812211) (xy 101.576422 -272.765937) (xy 101.560374 -272.716544) (xy 101.552249 -272.665249)
			(xy 101.272339 -272.665249) (xy 101.264214 -272.716544) (xy 101.248166 -272.765937) (xy 101.224588 -272.812211)
			(xy 101.194062 -272.854227) (xy 101.157339 -272.89095) (xy 101.115323 -272.921476) (xy 101.069049 -272.945054)
			(xy 101.019656 -272.961102) (xy 100.968361 -272.969227) (xy 100.916427 -272.969227) (xy 100.865132 -272.961102)
			(xy 100.815739 -272.945054) (xy 100.769465 -272.921476) (xy 100.727449 -272.89095) (xy 100.690726 -272.854227)
			(xy 100.6602 -272.812211) (xy 100.636622 -272.765937) (xy 100.620574 -272.716544) (xy 100.612449 -272.665249)
			(xy 100.332539 -272.665249) (xy 100.324414 -272.716544) (xy 100.308366 -272.765937) (xy 100.284788 -272.812211)
			(xy 100.254262 -272.854227) (xy 100.217539 -272.89095) (xy 100.175523 -272.921476) (xy 100.129249 -272.945054)
			(xy 100.079856 -272.961102) (xy 100.028561 -272.969227) (xy 99.976627 -272.969227) (xy 99.925332 -272.961102)
			(xy 99.875939 -272.945054) (xy 99.829665 -272.921476) (xy 99.787649 -272.89095) (xy 99.750926 -272.854227)
			(xy 99.7204 -272.812211) (xy 99.696822 -272.765937) (xy 99.680774 -272.716544) (xy 99.672649 -272.665249)
			(xy 99.392739 -272.665249) (xy 99.384614 -272.716544) (xy 99.368566 -272.765937) (xy 99.344988 -272.812211)
			(xy 99.314462 -272.854227) (xy 99.277739 -272.89095) (xy 99.235723 -272.921476) (xy 99.189449 -272.945054)
			(xy 99.140056 -272.961102) (xy 99.088761 -272.969227) (xy 99.036827 -272.969227) (xy 98.985532 -272.961102)
			(xy 98.936139 -272.945054) (xy 98.889865 -272.921476) (xy 98.847849 -272.89095) (xy 98.811126 -272.854227)
			(xy 98.7806 -272.812211) (xy 98.757022 -272.765937) (xy 98.740974 -272.716544) (xy 98.732849 -272.665249)
			(xy 98.452939 -272.665249) (xy 98.444814 -272.716544) (xy 98.428766 -272.765937) (xy 98.405188 -272.812211)
			(xy 98.374662 -272.854227) (xy 98.337939 -272.89095) (xy 98.295923 -272.921476) (xy 98.249649 -272.945054)
			(xy 98.200256 -272.961102) (xy 98.148961 -272.969227) (xy 98.097027 -272.969227) (xy 98.045732 -272.961102)
			(xy 97.996339 -272.945054) (xy 97.950065 -272.921476) (xy 97.908049 -272.89095) (xy 97.871326 -272.854227)
			(xy 97.8408 -272.812211) (xy 97.817222 -272.765937) (xy 97.801174 -272.716544) (xy 97.793049 -272.665249)
			(xy 97.513393 -272.665249) (xy 97.505268 -272.716544) (xy 97.48922 -272.765937) (xy 97.465642 -272.812211)
			(xy 97.435116 -272.854227) (xy 97.398393 -272.89095) (xy 97.356377 -272.921476) (xy 97.310103 -272.945054)
			(xy 97.26071 -272.961102) (xy 97.209415 -272.969227) (xy 97.157481 -272.969227) (xy 97.106186 -272.961102)
			(xy 97.056793 -272.945054) (xy 97.010519 -272.921476) (xy 96.968503 -272.89095) (xy 96.93178 -272.854227)
			(xy 96.901254 -272.812211) (xy 96.877676 -272.765937) (xy 96.861628 -272.716544) (xy 96.853503 -272.665249)
			(xy 96.573643 -272.665249) (xy 96.573643 -272.665291) (xy 96.565511 -272.716633) (xy 96.549447 -272.766071)
			(xy 96.525848 -272.812387) (xy 96.495293 -272.854441) (xy 96.458536 -272.891197) (xy 96.416482 -272.921751)
			(xy 96.370165 -272.94535) (xy 96.320727 -272.961412) (xy 96.269385 -272.969543) (xy 96.243394 -272.96999)
			(xy 96.242632 -272.96999) (xy 96.227171 -272.969787) (xy 96.196386 -272.966865) (xy 96.181164 -272.964148)
			(xy 96.169734 -272.961862) (xy 96.159066 -272.964656) (xy 96.153662 -272.966201) (xy 96.143662 -272.971329)
			(xy 96.139254 -272.974816) (xy 96.079056 -273.0246) (xy 96.070777 -273.032203) (xy 96.061169 -273.052494)
			(xy 96.060514 -273.063716) (xy 96.060514 -273.275298) (xy 96.065594 -273.297396) (xy 96.066102 -273.298158)
			(xy 96.066356 -273.29892) (xy 96.078362 -273.322827) (xy 96.095345 -273.373553) (xy 96.103949 -273.426351)
			(xy 96.103949 -273.479065) (xy 96.383603 -273.479065) (xy 96.383603 -273.427131) (xy 96.391728 -273.375836)
			(xy 96.407776 -273.326443) (xy 96.431354 -273.280169) (xy 96.46188 -273.238153) (xy 96.498603 -273.20143)
			(xy 96.540619 -273.170904) (xy 96.586893 -273.147326) (xy 96.636286 -273.131278) (xy 96.687581 -273.123153)
			(xy 96.739515 -273.123153) (xy 96.79081 -273.131278) (xy 96.840203 -273.147326) (xy 96.886477 -273.170904)
			(xy 96.928493 -273.20143) (xy 96.965216 -273.238153) (xy 96.995742 -273.280169) (xy 97.01932 -273.326443)
			(xy 97.035368 -273.375836) (xy 97.043493 -273.427131) (xy 97.044002 -273.453098) (xy 97.043493 -273.479065)
			(xy 97.323403 -273.479065) (xy 97.323403 -273.427131) (xy 97.331528 -273.375836) (xy 97.347576 -273.326443)
			(xy 97.371154 -273.280169) (xy 97.40168 -273.238153) (xy 97.438403 -273.20143) (xy 97.480419 -273.170904)
			(xy 97.526693 -273.147326) (xy 97.576086 -273.131278) (xy 97.627381 -273.123153) (xy 97.679315 -273.123153)
			(xy 97.73061 -273.131278) (xy 97.780003 -273.147326) (xy 97.826277 -273.170904) (xy 97.868293 -273.20143)
			(xy 97.905016 -273.238153) (xy 97.935542 -273.280169) (xy 97.95912 -273.326443) (xy 97.975168 -273.375836)
			(xy 97.983293 -273.427131) (xy 97.983802 -273.453098) (xy 97.983293 -273.479065) (xy 98.263203 -273.479065)
			(xy 98.263203 -273.427131) (xy 98.271328 -273.375836) (xy 98.287376 -273.326443) (xy 98.310954 -273.280169)
			(xy 98.34148 -273.238153) (xy 98.378203 -273.20143) (xy 98.420219 -273.170904) (xy 98.466493 -273.147326)
			(xy 98.515886 -273.131278) (xy 98.567181 -273.123153) (xy 98.619115 -273.123153) (xy 98.67041 -273.131278)
			(xy 98.719803 -273.147326) (xy 98.766077 -273.170904) (xy 98.808093 -273.20143) (xy 98.844816 -273.238153)
			(xy 98.875342 -273.280169) (xy 98.89892 -273.326443) (xy 98.914968 -273.375836) (xy 98.923093 -273.427131)
			(xy 98.923602 -273.453098) (xy 98.923093 -273.479065) (xy 99.203003 -273.479065) (xy 99.203003 -273.427131)
			(xy 99.211128 -273.375836) (xy 99.227176 -273.326443) (xy 99.250754 -273.280169) (xy 99.28128 -273.238153)
			(xy 99.318003 -273.20143) (xy 99.360019 -273.170904) (xy 99.406293 -273.147326) (xy 99.455686 -273.131278)
			(xy 99.506981 -273.123153) (xy 99.558915 -273.123153) (xy 99.61021 -273.131278) (xy 99.659603 -273.147326)
			(xy 99.705877 -273.170904) (xy 99.747893 -273.20143) (xy 99.784616 -273.238153) (xy 99.815142 -273.280169)
			(xy 99.83872 -273.326443) (xy 99.854768 -273.375836) (xy 99.862893 -273.427131) (xy 99.863402 -273.453098)
			(xy 99.862893 -273.479065) (xy 100.142803 -273.479065) (xy 100.142803 -273.427131) (xy 100.150928 -273.375836)
			(xy 100.166976 -273.326443) (xy 100.190554 -273.280169) (xy 100.22108 -273.238153) (xy 100.257803 -273.20143)
			(xy 100.299819 -273.170904) (xy 100.346093 -273.147326) (xy 100.395486 -273.131278) (xy 100.446781 -273.123153)
			(xy 100.498715 -273.123153) (xy 100.55001 -273.131278) (xy 100.599403 -273.147326) (xy 100.645677 -273.170904)
			(xy 100.687693 -273.20143) (xy 100.724416 -273.238153) (xy 100.754942 -273.280169) (xy 100.77852 -273.326443)
			(xy 100.794568 -273.375836) (xy 100.802693 -273.427131) (xy 100.803202 -273.453098) (xy 100.802693 -273.479065)
			(xy 101.082349 -273.479065) (xy 101.082349 -273.427131) (xy 101.090474 -273.375836) (xy 101.106522 -273.326443)
			(xy 101.1301 -273.280169) (xy 101.160626 -273.238153) (xy 101.197349 -273.20143) (xy 101.239365 -273.170904)
			(xy 101.285639 -273.147326) (xy 101.335032 -273.131278) (xy 101.386327 -273.123153) (xy 101.438261 -273.123153)
			(xy 101.489556 -273.131278) (xy 101.538949 -273.147326) (xy 101.585223 -273.170904) (xy 101.627239 -273.20143)
			(xy 101.663962 -273.238153) (xy 101.694488 -273.280169) (xy 101.718066 -273.326443) (xy 101.734114 -273.375836)
			(xy 101.742239 -273.427131) (xy 101.742748 -273.453098) (xy 101.742239 -273.479065) (xy 102.022403 -273.479065)
			(xy 102.022403 -273.427131) (xy 102.030528 -273.375836) (xy 102.046576 -273.326443) (xy 102.070154 -273.280169)
			(xy 102.10068 -273.238153) (xy 102.137403 -273.20143) (xy 102.179419 -273.170904) (xy 102.225693 -273.147326)
			(xy 102.275086 -273.131278) (xy 102.326381 -273.123153) (xy 102.378315 -273.123153) (xy 102.42961 -273.131278)
			(xy 102.479003 -273.147326) (xy 102.525277 -273.170904) (xy 102.567293 -273.20143) (xy 102.604016 -273.238153)
			(xy 102.634542 -273.280169) (xy 102.65812 -273.326443) (xy 102.674168 -273.375836) (xy 102.682293 -273.427131)
			(xy 102.682802 -273.453098) (xy 102.682293 -273.479065) (xy 102.961949 -273.479065) (xy 102.961949 -273.427131)
			(xy 102.970074 -273.375836) (xy 102.986122 -273.326443) (xy 103.0097 -273.280169) (xy 103.040226 -273.238153)
			(xy 103.076949 -273.20143) (xy 103.118965 -273.170904) (xy 103.165239 -273.147326) (xy 103.214632 -273.131278)
			(xy 103.265927 -273.123153) (xy 103.317861 -273.123153) (xy 103.369156 -273.131278) (xy 103.418549 -273.147326)
			(xy 103.464823 -273.170904) (xy 103.506839 -273.20143) (xy 103.543562 -273.238153) (xy 103.574088 -273.280169)
			(xy 103.597666 -273.326443) (xy 103.613714 -273.375836) (xy 103.621839 -273.427131) (xy 103.622348 -273.453098)
			(xy 103.621839 -273.479065) (xy 103.902003 -273.479065) (xy 103.902003 -273.427131) (xy 103.910128 -273.375836)
			(xy 103.926176 -273.326443) (xy 103.949754 -273.280169) (xy 103.98028 -273.238153) (xy 104.017003 -273.20143)
			(xy 104.059019 -273.170904) (xy 104.105293 -273.147326) (xy 104.154686 -273.131278) (xy 104.205981 -273.123153)
			(xy 104.257915 -273.123153) (xy 104.30921 -273.131278) (xy 104.358603 -273.147326) (xy 104.404877 -273.170904)
			(xy 104.446893 -273.20143) (xy 104.483616 -273.238153) (xy 104.514142 -273.280169) (xy 104.53772 -273.326443)
			(xy 104.553768 -273.375836) (xy 104.561893 -273.427131) (xy 104.562402 -273.453098) (xy 104.561893 -273.479065)
			(xy 105.781603 -273.479065) (xy 105.781603 -273.427131) (xy 105.789728 -273.375836) (xy 105.805776 -273.326443)
			(xy 105.829354 -273.280169) (xy 105.85988 -273.238153) (xy 105.896603 -273.20143) (xy 105.938619 -273.170904)
			(xy 105.984893 -273.147326) (xy 106.034286 -273.131278) (xy 106.085581 -273.123153) (xy 106.137515 -273.123153)
			(xy 106.18881 -273.131278) (xy 106.238203 -273.147326) (xy 106.284477 -273.170904) (xy 106.326493 -273.20143)
			(xy 106.363216 -273.238153) (xy 106.393742 -273.280169) (xy 106.41732 -273.326443) (xy 106.433368 -273.375836)
			(xy 106.441493 -273.427131) (xy 106.442002 -273.453098) (xy 106.441493 -273.479065) (xy 106.721403 -273.479065)
			(xy 106.721403 -273.427131) (xy 106.729528 -273.375836) (xy 106.745576 -273.326443) (xy 106.769154 -273.280169)
			(xy 106.79968 -273.238153) (xy 106.836403 -273.20143) (xy 106.878419 -273.170904) (xy 106.924693 -273.147326)
			(xy 106.974086 -273.131278) (xy 107.025381 -273.123153) (xy 107.077315 -273.123153) (xy 107.12861 -273.131278)
			(xy 107.178003 -273.147326) (xy 107.224277 -273.170904) (xy 107.266293 -273.20143) (xy 107.303016 -273.238153)
			(xy 107.333542 -273.280169) (xy 107.35712 -273.326443) (xy 107.373168 -273.375836) (xy 107.381293 -273.427131)
			(xy 107.381802 -273.453098) (xy 107.381293 -273.479065) (xy 107.661203 -273.479065) (xy 107.661203 -273.427131)
			(xy 107.669328 -273.375836) (xy 107.685376 -273.326443) (xy 107.708954 -273.280169) (xy 107.73948 -273.238153)
			(xy 107.776203 -273.20143) (xy 107.818219 -273.170904) (xy 107.864493 -273.147326) (xy 107.913886 -273.131278)
			(xy 107.965181 -273.123153) (xy 108.017115 -273.123153) (xy 108.06841 -273.131278) (xy 108.117803 -273.147326)
			(xy 108.164077 -273.170904) (xy 108.206093 -273.20143) (xy 108.242816 -273.238153) (xy 108.273342 -273.280169)
			(xy 108.29692 -273.326443) (xy 108.312968 -273.375836) (xy 108.321093 -273.427131) (xy 108.321602 -273.453098)
			(xy 108.60024 -273.453098) (xy 108.600749 -273.427131) (xy 108.608874 -273.375836) (xy 108.624922 -273.326443)
			(xy 108.6485 -273.280169) (xy 108.679026 -273.238153) (xy 108.715749 -273.20143) (xy 108.757765 -273.170904)
			(xy 108.804039 -273.147326) (xy 108.853432 -273.131278) (xy 108.904727 -273.123153) (xy 108.956661 -273.123153)
			(xy 109.007956 -273.131278) (xy 109.057349 -273.147326) (xy 109.103623 -273.170904) (xy 109.145639 -273.20143)
			(xy 109.182362 -273.238153) (xy 109.212888 -273.280169) (xy 109.236466 -273.326443) (xy 109.252514 -273.375836)
			(xy 109.260639 -273.427131) (xy 109.261148 -273.453098) (xy 109.260554 -273.479065) (xy 109.540549 -273.479065)
			(xy 109.540549 -273.427131) (xy 109.548674 -273.375836) (xy 109.564722 -273.326443) (xy 109.5883 -273.280169)
			(xy 109.618826 -273.238153) (xy 109.655549 -273.20143) (xy 109.697565 -273.170904) (xy 109.743839 -273.147326)
			(xy 109.793232 -273.131278) (xy 109.844527 -273.123153) (xy 109.896461 -273.123153) (xy 109.947756 -273.131278)
			(xy 109.997149 -273.147326) (xy 110.043423 -273.170904) (xy 110.085439 -273.20143) (xy 110.122162 -273.238153)
			(xy 110.152688 -273.280169) (xy 110.176266 -273.326443) (xy 110.192314 -273.375836) (xy 110.200439 -273.427131)
			(xy 110.200948 -273.453098) (xy 110.200439 -273.479065) (xy 113.299749 -273.479065) (xy 113.299749 -273.427131)
			(xy 113.307874 -273.375836) (xy 113.323922 -273.326443) (xy 113.3475 -273.280169) (xy 113.378026 -273.238153)
			(xy 113.414749 -273.20143) (xy 113.456765 -273.170904) (xy 113.503039 -273.147326) (xy 113.552432 -273.131278)
			(xy 113.603727 -273.123153) (xy 113.655661 -273.123153) (xy 113.706956 -273.131278) (xy 113.756349 -273.147326)
			(xy 113.802623 -273.170904) (xy 113.844639 -273.20143) (xy 113.881362 -273.238153) (xy 113.911888 -273.280169)
			(xy 113.935466 -273.326443) (xy 113.951514 -273.375836) (xy 113.959639 -273.427131) (xy 113.960148 -273.453098)
			(xy 113.959639 -273.479065) (xy 114.239549 -273.479065) (xy 114.239549 -273.427131) (xy 114.247674 -273.375836)
			(xy 114.263722 -273.326443) (xy 114.2873 -273.280169) (xy 114.317826 -273.238153) (xy 114.354549 -273.20143)
			(xy 114.396565 -273.170904) (xy 114.442839 -273.147326) (xy 114.492232 -273.131278) (xy 114.543527 -273.123153)
			(xy 114.595461 -273.123153) (xy 114.646756 -273.131278) (xy 114.696149 -273.147326) (xy 114.742423 -273.170904)
			(xy 114.784439 -273.20143) (xy 114.821162 -273.238153) (xy 114.851688 -273.280169) (xy 114.875266 -273.326443)
			(xy 114.891314 -273.375836) (xy 114.899439 -273.427131) (xy 114.899948 -273.453098) (xy 114.899439 -273.479065)
			(xy 114.891314 -273.53036) (xy 114.875266 -273.579753) (xy 114.851688 -273.626027) (xy 114.821162 -273.668043)
			(xy 114.784439 -273.704766) (xy 114.742423 -273.735292) (xy 114.696149 -273.75887) (xy 114.646756 -273.774918)
			(xy 114.595461 -273.783043) (xy 114.543527 -273.783043) (xy 114.492232 -273.774918) (xy 114.442839 -273.75887)
			(xy 114.396565 -273.735292) (xy 114.354549 -273.704766) (xy 114.317826 -273.668043) (xy 114.2873 -273.626027)
			(xy 114.263722 -273.579753) (xy 114.247674 -273.53036) (xy 114.239549 -273.479065) (xy 113.959639 -273.479065)
			(xy 113.951514 -273.53036) (xy 113.935466 -273.579753) (xy 113.911888 -273.626027) (xy 113.881362 -273.668043)
			(xy 113.844639 -273.704766) (xy 113.802623 -273.735292) (xy 113.756349 -273.75887) (xy 113.706956 -273.774918)
			(xy 113.655661 -273.783043) (xy 113.603727 -273.783043) (xy 113.552432 -273.774918) (xy 113.503039 -273.75887)
			(xy 113.456765 -273.735292) (xy 113.414749 -273.704766) (xy 113.378026 -273.668043) (xy 113.3475 -273.626027)
			(xy 113.323922 -273.579753) (xy 113.307874 -273.53036) (xy 113.299749 -273.479065) (xy 110.200439 -273.479065)
			(xy 110.192314 -273.53036) (xy 110.176266 -273.579753) (xy 110.152688 -273.626027) (xy 110.122162 -273.668043)
			(xy 110.085439 -273.704766) (xy 110.043423 -273.735292) (xy 109.997149 -273.75887) (xy 109.947756 -273.774918)
			(xy 109.896461 -273.783043) (xy 109.844527 -273.783043) (xy 109.793232 -273.774918) (xy 109.743839 -273.75887)
			(xy 109.697565 -273.735292) (xy 109.655549 -273.704766) (xy 109.618826 -273.668043) (xy 109.5883 -273.626027)
			(xy 109.564722 -273.579753) (xy 109.548674 -273.53036) (xy 109.540549 -273.479065) (xy 109.260554 -273.479065)
			(xy 109.260509 -273.481014) (xy 109.251068 -273.536044) (xy 109.242352 -273.562572) (xy 109.234732 -273.58467)
			(xy 109.43844 -273.93773) (xy 109.461554 -273.942048) (xy 109.486474 -273.947223) (xy 109.534457 -273.964188)
			(xy 109.579273 -273.988305) (xy 109.619865 -274.019005) (xy 109.655273 -274.055562) (xy 109.684662 -274.097113)
			(xy 109.707337 -274.142677) (xy 109.722762 -274.191177) (xy 109.730573 -274.241467) (xy 109.731048 -274.266914)
			(xy 109.730539 -274.292881) (xy 110.010449 -274.292881) (xy 110.010449 -274.240947) (xy 110.018574 -274.189652)
			(xy 110.034622 -274.140259) (xy 110.0582 -274.093985) (xy 110.088726 -274.051969) (xy 110.125449 -274.015246)
			(xy 110.167465 -273.98472) (xy 110.213739 -273.961142) (xy 110.263132 -273.945094) (xy 110.314427 -273.936969)
			(xy 110.366361 -273.936969) (xy 110.417656 -273.945094) (xy 110.467049 -273.961142) (xy 110.513323 -273.98472)
			(xy 110.555339 -274.015246) (xy 110.592062 -274.051969) (xy 110.622588 -274.093985) (xy 110.646166 -274.140259)
			(xy 110.662214 -274.189652) (xy 110.670339 -274.240947) (xy 110.670848 -274.266914) (xy 110.670339 -274.292881)
			(xy 113.769649 -274.292881) (xy 113.769649 -274.240947) (xy 113.777774 -274.189652) (xy 113.793822 -274.140259)
			(xy 113.8174 -274.093985) (xy 113.847926 -274.051969) (xy 113.884649 -274.015246) (xy 113.926665 -273.98472)
			(xy 113.972939 -273.961142) (xy 114.022332 -273.945094) (xy 114.073627 -273.936969) (xy 114.125561 -273.936969)
			(xy 114.176856 -273.945094) (xy 114.226249 -273.961142) (xy 114.272523 -273.98472) (xy 114.314539 -274.015246)
			(xy 114.351262 -274.051969) (xy 114.381788 -274.093985) (xy 114.405366 -274.140259) (xy 114.421414 -274.189652)
			(xy 114.429539 -274.240947) (xy 114.430048 -274.266914) (xy 114.429539 -274.292881) (xy 114.421414 -274.344176)
			(xy 114.405366 -274.393569) (xy 114.381788 -274.439843) (xy 114.351262 -274.481859) (xy 114.314539 -274.518582)
			(xy 114.272523 -274.549108) (xy 114.226249 -274.572686) (xy 114.176856 -274.588734) (xy 114.125561 -274.596859)
			(xy 114.073627 -274.596859) (xy 114.022332 -274.588734) (xy 113.972939 -274.572686) (xy 113.926665 -274.549108)
			(xy 113.884649 -274.518582) (xy 113.847926 -274.481859) (xy 113.8174 -274.439843) (xy 113.793822 -274.393569)
			(xy 113.777774 -274.344176) (xy 113.769649 -274.292881) (xy 110.670339 -274.292881) (xy 110.662214 -274.344176)
			(xy 110.646166 -274.393569) (xy 110.622588 -274.439843) (xy 110.592062 -274.481859) (xy 110.555339 -274.518582)
			(xy 110.513323 -274.549108) (xy 110.467049 -274.572686) (xy 110.417656 -274.588734) (xy 110.366361 -274.596859)
			(xy 110.314427 -274.596859) (xy 110.263132 -274.588734) (xy 110.213739 -274.572686) (xy 110.167465 -274.549108)
			(xy 110.125449 -274.518582) (xy 110.088726 -274.481859) (xy 110.0582 -274.439843) (xy 110.034622 -274.393569)
			(xy 110.018574 -274.344176) (xy 110.010449 -274.292881) (xy 109.730539 -274.292881) (xy 109.722414 -274.344176)
			(xy 109.706366 -274.393569) (xy 109.682788 -274.439843) (xy 109.652262 -274.481859) (xy 109.615539 -274.518582)
			(xy 109.573523 -274.549108) (xy 109.527249 -274.572686) (xy 109.477856 -274.588734) (xy 109.426561 -274.596859)
			(xy 109.374627 -274.596859) (xy 109.323332 -274.588734) (xy 109.273939 -274.572686) (xy 109.227665 -274.549108)
			(xy 109.185649 -274.518582) (xy 109.148926 -274.481859) (xy 109.1184 -274.439843) (xy 109.094822 -274.393569)
			(xy 109.078774 -274.344176) (xy 109.070649 -274.292881) (xy 109.07014 -274.266914) (xy 109.070694 -274.238928)
			(xy 109.080143 -274.18376) (xy 109.088936 -274.157186) (xy 109.096556 -274.135088) (xy 108.892848 -273.782282)
			(xy 108.869988 -273.777964) (xy 108.845037 -273.77287) (xy 108.79701 -273.755934) (xy 108.752149 -273.731832)
			(xy 108.711514 -273.701136) (xy 108.676069 -273.664571) (xy 108.64665 -273.623002) (xy 108.623955 -273.577414)
			(xy 108.608519 -273.528884) (xy 108.600709 -273.478561) (xy 108.60024 -273.453098) (xy 108.321602 -273.453098)
			(xy 108.321093 -273.479065) (xy 108.312968 -273.53036) (xy 108.29692 -273.579753) (xy 108.273342 -273.626027)
			(xy 108.242816 -273.668043) (xy 108.206093 -273.704766) (xy 108.164077 -273.735292) (xy 108.117803 -273.75887)
			(xy 108.06841 -273.774918) (xy 108.017115 -273.783043) (xy 107.965181 -273.783043) (xy 107.913886 -273.774918)
			(xy 107.864493 -273.75887) (xy 107.818219 -273.735292) (xy 107.776203 -273.704766) (xy 107.73948 -273.668043)
			(xy 107.708954 -273.626027) (xy 107.685376 -273.579753) (xy 107.669328 -273.53036) (xy 107.661203 -273.479065)
			(xy 107.381293 -273.479065) (xy 107.373168 -273.53036) (xy 107.35712 -273.579753) (xy 107.333542 -273.626027)
			(xy 107.303016 -273.668043) (xy 107.266293 -273.704766) (xy 107.224277 -273.735292) (xy 107.178003 -273.75887)
			(xy 107.12861 -273.774918) (xy 107.077315 -273.783043) (xy 107.025381 -273.783043) (xy 106.974086 -273.774918)
			(xy 106.924693 -273.75887) (xy 106.878419 -273.735292) (xy 106.836403 -273.704766) (xy 106.79968 -273.668043)
			(xy 106.769154 -273.626027) (xy 106.745576 -273.579753) (xy 106.729528 -273.53036) (xy 106.721403 -273.479065)
			(xy 106.441493 -273.479065) (xy 106.433368 -273.53036) (xy 106.41732 -273.579753) (xy 106.393742 -273.626027)
			(xy 106.363216 -273.668043) (xy 106.326493 -273.704766) (xy 106.284477 -273.735292) (xy 106.238203 -273.75887)
			(xy 106.18881 -273.774918) (xy 106.137515 -273.783043) (xy 106.085581 -273.783043) (xy 106.034286 -273.774918)
			(xy 105.984893 -273.75887) (xy 105.938619 -273.735292) (xy 105.896603 -273.704766) (xy 105.85988 -273.668043)
			(xy 105.829354 -273.626027) (xy 105.805776 -273.579753) (xy 105.789728 -273.53036) (xy 105.781603 -273.479065)
			(xy 104.561893 -273.479065) (xy 104.553768 -273.53036) (xy 104.53772 -273.579753) (xy 104.514142 -273.626027)
			(xy 104.483616 -273.668043) (xy 104.446893 -273.704766) (xy 104.404877 -273.735292) (xy 104.358603 -273.75887)
			(xy 104.30921 -273.774918) (xy 104.257915 -273.783043) (xy 104.205981 -273.783043) (xy 104.154686 -273.774918)
			(xy 104.105293 -273.75887) (xy 104.059019 -273.735292) (xy 104.017003 -273.704766) (xy 103.98028 -273.668043)
			(xy 103.949754 -273.626027) (xy 103.926176 -273.579753) (xy 103.910128 -273.53036) (xy 103.902003 -273.479065)
			(xy 103.621839 -273.479065) (xy 103.613714 -273.53036) (xy 103.597666 -273.579753) (xy 103.574088 -273.626027)
			(xy 103.543562 -273.668043) (xy 103.506839 -273.704766) (xy 103.464823 -273.735292) (xy 103.418549 -273.75887)
			(xy 103.369156 -273.774918) (xy 103.317861 -273.783043) (xy 103.265927 -273.783043) (xy 103.214632 -273.774918)
			(xy 103.165239 -273.75887) (xy 103.118965 -273.735292) (xy 103.076949 -273.704766) (xy 103.040226 -273.668043)
			(xy 103.0097 -273.626027) (xy 102.986122 -273.579753) (xy 102.970074 -273.53036) (xy 102.961949 -273.479065)
			(xy 102.682293 -273.479065) (xy 102.674168 -273.53036) (xy 102.65812 -273.579753) (xy 102.634542 -273.626027)
			(xy 102.604016 -273.668043) (xy 102.567293 -273.704766) (xy 102.525277 -273.735292) (xy 102.479003 -273.75887)
			(xy 102.42961 -273.774918) (xy 102.378315 -273.783043) (xy 102.326381 -273.783043) (xy 102.275086 -273.774918)
			(xy 102.225693 -273.75887) (xy 102.179419 -273.735292) (xy 102.137403 -273.704766) (xy 102.10068 -273.668043)
			(xy 102.070154 -273.626027) (xy 102.046576 -273.579753) (xy 102.030528 -273.53036) (xy 102.022403 -273.479065)
			(xy 101.742239 -273.479065) (xy 101.734114 -273.53036) (xy 101.718066 -273.579753) (xy 101.694488 -273.626027)
			(xy 101.663962 -273.668043) (xy 101.627239 -273.704766) (xy 101.585223 -273.735292) (xy 101.538949 -273.75887)
			(xy 101.489556 -273.774918) (xy 101.438261 -273.783043) (xy 101.386327 -273.783043) (xy 101.335032 -273.774918)
			(xy 101.285639 -273.75887) (xy 101.239365 -273.735292) (xy 101.197349 -273.704766) (xy 101.160626 -273.668043)
			(xy 101.1301 -273.626027) (xy 101.106522 -273.579753) (xy 101.090474 -273.53036) (xy 101.082349 -273.479065)
			(xy 100.802693 -273.479065) (xy 100.794568 -273.53036) (xy 100.77852 -273.579753) (xy 100.754942 -273.626027)
			(xy 100.724416 -273.668043) (xy 100.687693 -273.704766) (xy 100.645677 -273.735292) (xy 100.599403 -273.75887)
			(xy 100.55001 -273.774918) (xy 100.498715 -273.783043) (xy 100.446781 -273.783043) (xy 100.395486 -273.774918)
			(xy 100.346093 -273.75887) (xy 100.299819 -273.735292) (xy 100.257803 -273.704766) (xy 100.22108 -273.668043)
			(xy 100.190554 -273.626027) (xy 100.166976 -273.579753) (xy 100.150928 -273.53036) (xy 100.142803 -273.479065)
			(xy 99.862893 -273.479065) (xy 99.854768 -273.53036) (xy 99.83872 -273.579753) (xy 99.815142 -273.626027)
			(xy 99.784616 -273.668043) (xy 99.747893 -273.704766) (xy 99.705877 -273.735292) (xy 99.659603 -273.75887)
			(xy 99.61021 -273.774918) (xy 99.558915 -273.783043) (xy 99.506981 -273.783043) (xy 99.455686 -273.774918)
			(xy 99.406293 -273.75887) (xy 99.360019 -273.735292) (xy 99.318003 -273.704766) (xy 99.28128 -273.668043)
			(xy 99.250754 -273.626027) (xy 99.227176 -273.579753) (xy 99.211128 -273.53036) (xy 99.203003 -273.479065)
			(xy 98.923093 -273.479065) (xy 98.914968 -273.53036) (xy 98.89892 -273.579753) (xy 98.875342 -273.626027)
			(xy 98.844816 -273.668043) (xy 98.808093 -273.704766) (xy 98.766077 -273.735292) (xy 98.719803 -273.75887)
			(xy 98.67041 -273.774918) (xy 98.619115 -273.783043) (xy 98.567181 -273.783043) (xy 98.515886 -273.774918)
			(xy 98.466493 -273.75887) (xy 98.420219 -273.735292) (xy 98.378203 -273.704766) (xy 98.34148 -273.668043)
			(xy 98.310954 -273.626027) (xy 98.287376 -273.579753) (xy 98.271328 -273.53036) (xy 98.263203 -273.479065)
			(xy 97.983293 -273.479065) (xy 97.975168 -273.53036) (xy 97.95912 -273.579753) (xy 97.935542 -273.626027)
			(xy 97.905016 -273.668043) (xy 97.868293 -273.704766) (xy 97.826277 -273.735292) (xy 97.780003 -273.75887)
			(xy 97.73061 -273.774918) (xy 97.679315 -273.783043) (xy 97.627381 -273.783043) (xy 97.576086 -273.774918)
			(xy 97.526693 -273.75887) (xy 97.480419 -273.735292) (xy 97.438403 -273.704766) (xy 97.40168 -273.668043)
			(xy 97.371154 -273.626027) (xy 97.347576 -273.579753) (xy 97.331528 -273.53036) (xy 97.323403 -273.479065)
			(xy 97.043493 -273.479065) (xy 97.035368 -273.53036) (xy 97.01932 -273.579753) (xy 96.995742 -273.626027)
			(xy 96.965216 -273.668043) (xy 96.928493 -273.704766) (xy 96.886477 -273.735292) (xy 96.840203 -273.75887)
			(xy 96.79081 -273.774918) (xy 96.739515 -273.783043) (xy 96.687581 -273.783043) (xy 96.636286 -273.774918)
			(xy 96.586893 -273.75887) (xy 96.540619 -273.735292) (xy 96.498603 -273.704766) (xy 96.46188 -273.668043)
			(xy 96.431354 -273.626027) (xy 96.407776 -273.579753) (xy 96.391728 -273.53036) (xy 96.383603 -273.479065)
			(xy 96.103949 -273.479065) (xy 96.103949 -273.479845) (xy 96.095346 -273.532643) (xy 96.078363 -273.58337)
			(xy 96.066356 -273.607276) (xy 96.066102 -273.608038) (xy 96.063308 -273.613626) (xy 96.060514 -273.624548)
			(xy 96.060514 -273.84248) (xy 96.061096 -273.85372) (xy 96.070722 -273.874031) (xy 96.079056 -273.881596)
			(xy 96.139254 -273.93138) (xy 96.14367 -273.934855) (xy 96.153668 -273.939979) (xy 96.159066 -273.94154)
			(xy 96.169734 -273.944334) (xy 96.181164 -273.942048) (xy 96.196384 -273.939319) (xy 96.22717 -273.93639)
			(xy 96.242632 -273.936206) (xy 96.243394 -273.936206) (xy 96.269382 -273.936689) (xy 96.32072 -273.944819)
			(xy 96.370153 -273.96088) (xy 96.416465 -273.984476) (xy 96.458515 -274.015027) (xy 96.495269 -274.05178)
			(xy 96.525821 -274.09383) (xy 96.549418 -274.140142) (xy 96.56548 -274.189575) (xy 96.573611 -274.240912)
			(xy 96.573611 -274.292881) (xy 96.853249 -274.292881) (xy 96.853249 -274.240947) (xy 96.861374 -274.189652)
			(xy 96.877422 -274.140259) (xy 96.901 -274.093985) (xy 96.931526 -274.051969) (xy 96.968249 -274.015246)
			(xy 97.010265 -273.98472) (xy 97.056539 -273.961142) (xy 97.105932 -273.945094) (xy 97.157227 -273.936969)
			(xy 97.209161 -273.936969) (xy 97.260456 -273.945094) (xy 97.309849 -273.961142) (xy 97.356123 -273.98472)
			(xy 97.398139 -274.015246) (xy 97.434862 -274.051969) (xy 97.465388 -274.093985) (xy 97.488966 -274.140259)
			(xy 97.505014 -274.189652) (xy 97.513139 -274.240947) (xy 97.513648 -274.266914) (xy 97.513139 -274.292881)
			(xy 97.793049 -274.292881) (xy 97.793049 -274.240947) (xy 97.801174 -274.189652) (xy 97.817222 -274.140259)
			(xy 97.8408 -274.093985) (xy 97.871326 -274.051969) (xy 97.908049 -274.015246) (xy 97.950065 -273.98472)
			(xy 97.996339 -273.961142) (xy 98.045732 -273.945094) (xy 98.097027 -273.936969) (xy 98.148961 -273.936969)
			(xy 98.200256 -273.945094) (xy 98.249649 -273.961142) (xy 98.295923 -273.98472) (xy 98.337939 -274.015246)
			(xy 98.374662 -274.051969) (xy 98.405188 -274.093985) (xy 98.428766 -274.140259) (xy 98.444814 -274.189652)
			(xy 98.452939 -274.240947) (xy 98.453448 -274.266914) (xy 98.452939 -274.292881) (xy 98.732849 -274.292881)
			(xy 98.732849 -274.240947) (xy 98.740974 -274.189652) (xy 98.757022 -274.140259) (xy 98.7806 -274.093985)
			(xy 98.811126 -274.051969) (xy 98.847849 -274.015246) (xy 98.889865 -273.98472) (xy 98.936139 -273.961142)
			(xy 98.985532 -273.945094) (xy 99.036827 -273.936969) (xy 99.088761 -273.936969) (xy 99.140056 -273.945094)
			(xy 99.189449 -273.961142) (xy 99.235723 -273.98472) (xy 99.277739 -274.015246) (xy 99.314462 -274.051969)
			(xy 99.344988 -274.093985) (xy 99.368566 -274.140259) (xy 99.384614 -274.189652) (xy 99.392739 -274.240947)
			(xy 99.393248 -274.266914) (xy 99.392739 -274.292881) (xy 99.672649 -274.292881) (xy 99.672649 -274.240947)
			(xy 99.680774 -274.189652) (xy 99.696822 -274.140259) (xy 99.7204 -274.093985) (xy 99.750926 -274.051969)
			(xy 99.787649 -274.015246) (xy 99.829665 -273.98472) (xy 99.875939 -273.961142) (xy 99.925332 -273.945094)
			(xy 99.976627 -273.936969) (xy 100.028561 -273.936969) (xy 100.079856 -273.945094) (xy 100.129249 -273.961142)
			(xy 100.175523 -273.98472) (xy 100.217539 -274.015246) (xy 100.254262 -274.051969) (xy 100.284788 -274.093985)
			(xy 100.308366 -274.140259) (xy 100.324414 -274.189652) (xy 100.332539 -274.240947) (xy 100.333048 -274.266914)
			(xy 100.332539 -274.292881) (xy 100.612449 -274.292881) (xy 100.612449 -274.240947) (xy 100.620574 -274.189652)
			(xy 100.636622 -274.140259) (xy 100.6602 -274.093985) (xy 100.690726 -274.051969) (xy 100.727449 -274.015246)
			(xy 100.769465 -273.98472) (xy 100.815739 -273.961142) (xy 100.865132 -273.945094) (xy 100.916427 -273.936969)
			(xy 100.968361 -273.936969) (xy 101.019656 -273.945094) (xy 101.069049 -273.961142) (xy 101.115323 -273.98472)
			(xy 101.157339 -274.015246) (xy 101.194062 -274.051969) (xy 101.224588 -274.093985) (xy 101.248166 -274.140259)
			(xy 101.264214 -274.189652) (xy 101.272339 -274.240947) (xy 101.272848 -274.266914) (xy 101.272339 -274.292881)
			(xy 101.552249 -274.292881) (xy 101.552249 -274.240947) (xy 101.560374 -274.189652) (xy 101.576422 -274.140259)
			(xy 101.6 -274.093985) (xy 101.630526 -274.051969) (xy 101.667249 -274.015246) (xy 101.709265 -273.98472)
			(xy 101.755539 -273.961142) (xy 101.804932 -273.945094) (xy 101.856227 -273.936969) (xy 101.908161 -273.936969)
			(xy 101.959456 -273.945094) (xy 102.008849 -273.961142) (xy 102.055123 -273.98472) (xy 102.097139 -274.015246)
			(xy 102.133862 -274.051969) (xy 102.164388 -274.093985) (xy 102.187966 -274.140259) (xy 102.204014 -274.189652)
			(xy 102.212139 -274.240947) (xy 102.212648 -274.266914) (xy 102.212139 -274.292881) (xy 102.492049 -274.292881)
			(xy 102.492049 -274.240947) (xy 102.500174 -274.189652) (xy 102.516222 -274.140259) (xy 102.5398 -274.093985)
			(xy 102.570326 -274.051969) (xy 102.607049 -274.015246) (xy 102.649065 -273.98472) (xy 102.695339 -273.961142)
			(xy 102.744732 -273.945094) (xy 102.796027 -273.936969) (xy 102.847961 -273.936969) (xy 102.899256 -273.945094)
			(xy 102.948649 -273.961142) (xy 102.994923 -273.98472) (xy 103.036939 -274.015246) (xy 103.073662 -274.051969)
			(xy 103.104188 -274.093985) (xy 103.127766 -274.140259) (xy 103.143814 -274.189652) (xy 103.151939 -274.240947)
			(xy 103.152448 -274.266914) (xy 103.43134 -274.266914) (xy 103.431849 -274.240947) (xy 103.439974 -274.189652)
			(xy 103.456022 -274.140259) (xy 103.4796 -274.093985) (xy 103.510126 -274.051969) (xy 103.546849 -274.015246)
			(xy 103.588865 -273.98472) (xy 103.635139 -273.961142) (xy 103.684532 -273.945094) (xy 103.735827 -273.936969)
			(xy 103.787761 -273.936969) (xy 103.839056 -273.945094) (xy 103.888449 -273.961142) (xy 103.934723 -273.98472)
			(xy 103.976739 -274.015246) (xy 104.013462 -274.051969) (xy 104.043988 -274.093985) (xy 104.067566 -274.140259)
			(xy 104.083614 -274.189652) (xy 104.091739 -274.240947) (xy 104.092248 -274.266914) (xy 104.092248 -274.267168)
			(xy 104.091707 -274.292881) (xy 104.371649 -274.292881) (xy 104.371649 -274.240947) (xy 104.379774 -274.189652)
			(xy 104.395822 -274.140259) (xy 104.4194 -274.093985) (xy 104.449926 -274.051969) (xy 104.486649 -274.015246)
			(xy 104.528665 -273.98472) (xy 104.574939 -273.961142) (xy 104.624332 -273.945094) (xy 104.675627 -273.936969)
			(xy 104.727561 -273.936969) (xy 104.778856 -273.945094) (xy 104.828249 -273.961142) (xy 104.874523 -273.98472)
			(xy 104.916539 -274.015246) (xy 104.953262 -274.051969) (xy 104.983788 -274.093985) (xy 105.007366 -274.140259)
			(xy 105.023414 -274.189652) (xy 105.031539 -274.240947) (xy 105.032048 -274.266914) (xy 105.031539 -274.292881)
			(xy 105.311449 -274.292881) (xy 105.311449 -274.240947) (xy 105.319574 -274.189652) (xy 105.335622 -274.140259)
			(xy 105.3592 -274.093985) (xy 105.389726 -274.051969) (xy 105.426449 -274.015246) (xy 105.468465 -273.98472)
			(xy 105.514739 -273.961142) (xy 105.564132 -273.945094) (xy 105.615427 -273.936969) (xy 105.667361 -273.936969)
			(xy 105.718656 -273.945094) (xy 105.768049 -273.961142) (xy 105.814323 -273.98472) (xy 105.856339 -274.015246)
			(xy 105.893062 -274.051969) (xy 105.923588 -274.093985) (xy 105.947166 -274.140259) (xy 105.963214 -274.189652)
			(xy 105.971339 -274.240947) (xy 105.971848 -274.266914) (xy 105.971339 -274.292881) (xy 106.251249 -274.292881)
			(xy 106.251249 -274.240947) (xy 106.259374 -274.189652) (xy 106.275422 -274.140259) (xy 106.299 -274.093985)
			(xy 106.329526 -274.051969) (xy 106.366249 -274.015246) (xy 106.408265 -273.98472) (xy 106.454539 -273.961142)
			(xy 106.503932 -273.945094) (xy 106.555227 -273.936969) (xy 106.607161 -273.936969) (xy 106.658456 -273.945094)
			(xy 106.707849 -273.961142) (xy 106.754123 -273.98472) (xy 106.796139 -274.015246) (xy 106.832862 -274.051969)
			(xy 106.863388 -274.093985) (xy 106.886966 -274.140259) (xy 106.903014 -274.189652) (xy 106.911139 -274.240947)
			(xy 106.911648 -274.266914) (xy 106.911139 -274.292881) (xy 107.191049 -274.292881) (xy 107.191049 -274.240947)
			(xy 107.199174 -274.189652) (xy 107.215222 -274.140259) (xy 107.2388 -274.093985) (xy 107.269326 -274.051969)
			(xy 107.306049 -274.015246) (xy 107.348065 -273.98472) (xy 107.394339 -273.961142) (xy 107.443732 -273.945094)
			(xy 107.495027 -273.936969) (xy 107.546961 -273.936969) (xy 107.598256 -273.945094) (xy 107.647649 -273.961142)
			(xy 107.693923 -273.98472) (xy 107.735939 -274.015246) (xy 107.772662 -274.051969) (xy 107.803188 -274.093985)
			(xy 107.826766 -274.140259) (xy 107.842814 -274.189652) (xy 107.850939 -274.240947) (xy 107.851448 -274.266914)
			(xy 107.850939 -274.292881) (xy 108.131103 -274.292881) (xy 108.131103 -274.240947) (xy 108.139228 -274.189652)
			(xy 108.155276 -274.140259) (xy 108.178854 -274.093985) (xy 108.20938 -274.051969) (xy 108.246103 -274.015246)
			(xy 108.288119 -273.98472) (xy 108.334393 -273.961142) (xy 108.383786 -273.945094) (xy 108.435081 -273.936969)
			(xy 108.487015 -273.936969) (xy 108.53831 -273.945094) (xy 108.587703 -273.961142) (xy 108.633977 -273.98472)
			(xy 108.675993 -274.015246) (xy 108.712716 -274.051969) (xy 108.743242 -274.093985) (xy 108.76682 -274.140259)
			(xy 108.782868 -274.189652) (xy 108.790993 -274.240947) (xy 108.791502 -274.266914) (xy 108.790993 -274.292881)
			(xy 108.782868 -274.344176) (xy 108.76682 -274.393569) (xy 108.743242 -274.439843) (xy 108.712716 -274.481859)
			(xy 108.675993 -274.518582) (xy 108.633977 -274.549108) (xy 108.587703 -274.572686) (xy 108.53831 -274.588734)
			(xy 108.487015 -274.596859) (xy 108.435081 -274.596859) (xy 108.383786 -274.588734) (xy 108.334393 -274.572686)
			(xy 108.288119 -274.549108) (xy 108.246103 -274.518582) (xy 108.20938 -274.481859) (xy 108.178854 -274.439843)
			(xy 108.155276 -274.393569) (xy 108.139228 -274.344176) (xy 108.131103 -274.292881) (xy 107.850939 -274.292881)
			(xy 107.842814 -274.344176) (xy 107.826766 -274.393569) (xy 107.803188 -274.439843) (xy 107.772662 -274.481859)
			(xy 107.735939 -274.518582) (xy 107.693923 -274.549108) (xy 107.647649 -274.572686) (xy 107.598256 -274.588734)
			(xy 107.546961 -274.596859) (xy 107.495027 -274.596859) (xy 107.443732 -274.588734) (xy 107.394339 -274.572686)
			(xy 107.348065 -274.549108) (xy 107.306049 -274.518582) (xy 107.269326 -274.481859) (xy 107.2388 -274.439843)
			(xy 107.215222 -274.393569) (xy 107.199174 -274.344176) (xy 107.191049 -274.292881) (xy 106.911139 -274.292881)
			(xy 106.903014 -274.344176) (xy 106.886966 -274.393569) (xy 106.863388 -274.439843) (xy 106.832862 -274.481859)
			(xy 106.796139 -274.518582) (xy 106.754123 -274.549108) (xy 106.707849 -274.572686) (xy 106.658456 -274.588734)
			(xy 106.607161 -274.596859) (xy 106.555227 -274.596859) (xy 106.503932 -274.588734) (xy 106.454539 -274.572686)
			(xy 106.408265 -274.549108) (xy 106.366249 -274.518582) (xy 106.329526 -274.481859) (xy 106.299 -274.439843)
			(xy 106.275422 -274.393569) (xy 106.259374 -274.344176) (xy 106.251249 -274.292881) (xy 105.971339 -274.292881)
			(xy 105.963214 -274.344176) (xy 105.947166 -274.393569) (xy 105.923588 -274.439843) (xy 105.893062 -274.481859)
			(xy 105.856339 -274.518582) (xy 105.814323 -274.549108) (xy 105.768049 -274.572686) (xy 105.718656 -274.588734)
			(xy 105.667361 -274.596859) (xy 105.615427 -274.596859) (xy 105.564132 -274.588734) (xy 105.514739 -274.572686)
			(xy 105.468465 -274.549108) (xy 105.426449 -274.518582) (xy 105.389726 -274.481859) (xy 105.3592 -274.439843)
			(xy 105.335622 -274.393569) (xy 105.319574 -274.344176) (xy 105.311449 -274.292881) (xy 105.031539 -274.292881)
			(xy 105.023414 -274.344176) (xy 105.007366 -274.393569) (xy 104.983788 -274.439843) (xy 104.953262 -274.481859)
			(xy 104.916539 -274.518582) (xy 104.874523 -274.549108) (xy 104.828249 -274.572686) (xy 104.778856 -274.588734)
			(xy 104.727561 -274.596859) (xy 104.675627 -274.596859) (xy 104.624332 -274.588734) (xy 104.574939 -274.572686)
			(xy 104.528665 -274.549108) (xy 104.486649 -274.518582) (xy 104.449926 -274.481859) (xy 104.4194 -274.439843)
			(xy 104.395822 -274.393569) (xy 104.379774 -274.344176) (xy 104.371649 -274.292881) (xy 104.091707 -274.292881)
			(xy 104.091664 -274.294949) (xy 104.082349 -274.349725) (xy 104.073706 -274.376134) (xy 104.065832 -274.398232)
			(xy 104.269794 -274.751546) (xy 104.292908 -274.755864) (xy 104.317824 -274.761057) (xy 104.365808 -274.778017)
			(xy 104.410626 -274.80213) (xy 104.45122 -274.832827) (xy 104.486629 -274.869382) (xy 104.516019 -274.910931)
			(xy 104.538694 -274.956494) (xy 104.554118 -275.004993) (xy 104.561928 -275.055284) (xy 104.562402 -275.08073)
			(xy 104.561893 -275.106697) (xy 104.553768 -275.157992) (xy 104.53772 -275.207385) (xy 104.514142 -275.253659)
			(xy 104.483616 -275.295675) (xy 104.446893 -275.332398) (xy 104.404877 -275.362924) (xy 104.358603 -275.386502)
			(xy 104.30921 -275.40255) (xy 104.257915 -275.410675) (xy 104.205981 -275.410675) (xy 104.154686 -275.40255)
			(xy 104.105293 -275.386502) (xy 104.059019 -275.362924) (xy 104.017003 -275.332398) (xy 103.98028 -275.295675)
			(xy 103.949754 -275.253659) (xy 103.926176 -275.207385) (xy 103.910128 -275.157992) (xy 103.902003 -275.106697)
			(xy 103.901494 -275.08073) (xy 103.902054 -275.052745) (xy 103.911499 -274.997577) (xy 103.92029 -274.971002)
			(xy 103.92791 -274.948904) (xy 103.724202 -274.596098) (xy 103.701342 -274.59178) (xy 103.676384 -274.586659)
			(xy 103.628321 -274.569761) (xy 103.58342 -274.545687) (xy 103.542746 -274.515007) (xy 103.507263 -274.478448)
			(xy 103.477811 -274.436877) (xy 103.455088 -274.391277) (xy 103.439633 -274.342731) (xy 103.431812 -274.292388)
			(xy 103.43134 -274.266914) (xy 103.152448 -274.266914) (xy 103.151939 -274.292881) (xy 103.143814 -274.344176)
			(xy 103.127766 -274.393569) (xy 103.104188 -274.439843) (xy 103.073662 -274.481859) (xy 103.036939 -274.518582)
			(xy 102.994923 -274.549108) (xy 102.948649 -274.572686) (xy 102.899256 -274.588734) (xy 102.847961 -274.596859)
			(xy 102.796027 -274.596859) (xy 102.744732 -274.588734) (xy 102.695339 -274.572686) (xy 102.649065 -274.549108)
			(xy 102.607049 -274.518582) (xy 102.570326 -274.481859) (xy 102.5398 -274.439843) (xy 102.516222 -274.393569)
			(xy 102.500174 -274.344176) (xy 102.492049 -274.292881) (xy 102.212139 -274.292881) (xy 102.204014 -274.344176)
			(xy 102.187966 -274.393569) (xy 102.164388 -274.439843) (xy 102.133862 -274.481859) (xy 102.097139 -274.518582)
			(xy 102.055123 -274.549108) (xy 102.008849 -274.572686) (xy 101.959456 -274.588734) (xy 101.908161 -274.596859)
			(xy 101.856227 -274.596859) (xy 101.804932 -274.588734) (xy 101.755539 -274.572686) (xy 101.709265 -274.549108)
			(xy 101.667249 -274.518582) (xy 101.630526 -274.481859) (xy 101.6 -274.439843) (xy 101.576422 -274.393569)
			(xy 101.560374 -274.344176) (xy 101.552249 -274.292881) (xy 101.272339 -274.292881) (xy 101.264214 -274.344176)
			(xy 101.248166 -274.393569) (xy 101.224588 -274.439843) (xy 101.194062 -274.481859) (xy 101.157339 -274.518582)
			(xy 101.115323 -274.549108) (xy 101.069049 -274.572686) (xy 101.019656 -274.588734) (xy 100.968361 -274.596859)
			(xy 100.916427 -274.596859) (xy 100.865132 -274.588734) (xy 100.815739 -274.572686) (xy 100.769465 -274.549108)
			(xy 100.727449 -274.518582) (xy 100.690726 -274.481859) (xy 100.6602 -274.439843) (xy 100.636622 -274.393569)
			(xy 100.620574 -274.344176) (xy 100.612449 -274.292881) (xy 100.332539 -274.292881) (xy 100.324414 -274.344176)
			(xy 100.308366 -274.393569) (xy 100.284788 -274.439843) (xy 100.254262 -274.481859) (xy 100.217539 -274.518582)
			(xy 100.175523 -274.549108) (xy 100.129249 -274.572686) (xy 100.079856 -274.588734) (xy 100.028561 -274.596859)
			(xy 99.976627 -274.596859) (xy 99.925332 -274.588734) (xy 99.875939 -274.572686) (xy 99.829665 -274.549108)
			(xy 99.787649 -274.518582) (xy 99.750926 -274.481859) (xy 99.7204 -274.439843) (xy 99.696822 -274.393569)
			(xy 99.680774 -274.344176) (xy 99.672649 -274.292881) (xy 99.392739 -274.292881) (xy 99.384614 -274.344176)
			(xy 99.368566 -274.393569) (xy 99.344988 -274.439843) (xy 99.314462 -274.481859) (xy 99.277739 -274.518582)
			(xy 99.235723 -274.549108) (xy 99.189449 -274.572686) (xy 99.140056 -274.588734) (xy 99.088761 -274.596859)
			(xy 99.036827 -274.596859) (xy 98.985532 -274.588734) (xy 98.936139 -274.572686) (xy 98.889865 -274.549108)
			(xy 98.847849 -274.518582) (xy 98.811126 -274.481859) (xy 98.7806 -274.439843) (xy 98.757022 -274.393569)
			(xy 98.740974 -274.344176) (xy 98.732849 -274.292881) (xy 98.452939 -274.292881) (xy 98.444814 -274.344176)
			(xy 98.428766 -274.393569) (xy 98.405188 -274.439843) (xy 98.374662 -274.481859) (xy 98.337939 -274.518582)
			(xy 98.295923 -274.549108) (xy 98.249649 -274.572686) (xy 98.200256 -274.588734) (xy 98.148961 -274.596859)
			(xy 98.097027 -274.596859) (xy 98.045732 -274.588734) (xy 97.996339 -274.572686) (xy 97.950065 -274.549108)
			(xy 97.908049 -274.518582) (xy 97.871326 -274.481859) (xy 97.8408 -274.439843) (xy 97.817222 -274.393569)
			(xy 97.801174 -274.344176) (xy 97.793049 -274.292881) (xy 97.513139 -274.292881) (xy 97.505014 -274.344176)
			(xy 97.488966 -274.393569) (xy 97.465388 -274.439843) (xy 97.434862 -274.481859) (xy 97.398139 -274.518582)
			(xy 97.356123 -274.549108) (xy 97.309849 -274.572686) (xy 97.260456 -274.588734) (xy 97.209161 -274.596859)
			(xy 97.157227 -274.596859) (xy 97.105932 -274.588734) (xy 97.056539 -274.572686) (xy 97.010265 -274.549108)
			(xy 96.968249 -274.518582) (xy 96.931526 -274.481859) (xy 96.901 -274.439843) (xy 96.877422 -274.393569)
			(xy 96.861374 -274.344176) (xy 96.853249 -274.292881) (xy 96.573611 -274.292881) (xy 96.573611 -274.292888)
			(xy 96.56548 -274.344225) (xy 96.549418 -274.393658) (xy 96.525821 -274.43997) (xy 96.495269 -274.48202)
			(xy 96.458515 -274.518773) (xy 96.416465 -274.549324) (xy 96.370153 -274.57292) (xy 96.32072 -274.588981)
			(xy 96.269382 -274.597111) (xy 96.243394 -274.597622) (xy 96.242632 -274.597622) (xy 96.227171 -274.597419)
			(xy 96.196386 -274.594497) (xy 96.181164 -274.59178) (xy 96.169734 -274.589494) (xy 96.159066 -274.592288)
			(xy 96.153662 -274.593834) (xy 96.143665 -274.598964) (xy 96.139254 -274.602448) (xy 96.079056 -274.652232)
			(xy 96.070766 -274.659831) (xy 96.061132 -274.680121) (xy 96.060514 -274.691348) (xy 96.060514 -274.90293)
			(xy 96.065594 -274.925028) (xy 96.066102 -274.92579) (xy 96.066356 -274.926552) (xy 96.078359 -274.950459)
			(xy 96.095337 -275.001185) (xy 96.103936 -275.053981) (xy 96.103932 -275.106697) (xy 96.383603 -275.106697)
			(xy 96.383603 -275.054763) (xy 96.391728 -275.003468) (xy 96.407776 -274.954075) (xy 96.431354 -274.907801)
			(xy 96.46188 -274.865785) (xy 96.498603 -274.829062) (xy 96.540619 -274.798536) (xy 96.586893 -274.774958)
			(xy 96.636286 -274.75891) (xy 96.687581 -274.750785) (xy 96.739515 -274.750785) (xy 96.79081 -274.75891)
			(xy 96.840203 -274.774958) (xy 96.886477 -274.798536) (xy 96.928493 -274.829062) (xy 96.965216 -274.865785)
			(xy 96.995742 -274.907801) (xy 97.01932 -274.954075) (xy 97.035368 -275.003468) (xy 97.043493 -275.054763)
			(xy 97.044002 -275.08073) (xy 97.043493 -275.106697) (xy 97.323403 -275.106697) (xy 97.323403 -275.054763)
			(xy 97.331528 -275.003468) (xy 97.347576 -274.954075) (xy 97.371154 -274.907801) (xy 97.40168 -274.865785)
			(xy 97.438403 -274.829062) (xy 97.480419 -274.798536) (xy 97.526693 -274.774958) (xy 97.576086 -274.75891)
			(xy 97.627381 -274.750785) (xy 97.679315 -274.750785) (xy 97.73061 -274.75891) (xy 97.780003 -274.774958)
			(xy 97.826277 -274.798536) (xy 97.868293 -274.829062) (xy 97.905016 -274.865785) (xy 97.935542 -274.907801)
			(xy 97.95912 -274.954075) (xy 97.975168 -275.003468) (xy 97.983293 -275.054763) (xy 97.983802 -275.08073)
			(xy 97.983293 -275.106697) (xy 98.262949 -275.106697) (xy 98.262949 -275.054763) (xy 98.271074 -275.003468)
			(xy 98.287122 -274.954075) (xy 98.3107 -274.907801) (xy 98.341226 -274.865785) (xy 98.377949 -274.829062)
			(xy 98.419965 -274.798536) (xy 98.466239 -274.774958) (xy 98.515632 -274.75891) (xy 98.566927 -274.750785)
			(xy 98.618861 -274.750785) (xy 98.670156 -274.75891) (xy 98.719549 -274.774958) (xy 98.765823 -274.798536)
			(xy 98.807839 -274.829062) (xy 98.844562 -274.865785) (xy 98.875088 -274.907801) (xy 98.898666 -274.954075)
			(xy 98.914714 -275.003468) (xy 98.922839 -275.054763) (xy 98.923348 -275.08073) (xy 98.922839 -275.106697)
			(xy 99.203003 -275.106697) (xy 99.203003 -275.054763) (xy 99.211128 -275.003468) (xy 99.227176 -274.954075)
			(xy 99.250754 -274.907801) (xy 99.28128 -274.865785) (xy 99.318003 -274.829062) (xy 99.360019 -274.798536)
			(xy 99.406293 -274.774958) (xy 99.455686 -274.75891) (xy 99.506981 -274.750785) (xy 99.558915 -274.750785)
			(xy 99.61021 -274.75891) (xy 99.659603 -274.774958) (xy 99.705877 -274.798536) (xy 99.747893 -274.829062)
			(xy 99.784616 -274.865785) (xy 99.815142 -274.907801) (xy 99.83872 -274.954075) (xy 99.854768 -275.003468)
			(xy 99.862893 -275.054763) (xy 99.863402 -275.08073) (xy 99.862893 -275.106697) (xy 100.142803 -275.106697)
			(xy 100.142803 -275.054763) (xy 100.150928 -275.003468) (xy 100.166976 -274.954075) (xy 100.190554 -274.907801)
			(xy 100.22108 -274.865785) (xy 100.257803 -274.829062) (xy 100.299819 -274.798536) (xy 100.346093 -274.774958)
			(xy 100.395486 -274.75891) (xy 100.446781 -274.750785) (xy 100.498715 -274.750785) (xy 100.55001 -274.75891)
			(xy 100.599403 -274.774958) (xy 100.645677 -274.798536) (xy 100.687693 -274.829062) (xy 100.724416 -274.865785)
			(xy 100.754942 -274.907801) (xy 100.77852 -274.954075) (xy 100.794568 -275.003468) (xy 100.802693 -275.054763)
			(xy 100.803202 -275.08073) (xy 100.802693 -275.106697) (xy 101.082603 -275.106697) (xy 101.082603 -275.054763)
			(xy 101.090728 -275.003468) (xy 101.106776 -274.954075) (xy 101.130354 -274.907801) (xy 101.16088 -274.865785)
			(xy 101.197603 -274.829062) (xy 101.239619 -274.798536) (xy 101.285893 -274.774958) (xy 101.335286 -274.75891)
			(xy 101.386581 -274.750785) (xy 101.438515 -274.750785) (xy 101.48981 -274.75891) (xy 101.539203 -274.774958)
			(xy 101.585477 -274.798536) (xy 101.627493 -274.829062) (xy 101.664216 -274.865785) (xy 101.694742 -274.907801)
			(xy 101.71832 -274.954075) (xy 101.734368 -275.003468) (xy 101.742493 -275.054763) (xy 101.743002 -275.08073)
			(xy 101.742494 -275.106669) (xy 102.022359 -275.106669) (xy 102.022359 -275.054731) (xy 102.030485 -275.003432)
			(xy 102.046536 -274.954035) (xy 102.070118 -274.907759) (xy 102.100649 -274.865741) (xy 102.137378 -274.829018)
			(xy 102.1794 -274.798493) (xy 102.22568 -274.774918) (xy 102.275078 -274.758873) (xy 102.326379 -274.750755)
			(xy 102.352348 -274.750276) (xy 102.377982 -274.750805) (xy 102.428635 -274.758722) (xy 102.477456 -274.774373)
			(xy 102.523271 -274.797381) (xy 102.564978 -274.827195) (xy 102.601577 -274.863097) (xy 102.61727 -274.883372)
			(xy 103.027226 -274.883372) (xy 103.042943 -274.863115) (xy 103.079534 -274.827204) (xy 103.121236 -274.797381)
			(xy 103.167045 -274.77436) (xy 103.215862 -274.758696) (xy 103.266514 -274.750764) (xy 103.292148 -274.750276)
			(xy 103.318115 -274.750729) (xy 103.369409 -274.75886) (xy 103.4188 -274.774914) (xy 103.465071 -274.798497)
			(xy 103.507084 -274.829027) (xy 103.543805 -274.865752) (xy 103.574328 -274.90777) (xy 103.597904 -274.954045)
			(xy 103.613951 -275.003438) (xy 103.622075 -275.054733) (xy 103.622075 -275.106667) (xy 103.613951 -275.157962)
			(xy 103.597904 -275.207355) (xy 103.574328 -275.25363) (xy 103.543805 -275.295648) (xy 103.507084 -275.332373)
			(xy 103.465071 -275.362903) (xy 103.4188 -275.386486) (xy 103.369409 -275.40254) (xy 103.318115 -275.410671)
			(xy 103.292148 -275.411184) (xy 103.266513 -275.410673) (xy 103.215858 -275.402755) (xy 103.167037 -275.387102)
			(xy 103.121221 -275.36409) (xy 103.079514 -275.334272) (xy 103.042918 -275.298365) (xy 103.027226 -275.278088)
			(xy 102.61727 -275.278088) (xy 102.601544 -275.298339) (xy 102.564956 -275.334251) (xy 102.523257 -275.364077)
			(xy 102.477449 -275.387099) (xy 102.428633 -275.402764) (xy 102.377982 -275.410696) (xy 102.352348 -275.411184)
			(xy 102.326379 -275.410645) (xy 102.275078 -275.402527) (xy 102.22568 -275.386482) (xy 102.1794 -275.362907)
			(xy 102.137378 -275.332382) (xy 102.100649 -275.295659) (xy 102.070118 -275.253641) (xy 102.046536 -275.207365)
			(xy 102.030485 -275.157968) (xy 102.022359 -275.106669) (xy 101.742494 -275.106669) (xy 101.742493 -275.106697)
			(xy 101.734368 -275.157992) (xy 101.71832 -275.207385) (xy 101.694742 -275.253659) (xy 101.664216 -275.295675)
			(xy 101.627493 -275.332398) (xy 101.585477 -275.362924) (xy 101.539203 -275.386502) (xy 101.48981 -275.40255)
			(xy 101.438515 -275.410675) (xy 101.386581 -275.410675) (xy 101.335286 -275.40255) (xy 101.285893 -275.386502)
			(xy 101.239619 -275.362924) (xy 101.197603 -275.332398) (xy 101.16088 -275.295675) (xy 101.130354 -275.253659)
			(xy 101.106776 -275.207385) (xy 101.090728 -275.157992) (xy 101.082603 -275.106697) (xy 100.802693 -275.106697)
			(xy 100.794568 -275.157992) (xy 100.77852 -275.207385) (xy 100.754942 -275.253659) (xy 100.724416 -275.295675)
			(xy 100.687693 -275.332398) (xy 100.645677 -275.362924) (xy 100.599403 -275.386502) (xy 100.55001 -275.40255)
			(xy 100.498715 -275.410675) (xy 100.446781 -275.410675) (xy 100.395486 -275.40255) (xy 100.346093 -275.386502)
			(xy 100.299819 -275.362924) (xy 100.257803 -275.332398) (xy 100.22108 -275.295675) (xy 100.190554 -275.253659)
			(xy 100.166976 -275.207385) (xy 100.150928 -275.157992) (xy 100.142803 -275.106697) (xy 99.862893 -275.106697)
			(xy 99.854768 -275.157992) (xy 99.83872 -275.207385) (xy 99.815142 -275.253659) (xy 99.784616 -275.295675)
			(xy 99.747893 -275.332398) (xy 99.705877 -275.362924) (xy 99.659603 -275.386502) (xy 99.61021 -275.40255)
			(xy 99.558915 -275.410675) (xy 99.506981 -275.410675) (xy 99.455686 -275.40255) (xy 99.406293 -275.386502)
			(xy 99.360019 -275.362924) (xy 99.318003 -275.332398) (xy 99.28128 -275.295675) (xy 99.250754 -275.253659)
			(xy 99.227176 -275.207385) (xy 99.211128 -275.157992) (xy 99.203003 -275.106697) (xy 98.922839 -275.106697)
			(xy 98.914714 -275.157992) (xy 98.898666 -275.207385) (xy 98.875088 -275.253659) (xy 98.844562 -275.295675)
			(xy 98.807839 -275.332398) (xy 98.765823 -275.362924) (xy 98.719549 -275.386502) (xy 98.670156 -275.40255)
			(xy 98.618861 -275.410675) (xy 98.566927 -275.410675) (xy 98.515632 -275.40255) (xy 98.466239 -275.386502)
			(xy 98.419965 -275.362924) (xy 98.377949 -275.332398) (xy 98.341226 -275.295675) (xy 98.3107 -275.253659)
			(xy 98.287122 -275.207385) (xy 98.271074 -275.157992) (xy 98.262949 -275.106697) (xy 97.983293 -275.106697)
			(xy 97.975168 -275.157992) (xy 97.95912 -275.207385) (xy 97.935542 -275.253659) (xy 97.905016 -275.295675)
			(xy 97.868293 -275.332398) (xy 97.826277 -275.362924) (xy 97.780003 -275.386502) (xy 97.73061 -275.40255)
			(xy 97.679315 -275.410675) (xy 97.627381 -275.410675) (xy 97.576086 -275.40255) (xy 97.526693 -275.386502)
			(xy 97.480419 -275.362924) (xy 97.438403 -275.332398) (xy 97.40168 -275.295675) (xy 97.371154 -275.253659)
			(xy 97.347576 -275.207385) (xy 97.331528 -275.157992) (xy 97.323403 -275.106697) (xy 97.043493 -275.106697)
			(xy 97.035368 -275.157992) (xy 97.01932 -275.207385) (xy 96.995742 -275.253659) (xy 96.965216 -275.295675)
			(xy 96.928493 -275.332398) (xy 96.886477 -275.362924) (xy 96.840203 -275.386502) (xy 96.79081 -275.40255)
			(xy 96.739515 -275.410675) (xy 96.687581 -275.410675) (xy 96.636286 -275.40255) (xy 96.586893 -275.386502)
			(xy 96.540619 -275.362924) (xy 96.498603 -275.332398) (xy 96.46188 -275.295675) (xy 96.431354 -275.253659)
			(xy 96.407776 -275.207385) (xy 96.391728 -275.157992) (xy 96.383603 -275.106697) (xy 96.103932 -275.106697)
			(xy 96.103932 -275.107472) (xy 96.095324 -275.160267) (xy 96.078338 -275.21099) (xy 96.066356 -275.234908)
			(xy 96.066102 -275.23567) (xy 96.063308 -275.241258) (xy 96.060514 -275.25218) (xy 96.060514 -275.470366)
			(xy 96.061093 -275.481607) (xy 96.070716 -275.501923) (xy 96.079056 -275.509482) (xy 96.139254 -275.559266)
			(xy 96.143673 -275.562736) (xy 96.153672 -275.567852) (xy 96.159066 -275.569426) (xy 96.169734 -275.57222)
			(xy 96.181164 -275.569934) (xy 96.196384 -275.567205) (xy 96.22717 -275.564276) (xy 96.242632 -275.564092)
			(xy 96.243394 -275.564092) (xy 96.269384 -275.564575) (xy 96.320723 -275.572705) (xy 96.370158 -275.588767)
			(xy 96.416472 -275.612364) (xy 96.458525 -275.642916) (xy 96.49528 -275.679671) (xy 96.525833 -275.721723)
			(xy 96.549431 -275.768036) (xy 96.565493 -275.817471) (xy 96.573625 -275.86881) (xy 96.573625 -275.920767)
			(xy 96.853249 -275.920767) (xy 96.853249 -275.868833) (xy 96.861374 -275.817538) (xy 96.877422 -275.768145)
			(xy 96.901 -275.721871) (xy 96.931526 -275.679855) (xy 96.968249 -275.643132) (xy 97.010265 -275.612606)
			(xy 97.056539 -275.589028) (xy 97.105932 -275.57298) (xy 97.157227 -275.564855) (xy 97.209161 -275.564855)
			(xy 97.260456 -275.57298) (xy 97.309849 -275.589028) (xy 97.356123 -275.612606) (xy 97.398139 -275.643132)
			(xy 97.434862 -275.679855) (xy 97.465388 -275.721871) (xy 97.488966 -275.768145) (xy 97.505014 -275.817538)
			(xy 97.513139 -275.868833) (xy 97.513648 -275.8948) (xy 97.513139 -275.920767) (xy 97.793049 -275.920767)
			(xy 97.793049 -275.868833) (xy 97.801174 -275.817538) (xy 97.817222 -275.768145) (xy 97.8408 -275.721871)
			(xy 97.871326 -275.679855) (xy 97.908049 -275.643132) (xy 97.950065 -275.612606) (xy 97.996339 -275.589028)
			(xy 98.045732 -275.57298) (xy 98.097027 -275.564855) (xy 98.148961 -275.564855) (xy 98.200256 -275.57298)
			(xy 98.249649 -275.589028) (xy 98.295923 -275.612606) (xy 98.337939 -275.643132) (xy 98.374662 -275.679855)
			(xy 98.405188 -275.721871) (xy 98.428766 -275.768145) (xy 98.444814 -275.817538) (xy 98.452939 -275.868833)
			(xy 98.453448 -275.8948) (xy 98.452939 -275.920767) (xy 98.732849 -275.920767) (xy 98.732849 -275.868833)
			(xy 98.740974 -275.817538) (xy 98.757022 -275.768145) (xy 98.7806 -275.721871) (xy 98.811126 -275.679855)
			(xy 98.847849 -275.643132) (xy 98.889865 -275.612606) (xy 98.936139 -275.589028) (xy 98.985532 -275.57298)
			(xy 99.036827 -275.564855) (xy 99.088761 -275.564855) (xy 99.140056 -275.57298) (xy 99.189449 -275.589028)
			(xy 99.235723 -275.612606) (xy 99.277739 -275.643132) (xy 99.314462 -275.679855) (xy 99.344988 -275.721871)
			(xy 99.368566 -275.768145) (xy 99.384614 -275.817538) (xy 99.392739 -275.868833) (xy 99.393248 -275.8948)
			(xy 99.392739 -275.920767) (xy 99.672649 -275.920767) (xy 99.672649 -275.868833) (xy 99.680774 -275.817538)
			(xy 99.696822 -275.768145) (xy 99.7204 -275.721871) (xy 99.750926 -275.679855) (xy 99.787649 -275.643132)
			(xy 99.829665 -275.612606) (xy 99.875939 -275.589028) (xy 99.925332 -275.57298) (xy 99.976627 -275.564855)
			(xy 100.028561 -275.564855) (xy 100.079856 -275.57298) (xy 100.129249 -275.589028) (xy 100.175523 -275.612606)
			(xy 100.217539 -275.643132) (xy 100.254262 -275.679855) (xy 100.284788 -275.721871) (xy 100.308366 -275.768145)
			(xy 100.324414 -275.817538) (xy 100.332539 -275.868833) (xy 100.333048 -275.8948) (xy 100.332539 -275.920767)
			(xy 100.612703 -275.920767) (xy 100.612703 -275.868833) (xy 100.620828 -275.817538) (xy 100.636876 -275.768145)
			(xy 100.660454 -275.721871) (xy 100.69098 -275.679855) (xy 100.727703 -275.643132) (xy 100.769719 -275.612606)
			(xy 100.815993 -275.589028) (xy 100.865386 -275.57298) (xy 100.916681 -275.564855) (xy 100.968615 -275.564855)
			(xy 101.01991 -275.57298) (xy 101.069303 -275.589028) (xy 101.115577 -275.612606) (xy 101.157593 -275.643132)
			(xy 101.194316 -275.679855) (xy 101.224842 -275.721871) (xy 101.24842 -275.768145) (xy 101.264468 -275.817538)
			(xy 101.272593 -275.868833) (xy 101.273102 -275.8948) (xy 101.272593 -275.920767) (xy 101.552249 -275.920767)
			(xy 101.552249 -275.868833) (xy 101.560374 -275.817538) (xy 101.576422 -275.768145) (xy 101.6 -275.721871)
			(xy 101.630526 -275.679855) (xy 101.667249 -275.643132) (xy 101.709265 -275.612606) (xy 101.755539 -275.589028)
			(xy 101.804932 -275.57298) (xy 101.856227 -275.564855) (xy 101.908161 -275.564855) (xy 101.959456 -275.57298)
			(xy 102.008849 -275.589028) (xy 102.055123 -275.612606) (xy 102.097139 -275.643132) (xy 102.133862 -275.679855)
			(xy 102.164388 -275.721871) (xy 102.187966 -275.768145) (xy 102.204014 -275.817538) (xy 102.212139 -275.868833)
			(xy 102.212648 -275.8948) (xy 102.212139 -275.920767) (xy 102.204014 -275.972062) (xy 102.187966 -276.021455)
			(xy 102.164388 -276.067729) (xy 102.133862 -276.109745) (xy 102.097139 -276.146468) (xy 102.055123 -276.176994)
			(xy 102.008849 -276.200572) (xy 101.959456 -276.21662) (xy 101.908161 -276.224745) (xy 101.856227 -276.224745)
			(xy 101.804932 -276.21662) (xy 101.755539 -276.200572) (xy 101.709265 -276.176994) (xy 101.667249 -276.146468)
			(xy 101.630526 -276.109745) (xy 101.6 -276.067729) (xy 101.576422 -276.021455) (xy 101.560374 -275.972062)
			(xy 101.552249 -275.920767) (xy 101.272593 -275.920767) (xy 101.264468 -275.972062) (xy 101.24842 -276.021455)
			(xy 101.224842 -276.067729) (xy 101.194316 -276.109745) (xy 101.157593 -276.146468) (xy 101.115577 -276.176994)
			(xy 101.069303 -276.200572) (xy 101.01991 -276.21662) (xy 100.968615 -276.224745) (xy 100.916681 -276.224745)
			(xy 100.865386 -276.21662) (xy 100.815993 -276.200572) (xy 100.769719 -276.176994) (xy 100.727703 -276.146468)
			(xy 100.69098 -276.109745) (xy 100.660454 -276.067729) (xy 100.636876 -276.021455) (xy 100.620828 -275.972062)
			(xy 100.612703 -275.920767) (xy 100.332539 -275.920767) (xy 100.324414 -275.972062) (xy 100.308366 -276.021455)
			(xy 100.284788 -276.067729) (xy 100.254262 -276.109745) (xy 100.217539 -276.146468) (xy 100.175523 -276.176994)
			(xy 100.129249 -276.200572) (xy 100.079856 -276.21662) (xy 100.028561 -276.224745) (xy 99.976627 -276.224745)
			(xy 99.925332 -276.21662) (xy 99.875939 -276.200572) (xy 99.829665 -276.176994) (xy 99.787649 -276.146468)
			(xy 99.750926 -276.109745) (xy 99.7204 -276.067729) (xy 99.696822 -276.021455) (xy 99.680774 -275.972062)
			(xy 99.672649 -275.920767) (xy 99.392739 -275.920767) (xy 99.384614 -275.972062) (xy 99.368566 -276.021455)
			(xy 99.344988 -276.067729) (xy 99.314462 -276.109745) (xy 99.277739 -276.146468) (xy 99.235723 -276.176994)
			(xy 99.189449 -276.200572) (xy 99.140056 -276.21662) (xy 99.088761 -276.224745) (xy 99.036827 -276.224745)
			(xy 98.985532 -276.21662) (xy 98.936139 -276.200572) (xy 98.889865 -276.176994) (xy 98.847849 -276.146468)
			(xy 98.811126 -276.109745) (xy 98.7806 -276.067729) (xy 98.757022 -276.021455) (xy 98.740974 -275.972062)
			(xy 98.732849 -275.920767) (xy 98.452939 -275.920767) (xy 98.444814 -275.972062) (xy 98.428766 -276.021455)
			(xy 98.405188 -276.067729) (xy 98.374662 -276.109745) (xy 98.337939 -276.146468) (xy 98.295923 -276.176994)
			(xy 98.249649 -276.200572) (xy 98.200256 -276.21662) (xy 98.148961 -276.224745) (xy 98.097027 -276.224745)
			(xy 98.045732 -276.21662) (xy 97.996339 -276.200572) (xy 97.950065 -276.176994) (xy 97.908049 -276.146468)
			(xy 97.871326 -276.109745) (xy 97.8408 -276.067729) (xy 97.817222 -276.021455) (xy 97.801174 -275.972062)
			(xy 97.793049 -275.920767) (xy 97.513139 -275.920767) (xy 97.505014 -275.972062) (xy 97.488966 -276.021455)
			(xy 97.465388 -276.067729) (xy 97.434862 -276.109745) (xy 97.398139 -276.146468) (xy 97.356123 -276.176994)
			(xy 97.309849 -276.200572) (xy 97.260456 -276.21662) (xy 97.209161 -276.224745) (xy 97.157227 -276.224745)
			(xy 97.105932 -276.21662) (xy 97.056539 -276.200572) (xy 97.010265 -276.176994) (xy 96.968249 -276.146468)
			(xy 96.931526 -276.109745) (xy 96.901 -276.067729) (xy 96.877422 -276.021455) (xy 96.861374 -275.972062)
			(xy 96.853249 -275.920767) (xy 96.573625 -275.920767) (xy 96.573625 -275.92079) (xy 96.565493 -275.972129)
			(xy 96.549431 -276.021564) (xy 96.525833 -276.067877) (xy 96.49528 -276.109929) (xy 96.458525 -276.146684)
			(xy 96.416472 -276.177236) (xy 96.370158 -276.200833) (xy 96.320723 -276.216895) (xy 96.269384 -276.225025)
			(xy 96.243394 -276.225508) (xy 96.242632 -276.225508) (xy 96.227171 -276.225305) (xy 96.196386 -276.222383)
			(xy 96.181164 -276.219666) (xy 96.169734 -276.21738) (xy 96.159066 -276.220174) (xy 96.153662 -276.22172)
			(xy 96.143664 -276.226849) (xy 96.139254 -276.230334) (xy 96.079056 -276.280118) (xy 96.070764 -276.287716)
			(xy 96.061124 -276.308006) (xy 96.060514 -276.319234) (xy 96.060514 -276.530816) (xy 96.065594 -276.552914)
			(xy 96.066102 -276.553676) (xy 96.066356 -276.554438) (xy 96.07836 -276.578345) (xy 96.095341 -276.629071)
			(xy 96.103941 -276.681868) (xy 96.103939 -276.734583) (xy 96.383603 -276.734583) (xy 96.383603 -276.682649)
			(xy 96.391728 -276.631354) (xy 96.407776 -276.581961) (xy 96.431354 -276.535687) (xy 96.46188 -276.493671)
			(xy 96.498603 -276.456948) (xy 96.540619 -276.426422) (xy 96.586893 -276.402844) (xy 96.636286 -276.386796)
			(xy 96.687581 -276.378671) (xy 96.739515 -276.378671) (xy 96.79081 -276.386796) (xy 96.840203 -276.402844)
			(xy 96.886477 -276.426422) (xy 96.928493 -276.456948) (xy 96.965216 -276.493671) (xy 96.995742 -276.535687)
			(xy 97.01932 -276.581961) (xy 97.035368 -276.631354) (xy 97.043493 -276.682649) (xy 97.044002 -276.708616)
			(xy 97.043493 -276.734583) (xy 97.323149 -276.734583) (xy 97.323149 -276.682649) (xy 97.331274 -276.631354)
			(xy 97.347322 -276.581961) (xy 97.3709 -276.535687) (xy 97.401426 -276.493671) (xy 97.438149 -276.456948)
			(xy 97.480165 -276.426422) (xy 97.526439 -276.402844) (xy 97.575832 -276.386796) (xy 97.627127 -276.378671)
			(xy 97.679061 -276.378671) (xy 97.730356 -276.386796) (xy 97.779749 -276.402844) (xy 97.826023 -276.426422)
			(xy 97.868039 -276.456948) (xy 97.904762 -276.493671) (xy 97.935288 -276.535687) (xy 97.958866 -276.581961)
			(xy 97.974914 -276.631354) (xy 97.983039 -276.682649) (xy 97.983548 -276.708616) (xy 97.983039 -276.734583)
			(xy 98.263203 -276.734583) (xy 98.263203 -276.682649) (xy 98.271328 -276.631354) (xy 98.287376 -276.581961)
			(xy 98.310954 -276.535687) (xy 98.34148 -276.493671) (xy 98.378203 -276.456948) (xy 98.420219 -276.426422)
			(xy 98.466493 -276.402844) (xy 98.515886 -276.386796) (xy 98.567181 -276.378671) (xy 98.619115 -276.378671)
			(xy 98.67041 -276.386796) (xy 98.719803 -276.402844) (xy 98.766077 -276.426422) (xy 98.808093 -276.456948)
			(xy 98.844816 -276.493671) (xy 98.875342 -276.535687) (xy 98.89892 -276.581961) (xy 98.914968 -276.631354)
			(xy 98.923093 -276.682649) (xy 98.923602 -276.708616) (xy 98.923093 -276.734583) (xy 99.203003 -276.734583)
			(xy 99.203003 -276.682649) (xy 99.211128 -276.631354) (xy 99.227176 -276.581961) (xy 99.250754 -276.535687)
			(xy 99.28128 -276.493671) (xy 99.318003 -276.456948) (xy 99.360019 -276.426422) (xy 99.406293 -276.402844)
			(xy 99.455686 -276.386796) (xy 99.506981 -276.378671) (xy 99.558915 -276.378671) (xy 99.61021 -276.386796)
			(xy 99.659603 -276.402844) (xy 99.705877 -276.426422) (xy 99.747893 -276.456948) (xy 99.784616 -276.493671)
			(xy 99.815142 -276.535687) (xy 99.83872 -276.581961) (xy 99.854768 -276.631354) (xy 99.862893 -276.682649)
			(xy 99.863402 -276.708616) (xy 99.862893 -276.734583) (xy 100.142803 -276.734583) (xy 100.142803 -276.682649)
			(xy 100.150928 -276.631354) (xy 100.166976 -276.581961) (xy 100.190554 -276.535687) (xy 100.22108 -276.493671)
			(xy 100.257803 -276.456948) (xy 100.299819 -276.426422) (xy 100.346093 -276.402844) (xy 100.395486 -276.386796)
			(xy 100.446781 -276.378671) (xy 100.498715 -276.378671) (xy 100.55001 -276.386796) (xy 100.599403 -276.402844)
			(xy 100.645677 -276.426422) (xy 100.687693 -276.456948) (xy 100.724416 -276.493671) (xy 100.754942 -276.535687)
			(xy 100.77852 -276.581961) (xy 100.794568 -276.631354) (xy 100.802693 -276.682649) (xy 100.803202 -276.708616)
			(xy 100.802693 -276.734583) (xy 101.082603 -276.734583) (xy 101.082603 -276.682649) (xy 101.090728 -276.631354)
			(xy 101.106776 -276.581961) (xy 101.130354 -276.535687) (xy 101.16088 -276.493671) (xy 101.197603 -276.456948)
			(xy 101.239619 -276.426422) (xy 101.285893 -276.402844) (xy 101.335286 -276.386796) (xy 101.386581 -276.378671)
			(xy 101.438515 -276.378671) (xy 101.48981 -276.386796) (xy 101.539203 -276.402844) (xy 101.585477 -276.426422)
			(xy 101.627493 -276.456948) (xy 101.664216 -276.493671) (xy 101.694742 -276.535687) (xy 101.71832 -276.581961)
			(xy 101.734368 -276.631354) (xy 101.742493 -276.682649) (xy 101.743002 -276.708616) (xy 102.02164 -276.708616)
			(xy 102.022056 -276.683163) (xy 102.029846 -276.632856) (xy 102.04526 -276.58434) (xy 102.067933 -276.538762)
			(xy 102.097328 -276.497201) (xy 102.13275 -276.46064) (xy 102.173361 -276.429945) (xy 102.218199 -276.405841)
			(xy 102.266203 -276.3889) (xy 102.291134 -276.38375) (xy 102.314248 -276.379432) (xy 102.517956 -276.026372)
			(xy 102.510336 -276.004274) (xy 102.501583 -275.977755) (xy 102.492139 -275.92272) (xy 102.49154 -275.8948)
			(xy 102.492049 -275.868833) (xy 102.500174 -275.817538) (xy 102.516222 -275.768145) (xy 102.5398 -275.721871)
			(xy 102.570326 -275.679855) (xy 102.607049 -275.643132) (xy 102.649065 -275.612606) (xy 102.695339 -275.589028)
			(xy 102.744732 -275.57298) (xy 102.796027 -275.564855) (xy 102.847961 -275.564855) (xy 102.899256 -275.57298)
			(xy 102.948649 -275.589028) (xy 102.994923 -275.612606) (xy 103.036939 -275.643132) (xy 103.073662 -275.679855)
			(xy 103.104188 -275.721871) (xy 103.127766 -275.768145) (xy 103.143814 -275.817538) (xy 103.151939 -275.868833)
			(xy 103.152448 -275.8948) (xy 103.151928 -275.92026) (xy 103.151849 -275.920767) (xy 103.431849 -275.920767)
			(xy 103.431849 -275.868833) (xy 103.439974 -275.817538) (xy 103.456022 -275.768145) (xy 103.4796 -275.721871)
			(xy 103.510126 -275.679855) (xy 103.546849 -275.643132) (xy 103.588865 -275.612606) (xy 103.635139 -275.589028)
			(xy 103.684532 -275.57298) (xy 103.735827 -275.564855) (xy 103.787761 -275.564855) (xy 103.839056 -275.57298)
			(xy 103.888449 -275.589028) (xy 103.934723 -275.612606) (xy 103.976739 -275.643132) (xy 104.013462 -275.679855)
			(xy 104.043988 -275.721871) (xy 104.067566 -275.768145) (xy 104.083614 -275.817538) (xy 104.091739 -275.868833)
			(xy 104.092248 -275.8948) (xy 104.37114 -275.8948) (xy 104.371632 -275.869349) (xy 104.37941 -275.819046)
			(xy 104.394812 -275.770532) (xy 104.417475 -275.724954) (xy 104.44686 -275.683392) (xy 104.482274 -275.64683)
			(xy 104.522876 -275.616133) (xy 104.567708 -275.592028) (xy 104.615706 -275.575085) (xy 104.640634 -275.569934)
			(xy 104.663748 -275.565616) (xy 104.86771 -275.212302) (xy 104.859836 -275.190204) (xy 104.851224 -275.163853)
			(xy 104.841903 -275.109208) (xy 104.841294 -275.081492) (xy 104.841294 -275.08073) (xy 104.841803 -275.054763)
			(xy 104.849928 -275.003468) (xy 104.865976 -274.954075) (xy 104.889554 -274.907801) (xy 104.92008 -274.865785)
			(xy 104.956803 -274.829062) (xy 104.998819 -274.798536) (xy 105.045093 -274.774958) (xy 105.094486 -274.75891)
			(xy 105.145781 -274.750785) (xy 105.197715 -274.750785) (xy 105.24901 -274.75891) (xy 105.298403 -274.774958)
			(xy 105.344677 -274.798536) (xy 105.386693 -274.829062) (xy 105.423416 -274.865785) (xy 105.453942 -274.907801)
			(xy 105.47752 -274.954075) (xy 105.493568 -275.003468) (xy 105.501693 -275.054763) (xy 105.502202 -275.08073)
			(xy 105.501746 -275.106193) (xy 105.501668 -275.106697) (xy 105.781349 -275.106697) (xy 105.781349 -275.054763)
			(xy 105.789474 -275.003468) (xy 105.805522 -274.954075) (xy 105.8291 -274.907801) (xy 105.859626 -274.865785)
			(xy 105.896349 -274.829062) (xy 105.938365 -274.798536) (xy 105.984639 -274.774958) (xy 106.034032 -274.75891)
			(xy 106.085327 -274.750785) (xy 106.137261 -274.750785) (xy 106.188556 -274.75891) (xy 106.237949 -274.774958)
			(xy 106.284223 -274.798536) (xy 106.326239 -274.829062) (xy 106.362962 -274.865785) (xy 106.393488 -274.907801)
			(xy 106.417066 -274.954075) (xy 106.433114 -275.003468) (xy 106.441239 -275.054763) (xy 106.441748 -275.08073)
			(xy 106.441239 -275.106697) (xy 106.721403 -275.106697) (xy 106.721403 -275.054763) (xy 106.729528 -275.003468)
			(xy 106.745576 -274.954075) (xy 106.769154 -274.907801) (xy 106.79968 -274.865785) (xy 106.836403 -274.829062)
			(xy 106.878419 -274.798536) (xy 106.924693 -274.774958) (xy 106.974086 -274.75891) (xy 107.025381 -274.750785)
			(xy 107.077315 -274.750785) (xy 107.12861 -274.75891) (xy 107.178003 -274.774958) (xy 107.224277 -274.798536)
			(xy 107.266293 -274.829062) (xy 107.303016 -274.865785) (xy 107.333542 -274.907801) (xy 107.35712 -274.954075)
			(xy 107.373168 -275.003468) (xy 107.381293 -275.054763) (xy 107.381802 -275.08073) (xy 107.660694 -275.08073)
			(xy 107.661203 -275.054763) (xy 107.669328 -275.003468) (xy 107.685376 -274.954075) (xy 107.708954 -274.907801)
			(xy 107.73948 -274.865785) (xy 107.776203 -274.829062) (xy 107.818219 -274.798536) (xy 107.864493 -274.774958)
			(xy 107.913886 -274.75891) (xy 107.965181 -274.750785) (xy 108.017115 -274.750785) (xy 108.06841 -274.75891)
			(xy 108.117803 -274.774958) (xy 108.164077 -274.798536) (xy 108.206093 -274.829062) (xy 108.242816 -274.865785)
			(xy 108.273342 -274.907801) (xy 108.29692 -274.954075) (xy 108.312968 -275.003468) (xy 108.321093 -275.054763)
			(xy 108.321602 -275.08073) (xy 108.321096 -275.106697) (xy 108.600749 -275.106697) (xy 108.600749 -275.054763)
			(xy 108.608874 -275.003468) (xy 108.624922 -274.954075) (xy 108.6485 -274.907801) (xy 108.679026 -274.865785)
			(xy 108.715749 -274.829062) (xy 108.757765 -274.798536) (xy 108.804039 -274.774958) (xy 108.853432 -274.75891)
			(xy 108.904727 -274.750785) (xy 108.956661 -274.750785) (xy 109.007956 -274.75891) (xy 109.057349 -274.774958)
			(xy 109.103623 -274.798536) (xy 109.145639 -274.829062) (xy 109.182362 -274.865785) (xy 109.212888 -274.907801)
			(xy 109.236466 -274.954075) (xy 109.252514 -275.003468) (xy 109.260639 -275.054763) (xy 109.261148 -275.08073)
			(xy 109.260639 -275.106697) (xy 109.540549 -275.106697) (xy 109.540549 -275.054763) (xy 109.548674 -275.003468)
			(xy 109.564722 -274.954075) (xy 109.5883 -274.907801) (xy 109.618826 -274.865785) (xy 109.655549 -274.829062)
			(xy 109.697565 -274.798536) (xy 109.743839 -274.774958) (xy 109.793232 -274.75891) (xy 109.844527 -274.750785)
			(xy 109.896461 -274.750785) (xy 109.947756 -274.75891) (xy 109.997149 -274.774958) (xy 110.043423 -274.798536)
			(xy 110.085439 -274.829062) (xy 110.122162 -274.865785) (xy 110.152688 -274.907801) (xy 110.176266 -274.954075)
			(xy 110.192314 -275.003468) (xy 110.200439 -275.054763) (xy 110.200948 -275.08073) (xy 110.200439 -275.106697)
			(xy 113.299749 -275.106697) (xy 113.299749 -275.054763) (xy 113.307874 -275.003468) (xy 113.323922 -274.954075)
			(xy 113.3475 -274.907801) (xy 113.378026 -274.865785) (xy 113.414749 -274.829062) (xy 113.456765 -274.798536)
			(xy 113.503039 -274.774958) (xy 113.552432 -274.75891) (xy 113.603727 -274.750785) (xy 113.655661 -274.750785)
			(xy 113.706956 -274.75891) (xy 113.756349 -274.774958) (xy 113.802623 -274.798536) (xy 113.844639 -274.829062)
			(xy 113.881362 -274.865785) (xy 113.911888 -274.907801) (xy 113.935466 -274.954075) (xy 113.951514 -275.003468)
			(xy 113.959639 -275.054763) (xy 113.960148 -275.08073) (xy 113.959639 -275.106697) (xy 113.951514 -275.157992)
			(xy 113.935466 -275.207385) (xy 113.911888 -275.253659) (xy 113.881362 -275.295675) (xy 113.844639 -275.332398)
			(xy 113.802623 -275.362924) (xy 113.756349 -275.386502) (xy 113.706956 -275.40255) (xy 113.655661 -275.410675)
			(xy 113.603727 -275.410675) (xy 113.552432 -275.40255) (xy 113.503039 -275.386502) (xy 113.456765 -275.362924)
			(xy 113.414749 -275.332398) (xy 113.378026 -275.295675) (xy 113.3475 -275.253659) (xy 113.323922 -275.207385)
			(xy 113.307874 -275.157992) (xy 113.299749 -275.106697) (xy 110.200439 -275.106697) (xy 110.192314 -275.157992)
			(xy 110.176266 -275.207385) (xy 110.152688 -275.253659) (xy 110.122162 -275.295675) (xy 110.085439 -275.332398)
			(xy 110.043423 -275.362924) (xy 109.997149 -275.386502) (xy 109.947756 -275.40255) (xy 109.896461 -275.410675)
			(xy 109.844527 -275.410675) (xy 109.793232 -275.40255) (xy 109.743839 -275.386502) (xy 109.697565 -275.362924)
			(xy 109.655549 -275.332398) (xy 109.618826 -275.295675) (xy 109.5883 -275.253659) (xy 109.564722 -275.207385)
			(xy 109.548674 -275.157992) (xy 109.540549 -275.106697) (xy 109.260639 -275.106697) (xy 109.252514 -275.157992)
			(xy 109.236466 -275.207385) (xy 109.212888 -275.253659) (xy 109.182362 -275.295675) (xy 109.145639 -275.332398)
			(xy 109.103623 -275.362924) (xy 109.057349 -275.386502) (xy 109.007956 -275.40255) (xy 108.956661 -275.410675)
			(xy 108.904727 -275.410675) (xy 108.853432 -275.40255) (xy 108.804039 -275.386502) (xy 108.757765 -275.362924)
			(xy 108.715749 -275.332398) (xy 108.679026 -275.295675) (xy 108.6485 -275.253659) (xy 108.624922 -275.207385)
			(xy 108.608874 -275.157992) (xy 108.600749 -275.106697) (xy 108.321096 -275.106697) (xy 108.321057 -275.108716)
			(xy 108.311602 -275.163884) (xy 108.302806 -275.190458) (xy 108.295186 -275.212556) (xy 108.498894 -275.565616)
			(xy 108.522008 -275.569934) (xy 108.546917 -275.575155) (xy 108.594899 -275.592113) (xy 108.639716 -275.616223)
			(xy 108.680308 -275.646917) (xy 108.715718 -275.683468) (xy 108.745108 -275.725014) (xy 108.767785 -275.770572)
			(xy 108.783212 -275.819068) (xy 108.791026 -275.869355) (xy 108.791502 -275.8948) (xy 108.790993 -275.920767)
			(xy 108.782868 -275.972062) (xy 108.76682 -276.021455) (xy 108.743242 -276.067729) (xy 108.712716 -276.109745)
			(xy 108.675993 -276.146468) (xy 108.633977 -276.176994) (xy 108.587703 -276.200572) (xy 108.53831 -276.21662)
			(xy 108.487015 -276.224745) (xy 108.435081 -276.224745) (xy 108.383786 -276.21662) (xy 108.334393 -276.200572)
			(xy 108.288119 -276.176994) (xy 108.246103 -276.146468) (xy 108.20938 -276.109745) (xy 108.178854 -276.067729)
			(xy 108.155276 -276.021455) (xy 108.139228 -275.972062) (xy 108.131103 -275.920767) (xy 108.130594 -275.8948)
			(xy 108.131147 -275.866814) (xy 108.140597 -275.811646) (xy 108.14939 -275.785072) (xy 108.15701 -275.762974)
			(xy 107.953302 -275.409914) (xy 107.930188 -275.405596) (xy 107.905262 -275.400444) (xy 107.857276 -275.38348)
			(xy 107.812455 -275.359363) (xy 107.771861 -275.328661) (xy 107.736451 -275.292101) (xy 107.707063 -275.250546)
			(xy 107.68439 -275.204978) (xy 107.66897 -275.156473) (xy 107.661165 -275.106178) (xy 107.660694 -275.08073)
			(xy 107.381802 -275.08073) (xy 107.381293 -275.106697) (xy 107.373168 -275.157992) (xy 107.35712 -275.207385)
			(xy 107.333542 -275.253659) (xy 107.303016 -275.295675) (xy 107.266293 -275.332398) (xy 107.224277 -275.362924)
			(xy 107.178003 -275.386502) (xy 107.12861 -275.40255) (xy 107.077315 -275.410675) (xy 107.025381 -275.410675)
			(xy 106.974086 -275.40255) (xy 106.924693 -275.386502) (xy 106.878419 -275.362924) (xy 106.836403 -275.332398)
			(xy 106.79968 -275.295675) (xy 106.769154 -275.253659) (xy 106.745576 -275.207385) (xy 106.729528 -275.157992)
			(xy 106.721403 -275.106697) (xy 106.441239 -275.106697) (xy 106.433114 -275.157992) (xy 106.417066 -275.207385)
			(xy 106.393488 -275.253659) (xy 106.362962 -275.295675) (xy 106.326239 -275.332398) (xy 106.284223 -275.362924)
			(xy 106.237949 -275.386502) (xy 106.188556 -275.40255) (xy 106.137261 -275.410675) (xy 106.085327 -275.410675)
			(xy 106.034032 -275.40255) (xy 105.984639 -275.386502) (xy 105.938365 -275.362924) (xy 105.896349 -275.332398)
			(xy 105.859626 -275.295675) (xy 105.8291 -275.253659) (xy 105.805522 -275.207385) (xy 105.789474 -275.157992)
			(xy 105.781349 -275.106697) (xy 105.501668 -275.106697) (xy 105.493943 -275.156518) (xy 105.478511 -275.205049)
			(xy 105.455815 -275.250638) (xy 105.426393 -275.292204) (xy 105.390941 -275.328765) (xy 105.3503 -275.359452)
			(xy 105.305431 -275.383541) (xy 105.257398 -275.40046) (xy 105.232454 -275.405596) (xy 105.20934 -275.409914)
			(xy 105.005632 -275.762974) (xy 105.013252 -275.785072) (xy 105.021982 -275.811663) (xy 105.031435 -275.86682)
			(xy 105.032048 -275.8948) (xy 105.031539 -275.920767) (xy 105.311703 -275.920767) (xy 105.311703 -275.868833)
			(xy 105.319828 -275.817538) (xy 105.335876 -275.768145) (xy 105.359454 -275.721871) (xy 105.38998 -275.679855)
			(xy 105.426703 -275.643132) (xy 105.468719 -275.612606) (xy 105.514993 -275.589028) (xy 105.564386 -275.57298)
			(xy 105.615681 -275.564855) (xy 105.667615 -275.564855) (xy 105.71891 -275.57298) (xy 105.768303 -275.589028)
			(xy 105.814577 -275.612606) (xy 105.856593 -275.643132) (xy 105.893316 -275.679855) (xy 105.923842 -275.721871)
			(xy 105.94742 -275.768145) (xy 105.963468 -275.817538) (xy 105.971593 -275.868833) (xy 105.972102 -275.8948)
			(xy 105.971593 -275.920767) (xy 106.251255 -275.920767) (xy 106.251255 -275.868833) (xy 106.259379 -275.817539)
			(xy 106.275428 -275.768147) (xy 106.299005 -275.721873) (xy 106.32953 -275.679857) (xy 106.366253 -275.643134)
			(xy 106.408268 -275.612608) (xy 106.454541 -275.58903) (xy 106.503933 -275.572981) (xy 106.555227 -275.564856)
			(xy 106.581194 -275.564346) (xy 106.606817 -275.564795) (xy 106.657446 -275.572725) (xy 106.706247 -275.588366)
			(xy 106.752053 -275.611343) (xy 106.793769 -275.641107) (xy 106.830398 -275.676946) (xy 106.846116 -275.697188)
			(xy 107.256072 -275.697188) (xy 107.271765 -275.676925) (xy 107.308388 -275.641075) (xy 107.350107 -275.611308)
			(xy 107.395921 -275.588339) (xy 107.444732 -275.572719) (xy 107.495369 -275.564821) (xy 107.520994 -275.564346)
			(xy 107.546964 -275.564828) (xy 107.598263 -275.572953) (xy 107.647661 -275.589002) (xy 107.693939 -275.612581)
			(xy 107.735959 -275.64311) (xy 107.772686 -275.679836) (xy 107.803216 -275.721856) (xy 107.826796 -275.768134)
			(xy 107.842846 -275.817531) (xy 107.850971 -275.86883) (xy 107.850971 -275.92077) (xy 107.842846 -275.972069)
			(xy 107.826796 -276.021466) (xy 107.803216 -276.067744) (xy 107.772686 -276.109764) (xy 107.735959 -276.14649)
			(xy 107.693939 -276.177019) (xy 107.647661 -276.200598) (xy 107.598263 -276.216647) (xy 107.546964 -276.224772)
			(xy 107.520994 -276.225254) (xy 107.495374 -276.224741) (xy 107.444748 -276.216825) (xy 107.395948 -276.201197)
			(xy 107.350141 -276.178232) (xy 107.308423 -276.148479) (xy 107.271792 -276.112649) (xy 107.256072 -276.092412)
			(xy 106.846116 -276.092412) (xy 106.830372 -276.112633) (xy 106.793759 -276.148486) (xy 106.752051 -276.178257)
			(xy 106.706247 -276.201233) (xy 106.657445 -276.216863) (xy 106.606816 -276.224772) (xy 106.581194 -276.225254)
			(xy 106.555227 -276.224744) (xy 106.503933 -276.216619) (xy 106.454541 -276.20057) (xy 106.408268 -276.176992)
			(xy 106.366253 -276.146466) (xy 106.32953 -276.109743) (xy 106.299005 -276.067727) (xy 106.275428 -276.021453)
			(xy 106.259379 -275.972061) (xy 106.251255 -275.920767) (xy 105.971593 -275.920767) (xy 105.963468 -275.972062)
			(xy 105.94742 -276.021455) (xy 105.923842 -276.067729) (xy 105.893316 -276.109745) (xy 105.856593 -276.146468)
			(xy 105.814577 -276.176994) (xy 105.768303 -276.200572) (xy 105.71891 -276.21662) (xy 105.667615 -276.224745)
			(xy 105.615681 -276.224745) (xy 105.564386 -276.21662) (xy 105.514993 -276.200572) (xy 105.468719 -276.176994)
			(xy 105.426703 -276.146468) (xy 105.38998 -276.109745) (xy 105.359454 -276.067729) (xy 105.335876 -276.021455)
			(xy 105.319828 -275.972062) (xy 105.311703 -275.920767) (xy 105.031539 -275.920767) (xy 105.023414 -275.972062)
			(xy 105.007366 -276.021455) (xy 104.983788 -276.067729) (xy 104.953262 -276.109745) (xy 104.916539 -276.146468)
			(xy 104.874523 -276.176994) (xy 104.828249 -276.200572) (xy 104.778856 -276.21662) (xy 104.727561 -276.224745)
			(xy 104.675627 -276.224745) (xy 104.624332 -276.21662) (xy 104.574939 -276.200572) (xy 104.528665 -276.176994)
			(xy 104.486649 -276.146468) (xy 104.449926 -276.109745) (xy 104.4194 -276.067729) (xy 104.395822 -276.021455)
			(xy 104.379774 -275.972062) (xy 104.371649 -275.920767) (xy 104.37114 -275.8948) (xy 104.092248 -275.8948)
			(xy 104.091739 -275.920767) (xy 104.083614 -275.972062) (xy 104.067566 -276.021455) (xy 104.043988 -276.067729)
			(xy 104.013462 -276.109745) (xy 103.976739 -276.146468) (xy 103.934723 -276.176994) (xy 103.888449 -276.200572)
			(xy 103.839056 -276.21662) (xy 103.787761 -276.224745) (xy 103.735827 -276.224745) (xy 103.684532 -276.21662)
			(xy 103.635139 -276.200572) (xy 103.588865 -276.176994) (xy 103.546849 -276.146468) (xy 103.510126 -276.109745)
			(xy 103.4796 -276.067729) (xy 103.456022 -276.021455) (xy 103.439974 -275.972062) (xy 103.431849 -275.920767)
			(xy 103.151849 -275.920767) (xy 103.14413 -275.97058) (xy 103.128705 -276.019108) (xy 103.106016 -276.064694)
			(xy 103.076602 -276.10626) (xy 103.041159 -276.142821) (xy 103.000526 -276.17351) (xy 102.955666 -276.197602)
			(xy 102.90764 -276.214526) (xy 102.8827 -276.219666) (xy 102.85984 -276.223984) (xy 102.656132 -276.57679)
			(xy 102.663752 -276.598888) (xy 102.672485 -276.625478) (xy 102.681936 -276.680636) (xy 102.682548 -276.708616)
			(xy 102.961694 -276.708616) (xy 102.962203 -276.682649) (xy 102.970328 -276.631354) (xy 102.986376 -276.581961)
			(xy 103.009954 -276.535687) (xy 103.04048 -276.493671) (xy 103.077203 -276.456948) (xy 103.119219 -276.426422)
			(xy 103.165493 -276.402844) (xy 103.214886 -276.386796) (xy 103.266181 -276.378671) (xy 103.318115 -276.378671)
			(xy 103.36941 -276.386796) (xy 103.418803 -276.402844) (xy 103.465077 -276.426422) (xy 103.507093 -276.456948)
			(xy 103.543816 -276.493671) (xy 103.574342 -276.535687) (xy 103.59792 -276.581961) (xy 103.613968 -276.631354)
			(xy 103.622093 -276.682649) (xy 103.622602 -276.708616) (xy 103.622093 -276.73457) (xy 103.901945 -276.73457)
			(xy 103.901945 -276.68263) (xy 103.910071 -276.631328) (xy 103.926123 -276.58193) (xy 103.949706 -276.535651)
			(xy 103.980238 -276.493632) (xy 104.016969 -276.456907) (xy 104.058992 -276.426381) (xy 104.105274 -276.402805)
			(xy 104.154675 -276.38676) (xy 104.205977 -276.378641) (xy 104.231948 -276.378162) (xy 104.257568 -276.378678)
			(xy 104.308192 -276.386599) (xy 104.35699 -276.402228) (xy 104.402796 -276.425193) (xy 104.444514 -276.454943)
			(xy 104.481148 -276.490769) (xy 104.49687 -276.511004) (xy 104.906826 -276.511004) (xy 104.92255 -276.490767)
			(xy 104.959166 -276.454914) (xy 105.000878 -276.425144) (xy 105.046686 -276.402171) (xy 105.095492 -276.386545)
			(xy 105.146125 -276.378641) (xy 105.171748 -276.378162) (xy 105.197714 -276.378643) (xy 105.249006 -276.386774)
			(xy 105.298394 -276.402827) (xy 105.344664 -276.426409) (xy 105.386675 -276.456937) (xy 105.423394 -276.493661)
			(xy 105.453916 -276.535677) (xy 105.477491 -276.58195) (xy 105.493538 -276.631341) (xy 105.501661 -276.682634)
			(xy 105.501661 -276.734566) (xy 105.501658 -276.734583) (xy 105.781349 -276.734583) (xy 105.781349 -276.682649)
			(xy 105.789474 -276.631354) (xy 105.805522 -276.581961) (xy 105.8291 -276.535687) (xy 105.859626 -276.493671)
			(xy 105.896349 -276.456948) (xy 105.938365 -276.426422) (xy 105.984639 -276.402844) (xy 106.034032 -276.386796)
			(xy 106.085327 -276.378671) (xy 106.137261 -276.378671) (xy 106.188556 -276.386796) (xy 106.237949 -276.402844)
			(xy 106.284223 -276.426422) (xy 106.326239 -276.456948) (xy 106.362962 -276.493671) (xy 106.393488 -276.535687)
			(xy 106.417066 -276.581961) (xy 106.433114 -276.631354) (xy 106.441239 -276.682649) (xy 106.441748 -276.708616)
			(xy 106.441239 -276.734583) (xy 106.433114 -276.785878) (xy 106.417066 -276.835271) (xy 106.393488 -276.881545)
			(xy 106.362962 -276.923561) (xy 106.326239 -276.960284) (xy 106.284223 -276.99081) (xy 106.237949 -277.014388)
			(xy 106.188556 -277.030436) (xy 106.137261 -277.038561) (xy 106.085327 -277.038561) (xy 106.034032 -277.030436)
			(xy 105.984639 -277.014388) (xy 105.938365 -276.99081) (xy 105.896349 -276.960284) (xy 105.859626 -276.923561)
			(xy 105.8291 -276.881545) (xy 105.805522 -276.835271) (xy 105.789474 -276.785878) (xy 105.781349 -276.734583)
			(xy 105.501658 -276.734583) (xy 105.493538 -276.785859) (xy 105.477491 -276.83525) (xy 105.453916 -276.881523)
			(xy 105.423394 -276.923539) (xy 105.386675 -276.960263) (xy 105.344664 -276.990791) (xy 105.298394 -277.014373)
			(xy 105.249006 -277.030426) (xy 105.197714 -277.038557) (xy 105.171748 -277.03907) (xy 105.146127 -277.038584)
			(xy 105.0955 -277.030661) (xy 105.0467 -277.015027) (xy 105.000894 -276.992057) (xy 104.959176 -276.9623)
			(xy 104.922545 -276.926467) (xy 104.906826 -276.906228) (xy 104.49687 -276.906228) (xy 104.481157 -276.926474)
			(xy 104.444538 -276.962325) (xy 104.402823 -276.992093) (xy 104.357013 -277.015064) (xy 104.308206 -277.030689)
			(xy 104.257572 -277.038592) (xy 104.231948 -277.03907) (xy 104.205977 -277.038559) (xy 104.154675 -277.03044)
			(xy 104.105274 -277.014395) (xy 104.058992 -276.990819) (xy 104.016969 -276.960293) (xy 103.980238 -276.923568)
			(xy 103.949706 -276.881549) (xy 103.926123 -276.83527) (xy 103.910071 -276.785872) (xy 103.901945 -276.73457)
			(xy 103.622093 -276.73457) (xy 103.622053 -276.736602) (xy 103.6126 -276.79177) (xy 103.603806 -276.818344)
			(xy 103.595932 -276.840442) (xy 103.79964 -277.193248) (xy 103.822754 -277.197566) (xy 103.847678 -277.202724)
			(xy 103.895662 -277.21969) (xy 103.940479 -277.243809) (xy 103.981072 -277.274511) (xy 104.01648 -277.31107)
			(xy 104.045868 -277.352624) (xy 104.068542 -277.39819) (xy 104.083965 -277.446692) (xy 104.091775 -277.496984)
			(xy 104.092248 -277.522432) (xy 104.091739 -277.548399) (xy 104.371649 -277.548399) (xy 104.371649 -277.496465)
			(xy 104.379774 -277.44517) (xy 104.395822 -277.395777) (xy 104.4194 -277.349503) (xy 104.449926 -277.307487)
			(xy 104.486649 -277.270764) (xy 104.528665 -277.240238) (xy 104.574939 -277.21666) (xy 104.624332 -277.200612)
			(xy 104.675627 -277.192487) (xy 104.727561 -277.192487) (xy 104.778856 -277.200612) (xy 104.828249 -277.21666)
			(xy 104.874523 -277.240238) (xy 104.916539 -277.270764) (xy 104.953262 -277.307487) (xy 104.983788 -277.349503)
			(xy 105.007366 -277.395777) (xy 105.023414 -277.44517) (xy 105.031539 -277.496465) (xy 105.032048 -277.522432)
			(xy 105.031539 -277.548399) (xy 105.311449 -277.548399) (xy 105.311449 -277.496465) (xy 105.319574 -277.44517)
			(xy 105.335622 -277.395777) (xy 105.3592 -277.349503) (xy 105.389726 -277.307487) (xy 105.426449 -277.270764)
			(xy 105.468465 -277.240238) (xy 105.514739 -277.21666) (xy 105.564132 -277.200612) (xy 105.615427 -277.192487)
			(xy 105.667361 -277.192487) (xy 105.718656 -277.200612) (xy 105.768049 -277.21666) (xy 105.814323 -277.240238)
			(xy 105.856339 -277.270764) (xy 105.893062 -277.307487) (xy 105.923588 -277.349503) (xy 105.947166 -277.395777)
			(xy 105.963214 -277.44517) (xy 105.971339 -277.496465) (xy 105.971848 -277.522432) (xy 106.25074 -277.522432)
			(xy 106.25117 -277.496979) (xy 106.258958 -277.446674) (xy 106.27437 -277.398158) (xy 106.297041 -277.35258)
			(xy 106.326434 -277.311018) (xy 106.361854 -277.274457) (xy 106.402464 -277.243761) (xy 106.4473 -277.219658)
			(xy 106.495304 -277.202716) (xy 106.520234 -277.197566) (xy 106.543348 -277.193248) (xy 106.74731 -276.839934)
			(xy 106.739436 -276.817836) (xy 106.730817 -276.791421) (xy 106.72149 -276.736649) (xy 106.720894 -276.70887)
			(xy 106.720894 -276.708616) (xy 106.721403 -276.682649) (xy 106.729528 -276.631354) (xy 106.745576 -276.581961)
			(xy 106.769154 -276.535687) (xy 106.79968 -276.493671) (xy 106.836403 -276.456948) (xy 106.878419 -276.426422)
			(xy 106.924693 -276.402844) (xy 106.974086 -276.386796) (xy 107.025381 -276.378671) (xy 107.077315 -276.378671)
			(xy 107.12861 -276.386796) (xy 107.178003 -276.402844) (xy 107.224277 -276.426422) (xy 107.266293 -276.456948)
			(xy 107.303016 -276.493671) (xy 107.333542 -276.535687) (xy 107.35712 -276.581961) (xy 107.373168 -276.631354)
			(xy 107.381293 -276.682649) (xy 107.381802 -276.708616) (xy 107.381295 -276.734088) (xy 107.381218 -276.734583)
			(xy 107.661203 -276.734583) (xy 107.661203 -276.682649) (xy 107.669328 -276.631354) (xy 107.685376 -276.581961)
			(xy 107.708954 -276.535687) (xy 107.73948 -276.493671) (xy 107.776203 -276.456948) (xy 107.818219 -276.426422)
			(xy 107.864493 -276.402844) (xy 107.913886 -276.386796) (xy 107.965181 -276.378671) (xy 108.017115 -276.378671)
			(xy 108.06841 -276.386796) (xy 108.117803 -276.402844) (xy 108.164077 -276.426422) (xy 108.206093 -276.456948)
			(xy 108.242816 -276.493671) (xy 108.273342 -276.535687) (xy 108.29692 -276.581961) (xy 108.312968 -276.631354)
			(xy 108.321093 -276.682649) (xy 108.321602 -276.708616) (xy 108.60024 -276.708616) (xy 108.600656 -276.683163)
			(xy 108.608446 -276.632856) (xy 108.62386 -276.58434) (xy 108.646533 -276.538762) (xy 108.675928 -276.497201)
			(xy 108.71135 -276.46064) (xy 108.751961 -276.429945) (xy 108.796799 -276.405841) (xy 108.844803 -276.3889)
			(xy 108.869734 -276.38375) (xy 108.892848 -276.379432) (xy 109.096556 -276.026626) (xy 109.088682 -276.004528)
			(xy 109.07995 -275.977938) (xy 109.070499 -275.92278) (xy 109.069886 -275.8948) (xy 109.070395 -275.868833)
			(xy 109.07852 -275.817538) (xy 109.094568 -275.768145) (xy 109.118146 -275.721871) (xy 109.148672 -275.679855)
			(xy 109.185395 -275.643132) (xy 109.227411 -275.612606) (xy 109.273685 -275.589028) (xy 109.323078 -275.57298)
			(xy 109.374373 -275.564855) (xy 109.426307 -275.564855) (xy 109.477602 -275.57298) (xy 109.526995 -275.589028)
			(xy 109.573269 -275.612606) (xy 109.615285 -275.643132) (xy 109.652008 -275.679855) (xy 109.682534 -275.721871)
			(xy 109.706112 -275.768145) (xy 109.72216 -275.817538) (xy 109.730285 -275.868833) (xy 109.730794 -275.8948)
			(xy 109.730274 -275.920249) (xy 109.730194 -275.920767) (xy 110.010449 -275.920767) (xy 110.010449 -275.868833)
			(xy 110.018574 -275.817538) (xy 110.034622 -275.768145) (xy 110.0582 -275.721871) (xy 110.088726 -275.679855)
			(xy 110.125449 -275.643132) (xy 110.167465 -275.612606) (xy 110.213739 -275.589028) (xy 110.263132 -275.57298)
			(xy 110.314427 -275.564855) (xy 110.366361 -275.564855) (xy 110.417656 -275.57298) (xy 110.467049 -275.589028)
			(xy 110.513323 -275.612606) (xy 110.555339 -275.643132) (xy 110.592062 -275.679855) (xy 110.622588 -275.721871)
			(xy 110.646166 -275.768145) (xy 110.662214 -275.817538) (xy 110.670339 -275.868833) (xy 110.670848 -275.8948)
			(xy 110.670339 -275.920767) (xy 110.662214 -275.972062) (xy 110.646166 -276.021455) (xy 110.622588 -276.067729)
			(xy 110.592062 -276.109745) (xy 110.555339 -276.146468) (xy 110.513323 -276.176994) (xy 110.467049 -276.200572)
			(xy 110.417656 -276.21662) (xy 110.366361 -276.224745) (xy 110.314427 -276.224745) (xy 110.263132 -276.21662)
			(xy 110.213739 -276.200572) (xy 110.167465 -276.176994) (xy 110.125449 -276.146468) (xy 110.088726 -276.109745)
			(xy 110.0582 -276.067729) (xy 110.034622 -276.021455) (xy 110.018574 -275.972062) (xy 110.010449 -275.920767)
			(xy 109.730194 -275.920767) (xy 109.722497 -275.97055) (xy 109.707097 -276.019062) (xy 109.684437 -276.064638)
			(xy 109.655055 -276.106199) (xy 109.619646 -276.142761) (xy 109.579047 -276.173459) (xy 109.53422 -276.197566)
			(xy 109.486226 -276.214512) (xy 109.4613 -276.219666) (xy 109.43844 -276.223984) (xy 109.234732 -276.57679)
			(xy 109.242352 -276.598888) (xy 109.251085 -276.625478) (xy 109.260536 -276.680636) (xy 109.261148 -276.708616)
			(xy 109.260639 -276.734583) (xy 109.540549 -276.734583) (xy 109.540549 -276.682649) (xy 109.548674 -276.631354)
			(xy 109.564722 -276.581961) (xy 109.5883 -276.535687) (xy 109.618826 -276.493671) (xy 109.655549 -276.456948)
			(xy 109.697565 -276.426422) (xy 109.743839 -276.402844) (xy 109.793232 -276.386796) (xy 109.844527 -276.378671)
			(xy 109.896461 -276.378671) (xy 109.947756 -276.386796) (xy 109.997149 -276.402844) (xy 110.043423 -276.426422)
			(xy 110.085439 -276.456948) (xy 110.122162 -276.493671) (xy 110.152688 -276.535687) (xy 110.176266 -276.581961)
			(xy 110.192314 -276.631354) (xy 110.200439 -276.682649) (xy 110.200948 -276.708616) (xy 110.200439 -276.734583)
			(xy 110.192314 -276.785878) (xy 110.176266 -276.835271) (xy 110.152688 -276.881545) (xy 110.122162 -276.923561)
			(xy 110.085439 -276.960284) (xy 110.043423 -276.99081) (xy 109.997149 -277.014388) (xy 109.947756 -277.030436)
			(xy 109.896461 -277.038561) (xy 109.844527 -277.038561) (xy 109.793232 -277.030436) (xy 109.743839 -277.014388)
			(xy 109.697565 -276.99081) (xy 109.655549 -276.960284) (xy 109.618826 -276.923561) (xy 109.5883 -276.881545)
			(xy 109.564722 -276.835271) (xy 109.548674 -276.785878) (xy 109.540549 -276.734583) (xy 109.260639 -276.734583)
			(xy 109.252514 -276.785878) (xy 109.236466 -276.835271) (xy 109.212888 -276.881545) (xy 109.182362 -276.923561)
			(xy 109.145639 -276.960284) (xy 109.103623 -276.99081) (xy 109.057349 -277.014388) (xy 109.007956 -277.030436)
			(xy 108.956661 -277.038561) (xy 108.904727 -277.038561) (xy 108.853432 -277.030436) (xy 108.804039 -277.014388)
			(xy 108.757765 -276.99081) (xy 108.715749 -276.960284) (xy 108.679026 -276.923561) (xy 108.6485 -276.881545)
			(xy 108.624922 -276.835271) (xy 108.608874 -276.785878) (xy 108.600749 -276.734583) (xy 108.60024 -276.708616)
			(xy 108.321602 -276.708616) (xy 108.321093 -276.734583) (xy 108.312968 -276.785878) (xy 108.29692 -276.835271)
			(xy 108.273342 -276.881545) (xy 108.242816 -276.923561) (xy 108.206093 -276.960284) (xy 108.164077 -276.99081)
			(xy 108.117803 -277.014388) (xy 108.06841 -277.030436) (xy 108.017115 -277.038561) (xy 107.965181 -277.038561)
			(xy 107.913886 -277.030436) (xy 107.864493 -277.014388) (xy 107.818219 -276.99081) (xy 107.776203 -276.960284)
			(xy 107.73948 -276.923561) (xy 107.708954 -276.881545) (xy 107.685376 -276.835271) (xy 107.669328 -276.785878)
			(xy 107.661203 -276.734583) (xy 107.381218 -276.734583) (xy 107.373475 -276.784428) (xy 107.358022 -276.832971)
			(xy 107.335303 -276.878568) (xy 107.305855 -276.920138) (xy 107.270377 -276.956697) (xy 107.229708 -276.987378)
			(xy 107.184813 -277.011454) (xy 107.136755 -277.028356) (xy 107.1118 -277.033482) (xy 107.08894 -277.0378)
			(xy 106.885232 -277.390606) (xy 106.892852 -277.412704) (xy 106.901589 -277.439292) (xy 106.911037 -277.494451)
			(xy 106.911648 -277.522432) (xy 107.19054 -277.522432) (xy 107.191049 -277.496465) (xy 107.199174 -277.44517)
			(xy 107.215222 -277.395777) (xy 107.2388 -277.349503) (xy 107.269326 -277.307487) (xy 107.306049 -277.270764)
			(xy 107.348065 -277.240238) (xy 107.394339 -277.21666) (xy 107.443732 -277.200612) (xy 107.495027 -277.192487)
			(xy 107.546961 -277.192487) (xy 107.598256 -277.200612) (xy 107.647649 -277.21666) (xy 107.693923 -277.240238)
			(xy 107.735939 -277.270764) (xy 107.772662 -277.307487) (xy 107.803188 -277.349503) (xy 107.826766 -277.395777)
			(xy 107.842814 -277.44517) (xy 107.850939 -277.496465) (xy 107.851448 -277.522432) (xy 107.851448 -277.523194)
			(xy 107.850915 -277.548364) (xy 108.130887 -277.548364) (xy 108.130887 -277.496436) (xy 108.13901 -277.445146)
			(xy 108.155057 -277.395759) (xy 108.178632 -277.34949) (xy 108.209155 -277.307478) (xy 108.245874 -277.270759)
			(xy 108.287885 -277.240235) (xy 108.334153 -277.216659) (xy 108.38354 -277.200612) (xy 108.43483 -277.192488)
			(xy 108.460794 -277.191978) (xy 108.486415 -277.192454) (xy 108.537042 -277.200382) (xy 108.585841 -277.216019)
			(xy 108.631647 -277.238991) (xy 108.673364 -277.268749) (xy 108.709996 -277.304582) (xy 108.725716 -277.32482)
			(xy 109.135672 -277.32482) (xy 109.151346 -277.304543) (xy 109.187976 -277.268696) (xy 109.229699 -277.238934)
			(xy 109.275516 -277.215968) (xy 109.324329 -277.20035) (xy 109.374968 -277.192453) (xy 109.400594 -277.191978)
			(xy 109.426566 -277.192396) (xy 109.477871 -277.200522) (xy 109.527273 -277.216572) (xy 109.573556 -277.240154)
			(xy 109.61558 -277.270686) (xy 109.65231 -277.307415) (xy 109.682843 -277.349439) (xy 109.706425 -277.395721)
			(xy 109.722477 -277.445123) (xy 109.730603 -277.496428) (xy 109.730603 -277.548372) (xy 109.730599 -277.548399)
			(xy 110.010449 -277.548399) (xy 110.010449 -277.496465) (xy 110.018574 -277.44517) (xy 110.034622 -277.395777)
			(xy 110.0582 -277.349503) (xy 110.088726 -277.307487) (xy 110.125449 -277.270764) (xy 110.167465 -277.240238)
			(xy 110.213739 -277.21666) (xy 110.263132 -277.200612) (xy 110.314427 -277.192487) (xy 110.366361 -277.192487)
			(xy 110.417656 -277.200612) (xy 110.467049 -277.21666) (xy 110.513323 -277.240238) (xy 110.555339 -277.270764)
			(xy 110.592062 -277.307487) (xy 110.622588 -277.349503) (xy 110.646166 -277.395777) (xy 110.662214 -277.44517)
			(xy 110.670339 -277.496465) (xy 110.670848 -277.522432) (xy 110.670339 -277.548399) (xy 110.662214 -277.599694)
			(xy 110.646166 -277.649087) (xy 110.622588 -277.695361) (xy 110.592062 -277.737377) (xy 110.555339 -277.7741)
			(xy 110.513323 -277.804626) (xy 110.467049 -277.828204) (xy 110.417656 -277.844252) (xy 110.366361 -277.852377)
			(xy 110.314427 -277.852377) (xy 110.263132 -277.844252) (xy 110.213739 -277.828204) (xy 110.167465 -277.804626)
			(xy 110.125449 -277.7741) (xy 110.088726 -277.737377) (xy 110.0582 -277.695361) (xy 110.034622 -277.649087)
			(xy 110.018574 -277.599694) (xy 110.010449 -277.548399) (xy 109.730599 -277.548399) (xy 109.722477 -277.599677)
			(xy 109.706425 -277.649079) (xy 109.682843 -277.695361) (xy 109.65231 -277.737385) (xy 109.61558 -277.774114)
			(xy 109.573556 -277.804646) (xy 109.527273 -277.828228) (xy 109.477871 -277.844278) (xy 109.426566 -277.852404)
			(xy 109.400594 -277.852886) (xy 109.374974 -277.852361) (xy 109.32435 -277.844445) (xy 109.275551 -277.828819)
			(xy 109.229744 -277.805856) (xy 109.188026 -277.776106) (xy 109.151393 -277.740279) (xy 109.135672 -277.720044)
			(xy 108.725716 -277.720044) (xy 108.709981 -277.740272) (xy 108.673365 -277.776122) (xy 108.631655 -277.805892)
			(xy 108.585849 -277.828866) (xy 108.537046 -277.844495) (xy 108.486416 -277.852404) (xy 108.460794 -277.852886)
			(xy 108.43483 -277.852312) (xy 108.38354 -277.844188) (xy 108.334153 -277.828141) (xy 108.287885 -277.804565)
			(xy 108.245874 -277.774041) (xy 108.209155 -277.737322) (xy 108.178632 -277.69531) (xy 108.155057 -277.649041)
			(xy 108.13901 -277.599654) (xy 108.130887 -277.548364) (xy 107.850915 -277.548364) (xy 107.850861 -277.550912)
			(xy 107.841537 -277.605559) (xy 107.832906 -277.631906) (xy 107.825032 -277.654004) (xy 108.028994 -278.007318)
			(xy 108.052108 -278.011636) (xy 108.077018 -278.016855) (xy 108.125 -278.033813) (xy 108.169817 -278.057924)
			(xy 108.210409 -278.088617) (xy 108.245819 -278.125169) (xy 108.275209 -278.166715) (xy 108.297886 -278.212274)
			(xy 108.313313 -278.26077) (xy 108.321126 -278.311057) (xy 108.321602 -278.336502) (xy 108.321093 -278.362469)
			(xy 108.600749 -278.362469) (xy 108.600749 -278.310535) (xy 108.608874 -278.25924) (xy 108.624922 -278.209847)
			(xy 108.6485 -278.163573) (xy 108.679026 -278.121557) (xy 108.715749 -278.084834) (xy 108.757765 -278.054308)
			(xy 108.804039 -278.03073) (xy 108.853432 -278.014682) (xy 108.904727 -278.006557) (xy 108.956661 -278.006557)
			(xy 109.007956 -278.014682) (xy 109.057349 -278.03073) (xy 109.103623 -278.054308) (xy 109.145639 -278.084834)
			(xy 109.182362 -278.121557) (xy 109.212888 -278.163573) (xy 109.236466 -278.209847) (xy 109.252514 -278.25924)
			(xy 109.260639 -278.310535) (xy 109.261148 -278.336502) (xy 109.260639 -278.362469) (xy 109.540549 -278.362469)
			(xy 109.540549 -278.310535) (xy 109.548674 -278.25924) (xy 109.564722 -278.209847) (xy 109.5883 -278.163573)
			(xy 109.618826 -278.121557) (xy 109.655549 -278.084834) (xy 109.697565 -278.054308) (xy 109.743839 -278.03073)
			(xy 109.793232 -278.014682) (xy 109.844527 -278.006557) (xy 109.896461 -278.006557) (xy 109.947756 -278.014682)
			(xy 109.997149 -278.03073) (xy 110.043423 -278.054308) (xy 110.085439 -278.084834) (xy 110.122162 -278.121557)
			(xy 110.152688 -278.163573) (xy 110.176266 -278.209847) (xy 110.192314 -278.25924) (xy 110.200439 -278.310535)
			(xy 110.200948 -278.336502) (xy 110.200439 -278.362469) (xy 110.192314 -278.413764) (xy 110.176266 -278.463157)
			(xy 110.152688 -278.509431) (xy 110.122162 -278.551447) (xy 110.085439 -278.58817) (xy 110.043423 -278.618696)
			(xy 109.997149 -278.642274) (xy 109.947756 -278.658322) (xy 109.896461 -278.666447) (xy 109.844527 -278.666447)
			(xy 109.793232 -278.658322) (xy 109.743839 -278.642274) (xy 109.697565 -278.618696) (xy 109.655549 -278.58817)
			(xy 109.618826 -278.551447) (xy 109.5883 -278.509431) (xy 109.564722 -278.463157) (xy 109.548674 -278.413764)
			(xy 109.540549 -278.362469) (xy 109.260639 -278.362469) (xy 109.252514 -278.413764) (xy 109.236466 -278.463157)
			(xy 109.212888 -278.509431) (xy 109.182362 -278.551447) (xy 109.145639 -278.58817) (xy 109.103623 -278.618696)
			(xy 109.057349 -278.642274) (xy 109.007956 -278.658322) (xy 108.956661 -278.666447) (xy 108.904727 -278.666447)
			(xy 108.853432 -278.658322) (xy 108.804039 -278.642274) (xy 108.757765 -278.618696) (xy 108.715749 -278.58817)
			(xy 108.679026 -278.551447) (xy 108.6485 -278.509431) (xy 108.624922 -278.463157) (xy 108.608874 -278.413764)
			(xy 108.600749 -278.362469) (xy 108.321093 -278.362469) (xy 108.312968 -278.413764) (xy 108.29692 -278.463157)
			(xy 108.273342 -278.509431) (xy 108.242816 -278.551447) (xy 108.206093 -278.58817) (xy 108.164077 -278.618696)
			(xy 108.117803 -278.642274) (xy 108.06841 -278.658322) (xy 108.017115 -278.666447) (xy 107.965181 -278.666447)
			(xy 107.913886 -278.658322) (xy 107.864493 -278.642274) (xy 107.818219 -278.618696) (xy 107.776203 -278.58817)
			(xy 107.73948 -278.551447) (xy 107.708954 -278.509431) (xy 107.685376 -278.463157) (xy 107.669328 -278.413764)
			(xy 107.661203 -278.362469) (xy 107.660694 -278.336502) (xy 107.661248 -278.308516) (xy 107.670697 -278.253348)
			(xy 107.67949 -278.226774) (xy 107.68711 -278.204676) (xy 107.483402 -277.851616) (xy 107.460288 -277.847298)
			(xy 107.435344 -277.842172) (xy 107.38732 -277.825238) (xy 107.34246 -277.80114) (xy 107.301827 -277.770447)
			(xy 107.266382 -277.733886) (xy 107.236962 -277.692322) (xy 107.214264 -277.646738) (xy 107.198826 -277.598212)
			(xy 107.191012 -277.547893) (xy 107.19054 -277.522432) (xy 106.911648 -277.522432) (xy 106.911139 -277.548399)
			(xy 106.903014 -277.599694) (xy 106.886966 -277.649087) (xy 106.863388 -277.695361) (xy 106.832862 -277.737377)
			(xy 106.796139 -277.7741) (xy 106.754123 -277.804626) (xy 106.707849 -277.828204) (xy 106.658456 -277.844252)
			(xy 106.607161 -277.852377) (xy 106.555227 -277.852377) (xy 106.503932 -277.844252) (xy 106.454539 -277.828204)
			(xy 106.408265 -277.804626) (xy 106.366249 -277.7741) (xy 106.329526 -277.737377) (xy 106.299 -277.695361)
			(xy 106.275422 -277.649087) (xy 106.259374 -277.599694) (xy 106.251249 -277.548399) (xy 106.25074 -277.522432)
			(xy 105.971848 -277.522432) (xy 105.971339 -277.548399) (xy 105.963214 -277.599694) (xy 105.947166 -277.649087)
			(xy 105.923588 -277.695361) (xy 105.893062 -277.737377) (xy 105.856339 -277.7741) (xy 105.814323 -277.804626)
			(xy 105.768049 -277.828204) (xy 105.718656 -277.844252) (xy 105.667361 -277.852377) (xy 105.615427 -277.852377)
			(xy 105.564132 -277.844252) (xy 105.514739 -277.828204) (xy 105.468465 -277.804626) (xy 105.426449 -277.7741)
			(xy 105.389726 -277.737377) (xy 105.3592 -277.695361) (xy 105.335622 -277.649087) (xy 105.319574 -277.599694)
			(xy 105.311449 -277.548399) (xy 105.031539 -277.548399) (xy 105.023414 -277.599694) (xy 105.007366 -277.649087)
			(xy 104.983788 -277.695361) (xy 104.953262 -277.737377) (xy 104.916539 -277.7741) (xy 104.874523 -277.804626)
			(xy 104.828249 -277.828204) (xy 104.778856 -277.844252) (xy 104.727561 -277.852377) (xy 104.675627 -277.852377)
			(xy 104.624332 -277.844252) (xy 104.574939 -277.828204) (xy 104.528665 -277.804626) (xy 104.486649 -277.7741)
			(xy 104.449926 -277.737377) (xy 104.4194 -277.695361) (xy 104.395822 -277.649087) (xy 104.379774 -277.599694)
			(xy 104.371649 -277.548399) (xy 104.091739 -277.548399) (xy 104.083614 -277.599694) (xy 104.067566 -277.649087)
			(xy 104.043988 -277.695361) (xy 104.013462 -277.737377) (xy 103.976739 -277.7741) (xy 103.934723 -277.804626)
			(xy 103.888449 -277.828204) (xy 103.839056 -277.844252) (xy 103.787761 -277.852377) (xy 103.735827 -277.852377)
			(xy 103.684532 -277.844252) (xy 103.635139 -277.828204) (xy 103.588865 -277.804626) (xy 103.546849 -277.7741)
			(xy 103.510126 -277.737377) (xy 103.4796 -277.695361) (xy 103.456022 -277.649087) (xy 103.439974 -277.599694)
			(xy 103.431849 -277.548399) (xy 103.43134 -277.522432) (xy 103.431899 -277.494446) (xy 103.441344 -277.439278)
			(xy 103.450136 -277.412704) (xy 103.457756 -277.390606) (xy 103.254048 -277.0378) (xy 103.231188 -277.033482)
			(xy 103.206259 -277.028343) (xy 103.158271 -277.011378) (xy 103.11345 -276.98726) (xy 103.072856 -276.956557)
			(xy 103.037446 -276.919995) (xy 103.008058 -276.878438) (xy 102.985386 -276.832868) (xy 102.969967 -276.784362)
			(xy 102.962164 -276.734065) (xy 102.961694 -276.708616) (xy 102.682548 -276.708616) (xy 102.682039 -276.734583)
			(xy 102.673914 -276.785878) (xy 102.657866 -276.835271) (xy 102.634288 -276.881545) (xy 102.603762 -276.923561)
			(xy 102.567039 -276.960284) (xy 102.525023 -276.99081) (xy 102.478749 -277.014388) (xy 102.429356 -277.030436)
			(xy 102.378061 -277.038561) (xy 102.326127 -277.038561) (xy 102.274832 -277.030436) (xy 102.225439 -277.014388)
			(xy 102.179165 -276.99081) (xy 102.137149 -276.960284) (xy 102.100426 -276.923561) (xy 102.0699 -276.881545)
			(xy 102.046322 -276.835271) (xy 102.030274 -276.785878) (xy 102.022149 -276.734583) (xy 102.02164 -276.708616)
			(xy 101.743002 -276.708616) (xy 101.742493 -276.734583) (xy 101.734368 -276.785878) (xy 101.71832 -276.835271)
			(xy 101.694742 -276.881545) (xy 101.664216 -276.923561) (xy 101.627493 -276.960284) (xy 101.585477 -276.99081)
			(xy 101.539203 -277.014388) (xy 101.48981 -277.030436) (xy 101.438515 -277.038561) (xy 101.386581 -277.038561)
			(xy 101.335286 -277.030436) (xy 101.285893 -277.014388) (xy 101.239619 -276.99081) (xy 101.197603 -276.960284)
			(xy 101.16088 -276.923561) (xy 101.130354 -276.881545) (xy 101.106776 -276.835271) (xy 101.090728 -276.785878)
			(xy 101.082603 -276.734583) (xy 100.802693 -276.734583) (xy 100.794568 -276.785878) (xy 100.77852 -276.835271)
			(xy 100.754942 -276.881545) (xy 100.724416 -276.923561) (xy 100.687693 -276.960284) (xy 100.645677 -276.99081)
			(xy 100.599403 -277.014388) (xy 100.55001 -277.030436) (xy 100.498715 -277.038561) (xy 100.446781 -277.038561)
			(xy 100.395486 -277.030436) (xy 100.346093 -277.014388) (xy 100.299819 -276.99081) (xy 100.257803 -276.960284)
			(xy 100.22108 -276.923561) (xy 100.190554 -276.881545) (xy 100.166976 -276.835271) (xy 100.150928 -276.785878)
			(xy 100.142803 -276.734583) (xy 99.862893 -276.734583) (xy 99.854768 -276.785878) (xy 99.83872 -276.835271)
			(xy 99.815142 -276.881545) (xy 99.784616 -276.923561) (xy 99.747893 -276.960284) (xy 99.705877 -276.99081)
			(xy 99.659603 -277.014388) (xy 99.61021 -277.030436) (xy 99.558915 -277.038561) (xy 99.506981 -277.038561)
			(xy 99.455686 -277.030436) (xy 99.406293 -277.014388) (xy 99.360019 -276.99081) (xy 99.318003 -276.960284)
			(xy 99.28128 -276.923561) (xy 99.250754 -276.881545) (xy 99.227176 -276.835271) (xy 99.211128 -276.785878)
			(xy 99.203003 -276.734583) (xy 98.923093 -276.734583) (xy 98.914968 -276.785878) (xy 98.89892 -276.835271)
			(xy 98.875342 -276.881545) (xy 98.844816 -276.923561) (xy 98.808093 -276.960284) (xy 98.766077 -276.99081)
			(xy 98.719803 -277.014388) (xy 98.67041 -277.030436) (xy 98.619115 -277.038561) (xy 98.567181 -277.038561)
			(xy 98.515886 -277.030436) (xy 98.466493 -277.014388) (xy 98.420219 -276.99081) (xy 98.378203 -276.960284)
			(xy 98.34148 -276.923561) (xy 98.310954 -276.881545) (xy 98.287376 -276.835271) (xy 98.271328 -276.785878)
			(xy 98.263203 -276.734583) (xy 97.983039 -276.734583) (xy 97.974914 -276.785878) (xy 97.958866 -276.835271)
			(xy 97.935288 -276.881545) (xy 97.904762 -276.923561) (xy 97.868039 -276.960284) (xy 97.826023 -276.99081)
			(xy 97.779749 -277.014388) (xy 97.730356 -277.030436) (xy 97.679061 -277.038561) (xy 97.627127 -277.038561)
			(xy 97.575832 -277.030436) (xy 97.526439 -277.014388) (xy 97.480165 -276.99081) (xy 97.438149 -276.960284)
			(xy 97.401426 -276.923561) (xy 97.3709 -276.881545) (xy 97.347322 -276.835271) (xy 97.331274 -276.785878)
			(xy 97.323149 -276.734583) (xy 97.043493 -276.734583) (xy 97.035368 -276.785878) (xy 97.01932 -276.835271)
			(xy 96.995742 -276.881545) (xy 96.965216 -276.923561) (xy 96.928493 -276.960284) (xy 96.886477 -276.99081)
			(xy 96.840203 -277.014388) (xy 96.79081 -277.030436) (xy 96.739515 -277.038561) (xy 96.687581 -277.038561)
			(xy 96.636286 -277.030436) (xy 96.586893 -277.014388) (xy 96.540619 -276.99081) (xy 96.498603 -276.960284)
			(xy 96.46188 -276.923561) (xy 96.431354 -276.881545) (xy 96.407776 -276.835271) (xy 96.391728 -276.785878)
			(xy 96.383603 -276.734583) (xy 96.103939 -276.734583) (xy 96.103939 -276.735361) (xy 96.095334 -276.788157)
			(xy 96.078349 -276.838881) (xy 96.066356 -276.862794) (xy 96.066102 -276.863556) (xy 96.063308 -276.869144)
			(xy 96.060514 -276.880066) (xy 96.060514 -277.097998) (xy 96.0611 -277.109236) (xy 96.070731 -277.129542)
			(xy 96.079056 -277.137114) (xy 96.139254 -277.186898) (xy 96.143671 -277.190371) (xy 96.153669 -277.195494)
			(xy 96.159066 -277.197058) (xy 96.169734 -277.199852) (xy 96.181164 -277.197566) (xy 96.196384 -277.194837)
			(xy 96.22717 -277.191908) (xy 96.242632 -277.191724) (xy 96.243394 -277.191724) (xy 96.269381 -277.192207)
			(xy 96.320715 -277.200336) (xy 96.370146 -277.216396) (xy 96.416456 -277.239992) (xy 96.458504 -277.270541)
			(xy 96.495255 -277.307292) (xy 96.525805 -277.349339) (xy 96.549401 -277.395649) (xy 96.565462 -277.445079)
			(xy 96.573593 -277.496413) (xy 96.573593 -277.548387) (xy 96.573591 -277.548399) (xy 96.853249 -277.548399)
			(xy 96.853249 -277.496465) (xy 96.861374 -277.44517) (xy 96.877422 -277.395777) (xy 96.901 -277.349503)
			(xy 96.931526 -277.307487) (xy 96.968249 -277.270764) (xy 97.010265 -277.240238) (xy 97.056539 -277.21666)
			(xy 97.105932 -277.200612) (xy 97.157227 -277.192487) (xy 97.209161 -277.192487) (xy 97.260456 -277.200612)
			(xy 97.309849 -277.21666) (xy 97.356123 -277.240238) (xy 97.398139 -277.270764) (xy 97.434862 -277.307487)
			(xy 97.465388 -277.349503) (xy 97.488966 -277.395777) (xy 97.505014 -277.44517) (xy 97.513139 -277.496465)
			(xy 97.513648 -277.522432) (xy 97.513139 -277.548399) (xy 97.793049 -277.548399) (xy 97.793049 -277.496465)
			(xy 97.801174 -277.44517) (xy 97.817222 -277.395777) (xy 97.8408 -277.349503) (xy 97.871326 -277.307487)
			(xy 97.908049 -277.270764) (xy 97.950065 -277.240238) (xy 97.996339 -277.21666) (xy 98.045732 -277.200612)
			(xy 98.097027 -277.192487) (xy 98.148961 -277.192487) (xy 98.200256 -277.200612) (xy 98.249649 -277.21666)
			(xy 98.295923 -277.240238) (xy 98.337939 -277.270764) (xy 98.374662 -277.307487) (xy 98.405188 -277.349503)
			(xy 98.428766 -277.395777) (xy 98.444814 -277.44517) (xy 98.452939 -277.496465) (xy 98.453448 -277.522432)
			(xy 98.452939 -277.548399) (xy 98.732849 -277.548399) (xy 98.732849 -277.496465) (xy 98.740974 -277.44517)
			(xy 98.757022 -277.395777) (xy 98.7806 -277.349503) (xy 98.811126 -277.307487) (xy 98.847849 -277.270764)
			(xy 98.889865 -277.240238) (xy 98.936139 -277.21666) (xy 98.985532 -277.200612) (xy 99.036827 -277.192487)
			(xy 99.088761 -277.192487) (xy 99.140056 -277.200612) (xy 99.189449 -277.21666) (xy 99.235723 -277.240238)
			(xy 99.277739 -277.270764) (xy 99.314462 -277.307487) (xy 99.344988 -277.349503) (xy 99.368566 -277.395777)
			(xy 99.384614 -277.44517) (xy 99.392739 -277.496465) (xy 99.393248 -277.522432) (xy 99.392739 -277.548399)
			(xy 99.672649 -277.548399) (xy 99.672649 -277.496465) (xy 99.680774 -277.44517) (xy 99.696822 -277.395777)
			(xy 99.7204 -277.349503) (xy 99.750926 -277.307487) (xy 99.787649 -277.270764) (xy 99.829665 -277.240238)
			(xy 99.875939 -277.21666) (xy 99.925332 -277.200612) (xy 99.976627 -277.192487) (xy 100.028561 -277.192487)
			(xy 100.079856 -277.200612) (xy 100.129249 -277.21666) (xy 100.175523 -277.240238) (xy 100.217539 -277.270764)
			(xy 100.254262 -277.307487) (xy 100.284788 -277.349503) (xy 100.308366 -277.395777) (xy 100.324414 -277.44517)
			(xy 100.332539 -277.496465) (xy 100.333048 -277.522432) (xy 100.332539 -277.548399) (xy 100.612449 -277.548399)
			(xy 100.612449 -277.496465) (xy 100.620574 -277.44517) (xy 100.636622 -277.395777) (xy 100.6602 -277.349503)
			(xy 100.690726 -277.307487) (xy 100.727449 -277.270764) (xy 100.769465 -277.240238) (xy 100.815739 -277.21666)
			(xy 100.865132 -277.200612) (xy 100.916427 -277.192487) (xy 100.968361 -277.192487) (xy 101.019656 -277.200612)
			(xy 101.069049 -277.21666) (xy 101.115323 -277.240238) (xy 101.157339 -277.270764) (xy 101.194062 -277.307487)
			(xy 101.224588 -277.349503) (xy 101.248166 -277.395777) (xy 101.264214 -277.44517) (xy 101.272339 -277.496465)
			(xy 101.272848 -277.522432) (xy 101.272339 -277.548399) (xy 101.552503 -277.548399) (xy 101.552503 -277.496465)
			(xy 101.560628 -277.44517) (xy 101.576676 -277.395777) (xy 101.600254 -277.349503) (xy 101.63078 -277.307487)
			(xy 101.667503 -277.270764) (xy 101.709519 -277.240238) (xy 101.755793 -277.21666) (xy 101.805186 -277.200612)
			(xy 101.856481 -277.192487) (xy 101.908415 -277.192487) (xy 101.95971 -277.200612) (xy 102.009103 -277.21666)
			(xy 102.055377 -277.240238) (xy 102.097393 -277.270764) (xy 102.134116 -277.307487) (xy 102.164642 -277.349503)
			(xy 102.18822 -277.395777) (xy 102.204268 -277.44517) (xy 102.212393 -277.496465) (xy 102.212902 -277.522432)
			(xy 102.212393 -277.548399) (xy 102.492049 -277.548399) (xy 102.492049 -277.496465) (xy 102.500174 -277.44517)
			(xy 102.516222 -277.395777) (xy 102.5398 -277.349503) (xy 102.570326 -277.307487) (xy 102.607049 -277.270764)
			(xy 102.649065 -277.240238) (xy 102.695339 -277.21666) (xy 102.744732 -277.200612) (xy 102.796027 -277.192487)
			(xy 102.847961 -277.192487) (xy 102.899256 -277.200612) (xy 102.948649 -277.21666) (xy 102.994923 -277.240238)
			(xy 103.036939 -277.270764) (xy 103.073662 -277.307487) (xy 103.104188 -277.349503) (xy 103.127766 -277.395777)
			(xy 103.143814 -277.44517) (xy 103.151939 -277.496465) (xy 103.152448 -277.522432) (xy 103.151939 -277.548399)
			(xy 103.143814 -277.599694) (xy 103.127766 -277.649087) (xy 103.104188 -277.695361) (xy 103.073662 -277.737377)
			(xy 103.036939 -277.7741) (xy 102.994923 -277.804626) (xy 102.948649 -277.828204) (xy 102.899256 -277.844252)
			(xy 102.847961 -277.852377) (xy 102.796027 -277.852377) (xy 102.744732 -277.844252) (xy 102.695339 -277.828204)
			(xy 102.649065 -277.804626) (xy 102.607049 -277.7741) (xy 102.570326 -277.737377) (xy 102.5398 -277.695361)
			(xy 102.516222 -277.649087) (xy 102.500174 -277.599694) (xy 102.492049 -277.548399) (xy 102.212393 -277.548399)
			(xy 102.204268 -277.599694) (xy 102.18822 -277.649087) (xy 102.164642 -277.695361) (xy 102.134116 -277.737377)
			(xy 102.097393 -277.7741) (xy 102.055377 -277.804626) (xy 102.009103 -277.828204) (xy 101.95971 -277.844252)
			(xy 101.908415 -277.852377) (xy 101.856481 -277.852377) (xy 101.805186 -277.844252) (xy 101.755793 -277.828204)
			(xy 101.709519 -277.804626) (xy 101.667503 -277.7741) (xy 101.63078 -277.737377) (xy 101.600254 -277.695361)
			(xy 101.576676 -277.649087) (xy 101.560628 -277.599694) (xy 101.552503 -277.548399) (xy 101.272339 -277.548399)
			(xy 101.264214 -277.599694) (xy 101.248166 -277.649087) (xy 101.224588 -277.695361) (xy 101.194062 -277.737377)
			(xy 101.157339 -277.7741) (xy 101.115323 -277.804626) (xy 101.069049 -277.828204) (xy 101.019656 -277.844252)
			(xy 100.968361 -277.852377) (xy 100.916427 -277.852377) (xy 100.865132 -277.844252) (xy 100.815739 -277.828204)
			(xy 100.769465 -277.804626) (xy 100.727449 -277.7741) (xy 100.690726 -277.737377) (xy 100.6602 -277.695361)
			(xy 100.636622 -277.649087) (xy 100.620574 -277.599694) (xy 100.612449 -277.548399) (xy 100.332539 -277.548399)
			(xy 100.324414 -277.599694) (xy 100.308366 -277.649087) (xy 100.284788 -277.695361) (xy 100.254262 -277.737377)
			(xy 100.217539 -277.7741) (xy 100.175523 -277.804626) (xy 100.129249 -277.828204) (xy 100.079856 -277.844252)
			(xy 100.028561 -277.852377) (xy 99.976627 -277.852377) (xy 99.925332 -277.844252) (xy 99.875939 -277.828204)
			(xy 99.829665 -277.804626) (xy 99.787649 -277.7741) (xy 99.750926 -277.737377) (xy 99.7204 -277.695361)
			(xy 99.696822 -277.649087) (xy 99.680774 -277.599694) (xy 99.672649 -277.548399) (xy 99.392739 -277.548399)
			(xy 99.384614 -277.599694) (xy 99.368566 -277.649087) (xy 99.344988 -277.695361) (xy 99.314462 -277.737377)
			(xy 99.277739 -277.7741) (xy 99.235723 -277.804626) (xy 99.189449 -277.828204) (xy 99.140056 -277.844252)
			(xy 99.088761 -277.852377) (xy 99.036827 -277.852377) (xy 98.985532 -277.844252) (xy 98.936139 -277.828204)
			(xy 98.889865 -277.804626) (xy 98.847849 -277.7741) (xy 98.811126 -277.737377) (xy 98.7806 -277.695361)
			(xy 98.757022 -277.649087) (xy 98.740974 -277.599694) (xy 98.732849 -277.548399) (xy 98.452939 -277.548399)
			(xy 98.444814 -277.599694) (xy 98.428766 -277.649087) (xy 98.405188 -277.695361) (xy 98.374662 -277.737377)
			(xy 98.337939 -277.7741) (xy 98.295923 -277.804626) (xy 98.249649 -277.828204) (xy 98.200256 -277.844252)
			(xy 98.148961 -277.852377) (xy 98.097027 -277.852377) (xy 98.045732 -277.844252) (xy 97.996339 -277.828204)
			(xy 97.950065 -277.804626) (xy 97.908049 -277.7741) (xy 97.871326 -277.737377) (xy 97.8408 -277.695361)
			(xy 97.817222 -277.649087) (xy 97.801174 -277.599694) (xy 97.793049 -277.548399) (xy 97.513139 -277.548399)
			(xy 97.505014 -277.599694) (xy 97.488966 -277.649087) (xy 97.465388 -277.695361) (xy 97.434862 -277.737377)
			(xy 97.398139 -277.7741) (xy 97.356123 -277.804626) (xy 97.309849 -277.828204) (xy 97.260456 -277.844252)
			(xy 97.209161 -277.852377) (xy 97.157227 -277.852377) (xy 97.105932 -277.844252) (xy 97.056539 -277.828204)
			(xy 97.010265 -277.804626) (xy 96.968249 -277.7741) (xy 96.931526 -277.737377) (xy 96.901 -277.695361)
			(xy 96.877422 -277.649087) (xy 96.861374 -277.599694) (xy 96.853249 -277.548399) (xy 96.573591 -277.548399)
			(xy 96.565462 -277.599721) (xy 96.549401 -277.649151) (xy 96.525805 -277.695461) (xy 96.495255 -277.737508)
			(xy 96.458504 -277.774259) (xy 96.416456 -277.804808) (xy 96.370146 -277.828404) (xy 96.320715 -277.844464)
			(xy 96.269381 -277.852593) (xy 96.243394 -277.85314) (xy 96.242632 -277.85314) (xy 96.227171 -277.852937)
			(xy 96.196386 -277.850016) (xy 96.181164 -277.847298) (xy 96.169734 -277.845012) (xy 96.159066 -277.847806)
			(xy 96.153663 -277.849353) (xy 96.143666 -277.854484) (xy 96.139254 -277.857966) (xy 96.079056 -277.90775)
			(xy 96.070769 -277.91535) (xy 96.061141 -277.93564) (xy 96.060514 -277.946866) (xy 96.060514 -278.362469)
			(xy 96.383603 -278.362469) (xy 96.383603 -278.310535) (xy 96.391728 -278.25924) (xy 96.407776 -278.209847)
			(xy 96.431354 -278.163573) (xy 96.46188 -278.121557) (xy 96.498603 -278.084834) (xy 96.540619 -278.054308)
			(xy 96.586893 -278.03073) (xy 96.636286 -278.014682) (xy 96.687581 -278.006557) (xy 96.739515 -278.006557)
			(xy 96.79081 -278.014682) (xy 96.840203 -278.03073) (xy 96.886477 -278.054308) (xy 96.928493 -278.084834)
			(xy 96.965216 -278.121557) (xy 96.995742 -278.163573) (xy 97.01932 -278.209847) (xy 97.035368 -278.25924)
			(xy 97.043493 -278.310535) (xy 97.044002 -278.336502) (xy 97.043493 -278.362469) (xy 97.323403 -278.362469)
			(xy 97.323403 -278.310535) (xy 97.331528 -278.25924) (xy 97.347576 -278.209847) (xy 97.371154 -278.163573)
			(xy 97.40168 -278.121557) (xy 97.438403 -278.084834) (xy 97.480419 -278.054308) (xy 97.526693 -278.03073)
			(xy 97.576086 -278.014682) (xy 97.627381 -278.006557) (xy 97.679315 -278.006557) (xy 97.73061 -278.014682)
			(xy 97.780003 -278.03073) (xy 97.826277 -278.054308) (xy 97.868293 -278.084834) (xy 97.905016 -278.121557)
			(xy 97.935542 -278.163573) (xy 97.95912 -278.209847) (xy 97.975168 -278.25924) (xy 97.983293 -278.310535)
			(xy 97.983802 -278.336502) (xy 97.983293 -278.362469) (xy 98.263203 -278.362469) (xy 98.263203 -278.310535)
			(xy 98.271328 -278.25924) (xy 98.287376 -278.209847) (xy 98.310954 -278.163573) (xy 98.34148 -278.121557)
			(xy 98.378203 -278.084834) (xy 98.420219 -278.054308) (xy 98.466493 -278.03073) (xy 98.515886 -278.014682)
			(xy 98.567181 -278.006557) (xy 98.619115 -278.006557) (xy 98.67041 -278.014682) (xy 98.719803 -278.03073)
			(xy 98.766077 -278.054308) (xy 98.808093 -278.084834) (xy 98.844816 -278.121557) (xy 98.875342 -278.163573)
			(xy 98.89892 -278.209847) (xy 98.914968 -278.25924) (xy 98.923093 -278.310535) (xy 98.923602 -278.336502)
			(xy 98.923093 -278.362469) (xy 99.203003 -278.362469) (xy 99.203003 -278.310535) (xy 99.211128 -278.25924)
			(xy 99.227176 -278.209847) (xy 99.250754 -278.163573) (xy 99.28128 -278.121557) (xy 99.318003 -278.084834)
			(xy 99.360019 -278.054308) (xy 99.406293 -278.03073) (xy 99.455686 -278.014682) (xy 99.506981 -278.006557)
			(xy 99.558915 -278.006557) (xy 99.61021 -278.014682) (xy 99.659603 -278.03073) (xy 99.705877 -278.054308)
			(xy 99.747893 -278.084834) (xy 99.784616 -278.121557) (xy 99.815142 -278.163573) (xy 99.83872 -278.209847)
			(xy 99.854768 -278.25924) (xy 99.862893 -278.310535) (xy 99.863402 -278.336502) (xy 99.862893 -278.362469)
			(xy 100.142803 -278.362469) (xy 100.142803 -278.310535) (xy 100.150928 -278.25924) (xy 100.166976 -278.209847)
			(xy 100.190554 -278.163573) (xy 100.22108 -278.121557) (xy 100.257803 -278.084834) (xy 100.299819 -278.054308)
			(xy 100.346093 -278.03073) (xy 100.395486 -278.014682) (xy 100.446781 -278.006557) (xy 100.498715 -278.006557)
			(xy 100.55001 -278.014682) (xy 100.599403 -278.03073) (xy 100.645677 -278.054308) (xy 100.687693 -278.084834)
			(xy 100.724416 -278.121557) (xy 100.754942 -278.163573) (xy 100.77852 -278.209847) (xy 100.794568 -278.25924)
			(xy 100.802693 -278.310535) (xy 100.803202 -278.336502) (xy 100.802693 -278.362469) (xy 101.082349 -278.362469)
			(xy 101.082349 -278.310535) (xy 101.090474 -278.25924) (xy 101.106522 -278.209847) (xy 101.1301 -278.163573)
			(xy 101.160626 -278.121557) (xy 101.197349 -278.084834) (xy 101.239365 -278.054308) (xy 101.285639 -278.03073)
			(xy 101.335032 -278.014682) (xy 101.386327 -278.006557) (xy 101.438261 -278.006557) (xy 101.489556 -278.014682)
			(xy 101.538949 -278.03073) (xy 101.585223 -278.054308) (xy 101.627239 -278.084834) (xy 101.663962 -278.121557)
			(xy 101.694488 -278.163573) (xy 101.718066 -278.209847) (xy 101.734114 -278.25924) (xy 101.742239 -278.310535)
			(xy 101.742748 -278.336502) (xy 101.742239 -278.362469) (xy 102.022403 -278.362469) (xy 102.022403 -278.310535)
			(xy 102.030528 -278.25924) (xy 102.046576 -278.209847) (xy 102.070154 -278.163573) (xy 102.10068 -278.121557)
			(xy 102.137403 -278.084834) (xy 102.179419 -278.054308) (xy 102.225693 -278.03073) (xy 102.275086 -278.014682)
			(xy 102.326381 -278.006557) (xy 102.378315 -278.006557) (xy 102.42961 -278.014682) (xy 102.479003 -278.03073)
			(xy 102.525277 -278.054308) (xy 102.567293 -278.084834) (xy 102.604016 -278.121557) (xy 102.634542 -278.163573)
			(xy 102.65812 -278.209847) (xy 102.674168 -278.25924) (xy 102.682293 -278.310535) (xy 102.682802 -278.336502)
			(xy 102.682293 -278.362469) (xy 102.962203 -278.362469) (xy 102.962203 -278.310535) (xy 102.970328 -278.25924)
			(xy 102.986376 -278.209847) (xy 103.009954 -278.163573) (xy 103.04048 -278.121557) (xy 103.077203 -278.084834)
			(xy 103.119219 -278.054308) (xy 103.165493 -278.03073) (xy 103.214886 -278.014682) (xy 103.266181 -278.006557)
			(xy 103.318115 -278.006557) (xy 103.36941 -278.014682) (xy 103.418803 -278.03073) (xy 103.465077 -278.054308)
			(xy 103.507093 -278.084834) (xy 103.543816 -278.121557) (xy 103.574342 -278.163573) (xy 103.59792 -278.209847)
			(xy 103.613968 -278.25924) (xy 103.622093 -278.310535) (xy 103.622602 -278.336502) (xy 103.622093 -278.362469)
			(xy 103.902003 -278.362469) (xy 103.902003 -278.310535) (xy 103.910128 -278.25924) (xy 103.926176 -278.209847)
			(xy 103.949754 -278.163573) (xy 103.98028 -278.121557) (xy 104.017003 -278.084834) (xy 104.059019 -278.054308)
			(xy 104.105293 -278.03073) (xy 104.154686 -278.014682) (xy 104.205981 -278.006557) (xy 104.257915 -278.006557)
			(xy 104.30921 -278.014682) (xy 104.358603 -278.03073) (xy 104.404877 -278.054308) (xy 104.446893 -278.084834)
			(xy 104.483616 -278.121557) (xy 104.514142 -278.163573) (xy 104.53772 -278.209847) (xy 104.553768 -278.25924)
			(xy 104.561893 -278.310535) (xy 104.562402 -278.336502) (xy 104.561893 -278.362469) (xy 104.841549 -278.362469)
			(xy 104.841549 -278.310535) (xy 104.849674 -278.25924) (xy 104.865722 -278.209847) (xy 104.8893 -278.163573)
			(xy 104.919826 -278.121557) (xy 104.956549 -278.084834) (xy 104.998565 -278.054308) (xy 105.044839 -278.03073)
			(xy 105.094232 -278.014682) (xy 105.145527 -278.006557) (xy 105.197461 -278.006557) (xy 105.248756 -278.014682)
			(xy 105.298149 -278.03073) (xy 105.344423 -278.054308) (xy 105.386439 -278.084834) (xy 105.423162 -278.121557)
			(xy 105.453688 -278.163573) (xy 105.477266 -278.209847) (xy 105.493314 -278.25924) (xy 105.501439 -278.310535)
			(xy 105.501948 -278.336502) (xy 105.501439 -278.362469) (xy 105.781603 -278.362469) (xy 105.781603 -278.310535)
			(xy 105.789728 -278.25924) (xy 105.805776 -278.209847) (xy 105.829354 -278.163573) (xy 105.85988 -278.121557)
			(xy 105.896603 -278.084834) (xy 105.938619 -278.054308) (xy 105.984893 -278.03073) (xy 106.034286 -278.014682)
			(xy 106.085581 -278.006557) (xy 106.137515 -278.006557) (xy 106.18881 -278.014682) (xy 106.238203 -278.03073)
			(xy 106.284477 -278.054308) (xy 106.326493 -278.084834) (xy 106.363216 -278.121557) (xy 106.393742 -278.163573)
			(xy 106.41732 -278.209847) (xy 106.433368 -278.25924) (xy 106.441493 -278.310535) (xy 106.442002 -278.336502)
			(xy 106.441493 -278.362469) (xy 106.721403 -278.362469) (xy 106.721403 -278.310535) (xy 106.729528 -278.25924)
			(xy 106.745576 -278.209847) (xy 106.769154 -278.163573) (xy 106.79968 -278.121557) (xy 106.836403 -278.084834)
			(xy 106.878419 -278.054308) (xy 106.924693 -278.03073) (xy 106.974086 -278.014682) (xy 107.025381 -278.006557)
			(xy 107.077315 -278.006557) (xy 107.12861 -278.014682) (xy 107.178003 -278.03073) (xy 107.224277 -278.054308)
			(xy 107.266293 -278.084834) (xy 107.303016 -278.121557) (xy 107.333542 -278.163573) (xy 107.35712 -278.209847)
			(xy 107.373168 -278.25924) (xy 107.381293 -278.310535) (xy 107.381802 -278.336502) (xy 107.381293 -278.362469)
			(xy 107.373168 -278.413764) (xy 107.35712 -278.463157) (xy 107.333542 -278.509431) (xy 107.303016 -278.551447)
			(xy 107.266293 -278.58817) (xy 107.224277 -278.618696) (xy 107.178003 -278.642274) (xy 107.12861 -278.658322)
			(xy 107.077315 -278.666447) (xy 107.025381 -278.666447) (xy 106.974086 -278.658322) (xy 106.924693 -278.642274)
			(xy 106.878419 -278.618696) (xy 106.836403 -278.58817) (xy 106.79968 -278.551447) (xy 106.769154 -278.509431)
			(xy 106.745576 -278.463157) (xy 106.729528 -278.413764) (xy 106.721403 -278.362469) (xy 106.441493 -278.362469)
			(xy 106.433368 -278.413764) (xy 106.41732 -278.463157) (xy 106.393742 -278.509431) (xy 106.363216 -278.551447)
			(xy 106.326493 -278.58817) (xy 106.284477 -278.618696) (xy 106.238203 -278.642274) (xy 106.18881 -278.658322)
			(xy 106.137515 -278.666447) (xy 106.085581 -278.666447) (xy 106.034286 -278.658322) (xy 105.984893 -278.642274)
			(xy 105.938619 -278.618696) (xy 105.896603 -278.58817) (xy 105.85988 -278.551447) (xy 105.829354 -278.509431)
			(xy 105.805776 -278.463157) (xy 105.789728 -278.413764) (xy 105.781603 -278.362469) (xy 105.501439 -278.362469)
			(xy 105.493314 -278.413764) (xy 105.477266 -278.463157) (xy 105.453688 -278.509431) (xy 105.423162 -278.551447)
			(xy 105.386439 -278.58817) (xy 105.344423 -278.618696) (xy 105.298149 -278.642274) (xy 105.248756 -278.658322)
			(xy 105.197461 -278.666447) (xy 105.145527 -278.666447) (xy 105.094232 -278.658322) (xy 105.044839 -278.642274)
			(xy 104.998565 -278.618696) (xy 104.956549 -278.58817) (xy 104.919826 -278.551447) (xy 104.8893 -278.509431)
			(xy 104.865722 -278.463157) (xy 104.849674 -278.413764) (xy 104.841549 -278.362469) (xy 104.561893 -278.362469)
			(xy 104.553768 -278.413764) (xy 104.53772 -278.463157) (xy 104.514142 -278.509431) (xy 104.483616 -278.551447)
			(xy 104.446893 -278.58817) (xy 104.404877 -278.618696) (xy 104.358603 -278.642274) (xy 104.30921 -278.658322)
			(xy 104.257915 -278.666447) (xy 104.205981 -278.666447) (xy 104.154686 -278.658322) (xy 104.105293 -278.642274)
			(xy 104.059019 -278.618696) (xy 104.017003 -278.58817) (xy 103.98028 -278.551447) (xy 103.949754 -278.509431)
			(xy 103.926176 -278.463157) (xy 103.910128 -278.413764) (xy 103.902003 -278.362469) (xy 103.622093 -278.362469)
			(xy 103.613968 -278.413764) (xy 103.59792 -278.463157) (xy 103.574342 -278.509431) (xy 103.543816 -278.551447)
			(xy 103.507093 -278.58817) (xy 103.465077 -278.618696) (xy 103.418803 -278.642274) (xy 103.36941 -278.658322)
			(xy 103.318115 -278.666447) (xy 103.266181 -278.666447) (xy 103.214886 -278.658322) (xy 103.165493 -278.642274)
			(xy 103.119219 -278.618696) (xy 103.077203 -278.58817) (xy 103.04048 -278.551447) (xy 103.009954 -278.509431)
			(xy 102.986376 -278.463157) (xy 102.970328 -278.413764) (xy 102.962203 -278.362469) (xy 102.682293 -278.362469)
			(xy 102.674168 -278.413764) (xy 102.65812 -278.463157) (xy 102.634542 -278.509431) (xy 102.604016 -278.551447)
			(xy 102.567293 -278.58817) (xy 102.525277 -278.618696) (xy 102.479003 -278.642274) (xy 102.42961 -278.658322)
			(xy 102.378315 -278.666447) (xy 102.326381 -278.666447) (xy 102.275086 -278.658322) (xy 102.225693 -278.642274)
			(xy 102.179419 -278.618696) (xy 102.137403 -278.58817) (xy 102.10068 -278.551447) (xy 102.070154 -278.509431)
			(xy 102.046576 -278.463157) (xy 102.030528 -278.413764) (xy 102.022403 -278.362469) (xy 101.742239 -278.362469)
			(xy 101.734114 -278.413764) (xy 101.718066 -278.463157) (xy 101.694488 -278.509431) (xy 101.663962 -278.551447)
			(xy 101.627239 -278.58817) (xy 101.585223 -278.618696) (xy 101.538949 -278.642274) (xy 101.489556 -278.658322)
			(xy 101.438261 -278.666447) (xy 101.386327 -278.666447) (xy 101.335032 -278.658322) (xy 101.285639 -278.642274)
			(xy 101.239365 -278.618696) (xy 101.197349 -278.58817) (xy 101.160626 -278.551447) (xy 101.1301 -278.509431)
			(xy 101.106522 -278.463157) (xy 101.090474 -278.413764) (xy 101.082349 -278.362469) (xy 100.802693 -278.362469)
			(xy 100.794568 -278.413764) (xy 100.77852 -278.463157) (xy 100.754942 -278.509431) (xy 100.724416 -278.551447)
			(xy 100.687693 -278.58817) (xy 100.645677 -278.618696) (xy 100.599403 -278.642274) (xy 100.55001 -278.658322)
			(xy 100.498715 -278.666447) (xy 100.446781 -278.666447) (xy 100.395486 -278.658322) (xy 100.346093 -278.642274)
			(xy 100.299819 -278.618696) (xy 100.257803 -278.58817) (xy 100.22108 -278.551447) (xy 100.190554 -278.509431)
			(xy 100.166976 -278.463157) (xy 100.150928 -278.413764) (xy 100.142803 -278.362469) (xy 99.862893 -278.362469)
			(xy 99.854768 -278.413764) (xy 99.83872 -278.463157) (xy 99.815142 -278.509431) (xy 99.784616 -278.551447)
			(xy 99.747893 -278.58817) (xy 99.705877 -278.618696) (xy 99.659603 -278.642274) (xy 99.61021 -278.658322)
			(xy 99.558915 -278.666447) (xy 99.506981 -278.666447) (xy 99.455686 -278.658322) (xy 99.406293 -278.642274)
			(xy 99.360019 -278.618696) (xy 99.318003 -278.58817) (xy 99.28128 -278.551447) (xy 99.250754 -278.509431)
			(xy 99.227176 -278.463157) (xy 99.211128 -278.413764) (xy 99.203003 -278.362469) (xy 98.923093 -278.362469)
			(xy 98.914968 -278.413764) (xy 98.89892 -278.463157) (xy 98.875342 -278.509431) (xy 98.844816 -278.551447)
			(xy 98.808093 -278.58817) (xy 98.766077 -278.618696) (xy 98.719803 -278.642274) (xy 98.67041 -278.658322)
			(xy 98.619115 -278.666447) (xy 98.567181 -278.666447) (xy 98.515886 -278.658322) (xy 98.466493 -278.642274)
			(xy 98.420219 -278.618696) (xy 98.378203 -278.58817) (xy 98.34148 -278.551447) (xy 98.310954 -278.509431)
			(xy 98.287376 -278.463157) (xy 98.271328 -278.413764) (xy 98.263203 -278.362469) (xy 97.983293 -278.362469)
			(xy 97.975168 -278.413764) (xy 97.95912 -278.463157) (xy 97.935542 -278.509431) (xy 97.905016 -278.551447)
			(xy 97.868293 -278.58817) (xy 97.826277 -278.618696) (xy 97.780003 -278.642274) (xy 97.73061 -278.658322)
			(xy 97.679315 -278.666447) (xy 97.627381 -278.666447) (xy 97.576086 -278.658322) (xy 97.526693 -278.642274)
			(xy 97.480419 -278.618696) (xy 97.438403 -278.58817) (xy 97.40168 -278.551447) (xy 97.371154 -278.509431)
			(xy 97.347576 -278.463157) (xy 97.331528 -278.413764) (xy 97.323403 -278.362469) (xy 97.043493 -278.362469)
			(xy 97.035368 -278.413764) (xy 97.01932 -278.463157) (xy 96.995742 -278.509431) (xy 96.965216 -278.551447)
			(xy 96.928493 -278.58817) (xy 96.886477 -278.618696) (xy 96.840203 -278.642274) (xy 96.79081 -278.658322)
			(xy 96.739515 -278.666447) (xy 96.687581 -278.666447) (xy 96.636286 -278.658322) (xy 96.586893 -278.642274)
			(xy 96.540619 -278.618696) (xy 96.498603 -278.58817) (xy 96.46188 -278.551447) (xy 96.431354 -278.509431)
			(xy 96.407776 -278.463157) (xy 96.391728 -278.413764) (xy 96.383603 -278.362469) (xy 96.060514 -278.362469)
			(xy 96.060514 -278.725884) (xy 96.061097 -278.737124) (xy 96.070724 -278.757434) (xy 96.079056 -278.765)
			(xy 96.139254 -278.814784) (xy 96.14367 -278.818258) (xy 96.153668 -278.823382) (xy 96.159066 -278.824944)
			(xy 96.169734 -278.827738) (xy 96.181164 -278.825452) (xy 96.196384 -278.822723) (xy 96.22717 -278.819794)
			(xy 96.242632 -278.81961) (xy 96.243394 -278.81961) (xy 96.269382 -278.820093) (xy 96.320719 -278.828223)
			(xy 96.370151 -278.844284) (xy 96.416463 -278.86788) (xy 96.458513 -278.89843) (xy 96.495266 -278.935183)
			(xy 96.525817 -278.977232) (xy 96.549414 -279.023543) (xy 96.565476 -279.072975) (xy 96.573607 -279.124312)
			(xy 96.573607 -279.176285) (xy 96.853249 -279.176285) (xy 96.853249 -279.124351) (xy 96.861374 -279.073056)
			(xy 96.877422 -279.023663) (xy 96.901 -278.977389) (xy 96.931526 -278.935373) (xy 96.968249 -278.89865)
			(xy 97.010265 -278.868124) (xy 97.056539 -278.844546) (xy 97.105932 -278.828498) (xy 97.157227 -278.820373)
			(xy 97.209161 -278.820373) (xy 97.260456 -278.828498) (xy 97.309849 -278.844546) (xy 97.356123 -278.868124)
			(xy 97.398139 -278.89865) (xy 97.434862 -278.935373) (xy 97.465388 -278.977389) (xy 97.488966 -279.023663)
			(xy 97.505014 -279.073056) (xy 97.513139 -279.124351) (xy 97.513648 -279.150318) (xy 97.513139 -279.176285)
			(xy 97.793303 -279.176285) (xy 97.793303 -279.124351) (xy 97.801428 -279.073056) (xy 97.817476 -279.023663)
			(xy 97.841054 -278.977389) (xy 97.87158 -278.935373) (xy 97.908303 -278.89865) (xy 97.950319 -278.868124)
			(xy 97.996593 -278.844546) (xy 98.045986 -278.828498) (xy 98.097281 -278.820373) (xy 98.149215 -278.820373)
			(xy 98.20051 -278.828498) (xy 98.249903 -278.844546) (xy 98.296177 -278.868124) (xy 98.338193 -278.89865)
			(xy 98.374916 -278.935373) (xy 98.405442 -278.977389) (xy 98.42902 -279.023663) (xy 98.445068 -279.073056)
			(xy 98.453193 -279.124351) (xy 98.453702 -279.150318) (xy 98.453193 -279.176285) (xy 98.732849 -279.176285)
			(xy 98.732849 -279.124351) (xy 98.740974 -279.073056) (xy 98.757022 -279.023663) (xy 98.7806 -278.977389)
			(xy 98.811126 -278.935373) (xy 98.847849 -278.89865) (xy 98.889865 -278.868124) (xy 98.936139 -278.844546)
			(xy 98.985532 -278.828498) (xy 99.036827 -278.820373) (xy 99.088761 -278.820373) (xy 99.140056 -278.828498)
			(xy 99.189449 -278.844546) (xy 99.235723 -278.868124) (xy 99.277739 -278.89865) (xy 99.314462 -278.935373)
			(xy 99.344988 -278.977389) (xy 99.368566 -279.023663) (xy 99.384614 -279.073056) (xy 99.392739 -279.124351)
			(xy 99.393248 -279.150318) (xy 99.392739 -279.176285) (xy 99.672649 -279.176285) (xy 99.672649 -279.124351)
			(xy 99.680774 -279.073056) (xy 99.696822 -279.023663) (xy 99.7204 -278.977389) (xy 99.750926 -278.935373)
			(xy 99.787649 -278.89865) (xy 99.829665 -278.868124) (xy 99.875939 -278.844546) (xy 99.925332 -278.828498)
			(xy 99.976627 -278.820373) (xy 100.028561 -278.820373) (xy 100.079856 -278.828498) (xy 100.129249 -278.844546)
			(xy 100.175523 -278.868124) (xy 100.217539 -278.89865) (xy 100.254262 -278.935373) (xy 100.284788 -278.977389)
			(xy 100.308366 -279.023663) (xy 100.324414 -279.073056) (xy 100.332539 -279.124351) (xy 100.333048 -279.150318)
			(xy 100.332539 -279.176285) (xy 100.612703 -279.176285) (xy 100.612703 -279.124351) (xy 100.620828 -279.073056)
			(xy 100.636876 -279.023663) (xy 100.660454 -278.977389) (xy 100.69098 -278.935373) (xy 100.727703 -278.89865)
			(xy 100.769719 -278.868124) (xy 100.815993 -278.844546) (xy 100.865386 -278.828498) (xy 100.916681 -278.820373)
			(xy 100.968615 -278.820373) (xy 101.01991 -278.828498) (xy 101.069303 -278.844546) (xy 101.115577 -278.868124)
			(xy 101.157593 -278.89865) (xy 101.194316 -278.935373) (xy 101.224842 -278.977389) (xy 101.24842 -279.023663)
			(xy 101.264468 -279.073056) (xy 101.272593 -279.124351) (xy 101.273102 -279.150318) (xy 101.55174 -279.150318)
			(xy 101.552249 -279.124351) (xy 101.560374 -279.073056) (xy 101.576422 -279.023663) (xy 101.6 -278.977389)
			(xy 101.630526 -278.935373) (xy 101.667249 -278.89865) (xy 101.709265 -278.868124) (xy 101.755539 -278.844546)
			(xy 101.804932 -278.828498) (xy 101.856227 -278.820373) (xy 101.908161 -278.820373) (xy 101.959456 -278.828498)
			(xy 102.008849 -278.844546) (xy 102.055123 -278.868124) (xy 102.097139 -278.89865) (xy 102.133862 -278.935373)
			(xy 102.164388 -278.977389) (xy 102.187966 -279.023663) (xy 102.204014 -279.073056) (xy 102.212139 -279.124351)
			(xy 102.212648 -279.150318) (xy 102.212648 -279.150572) (xy 102.212109 -279.176266) (xy 102.492073 -279.176266)
			(xy 102.492073 -279.124334) (xy 102.500197 -279.073043) (xy 102.516244 -279.023653) (xy 102.53982 -278.977382)
			(xy 102.570344 -278.935369) (xy 102.607065 -278.898648) (xy 102.649077 -278.868123) (xy 102.695348 -278.844547)
			(xy 102.744737 -278.828498) (xy 102.796029 -278.820374) (xy 102.821994 -278.819864) (xy 102.847629 -278.820365)
			(xy 102.898283 -278.828288) (xy 102.947104 -278.843945) (xy 102.992919 -278.866959) (xy 103.034626 -278.896777)
			(xy 103.071223 -278.932684) (xy 103.086916 -278.95296) (xy 103.496872 -278.95296) (xy 103.512559 -278.932678)
			(xy 103.549157 -278.89677) (xy 103.590865 -278.866949) (xy 103.63668 -278.843933) (xy 103.685502 -278.828274)
			(xy 103.736158 -278.820349) (xy 103.761794 -278.819864) (xy 103.787765 -278.82031) (xy 103.839068 -278.828435)
			(xy 103.888468 -278.844485) (xy 103.934749 -278.868066) (xy 103.976771 -278.898596) (xy 104.0135 -278.935324)
			(xy 104.044031 -278.977346) (xy 104.067612 -279.023627) (xy 104.083663 -279.073026) (xy 104.091789 -279.124329)
			(xy 104.091789 -279.176271) (xy 104.091787 -279.176285) (xy 104.371649 -279.176285) (xy 104.371649 -279.124351)
			(xy 104.379774 -279.073056) (xy 104.395822 -279.023663) (xy 104.4194 -278.977389) (xy 104.449926 -278.935373)
			(xy 104.486649 -278.89865) (xy 104.528665 -278.868124) (xy 104.574939 -278.844546) (xy 104.624332 -278.828498)
			(xy 104.675627 -278.820373) (xy 104.727561 -278.820373) (xy 104.778856 -278.828498) (xy 104.828249 -278.844546)
			(xy 104.874523 -278.868124) (xy 104.916539 -278.89865) (xy 104.953262 -278.935373) (xy 104.983788 -278.977389)
			(xy 105.007366 -279.023663) (xy 105.023414 -279.073056) (xy 105.031539 -279.124351) (xy 105.032048 -279.150318)
			(xy 105.031539 -279.176285) (xy 105.311703 -279.176285) (xy 105.311703 -279.124351) (xy 105.319828 -279.073056)
			(xy 105.335876 -279.023663) (xy 105.359454 -278.977389) (xy 105.38998 -278.935373) (xy 105.426703 -278.89865)
			(xy 105.468719 -278.868124) (xy 105.514993 -278.844546) (xy 105.564386 -278.828498) (xy 105.615681 -278.820373)
			(xy 105.667615 -278.820373) (xy 105.71891 -278.828498) (xy 105.768303 -278.844546) (xy 105.814577 -278.868124)
			(xy 105.856593 -278.89865) (xy 105.893316 -278.935373) (xy 105.923842 -278.977389) (xy 105.94742 -279.023663)
			(xy 105.963468 -279.073056) (xy 105.971593 -279.124351) (xy 105.972102 -279.150318) (xy 105.971593 -279.176285)
			(xy 106.251503 -279.176285) (xy 106.251503 -279.124351) (xy 106.259628 -279.073056) (xy 106.275676 -279.023663)
			(xy 106.299254 -278.977389) (xy 106.32978 -278.935373) (xy 106.366503 -278.89865) (xy 106.408519 -278.868124)
			(xy 106.454793 -278.844546) (xy 106.504186 -278.828498) (xy 106.555481 -278.820373) (xy 106.607415 -278.820373)
			(xy 106.65871 -278.828498) (xy 106.708103 -278.844546) (xy 106.754377 -278.868124) (xy 106.796393 -278.89865)
			(xy 106.833116 -278.935373) (xy 106.863642 -278.977389) (xy 106.88722 -279.023663) (xy 106.903268 -279.073056)
			(xy 106.911393 -279.124351) (xy 106.911902 -279.150318) (xy 106.911393 -279.176285) (xy 107.191049 -279.176285)
			(xy 107.191049 -279.124351) (xy 107.199174 -279.073056) (xy 107.215222 -279.023663) (xy 107.2388 -278.977389)
			(xy 107.269326 -278.935373) (xy 107.306049 -278.89865) (xy 107.348065 -278.868124) (xy 107.394339 -278.844546)
			(xy 107.443732 -278.828498) (xy 107.495027 -278.820373) (xy 107.546961 -278.820373) (xy 107.598256 -278.828498)
			(xy 107.647649 -278.844546) (xy 107.693923 -278.868124) (xy 107.735939 -278.89865) (xy 107.772662 -278.935373)
			(xy 107.803188 -278.977389) (xy 107.826766 -279.023663) (xy 107.842814 -279.073056) (xy 107.850939 -279.124351)
			(xy 107.851448 -279.150318) (xy 107.850939 -279.176285) (xy 108.130849 -279.176285) (xy 108.130849 -279.124351)
			(xy 108.138974 -279.073056) (xy 108.155022 -279.023663) (xy 108.1786 -278.977389) (xy 108.209126 -278.935373)
			(xy 108.245849 -278.89865) (xy 108.287865 -278.868124) (xy 108.334139 -278.844546) (xy 108.383532 -278.828498)
			(xy 108.434827 -278.820373) (xy 108.486761 -278.820373) (xy 108.538056 -278.828498) (xy 108.587449 -278.844546)
			(xy 108.633723 -278.868124) (xy 108.675739 -278.89865) (xy 108.712462 -278.935373) (xy 108.742988 -278.977389)
			(xy 108.766566 -279.023663) (xy 108.782614 -279.073056) (xy 108.790739 -279.124351) (xy 108.791248 -279.150318)
			(xy 108.790739 -279.176285) (xy 108.782614 -279.22758) (xy 108.766566 -279.276973) (xy 108.742988 -279.323247)
			(xy 108.712462 -279.365263) (xy 108.675739 -279.401986) (xy 108.633723 -279.432512) (xy 108.587449 -279.45609)
			(xy 108.538056 -279.472138) (xy 108.486761 -279.480263) (xy 108.434827 -279.480263) (xy 108.383532 -279.472138)
			(xy 108.334139 -279.45609) (xy 108.287865 -279.432512) (xy 108.245849 -279.401986) (xy 108.209126 -279.365263)
			(xy 108.1786 -279.323247) (xy 108.155022 -279.276973) (xy 108.138974 -279.22758) (xy 108.130849 -279.176285)
			(xy 107.850939 -279.176285) (xy 107.842814 -279.22758) (xy 107.826766 -279.276973) (xy 107.803188 -279.323247)
			(xy 107.772662 -279.365263) (xy 107.735939 -279.401986) (xy 107.693923 -279.432512) (xy 107.647649 -279.45609)
			(xy 107.598256 -279.472138) (xy 107.546961 -279.480263) (xy 107.495027 -279.480263) (xy 107.443732 -279.472138)
			(xy 107.394339 -279.45609) (xy 107.348065 -279.432512) (xy 107.306049 -279.401986) (xy 107.269326 -279.365263)
			(xy 107.2388 -279.323247) (xy 107.215222 -279.276973) (xy 107.199174 -279.22758) (xy 107.191049 -279.176285)
			(xy 106.911393 -279.176285) (xy 106.903268 -279.22758) (xy 106.88722 -279.276973) (xy 106.863642 -279.323247)
			(xy 106.833116 -279.365263) (xy 106.796393 -279.401986) (xy 106.754377 -279.432512) (xy 106.708103 -279.45609)
			(xy 106.65871 -279.472138) (xy 106.607415 -279.480263) (xy 106.555481 -279.480263) (xy 106.504186 -279.472138)
			(xy 106.454793 -279.45609) (xy 106.408519 -279.432512) (xy 106.366503 -279.401986) (xy 106.32978 -279.365263)
			(xy 106.299254 -279.323247) (xy 106.275676 -279.276973) (xy 106.259628 -279.22758) (xy 106.251503 -279.176285)
			(xy 105.971593 -279.176285) (xy 105.963468 -279.22758) (xy 105.94742 -279.276973) (xy 105.923842 -279.323247)
			(xy 105.893316 -279.365263) (xy 105.856593 -279.401986) (xy 105.814577 -279.432512) (xy 105.768303 -279.45609)
			(xy 105.71891 -279.472138) (xy 105.667615 -279.480263) (xy 105.615681 -279.480263) (xy 105.564386 -279.472138)
			(xy 105.514993 -279.45609) (xy 105.468719 -279.432512) (xy 105.426703 -279.401986) (xy 105.38998 -279.365263)
			(xy 105.359454 -279.323247) (xy 105.335876 -279.276973) (xy 105.319828 -279.22758) (xy 105.311703 -279.176285)
			(xy 105.031539 -279.176285) (xy 105.023414 -279.22758) (xy 105.007366 -279.276973) (xy 104.983788 -279.323247)
			(xy 104.953262 -279.365263) (xy 104.916539 -279.401986) (xy 104.874523 -279.432512) (xy 104.828249 -279.45609)
			(xy 104.778856 -279.472138) (xy 104.727561 -279.480263) (xy 104.675627 -279.480263) (xy 104.624332 -279.472138)
			(xy 104.574939 -279.45609) (xy 104.528665 -279.432512) (xy 104.486649 -279.401986) (xy 104.449926 -279.365263)
			(xy 104.4194 -279.323247) (xy 104.395822 -279.276973) (xy 104.379774 -279.22758) (xy 104.371649 -279.176285)
			(xy 104.091787 -279.176285) (xy 104.083663 -279.227574) (xy 104.067612 -279.276973) (xy 104.044031 -279.323254)
			(xy 104.0135 -279.365276) (xy 103.976771 -279.402004) (xy 103.934749 -279.432534) (xy 103.888468 -279.456115)
			(xy 103.839068 -279.472165) (xy 103.787765 -279.48029) (xy 103.761794 -279.480772) (xy 103.736157 -279.480305)
			(xy 103.6855 -279.472379) (xy 103.636677 -279.456717) (xy 103.590862 -279.433696) (xy 103.549157 -279.40387)
			(xy 103.512562 -279.367956) (xy 103.496872 -279.347676) (xy 103.086916 -279.347676) (xy 103.071219 -279.36795)
			(xy 103.034625 -279.403862) (xy 102.99292 -279.433685) (xy 102.947106 -279.456703) (xy 102.898285 -279.472363)
			(xy 102.84763 -279.480288) (xy 102.821994 -279.480772) (xy 102.796029 -279.480226) (xy 102.744737 -279.472102)
			(xy 102.695348 -279.456053) (xy 102.649077 -279.432477) (xy 102.607065 -279.401952) (xy 102.570344 -279.365231)
			(xy 102.53982 -279.323218) (xy 102.516244 -279.276947) (xy 102.500197 -279.227557) (xy 102.492073 -279.176266)
			(xy 102.212109 -279.176266) (xy 102.212065 -279.178353) (xy 102.202749 -279.233129) (xy 102.194106 -279.259538)
			(xy 102.186232 -279.281636) (xy 102.390194 -279.63495) (xy 102.413308 -279.639268) (xy 102.438225 -279.644457)
			(xy 102.486209 -279.661417) (xy 102.531028 -279.685531) (xy 102.571621 -279.716228) (xy 102.607031 -279.752783)
			(xy 102.63642 -279.794333) (xy 102.659095 -279.839897) (xy 102.674519 -279.888397) (xy 102.682329 -279.938687)
			(xy 102.682802 -279.964134) (xy 102.682293 -279.990101) (xy 102.961949 -279.990101) (xy 102.961949 -279.938167)
			(xy 102.970074 -279.886872) (xy 102.986122 -279.837479) (xy 103.0097 -279.791205) (xy 103.040226 -279.749189)
			(xy 103.076949 -279.712466) (xy 103.118965 -279.68194) (xy 103.165239 -279.658362) (xy 103.214632 -279.642314)
			(xy 103.265927 -279.634189) (xy 103.317861 -279.634189) (xy 103.369156 -279.642314) (xy 103.418549 -279.658362)
			(xy 103.464823 -279.68194) (xy 103.506839 -279.712466) (xy 103.543562 -279.749189) (xy 103.574088 -279.791205)
			(xy 103.597666 -279.837479) (xy 103.613714 -279.886872) (xy 103.621839 -279.938167) (xy 103.622348 -279.964134)
			(xy 103.621839 -279.990101) (xy 103.902003 -279.990101) (xy 103.902003 -279.938167) (xy 103.910128 -279.886872)
			(xy 103.926176 -279.837479) (xy 103.949754 -279.791205) (xy 103.98028 -279.749189) (xy 104.017003 -279.712466)
			(xy 104.059019 -279.68194) (xy 104.105293 -279.658362) (xy 104.154686 -279.642314) (xy 104.205981 -279.634189)
			(xy 104.257915 -279.634189) (xy 104.30921 -279.642314) (xy 104.358603 -279.658362) (xy 104.404877 -279.68194)
			(xy 104.446893 -279.712466) (xy 104.483616 -279.749189) (xy 104.514142 -279.791205) (xy 104.53772 -279.837479)
			(xy 104.553768 -279.886872) (xy 104.561893 -279.938167) (xy 104.562402 -279.964134) (xy 104.561893 -279.990101)
			(xy 104.553768 -280.041396) (xy 104.53772 -280.090789) (xy 104.514142 -280.137063) (xy 104.483616 -280.179079)
			(xy 104.446893 -280.215802) (xy 104.404877 -280.246328) (xy 104.358603 -280.269906) (xy 104.30921 -280.285954)
			(xy 104.257915 -280.294079) (xy 104.205981 -280.294079) (xy 104.154686 -280.285954) (xy 104.105293 -280.269906)
			(xy 104.059019 -280.246328) (xy 104.017003 -280.215802) (xy 103.98028 -280.179079) (xy 103.949754 -280.137063)
			(xy 103.926176 -280.090789) (xy 103.910128 -280.041396) (xy 103.902003 -279.990101) (xy 103.621839 -279.990101)
			(xy 103.613714 -280.041396) (xy 103.597666 -280.090789) (xy 103.574088 -280.137063) (xy 103.543562 -280.179079)
			(xy 103.506839 -280.215802) (xy 103.464823 -280.246328) (xy 103.418549 -280.269906) (xy 103.369156 -280.285954)
			(xy 103.317861 -280.294079) (xy 103.265927 -280.294079) (xy 103.214632 -280.285954) (xy 103.165239 -280.269906)
			(xy 103.118965 -280.246328) (xy 103.076949 -280.215802) (xy 103.040226 -280.179079) (xy 103.0097 -280.137063)
			(xy 102.986122 -280.090789) (xy 102.970074 -280.041396) (xy 102.961949 -279.990101) (xy 102.682293 -279.990101)
			(xy 102.674168 -280.041396) (xy 102.65812 -280.090789) (xy 102.634542 -280.137063) (xy 102.604016 -280.179079)
			(xy 102.567293 -280.215802) (xy 102.525277 -280.246328) (xy 102.479003 -280.269906) (xy 102.42961 -280.285954)
			(xy 102.378315 -280.294079) (xy 102.326381 -280.294079) (xy 102.275086 -280.285954) (xy 102.225693 -280.269906)
			(xy 102.179419 -280.246328) (xy 102.137403 -280.215802) (xy 102.10068 -280.179079) (xy 102.070154 -280.137063)
			(xy 102.046576 -280.090789) (xy 102.030528 -280.041396) (xy 102.022403 -279.990101) (xy 102.021894 -279.964134)
			(xy 102.022455 -279.936149) (xy 102.0319 -279.880981) (xy 102.04069 -279.854406) (xy 102.04831 -279.832308)
			(xy 101.844602 -279.479502) (xy 101.821742 -279.475184) (xy 101.796785 -279.470059) (xy 101.748722 -279.453162)
			(xy 101.703821 -279.429088) (xy 101.663148 -279.398409) (xy 101.627665 -279.36185) (xy 101.598212 -279.320279)
			(xy 101.575489 -279.27468) (xy 101.560034 -279.226134) (xy 101.552212 -279.175791) (xy 101.55174 -279.150318)
			(xy 101.273102 -279.150318) (xy 101.272593 -279.176285) (xy 101.264468 -279.22758) (xy 101.24842 -279.276973)
			(xy 101.224842 -279.323247) (xy 101.194316 -279.365263) (xy 101.157593 -279.401986) (xy 101.115577 -279.432512)
			(xy 101.069303 -279.45609) (xy 101.01991 -279.472138) (xy 100.968615 -279.480263) (xy 100.916681 -279.480263)
			(xy 100.865386 -279.472138) (xy 100.815993 -279.45609) (xy 100.769719 -279.432512) (xy 100.727703 -279.401986)
			(xy 100.69098 -279.365263) (xy 100.660454 -279.323247) (xy 100.636876 -279.276973) (xy 100.620828 -279.22758)
			(xy 100.612703 -279.176285) (xy 100.332539 -279.176285) (xy 100.324414 -279.22758) (xy 100.308366 -279.276973)
			(xy 100.284788 -279.323247) (xy 100.254262 -279.365263) (xy 100.217539 -279.401986) (xy 100.175523 -279.432512)
			(xy 100.129249 -279.45609) (xy 100.079856 -279.472138) (xy 100.028561 -279.480263) (xy 99.976627 -279.480263)
			(xy 99.925332 -279.472138) (xy 99.875939 -279.45609) (xy 99.829665 -279.432512) (xy 99.787649 -279.401986)
			(xy 99.750926 -279.365263) (xy 99.7204 -279.323247) (xy 99.696822 -279.276973) (xy 99.680774 -279.22758)
			(xy 99.672649 -279.176285) (xy 99.392739 -279.176285) (xy 99.384614 -279.22758) (xy 99.368566 -279.276973)
			(xy 99.344988 -279.323247) (xy 99.314462 -279.365263) (xy 99.277739 -279.401986) (xy 99.235723 -279.432512)
			(xy 99.189449 -279.45609) (xy 99.140056 -279.472138) (xy 99.088761 -279.480263) (xy 99.036827 -279.480263)
			(xy 98.985532 -279.472138) (xy 98.936139 -279.45609) (xy 98.889865 -279.432512) (xy 98.847849 -279.401986)
			(xy 98.811126 -279.365263) (xy 98.7806 -279.323247) (xy 98.757022 -279.276973) (xy 98.740974 -279.22758)
			(xy 98.732849 -279.176285) (xy 98.453193 -279.176285) (xy 98.445068 -279.22758) (xy 98.42902 -279.276973)
			(xy 98.405442 -279.323247) (xy 98.374916 -279.365263) (xy 98.338193 -279.401986) (xy 98.296177 -279.432512)
			(xy 98.249903 -279.45609) (xy 98.20051 -279.472138) (xy 98.149215 -279.480263) (xy 98.097281 -279.480263)
			(xy 98.045986 -279.472138) (xy 97.996593 -279.45609) (xy 97.950319 -279.432512) (xy 97.908303 -279.401986)
			(xy 97.87158 -279.365263) (xy 97.841054 -279.323247) (xy 97.817476 -279.276973) (xy 97.801428 -279.22758)
			(xy 97.793303 -279.176285) (xy 97.513139 -279.176285) (xy 97.505014 -279.22758) (xy 97.488966 -279.276973)
			(xy 97.465388 -279.323247) (xy 97.434862 -279.365263) (xy 97.398139 -279.401986) (xy 97.356123 -279.432512)
			(xy 97.309849 -279.45609) (xy 97.260456 -279.472138) (xy 97.209161 -279.480263) (xy 97.157227 -279.480263)
			(xy 97.105932 -279.472138) (xy 97.056539 -279.45609) (xy 97.010265 -279.432512) (xy 96.968249 -279.401986)
			(xy 96.931526 -279.365263) (xy 96.901 -279.323247) (xy 96.877422 -279.276973) (xy 96.861374 -279.22758)
			(xy 96.853249 -279.176285) (xy 96.573607 -279.176285) (xy 96.573607 -279.176288) (xy 96.565476 -279.227625)
			(xy 96.549414 -279.277057) (xy 96.525817 -279.323368) (xy 96.495266 -279.365417) (xy 96.458513 -279.40217)
			(xy 96.416463 -279.43272) (xy 96.370151 -279.456316) (xy 96.320719 -279.472377) (xy 96.269382 -279.480507)
			(xy 96.243394 -279.481026) (xy 96.242632 -279.481026) (xy 96.227171 -279.480823) (xy 96.196386 -279.477902)
			(xy 96.181164 -279.475184) (xy 96.169734 -279.472898) (xy 96.159066 -279.475692) (xy 96.153662 -279.477238)
			(xy 96.143665 -279.482369) (xy 96.139254 -279.485852) (xy 96.079056 -279.535636) (xy 96.070767 -279.543235)
			(xy 96.061134 -279.563525) (xy 96.060514 -279.574752) (xy 96.060514 -279.786334) (xy 96.065594 -279.808432)
			(xy 96.066102 -279.809194) (xy 96.066356 -279.809956) (xy 96.078359 -279.833863) (xy 96.095336 -279.884588)
			(xy 96.103934 -279.937384) (xy 96.103932 -279.964134) (xy 96.383094 -279.964134) (xy 96.383603 -279.938167)
			(xy 96.391728 -279.886872) (xy 96.407776 -279.837479) (xy 96.431354 -279.791205) (xy 96.46188 -279.749189)
			(xy 96.498603 -279.712466) (xy 96.540619 -279.68194) (xy 96.586893 -279.658362) (xy 96.636286 -279.642314)
			(xy 96.687581 -279.634189) (xy 96.739515 -279.634189) (xy 96.79081 -279.642314) (xy 96.840203 -279.658362)
			(xy 96.886477 -279.68194) (xy 96.928493 -279.712466) (xy 96.965216 -279.749189) (xy 96.995742 -279.791205)
			(xy 97.01932 -279.837479) (xy 97.035368 -279.886872) (xy 97.043493 -279.938167) (xy 97.044002 -279.964134)
			(xy 97.044002 -279.964388) (xy 97.043491 -279.990101) (xy 97.323403 -279.990101) (xy 97.323403 -279.938167)
			(xy 97.331528 -279.886872) (xy 97.347576 -279.837479) (xy 97.371154 -279.791205) (xy 97.40168 -279.749189)
			(xy 97.438403 -279.712466) (xy 97.480419 -279.68194) (xy 97.526693 -279.658362) (xy 97.576086 -279.642314)
			(xy 97.627381 -279.634189) (xy 97.679315 -279.634189) (xy 97.73061 -279.642314) (xy 97.780003 -279.658362)
			(xy 97.826277 -279.68194) (xy 97.868293 -279.712466) (xy 97.905016 -279.749189) (xy 97.935542 -279.791205)
			(xy 97.95912 -279.837479) (xy 97.975168 -279.886872) (xy 97.983293 -279.938167) (xy 97.983802 -279.964134)
			(xy 97.983293 -279.990101) (xy 98.263203 -279.990101) (xy 98.263203 -279.938167) (xy 98.271328 -279.886872)
			(xy 98.287376 -279.837479) (xy 98.310954 -279.791205) (xy 98.34148 -279.749189) (xy 98.378203 -279.712466)
			(xy 98.420219 -279.68194) (xy 98.466493 -279.658362) (xy 98.515886 -279.642314) (xy 98.567181 -279.634189)
			(xy 98.619115 -279.634189) (xy 98.67041 -279.642314) (xy 98.719803 -279.658362) (xy 98.766077 -279.68194)
			(xy 98.808093 -279.712466) (xy 98.844816 -279.749189) (xy 98.875342 -279.791205) (xy 98.89892 -279.837479)
			(xy 98.914968 -279.886872) (xy 98.923093 -279.938167) (xy 98.923602 -279.964134) (xy 98.923093 -279.990101)
			(xy 99.203003 -279.990101) (xy 99.203003 -279.938167) (xy 99.211128 -279.886872) (xy 99.227176 -279.837479)
			(xy 99.250754 -279.791205) (xy 99.28128 -279.749189) (xy 99.318003 -279.712466) (xy 99.360019 -279.68194)
			(xy 99.406293 -279.658362) (xy 99.455686 -279.642314) (xy 99.506981 -279.634189) (xy 99.558915 -279.634189)
			(xy 99.61021 -279.642314) (xy 99.659603 -279.658362) (xy 99.705877 -279.68194) (xy 99.747893 -279.712466)
			(xy 99.784616 -279.749189) (xy 99.815142 -279.791205) (xy 99.83872 -279.837479) (xy 99.854768 -279.886872)
			(xy 99.862893 -279.938167) (xy 99.863402 -279.964134) (xy 99.862893 -279.990101) (xy 100.142803 -279.990101)
			(xy 100.142803 -279.938167) (xy 100.150928 -279.886872) (xy 100.166976 -279.837479) (xy 100.190554 -279.791205)
			(xy 100.22108 -279.749189) (xy 100.257803 -279.712466) (xy 100.299819 -279.68194) (xy 100.346093 -279.658362)
			(xy 100.395486 -279.642314) (xy 100.446781 -279.634189) (xy 100.498715 -279.634189) (xy 100.55001 -279.642314)
			(xy 100.599403 -279.658362) (xy 100.645677 -279.68194) (xy 100.687693 -279.712466) (xy 100.724416 -279.749189)
			(xy 100.754942 -279.791205) (xy 100.77852 -279.837479) (xy 100.794568 -279.886872) (xy 100.802693 -279.938167)
			(xy 100.803202 -279.964134) (xy 100.802693 -279.990101) (xy 101.082603 -279.990101) (xy 101.082603 -279.938167)
			(xy 101.090728 -279.886872) (xy 101.106776 -279.837479) (xy 101.130354 -279.791205) (xy 101.16088 -279.749189)
			(xy 101.197603 -279.712466) (xy 101.239619 -279.68194) (xy 101.285893 -279.658362) (xy 101.335286 -279.642314)
			(xy 101.386581 -279.634189) (xy 101.438515 -279.634189) (xy 101.48981 -279.642314) (xy 101.539203 -279.658362)
			(xy 101.585477 -279.68194) (xy 101.627493 -279.712466) (xy 101.664216 -279.749189) (xy 101.694742 -279.791205)
			(xy 101.71832 -279.837479) (xy 101.734368 -279.886872) (xy 101.742493 -279.938167) (xy 101.743002 -279.964134)
			(xy 101.742493 -279.990101) (xy 101.734368 -280.041396) (xy 101.71832 -280.090789) (xy 101.694742 -280.137063)
			(xy 101.664216 -280.179079) (xy 101.627493 -280.215802) (xy 101.585477 -280.246328) (xy 101.539203 -280.269906)
			(xy 101.48981 -280.285954) (xy 101.438515 -280.294079) (xy 101.386581 -280.294079) (xy 101.335286 -280.285954)
			(xy 101.285893 -280.269906) (xy 101.239619 -280.246328) (xy 101.197603 -280.215802) (xy 101.16088 -280.179079)
			(xy 101.130354 -280.137063) (xy 101.106776 -280.090789) (xy 101.090728 -280.041396) (xy 101.082603 -279.990101)
			(xy 100.802693 -279.990101) (xy 100.794568 -280.041396) (xy 100.77852 -280.090789) (xy 100.754942 -280.137063)
			(xy 100.724416 -280.179079) (xy 100.687693 -280.215802) (xy 100.645677 -280.246328) (xy 100.599403 -280.269906)
			(xy 100.55001 -280.285954) (xy 100.498715 -280.294079) (xy 100.446781 -280.294079) (xy 100.395486 -280.285954)
			(xy 100.346093 -280.269906) (xy 100.299819 -280.246328) (xy 100.257803 -280.215802) (xy 100.22108 -280.179079)
			(xy 100.190554 -280.137063) (xy 100.166976 -280.090789) (xy 100.150928 -280.041396) (xy 100.142803 -279.990101)
			(xy 99.862893 -279.990101) (xy 99.854768 -280.041396) (xy 99.83872 -280.090789) (xy 99.815142 -280.137063)
			(xy 99.784616 -280.179079) (xy 99.747893 -280.215802) (xy 99.705877 -280.246328) (xy 99.659603 -280.269906)
			(xy 99.61021 -280.285954) (xy 99.558915 -280.294079) (xy 99.506981 -280.294079) (xy 99.455686 -280.285954)
			(xy 99.406293 -280.269906) (xy 99.360019 -280.246328) (xy 99.318003 -280.215802) (xy 99.28128 -280.179079)
			(xy 99.250754 -280.137063) (xy 99.227176 -280.090789) (xy 99.211128 -280.041396) (xy 99.203003 -279.990101)
			(xy 98.923093 -279.990101) (xy 98.914968 -280.041396) (xy 98.89892 -280.090789) (xy 98.875342 -280.137063)
			(xy 98.844816 -280.179079) (xy 98.808093 -280.215802) (xy 98.766077 -280.246328) (xy 98.719803 -280.269906)
			(xy 98.67041 -280.285954) (xy 98.619115 -280.294079) (xy 98.567181 -280.294079) (xy 98.515886 -280.285954)
			(xy 98.466493 -280.269906) (xy 98.420219 -280.246328) (xy 98.378203 -280.215802) (xy 98.34148 -280.179079)
			(xy 98.310954 -280.137063) (xy 98.287376 -280.090789) (xy 98.271328 -280.041396) (xy 98.263203 -279.990101)
			(xy 97.983293 -279.990101) (xy 97.975168 -280.041396) (xy 97.95912 -280.090789) (xy 97.935542 -280.137063)
			(xy 97.905016 -280.179079) (xy 97.868293 -280.215802) (xy 97.826277 -280.246328) (xy 97.780003 -280.269906)
			(xy 97.73061 -280.285954) (xy 97.679315 -280.294079) (xy 97.627381 -280.294079) (xy 97.576086 -280.285954)
			(xy 97.526693 -280.269906) (xy 97.480419 -280.246328) (xy 97.438403 -280.215802) (xy 97.40168 -280.179079)
			(xy 97.371154 -280.137063) (xy 97.347576 -280.090789) (xy 97.331528 -280.041396) (xy 97.323403 -279.990101)
			(xy 97.043491 -279.990101) (xy 97.043446 -279.992374) (xy 97.033998 -280.047542) (xy 97.025206 -280.074116)
			(xy 97.017332 -280.096214) (xy 97.22104 -280.44902) (xy 97.244154 -280.453338) (xy 97.269072 -280.458522)
			(xy 97.317054 -280.475487) (xy 97.36187 -280.499603) (xy 97.402461 -280.530302) (xy 97.437869 -280.566858)
			(xy 97.467258 -280.608407) (xy 97.489934 -280.65397) (xy 97.50536 -280.702468) (xy 97.513173 -280.752758)
			(xy 97.513648 -280.778204) (xy 97.513139 -280.804171) (xy 97.505014 -280.855466) (xy 97.488966 -280.904859)
			(xy 97.465388 -280.951133) (xy 97.434862 -280.993149) (xy 97.398139 -281.029872) (xy 97.356123 -281.060398)
			(xy 97.309849 -281.083976) (xy 97.260456 -281.100024) (xy 97.209161 -281.108149) (xy 97.157227 -281.108149)
			(xy 97.105932 -281.100024) (xy 97.056539 -281.083976) (xy 97.010265 -281.060398) (xy 96.968249 -281.029872)
			(xy 96.931526 -280.993149) (xy 96.901 -280.951133) (xy 96.877422 -280.904859) (xy 96.861374 -280.855466)
			(xy 96.853249 -280.804171) (xy 96.85274 -280.778204) (xy 96.853292 -280.750218) (xy 96.862742 -280.69505)
			(xy 96.871536 -280.668476) (xy 96.879156 -280.646378) (xy 96.675448 -280.293318) (xy 96.652334 -280.289)
			(xy 96.627429 -280.283804) (xy 96.579472 -280.266825) (xy 96.534684 -280.242698) (xy 96.494122 -280.211993)
			(xy 96.458743 -280.175435) (xy 96.429385 -280.133888) (xy 96.406739 -280.088332) (xy 96.391342 -280.039845)
			(xy 96.383557 -279.989571) (xy 96.383094 -279.964134) (xy 96.103932 -279.964134) (xy 96.10393 -279.990876)
			(xy 96.095322 -280.04367) (xy 96.078335 -280.094393) (xy 96.066356 -280.118312) (xy 96.066102 -280.119074)
			(xy 96.063308 -280.124662) (xy 96.060514 -280.135584) (xy 96.060514 -280.35377) (xy 96.061094 -280.365011)
			(xy 96.070718 -280.385326) (xy 96.079056 -280.392886) (xy 96.139254 -280.44267) (xy 96.143673 -280.446139)
			(xy 96.153673 -280.451255) (xy 96.159066 -280.45283) (xy 96.169734 -280.455624) (xy 96.181164 -280.453338)
			(xy 96.196635 -280.450567) (xy 96.227931 -280.447639) (xy 96.243648 -280.447496) (xy 96.269632 -280.448009)
			(xy 96.32096 -280.456146) (xy 96.370384 -280.472211) (xy 96.416686 -280.495809) (xy 96.458727 -280.526359)
			(xy 96.495472 -280.563109) (xy 96.526016 -280.605155) (xy 96.549608 -280.65146) (xy 96.565666 -280.700886)
			(xy 96.573795 -280.752216) (xy 96.573795 -280.804184) (xy 96.565666 -280.855514) (xy 96.549608 -280.90494)
			(xy 96.526016 -280.951245) (xy 96.495472 -280.993291) (xy 96.458727 -281.030041) (xy 96.416686 -281.060591)
			(xy 96.370384 -281.084189) (xy 96.32096 -281.100254) (xy 96.269632 -281.108391) (xy 96.243648 -281.108912)
			(xy 96.227932 -281.10875) (xy 96.196637 -281.105827) (xy 96.181164 -281.10307) (xy 96.169734 -281.100784)
			(xy 96.159066 -281.103578) (xy 96.153662 -281.105124) (xy 96.143664 -281.110253) (xy 96.139254 -281.113738)
			(xy 96.079056 -281.163522) (xy 96.070765 -281.17112) (xy 96.061126 -281.19141) (xy 96.060514 -281.202638)
			(xy 96.060514 -281.41422) (xy 96.065594 -281.436318) (xy 96.066102 -281.43708) (xy 96.066356 -281.437842)
			(xy 96.07836 -281.461749) (xy 96.09534 -281.512475) (xy 96.10394 -281.565271) (xy 96.103937 -281.617987)
			(xy 96.383603 -281.617987) (xy 96.383603 -281.566053) (xy 96.391728 -281.514758) (xy 96.407776 -281.465365)
			(xy 96.431354 -281.419091) (xy 96.46188 -281.377075) (xy 96.498603 -281.340352) (xy 96.540619 -281.309826)
			(xy 96.586893 -281.286248) (xy 96.636286 -281.2702) (xy 96.687581 -281.262075) (xy 96.739515 -281.262075)
			(xy 96.79081 -281.2702) (xy 96.840203 -281.286248) (xy 96.886477 -281.309826) (xy 96.928493 -281.340352)
			(xy 96.965216 -281.377075) (xy 96.995742 -281.419091) (xy 97.01932 -281.465365) (xy 97.035368 -281.514758)
			(xy 97.043493 -281.566053) (xy 97.044002 -281.59202) (xy 97.322894 -281.59202) (xy 97.323351 -281.566569)
			(xy 97.331139 -281.516266) (xy 97.34655 -281.467753) (xy 97.369218 -281.422177) (xy 97.398609 -281.380617)
			(xy 97.434025 -281.344056) (xy 97.474629 -281.313359) (xy 97.519461 -281.289253) (xy 97.56746 -281.272307)
			(xy 97.592388 -281.267154) (xy 97.615502 -281.262836) (xy 97.81921 -280.91003) (xy 97.811336 -280.887932)
			(xy 97.802607 -280.861341) (xy 97.793154 -280.806184) (xy 97.79254 -280.778204) (xy 97.793049 -280.752237)
			(xy 97.801174 -280.700942) (xy 97.817222 -280.651549) (xy 97.8408 -280.605275) (xy 97.871326 -280.563259)
			(xy 97.908049 -280.526536) (xy 97.950065 -280.49601) (xy 97.996339 -280.472432) (xy 98.045732 -280.456384)
			(xy 98.097027 -280.448259) (xy 98.148961 -280.448259) (xy 98.200256 -280.456384) (xy 98.249649 -280.472432)
			(xy 98.295923 -280.49601) (xy 98.337939 -280.526536) (xy 98.374662 -280.563259) (xy 98.405188 -280.605275)
			(xy 98.428766 -280.651549) (xy 98.444814 -280.700942) (xy 98.452939 -280.752237) (xy 98.453448 -280.778204)
			(xy 98.452969 -280.803655) (xy 98.452889 -280.804171) (xy 98.732849 -280.804171) (xy 98.732849 -280.752237)
			(xy 98.740974 -280.700942) (xy 98.757022 -280.651549) (xy 98.7806 -280.605275) (xy 98.811126 -280.563259)
			(xy 98.847849 -280.526536) (xy 98.889865 -280.49601) (xy 98.936139 -280.472432) (xy 98.985532 -280.456384)
			(xy 99.036827 -280.448259) (xy 99.088761 -280.448259) (xy 99.140056 -280.456384) (xy 99.189449 -280.472432)
			(xy 99.235723 -280.49601) (xy 99.277739 -280.526536) (xy 99.314462 -280.563259) (xy 99.344988 -280.605275)
			(xy 99.368566 -280.651549) (xy 99.384614 -280.700942) (xy 99.392739 -280.752237) (xy 99.393248 -280.778204)
			(xy 99.392739 -280.804171) (xy 99.672649 -280.804171) (xy 99.672649 -280.752237) (xy 99.680774 -280.700942)
			(xy 99.696822 -280.651549) (xy 99.7204 -280.605275) (xy 99.750926 -280.563259) (xy 99.787649 -280.526536)
			(xy 99.829665 -280.49601) (xy 99.875939 -280.472432) (xy 99.925332 -280.456384) (xy 99.976627 -280.448259)
			(xy 100.028561 -280.448259) (xy 100.079856 -280.456384) (xy 100.129249 -280.472432) (xy 100.175523 -280.49601)
			(xy 100.217539 -280.526536) (xy 100.254262 -280.563259) (xy 100.284788 -280.605275) (xy 100.308366 -280.651549)
			(xy 100.324414 -280.700942) (xy 100.332539 -280.752237) (xy 100.333048 -280.778204) (xy 100.61194 -280.778204)
			(xy 100.612449 -280.752237) (xy 100.620574 -280.700942) (xy 100.636622 -280.651549) (xy 100.6602 -280.605275)
			(xy 100.690726 -280.563259) (xy 100.727449 -280.526536) (xy 100.769465 -280.49601) (xy 100.815739 -280.472432)
			(xy 100.865132 -280.456384) (xy 100.916427 -280.448259) (xy 100.968361 -280.448259) (xy 101.019656 -280.456384)
			(xy 101.069049 -280.472432) (xy 101.115323 -280.49601) (xy 101.157339 -280.526536) (xy 101.194062 -280.563259)
			(xy 101.224588 -280.605275) (xy 101.248166 -280.651549) (xy 101.264214 -280.700942) (xy 101.272339 -280.752237)
			(xy 101.272848 -280.778204) (xy 101.272848 -280.778458) (xy 101.272306 -280.804171) (xy 101.552249 -280.804171)
			(xy 101.552249 -280.752237) (xy 101.560374 -280.700942) (xy 101.576422 -280.651549) (xy 101.6 -280.605275)
			(xy 101.630526 -280.563259) (xy 101.667249 -280.526536) (xy 101.709265 -280.49601) (xy 101.755539 -280.472432)
			(xy 101.804932 -280.456384) (xy 101.856227 -280.448259) (xy 101.908161 -280.448259) (xy 101.959456 -280.456384)
			(xy 102.008849 -280.472432) (xy 102.055123 -280.49601) (xy 102.097139 -280.526536) (xy 102.133862 -280.563259)
			(xy 102.164388 -280.605275) (xy 102.187966 -280.651549) (xy 102.204014 -280.700942) (xy 102.212139 -280.752237)
			(xy 102.212648 -280.778204) (xy 102.212139 -280.804171) (xy 102.492303 -280.804171) (xy 102.492303 -280.752237)
			(xy 102.500428 -280.700942) (xy 102.516476 -280.651549) (xy 102.540054 -280.605275) (xy 102.57058 -280.563259)
			(xy 102.607303 -280.526536) (xy 102.649319 -280.49601) (xy 102.695593 -280.472432) (xy 102.744986 -280.456384)
			(xy 102.796281 -280.448259) (xy 102.848215 -280.448259) (xy 102.89951 -280.456384) (xy 102.948903 -280.472432)
			(xy 102.995177 -280.49601) (xy 103.037193 -280.526536) (xy 103.073916 -280.563259) (xy 103.104442 -280.605275)
			(xy 103.12802 -280.651549) (xy 103.144068 -280.700942) (xy 103.152193 -280.752237) (xy 103.152702 -280.778204)
			(xy 103.43134 -280.778204) (xy 103.431849 -280.752237) (xy 103.439974 -280.700942) (xy 103.456022 -280.651549)
			(xy 103.4796 -280.605275) (xy 103.510126 -280.563259) (xy 103.546849 -280.526536) (xy 103.588865 -280.49601)
			(xy 103.635139 -280.472432) (xy 103.684532 -280.456384) (xy 103.735827 -280.448259) (xy 103.787761 -280.448259)
			(xy 103.839056 -280.456384) (xy 103.888449 -280.472432) (xy 103.934723 -280.49601) (xy 103.976739 -280.526536)
			(xy 104.013462 -280.563259) (xy 104.043988 -280.605275) (xy 104.067566 -280.651549) (xy 104.083614 -280.700942)
			(xy 104.091739 -280.752237) (xy 104.092248 -280.778204) (xy 104.37114 -280.778204) (xy 104.371636 -280.752753)
			(xy 104.379413 -280.70245) (xy 104.394815 -280.653936) (xy 104.417477 -280.608358) (xy 104.446862 -280.566796)
			(xy 104.482275 -280.530234) (xy 104.522877 -280.499537) (xy 104.567708 -280.475432) (xy 104.615706 -280.458489)
			(xy 104.640634 -280.453338) (xy 104.663748 -280.44902) (xy 104.86771 -280.095706) (xy 104.859836 -280.073608)
			(xy 104.851225 -280.047256) (xy 104.841904 -279.992612) (xy 104.841294 -279.964896) (xy 104.841294 -279.964134)
			(xy 104.841803 -279.938167) (xy 104.849928 -279.886872) (xy 104.865976 -279.837479) (xy 104.889554 -279.791205)
			(xy 104.92008 -279.749189) (xy 104.956803 -279.712466) (xy 104.998819 -279.68194) (xy 105.045093 -279.658362)
			(xy 105.094486 -279.642314) (xy 105.145781 -279.634189) (xy 105.197715 -279.634189) (xy 105.24901 -279.642314)
			(xy 105.298403 -279.658362) (xy 105.344677 -279.68194) (xy 105.386693 -279.712466) (xy 105.423416 -279.749189)
			(xy 105.453942 -279.791205) (xy 105.47752 -279.837479) (xy 105.493568 -279.886872) (xy 105.501693 -279.938167)
			(xy 105.502202 -279.964134) (xy 105.50175 -279.989597) (xy 105.501672 -279.990101) (xy 105.781603 -279.990101)
			(xy 105.781603 -279.938167) (xy 105.789728 -279.886872) (xy 105.805776 -279.837479) (xy 105.829354 -279.791205)
			(xy 105.85988 -279.749189) (xy 105.896603 -279.712466) (xy 105.938619 -279.68194) (xy 105.984893 -279.658362)
			(xy 106.034286 -279.642314) (xy 106.085581 -279.634189) (xy 106.137515 -279.634189) (xy 106.18881 -279.642314)
			(xy 106.238203 -279.658362) (xy 106.284477 -279.68194) (xy 106.326493 -279.712466) (xy 106.363216 -279.749189)
			(xy 106.393742 -279.791205) (xy 106.41732 -279.837479) (xy 106.433368 -279.886872) (xy 106.441493 -279.938167)
			(xy 106.442002 -279.964134) (xy 106.441493 -279.990101) (xy 106.721403 -279.990101) (xy 106.721403 -279.938167)
			(xy 106.729528 -279.886872) (xy 106.745576 -279.837479) (xy 106.769154 -279.791205) (xy 106.79968 -279.749189)
			(xy 106.836403 -279.712466) (xy 106.878419 -279.68194) (xy 106.924693 -279.658362) (xy 106.974086 -279.642314)
			(xy 107.025381 -279.634189) (xy 107.077315 -279.634189) (xy 107.12861 -279.642314) (xy 107.178003 -279.658362)
			(xy 107.224277 -279.68194) (xy 107.266293 -279.712466) (xy 107.303016 -279.749189) (xy 107.333542 -279.791205)
			(xy 107.35712 -279.837479) (xy 107.373168 -279.886872) (xy 107.381293 -279.938167) (xy 107.381802 -279.964134)
			(xy 107.381293 -279.990101) (xy 107.660949 -279.990101) (xy 107.660949 -279.938167) (xy 107.669074 -279.886872)
			(xy 107.685122 -279.837479) (xy 107.7087 -279.791205) (xy 107.739226 -279.749189) (xy 107.775949 -279.712466)
			(xy 107.817965 -279.68194) (xy 107.864239 -279.658362) (xy 107.913632 -279.642314) (xy 107.964927 -279.634189)
			(xy 108.016861 -279.634189) (xy 108.068156 -279.642314) (xy 108.117549 -279.658362) (xy 108.163823 -279.68194)
			(xy 108.205839 -279.712466) (xy 108.242562 -279.749189) (xy 108.273088 -279.791205) (xy 108.296666 -279.837479)
			(xy 108.312714 -279.886872) (xy 108.320839 -279.938167) (xy 108.321348 -279.964134) (xy 108.320839 -279.990101)
			(xy 113.299749 -279.990101) (xy 113.299749 -279.938167) (xy 113.307874 -279.886872) (xy 113.323922 -279.837479)
			(xy 113.3475 -279.791205) (xy 113.378026 -279.749189) (xy 113.414749 -279.712466) (xy 113.456765 -279.68194)
			(xy 113.503039 -279.658362) (xy 113.552432 -279.642314) (xy 113.603727 -279.634189) (xy 113.655661 -279.634189)
			(xy 113.706956 -279.642314) (xy 113.756349 -279.658362) (xy 113.802623 -279.68194) (xy 113.844639 -279.712466)
			(xy 113.881362 -279.749189) (xy 113.911888 -279.791205) (xy 113.935466 -279.837479) (xy 113.951514 -279.886872)
			(xy 113.959639 -279.938167) (xy 113.960148 -279.964134) (xy 113.959639 -279.990101) (xy 113.951514 -280.041396)
			(xy 113.935466 -280.090789) (xy 113.911888 -280.137063) (xy 113.881362 -280.179079) (xy 113.844639 -280.215802)
			(xy 113.802623 -280.246328) (xy 113.756349 -280.269906) (xy 113.706956 -280.285954) (xy 113.655661 -280.294079)
			(xy 113.603727 -280.294079) (xy 113.552432 -280.285954) (xy 113.503039 -280.269906) (xy 113.456765 -280.246328)
			(xy 113.414749 -280.215802) (xy 113.378026 -280.179079) (xy 113.3475 -280.137063) (xy 113.323922 -280.090789)
			(xy 113.307874 -280.041396) (xy 113.299749 -279.990101) (xy 108.320839 -279.990101) (xy 108.312714 -280.041396)
			(xy 108.296666 -280.090789) (xy 108.273088 -280.137063) (xy 108.242562 -280.179079) (xy 108.205839 -280.215802)
			(xy 108.163823 -280.246328) (xy 108.117549 -280.269906) (xy 108.068156 -280.285954) (xy 108.016861 -280.294079)
			(xy 107.964927 -280.294079) (xy 107.913632 -280.285954) (xy 107.864239 -280.269906) (xy 107.817965 -280.246328)
			(xy 107.775949 -280.215802) (xy 107.739226 -280.179079) (xy 107.7087 -280.137063) (xy 107.685122 -280.090789)
			(xy 107.669074 -280.041396) (xy 107.660949 -279.990101) (xy 107.381293 -279.990101) (xy 107.373168 -280.041396)
			(xy 107.35712 -280.090789) (xy 107.333542 -280.137063) (xy 107.303016 -280.179079) (xy 107.266293 -280.215802)
			(xy 107.224277 -280.246328) (xy 107.178003 -280.269906) (xy 107.12861 -280.285954) (xy 107.077315 -280.294079)
			(xy 107.025381 -280.294079) (xy 106.974086 -280.285954) (xy 106.924693 -280.269906) (xy 106.878419 -280.246328)
			(xy 106.836403 -280.215802) (xy 106.79968 -280.179079) (xy 106.769154 -280.137063) (xy 106.745576 -280.090789)
			(xy 106.729528 -280.041396) (xy 106.721403 -279.990101) (xy 106.441493 -279.990101) (xy 106.433368 -280.041396)
			(xy 106.41732 -280.090789) (xy 106.393742 -280.137063) (xy 106.363216 -280.179079) (xy 106.326493 -280.215802)
			(xy 106.284477 -280.246328) (xy 106.238203 -280.269906) (xy 106.18881 -280.285954) (xy 106.137515 -280.294079)
			(xy 106.085581 -280.294079) (xy 106.034286 -280.285954) (xy 105.984893 -280.269906) (xy 105.938619 -280.246328)
			(xy 105.896603 -280.215802) (xy 105.85988 -280.179079) (xy 105.829354 -280.137063) (xy 105.805776 -280.090789)
			(xy 105.789728 -280.041396) (xy 105.781603 -279.990101) (xy 105.501672 -279.990101) (xy 105.493946 -280.039922)
			(xy 105.478513 -280.088453) (xy 105.455817 -280.134042) (xy 105.426394 -280.175609) (xy 105.390942 -280.212169)
			(xy 105.350301 -280.242856) (xy 105.305432 -280.266945) (xy 105.257398 -280.283864) (xy 105.232454 -280.289)
			(xy 105.20934 -280.293318) (xy 105.005632 -280.646378) (xy 105.013252 -280.668476) (xy 105.021982 -280.695066)
			(xy 105.031435 -280.750224) (xy 105.032048 -280.778204) (xy 105.031539 -280.804167) (xy 105.311459 -280.804167)
			(xy 105.311459 -280.752233) (xy 105.319583 -280.70094) (xy 105.335631 -280.651548) (xy 105.359208 -280.605275)
			(xy 105.389734 -280.56326) (xy 105.426456 -280.526537) (xy 105.46847 -280.496011) (xy 105.514743 -280.472434)
			(xy 105.564134 -280.456385) (xy 105.615427 -280.44826) (xy 105.641394 -280.44775) (xy 105.667017 -280.448197)
			(xy 105.717646 -280.456128) (xy 105.766447 -280.471768) (xy 105.812253 -280.494746) (xy 105.853969 -280.52451)
			(xy 105.890598 -280.56035) (xy 105.906316 -280.580592) (xy 106.316272 -280.580592) (xy 106.331966 -280.56033)
			(xy 106.368589 -280.52448) (xy 106.410307 -280.494713) (xy 106.456121 -280.471744) (xy 106.504932 -280.456123)
			(xy 106.555569 -280.448225) (xy 106.581194 -280.44775) (xy 106.607164 -280.448224) (xy 106.658464 -280.456349)
			(xy 106.707862 -280.472398) (xy 106.754141 -280.495978) (xy 106.796162 -280.526507) (xy 106.832889 -280.563234)
			(xy 106.863419 -280.605254) (xy 106.886999 -280.651532) (xy 106.90305 -280.70093) (xy 106.911175 -280.75223)
			(xy 106.911175 -280.80417) (xy 106.911175 -280.804171) (xy 107.191049 -280.804171) (xy 107.191049 -280.752237)
			(xy 107.199174 -280.700942) (xy 107.215222 -280.651549) (xy 107.2388 -280.605275) (xy 107.269326 -280.563259)
			(xy 107.306049 -280.526536) (xy 107.348065 -280.49601) (xy 107.394339 -280.472432) (xy 107.443732 -280.456384)
			(xy 107.495027 -280.448259) (xy 107.546961 -280.448259) (xy 107.598256 -280.456384) (xy 107.647649 -280.472432)
			(xy 107.693923 -280.49601) (xy 107.735939 -280.526536) (xy 107.772662 -280.563259) (xy 107.803188 -280.605275)
			(xy 107.826766 -280.651549) (xy 107.842814 -280.700942) (xy 107.850939 -280.752237) (xy 107.851448 -280.778204)
			(xy 107.850939 -280.804171) (xy 110.010449 -280.804171) (xy 110.010449 -280.752237) (xy 110.018574 -280.700942)
			(xy 110.034622 -280.651549) (xy 110.0582 -280.605275) (xy 110.088726 -280.563259) (xy 110.125449 -280.526536)
			(xy 110.167465 -280.49601) (xy 110.213739 -280.472432) (xy 110.263132 -280.456384) (xy 110.314427 -280.448259)
			(xy 110.366361 -280.448259) (xy 110.417656 -280.456384) (xy 110.467049 -280.472432) (xy 110.513323 -280.49601)
			(xy 110.555339 -280.526536) (xy 110.592062 -280.563259) (xy 110.622588 -280.605275) (xy 110.646166 -280.651549)
			(xy 110.662214 -280.700942) (xy 110.670339 -280.752237) (xy 110.670848 -280.778204) (xy 110.670339 -280.804171)
			(xy 110.662214 -280.855466) (xy 110.646166 -280.904859) (xy 110.622588 -280.951133) (xy 110.592062 -280.993149)
			(xy 110.555339 -281.029872) (xy 110.513323 -281.060398) (xy 110.467049 -281.083976) (xy 110.417656 -281.100024)
			(xy 110.366361 -281.108149) (xy 110.314427 -281.108149) (xy 110.263132 -281.100024) (xy 110.213739 -281.083976)
			(xy 110.167465 -281.060398) (xy 110.125449 -281.029872) (xy 110.088726 -280.993149) (xy 110.0582 -280.951133)
			(xy 110.034622 -280.904859) (xy 110.018574 -280.855466) (xy 110.010449 -280.804171) (xy 107.850939 -280.804171)
			(xy 107.842814 -280.855466) (xy 107.826766 -280.904859) (xy 107.803188 -280.951133) (xy 107.772662 -280.993149)
			(xy 107.735939 -281.029872) (xy 107.693923 -281.060398) (xy 107.647649 -281.083976) (xy 107.598256 -281.100024)
			(xy 107.546961 -281.108149) (xy 107.495027 -281.108149) (xy 107.443732 -281.100024) (xy 107.394339 -281.083976)
			(xy 107.348065 -281.060398) (xy 107.306049 -281.029872) (xy 107.269326 -280.993149) (xy 107.2388 -280.951133)
			(xy 107.215222 -280.904859) (xy 107.199174 -280.855466) (xy 107.191049 -280.804171) (xy 106.911175 -280.804171)
			(xy 106.90305 -280.85547) (xy 106.886999 -280.904868) (xy 106.863419 -280.951146) (xy 106.832889 -280.993166)
			(xy 106.796162 -281.029893) (xy 106.754141 -281.060422) (xy 106.707862 -281.084002) (xy 106.658464 -281.100051)
			(xy 106.607164 -281.108176) (xy 106.581194 -281.108658) (xy 106.555574 -281.108144) (xy 106.504948 -281.100227)
			(xy 106.456148 -281.0846) (xy 106.410342 -281.061635) (xy 106.368624 -281.031882) (xy 106.331992 -280.996053)
			(xy 106.316272 -280.975816) (xy 105.906316 -280.975816) (xy 105.890573 -280.996038) (xy 105.85396 -281.03189)
			(xy 105.812252 -281.061661) (xy 105.766447 -281.084637) (xy 105.717645 -281.100267) (xy 105.667016 -281.108176)
			(xy 105.641394 -281.108658) (xy 105.615427 -281.10814) (xy 105.564134 -281.100015) (xy 105.514743 -281.083966)
			(xy 105.46847 -281.060389) (xy 105.426456 -281.029863) (xy 105.389734 -280.99314) (xy 105.359208 -280.951125)
			(xy 105.335631 -280.904852) (xy 105.319583 -280.85546) (xy 105.311459 -280.804167) (xy 105.031539 -280.804167)
			(xy 105.031539 -280.804171) (xy 105.023414 -280.855466) (xy 105.007366 -280.904859) (xy 104.983788 -280.951133)
			(xy 104.953262 -280.993149) (xy 104.916539 -281.029872) (xy 104.874523 -281.060398) (xy 104.828249 -281.083976)
			(xy 104.778856 -281.100024) (xy 104.727561 -281.108149) (xy 104.675627 -281.108149) (xy 104.624332 -281.100024)
			(xy 104.574939 -281.083976) (xy 104.528665 -281.060398) (xy 104.486649 -281.029872) (xy 104.449926 -280.993149)
			(xy 104.4194 -280.951133) (xy 104.395822 -280.904859) (xy 104.379774 -280.855466) (xy 104.371649 -280.804171)
			(xy 104.37114 -280.778204) (xy 104.092248 -280.778204) (xy 104.092248 -280.778458) (xy 104.091662 -280.806239)
			(xy 104.082348 -280.861015) (xy 104.073706 -280.887424) (xy 104.065832 -280.909522) (xy 104.269794 -281.262836)
			(xy 104.292908 -281.267154) (xy 104.317822 -281.272356) (xy 104.365805 -281.289316) (xy 104.410623 -281.313428)
			(xy 104.451216 -281.344123) (xy 104.486626 -281.380677) (xy 104.516015 -281.422225) (xy 104.538691 -281.467787)
			(xy 104.554116 -281.516285) (xy 104.561928 -281.566574) (xy 104.562402 -281.59202) (xy 104.561893 -281.617987)
			(xy 104.841803 -281.617987) (xy 104.841803 -281.566053) (xy 104.849928 -281.514758) (xy 104.865976 -281.465365)
			(xy 104.889554 -281.419091) (xy 104.92008 -281.377075) (xy 104.956803 -281.340352) (xy 104.998819 -281.309826)
			(xy 105.045093 -281.286248) (xy 105.094486 -281.2702) (xy 105.145781 -281.262075) (xy 105.197715 -281.262075)
			(xy 105.24901 -281.2702) (xy 105.298403 -281.286248) (xy 105.344677 -281.309826) (xy 105.386693 -281.340352)
			(xy 105.423416 -281.377075) (xy 105.453942 -281.419091) (xy 105.47752 -281.465365) (xy 105.493568 -281.514758)
			(xy 105.501693 -281.566053) (xy 105.502202 -281.59202) (xy 105.781094 -281.59202) (xy 105.781603 -281.566053)
			(xy 105.789728 -281.514758) (xy 105.805776 -281.465365) (xy 105.829354 -281.419091) (xy 105.85988 -281.377075)
			(xy 105.896603 -281.340352) (xy 105.938619 -281.309826) (xy 105.984893 -281.286248) (xy 106.034286 -281.2702)
			(xy 106.085581 -281.262075) (xy 106.137515 -281.262075) (xy 106.18881 -281.2702) (xy 106.238203 -281.286248)
			(xy 106.284477 -281.309826) (xy 106.326493 -281.340352) (xy 106.363216 -281.377075) (xy 106.393742 -281.419091)
			(xy 106.41732 -281.465365) (xy 106.433368 -281.514758) (xy 106.441493 -281.566053) (xy 106.442002 -281.59202)
			(xy 106.441494 -281.617987) (xy 106.721403 -281.617987) (xy 106.721403 -281.566053) (xy 106.729528 -281.514758)
			(xy 106.745576 -281.465365) (xy 106.769154 -281.419091) (xy 106.79968 -281.377075) (xy 106.836403 -281.340352)
			(xy 106.878419 -281.309826) (xy 106.924693 -281.286248) (xy 106.974086 -281.2702) (xy 107.025381 -281.262075)
			(xy 107.077315 -281.262075) (xy 107.12861 -281.2702) (xy 107.178003 -281.286248) (xy 107.224277 -281.309826)
			(xy 107.266293 -281.340352) (xy 107.303016 -281.377075) (xy 107.333542 -281.419091) (xy 107.35712 -281.465365)
			(xy 107.373168 -281.514758) (xy 107.381293 -281.566053) (xy 107.381802 -281.59202) (xy 107.381293 -281.617987)
			(xy 113.299749 -281.617987) (xy 113.299749 -281.566053) (xy 113.307874 -281.514758) (xy 113.323922 -281.465365)
			(xy 113.3475 -281.419091) (xy 113.378026 -281.377075) (xy 113.414749 -281.340352) (xy 113.456765 -281.309826)
			(xy 113.503039 -281.286248) (xy 113.552432 -281.2702) (xy 113.603727 -281.262075) (xy 113.655661 -281.262075)
			(xy 113.706956 -281.2702) (xy 113.756349 -281.286248) (xy 113.802623 -281.309826) (xy 113.844639 -281.340352)
			(xy 113.881362 -281.377075) (xy 113.911888 -281.419091) (xy 113.935466 -281.465365) (xy 113.951514 -281.514758)
			(xy 113.959639 -281.566053) (xy 113.960148 -281.59202) (xy 113.959639 -281.617987) (xy 113.951514 -281.669282)
			(xy 113.935466 -281.718675) (xy 113.911888 -281.764949) (xy 113.881362 -281.806965) (xy 113.844639 -281.843688)
			(xy 113.802623 -281.874214) (xy 113.756349 -281.897792) (xy 113.706956 -281.91384) (xy 113.655661 -281.921965)
			(xy 113.603727 -281.921965) (xy 113.552432 -281.91384) (xy 113.503039 -281.897792) (xy 113.456765 -281.874214)
			(xy 113.414749 -281.843688) (xy 113.378026 -281.806965) (xy 113.3475 -281.764949) (xy 113.323922 -281.718675)
			(xy 113.307874 -281.669282) (xy 113.299749 -281.617987) (xy 107.381293 -281.617987) (xy 107.373168 -281.669282)
			(xy 107.35712 -281.718675) (xy 107.333542 -281.764949) (xy 107.303016 -281.806965) (xy 107.266293 -281.843688)
			(xy 107.224277 -281.874214) (xy 107.178003 -281.897792) (xy 107.12861 -281.91384) (xy 107.077315 -281.921965)
			(xy 107.025381 -281.921965) (xy 106.974086 -281.91384) (xy 106.924693 -281.897792) (xy 106.878419 -281.874214)
			(xy 106.836403 -281.843688) (xy 106.79968 -281.806965) (xy 106.769154 -281.764949) (xy 106.745576 -281.718675)
			(xy 106.729528 -281.669282) (xy 106.721403 -281.617987) (xy 106.441494 -281.617987) (xy 106.441454 -281.620006)
			(xy 106.432001 -281.675174) (xy 106.423206 -281.701748) (xy 106.415332 -281.723846) (xy 106.61904 -282.076652)
			(xy 106.642154 -282.08097) (xy 106.667079 -282.086124) (xy 106.715063 -282.103091) (xy 106.759881 -282.12721)
			(xy 106.800473 -282.157912) (xy 106.835882 -282.194472) (xy 106.86527 -282.236026) (xy 106.887943 -282.281593)
			(xy 106.903366 -282.330095) (xy 106.911175 -282.380388) (xy 106.911648 -282.405836) (xy 106.911139 -282.431803)
			(xy 107.191049 -282.431803) (xy 107.191049 -282.379869) (xy 107.199174 -282.328574) (xy 107.215222 -282.279181)
			(xy 107.2388 -282.232907) (xy 107.269326 -282.190891) (xy 107.306049 -282.154168) (xy 107.348065 -282.123642)
			(xy 107.394339 -282.100064) (xy 107.443732 -282.084016) (xy 107.495027 -282.075891) (xy 107.546961 -282.075891)
			(xy 107.598256 -282.084016) (xy 107.647649 -282.100064) (xy 107.693923 -282.123642) (xy 107.735939 -282.154168)
			(xy 107.772662 -282.190891) (xy 107.803188 -282.232907) (xy 107.826766 -282.279181) (xy 107.842814 -282.328574)
			(xy 107.850939 -282.379869) (xy 107.851448 -282.405836) (xy 107.850939 -282.431803) (xy 110.010449 -282.431803)
			(xy 110.010449 -282.379869) (xy 110.018574 -282.328574) (xy 110.034622 -282.279181) (xy 110.0582 -282.232907)
			(xy 110.088726 -282.190891) (xy 110.125449 -282.154168) (xy 110.167465 -282.123642) (xy 110.213739 -282.100064)
			(xy 110.263132 -282.084016) (xy 110.314427 -282.075891) (xy 110.366361 -282.075891) (xy 110.417656 -282.084016)
			(xy 110.467049 -282.100064) (xy 110.513323 -282.123642) (xy 110.555339 -282.154168) (xy 110.592062 -282.190891)
			(xy 110.622588 -282.232907) (xy 110.646166 -282.279181) (xy 110.662214 -282.328574) (xy 110.670339 -282.379869)
			(xy 110.670848 -282.405836) (xy 110.670339 -282.431803) (xy 117.529103 -282.431803) (xy 117.529103 -282.379869)
			(xy 117.537228 -282.328574) (xy 117.553276 -282.279181) (xy 117.576854 -282.232907) (xy 117.60738 -282.190891)
			(xy 117.644103 -282.154168) (xy 117.686119 -282.123642) (xy 117.732393 -282.100064) (xy 117.781786 -282.084016)
			(xy 117.833081 -282.075891) (xy 117.885015 -282.075891) (xy 117.93631 -282.084016) (xy 117.985703 -282.100064)
			(xy 118.031977 -282.123642) (xy 118.073993 -282.154168) (xy 118.110716 -282.190891) (xy 118.141242 -282.232907)
			(xy 118.16482 -282.279181) (xy 118.180868 -282.328574) (xy 118.188993 -282.379869) (xy 118.189502 -282.405836)
			(xy 118.188993 -282.431803) (xy 118.180868 -282.483098) (xy 118.16482 -282.532491) (xy 118.141242 -282.578765)
			(xy 118.110716 -282.620781) (xy 118.073993 -282.657504) (xy 118.031977 -282.68803) (xy 117.985703 -282.711608)
			(xy 117.93631 -282.727656) (xy 117.885015 -282.735781) (xy 117.833081 -282.735781) (xy 117.781786 -282.727656)
			(xy 117.732393 -282.711608) (xy 117.686119 -282.68803) (xy 117.644103 -282.657504) (xy 117.60738 -282.620781)
			(xy 117.576854 -282.578765) (xy 117.553276 -282.532491) (xy 117.537228 -282.483098) (xy 117.529103 -282.431803)
			(xy 110.670339 -282.431803) (xy 110.662214 -282.483098) (xy 110.646166 -282.532491) (xy 110.622588 -282.578765)
			(xy 110.592062 -282.620781) (xy 110.555339 -282.657504) (xy 110.513323 -282.68803) (xy 110.467049 -282.711608)
			(xy 110.417656 -282.727656) (xy 110.366361 -282.735781) (xy 110.314427 -282.735781) (xy 110.263132 -282.727656)
			(xy 110.213739 -282.711608) (xy 110.167465 -282.68803) (xy 110.125449 -282.657504) (xy 110.088726 -282.620781)
			(xy 110.0582 -282.578765) (xy 110.034622 -282.532491) (xy 110.018574 -282.483098) (xy 110.010449 -282.431803)
			(xy 107.850939 -282.431803) (xy 107.842814 -282.483098) (xy 107.826766 -282.532491) (xy 107.803188 -282.578765)
			(xy 107.772662 -282.620781) (xy 107.735939 -282.657504) (xy 107.693923 -282.68803) (xy 107.647649 -282.711608)
			(xy 107.598256 -282.727656) (xy 107.546961 -282.735781) (xy 107.495027 -282.735781) (xy 107.443732 -282.727656)
			(xy 107.394339 -282.711608) (xy 107.348065 -282.68803) (xy 107.306049 -282.657504) (xy 107.269326 -282.620781)
			(xy 107.2388 -282.578765) (xy 107.215222 -282.532491) (xy 107.199174 -282.483098) (xy 107.191049 -282.431803)
			(xy 106.911139 -282.431803) (xy 106.903014 -282.483098) (xy 106.886966 -282.532491) (xy 106.863388 -282.578765)
			(xy 106.832862 -282.620781) (xy 106.796139 -282.657504) (xy 106.754123 -282.68803) (xy 106.707849 -282.711608)
			(xy 106.658456 -282.727656) (xy 106.607161 -282.735781) (xy 106.555227 -282.735781) (xy 106.503932 -282.727656)
			(xy 106.454539 -282.711608) (xy 106.408265 -282.68803) (xy 106.366249 -282.657504) (xy 106.329526 -282.620781)
			(xy 106.299 -282.578765) (xy 106.275422 -282.532491) (xy 106.259374 -282.483098) (xy 106.251249 -282.431803)
			(xy 106.25074 -282.405836) (xy 106.2513 -282.37785) (xy 106.260745 -282.322683) (xy 106.269536 -282.296108)
			(xy 106.277156 -282.27401) (xy 106.073448 -281.921204) (xy 106.050588 -281.916886) (xy 106.02566 -281.911743)
			(xy 105.977673 -281.894779) (xy 105.932852 -281.870661) (xy 105.892257 -281.839958) (xy 105.856847 -281.803397)
			(xy 105.827459 -281.76184) (xy 105.804788 -281.716271) (xy 105.789368 -281.667765) (xy 105.781564 -281.617469)
			(xy 105.781094 -281.59202) (xy 105.502202 -281.59202) (xy 105.501693 -281.617987) (xy 105.493568 -281.669282)
			(xy 105.47752 -281.718675) (xy 105.453942 -281.764949) (xy 105.423416 -281.806965) (xy 105.386693 -281.843688)
			(xy 105.344677 -281.874214) (xy 105.298403 -281.897792) (xy 105.24901 -281.91384) (xy 105.197715 -281.921965)
			(xy 105.145781 -281.921965) (xy 105.094486 -281.91384) (xy 105.045093 -281.897792) (xy 104.998819 -281.874214)
			(xy 104.956803 -281.843688) (xy 104.92008 -281.806965) (xy 104.889554 -281.764949) (xy 104.865976 -281.718675)
			(xy 104.849928 -281.669282) (xy 104.841803 -281.617987) (xy 104.561893 -281.617987) (xy 104.553768 -281.669282)
			(xy 104.53772 -281.718675) (xy 104.514142 -281.764949) (xy 104.483616 -281.806965) (xy 104.446893 -281.843688)
			(xy 104.404877 -281.874214) (xy 104.358603 -281.897792) (xy 104.30921 -281.91384) (xy 104.257915 -281.921965)
			(xy 104.205981 -281.921965) (xy 104.154686 -281.91384) (xy 104.105293 -281.897792) (xy 104.059019 -281.874214)
			(xy 104.017003 -281.843688) (xy 103.98028 -281.806965) (xy 103.949754 -281.764949) (xy 103.926176 -281.718675)
			(xy 103.910128 -281.669282) (xy 103.902003 -281.617987) (xy 103.901494 -281.59202) (xy 103.902052 -281.564034)
			(xy 103.911499 -281.508867) (xy 103.92029 -281.482292) (xy 103.92791 -281.460194) (xy 103.724202 -281.107388)
			(xy 103.701342 -281.10307) (xy 103.676382 -281.097959) (xy 103.628318 -281.08106) (xy 103.583417 -281.056985)
			(xy 103.542742 -281.026304) (xy 103.507259 -280.989744) (xy 103.477808 -280.948171) (xy 103.455085 -280.90257)
			(xy 103.439631 -280.854022) (xy 103.431811 -280.803678) (xy 103.43134 -280.778204) (xy 103.152702 -280.778204)
			(xy 103.152193 -280.804171) (xy 103.144068 -280.855466) (xy 103.12802 -280.904859) (xy 103.104442 -280.951133)
			(xy 103.073916 -280.993149) (xy 103.037193 -281.029872) (xy 102.995177 -281.060398) (xy 102.948903 -281.083976)
			(xy 102.89951 -281.100024) (xy 102.848215 -281.108149) (xy 102.796281 -281.108149) (xy 102.744986 -281.100024)
			(xy 102.695593 -281.083976) (xy 102.649319 -281.060398) (xy 102.607303 -281.029872) (xy 102.57058 -280.993149)
			(xy 102.540054 -280.951133) (xy 102.516476 -280.904859) (xy 102.500428 -280.855466) (xy 102.492303 -280.804171)
			(xy 102.212139 -280.804171) (xy 102.204014 -280.855466) (xy 102.187966 -280.904859) (xy 102.164388 -280.951133)
			(xy 102.133862 -280.993149) (xy 102.097139 -281.029872) (xy 102.055123 -281.060398) (xy 102.008849 -281.083976)
			(xy 101.959456 -281.100024) (xy 101.908161 -281.108149) (xy 101.856227 -281.108149) (xy 101.804932 -281.100024)
			(xy 101.755539 -281.083976) (xy 101.709265 -281.060398) (xy 101.667249 -281.029872) (xy 101.630526 -280.993149)
			(xy 101.6 -280.951133) (xy 101.576422 -280.904859) (xy 101.560374 -280.855466) (xy 101.552249 -280.804171)
			(xy 101.272306 -280.804171) (xy 101.272262 -280.806239) (xy 101.262948 -280.861015) (xy 101.254306 -280.887424)
			(xy 101.246432 -280.909522) (xy 101.450394 -281.262836) (xy 101.473508 -281.267154) (xy 101.498422 -281.272356)
			(xy 101.546405 -281.289316) (xy 101.591223 -281.313428) (xy 101.631816 -281.344123) (xy 101.667226 -281.380677)
			(xy 101.696615 -281.422225) (xy 101.719291 -281.467787) (xy 101.734716 -281.516285) (xy 101.742528 -281.566574)
			(xy 101.743002 -281.59202) (xy 101.742493 -281.617987) (xy 101.734368 -281.669282) (xy 101.71832 -281.718675)
			(xy 101.694742 -281.764949) (xy 101.664216 -281.806965) (xy 101.627493 -281.843688) (xy 101.585477 -281.874214)
			(xy 101.539203 -281.897792) (xy 101.48981 -281.91384) (xy 101.438515 -281.921965) (xy 101.386581 -281.921965)
			(xy 101.335286 -281.91384) (xy 101.285893 -281.897792) (xy 101.239619 -281.874214) (xy 101.197603 -281.843688)
			(xy 101.16088 -281.806965) (xy 101.130354 -281.764949) (xy 101.106776 -281.718675) (xy 101.090728 -281.669282)
			(xy 101.082603 -281.617987) (xy 101.082094 -281.59202) (xy 101.082652 -281.564034) (xy 101.092099 -281.508867)
			(xy 101.10089 -281.482292) (xy 101.10851 -281.460194) (xy 100.904802 -281.107388) (xy 100.881942 -281.10307)
			(xy 100.856982 -281.097959) (xy 100.808918 -281.08106) (xy 100.764017 -281.056985) (xy 100.723342 -281.026304)
			(xy 100.687859 -280.989744) (xy 100.658408 -280.948171) (xy 100.635685 -280.90257) (xy 100.620231 -280.854022)
			(xy 100.612411 -280.803678) (xy 100.61194 -280.778204) (xy 100.333048 -280.778204) (xy 100.332539 -280.804171)
			(xy 100.324414 -280.855466) (xy 100.308366 -280.904859) (xy 100.284788 -280.951133) (xy 100.254262 -280.993149)
			(xy 100.217539 -281.029872) (xy 100.175523 -281.060398) (xy 100.129249 -281.083976) (xy 100.079856 -281.100024)
			(xy 100.028561 -281.108149) (xy 99.976627 -281.108149) (xy 99.925332 -281.100024) (xy 99.875939 -281.083976)
			(xy 99.829665 -281.060398) (xy 99.787649 -281.029872) (xy 99.750926 -280.993149) (xy 99.7204 -280.951133)
			(xy 99.696822 -280.904859) (xy 99.680774 -280.855466) (xy 99.672649 -280.804171) (xy 99.392739 -280.804171)
			(xy 99.384614 -280.855466) (xy 99.368566 -280.904859) (xy 99.344988 -280.951133) (xy 99.314462 -280.993149)
			(xy 99.277739 -281.029872) (xy 99.235723 -281.060398) (xy 99.189449 -281.083976) (xy 99.140056 -281.100024)
			(xy 99.088761 -281.108149) (xy 99.036827 -281.108149) (xy 98.985532 -281.100024) (xy 98.936139 -281.083976)
			(xy 98.889865 -281.060398) (xy 98.847849 -281.029872) (xy 98.811126 -280.993149) (xy 98.7806 -280.951133)
			(xy 98.757022 -280.904859) (xy 98.740974 -280.855466) (xy 98.732849 -280.804171) (xy 98.452889 -280.804171)
			(xy 98.44519 -280.853959) (xy 98.429787 -280.902475) (xy 98.407123 -280.948053) (xy 98.377736 -280.989615)
			(xy 98.342321 -281.026177) (xy 98.301716 -281.056874) (xy 98.256883 -281.080978) (xy 98.208883 -281.097919)
			(xy 98.183954 -281.10307) (xy 98.161094 -281.107388) (xy 97.957386 -281.460194) (xy 97.965006 -281.482292)
			(xy 97.973742 -281.508881) (xy 97.983191 -281.56404) (xy 97.983802 -281.59202) (xy 97.983293 -281.617987)
			(xy 98.263203 -281.617987) (xy 98.263203 -281.566053) (xy 98.271328 -281.514758) (xy 98.287376 -281.465365)
			(xy 98.310954 -281.419091) (xy 98.34148 -281.377075) (xy 98.378203 -281.340352) (xy 98.420219 -281.309826)
			(xy 98.466493 -281.286248) (xy 98.515886 -281.2702) (xy 98.567181 -281.262075) (xy 98.619115 -281.262075)
			(xy 98.67041 -281.2702) (xy 98.719803 -281.286248) (xy 98.766077 -281.309826) (xy 98.808093 -281.340352)
			(xy 98.844816 -281.377075) (xy 98.875342 -281.419091) (xy 98.89892 -281.465365) (xy 98.914968 -281.514758)
			(xy 98.923093 -281.566053) (xy 98.923602 -281.59202) (xy 98.923093 -281.61797) (xy 99.202949 -281.61797)
			(xy 99.202949 -281.56603) (xy 99.211075 -281.514729) (xy 99.227127 -281.465332) (xy 99.250709 -281.419054)
			(xy 99.281241 -281.377035) (xy 99.317971 -281.34031) (xy 99.359995 -281.309784) (xy 99.406276 -281.286208)
			(xy 99.455676 -281.270164) (xy 99.506978 -281.262045) (xy 99.532948 -281.261566) (xy 99.558568 -281.26208)
			(xy 99.609192 -281.270001) (xy 99.65799 -281.285631) (xy 99.703796 -281.308596) (xy 99.745515 -281.338347)
			(xy 99.782148 -281.374173) (xy 99.79787 -281.394408) (xy 100.207826 -281.394408) (xy 100.223551 -281.374171)
			(xy 100.260167 -281.338319) (xy 100.301879 -281.308549) (xy 100.347687 -281.285575) (xy 100.396492 -281.269949)
			(xy 100.447125 -281.262045) (xy 100.472748 -281.261566) (xy 100.498714 -281.262039) (xy 100.550007 -281.27017)
			(xy 100.599396 -281.286224) (xy 100.645666 -281.309805) (xy 100.687678 -281.340334) (xy 100.724397 -281.377059)
			(xy 100.75492 -281.419075) (xy 100.778495 -281.465349) (xy 100.794542 -281.51474) (xy 100.802665 -281.566034)
			(xy 100.802665 -281.617966) (xy 100.794542 -281.66926) (xy 100.778495 -281.718651) (xy 100.75492 -281.764925)
			(xy 100.724397 -281.806941) (xy 100.687678 -281.843666) (xy 100.645666 -281.874195) (xy 100.599396 -281.897776)
			(xy 100.550007 -281.91383) (xy 100.498714 -281.921961) (xy 100.472748 -281.922474) (xy 100.447127 -281.921987)
			(xy 100.3965 -281.914064) (xy 100.3477 -281.89843) (xy 100.301894 -281.87546) (xy 100.260177 -281.845703)
			(xy 100.223545 -281.80987) (xy 100.207826 -281.789632) (xy 99.79787 -281.789632) (xy 99.782158 -281.809879)
			(xy 99.745538 -281.845729) (xy 99.703823 -281.875497) (xy 99.658013 -281.898468) (xy 99.609206 -281.914093)
			(xy 99.558572 -281.921996) (xy 99.532948 -281.922474) (xy 99.506978 -281.921955) (xy 99.455676 -281.913836)
			(xy 99.406276 -281.897792) (xy 99.359995 -281.874216) (xy 99.317971 -281.84369) (xy 99.281241 -281.806965)
			(xy 99.250709 -281.764946) (xy 99.227127 -281.718668) (xy 99.211075 -281.669271) (xy 99.202949 -281.61797)
			(xy 98.923093 -281.61797) (xy 98.923093 -281.617987) (xy 98.914968 -281.669282) (xy 98.89892 -281.718675)
			(xy 98.875342 -281.764949) (xy 98.844816 -281.806965) (xy 98.808093 -281.843688) (xy 98.766077 -281.874214)
			(xy 98.719803 -281.897792) (xy 98.67041 -281.91384) (xy 98.619115 -281.921965) (xy 98.567181 -281.921965)
			(xy 98.515886 -281.91384) (xy 98.466493 -281.897792) (xy 98.420219 -281.874214) (xy 98.378203 -281.843688)
			(xy 98.34148 -281.806965) (xy 98.310954 -281.764949) (xy 98.287376 -281.718675) (xy 98.271328 -281.669282)
			(xy 98.263203 -281.617987) (xy 97.983293 -281.617987) (xy 97.975168 -281.669282) (xy 97.95912 -281.718675)
			(xy 97.935542 -281.764949) (xy 97.905016 -281.806965) (xy 97.868293 -281.843688) (xy 97.826277 -281.874214)
			(xy 97.780003 -281.897792) (xy 97.73061 -281.91384) (xy 97.679315 -281.921965) (xy 97.627381 -281.921965)
			(xy 97.576086 -281.91384) (xy 97.526693 -281.897792) (xy 97.480419 -281.874214) (xy 97.438403 -281.843688)
			(xy 97.40168 -281.806965) (xy 97.371154 -281.764949) (xy 97.347576 -281.718675) (xy 97.331528 -281.669282)
			(xy 97.323403 -281.617987) (xy 97.322894 -281.59202) (xy 97.044002 -281.59202) (xy 97.043493 -281.617987)
			(xy 97.035368 -281.669282) (xy 97.01932 -281.718675) (xy 96.995742 -281.764949) (xy 96.965216 -281.806965)
			(xy 96.928493 -281.843688) (xy 96.886477 -281.874214) (xy 96.840203 -281.897792) (xy 96.79081 -281.91384)
			(xy 96.739515 -281.921965) (xy 96.687581 -281.921965) (xy 96.636286 -281.91384) (xy 96.586893 -281.897792)
			(xy 96.540619 -281.874214) (xy 96.498603 -281.843688) (xy 96.46188 -281.806965) (xy 96.431354 -281.764949)
			(xy 96.407776 -281.718675) (xy 96.391728 -281.669282) (xy 96.383603 -281.617987) (xy 96.103937 -281.617987)
			(xy 96.103937 -281.618764) (xy 96.095331 -281.67156) (xy 96.078346 -281.722284) (xy 96.066356 -281.746198)
			(xy 96.066102 -281.74696) (xy 96.063308 -281.752548) (xy 96.060514 -281.76347) (xy 96.060514 -281.981402)
			(xy 96.061101 -281.99264) (xy 96.070732 -282.012944) (xy 96.079056 -282.020518) (xy 96.139254 -282.070302)
			(xy 96.143671 -282.073775) (xy 96.153669 -282.078898) (xy 96.159066 -282.080462) (xy 96.169734 -282.083256)
			(xy 96.181164 -282.08097) (xy 96.196385 -282.078241) (xy 96.22717 -282.075313) (xy 96.242632 -282.075128)
			(xy 96.243394 -282.075128) (xy 96.269383 -282.075611) (xy 96.32072 -282.083741) (xy 96.370153 -282.099804)
			(xy 96.416464 -282.123402) (xy 96.458514 -282.153954) (xy 96.495265 -282.190709) (xy 96.525814 -282.232761)
			(xy 96.549408 -282.279075) (xy 96.565466 -282.328509) (xy 96.573592 -282.379847) (xy 96.574102 -282.405836)
			(xy 96.573555 -282.431764) (xy 96.853291 -282.431764) (xy 96.853291 -282.379836) (xy 96.861414 -282.328547)
			(xy 96.877461 -282.27916) (xy 96.901036 -282.232892) (xy 96.931558 -282.190881) (xy 96.968276 -282.154162)
			(xy 97.010287 -282.123639) (xy 97.056555 -282.100063) (xy 97.105941 -282.084016) (xy 97.15723 -282.075892)
			(xy 97.183194 -282.075382) (xy 97.208815 -282.075856) (xy 97.259442 -282.083785) (xy 97.308241 -282.099422)
			(xy 97.354047 -282.122394) (xy 97.395764 -282.152153) (xy 97.432396 -282.187986) (xy 97.448116 -282.208224)
			(xy 97.858072 -282.208224) (xy 97.873747 -282.187948) (xy 97.910376 -282.152101) (xy 97.952099 -282.122338)
			(xy 97.997917 -282.099372) (xy 98.04673 -282.083754) (xy 98.097368 -282.075857) (xy 98.122994 -282.075382)
			(xy 98.148966 -282.075792) (xy 98.200272 -282.083918) (xy 98.249675 -282.099969) (xy 98.295958 -282.123551)
			(xy 98.337983 -282.154083) (xy 98.374714 -282.190813) (xy 98.405246 -282.232837) (xy 98.428829 -282.27912)
			(xy 98.444881 -282.328522) (xy 98.453007 -282.379828) (xy 98.453007 -282.431772) (xy 98.453002 -282.431803)
			(xy 98.732849 -282.431803) (xy 98.732849 -282.379869) (xy 98.740974 -282.328574) (xy 98.757022 -282.279181)
			(xy 98.7806 -282.232907) (xy 98.811126 -282.190891) (xy 98.847849 -282.154168) (xy 98.889865 -282.123642)
			(xy 98.936139 -282.100064) (xy 98.985532 -282.084016) (xy 99.036827 -282.075891) (xy 99.088761 -282.075891)
			(xy 99.140056 -282.084016) (xy 99.189449 -282.100064) (xy 99.235723 -282.123642) (xy 99.277739 -282.154168)
			(xy 99.314462 -282.190891) (xy 99.344988 -282.232907) (xy 99.368566 -282.279181) (xy 99.384614 -282.328574)
			(xy 99.392739 -282.379869) (xy 99.393248 -282.405836) (xy 99.392739 -282.431803) (xy 99.384614 -282.483098)
			(xy 99.368566 -282.532491) (xy 99.344988 -282.578765) (xy 99.314462 -282.620781) (xy 99.277739 -282.657504)
			(xy 99.235723 -282.68803) (xy 99.189449 -282.711608) (xy 99.140056 -282.727656) (xy 99.088761 -282.735781)
			(xy 99.036827 -282.735781) (xy 98.985532 -282.727656) (xy 98.936139 -282.711608) (xy 98.889865 -282.68803)
			(xy 98.847849 -282.657504) (xy 98.811126 -282.620781) (xy 98.7806 -282.578765) (xy 98.757022 -282.532491)
			(xy 98.740974 -282.483098) (xy 98.732849 -282.431803) (xy 98.453002 -282.431803) (xy 98.444881 -282.483078)
			(xy 98.428829 -282.53248) (xy 98.405246 -282.578763) (xy 98.374714 -282.620787) (xy 98.337983 -282.657517)
			(xy 98.295958 -282.688049) (xy 98.249675 -282.711631) (xy 98.200272 -282.727682) (xy 98.148966 -282.735808)
			(xy 98.122994 -282.73629) (xy 98.097374 -282.735763) (xy 98.04675 -282.727847) (xy 97.997951 -282.712221)
			(xy 97.952145 -282.689259) (xy 97.910426 -282.659509) (xy 97.873793 -282.623683) (xy 97.858072 -282.603448)
			(xy 97.448116 -282.603448) (xy 97.432382 -282.623676) (xy 97.395766 -282.659527) (xy 97.354055 -282.689296)
			(xy 97.308249 -282.712271) (xy 97.259447 -282.7279) (xy 97.208816 -282.735808) (xy 97.183194 -282.73629)
			(xy 97.15723 -282.735708) (xy 97.105941 -282.727584) (xy 97.056555 -282.711537) (xy 97.010287 -282.687961)
			(xy 96.968276 -282.657438) (xy 96.931558 -282.620719) (xy 96.901036 -282.578708) (xy 96.877461 -282.53244)
			(xy 96.861414 -282.483053) (xy 96.853291 -282.431764) (xy 96.573555 -282.431764) (xy 96.573487 -282.434968)
			(xy 96.563263 -282.492329) (xy 96.553782 -282.519882) (xy 96.547686 -282.537662) (xy 96.751394 -282.890722)
			(xy 96.774508 -282.89504) (xy 96.799434 -282.900194) (xy 96.847426 -282.917141) (xy 96.892252 -282.941249)
			(xy 96.932849 -282.971947) (xy 96.968257 -283.00851) (xy 96.997637 -283.05007) (xy 97.020295 -283.095646)
			(xy 97.035694 -283.144158) (xy 97.04347 -283.194457) (xy 97.044002 -283.219906) (xy 97.043493 -283.245873)
			(xy 97.323149 -283.245873) (xy 97.323149 -283.193939) (xy 97.331274 -283.142644) (xy 97.347322 -283.093251)
			(xy 97.3709 -283.046977) (xy 97.401426 -283.004961) (xy 97.438149 -282.968238) (xy 97.480165 -282.937712)
			(xy 97.526439 -282.914134) (xy 97.575832 -282.898086) (xy 97.627127 -282.889961) (xy 97.679061 -282.889961)
			(xy 97.730356 -282.898086) (xy 97.779749 -282.914134) (xy 97.826023 -282.937712) (xy 97.868039 -282.968238)
			(xy 97.904762 -283.004961) (xy 97.935288 -283.046977) (xy 97.958866 -283.093251) (xy 97.974914 -283.142644)
			(xy 97.983039 -283.193939) (xy 97.983548 -283.219906) (xy 97.983039 -283.245873) (xy 98.262949 -283.245873)
			(xy 98.262949 -283.193939) (xy 98.271074 -283.142644) (xy 98.287122 -283.093251) (xy 98.3107 -283.046977)
			(xy 98.341226 -283.004961) (xy 98.377949 -282.968238) (xy 98.419965 -282.937712) (xy 98.466239 -282.914134)
			(xy 98.515632 -282.898086) (xy 98.566927 -282.889961) (xy 98.618861 -282.889961) (xy 98.670156 -282.898086)
			(xy 98.719549 -282.914134) (xy 98.765823 -282.937712) (xy 98.807839 -282.968238) (xy 98.844562 -283.004961)
			(xy 98.875088 -283.046977) (xy 98.898666 -283.093251) (xy 98.914714 -283.142644) (xy 98.922839 -283.193939)
			(xy 98.923348 -283.219906) (xy 99.202494 -283.219906) (xy 99.203029 -283.194457) (xy 99.210805 -283.144158)
			(xy 99.226204 -283.095647) (xy 99.248861 -283.050071) (xy 99.278241 -283.008511) (xy 99.313649 -282.971948)
			(xy 99.354245 -282.94125) (xy 99.39907 -282.917142) (xy 99.447063 -282.900194) (xy 99.471988 -282.89504)
			(xy 99.495102 -282.890722) (xy 99.69881 -282.537916) (xy 99.690936 -282.515818) (xy 99.682204 -282.489228)
			(xy 99.672752 -282.43407) (xy 99.67214 -282.40609) (xy 99.67214 -282.405836) (xy 99.672649 -282.379869)
			(xy 99.680774 -282.328574) (xy 99.696822 -282.279181) (xy 99.7204 -282.232907) (xy 99.750926 -282.190891)
			(xy 99.787649 -282.154168) (xy 99.829665 -282.123642) (xy 99.875939 -282.100064) (xy 99.925332 -282.084016)
			(xy 99.976627 -282.075891) (xy 100.028561 -282.075891) (xy 100.079856 -282.084016) (xy 100.129249 -282.100064)
			(xy 100.175523 -282.123642) (xy 100.217539 -282.154168) (xy 100.254262 -282.190891) (xy 100.284788 -282.232907)
			(xy 100.308366 -282.279181) (xy 100.324414 -282.328574) (xy 100.332539 -282.379869) (xy 100.333048 -282.405836)
			(xy 100.332513 -282.431267) (xy 100.33243 -282.431803) (xy 100.612449 -282.431803) (xy 100.612449 -282.379869)
			(xy 100.620574 -282.328574) (xy 100.636622 -282.279181) (xy 100.6602 -282.232907) (xy 100.690726 -282.190891)
			(xy 100.727449 -282.154168) (xy 100.769465 -282.123642) (xy 100.815739 -282.100064) (xy 100.865132 -282.084016)
			(xy 100.916427 -282.075891) (xy 100.968361 -282.075891) (xy 101.019656 -282.084016) (xy 101.069049 -282.100064)
			(xy 101.115323 -282.123642) (xy 101.157339 -282.154168) (xy 101.194062 -282.190891) (xy 101.224588 -282.232907)
			(xy 101.248166 -282.279181) (xy 101.264214 -282.328574) (xy 101.272339 -282.379869) (xy 101.272848 -282.405836)
			(xy 101.55174 -282.405836) (xy 101.552174 -282.380383) (xy 101.559961 -282.330078) (xy 101.575372 -282.281562)
			(xy 101.598043 -282.235984) (xy 101.627436 -282.194422) (xy 101.662856 -282.157861) (xy 101.703464 -282.127166)
			(xy 101.748301 -282.103062) (xy 101.796304 -282.08612) (xy 101.821234 -282.08097) (xy 101.844348 -282.076652)
			(xy 102.04831 -281.723338) (xy 102.040436 -281.70124) (xy 102.031818 -281.674825) (xy 102.022491 -281.620053)
			(xy 102.021894 -281.592274) (xy 102.021894 -281.59202) (xy 102.022403 -281.566053) (xy 102.030528 -281.514758)
			(xy 102.046576 -281.465365) (xy 102.070154 -281.419091) (xy 102.10068 -281.377075) (xy 102.137403 -281.340352)
			(xy 102.179419 -281.309826) (xy 102.225693 -281.286248) (xy 102.275086 -281.2702) (xy 102.326381 -281.262075)
			(xy 102.378315 -281.262075) (xy 102.42961 -281.2702) (xy 102.479003 -281.286248) (xy 102.525277 -281.309826)
			(xy 102.567293 -281.340352) (xy 102.604016 -281.377075) (xy 102.634542 -281.419091) (xy 102.65812 -281.465365)
			(xy 102.674168 -281.514758) (xy 102.682293 -281.566053) (xy 102.682802 -281.59202) (xy 102.682299 -281.617492)
			(xy 102.682222 -281.617987) (xy 102.961949 -281.617987) (xy 102.961949 -281.566053) (xy 102.970074 -281.514758)
			(xy 102.986122 -281.465365) (xy 103.0097 -281.419091) (xy 103.040226 -281.377075) (xy 103.076949 -281.340352)
			(xy 103.118965 -281.309826) (xy 103.165239 -281.286248) (xy 103.214632 -281.2702) (xy 103.265927 -281.262075)
			(xy 103.317861 -281.262075) (xy 103.369156 -281.2702) (xy 103.418549 -281.286248) (xy 103.464823 -281.309826)
			(xy 103.506839 -281.340352) (xy 103.543562 -281.377075) (xy 103.574088 -281.419091) (xy 103.597666 -281.465365)
			(xy 103.613714 -281.514758) (xy 103.621839 -281.566053) (xy 103.622348 -281.59202) (xy 103.621839 -281.617987)
			(xy 103.613714 -281.669282) (xy 103.597666 -281.718675) (xy 103.574088 -281.764949) (xy 103.543562 -281.806965)
			(xy 103.506839 -281.843688) (xy 103.464823 -281.874214) (xy 103.418549 -281.897792) (xy 103.369156 -281.91384)
			(xy 103.317861 -281.921965) (xy 103.265927 -281.921965) (xy 103.214632 -281.91384) (xy 103.165239 -281.897792)
			(xy 103.118965 -281.874214) (xy 103.076949 -281.843688) (xy 103.040226 -281.806965) (xy 103.0097 -281.764949)
			(xy 102.986122 -281.718675) (xy 102.970074 -281.669282) (xy 102.961949 -281.617987) (xy 102.682222 -281.617987)
			(xy 102.674478 -281.667832) (xy 102.659025 -281.716375) (xy 102.636305 -281.761972) (xy 102.606857 -281.803542)
			(xy 102.571378 -281.840101) (xy 102.530709 -281.870782) (xy 102.485814 -281.894859) (xy 102.437755 -281.91176)
			(xy 102.4128 -281.916886) (xy 102.38994 -281.921204) (xy 102.186232 -282.27401) (xy 102.193852 -282.296108)
			(xy 102.20259 -282.322696) (xy 102.212038 -282.377855) (xy 102.212648 -282.405836) (xy 102.212139 -282.431803)
			(xy 102.492303 -282.431803) (xy 102.492303 -282.379869) (xy 102.500428 -282.328574) (xy 102.516476 -282.279181)
			(xy 102.540054 -282.232907) (xy 102.57058 -282.190891) (xy 102.607303 -282.154168) (xy 102.649319 -282.123642)
			(xy 102.695593 -282.100064) (xy 102.744986 -282.084016) (xy 102.796281 -282.075891) (xy 102.848215 -282.075891)
			(xy 102.89951 -282.084016) (xy 102.948903 -282.100064) (xy 102.995177 -282.123642) (xy 103.037193 -282.154168)
			(xy 103.073916 -282.190891) (xy 103.104442 -282.232907) (xy 103.12802 -282.279181) (xy 103.144068 -282.328574)
			(xy 103.152193 -282.379869) (xy 103.152702 -282.405836) (xy 103.152194 -282.431764) (xy 103.431891 -282.431764)
			(xy 103.431891 -282.379836) (xy 103.440014 -282.328547) (xy 103.456061 -282.27916) (xy 103.479636 -282.232892)
			(xy 103.510158 -282.190881) (xy 103.546876 -282.154162) (xy 103.588887 -282.123639) (xy 103.635155 -282.100063)
			(xy 103.684541 -282.084016) (xy 103.73583 -282.075892) (xy 103.761794 -282.075382) (xy 103.787415 -282.075856)
			(xy 103.838042 -282.083785) (xy 103.886841 -282.099422) (xy 103.932647 -282.122394) (xy 103.974364 -282.152153)
			(xy 104.010996 -282.187986) (xy 104.026716 -282.208224) (xy 104.436672 -282.208224) (xy 104.452347 -282.187948)
			(xy 104.488976 -282.152101) (xy 104.530699 -282.122338) (xy 104.576517 -282.099372) (xy 104.62533 -282.083754)
			(xy 104.675968 -282.075857) (xy 104.701594 -282.075382) (xy 104.727566 -282.075792) (xy 104.778872 -282.083918)
			(xy 104.828275 -282.099969) (xy 104.874558 -282.123551) (xy 104.916583 -282.154083) (xy 104.953314 -282.190813)
			(xy 104.983846 -282.232837) (xy 105.007429 -282.27912) (xy 105.023481 -282.328522) (xy 105.031607 -282.379828)
			(xy 105.031607 -282.431772) (xy 105.023481 -282.483078) (xy 105.007429 -282.53248) (xy 104.983846 -282.578763)
			(xy 104.953314 -282.620787) (xy 104.916583 -282.657517) (xy 104.874558 -282.688049) (xy 104.828275 -282.711631)
			(xy 104.778872 -282.727682) (xy 104.727566 -282.735808) (xy 104.701594 -282.73629) (xy 104.675974 -282.735763)
			(xy 104.62535 -282.727847) (xy 104.576551 -282.712221) (xy 104.530745 -282.689259) (xy 104.489026 -282.659509)
			(xy 104.452393 -282.623683) (xy 104.436672 -282.603448) (xy 104.026716 -282.603448) (xy 104.010982 -282.623676)
			(xy 103.974366 -282.659527) (xy 103.932655 -282.689296) (xy 103.886849 -282.712271) (xy 103.838047 -282.7279)
			(xy 103.787416 -282.735808) (xy 103.761794 -282.73629) (xy 103.73583 -282.735708) (xy 103.684541 -282.727584)
			(xy 103.635155 -282.711537) (xy 103.588887 -282.687961) (xy 103.546876 -282.657438) (xy 103.510158 -282.620719)
			(xy 103.479636 -282.578708) (xy 103.456061 -282.53244) (xy 103.440014 -282.483053) (xy 103.431891 -282.431764)
			(xy 103.152194 -282.431764) (xy 103.152193 -282.431803) (xy 103.144068 -282.483098) (xy 103.12802 -282.532491)
			(xy 103.104442 -282.578765) (xy 103.073916 -282.620781) (xy 103.037193 -282.657504) (xy 102.995177 -282.68803)
			(xy 102.948903 -282.711608) (xy 102.89951 -282.727656) (xy 102.848215 -282.735781) (xy 102.796281 -282.735781)
			(xy 102.744986 -282.727656) (xy 102.695593 -282.711608) (xy 102.649319 -282.68803) (xy 102.607303 -282.657504)
			(xy 102.57058 -282.620781) (xy 102.540054 -282.578765) (xy 102.516476 -282.532491) (xy 102.500428 -282.483098)
			(xy 102.492303 -282.431803) (xy 102.212139 -282.431803) (xy 102.204014 -282.483098) (xy 102.187966 -282.532491)
			(xy 102.164388 -282.578765) (xy 102.133862 -282.620781) (xy 102.097139 -282.657504) (xy 102.055123 -282.68803)
			(xy 102.008849 -282.711608) (xy 101.959456 -282.727656) (xy 101.908161 -282.735781) (xy 101.856227 -282.735781)
			(xy 101.804932 -282.727656) (xy 101.755539 -282.711608) (xy 101.709265 -282.68803) (xy 101.667249 -282.657504)
			(xy 101.630526 -282.620781) (xy 101.6 -282.578765) (xy 101.576422 -282.532491) (xy 101.560374 -282.483098)
			(xy 101.552249 -282.431803) (xy 101.55174 -282.405836) (xy 101.272848 -282.405836) (xy 101.272339 -282.431803)
			(xy 101.264214 -282.483098) (xy 101.248166 -282.532491) (xy 101.224588 -282.578765) (xy 101.194062 -282.620781)
			(xy 101.157339 -282.657504) (xy 101.115323 -282.68803) (xy 101.069049 -282.711608) (xy 101.019656 -282.727656)
			(xy 100.968361 -282.735781) (xy 100.916427 -282.735781) (xy 100.865132 -282.727656) (xy 100.815739 -282.711608)
			(xy 100.769465 -282.68803) (xy 100.727449 -282.657504) (xy 100.690726 -282.620781) (xy 100.6602 -282.578765)
			(xy 100.636622 -282.532491) (xy 100.620574 -282.483098) (xy 100.612449 -282.431803) (xy 100.33243 -282.431803)
			(xy 100.324707 -282.481526) (xy 100.3093 -282.529997) (xy 100.286655 -282.57554) (xy 100.257306 -282.617079)
			(xy 100.221945 -282.653637) (xy 100.181404 -282.684351) (xy 100.13664 -282.708498) (xy 100.088707 -282.725508)
			(xy 100.063808 -282.730702) (xy 100.040694 -282.73502) (xy 99.836986 -283.08808) (xy 99.844606 -283.110178)
			(xy 99.853339 -283.136768) (xy 99.862789 -283.191926) (xy 99.863402 -283.219906) (xy 99.862893 -283.245873)
			(xy 100.142549 -283.245873) (xy 100.142549 -283.193939) (xy 100.150674 -283.142644) (xy 100.166722 -283.093251)
			(xy 100.1903 -283.046977) (xy 100.220826 -283.004961) (xy 100.257549 -282.968238) (xy 100.299565 -282.937712)
			(xy 100.345839 -282.914134) (xy 100.395232 -282.898086) (xy 100.446527 -282.889961) (xy 100.498461 -282.889961)
			(xy 100.549756 -282.898086) (xy 100.599149 -282.914134) (xy 100.645423 -282.937712) (xy 100.687439 -282.968238)
			(xy 100.724162 -283.004961) (xy 100.754688 -283.046977) (xy 100.778266 -283.093251) (xy 100.794314 -283.142644)
			(xy 100.802439 -283.193939) (xy 100.802948 -283.219906) (xy 100.802439 -283.245871) (xy 101.082535 -283.245871)
			(xy 101.082535 -283.193929) (xy 101.090661 -283.142626) (xy 101.106714 -283.093226) (xy 101.130297 -283.046946)
			(xy 101.160831 -283.004926) (xy 101.197562 -282.968199) (xy 101.239587 -282.937672) (xy 101.285871 -282.914095)
			(xy 101.335273 -282.89805) (xy 101.386577 -282.889931) (xy 101.412548 -282.889452) (xy 101.438184 -282.889951)
			(xy 101.48884 -282.89787) (xy 101.537662 -282.913524) (xy 101.583478 -282.936539) (xy 101.625184 -282.966359)
			(xy 101.661779 -283.002269) (xy 101.67747 -283.022548) (xy 102.087426 -283.022548) (xy 102.103137 -283.002286)
			(xy 102.13973 -282.966377) (xy 102.181433 -282.936554) (xy 102.227244 -282.913535) (xy 102.276062 -282.897871)
			(xy 102.326714 -282.88994) (xy 102.352348 -282.889452) (xy 102.378313 -282.889953) (xy 102.429603 -282.898083)
			(xy 102.47899 -282.914136) (xy 102.525259 -282.937717) (xy 102.567269 -282.968245) (xy 102.603986 -283.004968)
			(xy 102.634508 -283.046982) (xy 102.658082 -283.093254) (xy 102.674128 -283.142643) (xy 102.682251 -283.193935)
			(xy 102.682251 -283.245865) (xy 102.68225 -283.245873) (xy 102.961949 -283.245873) (xy 102.961949 -283.193939)
			(xy 102.970074 -283.142644) (xy 102.986122 -283.093251) (xy 103.0097 -283.046977) (xy 103.040226 -283.004961)
			(xy 103.076949 -282.968238) (xy 103.118965 -282.937712) (xy 103.165239 -282.914134) (xy 103.214632 -282.898086)
			(xy 103.265927 -282.889961) (xy 103.317861 -282.889961) (xy 103.369156 -282.898086) (xy 103.418549 -282.914134)
			(xy 103.464823 -282.937712) (xy 103.506839 -282.968238) (xy 103.543562 -283.004961) (xy 103.574088 -283.046977)
			(xy 103.597666 -283.093251) (xy 103.613714 -283.142644) (xy 103.621839 -283.193939) (xy 103.622348 -283.219906)
			(xy 103.621839 -283.245873) (xy 103.901749 -283.245873) (xy 103.901749 -283.193939) (xy 103.909874 -283.142644)
			(xy 103.925922 -283.093251) (xy 103.9495 -283.046977) (xy 103.980026 -283.004961) (xy 104.016749 -282.968238)
			(xy 104.058765 -282.937712) (xy 104.105039 -282.914134) (xy 104.154432 -282.898086) (xy 104.205727 -282.889961)
			(xy 104.257661 -282.889961) (xy 104.308956 -282.898086) (xy 104.358349 -282.914134) (xy 104.404623 -282.937712)
			(xy 104.446639 -282.968238) (xy 104.483362 -283.004961) (xy 104.513888 -283.046977) (xy 104.537466 -283.093251)
			(xy 104.553514 -283.142644) (xy 104.561639 -283.193939) (xy 104.562148 -283.219906) (xy 104.841294 -283.219906)
			(xy 104.841829 -283.194457) (xy 104.849605 -283.144158) (xy 104.865004 -283.095647) (xy 104.887661 -283.050071)
			(xy 104.917041 -283.008511) (xy 104.952449 -282.971948) (xy 104.993045 -282.94125) (xy 105.03787 -282.917142)
			(xy 105.085863 -282.900194) (xy 105.110788 -282.89504) (xy 105.133902 -282.890722) (xy 105.33761 -282.537916)
			(xy 105.329736 -282.515818) (xy 105.321004 -282.489228) (xy 105.311552 -282.43407) (xy 105.31094 -282.40609)
			(xy 105.31094 -282.405836) (xy 105.311449 -282.379869) (xy 105.319574 -282.328574) (xy 105.335622 -282.279181)
			(xy 105.3592 -282.232907) (xy 105.389726 -282.190891) (xy 105.426449 -282.154168) (xy 105.468465 -282.123642)
			(xy 105.514739 -282.100064) (xy 105.564132 -282.084016) (xy 105.615427 -282.075891) (xy 105.667361 -282.075891)
			(xy 105.718656 -282.084016) (xy 105.768049 -282.100064) (xy 105.814323 -282.123642) (xy 105.856339 -282.154168)
			(xy 105.893062 -282.190891) (xy 105.923588 -282.232907) (xy 105.947166 -282.279181) (xy 105.963214 -282.328574)
			(xy 105.971339 -282.379869) (xy 105.971848 -282.405836) (xy 105.971313 -282.431267) (xy 105.963507 -282.481526)
			(xy 105.9481 -282.529997) (xy 105.925455 -282.57554) (xy 105.896106 -282.617079) (xy 105.860745 -282.653637)
			(xy 105.820204 -282.684351) (xy 105.77544 -282.708498) (xy 105.727507 -282.725508) (xy 105.702608 -282.730702)
			(xy 105.679494 -282.73502) (xy 105.475786 -283.08808) (xy 105.483406 -283.110178) (xy 105.492139 -283.136768)
			(xy 105.501589 -283.191926) (xy 105.502202 -283.219906) (xy 105.501693 -283.245873) (xy 105.781349 -283.245873)
			(xy 105.781349 -283.193939) (xy 105.789474 -283.142644) (xy 105.805522 -283.093251) (xy 105.8291 -283.046977)
			(xy 105.859626 -283.004961) (xy 105.896349 -282.968238) (xy 105.938365 -282.937712) (xy 105.984639 -282.914134)
			(xy 106.034032 -282.898086) (xy 106.085327 -282.889961) (xy 106.137261 -282.889961) (xy 106.188556 -282.898086)
			(xy 106.237949 -282.914134) (xy 106.284223 -282.937712) (xy 106.326239 -282.968238) (xy 106.362962 -283.004961)
			(xy 106.393488 -283.046977) (xy 106.417066 -283.093251) (xy 106.433114 -283.142644) (xy 106.441239 -283.193939)
			(xy 106.441748 -283.219906) (xy 106.441239 -283.245873) (xy 106.721403 -283.245873) (xy 106.721403 -283.193939)
			(xy 106.729528 -283.142644) (xy 106.745576 -283.093251) (xy 106.769154 -283.046977) (xy 106.79968 -283.004961)
			(xy 106.836403 -282.968238) (xy 106.878419 -282.937712) (xy 106.924693 -282.914134) (xy 106.974086 -282.898086)
			(xy 107.025381 -282.889961) (xy 107.077315 -282.889961) (xy 107.12861 -282.898086) (xy 107.178003 -282.914134)
			(xy 107.224277 -282.937712) (xy 107.266293 -282.968238) (xy 107.303016 -283.004961) (xy 107.333542 -283.046977)
			(xy 107.35712 -283.093251) (xy 107.373168 -283.142644) (xy 107.381293 -283.193939) (xy 107.381802 -283.219906)
			(xy 107.381293 -283.245873) (xy 113.299749 -283.245873) (xy 113.299749 -283.193939) (xy 113.307874 -283.142644)
			(xy 113.323922 -283.093251) (xy 113.3475 -283.046977) (xy 113.378026 -283.004961) (xy 113.414749 -282.968238)
			(xy 113.456765 -282.937712) (xy 113.503039 -282.914134) (xy 113.552432 -282.898086) (xy 113.603727 -282.889961)
			(xy 113.655661 -282.889961) (xy 113.706956 -282.898086) (xy 113.756349 -282.914134) (xy 113.802623 -282.937712)
			(xy 113.844639 -282.968238) (xy 113.881362 -283.004961) (xy 113.911888 -283.046977) (xy 113.935466 -283.093251)
			(xy 113.951514 -283.142644) (xy 113.959639 -283.193939) (xy 113.960148 -283.219906) (xy 113.959639 -283.245873)
			(xy 116.119403 -283.245873) (xy 116.119403 -283.193939) (xy 116.127528 -283.142644) (xy 116.143576 -283.093251)
			(xy 116.167154 -283.046977) (xy 116.19768 -283.004961) (xy 116.234403 -282.968238) (xy 116.276419 -282.937712)
			(xy 116.322693 -282.914134) (xy 116.372086 -282.898086) (xy 116.423381 -282.889961) (xy 116.475315 -282.889961)
			(xy 116.52661 -282.898086) (xy 116.576003 -282.914134) (xy 116.622277 -282.937712) (xy 116.664293 -282.968238)
			(xy 116.701016 -283.004961) (xy 116.731542 -283.046977) (xy 116.75512 -283.093251) (xy 116.771168 -283.142644)
			(xy 116.779293 -283.193939) (xy 116.779802 -283.219906) (xy 116.779293 -283.245873) (xy 117.999003 -283.245873)
			(xy 117.999003 -283.193939) (xy 118.007128 -283.142644) (xy 118.023176 -283.093251) (xy 118.046754 -283.046977)
			(xy 118.07728 -283.004961) (xy 118.114003 -282.968238) (xy 118.156019 -282.937712) (xy 118.202293 -282.914134)
			(xy 118.251686 -282.898086) (xy 118.302981 -282.889961) (xy 118.354915 -282.889961) (xy 118.40621 -282.898086)
			(xy 118.455603 -282.914134) (xy 118.501877 -282.937712) (xy 118.543893 -282.968238) (xy 118.580616 -283.004961)
			(xy 118.611142 -283.046977) (xy 118.63472 -283.093251) (xy 118.650768 -283.142644) (xy 118.658893 -283.193939)
			(xy 118.659402 -283.219906) (xy 118.658893 -283.245873) (xy 118.650768 -283.297168) (xy 118.63472 -283.346561)
			(xy 118.611142 -283.392835) (xy 118.580616 -283.434851) (xy 118.543893 -283.471574) (xy 118.501877 -283.5021)
			(xy 118.455603 -283.525678) (xy 118.40621 -283.541726) (xy 118.354915 -283.549851) (xy 118.302981 -283.549851)
			(xy 118.251686 -283.541726) (xy 118.202293 -283.525678) (xy 118.156019 -283.5021) (xy 118.114003 -283.471574)
			(xy 118.07728 -283.434851) (xy 118.046754 -283.392835) (xy 118.023176 -283.346561) (xy 118.007128 -283.297168)
			(xy 117.999003 -283.245873) (xy 116.779293 -283.245873) (xy 116.771168 -283.297168) (xy 116.75512 -283.346561)
			(xy 116.731542 -283.392835) (xy 116.701016 -283.434851) (xy 116.664293 -283.471574) (xy 116.622277 -283.5021)
			(xy 116.576003 -283.525678) (xy 116.52661 -283.541726) (xy 116.475315 -283.549851) (xy 116.423381 -283.549851)
			(xy 116.372086 -283.541726) (xy 116.322693 -283.525678) (xy 116.276419 -283.5021) (xy 116.234403 -283.471574)
			(xy 116.19768 -283.434851) (xy 116.167154 -283.392835) (xy 116.143576 -283.346561) (xy 116.127528 -283.297168)
			(xy 116.119403 -283.245873) (xy 113.959639 -283.245873) (xy 113.951514 -283.297168) (xy 113.935466 -283.346561)
			(xy 113.911888 -283.392835) (xy 113.881362 -283.434851) (xy 113.844639 -283.471574) (xy 113.802623 -283.5021)
			(xy 113.756349 -283.525678) (xy 113.706956 -283.541726) (xy 113.655661 -283.549851) (xy 113.603727 -283.549851)
			(xy 113.552432 -283.541726) (xy 113.503039 -283.525678) (xy 113.456765 -283.5021) (xy 113.414749 -283.471574)
			(xy 113.378026 -283.434851) (xy 113.3475 -283.392835) (xy 113.323922 -283.346561) (xy 113.307874 -283.297168)
			(xy 113.299749 -283.245873) (xy 107.381293 -283.245873) (xy 107.373168 -283.297168) (xy 107.35712 -283.346561)
			(xy 107.333542 -283.392835) (xy 107.303016 -283.434851) (xy 107.266293 -283.471574) (xy 107.224277 -283.5021)
			(xy 107.178003 -283.525678) (xy 107.12861 -283.541726) (xy 107.077315 -283.549851) (xy 107.025381 -283.549851)
			(xy 106.974086 -283.541726) (xy 106.924693 -283.525678) (xy 106.878419 -283.5021) (xy 106.836403 -283.471574)
			(xy 106.79968 -283.434851) (xy 106.769154 -283.392835) (xy 106.745576 -283.346561) (xy 106.729528 -283.297168)
			(xy 106.721403 -283.245873) (xy 106.441239 -283.245873) (xy 106.433114 -283.297168) (xy 106.417066 -283.346561)
			(xy 106.393488 -283.392835) (xy 106.362962 -283.434851) (xy 106.326239 -283.471574) (xy 106.284223 -283.5021)
			(xy 106.237949 -283.525678) (xy 106.188556 -283.541726) (xy 106.137261 -283.549851) (xy 106.085327 -283.549851)
			(xy 106.034032 -283.541726) (xy 105.984639 -283.525678) (xy 105.938365 -283.5021) (xy 105.896349 -283.471574)
			(xy 105.859626 -283.434851) (xy 105.8291 -283.392835) (xy 105.805522 -283.346561) (xy 105.789474 -283.297168)
			(xy 105.781349 -283.245873) (xy 105.501693 -283.245873) (xy 105.493568 -283.297168) (xy 105.47752 -283.346561)
			(xy 105.453942 -283.392835) (xy 105.423416 -283.434851) (xy 105.386693 -283.471574) (xy 105.344677 -283.5021)
			(xy 105.298403 -283.525678) (xy 105.24901 -283.541726) (xy 105.197715 -283.549851) (xy 105.145781 -283.549851)
			(xy 105.094486 -283.541726) (xy 105.045093 -283.525678) (xy 104.998819 -283.5021) (xy 104.956803 -283.471574)
			(xy 104.92008 -283.434851) (xy 104.889554 -283.392835) (xy 104.865976 -283.346561) (xy 104.849928 -283.297168)
			(xy 104.841803 -283.245873) (xy 104.841294 -283.219906) (xy 104.562148 -283.219906) (xy 104.561639 -283.245873)
			(xy 104.553514 -283.297168) (xy 104.537466 -283.346561) (xy 104.513888 -283.392835) (xy 104.483362 -283.434851)
			(xy 104.446639 -283.471574) (xy 104.404623 -283.5021) (xy 104.358349 -283.525678) (xy 104.308956 -283.541726)
			(xy 104.257661 -283.549851) (xy 104.205727 -283.549851) (xy 104.154432 -283.541726) (xy 104.105039 -283.525678)
			(xy 104.058765 -283.5021) (xy 104.016749 -283.471574) (xy 103.980026 -283.434851) (xy 103.9495 -283.392835)
			(xy 103.925922 -283.346561) (xy 103.909874 -283.297168) (xy 103.901749 -283.245873) (xy 103.621839 -283.245873)
			(xy 103.613714 -283.297168) (xy 103.597666 -283.346561) (xy 103.574088 -283.392835) (xy 103.543562 -283.434851)
			(xy 103.506839 -283.471574) (xy 103.464823 -283.5021) (xy 103.418549 -283.525678) (xy 103.369156 -283.541726)
			(xy 103.317861 -283.549851) (xy 103.265927 -283.549851) (xy 103.214632 -283.541726) (xy 103.165239 -283.525678)
			(xy 103.118965 -283.5021) (xy 103.076949 -283.471574) (xy 103.040226 -283.434851) (xy 103.0097 -283.392835)
			(xy 102.986122 -283.346561) (xy 102.970074 -283.297168) (xy 102.961949 -283.245873) (xy 102.68225 -283.245873)
			(xy 102.674128 -283.297157) (xy 102.658082 -283.346546) (xy 102.634508 -283.392818) (xy 102.603986 -283.434832)
			(xy 102.567269 -283.471555) (xy 102.525259 -283.502083) (xy 102.47899 -283.525664) (xy 102.429603 -283.541717)
			(xy 102.378313 -283.549847) (xy 102.352348 -283.55036) (xy 102.326713 -283.549859) (xy 102.276057 -283.54194)
			(xy 102.227234 -283.526286) (xy 102.181419 -283.503272) (xy 102.139712 -283.473451) (xy 102.103117 -283.437542)
			(xy 102.087426 -283.417264) (xy 101.67747 -283.417264) (xy 101.661765 -283.437531) (xy 101.62517 -283.473439)
			(xy 101.583466 -283.50326) (xy 101.537654 -283.526279) (xy 101.488835 -283.541942) (xy 101.438183 -283.549872)
			(xy 101.412548 -283.55036) (xy 101.386577 -283.549869) (xy 101.335273 -283.54175) (xy 101.285871 -283.525705)
			(xy 101.239587 -283.502128) (xy 101.197562 -283.471601) (xy 101.160831 -283.434874) (xy 101.130297 -283.392854)
			(xy 101.106714 -283.346574) (xy 101.090661 -283.297174) (xy 101.082535 -283.245871) (xy 100.802439 -283.245871)
			(xy 100.802439 -283.245873) (xy 100.794314 -283.297168) (xy 100.778266 -283.346561) (xy 100.754688 -283.392835)
			(xy 100.724162 -283.434851) (xy 100.687439 -283.471574) (xy 100.645423 -283.5021) (xy 100.599149 -283.525678)
			(xy 100.549756 -283.541726) (xy 100.498461 -283.549851) (xy 100.446527 -283.549851) (xy 100.395232 -283.541726)
			(xy 100.345839 -283.525678) (xy 100.299565 -283.5021) (xy 100.257549 -283.471574) (xy 100.220826 -283.434851)
			(xy 100.1903 -283.392835) (xy 100.166722 -283.346561) (xy 100.150674 -283.297168) (xy 100.142549 -283.245873)
			(xy 99.862893 -283.245873) (xy 99.854768 -283.297168) (xy 99.83872 -283.346561) (xy 99.815142 -283.392835)
			(xy 99.784616 -283.434851) (xy 99.747893 -283.471574) (xy 99.705877 -283.5021) (xy 99.659603 -283.525678)
			(xy 99.61021 -283.541726) (xy 99.558915 -283.549851) (xy 99.506981 -283.549851) (xy 99.455686 -283.541726)
			(xy 99.406293 -283.525678) (xy 99.360019 -283.5021) (xy 99.318003 -283.471574) (xy 99.28128 -283.434851)
			(xy 99.250754 -283.392835) (xy 99.227176 -283.346561) (xy 99.211128 -283.297168) (xy 99.203003 -283.245873)
			(xy 99.202494 -283.219906) (xy 98.923348 -283.219906) (xy 98.922839 -283.245873) (xy 98.914714 -283.297168)
			(xy 98.898666 -283.346561) (xy 98.875088 -283.392835) (xy 98.844562 -283.434851) (xy 98.807839 -283.471574)
			(xy 98.765823 -283.5021) (xy 98.719549 -283.525678) (xy 98.670156 -283.541726) (xy 98.618861 -283.549851)
			(xy 98.566927 -283.549851) (xy 98.515632 -283.541726) (xy 98.466239 -283.525678) (xy 98.419965 -283.5021)
			(xy 98.377949 -283.471574) (xy 98.341226 -283.434851) (xy 98.3107 -283.392835) (xy 98.287122 -283.346561)
			(xy 98.271074 -283.297168) (xy 98.262949 -283.245873) (xy 97.983039 -283.245873) (xy 97.974914 -283.297168)
			(xy 97.958866 -283.346561) (xy 97.935288 -283.392835) (xy 97.904762 -283.434851) (xy 97.868039 -283.471574)
			(xy 97.826023 -283.5021) (xy 97.779749 -283.525678) (xy 97.730356 -283.541726) (xy 97.679061 -283.549851)
			(xy 97.627127 -283.549851) (xy 97.575832 -283.541726) (xy 97.526439 -283.525678) (xy 97.480165 -283.5021)
			(xy 97.438149 -283.471574) (xy 97.401426 -283.434851) (xy 97.3709 -283.392835) (xy 97.347322 -283.346561)
			(xy 97.331274 -283.297168) (xy 97.323149 -283.245873) (xy 97.043493 -283.245873) (xy 97.035368 -283.297168)
			(xy 97.01932 -283.346561) (xy 96.995742 -283.392835) (xy 96.965216 -283.434851) (xy 96.928493 -283.471574)
			(xy 96.886477 -283.5021) (xy 96.840203 -283.525678) (xy 96.79081 -283.541726) (xy 96.739515 -283.549851)
			(xy 96.687581 -283.549851) (xy 96.636286 -283.541726) (xy 96.586893 -283.525678) (xy 96.540619 -283.5021)
			(xy 96.498603 -283.471574) (xy 96.46188 -283.434851) (xy 96.431354 -283.392835) (xy 96.407776 -283.346561)
			(xy 96.391728 -283.297168) (xy 96.383603 -283.245873) (xy 96.383094 -283.219906) (xy 96.383707 -283.191926)
			(xy 96.393157 -283.136768) (xy 96.40189 -283.110178) (xy 96.40951 -283.08808) (xy 96.205802 -282.735274)
			(xy 96.188784 -282.731972) (xy 96.181164 -282.730702) (xy 96.169734 -282.728416) (xy 96.159066 -282.73121)
			(xy 96.153663 -282.732757) (xy 96.143667 -282.737888) (xy 96.139254 -282.74137) (xy 96.079056 -282.791154)
			(xy 96.07077 -282.798754) (xy 96.061144 -282.819045) (xy 96.060514 -282.83027) (xy 96.060514 -283.042614)
			(xy 96.060677 -283.048625) (xy 96.063494 -283.060311) (xy 96.066102 -283.065728) (xy 96.078109 -283.089634)
			(xy 96.095094 -283.140361) (xy 96.103697 -283.193159) (xy 96.104202 -283.219906) (xy 96.104202 -283.228288)
			(xy 96.103948 -283.238448) (xy 96.10852 -283.249878) (xy 96.1105 -283.25424) (xy 96.11587 -283.262171)
			(xy 96.119188 -283.265626) (xy 96.740218 -283.886656) (xy 96.747003 -283.892548) (xy 96.763525 -283.899585)
			(xy 96.772476 -283.900372) (xy 96.778826 -283.900372) (xy 96.861122 -283.889958) (xy 96.898206 -283.865828)
			(xy 96.901508 -283.860748) (xy 96.903286 -283.857446) (xy 96.904048 -283.85643) (xy 96.919381 -283.833339)
			(xy 96.956479 -283.792159) (xy 96.999921 -283.757738) (xy 97.048492 -283.731038) (xy 97.100834 -283.712806)
			(xy 97.155481 -283.703552) (xy 97.183194 -283.703014) (xy 97.209183 -283.703497) (xy 97.260521 -283.711627)
			(xy 97.309955 -283.727689) (xy 97.356267 -283.751287) (xy 97.398318 -283.78184) (xy 97.435071 -283.818594)
			(xy 97.465621 -283.860646) (xy 97.489217 -283.90696) (xy 97.505276 -283.956395) (xy 97.513405 -284.007733)
			(xy 97.513902 -284.033722) (xy 97.513902 -284.03423) (xy 97.513423 -284.059276) (xy 97.505833 -284.10879)
			(xy 97.490864 -284.156593) (xy 97.468855 -284.201591) (xy 97.454974 -284.222444) (xy 97.447464 -284.234083)
			(xy 97.438369 -284.260235) (xy 97.436632 -284.287868) (xy 97.44238 -284.314953) (xy 97.455192 -284.339498)
			(xy 97.474125 -284.359701) (xy 97.497788 -284.374077) (xy 97.524443 -284.38157) (xy 97.538286 -284.381956)
			(xy 97.76841 -284.381956) (xy 97.782248 -284.381438) (xy 97.808884 -284.373905) (xy 97.832523 -284.359502)
			(xy 97.851432 -284.339286) (xy 97.864224 -284.314739) (xy 97.869963 -284.28766) (xy 97.868227 -284.260034)
			(xy 97.859143 -284.233886) (xy 97.851722 -284.22219) (xy 97.837775 -284.201329) (xy 97.815674 -284.15628)
			(xy 97.80064 -284.108407) (xy 97.793018 -284.058811) (xy 97.79254 -284.033722) (xy 97.793049 -284.007755)
			(xy 97.801174 -283.95646) (xy 97.817222 -283.907067) (xy 97.8408 -283.860793) (xy 97.871326 -283.818777)
			(xy 97.908049 -283.782054) (xy 97.950065 -283.751528) (xy 97.996339 -283.72795) (xy 98.045732 -283.711902)
			(xy 98.097027 -283.703777) (xy 98.148961 -283.703777) (xy 98.200256 -283.711902) (xy 98.249649 -283.72795)
			(xy 98.295923 -283.751528) (xy 98.337939 -283.782054) (xy 98.374662 -283.818777) (xy 98.405188 -283.860793)
			(xy 98.428766 -283.907067) (xy 98.444814 -283.95646) (xy 98.452939 -284.007755) (xy 98.453448 -284.033722)
			(xy 98.452965 -284.058811) (xy 98.445348 -284.108409) (xy 98.430321 -284.156286) (xy 98.40823 -284.201341)
			(xy 98.394266 -284.22219) (xy 98.386722 -284.233827) (xy 98.377569 -284.259995) (xy 98.375794 -284.28766)
			(xy 98.38153 -284.314783) (xy 98.394352 -284.339362) (xy 98.413314 -284.359584) (xy 98.437019 -284.373958)
			(xy 98.463717 -284.381423) (xy 98.477578 -284.381956) (xy 98.70821 -284.381956) (xy 98.722048 -284.381438)
			(xy 98.748684 -284.373905) (xy 98.772323 -284.359502) (xy 98.791232 -284.339286) (xy 98.804024 -284.314739)
			(xy 98.809763 -284.28766) (xy 98.808027 -284.260034) (xy 98.798943 -284.233886) (xy 98.791522 -284.22219)
			(xy 98.777575 -284.201329) (xy 98.755474 -284.15628) (xy 98.74044 -284.108407) (xy 98.732818 -284.058811)
			(xy 98.73234 -284.033722) (xy 98.732849 -284.007755) (xy 98.740974 -283.95646) (xy 98.757022 -283.907067)
			(xy 98.7806 -283.860793) (xy 98.811126 -283.818777) (xy 98.847849 -283.782054) (xy 98.889865 -283.751528)
			(xy 98.936139 -283.72795) (xy 98.985532 -283.711902) (xy 99.036827 -283.703777) (xy 99.088761 -283.703777)
			(xy 99.140056 -283.711902) (xy 99.189449 -283.72795) (xy 99.235723 -283.751528) (xy 99.277739 -283.782054)
			(xy 99.314462 -283.818777) (xy 99.344988 -283.860793) (xy 99.368566 -283.907067) (xy 99.384614 -283.95646)
			(xy 99.392739 -284.007755) (xy 99.393248 -284.033722) (xy 99.392765 -284.058811) (xy 99.385148 -284.108409)
			(xy 99.370121 -284.156286) (xy 99.34803 -284.201341) (xy 99.334066 -284.22219) (xy 99.326522 -284.233827)
			(xy 99.317369 -284.259995) (xy 99.315594 -284.28766) (xy 99.32133 -284.314783) (xy 99.334152 -284.339362)
			(xy 99.353114 -284.359584) (xy 99.376819 -284.373958) (xy 99.403517 -284.381423) (xy 99.417378 -284.381956)
			(xy 99.64801 -284.381956) (xy 99.661848 -284.381438) (xy 99.688484 -284.373905) (xy 99.712123 -284.359502)
			(xy 99.731032 -284.339286) (xy 99.743824 -284.314739) (xy 99.749563 -284.28766) (xy 99.747827 -284.260034)
			(xy 99.738743 -284.233886) (xy 99.731322 -284.22219) (xy 99.717375 -284.201329) (xy 99.695274 -284.15628)
			(xy 99.68024 -284.108407) (xy 99.672618 -284.058811) (xy 99.67214 -284.033722) (xy 99.672649 -284.007755)
			(xy 99.680774 -283.95646) (xy 99.696822 -283.907067) (xy 99.7204 -283.860793) (xy 99.750926 -283.818777)
			(xy 99.787649 -283.782054) (xy 99.829665 -283.751528) (xy 99.875939 -283.72795) (xy 99.925332 -283.711902)
			(xy 99.976627 -283.703777) (xy 100.028561 -283.703777) (xy 100.079856 -283.711902) (xy 100.129249 -283.72795)
			(xy 100.175523 -283.751528) (xy 100.217539 -283.782054) (xy 100.254262 -283.818777) (xy 100.284788 -283.860793)
			(xy 100.308366 -283.907067) (xy 100.324414 -283.95646) (xy 100.332539 -284.007755) (xy 100.333048 -284.033722)
			(xy 100.332565 -284.058811) (xy 100.324948 -284.108409) (xy 100.309921 -284.156286) (xy 100.28783 -284.201341)
			(xy 100.273866 -284.22219) (xy 100.266322 -284.233827) (xy 100.257169 -284.259995) (xy 100.255394 -284.28766)
			(xy 100.26113 -284.314783) (xy 100.273952 -284.339362) (xy 100.292914 -284.359584) (xy 100.316619 -284.373958)
			(xy 100.343317 -284.381423) (xy 100.357178 -284.381956) (xy 100.58781 -284.381956) (xy 100.601648 -284.381438)
			(xy 100.628284 -284.373905) (xy 100.651923 -284.359502) (xy 100.670832 -284.339286) (xy 100.683624 -284.314739)
			(xy 100.689363 -284.28766) (xy 100.687627 -284.260034) (xy 100.678543 -284.233886) (xy 100.671122 -284.22219)
			(xy 100.657175 -284.201329) (xy 100.635074 -284.15628) (xy 100.62004 -284.108407) (xy 100.612418 -284.058811)
			(xy 100.61194 -284.033722) (xy 100.612449 -284.007755) (xy 100.620574 -283.95646) (xy 100.636622 -283.907067)
			(xy 100.6602 -283.860793) (xy 100.690726 -283.818777) (xy 100.727449 -283.782054) (xy 100.769465 -283.751528)
			(xy 100.815739 -283.72795) (xy 100.865132 -283.711902) (xy 100.916427 -283.703777) (xy 100.968361 -283.703777)
			(xy 101.019656 -283.711902) (xy 101.069049 -283.72795) (xy 101.115323 -283.751528) (xy 101.157339 -283.782054)
			(xy 101.194062 -283.818777) (xy 101.224588 -283.860793) (xy 101.248166 -283.907067) (xy 101.264214 -283.95646)
			(xy 101.272339 -284.007755) (xy 101.272848 -284.033722) (xy 101.272365 -284.058811) (xy 101.264748 -284.108409)
			(xy 101.249721 -284.156286) (xy 101.22763 -284.201341) (xy 101.213666 -284.22219) (xy 101.206122 -284.233827)
			(xy 101.196969 -284.259995) (xy 101.195194 -284.28766) (xy 101.20093 -284.314783) (xy 101.213752 -284.339362)
			(xy 101.232714 -284.359584) (xy 101.256419 -284.373958) (xy 101.283117 -284.381423) (xy 101.296978 -284.381956)
			(xy 101.52761 -284.381956) (xy 101.541448 -284.381438) (xy 101.568084 -284.373905) (xy 101.591723 -284.359502)
			(xy 101.610632 -284.339286) (xy 101.623424 -284.314739) (xy 101.629163 -284.28766) (xy 101.627427 -284.260034)
			(xy 101.618343 -284.233886) (xy 101.610922 -284.22219) (xy 101.596975 -284.201329) (xy 101.574874 -284.15628)
			(xy 101.55984 -284.108407) (xy 101.552218 -284.058811) (xy 101.55174 -284.033722) (xy 101.552249 -284.007755)
			(xy 101.560374 -283.95646) (xy 101.576422 -283.907067) (xy 101.6 -283.860793) (xy 101.630526 -283.818777)
			(xy 101.667249 -283.782054) (xy 101.709265 -283.751528) (xy 101.755539 -283.72795) (xy 101.804932 -283.711902)
			(xy 101.856227 -283.703777) (xy 101.908161 -283.703777) (xy 101.959456 -283.711902) (xy 102.008849 -283.72795)
			(xy 102.055123 -283.751528) (xy 102.097139 -283.782054) (xy 102.133862 -283.818777) (xy 102.164388 -283.860793)
			(xy 102.187966 -283.907067) (xy 102.204014 -283.95646) (xy 102.212139 -284.007755) (xy 102.212648 -284.033722)
			(xy 102.212165 -284.058811) (xy 102.204548 -284.108409) (xy 102.189521 -284.156286) (xy 102.16743 -284.201341)
			(xy 102.153466 -284.22219) (xy 102.145922 -284.233827) (xy 102.136769 -284.259995) (xy 102.134994 -284.28766)
			(xy 102.14073 -284.314783) (xy 102.153552 -284.339362) (xy 102.172514 -284.359584) (xy 102.196219 -284.373958)
			(xy 102.222917 -284.381423) (xy 102.236778 -284.381956) (xy 102.46741 -284.381956) (xy 102.481248 -284.381438)
			(xy 102.507884 -284.373905) (xy 102.531523 -284.359502) (xy 102.550432 -284.339286) (xy 102.563224 -284.314739)
			(xy 102.568963 -284.28766) (xy 102.567227 -284.260034) (xy 102.558143 -284.233886) (xy 102.550722 -284.22219)
			(xy 102.536775 -284.201329) (xy 102.514674 -284.15628) (xy 102.49964 -284.108407) (xy 102.492018 -284.058811)
			(xy 102.49154 -284.033722) (xy 102.492049 -284.007755) (xy 102.500174 -283.95646) (xy 102.516222 -283.907067)
			(xy 102.5398 -283.860793) (xy 102.570326 -283.818777) (xy 102.607049 -283.782054) (xy 102.649065 -283.751528)
			(xy 102.695339 -283.72795) (xy 102.744732 -283.711902) (xy 102.796027 -283.703777) (xy 102.847961 -283.703777)
			(xy 102.899256 -283.711902) (xy 102.948649 -283.72795) (xy 102.994923 -283.751528) (xy 103.036939 -283.782054)
			(xy 103.073662 -283.818777) (xy 103.104188 -283.860793) (xy 103.127766 -283.907067) (xy 103.143814 -283.95646)
			(xy 103.151939 -284.007755) (xy 103.152448 -284.033722) (xy 103.151965 -284.058811) (xy 103.144348 -284.108409)
			(xy 103.129321 -284.156286) (xy 103.10723 -284.201341) (xy 103.093266 -284.22219) (xy 103.085722 -284.233827)
			(xy 103.076569 -284.259995) (xy 103.074794 -284.28766) (xy 103.08053 -284.314783) (xy 103.093352 -284.339362)
			(xy 103.112314 -284.359584) (xy 103.136019 -284.373958) (xy 103.162717 -284.381423) (xy 103.176578 -284.381956)
			(xy 103.40721 -284.381956) (xy 103.421048 -284.381438) (xy 103.447684 -284.373905) (xy 103.471323 -284.359502)
			(xy 103.490232 -284.339286) (xy 103.503024 -284.314739) (xy 103.508763 -284.28766) (xy 103.507027 -284.260034)
			(xy 103.497943 -284.233886) (xy 103.490522 -284.22219) (xy 103.476575 -284.201329) (xy 103.454474 -284.15628)
			(xy 103.43944 -284.108407) (xy 103.431818 -284.058811) (xy 103.43134 -284.033722) (xy 103.431849 -284.007755)
			(xy 103.439974 -283.95646) (xy 103.456022 -283.907067) (xy 103.4796 -283.860793) (xy 103.510126 -283.818777)
			(xy 103.546849 -283.782054) (xy 103.588865 -283.751528) (xy 103.635139 -283.72795) (xy 103.684532 -283.711902)
			(xy 103.735827 -283.703777) (xy 103.787761 -283.703777) (xy 103.839056 -283.711902) (xy 103.888449 -283.72795)
			(xy 103.934723 -283.751528) (xy 103.976739 -283.782054) (xy 104.013462 -283.818777) (xy 104.043988 -283.860793)
			(xy 104.067566 -283.907067) (xy 104.083614 -283.95646) (xy 104.091739 -284.007755) (xy 104.092248 -284.033722)
			(xy 104.091825 -284.057993) (xy 104.091574 -284.059689) (xy 104.371649 -284.059689) (xy 104.371649 -284.007755)
			(xy 104.379774 -283.95646) (xy 104.395822 -283.907067) (xy 104.4194 -283.860793) (xy 104.449926 -283.818777)
			(xy 104.486649 -283.782054) (xy 104.528665 -283.751528) (xy 104.574939 -283.72795) (xy 104.624332 -283.711902)
			(xy 104.675627 -283.703777) (xy 104.727561 -283.703777) (xy 104.778856 -283.711902) (xy 104.828249 -283.72795)
			(xy 104.874523 -283.751528) (xy 104.916539 -283.782054) (xy 104.953262 -283.818777) (xy 104.983788 -283.860793)
			(xy 105.007366 -283.907067) (xy 105.023414 -283.95646) (xy 105.031539 -284.007755) (xy 105.032048 -284.033722)
			(xy 105.031539 -284.059689) (xy 105.311449 -284.059689) (xy 105.311449 -284.007755) (xy 105.319574 -283.95646)
			(xy 105.335622 -283.907067) (xy 105.3592 -283.860793) (xy 105.389726 -283.818777) (xy 105.426449 -283.782054)
			(xy 105.468465 -283.751528) (xy 105.514739 -283.72795) (xy 105.564132 -283.711902) (xy 105.615427 -283.703777)
			(xy 105.667361 -283.703777) (xy 105.718656 -283.711902) (xy 105.768049 -283.72795) (xy 105.814323 -283.751528)
			(xy 105.856339 -283.782054) (xy 105.893062 -283.818777) (xy 105.923588 -283.860793) (xy 105.947166 -283.907067)
			(xy 105.963214 -283.95646) (xy 105.971339 -284.007755) (xy 105.971848 -284.033722) (xy 105.971339 -284.059689)
			(xy 107.191049 -284.059689) (xy 107.191049 -284.007755) (xy 107.199174 -283.95646) (xy 107.215222 -283.907067)
			(xy 107.2388 -283.860793) (xy 107.269326 -283.818777) (xy 107.306049 -283.782054) (xy 107.348065 -283.751528)
			(xy 107.394339 -283.72795) (xy 107.443732 -283.711902) (xy 107.495027 -283.703777) (xy 107.546961 -283.703777)
			(xy 107.598256 -283.711902) (xy 107.647649 -283.72795) (xy 107.693923 -283.751528) (xy 107.735939 -283.782054)
			(xy 107.772662 -283.818777) (xy 107.803188 -283.860793) (xy 107.826766 -283.907067) (xy 107.842814 -283.95646)
			(xy 107.850939 -284.007755) (xy 107.851448 -284.033722) (xy 107.850939 -284.059689) (xy 110.010449 -284.059689)
			(xy 110.010449 -284.007755) (xy 110.018574 -283.95646) (xy 110.034622 -283.907067) (xy 110.0582 -283.860793)
			(xy 110.088726 -283.818777) (xy 110.125449 -283.782054) (xy 110.167465 -283.751528) (xy 110.213739 -283.72795)
			(xy 110.263132 -283.711902) (xy 110.314427 -283.703777) (xy 110.366361 -283.703777) (xy 110.417656 -283.711902)
			(xy 110.467049 -283.72795) (xy 110.513323 -283.751528) (xy 110.555339 -283.782054) (xy 110.592062 -283.818777)
			(xy 110.622588 -283.860793) (xy 110.646166 -283.907067) (xy 110.662214 -283.95646) (xy 110.670339 -284.007755)
			(xy 110.670848 -284.033722) (xy 110.670339 -284.059689) (xy 118.468649 -284.059689) (xy 118.468649 -284.007755)
			(xy 118.476774 -283.95646) (xy 118.492822 -283.907067) (xy 118.5164 -283.860793) (xy 118.546926 -283.818777)
			(xy 118.583649 -283.782054) (xy 118.625665 -283.751528) (xy 118.671939 -283.72795) (xy 118.721332 -283.711902)
			(xy 118.772627 -283.703777) (xy 118.824561 -283.703777) (xy 118.875856 -283.711902) (xy 118.925249 -283.72795)
			(xy 118.971523 -283.751528) (xy 119.013539 -283.782054) (xy 119.050262 -283.818777) (xy 119.080788 -283.860793)
			(xy 119.104366 -283.907067) (xy 119.120414 -283.95646) (xy 119.128539 -284.007755) (xy 119.129048 -284.033722)
			(xy 119.128539 -284.059689) (xy 119.120414 -284.110984) (xy 119.104366 -284.160377) (xy 119.080788 -284.206651)
			(xy 119.050262 -284.248667) (xy 119.013539 -284.28539) (xy 118.971523 -284.315916) (xy 118.925249 -284.339494)
			(xy 118.875856 -284.355542) (xy 118.824561 -284.363667) (xy 118.772627 -284.363667) (xy 118.721332 -284.355542)
			(xy 118.671939 -284.339494) (xy 118.625665 -284.315916) (xy 118.583649 -284.28539) (xy 118.546926 -284.248667)
			(xy 118.5164 -284.206651) (xy 118.492822 -284.160377) (xy 118.476774 -284.110984) (xy 118.468649 -284.059689)
			(xy 110.670339 -284.059689) (xy 110.662214 -284.110984) (xy 110.646166 -284.160377) (xy 110.622588 -284.206651)
			(xy 110.592062 -284.248667) (xy 110.555339 -284.28539) (xy 110.513323 -284.315916) (xy 110.467049 -284.339494)
			(xy 110.417656 -284.355542) (xy 110.366361 -284.363667) (xy 110.314427 -284.363667) (xy 110.263132 -284.355542)
			(xy 110.213739 -284.339494) (xy 110.167465 -284.315916) (xy 110.125449 -284.28539) (xy 110.088726 -284.248667)
			(xy 110.0582 -284.206651) (xy 110.034622 -284.160377) (xy 110.018574 -284.110984) (xy 110.010449 -284.059689)
			(xy 107.850939 -284.059689) (xy 107.842814 -284.110984) (xy 107.826766 -284.160377) (xy 107.803188 -284.206651)
			(xy 107.772662 -284.248667) (xy 107.735939 -284.28539) (xy 107.693923 -284.315916) (xy 107.647649 -284.339494)
			(xy 107.598256 -284.355542) (xy 107.546961 -284.363667) (xy 107.495027 -284.363667) (xy 107.443732 -284.355542)
			(xy 107.394339 -284.339494) (xy 107.348065 -284.315916) (xy 107.306049 -284.28539) (xy 107.269326 -284.248667)
			(xy 107.2388 -284.206651) (xy 107.215222 -284.160377) (xy 107.199174 -284.110984) (xy 107.191049 -284.059689)
			(xy 105.971339 -284.059689) (xy 105.963214 -284.110984) (xy 105.947166 -284.160377) (xy 105.923588 -284.206651)
			(xy 105.893062 -284.248667) (xy 105.856339 -284.28539) (xy 105.814323 -284.315916) (xy 105.768049 -284.339494)
			(xy 105.718656 -284.355542) (xy 105.667361 -284.363667) (xy 105.615427 -284.363667) (xy 105.564132 -284.355542)
			(xy 105.514739 -284.339494) (xy 105.468465 -284.315916) (xy 105.426449 -284.28539) (xy 105.389726 -284.248667)
			(xy 105.3592 -284.206651) (xy 105.335622 -284.160377) (xy 105.319574 -284.110984) (xy 105.311449 -284.059689)
			(xy 105.031539 -284.059689) (xy 105.023414 -284.110984) (xy 105.007366 -284.160377) (xy 104.983788 -284.206651)
			(xy 104.953262 -284.248667) (xy 104.916539 -284.28539) (xy 104.874523 -284.315916) (xy 104.828249 -284.339494)
			(xy 104.778856 -284.355542) (xy 104.727561 -284.363667) (xy 104.675627 -284.363667) (xy 104.624332 -284.355542)
			(xy 104.574939 -284.339494) (xy 104.528665 -284.315916) (xy 104.486649 -284.28539) (xy 104.449926 -284.248667)
			(xy 104.4194 -284.206651) (xy 104.395822 -284.160377) (xy 104.379774 -284.110984) (xy 104.371649 -284.059689)
			(xy 104.091574 -284.059689) (xy 104.08473 -284.106014) (xy 104.070683 -284.152479) (xy 104.049985 -284.196387)
			(xy 104.023082 -284.236793) (xy 103.990554 -284.272825) (xy 103.953102 -284.303707) (xy 103.911533 -284.328774)
			(xy 103.889302 -284.338522) (xy 103.876337 -284.344458) (xy 103.854099 -284.362287) (xy 103.837652 -284.385567)
			(xy 103.828277 -284.412483) (xy 103.826703 -284.440943) (xy 103.833053 -284.468729) (xy 103.846832 -284.49368)
			(xy 103.856536 -284.50413) (xy 103.980488 -284.628082) (xy 104.016302 -284.597348) (xy 104.034373 -284.582299)
			(xy 104.07397 -284.556931) (xy 104.116764 -284.537433) (xy 104.161889 -284.524199) (xy 104.208435 -284.517497)
			(xy 104.231948 -284.517084) (xy 104.257912 -284.517597) (xy 104.309199 -284.525727) (xy 104.358582 -284.541781)
			(xy 104.404847 -284.565362) (xy 104.446853 -284.595889) (xy 104.483567 -284.632612) (xy 104.514083 -284.674627)
			(xy 104.537652 -284.720897) (xy 104.553693 -284.770285) (xy 104.56181 -284.821574) (xy 104.562402 -284.847538)
			(xy 104.561928 -284.873009) (xy 104.561851 -284.873505) (xy 104.841549 -284.873505) (xy 104.841549 -284.821571)
			(xy 104.849674 -284.770276) (xy 104.865722 -284.720883) (xy 104.8893 -284.674609) (xy 104.919826 -284.632593)
			(xy 104.956549 -284.59587) (xy 104.998565 -284.565344) (xy 105.044839 -284.541766) (xy 105.094232 -284.525718)
			(xy 105.145527 -284.517593) (xy 105.197461 -284.517593) (xy 105.248756 -284.525718) (xy 105.298149 -284.541766)
			(xy 105.344423 -284.565344) (xy 105.386439 -284.59587) (xy 105.423162 -284.632593) (xy 105.453688 -284.674609)
			(xy 105.477266 -284.720883) (xy 105.493314 -284.770276) (xy 105.501439 -284.821571) (xy 105.501948 -284.847538)
			(xy 105.501439 -284.873505) (xy 113.299749 -284.873505) (xy 113.299749 -284.821571) (xy 113.307874 -284.770276)
			(xy 113.323922 -284.720883) (xy 113.3475 -284.674609) (xy 113.378026 -284.632593) (xy 113.414749 -284.59587)
			(xy 113.456765 -284.565344) (xy 113.503039 -284.541766) (xy 113.552432 -284.525718) (xy 113.603727 -284.517593)
			(xy 113.655661 -284.517593) (xy 113.706956 -284.525718) (xy 113.756349 -284.541766) (xy 113.802623 -284.565344)
			(xy 113.844639 -284.59587) (xy 113.881362 -284.632593) (xy 113.911888 -284.674609) (xy 113.935466 -284.720883)
			(xy 113.951514 -284.770276) (xy 113.959639 -284.821571) (xy 113.960148 -284.847538) (xy 113.959639 -284.873505)
			(xy 116.119403 -284.873505) (xy 116.119403 -284.821571) (xy 116.127528 -284.770276) (xy 116.143576 -284.720883)
			(xy 116.167154 -284.674609) (xy 116.19768 -284.632593) (xy 116.234403 -284.59587) (xy 116.276419 -284.565344)
			(xy 116.322693 -284.541766) (xy 116.372086 -284.525718) (xy 116.423381 -284.517593) (xy 116.475315 -284.517593)
			(xy 116.52661 -284.525718) (xy 116.576003 -284.541766) (xy 116.622277 -284.565344) (xy 116.664293 -284.59587)
			(xy 116.701016 -284.632593) (xy 116.731542 -284.674609) (xy 116.75512 -284.720883) (xy 116.771168 -284.770276)
			(xy 116.779293 -284.821571) (xy 116.779802 -284.847538) (xy 116.779293 -284.873505) (xy 117.999003 -284.873505)
			(xy 117.999003 -284.821571) (xy 118.007128 -284.770276) (xy 118.023176 -284.720883) (xy 118.046754 -284.674609)
			(xy 118.07728 -284.632593) (xy 118.114003 -284.59587) (xy 118.156019 -284.565344) (xy 118.202293 -284.541766)
			(xy 118.251686 -284.525718) (xy 118.302981 -284.517593) (xy 118.354915 -284.517593) (xy 118.40621 -284.525718)
			(xy 118.455603 -284.541766) (xy 118.501877 -284.565344) (xy 118.543893 -284.59587) (xy 118.580616 -284.632593)
			(xy 118.611142 -284.674609) (xy 118.63472 -284.720883) (xy 118.650768 -284.770276) (xy 118.658893 -284.821571)
			(xy 118.659402 -284.847538) (xy 118.658893 -284.873505) (xy 118.650768 -284.9248) (xy 118.63472 -284.974193)
			(xy 118.611142 -285.020467) (xy 118.580616 -285.062483) (xy 118.543893 -285.099206) (xy 118.501877 -285.129732)
			(xy 118.455603 -285.15331) (xy 118.40621 -285.169358) (xy 118.354915 -285.177483) (xy 118.302981 -285.177483)
			(xy 118.251686 -285.169358) (xy 118.202293 -285.15331) (xy 118.156019 -285.129732) (xy 118.114003 -285.099206)
			(xy 118.07728 -285.062483) (xy 118.046754 -285.020467) (xy 118.023176 -284.974193) (xy 118.007128 -284.9248)
			(xy 117.999003 -284.873505) (xy 116.779293 -284.873505) (xy 116.771168 -284.9248) (xy 116.75512 -284.974193)
			(xy 116.731542 -285.020467) (xy 116.701016 -285.062483) (xy 116.664293 -285.099206) (xy 116.622277 -285.129732)
			(xy 116.576003 -285.15331) (xy 116.52661 -285.169358) (xy 116.475315 -285.177483) (xy 116.423381 -285.177483)
			(xy 116.372086 -285.169358) (xy 116.322693 -285.15331) (xy 116.276419 -285.129732) (xy 116.234403 -285.099206)
			(xy 116.19768 -285.062483) (xy 116.167154 -285.020467) (xy 116.143576 -284.974193) (xy 116.127528 -284.9248)
			(xy 116.119403 -284.873505) (xy 113.959639 -284.873505) (xy 113.951514 -284.9248) (xy 113.935466 -284.974193)
			(xy 113.911888 -285.020467) (xy 113.881362 -285.062483) (xy 113.844639 -285.099206) (xy 113.802623 -285.129732)
			(xy 113.756349 -285.15331) (xy 113.706956 -285.169358) (xy 113.655661 -285.177483) (xy 113.603727 -285.177483)
			(xy 113.552432 -285.169358) (xy 113.503039 -285.15331) (xy 113.456765 -285.129732) (xy 113.414749 -285.099206)
			(xy 113.378026 -285.062483) (xy 113.3475 -285.020467) (xy 113.323922 -284.974193) (xy 113.307874 -284.9248)
			(xy 113.299749 -284.873505) (xy 105.501439 -284.873505) (xy 105.493314 -284.9248) (xy 105.477266 -284.974193)
			(xy 105.453688 -285.020467) (xy 105.423162 -285.062483) (xy 105.386439 -285.099206) (xy 105.344423 -285.129732)
			(xy 105.298149 -285.15331) (xy 105.248756 -285.169358) (xy 105.197461 -285.177483) (xy 105.145527 -285.177483)
			(xy 105.094232 -285.169358) (xy 105.044839 -285.15331) (xy 104.998565 -285.129732) (xy 104.956549 -285.099206)
			(xy 104.919826 -285.062483) (xy 104.8893 -285.020467) (xy 104.865722 -284.974193) (xy 104.849674 -284.9248)
			(xy 104.841549 -284.873505) (xy 104.561851 -284.873505) (xy 104.554103 -284.923347) (xy 104.538645 -284.971888)
			(xy 104.515919 -285.01748) (xy 104.486465 -285.059044) (xy 104.45098 -285.095595) (xy 104.410306 -285.126266)
			(xy 104.365405 -285.150331) (xy 104.317344 -285.167218) (xy 104.2924 -285.172404) (xy 104.26954 -285.176722)
			(xy 104.21112 -285.27756) (xy 104.21112 -285.687321) (xy 104.371649 -285.687321) (xy 104.371649 -285.635387)
			(xy 104.379774 -285.584092) (xy 104.395822 -285.534699) (xy 104.4194 -285.488425) (xy 104.449926 -285.446409)
			(xy 104.486649 -285.409686) (xy 104.528665 -285.37916) (xy 104.574939 -285.355582) (xy 104.624332 -285.339534)
			(xy 104.675627 -285.331409) (xy 104.727561 -285.331409) (xy 104.778856 -285.339534) (xy 104.828249 -285.355582)
			(xy 104.874523 -285.37916) (xy 104.916539 -285.409686) (xy 104.953262 -285.446409) (xy 104.983788 -285.488425)
			(xy 105.007366 -285.534699) (xy 105.023414 -285.584092) (xy 105.031539 -285.635387) (xy 105.032048 -285.661354)
			(xy 105.031539 -285.687321) (xy 107.191049 -285.687321) (xy 107.191049 -285.635387) (xy 107.199174 -285.584092)
			(xy 107.215222 -285.534699) (xy 107.2388 -285.488425) (xy 107.269326 -285.446409) (xy 107.306049 -285.409686)
			(xy 107.348065 -285.37916) (xy 107.394339 -285.355582) (xy 107.443732 -285.339534) (xy 107.495027 -285.331409)
			(xy 107.546961 -285.331409) (xy 107.598256 -285.339534) (xy 107.647649 -285.355582) (xy 107.693923 -285.37916)
			(xy 107.735939 -285.409686) (xy 107.772662 -285.446409) (xy 107.803188 -285.488425) (xy 107.826766 -285.534699)
			(xy 107.842814 -285.584092) (xy 107.850939 -285.635387) (xy 107.851448 -285.661354) (xy 107.850939 -285.687321)
			(xy 110.010449 -285.687321) (xy 110.010449 -285.635387) (xy 110.018574 -285.584092) (xy 110.034622 -285.534699)
			(xy 110.0582 -285.488425) (xy 110.088726 -285.446409) (xy 110.125449 -285.409686) (xy 110.167465 -285.37916)
			(xy 110.213739 -285.355582) (xy 110.263132 -285.339534) (xy 110.314427 -285.331409) (xy 110.366361 -285.331409)
			(xy 110.417656 -285.339534) (xy 110.467049 -285.355582) (xy 110.513323 -285.37916) (xy 110.555339 -285.409686)
			(xy 110.592062 -285.446409) (xy 110.622588 -285.488425) (xy 110.646166 -285.534699) (xy 110.662214 -285.584092)
			(xy 110.670339 -285.635387) (xy 110.670848 -285.661354) (xy 110.670339 -285.687321) (xy 118.468903 -285.687321)
			(xy 118.468903 -285.635387) (xy 118.477028 -285.584092) (xy 118.493076 -285.534699) (xy 118.516654 -285.488425)
			(xy 118.54718 -285.446409) (xy 118.583903 -285.409686) (xy 118.625919 -285.37916) (xy 118.672193 -285.355582)
			(xy 118.721586 -285.339534) (xy 118.772881 -285.331409) (xy 118.824815 -285.331409) (xy 118.87611 -285.339534)
			(xy 118.925503 -285.355582) (xy 118.971777 -285.37916) (xy 119.013793 -285.409686) (xy 119.050516 -285.446409)
			(xy 119.081042 -285.488425) (xy 119.10462 -285.534699) (xy 119.120668 -285.584092) (xy 119.128793 -285.635387)
			(xy 119.129302 -285.661354) (xy 119.128793 -285.687321) (xy 119.120668 -285.738616) (xy 119.10462 -285.788009)
			(xy 119.081042 -285.834283) (xy 119.050516 -285.876299) (xy 119.013793 -285.913022) (xy 118.971777 -285.943548)
			(xy 118.925503 -285.967126) (xy 118.87611 -285.983174) (xy 118.824815 -285.991299) (xy 118.772881 -285.991299)
			(xy 118.721586 -285.983174) (xy 118.672193 -285.967126) (xy 118.625919 -285.943548) (xy 118.583903 -285.913022)
			(xy 118.54718 -285.876299) (xy 118.516654 -285.834283) (xy 118.493076 -285.788009) (xy 118.477028 -285.738616)
			(xy 118.468903 -285.687321) (xy 110.670339 -285.687321) (xy 110.662214 -285.738616) (xy 110.646166 -285.788009)
			(xy 110.622588 -285.834283) (xy 110.592062 -285.876299) (xy 110.555339 -285.913022) (xy 110.513323 -285.943548)
			(xy 110.467049 -285.967126) (xy 110.417656 -285.983174) (xy 110.366361 -285.991299) (xy 110.314427 -285.991299)
			(xy 110.263132 -285.983174) (xy 110.213739 -285.967126) (xy 110.167465 -285.943548) (xy 110.125449 -285.913022)
			(xy 110.088726 -285.876299) (xy 110.0582 -285.834283) (xy 110.034622 -285.788009) (xy 110.018574 -285.738616)
			(xy 110.010449 -285.687321) (xy 107.850939 -285.687321) (xy 107.842814 -285.738616) (xy 107.826766 -285.788009)
			(xy 107.803188 -285.834283) (xy 107.772662 -285.876299) (xy 107.735939 -285.913022) (xy 107.693923 -285.943548)
			(xy 107.647649 -285.967126) (xy 107.598256 -285.983174) (xy 107.546961 -285.991299) (xy 107.495027 -285.991299)
			(xy 107.443732 -285.983174) (xy 107.394339 -285.967126) (xy 107.348065 -285.943548) (xy 107.306049 -285.913022)
			(xy 107.269326 -285.876299) (xy 107.2388 -285.834283) (xy 107.215222 -285.788009) (xy 107.199174 -285.738616)
			(xy 107.191049 -285.687321) (xy 105.031539 -285.687321) (xy 105.023414 -285.738616) (xy 105.007366 -285.788009)
			(xy 104.983788 -285.834283) (xy 104.953262 -285.876299) (xy 104.916539 -285.913022) (xy 104.874523 -285.943548)
			(xy 104.828249 -285.967126) (xy 104.778856 -285.983174) (xy 104.727561 -285.991299) (xy 104.675627 -285.991299)
			(xy 104.624332 -285.983174) (xy 104.574939 -285.967126) (xy 104.528665 -285.943548) (xy 104.486649 -285.913022)
			(xy 104.449926 -285.876299) (xy 104.4194 -285.834283) (xy 104.395822 -285.788009) (xy 104.379774 -285.738616)
			(xy 104.371649 -285.687321) (xy 104.21112 -285.687321) (xy 104.21112 -286.095186) (xy 104.211575 -286.104691)
			(xy 104.218599 -286.122362) (xy 104.231549 -286.136287) (xy 104.248664 -286.144574) (xy 104.25811 -286.145732)
			(xy 104.282658 -286.148157) (xy 104.330696 -286.159358) (xy 104.376536 -286.177572) (xy 104.419162 -286.202394)
			(xy 104.457626 -286.233274) (xy 104.491077 -286.269526) (xy 104.51877 -286.310345) (xy 104.540091 -286.354825)
			(xy 104.554567 -286.401979) (xy 104.561877 -286.450761) (xy 104.562402 -286.475424) (xy 104.561957 -286.500218)
			(xy 104.56178 -286.501391) (xy 104.841803 -286.501391) (xy 104.841803 -286.449457) (xy 104.849928 -286.398162)
			(xy 104.865976 -286.348769) (xy 104.889554 -286.302495) (xy 104.92008 -286.260479) (xy 104.956803 -286.223756)
			(xy 104.998819 -286.19323) (xy 105.045093 -286.169652) (xy 105.094486 -286.153604) (xy 105.145781 -286.145479)
			(xy 105.197715 -286.145479) (xy 105.24901 -286.153604) (xy 105.298403 -286.169652) (xy 105.344677 -286.19323)
			(xy 105.386693 -286.223756) (xy 105.423416 -286.260479) (xy 105.453942 -286.302495) (xy 105.47752 -286.348769)
			(xy 105.493568 -286.398162) (xy 105.501693 -286.449457) (xy 105.502202 -286.475424) (xy 105.501693 -286.501391)
			(xy 113.299749 -286.501391) (xy 113.299749 -286.449457) (xy 113.307874 -286.398162) (xy 113.323922 -286.348769)
			(xy 113.3475 -286.302495) (xy 113.378026 -286.260479) (xy 113.414749 -286.223756) (xy 113.456765 -286.19323)
			(xy 113.503039 -286.169652) (xy 113.552432 -286.153604) (xy 113.603727 -286.145479) (xy 113.655661 -286.145479)
			(xy 113.706956 -286.153604) (xy 113.756349 -286.169652) (xy 113.802623 -286.19323) (xy 113.844639 -286.223756)
			(xy 113.881362 -286.260479) (xy 113.911888 -286.302495) (xy 113.935466 -286.348769) (xy 113.951514 -286.398162)
			(xy 113.959639 -286.449457) (xy 113.960148 -286.475424) (xy 113.959639 -286.501391) (xy 116.119403 -286.501391)
			(xy 116.119403 -286.449457) (xy 116.127528 -286.398162) (xy 116.143576 -286.348769) (xy 116.167154 -286.302495)
			(xy 116.19768 -286.260479) (xy 116.234403 -286.223756) (xy 116.276419 -286.19323) (xy 116.322693 -286.169652)
			(xy 116.372086 -286.153604) (xy 116.423381 -286.145479) (xy 116.475315 -286.145479) (xy 116.52661 -286.153604)
			(xy 116.576003 -286.169652) (xy 116.622277 -286.19323) (xy 116.664293 -286.223756) (xy 116.701016 -286.260479)
			(xy 116.731542 -286.302495) (xy 116.75512 -286.348769) (xy 116.771168 -286.398162) (xy 116.779293 -286.449457)
			(xy 116.779802 -286.475424) (xy 116.779293 -286.501391) (xy 116.771168 -286.552686) (xy 116.75512 -286.602079)
			(xy 116.731542 -286.648353) (xy 116.701016 -286.690369) (xy 116.664293 -286.727092) (xy 116.622277 -286.757618)
			(xy 116.576003 -286.781196) (xy 116.52661 -286.797244) (xy 116.475315 -286.805369) (xy 116.423381 -286.805369)
			(xy 116.372086 -286.797244) (xy 116.322693 -286.781196) (xy 116.276419 -286.757618) (xy 116.234403 -286.727092)
			(xy 116.19768 -286.690369) (xy 116.167154 -286.648353) (xy 116.143576 -286.602079) (xy 116.127528 -286.552686)
			(xy 116.119403 -286.501391) (xy 113.959639 -286.501391) (xy 113.951514 -286.552686) (xy 113.935466 -286.602079)
			(xy 113.911888 -286.648353) (xy 113.881362 -286.690369) (xy 113.844639 -286.727092) (xy 113.802623 -286.757618)
			(xy 113.756349 -286.781196) (xy 113.706956 -286.797244) (xy 113.655661 -286.805369) (xy 113.603727 -286.805369)
			(xy 113.552432 -286.797244) (xy 113.503039 -286.781196) (xy 113.456765 -286.757618) (xy 113.414749 -286.727092)
			(xy 113.378026 -286.690369) (xy 113.3475 -286.648353) (xy 113.323922 -286.602079) (xy 113.307874 -286.552686)
			(xy 113.299749 -286.501391) (xy 105.501693 -286.501391) (xy 105.493568 -286.552686) (xy 105.47752 -286.602079)
			(xy 105.453942 -286.648353) (xy 105.423416 -286.690369) (xy 105.386693 -286.727092) (xy 105.344677 -286.757618)
			(xy 105.298403 -286.781196) (xy 105.24901 -286.797244) (xy 105.197715 -286.805369) (xy 105.145781 -286.805369)
			(xy 105.094486 -286.797244) (xy 105.045093 -286.781196) (xy 104.998819 -286.757618) (xy 104.956803 -286.727092)
			(xy 104.92008 -286.690369) (xy 104.889554 -286.648353) (xy 104.865976 -286.602079) (xy 104.849928 -286.552686)
			(xy 104.841803 -286.501391) (xy 104.56178 -286.501391) (xy 104.55455 -286.549251) (xy 104.539904 -286.596628)
			(xy 104.518349 -286.641287) (xy 104.490367 -286.682226) (xy 104.456586 -286.71853) (xy 104.417764 -286.749382)
			(xy 104.37477 -286.774092) (xy 104.351836 -286.783526) (xy 104.348788 -286.784796) (xy 104.342685 -286.787911)
			(xy 104.332258 -286.796791) (xy 104.328214 -286.802322) (xy 104.323896 -286.808418) (xy 104.319578 -286.822896)
			(xy 104.319578 -286.96412) (xy 104.321153 -286.97674) (xy 104.33475 -286.998194) (xy 104.345486 -287.005014)
			(xy 104.349042 -287.006792) (xy 104.432862 -287.0454) (xy 104.433116 -287.0454) (xy 104.441817 -287.048909)
			(xy 104.460527 -287.050039) (xy 104.478387 -287.044349) (xy 104.485948 -287.038796) (xy 104.487218 -287.03778)
			(xy 104.505246 -287.022895) (xy 104.544704 -286.997823) (xy 104.587303 -286.978565) (xy 104.632191 -286.965506)
			(xy 104.678473 -286.958907) (xy 104.701848 -286.958532) (xy 104.727832 -286.959046) (xy 104.779158 -286.967182)
			(xy 104.828579 -286.983248) (xy 104.874879 -287.006847) (xy 104.916917 -287.037398) (xy 104.953659 -287.07415)
			(xy 104.984199 -287.116196) (xy 105.007786 -287.162502) (xy 105.023838 -287.211928) (xy 105.031961 -287.263256)
			(xy 105.032556 -287.28924) (xy 105.031989 -287.315207) (xy 107.191049 -287.315207) (xy 107.191049 -287.263273)
			(xy 107.199174 -287.211978) (xy 107.215222 -287.162585) (xy 107.2388 -287.116311) (xy 107.269326 -287.074295)
			(xy 107.306049 -287.037572) (xy 107.348065 -287.007046) (xy 107.394339 -286.983468) (xy 107.443732 -286.96742)
			(xy 107.495027 -286.959295) (xy 107.546961 -286.959295) (xy 107.598256 -286.96742) (xy 107.647649 -286.983468)
			(xy 107.693923 -287.007046) (xy 107.735939 -287.037572) (xy 107.772662 -287.074295) (xy 107.803188 -287.116311)
			(xy 107.826766 -287.162585) (xy 107.842814 -287.211978) (xy 107.850939 -287.263273) (xy 107.851448 -287.28924)
			(xy 107.850939 -287.315207) (xy 110.010449 -287.315207) (xy 110.010449 -287.263273) (xy 110.018574 -287.211978)
			(xy 110.034622 -287.162585) (xy 110.0582 -287.116311) (xy 110.088726 -287.074295) (xy 110.125449 -287.037572)
			(xy 110.167465 -287.007046) (xy 110.213739 -286.983468) (xy 110.263132 -286.96742) (xy 110.314427 -286.959295)
			(xy 110.366361 -286.959295) (xy 110.417656 -286.96742) (xy 110.467049 -286.983468) (xy 110.513323 -287.007046)
			(xy 110.555339 -287.037572) (xy 110.592062 -287.074295) (xy 110.622588 -287.116311) (xy 110.646166 -287.162585)
			(xy 110.662214 -287.211978) (xy 110.670339 -287.263273) (xy 110.670848 -287.28924) (xy 110.670339 -287.315207)
			(xy 110.662214 -287.366502) (xy 110.646166 -287.415895) (xy 110.622588 -287.462169) (xy 110.592062 -287.504185)
			(xy 110.555339 -287.540908) (xy 110.513323 -287.571434) (xy 110.467049 -287.595012) (xy 110.417656 -287.61106)
			(xy 110.366361 -287.619185) (xy 110.314427 -287.619185) (xy 110.263132 -287.61106) (xy 110.213739 -287.595012)
			(xy 110.167465 -287.571434) (xy 110.125449 -287.540908) (xy 110.088726 -287.504185) (xy 110.0582 -287.462169)
			(xy 110.034622 -287.415895) (xy 110.018574 -287.366502) (xy 110.010449 -287.315207) (xy 107.850939 -287.315207)
			(xy 107.842814 -287.366502) (xy 107.826766 -287.415895) (xy 107.803188 -287.462169) (xy 107.772662 -287.504185)
			(xy 107.735939 -287.540908) (xy 107.693923 -287.571434) (xy 107.647649 -287.595012) (xy 107.598256 -287.61106)
			(xy 107.546961 -287.619185) (xy 107.495027 -287.619185) (xy 107.443732 -287.61106) (xy 107.394339 -287.595012)
			(xy 107.348065 -287.571434) (xy 107.306049 -287.540908) (xy 107.269326 -287.504185) (xy 107.2388 -287.462169)
			(xy 107.215222 -287.415895) (xy 107.199174 -287.366502) (xy 107.191049 -287.315207) (xy 105.031989 -287.315207)
			(xy 105.031926 -287.31807) (xy 105.021915 -287.374856) (xy 105.002204 -287.429043) (xy 104.98836 -287.45434)
			(xy 104.986328 -287.45815) (xy 104.979216 -287.483804) (xy 104.989884 -287.515046) (xy 104.994456 -287.521142)
			(xy 104.994964 -287.52165) (xy 104.99852 -287.526222) (xy 105.022108 -287.558255) (xy 105.064496 -287.625579)
			(xy 105.10116 -287.696183) (xy 105.116884 -287.732724) (xy 105.12044 -287.740852) (xy 105.166668 -287.772094)
			(xy 105.174288 -287.772348) (xy 105.200146 -287.773043) (xy 105.251177 -287.781481) (xy 105.300272 -287.797762)
			(xy 105.346233 -287.821489) (xy 105.387939 -287.852083) (xy 105.424372 -287.888798) (xy 105.454645 -287.930738)
			(xy 105.478017 -287.97688) (xy 105.49392 -288.026099) (xy 105.501965 -288.077194) (xy 105.502456 -288.103056)
			(xy 105.502018 -288.127533) (xy 105.501796 -288.129023) (xy 113.299749 -288.129023) (xy 113.299749 -288.077089)
			(xy 113.307874 -288.025794) (xy 113.323922 -287.976401) (xy 113.3475 -287.930127) (xy 113.378026 -287.888111)
			(xy 113.414749 -287.851388) (xy 113.456765 -287.820862) (xy 113.503039 -287.797284) (xy 113.552432 -287.781236)
			(xy 113.603727 -287.773111) (xy 113.655661 -287.773111) (xy 113.706956 -287.781236) (xy 113.756349 -287.797284)
			(xy 113.802623 -287.820862) (xy 113.844639 -287.851388) (xy 113.881362 -287.888111) (xy 113.911888 -287.930127)
			(xy 113.935466 -287.976401) (xy 113.951514 -288.025794) (xy 113.959639 -288.077089) (xy 113.960148 -288.103056)
			(xy 113.959639 -288.129023) (xy 116.119403 -288.129023) (xy 116.119403 -288.077089) (xy 116.127528 -288.025794)
			(xy 116.143576 -287.976401) (xy 116.167154 -287.930127) (xy 116.19768 -287.888111) (xy 116.234403 -287.851388)
			(xy 116.276419 -287.820862) (xy 116.322693 -287.797284) (xy 116.372086 -287.781236) (xy 116.423381 -287.773111)
			(xy 116.475315 -287.773111) (xy 116.52661 -287.781236) (xy 116.576003 -287.797284) (xy 116.622277 -287.820862)
			(xy 116.664293 -287.851388) (xy 116.701016 -287.888111) (xy 116.731542 -287.930127) (xy 116.75512 -287.976401)
			(xy 116.771168 -288.025794) (xy 116.779293 -288.077089) (xy 116.779802 -288.103056) (xy 116.779293 -288.129023)
			(xy 116.771168 -288.180318) (xy 116.75512 -288.229711) (xy 116.731542 -288.275985) (xy 116.701016 -288.318001)
			(xy 116.664293 -288.354724) (xy 116.622277 -288.38525) (xy 116.576003 -288.408828) (xy 116.52661 -288.424876)
			(xy 116.475315 -288.433001) (xy 116.423381 -288.433001) (xy 116.372086 -288.424876) (xy 116.322693 -288.408828)
			(xy 116.276419 -288.38525) (xy 116.234403 -288.354724) (xy 116.19768 -288.318001) (xy 116.167154 -288.275985)
			(xy 116.143576 -288.229711) (xy 116.127528 -288.180318) (xy 116.119403 -288.129023) (xy 113.959639 -288.129023)
			(xy 113.951514 -288.180318) (xy 113.935466 -288.229711) (xy 113.911888 -288.275985) (xy 113.881362 -288.318001)
			(xy 113.844639 -288.354724) (xy 113.802623 -288.38525) (xy 113.756349 -288.408828) (xy 113.706956 -288.424876)
			(xy 113.655661 -288.433001) (xy 113.603727 -288.433001) (xy 113.552432 -288.424876) (xy 113.503039 -288.408828)
			(xy 113.456765 -288.38525) (xy 113.414749 -288.354724) (xy 113.378026 -288.318001) (xy 113.3475 -288.275985)
			(xy 113.323922 -288.229711) (xy 113.307874 -288.180318) (xy 113.299749 -288.129023) (xy 105.501796 -288.129023)
			(xy 105.494811 -288.175954) (xy 105.480548 -288.222784) (xy 105.45954 -288.267001) (xy 105.432246 -288.30764)
			(xy 105.399261 -288.343814) (xy 105.361307 -288.374733) (xy 105.319211 -288.399721) (xy 105.296716 -288.40938)
			(xy 105.287826 -288.412936) (xy 105.281476 -288.418778) (xy 105.278745 -288.421441) (xy 105.274034 -288.427441)
			(xy 105.272078 -288.430716) (xy 105.239566 -288.495486) (xy 105.23749 -288.500378) (xy 105.235192 -288.51075)
			(xy 105.234994 -288.51606) (xy 105.236518 -288.528506) (xy 105.23728 -288.531554) (xy 105.243012 -288.553831)
			(xy 105.253301 -288.598669) (xy 105.257854 -288.621216) (xy 105.258362 -288.624264) (xy 105.26036 -288.631091)
			(xy 105.267579 -288.643342) (xy 105.272586 -288.648394) (xy 105.27792 -288.652966) (xy 105.320499 -288.692331)
			(xy 105.400341 -288.776441) (xy 105.473706 -288.866256) (xy 105.527464 -288.943093) (xy 107.191303 -288.943093)
			(xy 107.191303 -288.891159) (xy 107.199428 -288.839864) (xy 107.215476 -288.790471) (xy 107.239054 -288.744197)
			(xy 107.26958 -288.702181) (xy 107.306303 -288.665458) (xy 107.348319 -288.634932) (xy 107.394593 -288.611354)
			(xy 107.443986 -288.595306) (xy 107.495281 -288.587181) (xy 107.547215 -288.587181) (xy 107.59851 -288.595306)
			(xy 107.647903 -288.611354) (xy 107.694177 -288.634932) (xy 107.736193 -288.665458) (xy 107.772916 -288.702181)
			(xy 107.803442 -288.744197) (xy 107.82702 -288.790471) (xy 107.843068 -288.839864) (xy 107.851193 -288.891159)
			(xy 107.851702 -288.917126) (xy 107.851193 -288.943093) (xy 107.843068 -288.994388) (xy 107.834976 -289.019293)
			(xy 110.010703 -289.019293) (xy 110.010703 -288.967359) (xy 110.018828 -288.916064) (xy 110.034876 -288.866671)
			(xy 110.058454 -288.820397) (xy 110.08898 -288.778381) (xy 110.125703 -288.741658) (xy 110.167719 -288.711132)
			(xy 110.213993 -288.687554) (xy 110.263386 -288.671506) (xy 110.314681 -288.663381) (xy 110.366615 -288.663381)
			(xy 110.41791 -288.671506) (xy 110.467303 -288.687554) (xy 110.513577 -288.711132) (xy 110.555593 -288.741658)
			(xy 110.592316 -288.778381) (xy 110.622842 -288.820397) (xy 110.64642 -288.866671) (xy 110.662468 -288.916064)
			(xy 110.670593 -288.967359) (xy 110.671102 -288.993326) (xy 110.670593 -289.019293) (xy 110.662468 -289.070588)
			(xy 110.64642 -289.119981) (xy 110.622842 -289.166255) (xy 110.592316 -289.208271) (xy 110.555593 -289.244994)
			(xy 110.513577 -289.27552) (xy 110.467303 -289.299098) (xy 110.41791 -289.315146) (xy 110.366615 -289.323271)
			(xy 110.314681 -289.323271) (xy 110.263386 -289.315146) (xy 110.213993 -289.299098) (xy 110.167719 -289.27552)
			(xy 110.125703 -289.244994) (xy 110.08898 -289.208271) (xy 110.058454 -289.166255) (xy 110.034876 -289.119981)
			(xy 110.018828 -289.070588) (xy 110.010703 -289.019293) (xy 107.834976 -289.019293) (xy 107.82702 -289.043781)
			(xy 107.803442 -289.090055) (xy 107.772916 -289.132071) (xy 107.736193 -289.168794) (xy 107.694177 -289.19932)
			(xy 107.647903 -289.222898) (xy 107.59851 -289.238946) (xy 107.547215 -289.247071) (xy 107.495281 -289.247071)
			(xy 107.443986 -289.238946) (xy 107.394593 -289.222898) (xy 107.348319 -289.19932) (xy 107.306303 -289.168794)
			(xy 107.26958 -289.132071) (xy 107.239054 -289.090055) (xy 107.215476 -289.043781) (xy 107.199428 -288.994388)
			(xy 107.191303 -288.943093) (xy 105.527464 -288.943093) (xy 105.540188 -288.961279) (xy 105.570274 -289.010852)
			(xy 105.597692 -289.057808) (xy 105.646668 -289.154899) (xy 105.688746 -289.255173) (xy 105.706672 -289.306508)
			(xy 105.718507 -289.343228) (xy 105.736953 -289.418145) (xy 105.749326 -289.494302) (xy 105.755545 -289.571206)
			(xy 105.755948 -289.609784) (xy 105.755948 -291.139118) (xy 105.755427 -291.184049) (xy 105.747025 -291.273518)
			(xy 105.730289 -291.361807) (xy 105.705365 -291.448144) (xy 105.6894 -291.490146) (xy 105.670763 -291.535755)
			(xy 105.625448 -291.623249) (xy 105.5714 -291.705634) (xy 105.509187 -291.782042) (xy 105.47477 -291.817298)
			(xy 104.604058 -292.688264) (xy 104.597593 -292.696809) (xy 104.591651 -292.71737) (xy 104.594565 -292.738572)
			(xy 104.59974 -292.747954) (xy 104.61219 -292.768817) (xy 104.632288 -292.81305) (xy 104.646611 -292.859476)
			(xy 104.654928 -292.907344) (xy 104.656382 -292.931596) (xy 104.656636 -292.946328) (xy 104.656636 -292.952932)
			(xy 104.655925 -292.978574) (xy 104.655238 -292.983252) (xy 109.276358 -292.983252) (xy 109.276358 -292.928748)
			(xy 109.284114 -292.874798) (xy 109.29947 -292.822502) (xy 109.322111 -292.772923) (xy 109.351578 -292.727071)
			(xy 109.38727 -292.685878) (xy 109.428461 -292.650185) (xy 109.474312 -292.620717) (xy 109.523891 -292.598074)
			(xy 109.576187 -292.582717) (xy 109.630136 -292.574959) (xy 109.657388 -292.574472) (xy 109.657642 -292.574472)
			(xy 109.685656 -292.574991) (xy 109.741079 -292.583212) (xy 109.794706 -292.599443) (xy 109.845386 -292.623334)
			(xy 109.892032 -292.654374) (xy 109.913166 -292.67277) (xy 109.924608 -292.682415) (xy 109.951651 -292.695195)
			(xy 109.981238 -292.699581) (xy 110.010825 -292.695195) (xy 110.037868 -292.682415) (xy 110.04931 -292.67277)
			(xy 110.070415 -292.654335) (xy 110.117053 -292.623268) (xy 110.167739 -292.599366) (xy 110.221378 -292.583147)
			(xy 110.276815 -292.574958) (xy 110.304834 -292.574472) (xy 110.305342 -292.574472) (xy 110.333356 -292.574991)
			(xy 110.388779 -292.583212) (xy 110.442406 -292.599443) (xy 110.493086 -292.623334) (xy 110.539732 -292.654374)
			(xy 110.560866 -292.67277) (xy 110.572308 -292.682415) (xy 110.599351 -292.695195) (xy 110.628938 -292.699581)
			(xy 110.658525 -292.695195) (xy 110.685568 -292.682415) (xy 110.69701 -292.67277) (xy 110.718115 -292.654335)
			(xy 110.764753 -292.623268) (xy 110.815439 -292.599366) (xy 110.869078 -292.583147) (xy 110.924515 -292.574958)
			(xy 110.952534 -292.574472) (xy 110.952788 -292.574472) (xy 110.98004 -292.574974) (xy 111.033989 -292.58273)
			(xy 111.086286 -292.598084) (xy 111.135865 -292.620724) (xy 111.181717 -292.650191) (xy 111.222909 -292.685882)
			(xy 111.258602 -292.727073) (xy 111.28807 -292.772924) (xy 111.310712 -292.822503) (xy 111.326068 -292.874799)
			(xy 111.333825 -292.928748) (xy 111.333825 -292.983252) (xy 111.326068 -293.037201) (xy 111.310712 -293.089497)
			(xy 111.28807 -293.139076) (xy 111.258602 -293.184927) (xy 111.222909 -293.226118) (xy 111.181717 -293.261809)
			(xy 111.135865 -293.291276) (xy 111.086286 -293.313916) (xy 111.033989 -293.32927) (xy 110.98004 -293.337026)
			(xy 110.952788 -293.337488) (xy 110.952534 -293.337488) (xy 110.924519 -293.336994) (xy 110.869094 -293.328768)
			(xy 110.815467 -293.312532) (xy 110.764787 -293.288635) (xy 110.718143 -293.257589) (xy 110.69701 -293.23919)
			(xy 110.685568 -293.229545) (xy 110.658525 -293.216765) (xy 110.628938 -293.212379) (xy 110.599351 -293.216765)
			(xy 110.572308 -293.229545) (xy 110.560866 -293.23919) (xy 110.539725 -293.257583) (xy 110.493098 -293.288658)
			(xy 110.442421 -293.312568) (xy 110.38879 -293.328797) (xy 110.333359 -293.336996) (xy 110.305342 -293.337488)
			(xy 110.304834 -293.337488) (xy 110.276819 -293.336994) (xy 110.221394 -293.328768) (xy 110.167767 -293.312532)
			(xy 110.117087 -293.288635) (xy 110.070443 -293.257589) (xy 110.04931 -293.23919) (xy 110.037868 -293.229545)
			(xy 110.010825 -293.216765) (xy 109.981238 -293.212379) (xy 109.951651 -293.216765) (xy 109.924608 -293.229545)
			(xy 109.913166 -293.23919) (xy 109.892025 -293.257583) (xy 109.845398 -293.288658) (xy 109.794721 -293.312568)
			(xy 109.74109 -293.328797) (xy 109.685659 -293.336996) (xy 109.657642 -293.337488) (xy 109.657388 -293.337488)
			(xy 109.630136 -293.337041) (xy 109.576187 -293.329283) (xy 109.523891 -293.313926) (xy 109.474312 -293.291283)
			(xy 109.428461 -293.261815) (xy 109.38727 -293.226122) (xy 109.351578 -293.184929) (xy 109.322111 -293.139077)
			(xy 109.29947 -293.089498) (xy 109.284114 -293.037202) (xy 109.276358 -292.983252) (xy 104.655238 -292.983252)
			(xy 104.648475 -293.029328) (xy 104.634305 -293.07863) (xy 104.624378 -293.102284) (xy 104.611903 -293.12924)
			(xy 104.579853 -293.179243) (xy 104.54044 -293.223675) (xy 104.494617 -293.261462) (xy 104.443491 -293.29169)
			(xy 104.388298 -293.313628) (xy 104.359456 -293.320724) (xy 104.359202 -293.320724) (xy 104.356154 -293.321486)
			(xy 104.348763 -293.323937) (xy 104.33584 -293.332608) (xy 104.330754 -293.338504) (xy 104.32542 -293.345108)
			(xy 104.319578 -293.361364) (xy 104.319578 -294.610282) (xy 104.319939 -294.618823) (xy 104.325638 -294.63493)
			(xy 104.330754 -294.641778) (xy 104.336088 -294.648382) (xy 104.350312 -294.657272) (xy 104.359202 -294.659304)
			(xy 104.385512 -294.665737) (xy 104.436121 -294.685029) (xy 104.483493 -294.711286) (xy 104.526674 -294.743979)
			(xy 104.564798 -294.782451) (xy 104.597097 -294.825928) (xy 104.622921 -294.873537) (xy 104.641753 -294.924319)
			(xy 104.653212 -294.977255) (xy 104.657069 -295.031279) (xy 104.654608 -295.066052) (xy 109.276358 -295.066052)
			(xy 109.276358 -295.011548) (xy 109.284114 -294.957598) (xy 109.29947 -294.905302) (xy 109.322111 -294.855723)
			(xy 109.351578 -294.809871) (xy 109.38727 -294.768678) (xy 109.428461 -294.732985) (xy 109.474312 -294.703517)
			(xy 109.523891 -294.680874) (xy 109.576187 -294.665517) (xy 109.630136 -294.657759) (xy 109.657388 -294.657272)
			(xy 109.657642 -294.657272) (xy 109.685656 -294.657791) (xy 109.741079 -294.666012) (xy 109.794706 -294.682243)
			(xy 109.845386 -294.706134) (xy 109.892032 -294.737174) (xy 109.913166 -294.75557) (xy 109.924608 -294.765215)
			(xy 109.951651 -294.777995) (xy 109.981238 -294.782381) (xy 110.010825 -294.777995) (xy 110.037868 -294.765215)
			(xy 110.04931 -294.75557) (xy 110.070415 -294.737135) (xy 110.117053 -294.706068) (xy 110.167739 -294.682166)
			(xy 110.221378 -294.665947) (xy 110.276815 -294.657758) (xy 110.304834 -294.657272) (xy 110.305342 -294.657272)
			(xy 110.333356 -294.657791) (xy 110.388779 -294.666012) (xy 110.442406 -294.682243) (xy 110.493086 -294.706134)
			(xy 110.539732 -294.737174) (xy 110.560866 -294.75557) (xy 110.572308 -294.765215) (xy 110.599351 -294.777995)
			(xy 110.628938 -294.782381) (xy 110.658525 -294.777995) (xy 110.685568 -294.765215) (xy 110.69701 -294.75557)
			(xy 110.718115 -294.737135) (xy 110.764753 -294.706068) (xy 110.815439 -294.682166) (xy 110.869078 -294.665947)
			(xy 110.924515 -294.657758) (xy 110.952534 -294.657272) (xy 110.952788 -294.657272) (xy 110.98004 -294.657774)
			(xy 111.033989 -294.66553) (xy 111.086286 -294.680884) (xy 111.135865 -294.703524) (xy 111.181717 -294.732991)
			(xy 111.222909 -294.768682) (xy 111.258602 -294.809873) (xy 111.28807 -294.855724) (xy 111.310712 -294.905303)
			(xy 111.326068 -294.957599) (xy 111.333825 -295.011548) (xy 111.333825 -295.066052) (xy 111.326068 -295.120001)
			(xy 111.310712 -295.172297) (xy 111.28807 -295.221876) (xy 111.258602 -295.267727) (xy 111.222909 -295.308918)
			(xy 111.181717 -295.344609) (xy 111.135865 -295.374076) (xy 111.086286 -295.396716) (xy 111.033989 -295.41207)
			(xy 110.98004 -295.419826) (xy 110.952788 -295.420288) (xy 110.952534 -295.420288) (xy 110.924519 -295.419794)
			(xy 110.869094 -295.411568) (xy 110.815467 -295.395332) (xy 110.764787 -295.371435) (xy 110.718143 -295.340389)
			(xy 110.69701 -295.32199) (xy 110.685568 -295.312345) (xy 110.658525 -295.299565) (xy 110.628938 -295.295179)
			(xy 110.599351 -295.299565) (xy 110.572308 -295.312345) (xy 110.560866 -295.32199) (xy 110.539725 -295.340383)
			(xy 110.493098 -295.371458) (xy 110.442421 -295.395368) (xy 110.38879 -295.411597) (xy 110.333359 -295.419796)
			(xy 110.305342 -295.420288) (xy 110.304834 -295.420288) (xy 110.276819 -295.419794) (xy 110.221394 -295.411568)
			(xy 110.167767 -295.395332) (xy 110.117087 -295.371435) (xy 110.070443 -295.340389) (xy 110.04931 -295.32199)
			(xy 110.037868 -295.312345) (xy 110.010825 -295.299565) (xy 109.981238 -295.295179) (xy 109.951651 -295.299565)
			(xy 109.924608 -295.312345) (xy 109.913166 -295.32199) (xy 109.892025 -295.340383) (xy 109.845398 -295.371458)
			(xy 109.794721 -295.395368) (xy 109.74109 -295.411597) (xy 109.685659 -295.419796) (xy 109.657642 -295.420288)
			(xy 109.657388 -295.420288) (xy 109.630136 -295.419841) (xy 109.576187 -295.412083) (xy 109.523891 -295.396726)
			(xy 109.474312 -295.374083) (xy 109.428461 -295.344615) (xy 109.38727 -295.308922) (xy 109.351578 -295.267729)
			(xy 109.322111 -295.221877) (xy 109.29947 -295.172298) (xy 109.284114 -295.120002) (xy 109.276358 -295.066052)
			(xy 104.654608 -295.066052) (xy 104.653246 -295.085306) (xy 104.64182 -295.138248) (xy 104.623021 -295.189043)
			(xy 104.597227 -295.236668) (xy 104.564955 -295.280165) (xy 104.526856 -295.318662) (xy 104.483695 -295.351382)
			(xy 104.43634 -295.377669) (xy 104.385743 -295.396993) (xy 104.359456 -295.403524) (xy 104.359202 -295.403524)
			(xy 104.356154 -295.404286) (xy 104.348763 -295.406737) (xy 104.33584 -295.415408) (xy 104.330754 -295.421304)
			(xy 104.32542 -295.427908) (xy 104.319578 -295.444164) (xy 104.319578 -296.656506) (xy 104.319942 -296.665046)
			(xy 104.325648 -296.681148) (xy 104.330754 -296.688002) (xy 104.336088 -296.694606) (xy 104.350312 -296.703496)
			(xy 104.359202 -296.705528) (xy 104.385517 -296.711961) (xy 104.436137 -296.731255) (xy 104.483519 -296.757514)
			(xy 104.526711 -296.790212) (xy 104.564843 -296.82869) (xy 104.59715 -296.872174) (xy 104.622982 -296.919791)
			(xy 104.64182 -296.970582) (xy 104.653284 -297.023528) (xy 104.657144 -297.077562) (xy 104.653322 -297.1316)
			(xy 104.641897 -297.184553) (xy 104.62691 -297.225052) (xy 109.276358 -297.225052) (xy 109.276358 -297.170548)
			(xy 109.284114 -297.116598) (xy 109.29947 -297.064302) (xy 109.322111 -297.014723) (xy 109.351578 -296.968871)
			(xy 109.38727 -296.927678) (xy 109.428461 -296.891985) (xy 109.474312 -296.862517) (xy 109.523891 -296.839874)
			(xy 109.576187 -296.824517) (xy 109.630136 -296.816759) (xy 109.657388 -296.816272) (xy 109.657642 -296.816272)
			(xy 109.685656 -296.816791) (xy 109.741079 -296.825012) (xy 109.794706 -296.841243) (xy 109.845386 -296.865134)
			(xy 109.892032 -296.896174) (xy 109.913166 -296.91457) (xy 109.924608 -296.924215) (xy 109.951651 -296.936995)
			(xy 109.981238 -296.941381) (xy 110.010825 -296.936995) (xy 110.037868 -296.924215) (xy 110.04931 -296.91457)
			(xy 110.070415 -296.896135) (xy 110.117053 -296.865068) (xy 110.167739 -296.841166) (xy 110.221378 -296.824947)
			(xy 110.276815 -296.816758) (xy 110.304834 -296.816272) (xy 110.305342 -296.816272) (xy 110.333356 -296.816791)
			(xy 110.388779 -296.825012) (xy 110.442406 -296.841243) (xy 110.493086 -296.865134) (xy 110.539732 -296.896174)
			(xy 110.560866 -296.91457) (xy 110.572308 -296.924215) (xy 110.599351 -296.936995) (xy 110.628938 -296.941381)
			(xy 110.658525 -296.936995) (xy 110.685568 -296.924215) (xy 110.69701 -296.91457) (xy 110.718115 -296.896135)
			(xy 110.764753 -296.865068) (xy 110.815439 -296.841166) (xy 110.869078 -296.824947) (xy 110.924515 -296.816758)
			(xy 110.952534 -296.816272) (xy 110.952788 -296.816272) (xy 110.98004 -296.816774) (xy 111.033989 -296.82453)
			(xy 111.086286 -296.839884) (xy 111.135865 -296.862524) (xy 111.181717 -296.891991) (xy 111.222909 -296.927682)
			(xy 111.258602 -296.968873) (xy 111.28807 -297.014724) (xy 111.310712 -297.064303) (xy 111.326068 -297.116599)
			(xy 111.333825 -297.170548) (xy 111.333825 -297.225052) (xy 111.326068 -297.279001) (xy 111.310712 -297.331297)
			(xy 111.28807 -297.380876) (xy 111.258602 -297.426727) (xy 111.222909 -297.467918) (xy 111.181717 -297.503609)
			(xy 111.135865 -297.533076) (xy 111.086286 -297.555716) (xy 111.033989 -297.57107) (xy 110.98004 -297.578826)
			(xy 110.952788 -297.579288) (xy 110.952534 -297.579288) (xy 110.924519 -297.578794) (xy 110.869094 -297.570568)
			(xy 110.815467 -297.554332) (xy 110.764787 -297.530435) (xy 110.718143 -297.499389) (xy 110.69701 -297.48099)
			(xy 110.685568 -297.471345) (xy 110.658525 -297.458565) (xy 110.628938 -297.454179) (xy 110.599351 -297.458565)
			(xy 110.572308 -297.471345) (xy 110.560866 -297.48099) (xy 110.539725 -297.499383) (xy 110.493098 -297.530458)
			(xy 110.442421 -297.554368) (xy 110.38879 -297.570597) (xy 110.333359 -297.578796) (xy 110.305342 -297.579288)
			(xy 110.304834 -297.579288) (xy 110.276819 -297.578794) (xy 110.221394 -297.570568) (xy 110.167767 -297.554332)
			(xy 110.117087 -297.530435) (xy 110.070443 -297.499389) (xy 110.04931 -297.48099) (xy 110.037868 -297.471345)
			(xy 110.010825 -297.458565) (xy 109.981238 -297.454179) (xy 109.951651 -297.458565) (xy 109.924608 -297.471345)
			(xy 109.913166 -297.48099) (xy 109.892025 -297.499383) (xy 109.845398 -297.530458) (xy 109.794721 -297.554368)
			(xy 109.74109 -297.570597) (xy 109.685659 -297.578796) (xy 109.657642 -297.579288) (xy 109.657388 -297.579288)
			(xy 109.630136 -297.578841) (xy 109.576187 -297.571083) (xy 109.523891 -297.555726) (xy 109.474312 -297.533083)
			(xy 109.428461 -297.503615) (xy 109.38727 -297.467922) (xy 109.351578 -297.426729) (xy 109.322111 -297.380877)
			(xy 109.29947 -297.331298) (xy 109.284114 -297.279002) (xy 109.276358 -297.225052) (xy 104.62691 -297.225052)
			(xy 104.623096 -297.235358) (xy 104.597299 -297.282994) (xy 104.565023 -297.326501) (xy 104.526918 -297.365007)
			(xy 104.48375 -297.397735) (xy 104.436387 -297.424029) (xy 104.385781 -297.44336) (xy 104.359456 -297.449748)
			(xy 104.359202 -297.449748) (xy 104.356154 -297.45051) (xy 104.348764 -297.452962) (xy 104.335844 -297.461635)
			(xy 104.330754 -297.467528) (xy 104.32542 -297.474132) (xy 104.319578 -297.490388) (xy 104.319578 -298.50842)
			(xy 104.3178 -298.521628) (xy 103.714042 -300.698662) (xy 103.714042 -300.698916) (xy 103.711248 -300.706536)
			(xy 103.538782 -301.079154) (xy 103.536242 -301.085758) (xy 103.534972 -301.090584) (xy 103.028242 -303.965102)
			(xy 102.99319 -304.164238) (xy 102.985246 -304.206633) (xy 102.962937 -304.289958) (xy 102.933451 -304.371022)
			(xy 102.897013 -304.449208) (xy 102.853899 -304.523921) (xy 102.804438 -304.594592) (xy 102.749006 -304.660684)
			(xy 102.71887 -304.691542) (xy 100.594922 -306.81549) (xy 100.58908 -306.822602) (xy 100.586286 -306.82692)
			(xy 99.379024 -309.0799) (xy 99.377161 -309.083243) (xy 99.372561 -309.08936) (xy 99.36988 -309.092092)
			(xy 92.660134 -315.709738) (xy 97.636834 -315.709738) (xy 97.636834 -315.625042) (xy 97.644885 -315.540728)
			(xy 97.660914 -315.457562) (xy 97.684775 -315.376295) (xy 97.716254 -315.297665) (xy 97.755065 -315.222384)
			(xy 97.800855 -315.151132) (xy 97.853211 -315.084556) (xy 97.911659 -315.023258) (xy 97.975669 -314.967793)
			(xy 98.044661 -314.918664) (xy 98.118011 -314.876315) (xy 98.195054 -314.841131) (xy 98.275093 -314.813429)
			(xy 98.357402 -314.793461) (xy 98.441237 -314.781408) (xy 98.525838 -314.777378) (xy 98.610439 -314.781408)
			(xy 98.694274 -314.793461) (xy 98.776583 -314.813429) (xy 98.856622 -314.841131) (xy 98.933665 -314.876315)
			(xy 99.007015 -314.918664) (xy 99.076007 -314.967793) (xy 99.140017 -315.023258) (xy 99.198465 -315.084556)
			(xy 99.250821 -315.151132) (xy 99.296611 -315.222384) (xy 99.335422 -315.297665) (xy 99.366901 -315.376295)
			(xy 99.390762 -315.457562) (xy 99.406791 -315.540728) (xy 99.414842 -315.625042) (xy 99.415346 -315.66739)
			(xy 99.610423 -315.66739) (xy 99.614445 -315.58167) (xy 99.626476 -315.496702) (xy 99.646412 -315.413235)
			(xy 99.674075 -315.332001) (xy 99.709224 -315.253715) (xy 99.75155 -315.179064) (xy 99.800679 -315.108705)
			(xy 99.856182 -315.043255) (xy 99.917569 -314.983291) (xy 99.984302 -314.929338) (xy 100.055794 -314.881871)
			(xy 100.131416 -314.841307) (xy 100.210505 -314.808003) (xy 100.292365 -314.782251) (xy 100.376276 -314.764278)
			(xy 100.461502 -314.754242) (xy 100.547294 -314.75223) (xy 100.632896 -314.758261) (xy 100.717558 -314.772281)
			(xy 100.800535 -314.794167) (xy 100.881098 -314.823728) (xy 100.958538 -314.860702) (xy 101.032177 -314.904766)
			(xy 101.101365 -314.955532) (xy 101.165496 -315.012553) (xy 101.224005 -315.075329) (xy 101.276378 -315.143309)
			(xy 101.322156 -315.215894) (xy 101.360936 -315.292446) (xy 101.392377 -315.372294) (xy 101.416203 -315.454735)
			(xy 101.432204 -315.539045) (xy 101.440239 -315.624483) (xy 101.440742 -315.66739) (xy 101.440246 -315.709738)
			(xy 103.834434 -315.709738) (xy 103.834434 -315.625042) (xy 103.842485 -315.540728) (xy 103.858514 -315.457562)
			(xy 103.882375 -315.376295) (xy 103.913854 -315.297665) (xy 103.952665 -315.222384) (xy 103.998455 -315.151132)
			(xy 104.050811 -315.084556) (xy 104.109259 -315.023258) (xy 104.173269 -314.967793) (xy 104.242261 -314.918664)
			(xy 104.315611 -314.876315) (xy 104.392654 -314.841131) (xy 104.472693 -314.813429) (xy 104.555002 -314.793461)
			(xy 104.638837 -314.781408) (xy 104.723438 -314.777378) (xy 104.808039 -314.781408) (xy 104.891874 -314.793461)
			(xy 104.974183 -314.813429) (xy 105.054222 -314.841131) (xy 105.131265 -314.876315) (xy 105.204615 -314.918664)
			(xy 105.273607 -314.967793) (xy 105.337617 -315.023258) (xy 105.396065 -315.084556) (xy 105.448421 -315.151132)
			(xy 105.494211 -315.222384) (xy 105.533022 -315.297665) (xy 105.564501 -315.376295) (xy 105.588362 -315.457562)
			(xy 105.604391 -315.540728) (xy 105.612442 -315.625042) (xy 105.612946 -315.66739) (xy 105.808023 -315.66739)
			(xy 105.812045 -315.58167) (xy 105.824076 -315.496702) (xy 105.844012 -315.413235) (xy 105.871675 -315.332001)
			(xy 105.906824 -315.253715) (xy 105.94915 -315.179064) (xy 105.998279 -315.108705) (xy 106.053782 -315.043255)
			(xy 106.115169 -314.983291) (xy 106.181902 -314.929338) (xy 106.253394 -314.881871) (xy 106.329016 -314.841307)
			(xy 106.408105 -314.808003) (xy 106.489965 -314.782251) (xy 106.573876 -314.764278) (xy 106.659102 -314.754242)
			(xy 106.744894 -314.75223) (xy 106.830496 -314.758261) (xy 106.915158 -314.772281) (xy 106.998135 -314.794167)
			(xy 107.078698 -314.823728) (xy 107.156138 -314.860702) (xy 107.229777 -314.904766) (xy 107.298965 -314.955532)
			(xy 107.363096 -315.012553) (xy 107.421605 -315.075329) (xy 107.473978 -315.143309) (xy 107.519756 -315.215894)
			(xy 107.558536 -315.292446) (xy 107.589977 -315.372294) (xy 107.613803 -315.454735) (xy 107.629804 -315.539045)
			(xy 107.637839 -315.624483) (xy 107.638342 -315.66739) (xy 107.637846 -315.709738) (xy 110.012222 -315.709738)
			(xy 110.012222 -315.625042) (xy 110.020273 -315.540728) (xy 110.036302 -315.457562) (xy 110.060163 -315.376295)
			(xy 110.091642 -315.297665) (xy 110.130453 -315.222384) (xy 110.176243 -315.151132) (xy 110.228599 -315.084556)
			(xy 110.287047 -315.023258) (xy 110.351057 -314.967793) (xy 110.420049 -314.918664) (xy 110.493399 -314.876315)
			(xy 110.570442 -314.841131) (xy 110.650481 -314.813429) (xy 110.73279 -314.793461) (xy 110.816625 -314.781408)
			(xy 110.901226 -314.777378) (xy 110.985827 -314.781408) (xy 111.069662 -314.793461) (xy 111.151971 -314.813429)
			(xy 111.23201 -314.841131) (xy 111.309053 -314.876315) (xy 111.382403 -314.918664) (xy 111.451395 -314.967793)
			(xy 111.515405 -315.023258) (xy 111.573853 -315.084556) (xy 111.626209 -315.151132) (xy 111.671999 -315.222384)
			(xy 111.71081 -315.297665) (xy 111.742289 -315.376295) (xy 111.76615 -315.457562) (xy 111.782179 -315.540728)
			(xy 111.79023 -315.625042) (xy 111.790734 -315.66739) (xy 111.985811 -315.66739) (xy 111.989833 -315.58167)
			(xy 112.001864 -315.496702) (xy 112.0218 -315.413235) (xy 112.049463 -315.332001) (xy 112.084612 -315.253715)
			(xy 112.126938 -315.179064) (xy 112.176067 -315.108705) (xy 112.23157 -315.043255) (xy 112.292957 -314.983291)
			(xy 112.35969 -314.929338) (xy 112.431182 -314.881871) (xy 112.506804 -314.841307) (xy 112.585893 -314.808003)
			(xy 112.667753 -314.782251) (xy 112.751664 -314.764278) (xy 112.83689 -314.754242) (xy 112.922682 -314.75223)
			(xy 113.008284 -314.758261) (xy 113.092946 -314.772281) (xy 113.175923 -314.794167) (xy 113.256486 -314.823728)
			(xy 113.333926 -314.860702) (xy 113.407565 -314.904766) (xy 113.476753 -314.955532) (xy 113.540884 -315.012553)
			(xy 113.599393 -315.075329) (xy 113.651766 -315.143309) (xy 113.697544 -315.215894) (xy 113.736324 -315.292446)
			(xy 113.767765 -315.372294) (xy 113.791591 -315.454735) (xy 113.807592 -315.539045) (xy 113.815627 -315.624483)
			(xy 113.81613 -315.66739) (xy 113.815634 -315.709738) (xy 116.209822 -315.709738) (xy 116.209822 -315.625042)
			(xy 116.217873 -315.540728) (xy 116.233902 -315.457562) (xy 116.257763 -315.376295) (xy 116.289242 -315.297665)
			(xy 116.328053 -315.222384) (xy 116.373843 -315.151132) (xy 116.426199 -315.084556) (xy 116.484647 -315.023258)
			(xy 116.548657 -314.967793) (xy 116.617649 -314.918664) (xy 116.690999 -314.876315) (xy 116.768042 -314.841131)
			(xy 116.848081 -314.813429) (xy 116.93039 -314.793461) (xy 117.014225 -314.781408) (xy 117.098826 -314.777378)
			(xy 117.183427 -314.781408) (xy 117.267262 -314.793461) (xy 117.349571 -314.813429) (xy 117.42961 -314.841131)
			(xy 117.506653 -314.876315) (xy 117.580003 -314.918664) (xy 117.648995 -314.967793) (xy 117.713005 -315.023258)
			(xy 117.771453 -315.084556) (xy 117.823809 -315.151132) (xy 117.869599 -315.222384) (xy 117.90841 -315.297665)
			(xy 117.939889 -315.376295) (xy 117.96375 -315.457562) (xy 117.979779 -315.540728) (xy 117.98783 -315.625042)
			(xy 117.988334 -315.66739) (xy 118.183411 -315.66739) (xy 118.187433 -315.58167) (xy 118.199464 -315.496702)
			(xy 118.2194 -315.413235) (xy 118.247063 -315.332001) (xy 118.282212 -315.253715) (xy 118.324538 -315.179064)
			(xy 118.373667 -315.108705) (xy 118.42917 -315.043255) (xy 118.490557 -314.983291) (xy 118.55729 -314.929338)
			(xy 118.628782 -314.881871) (xy 118.704404 -314.841307) (xy 118.783493 -314.808003) (xy 118.865353 -314.782251)
			(xy 118.949264 -314.764278) (xy 119.03449 -314.754242) (xy 119.120282 -314.75223) (xy 119.205884 -314.758261)
			(xy 119.290546 -314.772281) (xy 119.373523 -314.794167) (xy 119.454086 -314.823728) (xy 119.531526 -314.860702)
			(xy 119.605165 -314.904766) (xy 119.674353 -314.955532) (xy 119.738484 -315.012553) (xy 119.796993 -315.075329)
			(xy 119.849366 -315.143309) (xy 119.895144 -315.215894) (xy 119.933924 -315.292446) (xy 119.965365 -315.372294)
			(xy 119.989191 -315.454735) (xy 120.005192 -315.539045) (xy 120.013227 -315.624483) (xy 120.01373 -315.66739)
			(xy 120.013234 -315.709738) (xy 122.407422 -315.709738) (xy 122.407422 -315.625042) (xy 122.415473 -315.540728)
			(xy 122.431502 -315.457562) (xy 122.455363 -315.376295) (xy 122.486842 -315.297665) (xy 122.525653 -315.222384)
			(xy 122.571443 -315.151132) (xy 122.623799 -315.084556) (xy 122.682247 -315.023258) (xy 122.746257 -314.967793)
			(xy 122.815249 -314.918664) (xy 122.888599 -314.876315) (xy 122.965642 -314.841131) (xy 123.045681 -314.813429)
			(xy 123.12799 -314.793461) (xy 123.211825 -314.781408) (xy 123.296426 -314.777378) (xy 123.381027 -314.781408)
			(xy 123.464862 -314.793461) (xy 123.547171 -314.813429) (xy 123.62721 -314.841131) (xy 123.704253 -314.876315)
			(xy 123.777603 -314.918664) (xy 123.846595 -314.967793) (xy 123.910605 -315.023258) (xy 123.969053 -315.084556)
			(xy 124.021409 -315.151132) (xy 124.067199 -315.222384) (xy 124.10601 -315.297665) (xy 124.137489 -315.376295)
			(xy 124.16135 -315.457562) (xy 124.177379 -315.540728) (xy 124.18543 -315.625042) (xy 124.185934 -315.66739)
			(xy 124.381011 -315.66739) (xy 124.385033 -315.58167) (xy 124.397064 -315.496702) (xy 124.417 -315.413235)
			(xy 124.444663 -315.332001) (xy 124.479812 -315.253715) (xy 124.522138 -315.179064) (xy 124.571267 -315.108705)
			(xy 124.62677 -315.043255) (xy 124.688157 -314.983291) (xy 124.75489 -314.929338) (xy 124.826382 -314.881871)
			(xy 124.902004 -314.841307) (xy 124.981093 -314.808003) (xy 125.062953 -314.782251) (xy 125.146864 -314.764278)
			(xy 125.23209 -314.754242) (xy 125.317882 -314.75223) (xy 125.403484 -314.758261) (xy 125.488146 -314.772281)
			(xy 125.571123 -314.794167) (xy 125.651686 -314.823728) (xy 125.729126 -314.860702) (xy 125.802765 -314.904766)
			(xy 125.871953 -314.955532) (xy 125.936084 -315.012553) (xy 125.994593 -315.075329) (xy 126.046966 -315.143309)
			(xy 126.092744 -315.215894) (xy 126.131524 -315.292446) (xy 126.162965 -315.372294) (xy 126.186791 -315.454735)
			(xy 126.202792 -315.539045) (xy 126.210827 -315.624483) (xy 126.21133 -315.66739) (xy 126.210827 -315.710297)
			(xy 126.202792 -315.795735) (xy 126.186791 -315.880045) (xy 126.162965 -315.962486) (xy 126.131524 -316.042334)
			(xy 126.092744 -316.118886) (xy 126.046966 -316.191471) (xy 125.994593 -316.259451) (xy 125.936084 -316.322227)
			(xy 125.871953 -316.379248) (xy 125.802765 -316.430014) (xy 125.729126 -316.474078) (xy 125.651686 -316.511052)
			(xy 125.571123 -316.540613) (xy 125.488146 -316.562499) (xy 125.403484 -316.576519) (xy 125.317882 -316.58255)
			(xy 125.23209 -316.580538) (xy 125.146864 -316.570502) (xy 125.062953 -316.552529) (xy 124.981093 -316.526777)
			(xy 124.902004 -316.493473) (xy 124.826382 -316.452909) (xy 124.75489 -316.405442) (xy 124.688157 -316.351489)
			(xy 124.62677 -316.291525) (xy 124.571267 -316.226075) (xy 124.522138 -316.155716) (xy 124.479812 -316.081065)
			(xy 124.444663 -316.002779) (xy 124.417 -315.921545) (xy 124.397064 -315.838078) (xy 124.385033 -315.75311)
			(xy 124.381011 -315.66739) (xy 124.185934 -315.66739) (xy 124.18543 -315.709738) (xy 124.177379 -315.794052)
			(xy 124.16135 -315.877218) (xy 124.137489 -315.958485) (xy 124.10601 -316.037115) (xy 124.067199 -316.112396)
			(xy 124.021409 -316.183648) (xy 123.969053 -316.250224) (xy 123.910605 -316.311522) (xy 123.846595 -316.366987)
			(xy 123.777603 -316.416116) (xy 123.704253 -316.458465) (xy 123.62721 -316.493649) (xy 123.547171 -316.521351)
			(xy 123.464862 -316.541319) (xy 123.381027 -316.553372) (xy 123.296426 -316.557403) (xy 123.211825 -316.553372)
			(xy 123.12799 -316.541319) (xy 123.045681 -316.521351) (xy 122.965642 -316.493649) (xy 122.888599 -316.458465)
			(xy 122.815249 -316.416116) (xy 122.746257 -316.366987) (xy 122.682247 -316.311522) (xy 122.623799 -316.250224)
			(xy 122.571443 -316.183648) (xy 122.525653 -316.112396) (xy 122.486842 -316.037115) (xy 122.455363 -315.958485)
			(xy 122.431502 -315.877218) (xy 122.415473 -315.794052) (xy 122.407422 -315.709738) (xy 120.013234 -315.709738)
			(xy 120.013227 -315.710297) (xy 120.005192 -315.795735) (xy 119.989191 -315.880045) (xy 119.965365 -315.962486)
			(xy 119.933924 -316.042334) (xy 119.895144 -316.118886) (xy 119.849366 -316.191471) (xy 119.796993 -316.259451)
			(xy 119.738484 -316.322227) (xy 119.674353 -316.379248) (xy 119.605165 -316.430014) (xy 119.531526 -316.474078)
			(xy 119.454086 -316.511052) (xy 119.373523 -316.540613) (xy 119.290546 -316.562499) (xy 119.205884 -316.576519)
			(xy 119.120282 -316.58255) (xy 119.03449 -316.580538) (xy 118.949264 -316.570502) (xy 118.865353 -316.552529)
			(xy 118.783493 -316.526777) (xy 118.704404 -316.493473) (xy 118.628782 -316.452909) (xy 118.55729 -316.405442)
			(xy 118.490557 -316.351489) (xy 118.42917 -316.291525) (xy 118.373667 -316.226075) (xy 118.324538 -316.155716)
			(xy 118.282212 -316.081065) (xy 118.247063 -316.002779) (xy 118.2194 -315.921545) (xy 118.199464 -315.838078)
			(xy 118.187433 -315.75311) (xy 118.183411 -315.66739) (xy 117.988334 -315.66739) (xy 117.98783 -315.709738)
			(xy 117.979779 -315.794052) (xy 117.96375 -315.877218) (xy 117.939889 -315.958485) (xy 117.90841 -316.037115)
			(xy 117.869599 -316.112396) (xy 117.823809 -316.183648) (xy 117.771453 -316.250224) (xy 117.713005 -316.311522)
			(xy 117.648995 -316.366987) (xy 117.580003 -316.416116) (xy 117.506653 -316.458465) (xy 117.42961 -316.493649)
			(xy 117.349571 -316.521351) (xy 117.267262 -316.541319) (xy 117.183427 -316.553372) (xy 117.098826 -316.557403)
			(xy 117.014225 -316.553372) (xy 116.93039 -316.541319) (xy 116.848081 -316.521351) (xy 116.768042 -316.493649)
			(xy 116.690999 -316.458465) (xy 116.617649 -316.416116) (xy 116.548657 -316.366987) (xy 116.484647 -316.311522)
			(xy 116.426199 -316.250224) (xy 116.373843 -316.183648) (xy 116.328053 -316.112396) (xy 116.289242 -316.037115)
			(xy 116.257763 -315.958485) (xy 116.233902 -315.877218) (xy 116.217873 -315.794052) (xy 116.209822 -315.709738)
			(xy 113.815634 -315.709738) (xy 113.815627 -315.710297) (xy 113.807592 -315.795735) (xy 113.791591 -315.880045)
			(xy 113.767765 -315.962486) (xy 113.736324 -316.042334) (xy 113.697544 -316.118886) (xy 113.651766 -316.191471)
			(xy 113.599393 -316.259451) (xy 113.540884 -316.322227) (xy 113.476753 -316.379248) (xy 113.407565 -316.430014)
			(xy 113.333926 -316.474078) (xy 113.256486 -316.511052) (xy 113.175923 -316.540613) (xy 113.092946 -316.562499)
			(xy 113.008284 -316.576519) (xy 112.922682 -316.58255) (xy 112.83689 -316.580538) (xy 112.751664 -316.570502)
			(xy 112.667753 -316.552529) (xy 112.585893 -316.526777) (xy 112.506804 -316.493473) (xy 112.431182 -316.452909)
			(xy 112.35969 -316.405442) (xy 112.292957 -316.351489) (xy 112.23157 -316.291525) (xy 112.176067 -316.226075)
			(xy 112.126938 -316.155716) (xy 112.084612 -316.081065) (xy 112.049463 -316.002779) (xy 112.0218 -315.921545)
			(xy 112.001864 -315.838078) (xy 111.989833 -315.75311) (xy 111.985811 -315.66739) (xy 111.790734 -315.66739)
			(xy 111.79023 -315.709738) (xy 111.782179 -315.794052) (xy 111.76615 -315.877218) (xy 111.742289 -315.958485)
			(xy 111.71081 -316.037115) (xy 111.671999 -316.112396) (xy 111.626209 -316.183648) (xy 111.573853 -316.250224)
			(xy 111.515405 -316.311522) (xy 111.451395 -316.366987) (xy 111.382403 -316.416116) (xy 111.309053 -316.458465)
			(xy 111.23201 -316.493649) (xy 111.151971 -316.521351) (xy 111.069662 -316.541319) (xy 110.985827 -316.553372)
			(xy 110.901226 -316.557403) (xy 110.816625 -316.553372) (xy 110.73279 -316.541319) (xy 110.650481 -316.521351)
			(xy 110.570442 -316.493649) (xy 110.493399 -316.458465) (xy 110.420049 -316.416116) (xy 110.351057 -316.366987)
			(xy 110.287047 -316.311522) (xy 110.228599 -316.250224) (xy 110.176243 -316.183648) (xy 110.130453 -316.112396)
			(xy 110.091642 -316.037115) (xy 110.060163 -315.958485) (xy 110.036302 -315.877218) (xy 110.020273 -315.794052)
			(xy 110.012222 -315.709738) (xy 107.637846 -315.709738) (xy 107.637839 -315.710297) (xy 107.629804 -315.795735)
			(xy 107.613803 -315.880045) (xy 107.589977 -315.962486) (xy 107.558536 -316.042334) (xy 107.519756 -316.118886)
			(xy 107.473978 -316.191471) (xy 107.421605 -316.259451) (xy 107.363096 -316.322227) (xy 107.298965 -316.379248)
			(xy 107.229777 -316.430014) (xy 107.156138 -316.474078) (xy 107.078698 -316.511052) (xy 106.998135 -316.540613)
			(xy 106.915158 -316.562499) (xy 106.830496 -316.576519) (xy 106.744894 -316.58255) (xy 106.659102 -316.580538)
			(xy 106.573876 -316.570502) (xy 106.489965 -316.552529) (xy 106.408105 -316.526777) (xy 106.329016 -316.493473)
			(xy 106.253394 -316.452909) (xy 106.181902 -316.405442) (xy 106.115169 -316.351489) (xy 106.053782 -316.291525)
			(xy 105.998279 -316.226075) (xy 105.94915 -316.155716) (xy 105.906824 -316.081065) (xy 105.871675 -316.002779)
			(xy 105.844012 -315.921545) (xy 105.824076 -315.838078) (xy 105.812045 -315.75311) (xy 105.808023 -315.66739)
			(xy 105.612946 -315.66739) (xy 105.612442 -315.709738) (xy 105.604391 -315.794052) (xy 105.588362 -315.877218)
			(xy 105.564501 -315.958485) (xy 105.533022 -316.037115) (xy 105.494211 -316.112396) (xy 105.448421 -316.183648)
			(xy 105.396065 -316.250224) (xy 105.337617 -316.311522) (xy 105.273607 -316.366987) (xy 105.204615 -316.416116)
			(xy 105.131265 -316.458465) (xy 105.054222 -316.493649) (xy 104.974183 -316.521351) (xy 104.891874 -316.541319)
			(xy 104.808039 -316.553372) (xy 104.723438 -316.557403) (xy 104.638837 -316.553372) (xy 104.555002 -316.541319)
			(xy 104.472693 -316.521351) (xy 104.392654 -316.493649) (xy 104.315611 -316.458465) (xy 104.242261 -316.416116)
			(xy 104.173269 -316.366987) (xy 104.109259 -316.311522) (xy 104.050811 -316.250224) (xy 103.998455 -316.183648)
			(xy 103.952665 -316.112396) (xy 103.913854 -316.037115) (xy 103.882375 -315.958485) (xy 103.858514 -315.877218)
			(xy 103.842485 -315.794052) (xy 103.834434 -315.709738) (xy 101.440246 -315.709738) (xy 101.440239 -315.710297)
			(xy 101.432204 -315.795735) (xy 101.416203 -315.880045) (xy 101.392377 -315.962486) (xy 101.360936 -316.042334)
			(xy 101.322156 -316.118886) (xy 101.276378 -316.191471) (xy 101.224005 -316.259451) (xy 101.165496 -316.322227)
			(xy 101.101365 -316.379248) (xy 101.032177 -316.430014) (xy 100.958538 -316.474078) (xy 100.881098 -316.511052)
			(xy 100.800535 -316.540613) (xy 100.717558 -316.562499) (xy 100.632896 -316.576519) (xy 100.547294 -316.58255)
			(xy 100.461502 -316.580538) (xy 100.376276 -316.570502) (xy 100.292365 -316.552529) (xy 100.210505 -316.526777)
			(xy 100.131416 -316.493473) (xy 100.055794 -316.452909) (xy 99.984302 -316.405442) (xy 99.917569 -316.351489)
			(xy 99.856182 -316.291525) (xy 99.800679 -316.226075) (xy 99.75155 -316.155716) (xy 99.709224 -316.081065)
			(xy 99.674075 -316.002779) (xy 99.646412 -315.921545) (xy 99.626476 -315.838078) (xy 99.614445 -315.75311)
			(xy 99.610423 -315.66739) (xy 99.415346 -315.66739) (xy 99.414842 -315.709738) (xy 99.406791 -315.794052)
			(xy 99.390762 -315.877218) (xy 99.366901 -315.958485) (xy 99.335422 -316.037115) (xy 99.296611 -316.112396)
			(xy 99.250821 -316.183648) (xy 99.198465 -316.250224) (xy 99.140017 -316.311522) (xy 99.076007 -316.366987)
			(xy 99.007015 -316.416116) (xy 98.933665 -316.458465) (xy 98.856622 -316.493649) (xy 98.776583 -316.521351)
			(xy 98.694274 -316.541319) (xy 98.610439 -316.553372) (xy 98.525838 -316.557403) (xy 98.441237 -316.553372)
			(xy 98.357402 -316.541319) (xy 98.275093 -316.521351) (xy 98.195054 -316.493649) (xy 98.118011 -316.458465)
			(xy 98.044661 -316.416116) (xy 97.975669 -316.366987) (xy 97.911659 -316.311522) (xy 97.853211 -316.250224)
			(xy 97.800855 -316.183648) (xy 97.755065 -316.112396) (xy 97.716254 -316.037115) (xy 97.684775 -315.958485)
			(xy 97.660914 -315.877218) (xy 97.644885 -315.794052) (xy 97.636834 -315.709738) (xy 92.660134 -315.709738)
			(xy 76.590652 -331.558646) (xy 76.587163 -331.562258) (xy 76.581541 -331.570578) (xy 76.579476 -331.575156)
			(xy 76.504546 -331.75575) (xy 76.449936 -331.887576) (xy 76.44892 -331.89164) (xy 76.447396 -331.903832)
			(xy 76.447396 -332.54823) (xy 76.44771 -332.556422) (xy 76.452899 -332.571963) (xy 76.457556 -332.57871)
			(xy 76.462382 -332.584298) (xy 76.794868 -332.916784) (xy 76.800456 -332.92161) (xy 76.807197 -332.926276)
			(xy 76.822743 -332.93145) (xy 76.830936 -332.93177)
		)
		(stroke
			(width 0)
			(type solid)
		)
		(fill yes)
		(layer "In4.Cu")
		(net "PVCCIN_CPU1")
	)
	(gr_poly
		(pts
			(xy 118.266464 -273.128486) (xy 118.281935 -273.125715) (xy 118.313231 -273.12279) (xy 118.328948 -273.122644)
			(xy 118.344664 -273.12281) (xy 118.375957 -273.12574) (xy 118.391432 -273.128486) (xy 118.396004 -273.129502)
			(xy 119.201692 -273.129502) (xy 119.206264 -273.128486) (xy 119.221735 -273.125715) (xy 119.253031 -273.12279)
			(xy 119.268748 -273.122644) (xy 119.284464 -273.12281) (xy 119.315757 -273.12574) (xy 119.331232 -273.128486)
			(xy 119.335804 -273.129502) (xy 120.141492 -273.129502) (xy 120.146064 -273.128486) (xy 120.161535 -273.125715)
			(xy 120.192831 -273.12279) (xy 120.208548 -273.122644) (xy 120.224264 -273.12281) (xy 120.255557 -273.12574)
			(xy 120.271032 -273.128486) (xy 120.275604 -273.129502) (xy 121.081292 -273.129502) (xy 121.085864 -273.128486)
			(xy 121.101335 -273.125715) (xy 121.132631 -273.12279) (xy 121.148348 -273.122644) (xy 121.164064 -273.12281)
			(xy 121.195357 -273.12574) (xy 121.210832 -273.128486) (xy 121.215404 -273.129502) (xy 122.021092 -273.129502)
			(xy 122.025664 -273.128486) (xy 122.041135 -273.125715) (xy 122.072431 -273.12279) (xy 122.088148 -273.122644)
			(xy 122.103864 -273.12281) (xy 122.135157 -273.12574) (xy 122.150632 -273.128486) (xy 122.155204 -273.129502)
			(xy 122.960638 -273.129502) (xy 122.96521 -273.128486) (xy 122.980681 -273.125713) (xy 123.011977 -273.122783)
			(xy 123.027694 -273.122644) (xy 123.04341 -273.122807) (xy 123.074705 -273.125732) (xy 123.090178 -273.128486)
			(xy 123.09475 -273.129502) (xy 123.900692 -273.129502) (xy 123.905264 -273.128486) (xy 123.920735 -273.125715)
			(xy 123.952031 -273.12279) (xy 123.967748 -273.122644) (xy 123.983464 -273.12281) (xy 124.014757 -273.12574)
			(xy 124.030232 -273.128486) (xy 124.034804 -273.129502) (xy 124.840492 -273.129502) (xy 124.845064 -273.128486)
			(xy 124.860535 -273.125715) (xy 124.891831 -273.12279) (xy 124.907548 -273.122644) (xy 124.923264 -273.12281)
			(xy 124.954557 -273.12574) (xy 124.970032 -273.128486) (xy 124.974604 -273.129502) (xy 125.780292 -273.129502)
			(xy 125.784864 -273.128486) (xy 125.800335 -273.125715) (xy 125.831631 -273.12279) (xy 125.847348 -273.122644)
			(xy 125.863064 -273.12281) (xy 125.894357 -273.12574) (xy 125.909832 -273.128486) (xy 125.914404 -273.129502)
			(xy 126.520956 -273.129502) (xy 126.893066 -272.757392) (xy 126.893066 -272.257266) (xy 126.892655 -272.243863)
			(xy 126.885665 -272.217983) (xy 126.872176 -272.194816) (xy 126.85312 -272.175962) (xy 126.829811 -272.162721)
			(xy 126.803858 -272.156008) (xy 126.79045 -272.155666) (xy 126.787148 -272.155666) (xy 126.761175 -272.155187)
			(xy 126.709869 -272.147067) (xy 126.660464 -272.131021) (xy 126.614178 -272.107443) (xy 126.572151 -272.076914)
			(xy 126.535417 -272.040186) (xy 126.504882 -271.998163) (xy 126.481297 -271.951881) (xy 126.465244 -271.902478)
			(xy 126.457117 -271.851173) (xy 126.457117 -271.799227) (xy 126.465244 -271.747922) (xy 126.481297 -271.698519)
			(xy 126.504882 -271.652237) (xy 126.535417 -271.610214) (xy 126.572151 -271.573486) (xy 126.614178 -271.542957)
			(xy 126.660464 -271.519379) (xy 126.709869 -271.503333) (xy 126.761175 -271.495213) (xy 126.787148 -271.494758)
			(xy 126.79045 -271.494758) (xy 126.803863 -271.494489) (xy 126.829827 -271.48777) (xy 126.853143 -271.474517)
			(xy 126.872201 -271.455647) (xy 126.885684 -271.432464) (xy 126.892662 -271.406568) (xy 126.893066 -271.393158)
			(xy 126.893066 -270.629634) (xy 126.892663 -270.616225) (xy 126.885685 -270.59033) (xy 126.8722 -270.567147)
			(xy 126.853142 -270.548279) (xy 126.829826 -270.535027) (xy 126.803863 -270.528308) (xy 126.79045 -270.528034)
			(xy 126.787148 -270.528034) (xy 126.761178 -270.527555) (xy 126.709876 -270.519436) (xy 126.660476 -270.503392)
			(xy 126.614195 -270.479816) (xy 126.572171 -270.44929) (xy 126.535441 -270.412565) (xy 126.504909 -270.370546)
			(xy 126.481327 -270.324268) (xy 126.465275 -270.274871) (xy 126.457149 -270.22357) (xy 126.457149 -270.17163)
			(xy 126.465275 -270.120329) (xy 126.481327 -270.070932) (xy 126.504909 -270.024654) (xy 126.535441 -269.982635)
			(xy 126.572171 -269.94591) (xy 126.614195 -269.915384) (xy 126.660476 -269.891808) (xy 126.709876 -269.875764)
			(xy 126.761178 -269.867645) (xy 126.787148 -269.867126) (xy 126.79045 -269.867126) (xy 126.803866 -269.866857)
			(xy 126.829837 -269.860139) (xy 126.853162 -269.846888) (xy 126.872231 -269.82802) (xy 126.885728 -269.804837)
			(xy 126.892721 -269.778939) (xy 126.893066 -269.765526) (xy 126.893066 -269.001748) (xy 126.892653 -268.988346)
			(xy 126.88566 -268.96247) (xy 126.87217 -268.939308) (xy 126.853114 -268.920457) (xy 126.829807 -268.90722)
			(xy 126.803857 -268.900507) (xy 126.79045 -268.900148) (xy 126.787148 -268.900148) (xy 126.761177 -268.899669)
			(xy 126.709873 -268.89155) (xy 126.660471 -268.875505) (xy 126.614187 -268.851928) (xy 126.572162 -268.821401)
			(xy 126.535431 -268.784674) (xy 126.504897 -268.742654) (xy 126.481314 -268.696374) (xy 126.465261 -268.646974)
			(xy 126.457135 -268.595671) (xy 126.457135 -268.543729) (xy 126.465261 -268.492426) (xy 126.481314 -268.443026)
			(xy 126.504897 -268.396746) (xy 126.535431 -268.354726) (xy 126.572162 -268.317999) (xy 126.614187 -268.287472)
			(xy 126.660471 -268.263895) (xy 126.709873 -268.24785) (xy 126.761177 -268.239731) (xy 126.787148 -268.23924)
			(xy 126.79045 -268.23924) (xy 126.803867 -268.238972) (xy 126.829839 -268.232253) (xy 126.853166 -268.219003)
			(xy 126.872237 -268.200136) (xy 126.885737 -268.176952) (xy 126.892733 -268.151053) (xy 126.893066 -268.13764)
			(xy 126.893066 -267.373862) (xy 126.892654 -267.360459) (xy 126.885664 -267.33458) (xy 126.872175 -267.311414)
			(xy 126.853118 -267.292561) (xy 126.82981 -267.279321) (xy 126.803858 -267.272608) (xy 126.79045 -267.272262)
			(xy 126.787148 -267.272262) (xy 126.761176 -267.271783) (xy 126.709869 -267.263663) (xy 126.660465 -267.247617)
			(xy 126.61418 -267.22404) (xy 126.572153 -267.193511) (xy 126.53542 -267.156783) (xy 126.504885 -267.114761)
			(xy 126.481301 -267.068479) (xy 126.465248 -267.019077) (xy 126.457121 -266.967772) (xy 126.457121 -266.915828)
			(xy 126.465248 -266.864523) (xy 126.481301 -266.815121) (xy 126.504885 -266.768839) (xy 126.53542 -266.726817)
			(xy 126.572153 -266.690089) (xy 126.61418 -266.65956) (xy 126.660465 -266.635983) (xy 126.709869 -266.619937)
			(xy 126.761176 -266.611817) (xy 126.787148 -266.611354) (xy 126.79045 -266.611354) (xy 126.803863 -266.611085)
			(xy 126.829826 -266.604365) (xy 126.853142 -266.591113) (xy 126.872199 -266.572243) (xy 126.885682 -266.549059)
			(xy 126.892658 -266.523164) (xy 126.893066 -266.509754) (xy 126.893066 -265.74623) (xy 126.892663 -265.732821)
			(xy 126.885683 -265.706927) (xy 126.872199 -265.683746) (xy 126.853141 -265.664878) (xy 126.829825 -265.651627)
			(xy 126.803863 -265.644908) (xy 126.79045 -265.64463) (xy 126.786894 -265.64463) (xy 126.760929 -265.64412)
			(xy 126.709638 -265.635996) (xy 126.66025 -265.619948) (xy 126.61398 -265.596372) (xy 126.571969 -265.565847)
			(xy 126.535249 -265.529127) (xy 126.504725 -265.487114) (xy 126.48115 -265.440844) (xy 126.465103 -265.391456)
			(xy 126.456979 -265.340165) (xy 126.456979 -265.288235) (xy 126.465103 -265.236944) (xy 126.48115 -265.187556)
			(xy 126.504725 -265.141286) (xy 126.535249 -265.099273) (xy 126.571969 -265.062553) (xy 126.61398 -265.032028)
			(xy 126.66025 -265.008452) (xy 126.709638 -264.992404) (xy 126.760929 -264.98428) (xy 126.786894 -264.983722)
			(xy 126.79045 -264.983722) (xy 126.803866 -264.983453) (xy 126.829837 -264.976735) (xy 126.853161 -264.963484)
			(xy 126.872229 -264.944616) (xy 126.885725 -264.921433) (xy 126.892717 -264.895535) (xy 126.893066 -264.882122)
			(xy 126.893066 -264.118598) (xy 126.892659 -264.105192) (xy 126.885674 -264.079305) (xy 126.872188 -264.056131)
			(xy 126.85313 -264.03727) (xy 126.829818 -264.024024) (xy 126.80386 -264.017308) (xy 126.79045 -264.016998)
			(xy 126.787148 -264.016998) (xy 126.761173 -264.016519) (xy 126.709861 -264.008399) (xy 126.660452 -263.992351)
			(xy 126.614161 -263.96877) (xy 126.57213 -263.938239) (xy 126.535393 -263.901507) (xy 126.504855 -263.85948)
			(xy 126.481268 -263.813193) (xy 126.465213 -263.763786) (xy 126.457085 -263.712475) (xy 126.457085 -263.660525)
			(xy 126.465213 -263.609214) (xy 126.481268 -263.559807) (xy 126.504855 -263.51352) (xy 126.535393 -263.471493)
			(xy 126.57213 -263.434761) (xy 126.614161 -263.40423) (xy 126.660452 -263.380649) (xy 126.709861 -263.364601)
			(xy 126.761173 -263.356481) (xy 126.787148 -263.35609) (xy 126.79045 -263.35609) (xy 126.803865 -263.355821)
			(xy 126.829832 -263.349102) (xy 126.853152 -263.335851) (xy 126.872215 -263.316982) (xy 126.885705 -263.293798)
			(xy 126.892689 -263.267901) (xy 126.893066 -263.25449) (xy 126.893066 -262.490712) (xy 126.89266 -262.477304)
			(xy 126.885678 -262.451415) (xy 126.872193 -262.428237) (xy 126.853135 -262.409373) (xy 126.829821 -262.396125)
			(xy 126.803861 -262.389408) (xy 126.79045 -262.389112) (xy 126.787148 -262.389112) (xy 126.76118 -262.388633)
			(xy 126.709881 -262.380515) (xy 126.660484 -262.364471) (xy 126.614206 -262.340897) (xy 126.572186 -262.310373)
			(xy 126.535458 -262.273651) (xy 126.504928 -262.231635) (xy 126.481347 -262.18536) (xy 126.465296 -262.135966)
			(xy 126.457171 -262.084668) (xy 126.457171 -262.032732) (xy 126.465296 -261.981434) (xy 126.481347 -261.93204)
			(xy 126.504928 -261.885765) (xy 126.535458 -261.843749) (xy 126.572186 -261.807027) (xy 126.614206 -261.776503)
			(xy 126.660484 -261.752929) (xy 126.709881 -261.736885) (xy 126.76118 -261.728767) (xy 126.787148 -261.728204)
			(xy 126.799131 -261.728327) (xy 126.82303 -261.730111) (xy 126.8349 -261.73176) (xy 126.838456 -261.732268)
			(xy 126.893066 -261.732268) (xy 126.893066 -261.63016) (xy 126.717044 -261.454138) (xy 126.706851 -261.444553)
			(xy 126.68246 -261.430864) (xy 126.655272 -261.424298) (xy 126.627322 -261.425349) (xy 126.600703 -261.433937)
			(xy 126.577409 -261.449419) (xy 126.567946 -261.459726) (xy 126.552187 -261.477523) (xy 126.516436 -261.508852)
			(xy 126.476561 -261.53473) (xy 126.433387 -261.554621) (xy 126.387806 -261.568114) (xy 126.340762 -261.574931)
			(xy 126.316994 -261.575296) (xy 126.291026 -261.574786) (xy 126.239729 -261.566662) (xy 126.190335 -261.550613)
			(xy 126.144059 -261.527036) (xy 126.10204 -261.49651) (xy 126.065314 -261.459787) (xy 126.034783 -261.417772)
			(xy 126.011201 -261.371499) (xy 125.995147 -261.322106) (xy 125.987016 -261.27081) (xy 125.98654 -261.244842)
			(xy 125.986958 -261.221078) (xy 125.993779 -261.174042) (xy 126.007272 -261.12847) (xy 126.027159 -261.085302)
			(xy 126.053028 -261.045431) (xy 126.084345 -261.009681) (xy 126.10211 -260.99389) (xy 126.112466 -260.984464)
			(xy 126.128007 -260.96118) (xy 126.136623 -260.934546) (xy 126.137666 -260.906572) (xy 126.131056 -260.87937)
			(xy 126.117293 -260.854994) (xy 126.107698 -260.844792) (xy 125.992382 -260.729476) (xy 125.961902 -260.740652)
			(xy 125.934237 -260.750231) (xy 125.876618 -260.760576) (xy 125.847348 -260.761226) (xy 125.821377 -260.760747)
			(xy 125.770074 -260.752628) (xy 125.720673 -260.736582) (xy 125.67439 -260.713004) (xy 125.632367 -260.682476)
			(xy 125.595637 -260.645748) (xy 125.565106 -260.603727) (xy 125.541526 -260.557446) (xy 125.525477 -260.508046)
			(xy 125.517355 -260.456743) (xy 125.516894 -260.430772) (xy 125.51738 -260.404839) (xy 125.525444 -260.353606)
			(xy 125.541416 -260.304262) (xy 125.552708 -260.280912) (xy 125.558296 -260.270244) (xy 125.558296 -260.041644)
			(xy 125.557783 -260.026734) (xy 125.549185 -259.99818) (xy 125.532709 -259.973326) (xy 125.509758 -259.954287)
			(xy 125.482287 -259.942686) (xy 125.452637 -259.939511) (xy 125.4379 -259.941822) (xy 125.42286 -259.944439)
			(xy 125.392459 -259.947234) (xy 125.377194 -259.94741) (xy 125.351231 -259.9469) (xy 125.299943 -259.938776)
			(xy 125.250558 -259.922729) (xy 125.204291 -259.899154) (xy 125.162281 -259.868632) (xy 125.125564 -259.831914)
			(xy 125.095042 -259.789904) (xy 125.071468 -259.743637) (xy 125.055422 -259.694251) (xy 125.047299 -259.642963)
			(xy 125.047299 -259.591037) (xy 125.055422 -259.539749) (xy 125.071468 -259.490363) (xy 125.095042 -259.444096)
			(xy 125.125564 -259.402086) (xy 125.162281 -259.365368) (xy 125.204291 -259.334846) (xy 125.250558 -259.311271)
			(xy 125.299943 -259.295224) (xy 125.351231 -259.2871) (xy 125.377194 -259.286502) (xy 125.39246 -259.286661)
			(xy 125.422862 -259.289461) (xy 125.4379 -259.29209) (xy 125.452645 -259.294337) (xy 125.482287 -259.291164)
			(xy 125.509753 -259.279572) (xy 125.532706 -259.260549) (xy 125.549194 -259.235712) (xy 125.557815 -259.207174)
			(xy 125.558296 -259.192268) (xy 125.558296 -258.963668) (xy 125.552708 -258.953) (xy 125.541417 -258.929649)
			(xy 125.525443 -258.880305) (xy 125.517369 -258.829073) (xy 125.516894 -258.80314) (xy 125.517383 -258.777208)
			(xy 125.525451 -258.725976) (xy 125.541427 -258.676635) (xy 125.552708 -258.65328) (xy 125.558296 -258.642612)
			(xy 125.558296 -258.413758) (xy 125.557786 -258.398874) (xy 125.549214 -258.370367) (xy 125.532781 -258.345546)
			(xy 125.509885 -258.326522) (xy 125.482474 -258.314913) (xy 125.452879 -258.311706) (xy 125.438154 -258.313936)
			(xy 125.423114 -258.316555) (xy 125.392713 -258.319355) (xy 125.377448 -258.319524) (xy 125.351479 -258.319045)
			(xy 125.300178 -258.310927) (xy 125.25078 -258.294882) (xy 125.2045 -258.271307) (xy 125.162478 -258.240782)
			(xy 125.125749 -258.204059) (xy 125.095218 -258.162041) (xy 125.071636 -258.115765) (xy 125.055585 -258.066368)
			(xy 125.047459 -258.015069) (xy 125.047459 -257.963131) (xy 125.055585 -257.911832) (xy 125.071636 -257.862435)
			(xy 125.095218 -257.816159) (xy 125.125749 -257.774141) (xy 125.162478 -257.737418) (xy 125.2045 -257.706893)
			(xy 125.25078 -257.683318) (xy 125.300178 -257.667273) (xy 125.351479 -257.659155) (xy 125.377448 -257.658616)
			(xy 125.392714 -257.658773) (xy 125.423117 -257.661569) (xy 125.438154 -257.664204) (xy 125.452877 -257.666413)
			(xy 125.482459 -257.663185) (xy 125.509857 -257.65157) (xy 125.532747 -257.632554) (xy 125.549187 -257.60775)
			(xy 125.557784 -257.579261) (xy 125.558296 -257.564382) (xy 125.558296 -257.33629) (xy 125.552708 -257.325368)
			(xy 125.541338 -257.301998) (xy 125.525275 -257.252573) (xy 125.517146 -257.201244) (xy 125.517153 -257.149274)
			(xy 125.525294 -257.097947) (xy 125.54137 -257.048526) (xy 125.552708 -257.02514) (xy 125.558296 -257.014218)
			(xy 125.558296 -256.786126) (xy 125.55778 -256.771218) (xy 125.549179 -256.742669) (xy 125.532703 -256.717819)
			(xy 125.509753 -256.698784) (xy 125.482285 -256.687185) (xy 125.452638 -256.684011) (xy 125.4379 -256.686304)
			(xy 125.42286 -256.688921) (xy 125.392459 -256.691716) (xy 125.377194 -256.691892) (xy 125.351224 -256.691382)
			(xy 125.299924 -256.683256) (xy 125.250526 -256.667205) (xy 125.204248 -256.643624) (xy 125.162228 -256.613095)
			(xy 125.125502 -256.576367) (xy 125.094972 -256.534347) (xy 125.071393 -256.488068) (xy 125.055342 -256.43867)
			(xy 125.047217 -256.38737) (xy 125.047217 -256.33543) (xy 125.055342 -256.28413) (xy 125.071393 -256.234732)
			(xy 125.094972 -256.188453) (xy 125.125502 -256.146433) (xy 125.162228 -256.109705) (xy 125.204248 -256.079176)
			(xy 125.250526 -256.055595) (xy 125.299924 -256.039544) (xy 125.351224 -256.031418) (xy 125.377194 -256.030984)
			(xy 125.39246 -256.031143) (xy 125.422862 -256.033943) (xy 125.4379 -256.036572) (xy 125.452644 -256.03882)
			(xy 125.482284 -256.035646) (xy 125.509748 -256.024054) (xy 125.532699 -256.00503) (xy 125.549184 -255.980193)
			(xy 125.5578 -255.951655) (xy 125.558296 -255.93675) (xy 125.558296 -255.70815) (xy 125.552708 -255.697482)
			(xy 125.541419 -255.674131) (xy 125.525447 -255.624787) (xy 125.517376 -255.573554) (xy 125.516894 -255.547622)
			(xy 125.517384 -255.52169) (xy 125.525455 -255.47046) (xy 125.541434 -255.42112) (xy 125.552708 -255.397762)
			(xy 125.558296 -255.387094) (xy 125.558296 -255.15824) (xy 125.557782 -255.14333) (xy 125.549184 -255.114778)
			(xy 125.532707 -255.089924) (xy 125.509757 -255.070886) (xy 125.482287 -255.059286) (xy 125.452637 -255.056111)
			(xy 125.4379 -255.058418) (xy 125.42286 -255.061035) (xy 125.392459 -255.06383) (xy 125.377194 -255.064006)
			(xy 125.351231 -255.063496) (xy 125.299944 -255.055373) (xy 125.250559 -255.039326) (xy 125.204293 -255.015751)
			(xy 125.162284 -254.985229) (xy 125.125567 -254.948511) (xy 125.095046 -254.906502) (xy 125.071472 -254.860235)
			(xy 125.055426 -254.81085) (xy 125.047303 -254.759563) (xy 125.047303 -254.707637) (xy 125.055426 -254.65635)
			(xy 125.071472 -254.606965) (xy 125.095046 -254.560698) (xy 125.125567 -254.518689) (xy 125.162284 -254.481971)
			(xy 125.204293 -254.451449) (xy 125.250559 -254.427874) (xy 125.299944 -254.411827) (xy 125.351231 -254.403704)
			(xy 125.377194 -254.403098) (xy 125.39246 -254.403257) (xy 125.422862 -254.406057) (xy 125.4379 -254.408686)
			(xy 125.452644 -254.410933) (xy 125.482286 -254.40776) (xy 125.509752 -254.396168) (xy 125.532705 -254.377145)
			(xy 125.549192 -254.352307) (xy 125.557812 -254.323769) (xy 125.558296 -254.308864) (xy 125.558296 -254.080264)
			(xy 125.552708 -254.069596) (xy 125.541418 -254.046245) (xy 125.525444 -253.996901) (xy 125.517371 -253.945669)
			(xy 125.516894 -253.919736) (xy 125.517383 -253.893804) (xy 125.525452 -253.842573) (xy 125.541429 -253.793232)
			(xy 125.552708 -253.769876) (xy 125.558296 -253.759208) (xy 125.558296 -253.419864) (xy 124.0282 -251.889768)
			(xy 124.0282 -249.76074) (xy 124.024136 -249.751088) (xy 124.015551 -249.730315) (xy 124.00345 -249.687028)
			(xy 123.997342 -249.642498) (xy 123.996958 -249.620024) (xy 123.997359 -249.597553) (xy 124.003486 -249.553029)
			(xy 124.015578 -249.509742) (xy 124.024136 -249.48896) (xy 124.0282 -249.479308) (xy 124.0282 -249.232674)
			(xy 124.02771 -249.217979) (xy 124.019344 -249.189805) (xy 124.003313 -249.165173) (xy 123.980938 -249.146117)
			(xy 123.954068 -249.134211) (xy 123.924921 -249.130438) (xy 123.910344 -249.132344) (xy 123.897291 -249.134347)
			(xy 123.87097 -249.136506) (xy 123.857766 -249.136662) (xy 123.8318 -249.13615) (xy 123.780508 -249.128021)
			(xy 123.731119 -249.111969) (xy 123.684848 -249.088389) (xy 123.642836 -249.057862) (xy 123.606116 -249.021138)
			(xy 123.575593 -248.979123) (xy 123.552018 -248.93285) (xy 123.535971 -248.883459) (xy 123.527847 -248.832166)
			(xy 123.527847 -248.780234) (xy 123.535971 -248.728941) (xy 123.552018 -248.67955) (xy 123.575593 -248.633277)
			(xy 123.606116 -248.591262) (xy 123.642836 -248.554538) (xy 123.684848 -248.524011) (xy 123.731119 -248.500431)
			(xy 123.780508 -248.484379) (xy 123.8318 -248.47625) (xy 123.857766 -248.475754) (xy 123.883093 -248.476212)
			(xy 123.933154 -248.483941) (xy 123.981447 -248.499224) (xy 124.02684 -248.521702) (xy 124.068269 -248.550848)
			(xy 124.104762 -248.585978) (xy 124.135462 -248.626268) (xy 124.15965 -248.670774) (xy 124.168662 -248.694448)
			(xy 124.17404 -248.708092) (xy 124.191328 -248.731766) (xy 124.214636 -248.749545) (xy 124.242038 -248.75996)
			(xy 124.27127 -248.762151) (xy 124.299919 -248.755938) (xy 124.325617 -248.741833) (xy 124.336302 -248.731786)
			(xy 124.957332 -248.110756) (xy 124.949204 -248.082054) (xy 124.943375 -248.060034) (xy 124.937133 -248.014913)
			(xy 124.936758 -247.992138) (xy 124.937238 -247.966167) (xy 124.945358 -247.914864) (xy 124.961405 -247.865463)
			(xy 124.984983 -247.819181) (xy 125.015511 -247.777158) (xy 125.052238 -247.740428) (xy 125.094259 -247.709896)
			(xy 125.140539 -247.686315) (xy 125.189939 -247.670264) (xy 125.241241 -247.66214) (xy 125.267212 -247.661684)
			(xy 125.289986 -247.662069) (xy 125.335104 -247.66832) (xy 125.357128 -247.67413) (xy 125.38583 -247.682258)
			(xy 125.508004 -247.560084) (xy 125.517222 -247.550281) (xy 125.530616 -247.526952) (xy 125.537454 -247.500936)
			(xy 125.537265 -247.474036) (xy 125.53006 -247.448119) (xy 125.516339 -247.424981) (xy 125.506988 -247.415304)
			(xy 125.488402 -247.396495) (xy 125.456853 -247.354063) (xy 125.432456 -247.307152) (xy 125.415831 -247.256959)
			(xy 125.407401 -247.20476) (xy 125.406912 -247.178322) (xy 125.40742 -247.152353) (xy 125.415541 -247.101053)
			(xy 125.431587 -247.051655) (xy 125.455163 -247.005376) (xy 125.485689 -246.963354) (xy 125.522412 -246.926625)
			(xy 125.564428 -246.896093) (xy 125.610703 -246.872509) (xy 125.660098 -246.856454) (xy 125.711397 -246.848324)
			(xy 125.737366 -246.847868) (xy 125.763803 -246.848385) (xy 125.816004 -246.856797) (xy 125.8662 -246.873412)
			(xy 125.913111 -246.897806) (xy 125.95554 -246.929358) (xy 125.974348 -246.947944) (xy 125.984019 -246.957298)
			(xy 126.007154 -246.971014) (xy 126.033069 -246.978213) (xy 126.059965 -246.978395) (xy 126.085974 -246.971546)
			(xy 126.109293 -246.958143) (xy 126.119128 -246.94896) (xy 126.205996 -246.862092) (xy 126.215554 -246.851948)
			(xy 126.229226 -246.827671) (xy 126.235823 -246.800602) (xy 126.234852 -246.772757) (xy 126.226388 -246.746213)
			(xy 126.211059 -246.722946) (xy 126.19001 -246.704693) (xy 126.164808 -246.692813) (xy 126.151132 -246.690134)
			(xy 126.125861 -246.685295) (xy 126.077115 -246.668829) (xy 126.03151 -246.645009) (xy 125.990147 -246.614409)
			(xy 125.954025 -246.577769) (xy 125.924018 -246.535974) (xy 125.90085 -246.490034) (xy 125.885081 -246.441059)
			(xy 125.877091 -246.390232) (xy 125.876558 -246.364506) (xy 125.87704 -246.338537) (xy 125.885165 -246.287238)
			(xy 125.901214 -246.237841) (xy 125.924794 -246.191563) (xy 125.955323 -246.149544) (xy 125.992049 -246.112819)
			(xy 126.034069 -246.082291) (xy 126.080347 -246.058712) (xy 126.129743 -246.042663) (xy 126.181043 -246.03454)
			(xy 126.207012 -246.034052) (xy 126.232745 -246.034536) (xy 126.28359 -246.042504) (xy 126.332585 -246.058261)
			(xy 126.378543 -246.081425) (xy 126.420353 -246.111436) (xy 126.457003 -246.147567) (xy 126.487606 -246.188946)
			(xy 126.511422 -246.23457) (xy 126.527874 -246.283335) (xy 126.53264 -246.308626) (xy 126.535407 -246.322263)
			(xy 126.547318 -246.347399) (xy 126.56557 -246.368389) (xy 126.588808 -246.383677) (xy 126.615309 -246.392127)
			(xy 126.643107 -246.393115) (xy 126.670141 -246.386565) (xy 126.694405 -246.372965) (xy 126.704598 -246.36349)
			(xy 126.850902 -246.217186) (xy 126.854458 -246.210328) (xy 126.866425 -246.18859) (xy 126.895872 -246.148653)
			(xy 126.930959 -246.113567) (xy 126.970897 -246.08412) (xy 126.992634 -246.072152) (xy 126.999492 -246.068596)
			(xy 127.337312 -245.730776) (xy 127.321056 -245.69801) (xy 127.310102 -245.675012) (xy 127.29461 -245.626486)
			(xy 127.286741 -245.576159) (xy 127.286258 -245.55069) (xy 127.286742 -245.524722) (xy 127.294868 -245.473424)
			(xy 127.310919 -245.42403) (xy 127.334499 -245.377755) (xy 127.365028 -245.335738) (xy 127.401754 -245.299014)
			(xy 127.443773 -245.268488) (xy 127.49005 -245.24491) (xy 127.539446 -245.228863) (xy 127.590744 -245.22074)
			(xy 127.616712 -245.220236) (xy 127.642181 -245.220724) (xy 127.692511 -245.22858) (xy 127.741037 -245.244073)
			(xy 127.764032 -245.255034) (xy 127.796798 -245.27129) (xy 127.907796 -245.160292) (xy 127.917823 -245.149513)
			(xy 127.93177 -245.123602) (xy 127.93776 -245.094791) (xy 127.935297 -245.065468) (xy 127.924584 -245.038061)
			(xy 127.906509 -245.014839) (xy 127.894842 -245.00586) (xy 127.873779 -244.990219) (xy 127.836414 -244.953396)
			(xy 127.805331 -244.911135) (xy 127.781309 -244.864497) (xy 127.764951 -244.814653) (xy 127.756666 -244.76285)
			(xy 127.756158 -244.73662) (xy 127.756596 -244.712204) (xy 127.763781 -244.663904) (xy 127.777999 -244.617188)
			(xy 127.798939 -244.573075) (xy 127.826145 -244.532524) (xy 127.859024 -244.49642) (xy 127.896859 -244.46555)
			(xy 127.938827 -244.440585) (xy 127.984013 -244.422071) (xy 128.007618 -244.415818) (xy 128.046226 -244.406166)
			(xy 128.046226 -244.20449) (xy 128.045773 -244.190747) (xy 128.038438 -244.164257) (xy 128.024303 -244.140684)
			(xy 128.004392 -244.121735) (xy 127.980148 -244.108785) (xy 127.953328 -244.10277) (xy 127.925875 -244.104128)
			(xy 127.899779 -244.11276) (xy 127.876932 -244.12804) (xy 127.867664 -244.138196) (xy 127.851885 -244.155915)
			(xy 127.816123 -244.187095) (xy 127.776273 -244.212846) (xy 127.733153 -244.232638) (xy 127.687647 -244.246066)
			(xy 127.640689 -244.252855) (xy 127.616966 -244.253258) (xy 127.591 -244.252746) (xy 127.539709 -244.244618)
			(xy 127.49032 -244.228566) (xy 127.44405 -244.204986) (xy 127.402039 -244.174459) (xy 127.365319 -244.137736)
			(xy 127.334796 -244.095721) (xy 127.311221 -244.049448) (xy 127.295175 -244.000058) (xy 127.287051 -243.948766)
			(xy 127.287051 -243.896834) (xy 127.295175 -243.845542) (xy 127.311221 -243.796152) (xy 127.334796 -243.749879)
			(xy 127.365319 -243.707864) (xy 127.402039 -243.671141) (xy 127.44405 -243.640614) (xy 127.49032 -243.617034)
			(xy 127.539709 -243.600982) (xy 127.591 -243.592854) (xy 127.616966 -243.59235) (xy 127.640689 -243.592757)
			(xy 127.687649 -243.599536) (xy 127.733157 -243.612959) (xy 127.776279 -243.632752) (xy 127.816127 -243.658506)
			(xy 127.851884 -243.689693) (xy 127.867664 -243.707412) (xy 127.876973 -243.717521) (xy 127.899807 -243.732791)
			(xy 127.925887 -243.741417) (xy 127.953324 -243.742774) (xy 127.980128 -243.736763) (xy 128.004357 -243.723821)
			(xy 128.024257 -243.704884) (xy 128.038385 -243.681326) (xy 128.045716 -243.654853) (xy 128.046226 -243.641118)
			(xy 128.046226 -243.439442) (xy 128.007618 -243.42979) (xy 127.982639 -243.423125) (xy 127.934979 -243.403097)
			(xy 127.89102 -243.375891) (xy 127.851835 -243.342169) (xy 127.818382 -243.302756) (xy 127.791476 -243.258612)
			(xy 127.771774 -243.210817) (xy 127.759757 -243.160536) (xy 127.755719 -243.108997) (xy 127.759758 -243.057458)
			(xy 127.771775 -243.007178) (xy 127.791478 -242.959382) (xy 127.818385 -242.91524) (xy 127.851839 -242.875827)
			(xy 127.891025 -242.842106) (xy 127.934984 -242.8149) (xy 127.982644 -242.794873) (xy 128.007618 -242.788186)
			(xy 128.046226 -242.778534) (xy 128.046226 -242.576604) (xy 128.045775 -242.562859) (xy 128.038442 -242.536366)
			(xy 128.024308 -242.512789) (xy 128.004396 -242.493838) (xy 127.98015 -242.480885) (xy 127.953327 -242.47487)
			(xy 127.925871 -242.476229) (xy 127.899773 -242.484863) (xy 127.876925 -242.500146) (xy 127.867664 -242.51031)
			(xy 127.851884 -242.528028) (xy 127.816122 -242.559207) (xy 127.776272 -242.584957) (xy 127.733152 -242.604748)
			(xy 127.687646 -242.618176) (xy 127.640689 -242.624964) (xy 127.616966 -242.625372) (xy 127.590999 -242.62486)
			(xy 127.539705 -242.616731) (xy 127.490315 -242.600679) (xy 127.444043 -242.577098) (xy 127.402029 -242.546569)
			(xy 127.365309 -242.509845) (xy 127.334784 -242.467828) (xy 127.311208 -242.421554) (xy 127.295161 -242.372161)
			(xy 127.287037 -242.320867) (xy 127.287037 -242.268933) (xy 127.295161 -242.217639) (xy 127.311208 -242.168246)
			(xy 127.334784 -242.121972) (xy 127.365309 -242.079955) (xy 127.402029 -242.043231) (xy 127.444043 -242.012702)
			(xy 127.490315 -241.989121) (xy 127.539705 -241.973069) (xy 127.590999 -241.96494) (xy 127.616966 -241.964464)
			(xy 127.640689 -241.964871) (xy 127.687649 -241.97165) (xy 127.733157 -241.985074) (xy 127.776277 -242.004867)
			(xy 127.816125 -242.030622) (xy 127.851881 -242.06181) (xy 127.867664 -242.079526) (xy 127.876974 -242.089634)
			(xy 127.899809 -242.104902) (xy 127.92589 -242.113527) (xy 127.953325 -242.114883) (xy 127.980129 -242.108872)
			(xy 128.004359 -242.095931) (xy 128.02426 -242.076996) (xy 128.038389 -242.053439) (xy 128.045724 -242.026967)
			(xy 128.046226 -242.013232) (xy 128.046226 -241.811556) (xy 128.007618 -241.801904) (xy 127.982638 -241.795239)
			(xy 127.934975 -241.775211) (xy 127.891015 -241.748004) (xy 127.851828 -241.714281) (xy 127.818373 -241.674866)
			(xy 127.791465 -241.630722) (xy 127.771762 -241.582924) (xy 127.759744 -241.532642) (xy 127.755705 -241.4811)
			(xy 127.759744 -241.429559) (xy 127.771762 -241.379277) (xy 127.791465 -241.331479) (xy 127.818372 -241.287334)
			(xy 127.851827 -241.24792) (xy 127.891014 -241.214197) (xy 127.934975 -241.186989) (xy 127.982637 -241.166962)
			(xy 128.007618 -241.1603) (xy 128.046226 -241.150648) (xy 128.046226 -240.948972) (xy 128.045771 -240.935231)
			(xy 128.038433 -240.908745) (xy 128.024298 -240.885177) (xy 128.004388 -240.866232) (xy 127.980146 -240.853284)
			(xy 127.953329 -240.84727) (xy 127.92588 -240.848627) (xy 127.899787 -240.857256) (xy 127.87694 -240.872532)
			(xy 127.867664 -240.882678) (xy 127.851882 -240.900393) (xy 127.816118 -240.931566) (xy 127.776267 -240.95731)
			(xy 127.733147 -240.977097) (xy 127.687643 -240.990522) (xy 127.640688 -240.997309) (xy 127.616966 -240.99774)
			(xy 127.591002 -240.997228) (xy 127.539713 -240.9891) (xy 127.490327 -240.973049) (xy 127.44406 -240.949471)
			(xy 127.40205 -240.918945) (xy 127.365333 -240.882224) (xy 127.334812 -240.840211) (xy 127.311238 -240.793942)
			(xy 127.295192 -240.744554) (xy 127.287069 -240.693264) (xy 127.287069 -240.641336) (xy 127.295192 -240.590046)
			(xy 127.311238 -240.540658) (xy 127.334812 -240.494389) (xy 127.365333 -240.452376) (xy 127.40205 -240.415655)
			(xy 127.44406 -240.385129) (xy 127.490327 -240.361551) (xy 127.539713 -240.3455) (xy 127.591002 -240.337372)
			(xy 127.616966 -240.336832) (xy 127.64069 -240.337239) (xy 127.68765 -240.344018) (xy 127.733158 -240.357441)
			(xy 127.77628 -240.377232) (xy 127.81613 -240.402986) (xy 127.851888 -240.434172) (xy 127.867664 -240.451894)
			(xy 127.876972 -240.462005) (xy 127.899805 -240.477277) (xy 127.925885 -240.485905) (xy 127.953321 -240.487262)
			(xy 127.980126 -240.481251) (xy 128.004355 -240.468308) (xy 128.024254 -240.44937) (xy 128.038379 -240.42581)
			(xy 128.045707 -240.399335) (xy 128.046226 -240.3856) (xy 128.046226 -240.18367) (xy 128.007618 -240.174018)
			(xy 127.982637 -240.167353) (xy 127.934972 -240.147325) (xy 127.891009 -240.120117) (xy 127.851821 -240.086393)
			(xy 127.818364 -240.046977) (xy 127.791454 -240.002831) (xy 127.77175 -239.955032) (xy 127.759731 -239.904747)
			(xy 127.755692 -239.853204) (xy 127.75973 -239.801661) (xy 127.771748 -239.751376) (xy 127.791451 -239.703576)
			(xy 127.818359 -239.659429) (xy 127.851815 -239.620012) (xy 127.891003 -239.586288) (xy 127.934965 -239.559079)
			(xy 127.982629 -239.53905) (xy 128.007618 -239.532414) (xy 128.046226 -239.522762) (xy 128.046226 -239.321086)
			(xy 128.045773 -239.307343) (xy 128.038437 -239.280855) (xy 128.024302 -239.257282) (xy 128.004391 -239.238334)
			(xy 127.980148 -239.225384) (xy 127.953328 -239.21937) (xy 127.925876 -239.220728) (xy 127.899781 -239.229359)
			(xy 127.876934 -239.244638) (xy 127.867664 -239.254792) (xy 127.851882 -239.272506) (xy 127.816117 -239.303678)
			(xy 127.776266 -239.329421) (xy 127.733146 -239.349207) (xy 127.687642 -239.362631) (xy 127.640687 -239.369418)
			(xy 127.616966 -239.369854) (xy 127.591001 -239.369342) (xy 127.53971 -239.361214) (xy 127.490322 -239.345162)
			(xy 127.444052 -239.321582) (xy 127.402041 -239.291056) (xy 127.365322 -239.254333) (xy 127.3348 -239.212319)
			(xy 127.311225 -239.166047) (xy 127.295178 -239.116657) (xy 127.287055 -239.065366) (xy 127.287055 -239.013434)
			(xy 127.295178 -238.962143) (xy 127.311225 -238.912753) (xy 127.3348 -238.866481) (xy 127.365322 -238.824467)
			(xy 127.402041 -238.787744) (xy 127.444052 -238.757218) (xy 127.490322 -238.733638) (xy 127.53971 -238.717586)
			(xy 127.591001 -238.709458) (xy 127.616966 -238.708946) (xy 127.640689 -238.709353) (xy 127.687649 -238.716132)
			(xy 127.733158 -238.729555) (xy 127.776279 -238.749347) (xy 127.816128 -238.775102) (xy 127.851885 -238.806289)
			(xy 127.867664 -238.824008) (xy 127.876972 -238.834118) (xy 127.899807 -238.849388) (xy 127.925887 -238.858014)
			(xy 127.953323 -238.859371) (xy 127.980127 -238.853361) (xy 128.004357 -238.840418) (xy 128.024256 -238.821481)
			(xy 128.038383 -238.797922) (xy 128.045714 -238.771449) (xy 128.046226 -238.757714) (xy 128.046226 -238.556038)
			(xy 128.007618 -238.546386) (xy 127.982639 -238.539721) (xy 127.93498 -238.519693) (xy 127.891021 -238.492487)
			(xy 127.851838 -238.458766) (xy 127.818384 -238.419353) (xy 127.791479 -238.37521) (xy 127.771777 -238.327415)
			(xy 127.759761 -238.277135) (xy 127.755723 -238.225596) (xy 127.759762 -238.174058) (xy 127.771779 -238.123778)
			(xy 127.791482 -238.075983) (xy 127.818389 -238.031841) (xy 127.851843 -237.992429) (xy 127.891028 -237.958708)
			(xy 127.934986 -237.931503) (xy 127.982646 -237.911477) (xy 128.007618 -237.904782) (xy 128.046226 -237.89513)
			(xy 128.046226 -237.6932) (xy 128.045774 -237.679456) (xy 128.038441 -237.652964) (xy 128.024307 -237.629388)
			(xy 128.004395 -237.610437) (xy 127.980149 -237.597485) (xy 127.953327 -237.59147) (xy 127.925872 -237.592829)
			(xy 127.899775 -237.601462) (xy 127.876927 -237.616745) (xy 127.867664 -237.626906) (xy 127.851884 -237.644624)
			(xy 127.816122 -237.675804) (xy 127.776272 -237.701553) (xy 127.733152 -237.721345) (xy 127.687646 -237.734773)
			(xy 127.640689 -237.741561) (xy 127.616966 -237.741968) (xy 127.590999 -237.741456) (xy 127.539706 -237.733327)
			(xy 127.490316 -237.717275) (xy 127.444045 -237.693694) (xy 127.402032 -237.663166) (xy 127.365312 -237.626442)
			(xy 127.334788 -237.584426) (xy 127.311212 -237.538152) (xy 127.295165 -237.488761) (xy 127.287041 -237.437467)
			(xy 127.287041 -237.385533) (xy 127.295165 -237.334239) (xy 127.311212 -237.284848) (xy 127.334788 -237.238574)
			(xy 127.365312 -237.196558) (xy 127.402032 -237.159834) (xy 127.444045 -237.129306) (xy 127.490316 -237.105725)
			(xy 127.539706 -237.089673) (xy 127.590999 -237.081544) (xy 127.616966 -237.08106) (xy 127.640689 -237.081467)
			(xy 127.687649 -237.088246) (xy 127.733157 -237.10167) (xy 127.776278 -237.121463) (xy 127.816126 -237.147218)
			(xy 127.851882 -237.178405) (xy 127.867664 -237.196122) (xy 127.876973 -237.206231) (xy 127.899809 -237.221499)
			(xy 127.925889 -237.230124) (xy 127.953325 -237.23148) (xy 127.980129 -237.22547) (xy 128.004359 -237.212528)
			(xy 128.024259 -237.193592) (xy 128.038388 -237.170035) (xy 128.045722 -237.143563) (xy 128.046226 -237.129828)
			(xy 128.046226 -236.928406) (xy 128.007618 -236.918754) (xy 127.982642 -236.912088) (xy 127.934987 -236.892062)
			(xy 127.891034 -236.864857) (xy 127.851855 -236.831138) (xy 127.818405 -236.791728) (xy 127.791503 -236.747589)
			(xy 127.771805 -236.699798) (xy 127.759791 -236.649522) (xy 127.755754 -236.597989) (xy 127.759794 -236.546455)
			(xy 127.771812 -236.49618) (xy 127.791514 -236.448391) (xy 127.818419 -236.404253) (xy 127.851871 -236.364846)
			(xy 127.891052 -236.331129) (xy 127.935008 -236.303928) (xy 127.982663 -236.283904) (xy 128.007618 -236.27715)
			(xy 128.046226 -236.267498) (xy 128.046226 -236.065568) (xy 128.04577 -236.051827) (xy 128.038432 -236.025343)
			(xy 128.024296 -236.001775) (xy 128.004387 -235.982831) (xy 127.980146 -235.969884) (xy 127.953329 -235.96387)
			(xy 127.925881 -235.965227) (xy 127.899788 -235.973856) (xy 127.876942 -235.989131) (xy 127.867664 -235.999274)
			(xy 127.851882 -236.016989) (xy 127.816118 -236.048162) (xy 127.776267 -236.073907) (xy 127.733147 -236.093694)
			(xy 127.687643 -236.107119) (xy 127.640688 -236.113906) (xy 127.616966 -236.114336) (xy 127.591002 -236.113824)
			(xy 127.539714 -236.105696) (xy 127.490328 -236.089645) (xy 127.444062 -236.066067) (xy 127.402053 -236.035542)
			(xy 127.365336 -235.998821) (xy 127.334815 -235.956809) (xy 127.311242 -235.91054) (xy 127.295196 -235.861153)
			(xy 127.287073 -235.809864) (xy 127.287073 -235.757936) (xy 127.295196 -235.706647) (xy 127.311242 -235.65726)
			(xy 127.334815 -235.610991) (xy 127.365336 -235.568979) (xy 127.402053 -235.532258) (xy 127.444062 -235.501733)
			(xy 127.490328 -235.478155) (xy 127.539714 -235.462104) (xy 127.591002 -235.453976) (xy 127.616966 -235.453428)
			(xy 127.64069 -235.453835) (xy 127.68765 -235.460613) (xy 127.733159 -235.474036) (xy 127.776281 -235.493828)
			(xy 127.81613 -235.519581) (xy 127.851889 -235.550767) (xy 127.867664 -235.56849) (xy 127.876971 -235.578601)
			(xy 127.899804 -235.593874) (xy 127.925884 -235.602502) (xy 127.953321 -235.60386) (xy 127.980125 -235.597849)
			(xy 128.004355 -235.584905) (xy 128.024253 -235.565966) (xy 128.038377 -235.542406) (xy 128.045705 -235.515931)
			(xy 128.046226 -235.502196) (xy 128.046226 -235.30052) (xy 128.007618 -235.290868) (xy 127.98264 -235.284203)
			(xy 127.934984 -235.264176) (xy 127.891028 -235.23697) (xy 127.851847 -235.20325) (xy 127.818396 -235.163839)
			(xy 127.791492 -235.119698) (xy 127.771792 -235.071905) (xy 127.759777 -235.021628) (xy 127.75574 -234.970092)
			(xy 127.75978 -234.918556) (xy 127.771797 -234.868279) (xy 127.7915 -234.820487) (xy 127.818406 -234.776348)
			(xy 127.851858 -234.736938) (xy 127.891041 -234.70322) (xy 127.934998 -234.676017) (xy 127.982656 -234.655992)
			(xy 128.007618 -234.649264) (xy 128.046226 -234.639612) (xy 128.046226 -234.437936) (xy 128.045779 -234.424188)
			(xy 128.038451 -234.397687) (xy 128.024318 -234.374102) (xy 128.004404 -234.355144) (xy 127.980153 -234.342186)
			(xy 127.953324 -234.33617) (xy 127.925863 -234.33753) (xy 127.89976 -234.346169) (xy 127.876909 -234.36146)
			(xy 127.867664 -234.371642) (xy 127.851883 -234.389359) (xy 127.81612 -234.420535) (xy 127.776269 -234.446282)
			(xy 127.733149 -234.466071) (xy 127.687644 -234.479498) (xy 127.640688 -234.486285) (xy 127.616966 -234.486704)
			(xy 127.590997 -234.486192) (xy 127.539698 -234.478062) (xy 127.490302 -234.462008) (xy 127.444026 -234.438425)
			(xy 127.402009 -234.407894) (xy 127.365284 -234.371165) (xy 127.334757 -234.329145) (xy 127.311179 -234.282866)
			(xy 127.29513 -234.233469) (xy 127.287005 -234.182169) (xy 127.287005 -234.130231) (xy 127.29513 -234.078931)
			(xy 127.311179 -234.029534) (xy 127.334757 -233.983255) (xy 127.365284 -233.941235) (xy 127.402009 -233.904506)
			(xy 127.444026 -233.873975) (xy 127.490302 -233.850392) (xy 127.539698 -233.834338) (xy 127.590997 -233.826208)
			(xy 127.616966 -233.825796) (xy 127.64069 -233.826203) (xy 127.687651 -233.832981) (xy 127.73316 -233.846403)
			(xy 127.776284 -233.866193) (xy 127.816135 -233.891944) (xy 127.851896 -233.923129) (xy 127.867664 -233.940858)
			(xy 127.876976 -233.950964) (xy 127.899813 -233.966228) (xy 127.925894 -233.974849) (xy 127.95333 -233.976203)
			(xy 127.980133 -233.970193) (xy 128.004363 -233.957254) (xy 128.024266 -233.938321) (xy 128.038399 -233.914768)
			(xy 128.04574 -233.888298) (xy 128.046226 -233.874564) (xy 128.046226 -233.672634) (xy 128.007618 -233.662982)
			(xy 127.982639 -233.656317) (xy 127.934981 -233.63629) (xy 127.891023 -233.609083) (xy 127.85184 -233.575362)
			(xy 127.818387 -233.53595) (xy 127.791482 -233.491807) (xy 127.771781 -233.444013) (xy 127.759764 -233.393733)
			(xy 127.755727 -233.342195) (xy 127.759766 -233.290658) (xy 127.771783 -233.240378) (xy 127.791486 -233.192584)
			(xy 127.818393 -233.148443) (xy 127.851846 -233.109031) (xy 127.891031 -233.075311) (xy 127.934989 -233.048106)
			(xy 127.982648 -233.02808) (xy 128.007618 -233.021378) (xy 128.046226 -233.011726) (xy 128.046226 -232.81005)
			(xy 128.04578 -232.796301) (xy 128.038455 -232.769796) (xy 128.024323 -232.746208) (xy 128.004408 -232.727246)
			(xy 127.980155 -232.714287) (xy 127.953323 -232.70827) (xy 127.925859 -232.709631) (xy 127.899754 -232.718272)
			(xy 127.876902 -232.733567) (xy 127.867664 -232.743756) (xy 127.851883 -232.761472) (xy 127.816119 -232.792647)
			(xy 127.776268 -232.818393) (xy 127.733148 -232.838181) (xy 127.687644 -232.851607) (xy 127.640688 -232.858394)
			(xy 127.616966 -232.858818) (xy 127.591003 -232.858306) (xy 127.539718 -232.850179) (xy 127.490335 -232.834129)
			(xy 127.444071 -232.810552) (xy 127.402065 -232.780028) (xy 127.36535 -232.74331) (xy 127.33483 -232.7013)
			(xy 127.311258 -232.655033) (xy 127.295213 -232.605649) (xy 127.287091 -232.554363) (xy 127.287091 -232.502437)
			(xy 127.295213 -232.451151) (xy 127.311258 -232.401767) (xy 127.33483 -232.3555) (xy 127.36535 -232.31349)
			(xy 127.402065 -232.276772) (xy 127.444071 -232.246248) (xy 127.490335 -232.222671) (xy 127.539718 -232.206621)
			(xy 127.591003 -232.198494) (xy 127.616966 -232.19791) (xy 127.64069 -232.198317) (xy 127.68765 -232.205095)
			(xy 127.73316 -232.218518) (xy 127.776282 -232.238308) (xy 127.816133 -232.26406) (xy 127.851892 -232.295245)
			(xy 127.867664 -232.312972) (xy 127.87697 -232.323084) (xy 127.899802 -232.338359) (xy 127.925882 -232.346989)
			(xy 127.953318 -232.348348) (xy 127.980123 -232.342337) (xy 128.004352 -232.329392) (xy 128.024249 -232.310452)
			(xy 128.038372 -232.28689) (xy 128.045695 -232.260413) (xy 128.046226 -232.246678) (xy 128.046226 -232.045002)
			(xy 128.007618 -232.03535) (xy 127.982634 -232.028685) (xy 127.934965 -232.008656) (xy 127.890997 -231.981446)
			(xy 127.851804 -231.94772) (xy 127.818343 -231.908301) (xy 127.79143 -231.864152) (xy 127.771723 -231.816349)
			(xy 127.759702 -231.766059) (xy 127.755661 -231.714511) (xy 127.759698 -231.662963) (xy 127.771716 -231.612673)
			(xy 127.79142 -231.564869) (xy 127.81833 -231.520717) (xy 127.851788 -231.481296) (xy 127.890979 -231.447567)
			(xy 127.934944 -231.420355) (xy 127.982612 -231.400323) (xy 128.007618 -231.393746) (xy 128.046226 -231.384094)
			(xy 128.046226 -231.182164) (xy 128.04577 -231.168424) (xy 128.038431 -231.14194) (xy 128.024295 -231.118373)
			(xy 128.004386 -231.09943) (xy 127.980145 -231.086483) (xy 127.95333 -231.08047) (xy 127.925882 -231.081827)
			(xy 127.89979 -231.090455) (xy 127.876944 -231.105729) (xy 127.867664 -231.11587) (xy 127.851883 -231.133585)
			(xy 127.816118 -231.164759) (xy 127.776267 -231.190504) (xy 127.733148 -231.210291) (xy 127.687643 -231.223717)
			(xy 127.640688 -231.230503) (xy 127.616966 -231.230932) (xy 127.591002 -231.23042) (xy 127.539715 -231.222292)
			(xy 127.49033 -231.206242) (xy 127.444064 -231.182664) (xy 127.402055 -231.152139) (xy 127.365339 -231.115419)
			(xy 127.334818 -231.073407) (xy 127.311245 -231.027139) (xy 127.2952 -230.977752) (xy 127.287077 -230.926464)
			(xy 127.287077 -230.874536) (xy 127.2952 -230.823248) (xy 127.311245 -230.773861) (xy 127.334818 -230.727593)
			(xy 127.365339 -230.685581) (xy 127.402055 -230.648861) (xy 127.444064 -230.618336) (xy 127.49033 -230.594758)
			(xy 127.539715 -230.578708) (xy 127.591002 -230.57058) (xy 127.616966 -230.570024) (xy 127.64069 -230.570431)
			(xy 127.68765 -230.577209) (xy 127.733159 -230.590632) (xy 127.776281 -230.610423) (xy 127.816131 -230.636176)
			(xy 127.851889 -230.667362) (xy 127.867664 -230.685086) (xy 127.876971 -230.695197) (xy 127.899804 -230.710471)
			(xy 127.925884 -230.719099) (xy 127.95332 -230.720457) (xy 127.980125 -230.714446) (xy 128.004354 -230.701502)
			(xy 128.024252 -230.682563) (xy 128.038376 -230.659002) (xy 128.045703 -230.632527) (xy 128.046226 -230.618792)
			(xy 128.046226 -230.417116) (xy 128.007618 -230.407464) (xy 127.982641 -230.400798) (xy 127.934985 -230.380772)
			(xy 127.89103 -230.353566) (xy 127.851849 -230.319847) (xy 127.818399 -230.280436) (xy 127.791496 -230.236295)
			(xy 127.771796 -230.188503) (xy 127.759782 -230.138226) (xy 127.755745 -230.086691) (xy 127.759784 -230.035156)
			(xy 127.771802 -229.98488) (xy 127.791504 -229.937089) (xy 127.81841 -229.89295) (xy 127.851862 -229.85354)
			(xy 127.891045 -229.819823) (xy 127.935001 -229.79262) (xy 127.982658 -229.772596) (xy 128.007618 -229.76586)
			(xy 128.046226 -229.756208) (xy 128.046226 -229.554532) (xy 128.045778 -229.540785) (xy 128.03845 -229.514285)
			(xy 128.024317 -229.490701) (xy 128.004403 -229.471743) (xy 127.980153 -229.458786) (xy 127.953325 -229.45277)
			(xy 127.925864 -229.45413) (xy 127.899762 -229.462769) (xy 127.876911 -229.478059) (xy 127.867664 -229.488238)
			(xy 127.851883 -229.505955) (xy 127.81612 -229.537131) (xy 127.77627 -229.562879) (xy 127.73315 -229.582668)
			(xy 127.687645 -229.596095) (xy 127.640688 -229.602882) (xy 127.616966 -229.6033) (xy 127.590997 -229.602788)
			(xy 127.539699 -229.594658) (xy 127.490304 -229.578605) (xy 127.444028 -229.555022) (xy 127.402011 -229.524491)
			(xy 127.365287 -229.487763) (xy 127.33476 -229.445743) (xy 127.311182 -229.399465) (xy 127.295134 -229.350068)
			(xy 127.287009 -229.298769) (xy 127.287009 -229.246831) (xy 127.295134 -229.195532) (xy 127.311182 -229.146135)
			(xy 127.33476 -229.099857) (xy 127.365287 -229.057837) (xy 127.402011 -229.021109) (xy 127.444028 -228.990578)
			(xy 127.490304 -228.966995) (xy 127.539699 -228.950942) (xy 127.590997 -228.942812) (xy 127.616966 -228.942392)
			(xy 127.64069 -228.942799) (xy 127.687651 -228.949577) (xy 127.733161 -228.962999) (xy 127.776284 -228.982789)
			(xy 127.816136 -229.00854) (xy 127.851896 -229.039724) (xy 127.867664 -229.057454) (xy 127.876975 -229.06756)
			(xy 127.899813 -229.082824) (xy 127.925894 -229.091446) (xy 127.953329 -229.092801) (xy 127.980132 -229.086791)
			(xy 128.004363 -229.073851) (xy 128.024265 -229.054918) (xy 128.038398 -229.031364) (xy 128.045738 -229.004894)
			(xy 128.046226 -228.99116) (xy 128.046226 -228.789484) (xy 128.007618 -228.779832) (xy 127.982635 -228.773167)
			(xy 127.934969 -228.753138) (xy 127.891004 -228.72593) (xy 127.851814 -228.692205) (xy 127.818355 -228.652788)
			(xy 127.791444 -228.60864) (xy 127.771738 -228.560839) (xy 127.759718 -228.510552) (xy 127.755678 -228.459007)
			(xy 127.759716 -228.407462) (xy 127.771734 -228.357175) (xy 127.791437 -228.309373) (xy 127.818346 -228.265224)
			(xy 127.851803 -228.225805) (xy 127.890992 -228.192079) (xy 127.934956 -228.164868) (xy 127.982622 -228.144838)
			(xy 128.007618 -228.138228) (xy 128.046226 -228.128576) (xy 128.046226 -227.926138) (xy 128.045776 -227.91237)
			(xy 128.038428 -227.885833) (xy 128.024256 -227.862225) (xy 128.004291 -227.843262) (xy 127.979985 -227.830324)
			(xy 127.953105 -227.824351) (xy 127.925607 -227.825779) (xy 127.89949 -227.834502) (xy 127.876653 -227.849887)
			(xy 127.86741 -227.860098) (xy 127.851651 -227.877851) (xy 127.815916 -227.909097) (xy 127.776075 -227.934904)
			(xy 127.732948 -227.95474) (xy 127.687426 -227.968196) (xy 127.640447 -227.974995) (xy 127.616712 -227.975414)
			(xy 127.590745 -227.974932) (xy 127.539451 -227.96681) (xy 127.490059 -227.950763) (xy 127.443785 -227.927187)
			(xy 127.401769 -227.896662) (xy 127.365046 -227.85994) (xy 127.33452 -227.817925) (xy 127.310942 -227.771652)
			(xy 127.294893 -227.722261) (xy 127.286769 -227.670967) (xy 127.286769 -227.619033) (xy 127.294893 -227.567739)
			(xy 127.310942 -227.518348) (xy 127.33452 -227.472075) (xy 127.365046 -227.43006) (xy 127.401769 -227.393338)
			(xy 127.443785 -227.362813) (xy 127.490059 -227.339237) (xy 127.539451 -227.32319) (xy 127.590745 -227.315068)
			(xy 127.616712 -227.314506) (xy 127.640446 -227.314919) (xy 127.687424 -227.32172) (xy 127.732944 -227.33518)
			(xy 127.776067 -227.355021) (xy 127.815902 -227.380835) (xy 127.85163 -227.412088) (xy 127.86741 -227.429822)
			(xy 127.876698 -227.439983) (xy 127.899521 -227.455355) (xy 127.925622 -227.464071) (xy 127.953102 -227.465496)
			(xy 127.979964 -227.459528) (xy 128.004255 -227.446599) (xy 128.024209 -227.42765) (xy 128.038374 -227.404059)
			(xy 128.045722 -227.377541) (xy 128.046226 -227.363782) (xy 128.046226 -227.161598) (xy 128.007618 -227.151946)
			(xy 127.982651 -227.145262) (xy 127.935019 -227.125206) (xy 127.89109 -227.097979) (xy 127.851934 -227.064246)
			(xy 127.818507 -227.024829) (xy 127.791623 -226.98069) (xy 127.771937 -226.932903) (xy 127.759929 -226.882635)
			(xy 127.755893 -226.831111) (xy 127.759926 -226.779586) (xy 127.77193 -226.729317) (xy 127.791613 -226.681529)
			(xy 127.818495 -226.637388) (xy 127.85192 -226.597969) (xy 127.891073 -226.564234) (xy 127.935 -226.537004)
			(xy 127.982631 -226.516944) (xy 128.007618 -226.510342) (xy 128.046226 -226.50069) (xy 128.046226 -226.299014)
			(xy 128.045776 -226.285268) (xy 128.038445 -226.258773) (xy 128.024311 -226.235193) (xy 128.004398 -226.21624)
			(xy 127.980151 -226.203286) (xy 127.953326 -226.19727) (xy 127.925869 -226.198629) (xy 127.899769 -226.207265)
			(xy 127.87692 -226.222551) (xy 127.867664 -226.23272) (xy 127.851884 -226.250438) (xy 127.816121 -226.281616)
			(xy 127.776271 -226.307364) (xy 127.733151 -226.327155) (xy 127.687645 -226.340583) (xy 127.640688 -226.347371)
			(xy 127.616966 -226.347782) (xy 127.590998 -226.34727) (xy 127.539703 -226.339141) (xy 127.490311 -226.323088)
			(xy 127.444038 -226.299506) (xy 127.402023 -226.268977) (xy 127.365301 -226.232251) (xy 127.334776 -226.190233)
			(xy 127.311199 -226.143958) (xy 127.295151 -226.094564) (xy 127.287027 -226.043268) (xy 127.287027 -225.991332)
			(xy 127.295151 -225.940036) (xy 127.311199 -225.890642) (xy 127.334776 -225.844367) (xy 127.365301 -225.802349)
			(xy 127.402023 -225.765623) (xy 127.444038 -225.735094) (xy 127.490311 -225.711512) (xy 127.539703 -225.695459)
			(xy 127.590998 -225.68733) (xy 127.616966 -225.686874) (xy 127.64069 -225.687281) (xy 127.687651 -225.694058)
			(xy 127.733162 -225.70748) (xy 127.776286 -225.727269) (xy 127.816138 -225.753019) (xy 127.8519 -225.784202)
			(xy 127.867664 -225.801936) (xy 127.876974 -225.812044) (xy 127.89981 -225.82731) (xy 127.925891 -225.835934)
			(xy 127.953327 -225.837289) (xy 127.98013 -225.831279) (xy 128.00436 -225.818338) (xy 128.024261 -225.799404)
			(xy 128.038392 -225.775848) (xy 128.045729 -225.749376) (xy 128.046226 -225.735642) (xy 128.046226 -225.533712)
			(xy 128.007618 -225.52406) (xy 127.982641 -225.517394) (xy 127.934986 -225.497368) (xy 127.891032 -225.470163)
			(xy 127.851851 -225.436443) (xy 127.818402 -225.397033) (xy 127.791499 -225.352893) (xy 127.7718 -225.305101)
			(xy 127.759785 -225.254824) (xy 127.755749 -225.20329) (xy 127.759788 -225.151756) (xy 127.771806 -225.10148)
			(xy 127.791508 -225.053689) (xy 127.818413 -225.009551) (xy 127.851866 -224.970143) (xy 127.891048 -224.936425)
			(xy 127.935004 -224.909223) (xy 127.98266 -224.889199) (xy 128.007618 -224.882456) (xy 128.046226 -224.872804)
			(xy 128.046226 -224.671128) (xy 128.045778 -224.657381) (xy 128.038449 -224.630882) (xy 128.024316 -224.607299)
			(xy 128.004402 -224.588342) (xy 127.980152 -224.575386) (xy 127.953325 -224.56937) (xy 127.925865 -224.57073)
			(xy 127.899763 -224.579368) (xy 127.876913 -224.594657) (xy 127.867664 -224.604834) (xy 127.851884 -224.622551)
			(xy 127.81612 -224.653728) (xy 127.77627 -224.679475) (xy 127.73315 -224.699266) (xy 127.687645 -224.712692)
			(xy 127.640688 -224.71948) (xy 127.616966 -224.719896) (xy 127.590999 -224.719384) (xy 127.539706 -224.711256)
			(xy 127.490315 -224.695205) (xy 127.444043 -224.671626) (xy 127.402028 -224.6411) (xy 127.365305 -224.604378)
			(xy 127.334778 -224.562364) (xy 127.311198 -224.516092) (xy 127.295146 -224.466702) (xy 127.287016 -224.415409)
			(xy 127.286512 -224.389442) (xy 127.286985 -224.363995) (xy 127.294793 -224.313704) (xy 127.310217 -224.265204)
			(xy 127.332892 -224.219641) (xy 127.362281 -224.178091) (xy 127.397691 -224.141535) (xy 127.438286 -224.110839)
			(xy 127.483105 -224.086727) (xy 127.531089 -224.069768) (xy 127.556006 -224.064576) (xy 127.578866 -224.060258)
			(xy 127.782574 -223.707198) (xy 127.774954 -223.685354) (xy 127.766157 -223.65878) (xy 127.756701 -223.603612)
			(xy 127.756158 -223.575626) (xy 127.756595 -223.55121) (xy 127.76378 -223.502909) (xy 127.777997 -223.456193)
			(xy 127.798937 -223.412078) (xy 127.826142 -223.371527) (xy 127.859021 -223.335422) (xy 127.896857 -223.304551)
			(xy 127.938825 -223.279586) (xy 127.984011 -223.261072) (xy 128.007618 -223.254824) (xy 128.046226 -223.245172)
			(xy 128.046226 -223.043242) (xy 128.045779 -223.029494) (xy 128.038453 -223.002991) (xy 128.02432 -222.979405)
			(xy 128.004406 -222.960445) (xy 127.980154 -222.947487) (xy 127.953324 -222.94147) (xy 127.925861 -222.942831)
			(xy 127.899757 -222.951471) (xy 127.876906 -222.966763) (xy 127.867664 -222.976948) (xy 127.851883 -222.994664)
			(xy 127.81612 -223.02584) (xy 127.776269 -223.051586) (xy 127.733149 -223.071376) (xy 127.687644 -223.084802)
			(xy 127.640688 -223.091589) (xy 127.616966 -223.09201) (xy 127.591004 -223.091498) (xy 127.53972 -223.083371)
			(xy 127.490338 -223.067321) (xy 127.444075 -223.043745) (xy 127.40207 -223.013222) (xy 127.365356 -222.976504)
			(xy 127.334837 -222.934496) (xy 127.311266 -222.88823) (xy 127.295221 -222.838847) (xy 127.287099 -222.787562)
			(xy 127.287099 -222.735638) (xy 127.295221 -222.684353) (xy 127.311266 -222.63497) (xy 127.334837 -222.588704)
			(xy 127.365356 -222.546696) (xy 127.40207 -222.509978) (xy 127.444075 -222.479455) (xy 127.490338 -222.455879)
			(xy 127.53972 -222.439829) (xy 127.591004 -222.431702) (xy 127.616966 -222.431102) (xy 127.64069 -222.431509)
			(xy 127.687651 -222.438287) (xy 127.73316 -222.451709) (xy 127.776283 -222.471499) (xy 127.816134 -222.497251)
			(xy 127.851894 -222.528436) (xy 127.867664 -222.546164) (xy 127.876976 -222.55627) (xy 127.899814 -222.571532)
			(xy 127.925895 -222.580153) (xy 127.95333 -222.581507) (xy 127.980134 -222.575497) (xy 128.004364 -222.562558)
			(xy 128.024267 -222.543626) (xy 128.038401 -222.520073) (xy 128.045744 -222.493604) (xy 128.046226 -222.47987)
			(xy 128.046226 -222.278194) (xy 128.007618 -222.268542) (xy 127.982635 -222.261877) (xy 127.934967 -222.241848)
			(xy 127.891 -222.214639) (xy 127.851808 -222.180914) (xy 127.818348 -222.141495) (xy 127.791436 -222.097346)
			(xy 127.77173 -222.049544) (xy 127.759709 -221.999256) (xy 127.755668 -221.94771) (xy 127.759706 -221.896163)
			(xy 127.771724 -221.845874) (xy 127.791428 -221.798071) (xy 127.818337 -221.75392) (xy 127.851795 -221.7145)
			(xy 127.890985 -221.680772) (xy 127.93495 -221.653561) (xy 127.982616 -221.633529) (xy 128.007618 -221.626938)
			(xy 128.046226 -221.617286) (xy 128.046226 -221.41561) (xy 128.045775 -221.401865) (xy 128.038444 -221.37537)
			(xy 128.02431 -221.351792) (xy 128.004397 -221.332839) (xy 127.98015 -221.319885) (xy 127.953326 -221.31387)
			(xy 127.92587 -221.315229) (xy 127.899771 -221.323864) (xy 127.876922 -221.339149) (xy 127.867664 -221.349316)
			(xy 127.848986 -221.370168) (xy 127.805881 -221.405879) (xy 127.757366 -221.433801) (xy 127.704834 -221.453133)
			(xy 127.677418 -221.45879) (xy 127.654304 -221.463108) (xy 127.45085 -221.815914) (xy 127.45847 -221.838012)
			(xy 127.467261 -221.864587) (xy 127.476705 -221.919755) (xy 127.477266 -221.94774) (xy 127.476757 -221.973707)
			(xy 127.468632 -222.025002) (xy 127.452584 -222.074395) (xy 127.429006 -222.120669) (xy 127.39848 -222.162685)
			(xy 127.361757 -222.199408) (xy 127.319741 -222.229934) (xy 127.273467 -222.253512) (xy 127.224074 -222.26956)
			(xy 127.172779 -222.277685) (xy 127.120845 -222.277685) (xy 127.06955 -222.26956) (xy 127.020157 -222.253512)
			(xy 126.973883 -222.229934) (xy 126.931867 -222.199408) (xy 126.895144 -222.162685) (xy 126.864618 -222.120669)
			(xy 126.84104 -222.074395) (xy 126.824992 -222.025002) (xy 126.816867 -221.973707) (xy 126.816358 -221.94774)
			(xy 126.816831 -221.922292) (xy 126.824639 -221.871999) (xy 126.840062 -221.823496) (xy 126.862735 -221.77793)
			(xy 126.892123 -221.736376) (xy 126.927532 -221.699816) (xy 126.968125 -221.669114) (xy 127.012943 -221.644995)
			(xy 127.060927 -221.628028) (xy 127.085852 -221.622874) (xy 127.108712 -221.618556) (xy 127.312674 -221.264988)
			(xy 127.305054 -221.243144) (xy 127.296395 -221.216673) (xy 127.287079 -221.161769) (xy 127.286512 -221.133924)
			(xy 127.287019 -221.107955) (xy 127.295141 -221.056655) (xy 127.311187 -221.007257) (xy 127.334763 -220.960977)
			(xy 127.365288 -220.918955) (xy 127.402011 -220.882226) (xy 127.444027 -220.851693) (xy 127.490303 -220.828109)
			(xy 127.539698 -220.812054) (xy 127.590997 -220.803924) (xy 127.616966 -220.80347) (xy 127.64069 -220.803877)
			(xy 127.687651 -220.810654) (xy 127.733162 -220.824076) (xy 127.776286 -220.843865) (xy 127.816139 -220.869615)
			(xy 127.851901 -220.900797) (xy 127.867664 -220.918532) (xy 127.876974 -220.92864) (xy 127.89981 -220.943907)
			(xy 127.92589 -220.952531) (xy 127.953326 -220.953887) (xy 127.98013 -220.947876) (xy 128.00436 -220.934935)
			(xy 128.024261 -220.916) (xy 128.038391 -220.892444) (xy 128.045727 -220.865972) (xy 128.046226 -220.852238)
			(xy 128.046226 -220.650308) (xy 128.007618 -220.640656) (xy 127.982641 -220.63399) (xy 127.934987 -220.613964)
			(xy 127.891033 -220.586759) (xy 127.851853 -220.55304) (xy 127.818404 -220.513629) (xy 127.791502 -220.46949)
			(xy 127.771803 -220.421699) (xy 127.759789 -220.371423) (xy 127.755752 -220.319889) (xy 127.759792 -220.268355)
			(xy 127.77181 -220.21808) (xy 127.791512 -220.17029) (xy 127.818417 -220.126153) (xy 127.851869 -220.086745)
			(xy 127.891051 -220.053028) (xy 127.935006 -220.025826) (xy 127.982662 -220.005803) (xy 128.007618 -219.999052)
			(xy 128.046226 -219.9894) (xy 128.046226 -219.787724) (xy 128.045777 -219.773977) (xy 128.038448 -219.747479)
			(xy 128.024314 -219.723897) (xy 128.004401 -219.704942) (xy 127.980152 -219.691986) (xy 127.953325 -219.68597)
			(xy 127.925866 -219.68733) (xy 127.899765 -219.695967) (xy 127.876915 -219.711255) (xy 127.867664 -219.72143)
			(xy 127.851884 -219.739147) (xy 127.816121 -219.770324) (xy 127.77627 -219.796072) (xy 127.73315 -219.815863)
			(xy 127.687645 -219.829289) (xy 127.640688 -219.836077) (xy 127.616966 -219.836492) (xy 127.58993 -219.835951)
			(xy 127.536581 -219.827149) (xy 127.485373 -219.809785) (xy 127.437673 -219.784321) (xy 127.394751 -219.751437)
			(xy 127.35775 -219.712008) (xy 127.327657 -219.667085) (xy 127.305273 -219.617865) (xy 127.291195 -219.565658)
			(xy 127.288036 -219.538804) (xy 127.285998 -219.523477) (xy 127.273931 -219.495027) (xy 127.253892 -219.471501)
			(xy 127.227725 -219.455059) (xy 127.197834 -219.447214) (xy 127.182372 -219.447364) (xy 127.146812 -219.44838)
			(xy 127.11176 -219.447364) (xy 127.0963 -219.447196) (xy 127.066418 -219.455072) (xy 127.040257 -219.471522)
			(xy 127.02021 -219.49504) (xy 127.008112 -219.523477) (xy 127.006096 -219.538804) (xy 127.002882 -219.565653)
			(xy 126.988837 -219.617867) (xy 126.966476 -219.667096) (xy 126.936396 -219.712027) (xy 126.8994 -219.751459)
			(xy 126.856476 -219.784339) (xy 126.80877 -219.809789) (xy 126.757556 -219.827129) (xy 126.704201 -219.835898)
			(xy 126.677166 -219.836492) (xy 126.651199 -219.83598) (xy 126.599906 -219.827852) (xy 126.550516 -219.811801)
			(xy 126.504244 -219.788222) (xy 126.46223 -219.757696) (xy 126.425507 -219.720974) (xy 126.39498 -219.67896)
			(xy 126.371401 -219.632688) (xy 126.355349 -219.583298) (xy 126.34722 -219.532005) (xy 126.346712 -219.506038)
			(xy 126.347209 -219.479947) (xy 126.355419 -219.428415) (xy 126.371625 -219.378813) (xy 126.395425 -219.332374)
			(xy 126.426227 -219.290252) (xy 126.463265 -219.253494) (xy 126.484126 -219.237814) (xy 126.49637 -219.228355)
			(xy 126.514955 -219.203636) (xy 126.525307 -219.174494) (xy 126.526482 -219.143591) (xy 126.518372 -219.113747)
			(xy 126.510542 -219.1004) (xy 126.491501 -219.069919) (xy 126.458618 -219.006007) (xy 126.431949 -218.939263)
			(xy 126.411732 -218.87029) (xy 126.398152 -218.79971) (xy 126.39133 -218.728159) (xy 126.390908 -218.692222)
			(xy 126.391151 -218.664433) (xy 126.395218 -218.609005) (xy 126.399036 -218.581478) (xy 126.371701 -218.57035)
			(xy 126.31868 -218.544414) (xy 126.293118 -218.529662) (xy 126.284373 -218.525011) (xy 126.264799 -218.522105)
			(xy 126.245583 -218.526831) (xy 126.229589 -218.538484) (xy 126.22403 -218.54668) (xy 126.205838 -218.575496)
			(xy 126.165007 -218.630062) (xy 126.142496 -218.655646) (xy 126.129812 -218.692915) (xy 126.097746 -218.764819)
			(xy 126.078488 -218.799156) (xy 125.922024 -219.070174) (xy 125.903736 -219.100146) (xy 125.895856 -219.113453)
			(xy 125.887718 -219.143276) (xy 125.888855 -219.174167) (xy 125.899163 -219.203311) (xy 125.917701 -219.228048)
			(xy 125.929898 -219.23756) (xy 125.950857 -219.253184) (xy 125.988025 -219.28994) (xy 126.018935 -219.332095)
			(xy 126.042814 -219.378595) (xy 126.059066 -219.428278) (xy 126.067283 -219.479901) (xy 126.06782 -219.506038)
			(xy 126.067308 -219.532002) (xy 126.059179 -219.583291) (xy 126.043126 -219.632676) (xy 126.019546 -219.678942)
			(xy 125.989018 -219.72095) (xy 125.952295 -219.757665) (xy 125.910281 -219.788184) (xy 125.864009 -219.811754)
			(xy 125.814621 -219.827795) (xy 125.76333 -219.835914) (xy 125.737366 -219.836492) (xy 125.71033 -219.835951)
			(xy 125.656981 -219.827149) (xy 125.605773 -219.809785) (xy 125.558073 -219.784321) (xy 125.515151 -219.751437)
			(xy 125.47815 -219.712008) (xy 125.448057 -219.667085) (xy 125.425673 -219.617865) (xy 125.411595 -219.565658)
			(xy 125.408436 -219.538804) (xy 125.406398 -219.523477) (xy 125.394331 -219.495027) (xy 125.374292 -219.471501)
			(xy 125.348125 -219.455059) (xy 125.318234 -219.447214) (xy 125.302772 -219.447364) (xy 125.267212 -219.44838)
			(xy 125.23216 -219.447364) (xy 125.2167 -219.447196) (xy 125.186818 -219.455072) (xy 125.160657 -219.471522)
			(xy 125.14061 -219.49504) (xy 125.128512 -219.523477) (xy 125.126496 -219.538804) (xy 125.123282 -219.565653)
			(xy 125.109237 -219.617867) (xy 125.086876 -219.667096) (xy 125.056796 -219.712027) (xy 125.0198 -219.751459)
			(xy 124.976876 -219.784339) (xy 124.92917 -219.809789) (xy 124.877956 -219.827129) (xy 124.824601 -219.835898)
			(xy 124.797566 -219.836492) (xy 124.771599 -219.83598) (xy 124.720306 -219.827852) (xy 124.670916 -219.811801)
			(xy 124.624644 -219.788222) (xy 124.58263 -219.757696) (xy 124.545907 -219.720974) (xy 124.51538 -219.67896)
			(xy 124.491801 -219.632688) (xy 124.475749 -219.583298) (xy 124.46762 -219.532005) (xy 124.467112 -219.506038)
			(xy 124.467609 -219.479947) (xy 124.475819 -219.428415) (xy 124.492025 -219.378813) (xy 124.515825 -219.332374)
			(xy 124.546627 -219.290252) (xy 124.583665 -219.253494) (xy 124.604526 -219.237814) (xy 124.61677 -219.228355)
			(xy 124.635355 -219.203636) (xy 124.645707 -219.174494) (xy 124.646882 -219.143591) (xy 124.638772 -219.113747)
			(xy 124.630942 -219.1004) (xy 124.611901 -219.069919) (xy 124.579018 -219.006007) (xy 124.552349 -218.939263)
			(xy 124.532132 -218.87029) (xy 124.518552 -218.79971) (xy 124.51173 -218.728159) (xy 124.511308 -218.692222)
			(xy 124.511551 -218.664433) (xy 124.515618 -218.609005) (xy 124.519436 -218.581478) (xy 124.492101 -218.57035)
			(xy 124.43908 -218.544414) (xy 124.413518 -218.529662) (xy 124.404773 -218.525011) (xy 124.385199 -218.522105)
			(xy 124.365983 -218.526831) (xy 124.349989 -218.538484) (xy 124.34443 -218.54668) (xy 124.326238 -218.575496)
			(xy 124.285407 -218.630062) (xy 124.262896 -218.655646) (xy 124.250212 -218.692915) (xy 124.218146 -218.764819)
			(xy 124.198888 -218.799156) (xy 124.042424 -219.070174) (xy 124.024136 -219.100146) (xy 124.016256 -219.113453)
			(xy 124.008118 -219.143276) (xy 124.009255 -219.174167) (xy 124.019563 -219.203311) (xy 124.038101 -219.228048)
			(xy 124.050298 -219.23756) (xy 124.071257 -219.253184) (xy 124.108425 -219.28994) (xy 124.139335 -219.332095)
			(xy 124.163214 -219.378595) (xy 124.179466 -219.428278) (xy 124.187683 -219.479901) (xy 124.18822 -219.506038)
			(xy 124.187708 -219.532002) (xy 124.179579 -219.583291) (xy 124.163526 -219.632676) (xy 124.139946 -219.678942)
			(xy 124.109418 -219.72095) (xy 124.072695 -219.757665) (xy 124.030681 -219.788184) (xy 123.984409 -219.811754)
			(xy 123.935021 -219.827795) (xy 123.88373 -219.835914) (xy 123.857766 -219.836492) (xy 123.83073 -219.835951)
			(xy 123.777381 -219.827149) (xy 123.726173 -219.809785) (xy 123.678473 -219.784321) (xy 123.635551 -219.751437)
			(xy 123.59855 -219.712008) (xy 123.568457 -219.667085) (xy 123.546073 -219.617865) (xy 123.531995 -219.565658)
			(xy 123.528836 -219.538804) (xy 123.526798 -219.523477) (xy 123.514731 -219.495027) (xy 123.494692 -219.471501)
			(xy 123.468525 -219.455059) (xy 123.438634 -219.447214) (xy 123.423172 -219.447364) (xy 123.387612 -219.44838)
			(xy 123.35256 -219.447364) (xy 123.3371 -219.447196) (xy 123.307218 -219.455072) (xy 123.281057 -219.471522)
			(xy 123.26101 -219.49504) (xy 123.248912 -219.523477) (xy 123.246896 -219.538804) (xy 123.243682 -219.565653)
			(xy 123.229637 -219.617867) (xy 123.207276 -219.667096) (xy 123.177196 -219.712027) (xy 123.1402 -219.751459)
			(xy 123.097276 -219.784339) (xy 123.04957 -219.809789) (xy 122.998356 -219.827129) (xy 122.945001 -219.835898)
			(xy 122.917966 -219.836492) (xy 122.891999 -219.83598) (xy 122.840706 -219.827852) (xy 122.791316 -219.811801)
			(xy 122.745044 -219.788222) (xy 122.70303 -219.757696) (xy 122.666307 -219.720974) (xy 122.63578 -219.67896)
			(xy 122.612201 -219.632688) (xy 122.596149 -219.583298) (xy 122.58802 -219.532005) (xy 122.587512 -219.506038)
			(xy 122.588009 -219.479947) (xy 122.596219 -219.428415) (xy 122.612425 -219.378813) (xy 122.636225 -219.332374)
			(xy 122.667027 -219.290252) (xy 122.704065 -219.253494) (xy 122.724926 -219.237814) (xy 122.73717 -219.228355)
			(xy 122.755755 -219.203636) (xy 122.766107 -219.174494) (xy 122.767282 -219.143591) (xy 122.759172 -219.113747)
			(xy 122.751342 -219.1004) (xy 122.732301 -219.069919) (xy 122.699418 -219.006007) (xy 122.672749 -218.939263)
			(xy 122.652532 -218.87029) (xy 122.638952 -218.79971) (xy 122.63213 -218.728159) (xy 122.631708 -218.692222)
			(xy 122.631951 -218.664433) (xy 122.636018 -218.609005) (xy 122.639836 -218.581478) (xy 122.612501 -218.57035)
			(xy 122.55948 -218.544414) (xy 122.533918 -218.529662) (xy 122.525173 -218.525011) (xy 122.505599 -218.522105)
			(xy 122.486383 -218.526831) (xy 122.470389 -218.538484) (xy 122.46483 -218.54668) (xy 122.446638 -218.575496)
			(xy 122.405807 -218.630062) (xy 122.383296 -218.655646) (xy 122.370612 -218.692915) (xy 122.338546 -218.764819)
			(xy 122.319288 -218.799156) (xy 122.162824 -219.070174) (xy 122.144536 -219.100146) (xy 122.136656 -219.113453)
			(xy 122.128518 -219.143276) (xy 122.129655 -219.174167) (xy 122.139963 -219.203311) (xy 122.158501 -219.228048)
			(xy 122.170698 -219.23756) (xy 122.191657 -219.253184) (xy 122.228825 -219.28994) (xy 122.259735 -219.332095)
			(xy 122.283614 -219.378595) (xy 122.299866 -219.428278) (xy 122.308083 -219.479901) (xy 122.30862 -219.506038)
			(xy 122.308108 -219.532002) (xy 122.299979 -219.583291) (xy 122.283926 -219.632676) (xy 122.260346 -219.678942)
			(xy 122.229818 -219.72095) (xy 122.193095 -219.757665) (xy 122.151081 -219.788184) (xy 122.104809 -219.811754)
			(xy 122.055421 -219.827795) (xy 122.00413 -219.835914) (xy 121.978166 -219.836492) (xy 121.95113 -219.835951)
			(xy 121.897781 -219.827149) (xy 121.846573 -219.809785) (xy 121.798873 -219.784321) (xy 121.755951 -219.751437)
			(xy 121.71895 -219.712008) (xy 121.688857 -219.667085) (xy 121.666473 -219.617865) (xy 121.652395 -219.565658)
			(xy 121.649236 -219.538804) (xy 121.647198 -219.523477) (xy 121.635131 -219.495027) (xy 121.615092 -219.471501)
			(xy 121.588925 -219.455059) (xy 121.559034 -219.447214) (xy 121.543572 -219.447364) (xy 121.508012 -219.44838)
			(xy 121.47296 -219.447364) (xy 121.4575 -219.447196) (xy 121.427618 -219.455072) (xy 121.401457 -219.471522)
			(xy 121.38141 -219.49504) (xy 121.369312 -219.523477) (xy 121.367296 -219.538804) (xy 121.364082 -219.565653)
			(xy 121.350037 -219.617867) (xy 121.327676 -219.667096) (xy 121.297596 -219.712027) (xy 121.2606 -219.751459)
			(xy 121.217676 -219.784339) (xy 121.16997 -219.809789) (xy 121.118756 -219.827129) (xy 121.065401 -219.835898)
			(xy 121.038366 -219.836492) (xy 121.012399 -219.83598) (xy 120.961106 -219.827852) (xy 120.911716 -219.811801)
			(xy 120.865444 -219.788222) (xy 120.82343 -219.757696) (xy 120.786707 -219.720974) (xy 120.75618 -219.67896)
			(xy 120.732601 -219.632688) (xy 120.716549 -219.583298) (xy 120.70842 -219.532005) (xy 120.707912 -219.506038)
			(xy 120.708409 -219.479947) (xy 120.716619 -219.428415) (xy 120.732825 -219.378813) (xy 120.756625 -219.332374)
			(xy 120.787427 -219.290252) (xy 120.824465 -219.253494) (xy 120.845326 -219.237814) (xy 120.85757 -219.228355)
			(xy 120.876155 -219.203636) (xy 120.886507 -219.174494) (xy 120.887682 -219.143591) (xy 120.879572 -219.113747)
			(xy 120.871742 -219.1004) (xy 120.852701 -219.069919) (xy 120.819818 -219.006007) (xy 120.793149 -218.939263)
			(xy 120.772932 -218.87029) (xy 120.759352 -218.79971) (xy 120.75253 -218.728159) (xy 120.752108 -218.692222)
			(xy 120.752351 -218.664433) (xy 120.756418 -218.609005) (xy 120.760236 -218.581478) (xy 120.732901 -218.57035)
			(xy 120.67988 -218.544414) (xy 120.654318 -218.529662) (xy 120.645573 -218.525011) (xy 120.625999 -218.522105)
			(xy 120.606783 -218.526831) (xy 120.590789 -218.538484) (xy 120.58523 -218.54668) (xy 120.567038 -218.575496)
			(xy 120.526207 -218.630062) (xy 120.503696 -218.655646) (xy 120.491012 -218.692915) (xy 120.458946 -218.764819)
			(xy 120.439688 -218.799156) (xy 120.283224 -219.070174) (xy 120.264936 -219.100146) (xy 120.257056 -219.113453)
			(xy 120.248918 -219.143276) (xy 120.250055 -219.174167) (xy 120.260363 -219.203311) (xy 120.278901 -219.228048)
			(xy 120.291098 -219.23756) (xy 120.312057 -219.253184) (xy 120.349225 -219.28994) (xy 120.380135 -219.332095)
			(xy 120.404014 -219.378595) (xy 120.420266 -219.428278) (xy 120.428483 -219.479901) (xy 120.42902 -219.506038)
			(xy 120.428508 -219.532002) (xy 120.420379 -219.583291) (xy 120.404326 -219.632676) (xy 120.380746 -219.678942)
			(xy 120.350218 -219.72095) (xy 120.313495 -219.757665) (xy 120.271481 -219.788184) (xy 120.225209 -219.811754)
			(xy 120.175821 -219.827795) (xy 120.12453 -219.835914) (xy 120.098566 -219.836492) (xy 120.07153 -219.835951)
			(xy 120.018181 -219.827149) (xy 119.966973 -219.809785) (xy 119.919273 -219.784321) (xy 119.876351 -219.751437)
			(xy 119.83935 -219.712008) (xy 119.809257 -219.667085) (xy 119.786873 -219.617865) (xy 119.772795 -219.565658)
			(xy 119.769636 -219.538804) (xy 119.767598 -219.523477) (xy 119.755531 -219.495027) (xy 119.735492 -219.471501)
			(xy 119.709325 -219.455059) (xy 119.679434 -219.447214) (xy 119.663972 -219.447364) (xy 119.628412 -219.44838)
			(xy 119.59336 -219.447364) (xy 119.5779 -219.447196) (xy 119.548018 -219.455072) (xy 119.521857 -219.471522)
			(xy 119.50181 -219.49504) (xy 119.489712 -219.523477) (xy 119.487696 -219.538804) (xy 119.484482 -219.565653)
			(xy 119.470437 -219.617867) (xy 119.448076 -219.667096) (xy 119.417996 -219.712027) (xy 119.381 -219.751459)
			(xy 119.338076 -219.784339) (xy 119.29037 -219.809789) (xy 119.239156 -219.827129) (xy 119.185801 -219.835898)
			(xy 119.158766 -219.836492) (xy 119.132799 -219.83598) (xy 119.081506 -219.827852) (xy 119.032116 -219.811801)
			(xy 118.985844 -219.788222) (xy 118.94383 -219.757696) (xy 118.907107 -219.720974) (xy 118.87658 -219.67896)
			(xy 118.853001 -219.632688) (xy 118.836949 -219.583298) (xy 118.82882 -219.532005) (xy 118.828312 -219.506038)
			(xy 118.828809 -219.479947) (xy 118.837019 -219.428415) (xy 118.853225 -219.378813) (xy 118.877025 -219.332374)
			(xy 118.907827 -219.290252) (xy 118.944865 -219.253494) (xy 118.965726 -219.237814) (xy 118.97797 -219.228355)
			(xy 118.996555 -219.203636) (xy 119.006907 -219.174494) (xy 119.008082 -219.143591) (xy 118.999972 -219.113747)
			(xy 118.992142 -219.1004) (xy 118.973101 -219.069919) (xy 118.940218 -219.006007) (xy 118.913549 -218.939263)
			(xy 118.893332 -218.87029) (xy 118.879752 -218.79971) (xy 118.87293 -218.728159) (xy 118.872508 -218.692222)
			(xy 118.872751 -218.664433) (xy 118.876818 -218.609005) (xy 118.880636 -218.581478) (xy 118.853301 -218.57035)
			(xy 118.80028 -218.544414) (xy 118.774718 -218.529662) (xy 118.765973 -218.525011) (xy 118.746399 -218.522105)
			(xy 118.727183 -218.526831) (xy 118.711189 -218.538484) (xy 118.70563 -218.54668) (xy 118.687438 -218.575496)
			(xy 118.646607 -218.630062) (xy 118.624096 -218.655646) (xy 118.611412 -218.692915) (xy 118.579346 -218.764819)
			(xy 118.560088 -218.799156) (xy 118.403624 -219.070174) (xy 118.385336 -219.100146) (xy 118.377456 -219.113453)
			(xy 118.369318 -219.143276) (xy 118.370455 -219.174167) (xy 118.380763 -219.203311) (xy 118.399301 -219.228048)
			(xy 118.411498 -219.23756) (xy 118.432457 -219.253184) (xy 118.469625 -219.28994) (xy 118.500535 -219.332095)
			(xy 118.524414 -219.378595) (xy 118.540666 -219.428278) (xy 118.548883 -219.479901) (xy 118.54942 -219.506038)
			(xy 118.548908 -219.532002) (xy 118.540779 -219.583291) (xy 118.524726 -219.632676) (xy 118.501146 -219.678942)
			(xy 118.470618 -219.72095) (xy 118.433895 -219.757665) (xy 118.391881 -219.788184) (xy 118.345609 -219.811754)
			(xy 118.296221 -219.827795) (xy 118.24493 -219.835914) (xy 118.218966 -219.836492) (xy 118.19193 -219.835951)
			(xy 118.138581 -219.827149) (xy 118.087373 -219.809785) (xy 118.039673 -219.784321) (xy 117.996751 -219.751437)
			(xy 117.95975 -219.712008) (xy 117.929657 -219.667085) (xy 117.907273 -219.617865) (xy 117.893195 -219.565658)
			(xy 117.890036 -219.538804) (xy 117.887998 -219.523477) (xy 117.875931 -219.495027) (xy 117.855892 -219.471501)
			(xy 117.829725 -219.455059) (xy 117.799834 -219.447214) (xy 117.784372 -219.447364) (xy 117.748812 -219.44838)
			(xy 117.71376 -219.447364) (xy 117.6983 -219.447196) (xy 117.668418 -219.455072) (xy 117.642257 -219.471522)
			(xy 117.62221 -219.49504) (xy 117.610112 -219.523477) (xy 117.608096 -219.538804) (xy 117.604882 -219.565653)
			(xy 117.590837 -219.617867) (xy 117.568476 -219.667096) (xy 117.538396 -219.712027) (xy 117.5014 -219.751459)
			(xy 117.458476 -219.784339) (xy 117.41077 -219.809789) (xy 117.359556 -219.827129) (xy 117.306201 -219.835898)
			(xy 117.279166 -219.836492) (xy 117.253199 -219.83598) (xy 117.201906 -219.827852) (xy 117.152516 -219.811801)
			(xy 117.106244 -219.788222) (xy 117.06423 -219.757696) (xy 117.027507 -219.720974) (xy 116.99698 -219.67896)
			(xy 116.973401 -219.632688) (xy 116.957349 -219.583298) (xy 116.94922 -219.532005) (xy 116.948712 -219.506038)
			(xy 116.949209 -219.479947) (xy 116.957419 -219.428415) (xy 116.973625 -219.378813) (xy 116.997425 -219.332374)
			(xy 117.028227 -219.290252) (xy 117.065265 -219.253494) (xy 117.086126 -219.237814) (xy 117.09837 -219.228355)
			(xy 117.116955 -219.203636) (xy 117.127307 -219.174494) (xy 117.128482 -219.143591) (xy 117.120372 -219.113747)
			(xy 117.112542 -219.1004) (xy 117.093501 -219.069919) (xy 117.060618 -219.006007) (xy 117.033949 -218.939263)
			(xy 117.013732 -218.87029) (xy 117.000152 -218.79971) (xy 116.99333 -218.728159) (xy 116.992908 -218.692222)
			(xy 116.993151 -218.664433) (xy 116.997218 -218.609005) (xy 117.001036 -218.581478) (xy 116.973701 -218.57035)
			(xy 116.92068 -218.544414) (xy 116.895118 -218.529662) (xy 116.886373 -218.525011) (xy 116.866799 -218.522105)
			(xy 116.847583 -218.526831) (xy 116.831589 -218.538484) (xy 116.82603 -218.54668) (xy 116.807838 -218.575496)
			(xy 116.767007 -218.630062) (xy 116.744496 -218.655646) (xy 116.731812 -218.692915) (xy 116.699746 -218.764819)
			(xy 116.680488 -218.799156) (xy 116.524024 -219.070174) (xy 116.505736 -219.100146) (xy 116.497856 -219.113453)
			(xy 116.489718 -219.143276) (xy 116.490855 -219.174167) (xy 116.501163 -219.203311) (xy 116.519701 -219.228048)
			(xy 116.531898 -219.23756) (xy 116.552857 -219.253184) (xy 116.590025 -219.28994) (xy 116.620935 -219.332095)
			(xy 116.644814 -219.378595) (xy 116.661066 -219.428278) (xy 116.669283 -219.479901) (xy 116.66982 -219.506038)
			(xy 116.669308 -219.532002) (xy 116.661179 -219.583291) (xy 116.645126 -219.632676) (xy 116.621546 -219.678942)
			(xy 116.591018 -219.72095) (xy 116.554295 -219.757665) (xy 116.512281 -219.788184) (xy 116.466009 -219.811754)
			(xy 116.416621 -219.827795) (xy 116.36533 -219.835914) (xy 116.339366 -219.836492) (xy 116.31233 -219.835951)
			(xy 116.258981 -219.827149) (xy 116.207773 -219.809785) (xy 116.160073 -219.784321) (xy 116.117151 -219.751437)
			(xy 116.08015 -219.712008) (xy 116.050057 -219.667085) (xy 116.027673 -219.617865) (xy 116.013595 -219.565658)
			(xy 116.010436 -219.538804) (xy 116.008398 -219.523477) (xy 115.996331 -219.495027) (xy 115.976292 -219.471501)
			(xy 115.950125 -219.455059) (xy 115.920234 -219.447214) (xy 115.904772 -219.447364) (xy 115.869212 -219.44838)
			(xy 115.83416 -219.447364) (xy 115.8187 -219.447196) (xy 115.788818 -219.455072) (xy 115.762657 -219.471522)
			(xy 115.74261 -219.49504) (xy 115.730512 -219.523477) (xy 115.728496 -219.538804) (xy 115.725282 -219.565653)
			(xy 115.711237 -219.617867) (xy 115.688876 -219.667096) (xy 115.658796 -219.712027) (xy 115.6218 -219.751459)
			(xy 115.578876 -219.784339) (xy 115.53117 -219.809789) (xy 115.479956 -219.827129) (xy 115.426601 -219.835898)
			(xy 115.399566 -219.836492) (xy 115.373599 -219.83598) (xy 115.322306 -219.827852) (xy 115.272916 -219.811801)
			(xy 115.226644 -219.788222) (xy 115.18463 -219.757696) (xy 115.147907 -219.720974) (xy 115.11738 -219.67896)
			(xy 115.093801 -219.632688) (xy 115.077749 -219.583298) (xy 115.06962 -219.532005) (xy 115.069112 -219.506038)
			(xy 115.069609 -219.479947) (xy 115.077819 -219.428415) (xy 115.094025 -219.378813) (xy 115.117825 -219.332374)
			(xy 115.148627 -219.290252) (xy 115.185665 -219.253494) (xy 115.206526 -219.237814) (xy 115.21877 -219.228355)
			(xy 115.237355 -219.203636) (xy 115.247707 -219.174494) (xy 115.248882 -219.143591) (xy 115.240772 -219.113747)
			(xy 115.232942 -219.1004) (xy 115.223496 -219.085527) (xy 115.205837 -219.055034) (xy 115.197636 -219.03944)
			(xy 115.190063 -219.025949) (xy 115.168311 -219.003969) (xy 115.14098 -218.989503) (xy 115.110573 -218.983876)
			(xy 115.079875 -218.987605) (xy 115.065556 -218.993466) (xy 115.044102 -219.00269) (xy 114.99925 -219.015692)
			(xy 114.953015 -219.022256) (xy 114.929666 -219.022676) (xy 114.906411 -219.022274) (xy 114.860359 -219.015754)
			(xy 114.815672 -219.00286) (xy 114.794284 -218.99372) (xy 114.780426 -218.988055) (xy 114.750751 -218.984204)
			(xy 114.721235 -218.989128) (xy 114.694418 -219.002405) (xy 114.672607 -219.022893) (xy 114.664744 -219.03563)
			(xy 114.644678 -219.070174) (xy 114.62639 -219.1004) (xy 114.618503 -219.113682) (xy 114.610351 -219.143463)
			(xy 114.611481 -219.174318) (xy 114.621789 -219.203422) (xy 114.640332 -219.228111) (xy 114.652552 -219.23756)
			(xy 114.67347 -219.253213) (xy 114.71056 -219.290007) (xy 114.741406 -219.332173) (xy 114.765239 -219.378664)
			(xy 114.781469 -219.428323) (xy 114.789691 -219.479916) (xy 114.79022 -219.506038) (xy 114.789708 -219.532002)
			(xy 114.781579 -219.583291) (xy 114.765526 -219.632676) (xy 114.741946 -219.678942) (xy 114.711418 -219.72095)
			(xy 114.674695 -219.757665) (xy 114.632681 -219.788184) (xy 114.586409 -219.811754) (xy 114.537021 -219.827795)
			(xy 114.48573 -219.835914) (xy 114.459766 -219.836492) (xy 114.43273 -219.835951) (xy 114.379381 -219.827149)
			(xy 114.328173 -219.809785) (xy 114.280473 -219.784321) (xy 114.237551 -219.751437) (xy 114.20055 -219.712008)
			(xy 114.170457 -219.667085) (xy 114.148073 -219.617865) (xy 114.133995 -219.565658) (xy 114.130836 -219.538804)
			(xy 114.128742 -219.523505) (xy 114.11661 -219.495125) (xy 114.096573 -219.471648) (xy 114.070451 -219.45521)
			(xy 114.040616 -219.447302) (xy 114.025172 -219.447364) (xy 113.989866 -219.44838) (xy 113.95456 -219.447364)
			(xy 113.9391 -219.447196) (xy 113.909218 -219.455072) (xy 113.883057 -219.471522) (xy 113.86301 -219.49504)
			(xy 113.850912 -219.523477) (xy 113.848896 -219.538804) (xy 113.845682 -219.565653) (xy 113.831637 -219.617867)
			(xy 113.809276 -219.667096) (xy 113.779196 -219.712027) (xy 113.7422 -219.751459) (xy 113.699276 -219.784339)
			(xy 113.65157 -219.809789) (xy 113.600356 -219.827129) (xy 113.547001 -219.835898) (xy 113.519966 -219.836492)
			(xy 113.493999 -219.83598) (xy 113.442706 -219.827852) (xy 113.393316 -219.811801) (xy 113.347044 -219.788222)
			(xy 113.30503 -219.757696) (xy 113.268307 -219.720974) (xy 113.23778 -219.67896) (xy 113.214201 -219.632688)
			(xy 113.198149 -219.583298) (xy 113.19002 -219.532005) (xy 113.189512 -219.506038) (xy 113.190004 -219.479913)
			(xy 113.198217 -219.428312) (xy 113.214445 -219.378645) (xy 113.238284 -219.33215) (xy 113.26914 -219.289983)
			(xy 113.306245 -219.253196) (xy 113.32718 -219.23756) (xy 113.339362 -219.228085) (xy 113.357834 -219.203378)
			(xy 113.368111 -219.174292) (xy 113.369262 -219.143465) (xy 113.361183 -219.113693) (xy 113.353342 -219.1004)
			(xy 113.343955 -219.085462) (xy 113.326421 -219.054843) (xy 113.31829 -219.039186) (xy 113.310695 -219.025676)
			(xy 113.288891 -219.003669) (xy 113.261504 -218.98919) (xy 113.23104 -218.983567) (xy 113.200288 -218.987312)
			(xy 113.185956 -218.993212) (xy 113.164472 -219.002498) (xy 113.119542 -219.015601) (xy 113.073213 -219.022234)
			(xy 113.049812 -219.022676) (xy 113.026556 -219.022278) (xy 112.980502 -219.015763) (xy 112.935812 -219.002875)
			(xy 112.91443 -218.99372) (xy 112.900574 -218.988064) (xy 112.870908 -218.984227) (xy 112.841405 -218.989161)
			(xy 112.814603 -219.002443) (xy 112.792806 -219.022929) (xy 112.78489 -219.03563) (xy 112.764824 -219.070174)
			(xy 112.746536 -219.100146) (xy 112.738656 -219.113453) (xy 112.730518 -219.143276) (xy 112.731655 -219.174167)
			(xy 112.741963 -219.203311) (xy 112.760501 -219.228048) (xy 112.772698 -219.23756) (xy 112.793657 -219.253184)
			(xy 112.830825 -219.28994) (xy 112.861735 -219.332095) (xy 112.885614 -219.378595) (xy 112.901866 -219.428278)
			(xy 112.910083 -219.479901) (xy 112.91062 -219.506038) (xy 112.910108 -219.532002) (xy 112.901979 -219.583291)
			(xy 112.885926 -219.632676) (xy 112.862346 -219.678942) (xy 112.831818 -219.72095) (xy 112.795095 -219.757665)
			(xy 112.753081 -219.788184) (xy 112.706809 -219.811754) (xy 112.657421 -219.827795) (xy 112.60613 -219.835914)
			(xy 112.580166 -219.836492) (xy 112.55313 -219.835951) (xy 112.499781 -219.827149) (xy 112.448573 -219.809785)
			(xy 112.400873 -219.784321) (xy 112.357951 -219.751437) (xy 112.32095 -219.712008) (xy 112.290857 -219.667085)
			(xy 112.268473 -219.617865) (xy 112.254395 -219.565658) (xy 112.251236 -219.538804) (xy 112.249198 -219.523477)
			(xy 112.237131 -219.495027) (xy 112.217092 -219.471501) (xy 112.190925 -219.455059) (xy 112.161034 -219.447214)
			(xy 112.145572 -219.447364) (xy 112.110012 -219.44838) (xy 112.07496 -219.447364) (xy 112.0595 -219.447196)
			(xy 112.029618 -219.455072) (xy 112.003457 -219.471522) (xy 111.98341 -219.49504) (xy 111.971312 -219.523477)
			(xy 111.969296 -219.538804) (xy 111.966082 -219.565653) (xy 111.952037 -219.617867) (xy 111.929676 -219.667096)
			(xy 111.899596 -219.712027) (xy 111.8626 -219.751459) (xy 111.819676 -219.784339) (xy 111.77197 -219.809789)
			(xy 111.720756 -219.827129) (xy 111.667401 -219.835898) (xy 111.640366 -219.836492) (xy 111.614399 -219.83598)
			(xy 111.563106 -219.827852) (xy 111.513716 -219.811801) (xy 111.467444 -219.788222) (xy 111.42543 -219.757696)
			(xy 111.388707 -219.720974) (xy 111.35818 -219.67896) (xy 111.334601 -219.632688) (xy 111.318549 -219.583298)
			(xy 111.31042 -219.532005) (xy 111.309912 -219.506038) (xy 111.310409 -219.479947) (xy 111.318619 -219.428415)
			(xy 111.334825 -219.378813) (xy 111.358625 -219.332374) (xy 111.389427 -219.290252) (xy 111.426465 -219.253494)
			(xy 111.447326 -219.237814) (xy 111.45957 -219.228355) (xy 111.478155 -219.203636) (xy 111.488507 -219.174494)
			(xy 111.489682 -219.143591) (xy 111.481572 -219.113747) (xy 111.473742 -219.1004) (xy 111.464292 -219.085464)
			(xy 111.446632 -219.054845) (xy 111.438436 -219.039186) (xy 111.430866 -219.02569) (xy 111.409117 -219.0037)
			(xy 111.381783 -218.989227) (xy 111.351371 -218.983598) (xy 111.320668 -218.987329) (xy 111.306356 -218.993212)
			(xy 111.284946 -219.002434) (xy 111.240179 -219.01544) (xy 111.194028 -219.022017) (xy 111.17072 -219.022422)
			(xy 111.155454 -219.022264) (xy 111.125052 -219.019465) (xy 111.110014 -219.016834) (xy 111.083598 -219.012008)
			(xy 110.950248 -219.145358) (xy 110.939684 -219.156677) (xy 110.925328 -219.184093) (xy 110.919826 -219.214547)
			(xy 110.923681 -219.245253) (xy 110.936542 -219.273402) (xy 110.946438 -219.285312) (xy 110.96229 -219.303584)
			(xy 110.989026 -219.343896) (xy 111.00959 -219.387679) (xy 111.023543 -219.433995) (xy 111.030585 -219.481852)
			(xy 111.03102 -219.506038) (xy 111.030508 -219.532002) (xy 111.022379 -219.583291) (xy 111.006326 -219.632676)
			(xy 110.982746 -219.678942) (xy 110.952218 -219.72095) (xy 110.915495 -219.757665) (xy 110.873481 -219.788184)
			(xy 110.827209 -219.811754) (xy 110.777821 -219.827795) (xy 110.72653 -219.835914) (xy 110.700566 -219.836492)
			(xy 110.67353 -219.835951) (xy 110.620181 -219.827149) (xy 110.568973 -219.809785) (xy 110.521273 -219.784321)
			(xy 110.478351 -219.751437) (xy 110.44135 -219.712008) (xy 110.411257 -219.667085) (xy 110.388873 -219.617865)
			(xy 110.374795 -219.565658) (xy 110.371636 -219.538804) (xy 110.369542 -219.523505) (xy 110.35741 -219.495125)
			(xy 110.337373 -219.471648) (xy 110.311251 -219.45521) (xy 110.281416 -219.447302) (xy 110.265972 -219.447364)
			(xy 110.230666 -219.44838) (xy 110.19536 -219.447364) (xy 110.1799 -219.447196) (xy 110.150018 -219.455072)
			(xy 110.123857 -219.471522) (xy 110.10381 -219.49504) (xy 110.091712 -219.523477) (xy 110.089696 -219.538804)
			(xy 110.086482 -219.565653) (xy 110.072437 -219.617867) (xy 110.050076 -219.667096) (xy 110.019996 -219.712027)
			(xy 109.983 -219.751459) (xy 109.940076 -219.784339) (xy 109.89237 -219.809789) (xy 109.841156 -219.827129)
			(xy 109.787801 -219.835898) (xy 109.760766 -219.836492) (xy 109.734799 -219.83598) (xy 109.683506 -219.827852)
			(xy 109.634116 -219.811801) (xy 109.587844 -219.788222) (xy 109.54583 -219.757696) (xy 109.509107 -219.720974)
			(xy 109.47858 -219.67896) (xy 109.455001 -219.632688) (xy 109.438949 -219.583298) (xy 109.43082 -219.532005)
			(xy 109.430312 -219.506038) (xy 109.431061 -219.474309) (xy 109.443214 -219.412025) (xy 109.454442 -219.38234)
			(xy 109.459344 -219.368981) (xy 109.462337 -219.340693) (xy 109.457409 -219.312678) (xy 109.444944 -219.28711)
			(xy 109.425908 -219.265973) (xy 109.401779 -219.250909) (xy 109.374431 -219.243086) (xy 109.360208 -219.24264)
			(xy 109.221524 -219.24264) (xy 109.207313 -219.243121) (xy 109.179995 -219.250971) (xy 109.155897 -219.266042)
			(xy 109.136882 -219.287167) (xy 109.124422 -219.312714) (xy 109.119481 -219.340704) (xy 109.122441 -219.368972)
			(xy 109.12729 -219.38234) (xy 109.13852 -219.412024) (xy 109.150668 -219.474309) (xy 109.15142 -219.506038)
			(xy 109.150908 -219.532002) (xy 109.142779 -219.583291) (xy 109.126726 -219.632676) (xy 109.103146 -219.678942)
			(xy 109.072618 -219.72095) (xy 109.035895 -219.757665) (xy 108.993881 -219.788184) (xy 108.947609 -219.811754)
			(xy 108.898221 -219.827795) (xy 108.84693 -219.835914) (xy 108.820966 -219.836492) (xy 108.79393 -219.835951)
			(xy 108.740581 -219.827149) (xy 108.689373 -219.809785) (xy 108.641673 -219.784321) (xy 108.598751 -219.751437)
			(xy 108.56175 -219.712008) (xy 108.531657 -219.667085) (xy 108.509273 -219.617865) (xy 108.495195 -219.565658)
			(xy 108.492036 -219.538804) (xy 108.489998 -219.523477) (xy 108.477931 -219.495027) (xy 108.457892 -219.471501)
			(xy 108.431725 -219.455059) (xy 108.401834 -219.447214) (xy 108.386372 -219.447364) (xy 108.350812 -219.44838)
			(xy 108.31576 -219.447364) (xy 108.3003 -219.447196) (xy 108.270418 -219.455072) (xy 108.244257 -219.471522)
			(xy 108.22421 -219.49504) (xy 108.212112 -219.523477) (xy 108.210096 -219.538804) (xy 108.206882 -219.565653)
			(xy 108.192837 -219.617867) (xy 108.170476 -219.667096) (xy 108.140396 -219.712027) (xy 108.1034 -219.751459)
			(xy 108.060476 -219.784339) (xy 108.01277 -219.809789) (xy 107.961556 -219.827129) (xy 107.908201 -219.835898)
			(xy 107.881166 -219.836492) (xy 107.855199 -219.83598) (xy 107.803906 -219.827852) (xy 107.754516 -219.811801)
			(xy 107.708244 -219.788222) (xy 107.66623 -219.757696) (xy 107.629507 -219.720974) (xy 107.59898 -219.67896)
			(xy 107.575401 -219.632688) (xy 107.559349 -219.583298) (xy 107.55122 -219.532005) (xy 107.550712 -219.506038)
			(xy 107.551461 -219.474309) (xy 107.563614 -219.412025) (xy 107.574842 -219.38234) (xy 107.579744 -219.368981)
			(xy 107.582737 -219.340693) (xy 107.577809 -219.312678) (xy 107.565344 -219.28711) (xy 107.546308 -219.265973)
			(xy 107.522179 -219.250909) (xy 107.494831 -219.243086) (xy 107.480608 -219.24264) (xy 107.341924 -219.24264)
			(xy 107.327713 -219.243121) (xy 107.300395 -219.250971) (xy 107.276297 -219.266042) (xy 107.257282 -219.287167)
			(xy 107.244822 -219.312714) (xy 107.239881 -219.340704) (xy 107.242841 -219.368972) (xy 107.24769 -219.38234)
			(xy 107.25892 -219.412024) (xy 107.271068 -219.474309) (xy 107.27182 -219.506038) (xy 107.271308 -219.532002)
			(xy 107.263179 -219.583291) (xy 107.247126 -219.632676) (xy 107.223546 -219.678942) (xy 107.193018 -219.72095)
			(xy 107.156295 -219.757665) (xy 107.114281 -219.788184) (xy 107.068009 -219.811754) (xy 107.018621 -219.827795)
			(xy 106.96733 -219.835914) (xy 106.941366 -219.836492) (xy 106.91433 -219.835951) (xy 106.860981 -219.827149)
			(xy 106.809773 -219.809785) (xy 106.762073 -219.784321) (xy 106.719151 -219.751437) (xy 106.68215 -219.712008)
			(xy 106.652057 -219.667085) (xy 106.629673 -219.617865) (xy 106.615595 -219.565658) (xy 106.612436 -219.538804)
			(xy 106.610398 -219.523477) (xy 106.598331 -219.495027) (xy 106.578292 -219.471501) (xy 106.552125 -219.455059)
			(xy 106.522234 -219.447214) (xy 106.506772 -219.447364) (xy 106.471212 -219.44838) (xy 106.43616 -219.447364)
			(xy 106.4207 -219.447196) (xy 106.390818 -219.455072) (xy 106.364657 -219.471522) (xy 106.34461 -219.49504)
			(xy 106.332512 -219.523477) (xy 106.330496 -219.538804) (xy 106.327282 -219.565653) (xy 106.313237 -219.617867)
			(xy 106.290876 -219.667096) (xy 106.260796 -219.712027) (xy 106.2238 -219.751459) (xy 106.180876 -219.784339)
			(xy 106.13317 -219.809789) (xy 106.081956 -219.827129) (xy 106.028601 -219.835898) (xy 106.001566 -219.836492)
			(xy 105.975599 -219.83598) (xy 105.924306 -219.827852) (xy 105.874916 -219.811801) (xy 105.828644 -219.788222)
			(xy 105.78663 -219.757696) (xy 105.749907 -219.720974) (xy 105.71938 -219.67896) (xy 105.695801 -219.632688)
			(xy 105.679749 -219.583298) (xy 105.67162 -219.532005) (xy 105.671112 -219.506038) (xy 105.671861 -219.474309)
			(xy 105.684014 -219.412025) (xy 105.695242 -219.38234) (xy 105.700144 -219.368981) (xy 105.703137 -219.340693)
			(xy 105.698209 -219.312678) (xy 105.685744 -219.28711) (xy 105.666708 -219.265973) (xy 105.642579 -219.250909)
			(xy 105.615231 -219.243086) (xy 105.601008 -219.24264) (xy 105.462324 -219.24264) (xy 105.448113 -219.243121)
			(xy 105.420795 -219.250971) (xy 105.396697 -219.266042) (xy 105.377682 -219.287167) (xy 105.365222 -219.312714)
			(xy 105.360281 -219.340704) (xy 105.363241 -219.368972) (xy 105.36809 -219.38234) (xy 105.37932 -219.412024)
			(xy 105.391468 -219.474309) (xy 105.39222 -219.506038) (xy 105.391708 -219.532002) (xy 105.383579 -219.583291)
			(xy 105.367526 -219.632676) (xy 105.343946 -219.678942) (xy 105.313418 -219.72095) (xy 105.276695 -219.757665)
			(xy 105.234681 -219.788184) (xy 105.188409 -219.811754) (xy 105.139021 -219.827795) (xy 105.08773 -219.835914)
			(xy 105.061766 -219.836492) (xy 105.03473 -219.835951) (xy 104.981381 -219.827149) (xy 104.930173 -219.809785)
			(xy 104.882473 -219.784321) (xy 104.839551 -219.751437) (xy 104.80255 -219.712008) (xy 104.772457 -219.667085)
			(xy 104.750073 -219.617865) (xy 104.735995 -219.565658) (xy 104.732836 -219.538804) (xy 104.730798 -219.523477)
			(xy 104.718731 -219.495027) (xy 104.698692 -219.471501) (xy 104.672525 -219.455059) (xy 104.642634 -219.447214)
			(xy 104.627172 -219.447364) (xy 104.591612 -219.44838) (xy 104.55656 -219.447364) (xy 104.5411 -219.447196)
			(xy 104.511218 -219.455072) (xy 104.485057 -219.471522) (xy 104.46501 -219.49504) (xy 104.452912 -219.523477)
			(xy 104.450896 -219.538804) (xy 104.447682 -219.565653) (xy 104.433637 -219.617867) (xy 104.411276 -219.667096)
			(xy 104.381196 -219.712027) (xy 104.3442 -219.751459) (xy 104.301276 -219.784339) (xy 104.25357 -219.809789)
			(xy 104.202356 -219.827129) (xy 104.149001 -219.835898) (xy 104.121966 -219.836492) (xy 104.095999 -219.83598)
			(xy 104.044706 -219.827852) (xy 103.995316 -219.811801) (xy 103.949044 -219.788222) (xy 103.90703 -219.757696)
			(xy 103.870307 -219.720974) (xy 103.83978 -219.67896) (xy 103.816201 -219.632688) (xy 103.800149 -219.583298)
			(xy 103.79202 -219.532005) (xy 103.791512 -219.506038) (xy 103.792261 -219.474309) (xy 103.804414 -219.412025)
			(xy 103.815642 -219.38234) (xy 103.820544 -219.368981) (xy 103.823537 -219.340693) (xy 103.818609 -219.312678)
			(xy 103.806144 -219.28711) (xy 103.787108 -219.265973) (xy 103.762979 -219.250909) (xy 103.735631 -219.243086)
			(xy 103.721408 -219.24264) (xy 103.582724 -219.24264) (xy 103.568513 -219.243121) (xy 103.541195 -219.250971)
			(xy 103.517097 -219.266042) (xy 103.498082 -219.287167) (xy 103.485622 -219.312714) (xy 103.480681 -219.340704)
			(xy 103.483641 -219.368972) (xy 103.48849 -219.38234) (xy 103.49972 -219.412024) (xy 103.511868 -219.474309)
			(xy 103.51262 -219.506038) (xy 103.512108 -219.532002) (xy 103.503979 -219.583291) (xy 103.487926 -219.632676)
			(xy 103.464346 -219.678942) (xy 103.433818 -219.72095) (xy 103.397095 -219.757665) (xy 103.355081 -219.788184)
			(xy 103.308809 -219.811754) (xy 103.259421 -219.827795) (xy 103.20813 -219.835914) (xy 103.182166 -219.836492)
			(xy 103.15513 -219.835951) (xy 103.101781 -219.827149) (xy 103.050573 -219.809785) (xy 103.002873 -219.784321)
			(xy 102.959951 -219.751437) (xy 102.92295 -219.712008) (xy 102.892857 -219.667085) (xy 102.870473 -219.617865)
			(xy 102.856395 -219.565658) (xy 102.853236 -219.538804) (xy 102.851198 -219.523477) (xy 102.839131 -219.495027)
			(xy 102.819092 -219.471501) (xy 102.792925 -219.455059) (xy 102.763034 -219.447214) (xy 102.747572 -219.447364)
			(xy 102.712012 -219.44838) (xy 102.664514 -219.446856) (xy 102.641654 -219.445332) (xy 102.573328 -219.513658)
			(xy 102.571804 -219.532454) (xy 102.569226 -219.558244) (xy 102.557063 -219.608624) (xy 102.537185 -219.656488)
			(xy 102.510078 -219.700662) (xy 102.476408 -219.740062) (xy 102.436999 -219.773724) (xy 102.392819 -219.80082)
			(xy 102.344951 -219.820687) (xy 102.294568 -219.832838) (xy 102.268782 -219.835476) (xy 102.249986 -219.837)
			(xy 102.163626 -219.92336) (xy 102.163626 -220.345821) (xy 102.382321 -220.345821) (xy 102.382321 -220.293887)
			(xy 102.390446 -220.242592) (xy 102.406494 -220.193199) (xy 102.430072 -220.146925) (xy 102.460598 -220.104909)
			(xy 102.497321 -220.068186) (xy 102.539337 -220.03766) (xy 102.585611 -220.014082) (xy 102.635004 -219.998034)
			(xy 102.686299 -219.989909) (xy 102.738233 -219.989909) (xy 102.789528 -219.998034) (xy 102.838921 -220.014082)
			(xy 102.885195 -220.03766) (xy 102.927211 -220.068186) (xy 102.963934 -220.104909) (xy 102.99446 -220.146925)
			(xy 103.018038 -220.193199) (xy 103.034086 -220.242592) (xy 103.042211 -220.293887) (xy 103.04272 -220.319854)
			(xy 103.042211 -220.345821) (xy 103.034086 -220.397116) (xy 103.018038 -220.446509) (xy 102.99446 -220.492783)
			(xy 102.963934 -220.534799) (xy 102.927211 -220.571522) (xy 102.885195 -220.602048) (xy 102.838921 -220.625626)
			(xy 102.789528 -220.641674) (xy 102.738233 -220.649799) (xy 102.686299 -220.649799) (xy 102.635004 -220.641674)
			(xy 102.585611 -220.625626) (xy 102.539337 -220.602048) (xy 102.497321 -220.571522) (xy 102.460598 -220.534799)
			(xy 102.430072 -220.492783) (xy 102.406494 -220.446509) (xy 102.390446 -220.397116) (xy 102.382321 -220.345821)
			(xy 102.163626 -220.345821) (xy 102.163626 -220.702378) (xy 102.164126 -220.717861) (xy 102.173322 -220.747427)
			(xy 102.190965 -220.772872) (xy 102.215428 -220.791851) (xy 102.24446 -220.802617) (xy 102.259892 -220.803978)
			(xy 102.284917 -220.805778) (xy 102.334038 -220.815991) (xy 102.381051 -220.833511) (xy 102.424876 -220.857935)
			(xy 102.464505 -220.888703) (xy 102.499029 -220.925108) (xy 102.527653 -220.966312) (xy 102.549721 -221.01137)
			(xy 102.564724 -221.059245) (xy 102.572319 -221.108838) (xy 102.57282 -221.133924) (xy 102.851712 -221.133924)
			(xy 102.852158 -221.108472) (xy 102.859946 -221.058168) (xy 102.875357 -221.009654) (xy 102.898027 -220.964077)
			(xy 102.927418 -220.922517) (xy 102.962836 -220.885956) (xy 103.003443 -220.855259) (xy 103.048276 -220.831154)
			(xy 103.096277 -220.81421) (xy 103.121206 -220.809058) (xy 103.144066 -220.80474) (xy 103.347774 -220.45168)
			(xy 103.340154 -220.429582) (xy 103.331414 -220.402995) (xy 103.321968 -220.347835) (xy 103.321358 -220.319854)
			(xy 103.321867 -220.293887) (xy 103.329992 -220.242592) (xy 103.34604 -220.193199) (xy 103.369618 -220.146925)
			(xy 103.400144 -220.104909) (xy 103.436867 -220.068186) (xy 103.478883 -220.03766) (xy 103.525157 -220.014082)
			(xy 103.57455 -219.998034) (xy 103.625845 -219.989909) (xy 103.677779 -219.989909) (xy 103.729074 -219.998034)
			(xy 103.778467 -220.014082) (xy 103.824741 -220.03766) (xy 103.866757 -220.068186) (xy 103.90348 -220.104909)
			(xy 103.934006 -220.146925) (xy 103.957584 -220.193199) (xy 103.973632 -220.242592) (xy 103.981757 -220.293887)
			(xy 103.982266 -220.319854) (xy 103.981818 -220.345306) (xy 103.981738 -220.345821) (xy 104.261921 -220.345821)
			(xy 104.261921 -220.293887) (xy 104.270046 -220.242592) (xy 104.286094 -220.193199) (xy 104.309672 -220.146925)
			(xy 104.340198 -220.104909) (xy 104.376921 -220.068186) (xy 104.418937 -220.03766) (xy 104.465211 -220.014082)
			(xy 104.514604 -219.998034) (xy 104.565899 -219.989909) (xy 104.617833 -219.989909) (xy 104.669128 -219.998034)
			(xy 104.718521 -220.014082) (xy 104.764795 -220.03766) (xy 104.806811 -220.068186) (xy 104.843534 -220.104909)
			(xy 104.87406 -220.146925) (xy 104.897638 -220.193199) (xy 104.913686 -220.242592) (xy 104.921811 -220.293887)
			(xy 104.92232 -220.319854) (xy 105.200958 -220.319854) (xy 105.201467 -220.293887) (xy 105.209592 -220.242592)
			(xy 105.22564 -220.193199) (xy 105.249218 -220.146925) (xy 105.279744 -220.104909) (xy 105.316467 -220.068186)
			(xy 105.358483 -220.03766) (xy 105.404757 -220.014082) (xy 105.45415 -219.998034) (xy 105.505445 -219.989909)
			(xy 105.557379 -219.989909) (xy 105.608674 -219.998034) (xy 105.658067 -220.014082) (xy 105.704341 -220.03766)
			(xy 105.746357 -220.068186) (xy 105.78308 -220.104909) (xy 105.813606 -220.146925) (xy 105.837184 -220.193199)
			(xy 105.853232 -220.242592) (xy 105.861357 -220.293887) (xy 105.861866 -220.319854) (xy 105.861369 -220.345821)
			(xy 106.141521 -220.345821) (xy 106.141521 -220.293887) (xy 106.149646 -220.242592) (xy 106.165694 -220.193199)
			(xy 106.189272 -220.146925) (xy 106.219798 -220.104909) (xy 106.256521 -220.068186) (xy 106.298537 -220.03766)
			(xy 106.344811 -220.014082) (xy 106.394204 -219.998034) (xy 106.445499 -219.989909) (xy 106.497433 -219.989909)
			(xy 106.548728 -219.998034) (xy 106.598121 -220.014082) (xy 106.644395 -220.03766) (xy 106.686411 -220.068186)
			(xy 106.723134 -220.104909) (xy 106.75366 -220.146925) (xy 106.777238 -220.193199) (xy 106.793286 -220.242592)
			(xy 106.801411 -220.293887) (xy 106.80192 -220.319854) (xy 107.080558 -220.319854) (xy 107.081067 -220.293887)
			(xy 107.089192 -220.242592) (xy 107.10524 -220.193199) (xy 107.128818 -220.146925) (xy 107.159344 -220.104909)
			(xy 107.196067 -220.068186) (xy 107.238083 -220.03766) (xy 107.284357 -220.014082) (xy 107.33375 -219.998034)
			(xy 107.385045 -219.989909) (xy 107.436979 -219.989909) (xy 107.488274 -219.998034) (xy 107.537667 -220.014082)
			(xy 107.583941 -220.03766) (xy 107.625957 -220.068186) (xy 107.66268 -220.104909) (xy 107.693206 -220.146925)
			(xy 107.716784 -220.193199) (xy 107.732832 -220.242592) (xy 107.740957 -220.293887) (xy 107.741466 -220.319854)
			(xy 107.740969 -220.345821) (xy 108.021121 -220.345821) (xy 108.021121 -220.293887) (xy 108.029246 -220.242592)
			(xy 108.045294 -220.193199) (xy 108.068872 -220.146925) (xy 108.099398 -220.104909) (xy 108.136121 -220.068186)
			(xy 108.178137 -220.03766) (xy 108.224411 -220.014082) (xy 108.273804 -219.998034) (xy 108.325099 -219.989909)
			(xy 108.377033 -219.989909) (xy 108.428328 -219.998034) (xy 108.477721 -220.014082) (xy 108.523995 -220.03766)
			(xy 108.566011 -220.068186) (xy 108.602734 -220.104909) (xy 108.63326 -220.146925) (xy 108.656838 -220.193199)
			(xy 108.672886 -220.242592) (xy 108.681011 -220.293887) (xy 108.68152 -220.319854) (xy 108.960158 -220.319854)
			(xy 108.960667 -220.293887) (xy 108.968792 -220.242592) (xy 108.98484 -220.193199) (xy 109.008418 -220.146925)
			(xy 109.038944 -220.104909) (xy 109.075667 -220.068186) (xy 109.117683 -220.03766) (xy 109.163957 -220.014082)
			(xy 109.21335 -219.998034) (xy 109.264645 -219.989909) (xy 109.316579 -219.989909) (xy 109.367874 -219.998034)
			(xy 109.417267 -220.014082) (xy 109.463541 -220.03766) (xy 109.505557 -220.068186) (xy 109.54228 -220.104909)
			(xy 109.572806 -220.146925) (xy 109.596384 -220.193199) (xy 109.612432 -220.242592) (xy 109.620557 -220.293887)
			(xy 109.621066 -220.319854) (xy 109.620569 -220.345821) (xy 109.900721 -220.345821) (xy 109.900721 -220.293887)
			(xy 109.908846 -220.242592) (xy 109.924894 -220.193199) (xy 109.948472 -220.146925) (xy 109.978998 -220.104909)
			(xy 110.015721 -220.068186) (xy 110.057737 -220.03766) (xy 110.104011 -220.014082) (xy 110.153404 -219.998034)
			(xy 110.204699 -219.989909) (xy 110.256633 -219.989909) (xy 110.307928 -219.998034) (xy 110.357321 -220.014082)
			(xy 110.403595 -220.03766) (xy 110.445611 -220.068186) (xy 110.482334 -220.104909) (xy 110.51286 -220.146925)
			(xy 110.536438 -220.193199) (xy 110.552486 -220.242592) (xy 110.560611 -220.293887) (xy 110.56112 -220.319854)
			(xy 110.839758 -220.319854) (xy 110.840267 -220.293887) (xy 110.848392 -220.242592) (xy 110.86444 -220.193199)
			(xy 110.888018 -220.146925) (xy 110.918544 -220.104909) (xy 110.955267 -220.068186) (xy 110.997283 -220.03766)
			(xy 111.043557 -220.014082) (xy 111.09295 -219.998034) (xy 111.144245 -219.989909) (xy 111.196179 -219.989909)
			(xy 111.247474 -219.998034) (xy 111.296867 -220.014082) (xy 111.343141 -220.03766) (xy 111.385157 -220.068186)
			(xy 111.42188 -220.104909) (xy 111.452406 -220.146925) (xy 111.475984 -220.193199) (xy 111.492032 -220.242592)
			(xy 111.500157 -220.293887) (xy 111.500666 -220.319854) (xy 111.500169 -220.345821) (xy 111.780321 -220.345821)
			(xy 111.780321 -220.293887) (xy 111.788446 -220.242592) (xy 111.804494 -220.193199) (xy 111.828072 -220.146925)
			(xy 111.858598 -220.104909) (xy 111.895321 -220.068186) (xy 111.937337 -220.03766) (xy 111.983611 -220.014082)
			(xy 112.033004 -219.998034) (xy 112.084299 -219.989909) (xy 112.136233 -219.989909) (xy 112.187528 -219.998034)
			(xy 112.236921 -220.014082) (xy 112.283195 -220.03766) (xy 112.325211 -220.068186) (xy 112.361934 -220.104909)
			(xy 112.39246 -220.146925) (xy 112.416038 -220.193199) (xy 112.432086 -220.242592) (xy 112.440211 -220.293887)
			(xy 112.44072 -220.319854) (xy 112.719358 -220.319854) (xy 112.719867 -220.293887) (xy 112.727992 -220.242592)
			(xy 112.74404 -220.193199) (xy 112.767618 -220.146925) (xy 112.798144 -220.104909) (xy 112.834867 -220.068186)
			(xy 112.876883 -220.03766) (xy 112.923157 -220.014082) (xy 112.97255 -219.998034) (xy 113.023845 -219.989909)
			(xy 113.075779 -219.989909) (xy 113.127074 -219.998034) (xy 113.176467 -220.014082) (xy 113.222741 -220.03766)
			(xy 113.264757 -220.068186) (xy 113.30148 -220.104909) (xy 113.332006 -220.146925) (xy 113.355584 -220.193199)
			(xy 113.371632 -220.242592) (xy 113.379757 -220.293887) (xy 113.380266 -220.319854) (xy 113.379769 -220.345821)
			(xy 113.659921 -220.345821) (xy 113.659921 -220.293887) (xy 113.668046 -220.242592) (xy 113.684094 -220.193199)
			(xy 113.707672 -220.146925) (xy 113.738198 -220.104909) (xy 113.774921 -220.068186) (xy 113.816937 -220.03766)
			(xy 113.863211 -220.014082) (xy 113.912604 -219.998034) (xy 113.963899 -219.989909) (xy 114.015833 -219.989909)
			(xy 114.067128 -219.998034) (xy 114.116521 -220.014082) (xy 114.162795 -220.03766) (xy 114.204811 -220.068186)
			(xy 114.241534 -220.104909) (xy 114.27206 -220.146925) (xy 114.295638 -220.193199) (xy 114.311686 -220.242592)
			(xy 114.319811 -220.293887) (xy 114.32032 -220.319854) (xy 114.598958 -220.319854) (xy 114.599467 -220.293887)
			(xy 114.607592 -220.242592) (xy 114.62364 -220.193199) (xy 114.647218 -220.146925) (xy 114.677744 -220.104909)
			(xy 114.714467 -220.068186) (xy 114.756483 -220.03766) (xy 114.802757 -220.014082) (xy 114.85215 -219.998034)
			(xy 114.903445 -219.989909) (xy 114.955379 -219.989909) (xy 115.006674 -219.998034) (xy 115.056067 -220.014082)
			(xy 115.102341 -220.03766) (xy 115.144357 -220.068186) (xy 115.18108 -220.104909) (xy 115.211606 -220.146925)
			(xy 115.235184 -220.193199) (xy 115.251232 -220.242592) (xy 115.259357 -220.293887) (xy 115.259866 -220.319854)
			(xy 115.259369 -220.345821) (xy 115.539521 -220.345821) (xy 115.539521 -220.293887) (xy 115.547646 -220.242592)
			(xy 115.563694 -220.193199) (xy 115.587272 -220.146925) (xy 115.617798 -220.104909) (xy 115.654521 -220.068186)
			(xy 115.696537 -220.03766) (xy 115.742811 -220.014082) (xy 115.792204 -219.998034) (xy 115.843499 -219.989909)
			(xy 115.895433 -219.989909) (xy 115.946728 -219.998034) (xy 115.996121 -220.014082) (xy 116.042395 -220.03766)
			(xy 116.084411 -220.068186) (xy 116.121134 -220.104909) (xy 116.15166 -220.146925) (xy 116.175238 -220.193199)
			(xy 116.191286 -220.242592) (xy 116.199411 -220.293887) (xy 116.19992 -220.319854) (xy 116.478558 -220.319854)
			(xy 116.479067 -220.293887) (xy 116.487192 -220.242592) (xy 116.50324 -220.193199) (xy 116.526818 -220.146925)
			(xy 116.557344 -220.104909) (xy 116.594067 -220.068186) (xy 116.636083 -220.03766) (xy 116.682357 -220.014082)
			(xy 116.73175 -219.998034) (xy 116.783045 -219.989909) (xy 116.834979 -219.989909) (xy 116.886274 -219.998034)
			(xy 116.935667 -220.014082) (xy 116.981941 -220.03766) (xy 117.023957 -220.068186) (xy 117.06068 -220.104909)
			(xy 117.091206 -220.146925) (xy 117.114784 -220.193199) (xy 117.130832 -220.242592) (xy 117.138957 -220.293887)
			(xy 117.139466 -220.319854) (xy 117.138969 -220.345821) (xy 117.419121 -220.345821) (xy 117.419121 -220.293887)
			(xy 117.427246 -220.242592) (xy 117.443294 -220.193199) (xy 117.466872 -220.146925) (xy 117.497398 -220.104909)
			(xy 117.534121 -220.068186) (xy 117.576137 -220.03766) (xy 117.622411 -220.014082) (xy 117.671804 -219.998034)
			(xy 117.723099 -219.989909) (xy 117.775033 -219.989909) (xy 117.826328 -219.998034) (xy 117.875721 -220.014082)
			(xy 117.921995 -220.03766) (xy 117.964011 -220.068186) (xy 118.000734 -220.104909) (xy 118.03126 -220.146925)
			(xy 118.054838 -220.193199) (xy 118.070886 -220.242592) (xy 118.079011 -220.293887) (xy 118.07952 -220.319854)
			(xy 118.358158 -220.319854) (xy 118.358667 -220.293887) (xy 118.366792 -220.242592) (xy 118.38284 -220.193199)
			(xy 118.406418 -220.146925) (xy 118.436944 -220.104909) (xy 118.473667 -220.068186) (xy 118.515683 -220.03766)
			(xy 118.561957 -220.014082) (xy 118.61135 -219.998034) (xy 118.662645 -219.989909) (xy 118.714579 -219.989909)
			(xy 118.765874 -219.998034) (xy 118.815267 -220.014082) (xy 118.861541 -220.03766) (xy 118.903557 -220.068186)
			(xy 118.94028 -220.104909) (xy 118.970806 -220.146925) (xy 118.994384 -220.193199) (xy 119.010432 -220.242592)
			(xy 119.018557 -220.293887) (xy 119.019066 -220.319854) (xy 119.018569 -220.345821) (xy 119.298721 -220.345821)
			(xy 119.298721 -220.293887) (xy 119.306846 -220.242592) (xy 119.322894 -220.193199) (xy 119.346472 -220.146925)
			(xy 119.376998 -220.104909) (xy 119.413721 -220.068186) (xy 119.455737 -220.03766) (xy 119.502011 -220.014082)
			(xy 119.551404 -219.998034) (xy 119.602699 -219.989909) (xy 119.654633 -219.989909) (xy 119.705928 -219.998034)
			(xy 119.755321 -220.014082) (xy 119.801595 -220.03766) (xy 119.843611 -220.068186) (xy 119.880334 -220.104909)
			(xy 119.91086 -220.146925) (xy 119.934438 -220.193199) (xy 119.950486 -220.242592) (xy 119.958611 -220.293887)
			(xy 119.95912 -220.319854) (xy 120.237758 -220.319854) (xy 120.238267 -220.293887) (xy 120.246392 -220.242592)
			(xy 120.26244 -220.193199) (xy 120.286018 -220.146925) (xy 120.316544 -220.104909) (xy 120.353267 -220.068186)
			(xy 120.395283 -220.03766) (xy 120.441557 -220.014082) (xy 120.49095 -219.998034) (xy 120.542245 -219.989909)
			(xy 120.594179 -219.989909) (xy 120.645474 -219.998034) (xy 120.694867 -220.014082) (xy 120.741141 -220.03766)
			(xy 120.783157 -220.068186) (xy 120.81988 -220.104909) (xy 120.850406 -220.146925) (xy 120.873984 -220.193199)
			(xy 120.890032 -220.242592) (xy 120.898157 -220.293887) (xy 120.898666 -220.319854) (xy 120.898169 -220.345821)
			(xy 121.178321 -220.345821) (xy 121.178321 -220.293887) (xy 121.186446 -220.242592) (xy 121.202494 -220.193199)
			(xy 121.226072 -220.146925) (xy 121.256598 -220.104909) (xy 121.293321 -220.068186) (xy 121.335337 -220.03766)
			(xy 121.381611 -220.014082) (xy 121.431004 -219.998034) (xy 121.482299 -219.989909) (xy 121.534233 -219.989909)
			(xy 121.585528 -219.998034) (xy 121.634921 -220.014082) (xy 121.681195 -220.03766) (xy 121.723211 -220.068186)
			(xy 121.759934 -220.104909) (xy 121.79046 -220.146925) (xy 121.814038 -220.193199) (xy 121.830086 -220.242592)
			(xy 121.838211 -220.293887) (xy 121.83872 -220.319854) (xy 122.117358 -220.319854) (xy 122.117867 -220.293887)
			(xy 122.125992 -220.242592) (xy 122.14204 -220.193199) (xy 122.165618 -220.146925) (xy 122.196144 -220.104909)
			(xy 122.232867 -220.068186) (xy 122.274883 -220.03766) (xy 122.321157 -220.014082) (xy 122.37055 -219.998034)
			(xy 122.421845 -219.989909) (xy 122.473779 -219.989909) (xy 122.525074 -219.998034) (xy 122.574467 -220.014082)
			(xy 122.620741 -220.03766) (xy 122.662757 -220.068186) (xy 122.69948 -220.104909) (xy 122.730006 -220.146925)
			(xy 122.753584 -220.193199) (xy 122.769632 -220.242592) (xy 122.777757 -220.293887) (xy 122.778266 -220.319854)
			(xy 122.777769 -220.345821) (xy 123.057921 -220.345821) (xy 123.057921 -220.293887) (xy 123.066046 -220.242592)
			(xy 123.082094 -220.193199) (xy 123.105672 -220.146925) (xy 123.136198 -220.104909) (xy 123.172921 -220.068186)
			(xy 123.214937 -220.03766) (xy 123.261211 -220.014082) (xy 123.310604 -219.998034) (xy 123.361899 -219.989909)
			(xy 123.413833 -219.989909) (xy 123.465128 -219.998034) (xy 123.514521 -220.014082) (xy 123.560795 -220.03766)
			(xy 123.602811 -220.068186) (xy 123.639534 -220.104909) (xy 123.67006 -220.146925) (xy 123.693638 -220.193199)
			(xy 123.709686 -220.242592) (xy 123.717811 -220.293887) (xy 123.71832 -220.319854) (xy 123.996958 -220.319854)
			(xy 123.997467 -220.293887) (xy 124.005592 -220.242592) (xy 124.02164 -220.193199) (xy 124.045218 -220.146925)
			(xy 124.075744 -220.104909) (xy 124.112467 -220.068186) (xy 124.154483 -220.03766) (xy 124.200757 -220.014082)
			(xy 124.25015 -219.998034) (xy 124.301445 -219.989909) (xy 124.353379 -219.989909) (xy 124.404674 -219.998034)
			(xy 124.454067 -220.014082) (xy 124.500341 -220.03766) (xy 124.542357 -220.068186) (xy 124.57908 -220.104909)
			(xy 124.609606 -220.146925) (xy 124.633184 -220.193199) (xy 124.649232 -220.242592) (xy 124.657357 -220.293887)
			(xy 124.657866 -220.319854) (xy 124.657369 -220.345821) (xy 124.937521 -220.345821) (xy 124.937521 -220.293887)
			(xy 124.945646 -220.242592) (xy 124.961694 -220.193199) (xy 124.985272 -220.146925) (xy 125.015798 -220.104909)
			(xy 125.052521 -220.068186) (xy 125.094537 -220.03766) (xy 125.140811 -220.014082) (xy 125.190204 -219.998034)
			(xy 125.241499 -219.989909) (xy 125.293433 -219.989909) (xy 125.344728 -219.998034) (xy 125.394121 -220.014082)
			(xy 125.440395 -220.03766) (xy 125.482411 -220.068186) (xy 125.519134 -220.104909) (xy 125.54966 -220.146925)
			(xy 125.573238 -220.193199) (xy 125.589286 -220.242592) (xy 125.597411 -220.293887) (xy 125.59792 -220.319854)
			(xy 125.876558 -220.319854) (xy 125.877067 -220.293887) (xy 125.885192 -220.242592) (xy 125.90124 -220.193199)
			(xy 125.924818 -220.146925) (xy 125.955344 -220.104909) (xy 125.992067 -220.068186) (xy 126.034083 -220.03766)
			(xy 126.080357 -220.014082) (xy 126.12975 -219.998034) (xy 126.181045 -219.989909) (xy 126.232979 -219.989909)
			(xy 126.284274 -219.998034) (xy 126.333667 -220.014082) (xy 126.379941 -220.03766) (xy 126.421957 -220.068186)
			(xy 126.45868 -220.104909) (xy 126.489206 -220.146925) (xy 126.512784 -220.193199) (xy 126.528832 -220.242592)
			(xy 126.536957 -220.293887) (xy 126.537466 -220.319854) (xy 126.536969 -220.345821) (xy 126.817121 -220.345821)
			(xy 126.817121 -220.293887) (xy 126.825246 -220.242592) (xy 126.841294 -220.193199) (xy 126.864872 -220.146925)
			(xy 126.895398 -220.104909) (xy 126.932121 -220.068186) (xy 126.974137 -220.03766) (xy 127.020411 -220.014082)
			(xy 127.069804 -219.998034) (xy 127.121099 -219.989909) (xy 127.173033 -219.989909) (xy 127.224328 -219.998034)
			(xy 127.273721 -220.014082) (xy 127.319995 -220.03766) (xy 127.362011 -220.068186) (xy 127.398734 -220.104909)
			(xy 127.42926 -220.146925) (xy 127.452838 -220.193199) (xy 127.468886 -220.242592) (xy 127.477011 -220.293887)
			(xy 127.47752 -220.319854) (xy 127.477011 -220.345821) (xy 127.468886 -220.397116) (xy 127.452838 -220.446509)
			(xy 127.42926 -220.492783) (xy 127.398734 -220.534799) (xy 127.362011 -220.571522) (xy 127.319995 -220.602048)
			(xy 127.273721 -220.625626) (xy 127.224328 -220.641674) (xy 127.173033 -220.649799) (xy 127.121099 -220.649799)
			(xy 127.069804 -220.641674) (xy 127.020411 -220.625626) (xy 126.974137 -220.602048) (xy 126.932121 -220.571522)
			(xy 126.895398 -220.534799) (xy 126.864872 -220.492783) (xy 126.841294 -220.446509) (xy 126.825246 -220.397116)
			(xy 126.817121 -220.345821) (xy 126.536969 -220.345821) (xy 126.536932 -220.347764) (xy 126.527604 -220.402797)
			(xy 126.518924 -220.429328) (xy 126.51105 -220.451172) (xy 126.715266 -220.80474) (xy 126.738126 -220.809058)
			(xy 126.763044 -220.814243) (xy 126.811027 -220.831206) (xy 126.855845 -220.85532) (xy 126.896438 -220.886018)
			(xy 126.931847 -220.922574) (xy 126.961236 -220.964124) (xy 126.983911 -221.009687) (xy 126.999335 -221.058187)
			(xy 127.007146 -221.108477) (xy 127.00762 -221.133924) (xy 127.007111 -221.159891) (xy 126.998986 -221.211186)
			(xy 126.982938 -221.260579) (xy 126.95936 -221.306853) (xy 126.928834 -221.348869) (xy 126.892111 -221.385592)
			(xy 126.850095 -221.416118) (xy 126.803821 -221.439696) (xy 126.754428 -221.455744) (xy 126.703133 -221.463869)
			(xy 126.651199 -221.463869) (xy 126.599904 -221.455744) (xy 126.550511 -221.439696) (xy 126.504237 -221.416118)
			(xy 126.462221 -221.385592) (xy 126.425498 -221.348869) (xy 126.394972 -221.306853) (xy 126.371394 -221.260579)
			(xy 126.355346 -221.211186) (xy 126.347221 -221.159891) (xy 126.346712 -221.133924) (xy 126.34727 -221.105938)
			(xy 126.356716 -221.050771) (xy 126.365508 -221.024196) (xy 126.373128 -221.002098) (xy 126.16942 -220.649038)
			(xy 126.146306 -220.64472) (xy 126.12137 -220.63956) (xy 126.073347 -220.62263) (xy 126.028488 -220.598536)
			(xy 125.987855 -220.567848) (xy 125.952409 -220.531292) (xy 125.922989 -220.489732) (xy 125.900289 -220.444152)
			(xy 125.884849 -220.39563) (xy 125.877032 -220.345314) (xy 125.876558 -220.319854) (xy 125.59792 -220.319854)
			(xy 125.597411 -220.345821) (xy 125.589286 -220.397116) (xy 125.573238 -220.446509) (xy 125.54966 -220.492783)
			(xy 125.519134 -220.534799) (xy 125.482411 -220.571522) (xy 125.440395 -220.602048) (xy 125.394121 -220.625626)
			(xy 125.344728 -220.641674) (xy 125.293433 -220.649799) (xy 125.241499 -220.649799) (xy 125.190204 -220.641674)
			(xy 125.140811 -220.625626) (xy 125.094537 -220.602048) (xy 125.052521 -220.571522) (xy 125.015798 -220.534799)
			(xy 124.985272 -220.492783) (xy 124.961694 -220.446509) (xy 124.945646 -220.397116) (xy 124.937521 -220.345821)
			(xy 124.657369 -220.345821) (xy 124.657332 -220.347764) (xy 124.648004 -220.402797) (xy 124.639324 -220.429328)
			(xy 124.63145 -220.451172) (xy 124.835666 -220.80474) (xy 124.858526 -220.809058) (xy 124.883444 -220.814243)
			(xy 124.931427 -220.831206) (xy 124.976245 -220.85532) (xy 125.016838 -220.886018) (xy 125.052247 -220.922574)
			(xy 125.081636 -220.964124) (xy 125.104311 -221.009687) (xy 125.119735 -221.058187) (xy 125.127546 -221.108477)
			(xy 125.12802 -221.133924) (xy 125.127511 -221.159891) (xy 125.119386 -221.211186) (xy 125.103338 -221.260579)
			(xy 125.07976 -221.306853) (xy 125.049234 -221.348869) (xy 125.012511 -221.385592) (xy 124.970495 -221.416118)
			(xy 124.924221 -221.439696) (xy 124.874828 -221.455744) (xy 124.823533 -221.463869) (xy 124.771599 -221.463869)
			(xy 124.720304 -221.455744) (xy 124.670911 -221.439696) (xy 124.624637 -221.416118) (xy 124.582621 -221.385592)
			(xy 124.545898 -221.348869) (xy 124.515372 -221.306853) (xy 124.491794 -221.260579) (xy 124.475746 -221.211186)
			(xy 124.467621 -221.159891) (xy 124.467112 -221.133924) (xy 124.46767 -221.105938) (xy 124.477116 -221.050771)
			(xy 124.485908 -221.024196) (xy 124.493528 -221.002098) (xy 124.28982 -220.649038) (xy 124.266706 -220.64472)
			(xy 124.24177 -220.63956) (xy 124.193747 -220.62263) (xy 124.148888 -220.598536) (xy 124.108255 -220.567848)
			(xy 124.072809 -220.531292) (xy 124.043389 -220.489732) (xy 124.020689 -220.444152) (xy 124.005249 -220.39563)
			(xy 123.997432 -220.345314) (xy 123.996958 -220.319854) (xy 123.71832 -220.319854) (xy 123.717811 -220.345821)
			(xy 123.709686 -220.397116) (xy 123.693638 -220.446509) (xy 123.67006 -220.492783) (xy 123.639534 -220.534799)
			(xy 123.602811 -220.571522) (xy 123.560795 -220.602048) (xy 123.514521 -220.625626) (xy 123.465128 -220.641674)
			(xy 123.413833 -220.649799) (xy 123.361899 -220.649799) (xy 123.310604 -220.641674) (xy 123.261211 -220.625626)
			(xy 123.214937 -220.602048) (xy 123.172921 -220.571522) (xy 123.136198 -220.534799) (xy 123.105672 -220.492783)
			(xy 123.082094 -220.446509) (xy 123.066046 -220.397116) (xy 123.057921 -220.345821) (xy 122.777769 -220.345821)
			(xy 122.777732 -220.347764) (xy 122.768404 -220.402797) (xy 122.759724 -220.429328) (xy 122.75185 -220.451172)
			(xy 122.956066 -220.80474) (xy 122.978926 -220.809058) (xy 123.003844 -220.814243) (xy 123.051827 -220.831206)
			(xy 123.096645 -220.85532) (xy 123.137238 -220.886018) (xy 123.172647 -220.922574) (xy 123.202036 -220.964124)
			(xy 123.224711 -221.009687) (xy 123.240135 -221.058187) (xy 123.247946 -221.108477) (xy 123.24842 -221.133924)
			(xy 123.247911 -221.159891) (xy 123.239786 -221.211186) (xy 123.223738 -221.260579) (xy 123.20016 -221.306853)
			(xy 123.169634 -221.348869) (xy 123.132911 -221.385592) (xy 123.090895 -221.416118) (xy 123.044621 -221.439696)
			(xy 122.995228 -221.455744) (xy 122.943933 -221.463869) (xy 122.891999 -221.463869) (xy 122.840704 -221.455744)
			(xy 122.791311 -221.439696) (xy 122.745037 -221.416118) (xy 122.703021 -221.385592) (xy 122.666298 -221.348869)
			(xy 122.635772 -221.306853) (xy 122.612194 -221.260579) (xy 122.596146 -221.211186) (xy 122.588021 -221.159891)
			(xy 122.587512 -221.133924) (xy 122.58807 -221.105938) (xy 122.597516 -221.050771) (xy 122.606308 -221.024196)
			(xy 122.613928 -221.002098) (xy 122.41022 -220.649038) (xy 122.387106 -220.64472) (xy 122.36217 -220.63956)
			(xy 122.314147 -220.62263) (xy 122.269288 -220.598536) (xy 122.228655 -220.567848) (xy 122.193209 -220.531292)
			(xy 122.163789 -220.489732) (xy 122.141089 -220.444152) (xy 122.125649 -220.39563) (xy 122.117832 -220.345314)
			(xy 122.117358 -220.319854) (xy 121.83872 -220.319854) (xy 121.838211 -220.345821) (xy 121.830086 -220.397116)
			(xy 121.814038 -220.446509) (xy 121.79046 -220.492783) (xy 121.759934 -220.534799) (xy 121.723211 -220.571522)
			(xy 121.681195 -220.602048) (xy 121.634921 -220.625626) (xy 121.585528 -220.641674) (xy 121.534233 -220.649799)
			(xy 121.482299 -220.649799) (xy 121.431004 -220.641674) (xy 121.381611 -220.625626) (xy 121.335337 -220.602048)
			(xy 121.293321 -220.571522) (xy 121.256598 -220.534799) (xy 121.226072 -220.492783) (xy 121.202494 -220.446509)
			(xy 121.186446 -220.397116) (xy 121.178321 -220.345821) (xy 120.898169 -220.345821) (xy 120.898132 -220.347764)
			(xy 120.888804 -220.402797) (xy 120.880124 -220.429328) (xy 120.87225 -220.451172) (xy 121.076466 -220.80474)
			(xy 121.099326 -220.809058) (xy 121.124244 -220.814243) (xy 121.172227 -220.831206) (xy 121.217045 -220.85532)
			(xy 121.257638 -220.886018) (xy 121.293047 -220.922574) (xy 121.322436 -220.964124) (xy 121.345111 -221.009687)
			(xy 121.360535 -221.058187) (xy 121.368346 -221.108477) (xy 121.36882 -221.133924) (xy 121.368311 -221.159891)
			(xy 121.360186 -221.211186) (xy 121.344138 -221.260579) (xy 121.32056 -221.306853) (xy 121.290034 -221.348869)
			(xy 121.253311 -221.385592) (xy 121.211295 -221.416118) (xy 121.165021 -221.439696) (xy 121.115628 -221.455744)
			(xy 121.064333 -221.463869) (xy 121.012399 -221.463869) (xy 120.961104 -221.455744) (xy 120.911711 -221.439696)
			(xy 120.865437 -221.416118) (xy 120.823421 -221.385592) (xy 120.786698 -221.348869) (xy 120.756172 -221.306853)
			(xy 120.732594 -221.260579) (xy 120.716546 -221.211186) (xy 120.708421 -221.159891) (xy 120.707912 -221.133924)
			(xy 120.70847 -221.105938) (xy 120.717916 -221.050771) (xy 120.726708 -221.024196) (xy 120.734328 -221.002098)
			(xy 120.53062 -220.649038) (xy 120.507506 -220.64472) (xy 120.48257 -220.63956) (xy 120.434547 -220.62263)
			(xy 120.389688 -220.598536) (xy 120.349055 -220.567848) (xy 120.313609 -220.531292) (xy 120.284189 -220.489732)
			(xy 120.261489 -220.444152) (xy 120.246049 -220.39563) (xy 120.238232 -220.345314) (xy 120.237758 -220.319854)
			(xy 119.95912 -220.319854) (xy 119.958611 -220.345821) (xy 119.950486 -220.397116) (xy 119.934438 -220.446509)
			(xy 119.91086 -220.492783) (xy 119.880334 -220.534799) (xy 119.843611 -220.571522) (xy 119.801595 -220.602048)
			(xy 119.755321 -220.625626) (xy 119.705928 -220.641674) (xy 119.654633 -220.649799) (xy 119.602699 -220.649799)
			(xy 119.551404 -220.641674) (xy 119.502011 -220.625626) (xy 119.455737 -220.602048) (xy 119.413721 -220.571522)
			(xy 119.376998 -220.534799) (xy 119.346472 -220.492783) (xy 119.322894 -220.446509) (xy 119.306846 -220.397116)
			(xy 119.298721 -220.345821) (xy 119.018569 -220.345821) (xy 119.018532 -220.347764) (xy 119.009204 -220.402797)
			(xy 119.000524 -220.429328) (xy 118.99265 -220.451172) (xy 119.196866 -220.80474) (xy 119.219726 -220.809058)
			(xy 119.244644 -220.814243) (xy 119.292627 -220.831206) (xy 119.337445 -220.85532) (xy 119.378038 -220.886018)
			(xy 119.413447 -220.922574) (xy 119.442836 -220.964124) (xy 119.465511 -221.009687) (xy 119.480935 -221.058187)
			(xy 119.488746 -221.108477) (xy 119.48922 -221.133924) (xy 119.488711 -221.159891) (xy 119.768367 -221.159891)
			(xy 119.768367 -221.107957) (xy 119.776492 -221.056662) (xy 119.79254 -221.007269) (xy 119.816118 -220.960995)
			(xy 119.846644 -220.918979) (xy 119.883367 -220.882256) (xy 119.925383 -220.85173) (xy 119.971657 -220.828152)
			(xy 120.02105 -220.812104) (xy 120.072345 -220.803979) (xy 120.124279 -220.803979) (xy 120.175574 -220.812104)
			(xy 120.224967 -220.828152) (xy 120.271241 -220.85173) (xy 120.313257 -220.882256) (xy 120.34998 -220.918979)
			(xy 120.380506 -220.960995) (xy 120.404084 -221.007269) (xy 120.420132 -221.056662) (xy 120.428257 -221.107957)
			(xy 120.428766 -221.133924) (xy 120.428257 -221.159891) (xy 120.420132 -221.211186) (xy 120.404084 -221.260579)
			(xy 120.380506 -221.306853) (xy 120.34998 -221.348869) (xy 120.313257 -221.385592) (xy 120.271241 -221.416118)
			(xy 120.224967 -221.439696) (xy 120.175574 -221.455744) (xy 120.124279 -221.463869) (xy 120.072345 -221.463869)
			(xy 120.02105 -221.455744) (xy 119.971657 -221.439696) (xy 119.925383 -221.416118) (xy 119.883367 -221.385592)
			(xy 119.846644 -221.348869) (xy 119.816118 -221.306853) (xy 119.79254 -221.260579) (xy 119.776492 -221.211186)
			(xy 119.768367 -221.159891) (xy 119.488711 -221.159891) (xy 119.480586 -221.211186) (xy 119.464538 -221.260579)
			(xy 119.44096 -221.306853) (xy 119.410434 -221.348869) (xy 119.373711 -221.385592) (xy 119.331695 -221.416118)
			(xy 119.285421 -221.439696) (xy 119.236028 -221.455744) (xy 119.184733 -221.463869) (xy 119.132799 -221.463869)
			(xy 119.081504 -221.455744) (xy 119.032111 -221.439696) (xy 118.985837 -221.416118) (xy 118.943821 -221.385592)
			(xy 118.907098 -221.348869) (xy 118.876572 -221.306853) (xy 118.852994 -221.260579) (xy 118.836946 -221.211186)
			(xy 118.828821 -221.159891) (xy 118.828312 -221.133924) (xy 118.82887 -221.105938) (xy 118.838316 -221.050771)
			(xy 118.847108 -221.024196) (xy 118.854728 -221.002098) (xy 118.65102 -220.649038) (xy 118.627906 -220.64472)
			(xy 118.60297 -220.63956) (xy 118.554947 -220.62263) (xy 118.510088 -220.598536) (xy 118.469455 -220.567848)
			(xy 118.434009 -220.531292) (xy 118.404589 -220.489732) (xy 118.381889 -220.444152) (xy 118.366449 -220.39563)
			(xy 118.358632 -220.345314) (xy 118.358158 -220.319854) (xy 118.07952 -220.319854) (xy 118.079011 -220.345821)
			(xy 118.070886 -220.397116) (xy 118.054838 -220.446509) (xy 118.03126 -220.492783) (xy 118.000734 -220.534799)
			(xy 117.964011 -220.571522) (xy 117.921995 -220.602048) (xy 117.875721 -220.625626) (xy 117.826328 -220.641674)
			(xy 117.775033 -220.649799) (xy 117.723099 -220.649799) (xy 117.671804 -220.641674) (xy 117.622411 -220.625626)
			(xy 117.576137 -220.602048) (xy 117.534121 -220.571522) (xy 117.497398 -220.534799) (xy 117.466872 -220.492783)
			(xy 117.443294 -220.446509) (xy 117.427246 -220.397116) (xy 117.419121 -220.345821) (xy 117.138969 -220.345821)
			(xy 117.138932 -220.347764) (xy 117.129604 -220.402797) (xy 117.120924 -220.429328) (xy 117.11305 -220.451172)
			(xy 117.317266 -220.80474) (xy 117.340126 -220.809058) (xy 117.365044 -220.814243) (xy 117.413027 -220.831206)
			(xy 117.457845 -220.85532) (xy 117.498438 -220.886018) (xy 117.533847 -220.922574) (xy 117.563236 -220.964124)
			(xy 117.585911 -221.009687) (xy 117.601335 -221.058187) (xy 117.609146 -221.108477) (xy 117.60962 -221.133924)
			(xy 117.609111 -221.159891) (xy 117.600986 -221.211186) (xy 117.584938 -221.260579) (xy 117.56136 -221.306853)
			(xy 117.530834 -221.348869) (xy 117.494111 -221.385592) (xy 117.452095 -221.416118) (xy 117.405821 -221.439696)
			(xy 117.356428 -221.455744) (xy 117.305133 -221.463869) (xy 117.253199 -221.463869) (xy 117.201904 -221.455744)
			(xy 117.152511 -221.439696) (xy 117.106237 -221.416118) (xy 117.064221 -221.385592) (xy 117.027498 -221.348869)
			(xy 116.996972 -221.306853) (xy 116.973394 -221.260579) (xy 116.957346 -221.211186) (xy 116.949221 -221.159891)
			(xy 116.948712 -221.133924) (xy 116.94927 -221.105938) (xy 116.958716 -221.050771) (xy 116.967508 -221.024196)
			(xy 116.975128 -221.002098) (xy 116.77142 -220.649038) (xy 116.748306 -220.64472) (xy 116.72337 -220.63956)
			(xy 116.675347 -220.62263) (xy 116.630488 -220.598536) (xy 116.589855 -220.567848) (xy 116.554409 -220.531292)
			(xy 116.524989 -220.489732) (xy 116.502289 -220.444152) (xy 116.486849 -220.39563) (xy 116.479032 -220.345314)
			(xy 116.478558 -220.319854) (xy 116.19992 -220.319854) (xy 116.199411 -220.345821) (xy 116.191286 -220.397116)
			(xy 116.175238 -220.446509) (xy 116.15166 -220.492783) (xy 116.121134 -220.534799) (xy 116.084411 -220.571522)
			(xy 116.042395 -220.602048) (xy 115.996121 -220.625626) (xy 115.946728 -220.641674) (xy 115.895433 -220.649799)
			(xy 115.843499 -220.649799) (xy 115.792204 -220.641674) (xy 115.742811 -220.625626) (xy 115.696537 -220.602048)
			(xy 115.654521 -220.571522) (xy 115.617798 -220.534799) (xy 115.587272 -220.492783) (xy 115.563694 -220.446509)
			(xy 115.547646 -220.397116) (xy 115.539521 -220.345821) (xy 115.259369 -220.345821) (xy 115.259332 -220.347764)
			(xy 115.250004 -220.402797) (xy 115.241324 -220.429328) (xy 115.23345 -220.451172) (xy 115.437666 -220.80474)
			(xy 115.460526 -220.809058) (xy 115.485444 -220.814243) (xy 115.533427 -220.831206) (xy 115.578245 -220.85532)
			(xy 115.618838 -220.886018) (xy 115.654247 -220.922574) (xy 115.683636 -220.964124) (xy 115.706311 -221.009687)
			(xy 115.721735 -221.058187) (xy 115.729546 -221.108477) (xy 115.73002 -221.133924) (xy 115.729511 -221.159891)
			(xy 115.721386 -221.211186) (xy 115.705338 -221.260579) (xy 115.68176 -221.306853) (xy 115.651234 -221.348869)
			(xy 115.614511 -221.385592) (xy 115.572495 -221.416118) (xy 115.526221 -221.439696) (xy 115.476828 -221.455744)
			(xy 115.425533 -221.463869) (xy 115.373599 -221.463869) (xy 115.322304 -221.455744) (xy 115.272911 -221.439696)
			(xy 115.226637 -221.416118) (xy 115.184621 -221.385592) (xy 115.147898 -221.348869) (xy 115.117372 -221.306853)
			(xy 115.093794 -221.260579) (xy 115.077746 -221.211186) (xy 115.069621 -221.159891) (xy 115.069112 -221.133924)
			(xy 115.06967 -221.105938) (xy 115.079116 -221.050771) (xy 115.087908 -221.024196) (xy 115.095528 -221.002098)
			(xy 114.89182 -220.649038) (xy 114.868706 -220.64472) (xy 114.84377 -220.63956) (xy 114.795747 -220.62263)
			(xy 114.750888 -220.598536) (xy 114.710255 -220.567848) (xy 114.674809 -220.531292) (xy 114.645389 -220.489732)
			(xy 114.622689 -220.444152) (xy 114.607249 -220.39563) (xy 114.599432 -220.345314) (xy 114.598958 -220.319854)
			(xy 114.32032 -220.319854) (xy 114.319811 -220.345821) (xy 114.311686 -220.397116) (xy 114.295638 -220.446509)
			(xy 114.27206 -220.492783) (xy 114.241534 -220.534799) (xy 114.204811 -220.571522) (xy 114.162795 -220.602048)
			(xy 114.116521 -220.625626) (xy 114.067128 -220.641674) (xy 114.015833 -220.649799) (xy 113.963899 -220.649799)
			(xy 113.912604 -220.641674) (xy 113.863211 -220.625626) (xy 113.816937 -220.602048) (xy 113.774921 -220.571522)
			(xy 113.738198 -220.534799) (xy 113.707672 -220.492783) (xy 113.684094 -220.446509) (xy 113.668046 -220.397116)
			(xy 113.659921 -220.345821) (xy 113.379769 -220.345821) (xy 113.379732 -220.347764) (xy 113.370404 -220.402797)
			(xy 113.361724 -220.429328) (xy 113.35385 -220.451172) (xy 113.558066 -220.80474) (xy 113.580926 -220.809058)
			(xy 113.605844 -220.814243) (xy 113.653827 -220.831206) (xy 113.698645 -220.85532) (xy 113.739238 -220.886018)
			(xy 113.774647 -220.922574) (xy 113.804036 -220.964124) (xy 113.826711 -221.009687) (xy 113.842135 -221.058187)
			(xy 113.849946 -221.108477) (xy 113.85042 -221.133924) (xy 113.849911 -221.159891) (xy 113.841786 -221.211186)
			(xy 113.825738 -221.260579) (xy 113.80216 -221.306853) (xy 113.771634 -221.348869) (xy 113.734911 -221.385592)
			(xy 113.692895 -221.416118) (xy 113.646621 -221.439696) (xy 113.597228 -221.455744) (xy 113.545933 -221.463869)
			(xy 113.493999 -221.463869) (xy 113.442704 -221.455744) (xy 113.393311 -221.439696) (xy 113.347037 -221.416118)
			(xy 113.305021 -221.385592) (xy 113.268298 -221.348869) (xy 113.237772 -221.306853) (xy 113.214194 -221.260579)
			(xy 113.198146 -221.211186) (xy 113.190021 -221.159891) (xy 113.189512 -221.133924) (xy 113.19007 -221.105938)
			(xy 113.199516 -221.050771) (xy 113.208308 -221.024196) (xy 113.215928 -221.002098) (xy 113.01222 -220.649038)
			(xy 112.989106 -220.64472) (xy 112.96417 -220.63956) (xy 112.916147 -220.62263) (xy 112.871288 -220.598536)
			(xy 112.830655 -220.567848) (xy 112.795209 -220.531292) (xy 112.765789 -220.489732) (xy 112.743089 -220.444152)
			(xy 112.727649 -220.39563) (xy 112.719832 -220.345314) (xy 112.719358 -220.319854) (xy 112.44072 -220.319854)
			(xy 112.440211 -220.345821) (xy 112.432086 -220.397116) (xy 112.416038 -220.446509) (xy 112.39246 -220.492783)
			(xy 112.361934 -220.534799) (xy 112.325211 -220.571522) (xy 112.283195 -220.602048) (xy 112.236921 -220.625626)
			(xy 112.187528 -220.641674) (xy 112.136233 -220.649799) (xy 112.084299 -220.649799) (xy 112.033004 -220.641674)
			(xy 111.983611 -220.625626) (xy 111.937337 -220.602048) (xy 111.895321 -220.571522) (xy 111.858598 -220.534799)
			(xy 111.828072 -220.492783) (xy 111.804494 -220.446509) (xy 111.788446 -220.397116) (xy 111.780321 -220.345821)
			(xy 111.500169 -220.345821) (xy 111.500132 -220.347764) (xy 111.490804 -220.402797) (xy 111.482124 -220.429328)
			(xy 111.47425 -220.451172) (xy 111.678466 -220.80474) (xy 111.701326 -220.809058) (xy 111.726244 -220.814243)
			(xy 111.774227 -220.831206) (xy 111.819045 -220.85532) (xy 111.859638 -220.886018) (xy 111.895047 -220.922574)
			(xy 111.924436 -220.964124) (xy 111.947111 -221.009687) (xy 111.962535 -221.058187) (xy 111.970346 -221.108477)
			(xy 111.97082 -221.133924) (xy 111.970311 -221.159891) (xy 111.962186 -221.211186) (xy 111.946138 -221.260579)
			(xy 111.92256 -221.306853) (xy 111.892034 -221.348869) (xy 111.855311 -221.385592) (xy 111.813295 -221.416118)
			(xy 111.767021 -221.439696) (xy 111.717628 -221.455744) (xy 111.666333 -221.463869) (xy 111.614399 -221.463869)
			(xy 111.563104 -221.455744) (xy 111.513711 -221.439696) (xy 111.467437 -221.416118) (xy 111.425421 -221.385592)
			(xy 111.388698 -221.348869) (xy 111.358172 -221.306853) (xy 111.334594 -221.260579) (xy 111.318546 -221.211186)
			(xy 111.310421 -221.159891) (xy 111.309912 -221.133924) (xy 111.31047 -221.105938) (xy 111.319916 -221.050771)
			(xy 111.328708 -221.024196) (xy 111.336328 -221.002098) (xy 111.13262 -220.649038) (xy 111.109506 -220.64472)
			(xy 111.08457 -220.63956) (xy 111.036547 -220.62263) (xy 110.991688 -220.598536) (xy 110.951055 -220.567848)
			(xy 110.915609 -220.531292) (xy 110.886189 -220.489732) (xy 110.863489 -220.444152) (xy 110.848049 -220.39563)
			(xy 110.840232 -220.345314) (xy 110.839758 -220.319854) (xy 110.56112 -220.319854) (xy 110.560611 -220.345821)
			(xy 110.552486 -220.397116) (xy 110.536438 -220.446509) (xy 110.51286 -220.492783) (xy 110.482334 -220.534799)
			(xy 110.445611 -220.571522) (xy 110.403595 -220.602048) (xy 110.357321 -220.625626) (xy 110.307928 -220.641674)
			(xy 110.256633 -220.649799) (xy 110.204699 -220.649799) (xy 110.153404 -220.641674) (xy 110.104011 -220.625626)
			(xy 110.057737 -220.602048) (xy 110.015721 -220.571522) (xy 109.978998 -220.534799) (xy 109.948472 -220.492783)
			(xy 109.924894 -220.446509) (xy 109.908846 -220.397116) (xy 109.900721 -220.345821) (xy 109.620569 -220.345821)
			(xy 109.620532 -220.347764) (xy 109.611204 -220.402797) (xy 109.602524 -220.429328) (xy 109.59465 -220.451172)
			(xy 109.798866 -220.80474) (xy 109.821726 -220.809058) (xy 109.846644 -220.814243) (xy 109.894627 -220.831206)
			(xy 109.939445 -220.85532) (xy 109.980038 -220.886018) (xy 110.015447 -220.922574) (xy 110.044836 -220.964124)
			(xy 110.067511 -221.009687) (xy 110.082935 -221.058187) (xy 110.090746 -221.108477) (xy 110.09122 -221.133924)
			(xy 110.090711 -221.159891) (xy 110.082586 -221.211186) (xy 110.066538 -221.260579) (xy 110.04296 -221.306853)
			(xy 110.012434 -221.348869) (xy 109.975711 -221.385592) (xy 109.933695 -221.416118) (xy 109.887421 -221.439696)
			(xy 109.838028 -221.455744) (xy 109.786733 -221.463869) (xy 109.734799 -221.463869) (xy 109.683504 -221.455744)
			(xy 109.634111 -221.439696) (xy 109.587837 -221.416118) (xy 109.545821 -221.385592) (xy 109.509098 -221.348869)
			(xy 109.478572 -221.306853) (xy 109.454994 -221.260579) (xy 109.438946 -221.211186) (xy 109.430821 -221.159891)
			(xy 109.430312 -221.133924) (xy 109.43087 -221.105938) (xy 109.440316 -221.050771) (xy 109.449108 -221.024196)
			(xy 109.456728 -221.002098) (xy 109.25302 -220.649038) (xy 109.229906 -220.64472) (xy 109.20497 -220.63956)
			(xy 109.156947 -220.62263) (xy 109.112088 -220.598536) (xy 109.071455 -220.567848) (xy 109.036009 -220.531292)
			(xy 109.006589 -220.489732) (xy 108.983889 -220.444152) (xy 108.968449 -220.39563) (xy 108.960632 -220.345314)
			(xy 108.960158 -220.319854) (xy 108.68152 -220.319854) (xy 108.681011 -220.345821) (xy 108.672886 -220.397116)
			(xy 108.656838 -220.446509) (xy 108.63326 -220.492783) (xy 108.602734 -220.534799) (xy 108.566011 -220.571522)
			(xy 108.523995 -220.602048) (xy 108.477721 -220.625626) (xy 108.428328 -220.641674) (xy 108.377033 -220.649799)
			(xy 108.325099 -220.649799) (xy 108.273804 -220.641674) (xy 108.224411 -220.625626) (xy 108.178137 -220.602048)
			(xy 108.136121 -220.571522) (xy 108.099398 -220.534799) (xy 108.068872 -220.492783) (xy 108.045294 -220.446509)
			(xy 108.029246 -220.397116) (xy 108.021121 -220.345821) (xy 107.740969 -220.345821) (xy 107.740932 -220.347764)
			(xy 107.731604 -220.402797) (xy 107.722924 -220.429328) (xy 107.71505 -220.451172) (xy 107.919266 -220.80474)
			(xy 107.942126 -220.809058) (xy 107.967044 -220.814243) (xy 108.015027 -220.831206) (xy 108.059845 -220.85532)
			(xy 108.100438 -220.886018) (xy 108.135847 -220.922574) (xy 108.165236 -220.964124) (xy 108.187911 -221.009687)
			(xy 108.203335 -221.058187) (xy 108.211146 -221.108477) (xy 108.21162 -221.133924) (xy 108.211111 -221.159891)
			(xy 108.202986 -221.211186) (xy 108.186938 -221.260579) (xy 108.16336 -221.306853) (xy 108.132834 -221.348869)
			(xy 108.096111 -221.385592) (xy 108.054095 -221.416118) (xy 108.007821 -221.439696) (xy 107.958428 -221.455744)
			(xy 107.907133 -221.463869) (xy 107.855199 -221.463869) (xy 107.803904 -221.455744) (xy 107.754511 -221.439696)
			(xy 107.708237 -221.416118) (xy 107.666221 -221.385592) (xy 107.629498 -221.348869) (xy 107.598972 -221.306853)
			(xy 107.575394 -221.260579) (xy 107.559346 -221.211186) (xy 107.551221 -221.159891) (xy 107.550712 -221.133924)
			(xy 107.55127 -221.105938) (xy 107.560716 -221.050771) (xy 107.569508 -221.024196) (xy 107.577128 -221.002098)
			(xy 107.37342 -220.649038) (xy 107.350306 -220.64472) (xy 107.32537 -220.63956) (xy 107.277347 -220.62263)
			(xy 107.232488 -220.598536) (xy 107.191855 -220.567848) (xy 107.156409 -220.531292) (xy 107.126989 -220.489732)
			(xy 107.104289 -220.444152) (xy 107.088849 -220.39563) (xy 107.081032 -220.345314) (xy 107.080558 -220.319854)
			(xy 106.80192 -220.319854) (xy 106.801411 -220.345821) (xy 106.793286 -220.397116) (xy 106.777238 -220.446509)
			(xy 106.75366 -220.492783) (xy 106.723134 -220.534799) (xy 106.686411 -220.571522) (xy 106.644395 -220.602048)
			(xy 106.598121 -220.625626) (xy 106.548728 -220.641674) (xy 106.497433 -220.649799) (xy 106.445499 -220.649799)
			(xy 106.394204 -220.641674) (xy 106.344811 -220.625626) (xy 106.298537 -220.602048) (xy 106.256521 -220.571522)
			(xy 106.219798 -220.534799) (xy 106.189272 -220.492783) (xy 106.165694 -220.446509) (xy 106.149646 -220.397116)
			(xy 106.141521 -220.345821) (xy 105.861369 -220.345821) (xy 105.861332 -220.347764) (xy 105.852004 -220.402797)
			(xy 105.843324 -220.429328) (xy 105.83545 -220.451172) (xy 106.039666 -220.80474) (xy 106.062526 -220.809058)
			(xy 106.087444 -220.814243) (xy 106.135427 -220.831206) (xy 106.180245 -220.85532) (xy 106.220838 -220.886018)
			(xy 106.256247 -220.922574) (xy 106.285636 -220.964124) (xy 106.308311 -221.009687) (xy 106.323735 -221.058187)
			(xy 106.331546 -221.108477) (xy 106.33202 -221.133924) (xy 106.331511 -221.159891) (xy 106.323386 -221.211186)
			(xy 106.307338 -221.260579) (xy 106.28376 -221.306853) (xy 106.253234 -221.348869) (xy 106.216511 -221.385592)
			(xy 106.174495 -221.416118) (xy 106.128221 -221.439696) (xy 106.078828 -221.455744) (xy 106.027533 -221.463869)
			(xy 105.975599 -221.463869) (xy 105.924304 -221.455744) (xy 105.874911 -221.439696) (xy 105.828637 -221.416118)
			(xy 105.786621 -221.385592) (xy 105.749898 -221.348869) (xy 105.719372 -221.306853) (xy 105.695794 -221.260579)
			(xy 105.679746 -221.211186) (xy 105.671621 -221.159891) (xy 105.671112 -221.133924) (xy 105.67167 -221.105938)
			(xy 105.681116 -221.050771) (xy 105.689908 -221.024196) (xy 105.697528 -221.002098) (xy 105.49382 -220.649038)
			(xy 105.470706 -220.64472) (xy 105.44577 -220.63956) (xy 105.397747 -220.62263) (xy 105.352888 -220.598536)
			(xy 105.312255 -220.567848) (xy 105.276809 -220.531292) (xy 105.247389 -220.489732) (xy 105.224689 -220.444152)
			(xy 105.209249 -220.39563) (xy 105.201432 -220.345314) (xy 105.200958 -220.319854) (xy 104.92232 -220.319854)
			(xy 104.921811 -220.345821) (xy 104.913686 -220.397116) (xy 104.897638 -220.446509) (xy 104.87406 -220.492783)
			(xy 104.843534 -220.534799) (xy 104.806811 -220.571522) (xy 104.764795 -220.602048) (xy 104.718521 -220.625626)
			(xy 104.669128 -220.641674) (xy 104.617833 -220.649799) (xy 104.565899 -220.649799) (xy 104.514604 -220.641674)
			(xy 104.465211 -220.625626) (xy 104.418937 -220.602048) (xy 104.376921 -220.571522) (xy 104.340198 -220.534799)
			(xy 104.309672 -220.492783) (xy 104.286094 -220.446509) (xy 104.270046 -220.397116) (xy 104.261921 -220.345821)
			(xy 103.981738 -220.345821) (xy 103.974033 -220.395611) (xy 103.958623 -220.444126) (xy 103.935955 -220.489704)
			(xy 103.906563 -220.531265) (xy 103.871145 -220.567826) (xy 103.830538 -220.598523) (xy 103.785703 -220.622627)
			(xy 103.737702 -220.639569) (xy 103.712772 -220.64472) (xy 103.689912 -220.649038) (xy 103.486204 -221.002098)
			(xy 103.493824 -221.024196) (xy 103.502561 -221.050784) (xy 103.512009 -221.105943) (xy 103.51262 -221.133924)
			(xy 103.512111 -221.159891) (xy 103.792021 -221.159891) (xy 103.792021 -221.107957) (xy 103.800146 -221.056662)
			(xy 103.816194 -221.007269) (xy 103.839772 -220.960995) (xy 103.870298 -220.918979) (xy 103.907021 -220.882256)
			(xy 103.949037 -220.85173) (xy 103.995311 -220.828152) (xy 104.044704 -220.812104) (xy 104.095999 -220.803979)
			(xy 104.147933 -220.803979) (xy 104.199228 -220.812104) (xy 104.248621 -220.828152) (xy 104.294895 -220.85173)
			(xy 104.336911 -220.882256) (xy 104.373634 -220.918979) (xy 104.40416 -220.960995) (xy 104.427738 -221.007269)
			(xy 104.443786 -221.056662) (xy 104.451911 -221.107957) (xy 104.45242 -221.133924) (xy 104.451911 -221.159891)
			(xy 104.443786 -221.211186) (xy 104.427738 -221.260579) (xy 104.40416 -221.306853) (xy 104.373634 -221.348869)
			(xy 104.336911 -221.385592) (xy 104.294895 -221.416118) (xy 104.248621 -221.439696) (xy 104.199228 -221.455744)
			(xy 104.147933 -221.463869) (xy 104.095999 -221.463869) (xy 104.044704 -221.455744) (xy 103.995311 -221.439696)
			(xy 103.949037 -221.416118) (xy 103.907021 -221.385592) (xy 103.870298 -221.348869) (xy 103.839772 -221.306853)
			(xy 103.816194 -221.260579) (xy 103.800146 -221.211186) (xy 103.792021 -221.159891) (xy 103.512111 -221.159891)
			(xy 103.503986 -221.211186) (xy 103.487938 -221.260579) (xy 103.46436 -221.306853) (xy 103.433834 -221.348869)
			(xy 103.397111 -221.385592) (xy 103.355095 -221.416118) (xy 103.308821 -221.439696) (xy 103.259428 -221.455744)
			(xy 103.208133 -221.463869) (xy 103.156199 -221.463869) (xy 103.104904 -221.455744) (xy 103.055511 -221.439696)
			(xy 103.009237 -221.416118) (xy 102.967221 -221.385592) (xy 102.930498 -221.348869) (xy 102.899972 -221.306853)
			(xy 102.876394 -221.260579) (xy 102.860346 -221.211186) (xy 102.852221 -221.159891) (xy 102.851712 -221.133924)
			(xy 102.57282 -221.133924) (xy 102.572205 -221.161904) (xy 102.56275 -221.21706) (xy 102.554024 -221.243652)
			(xy 102.546404 -221.26575) (xy 102.750112 -221.618556) (xy 102.772972 -221.622874) (xy 102.797902 -221.628025)
			(xy 102.845904 -221.644967) (xy 102.890739 -221.669071) (xy 102.931347 -221.699767) (xy 102.966766 -221.736328)
			(xy 102.996158 -221.77789) (xy 103.018827 -221.823467) (xy 103.034237 -221.871983) (xy 103.042024 -221.922288)
			(xy 103.042466 -221.94774) (xy 103.041957 -221.973707) (xy 103.321867 -221.973707) (xy 103.321867 -221.921773)
			(xy 103.329992 -221.870478) (xy 103.34604 -221.821085) (xy 103.369618 -221.774811) (xy 103.400144 -221.732795)
			(xy 103.436867 -221.696072) (xy 103.478883 -221.665546) (xy 103.525157 -221.641968) (xy 103.57455 -221.62592)
			(xy 103.625845 -221.617795) (xy 103.677779 -221.617795) (xy 103.729074 -221.62592) (xy 103.778467 -221.641968)
			(xy 103.824741 -221.665546) (xy 103.866757 -221.696072) (xy 103.90348 -221.732795) (xy 103.934006 -221.774811)
			(xy 103.957584 -221.821085) (xy 103.973632 -221.870478) (xy 103.981757 -221.921773) (xy 103.982266 -221.94774)
			(xy 104.261158 -221.94774) (xy 104.261581 -221.922287) (xy 104.269368 -221.87198) (xy 104.28478 -221.823463)
			(xy 104.307451 -221.777884) (xy 104.336845 -221.736322) (xy 104.372267 -221.699761) (xy 104.412878 -221.669066)
			(xy 104.457716 -221.644963) (xy 104.505721 -221.628023) (xy 104.530652 -221.622874) (xy 104.553512 -221.618556)
			(xy 104.757474 -221.264988) (xy 104.749854 -221.243144) (xy 104.741221 -221.216666) (xy 104.731893 -221.161767)
			(xy 104.731312 -221.133924) (xy 104.731821 -221.107957) (xy 104.739946 -221.056662) (xy 104.755994 -221.007269)
			(xy 104.779572 -220.960995) (xy 104.810098 -220.918979) (xy 104.846821 -220.882256) (xy 104.888837 -220.85173)
			(xy 104.935111 -220.828152) (xy 104.984504 -220.812104) (xy 105.035799 -220.803979) (xy 105.087733 -220.803979)
			(xy 105.139028 -220.812104) (xy 105.188421 -220.828152) (xy 105.234695 -220.85173) (xy 105.276711 -220.882256)
			(xy 105.313434 -220.918979) (xy 105.34396 -220.960995) (xy 105.367538 -221.007269) (xy 105.383586 -221.056662)
			(xy 105.391711 -221.107957) (xy 105.39222 -221.133924) (xy 105.391787 -221.159399) (xy 105.383963 -221.209746)
			(xy 105.368505 -221.258295) (xy 105.345778 -221.303896) (xy 105.316321 -221.345468) (xy 105.280832 -221.382027)
			(xy 105.240153 -221.412705) (xy 105.195246 -221.436776) (xy 105.147178 -221.453669) (xy 105.122218 -221.45879)
			(xy 105.099104 -221.463108) (xy 104.89565 -221.815914) (xy 104.90327 -221.838012) (xy 104.91201 -221.8646)
			(xy 104.921456 -221.919759) (xy 104.922066 -221.94774) (xy 104.921557 -221.973707) (xy 105.201467 -221.973707)
			(xy 105.201467 -221.921773) (xy 105.209592 -221.870478) (xy 105.22564 -221.821085) (xy 105.249218 -221.774811)
			(xy 105.279744 -221.732795) (xy 105.316467 -221.696072) (xy 105.358483 -221.665546) (xy 105.404757 -221.641968)
			(xy 105.45415 -221.62592) (xy 105.505445 -221.617795) (xy 105.557379 -221.617795) (xy 105.608674 -221.62592)
			(xy 105.658067 -221.641968) (xy 105.704341 -221.665546) (xy 105.746357 -221.696072) (xy 105.78308 -221.732795)
			(xy 105.813606 -221.774811) (xy 105.837184 -221.821085) (xy 105.853232 -221.870478) (xy 105.861357 -221.921773)
			(xy 105.861866 -221.94774) (xy 106.140758 -221.94774) (xy 106.141181 -221.922287) (xy 106.148968 -221.87198)
			(xy 106.16438 -221.823463) (xy 106.187051 -221.777884) (xy 106.216445 -221.736322) (xy 106.251867 -221.699761)
			(xy 106.292478 -221.669066) (xy 106.337316 -221.644963) (xy 106.385321 -221.628023) (xy 106.410252 -221.622874)
			(xy 106.433112 -221.618556) (xy 106.637074 -221.264988) (xy 106.629454 -221.243144) (xy 106.620821 -221.216666)
			(xy 106.611493 -221.161767) (xy 106.610912 -221.133924) (xy 106.611421 -221.107957) (xy 106.619546 -221.056662)
			(xy 106.635594 -221.007269) (xy 106.659172 -220.960995) (xy 106.689698 -220.918979) (xy 106.726421 -220.882256)
			(xy 106.768437 -220.85173) (xy 106.814711 -220.828152) (xy 106.864104 -220.812104) (xy 106.915399 -220.803979)
			(xy 106.967333 -220.803979) (xy 107.018628 -220.812104) (xy 107.068021 -220.828152) (xy 107.114295 -220.85173)
			(xy 107.156311 -220.882256) (xy 107.193034 -220.918979) (xy 107.22356 -220.960995) (xy 107.247138 -221.007269)
			(xy 107.263186 -221.056662) (xy 107.271311 -221.107957) (xy 107.27182 -221.133924) (xy 107.271387 -221.159399)
			(xy 107.263563 -221.209746) (xy 107.248105 -221.258295) (xy 107.225378 -221.303896) (xy 107.195921 -221.345468)
			(xy 107.160432 -221.382027) (xy 107.119753 -221.412705) (xy 107.074846 -221.436776) (xy 107.026778 -221.453669)
			(xy 107.001818 -221.45879) (xy 106.978704 -221.463108) (xy 106.77525 -221.815914) (xy 106.78287 -221.838012)
			(xy 106.79161 -221.8646) (xy 106.801056 -221.919759) (xy 106.801666 -221.94774) (xy 106.801157 -221.973707)
			(xy 107.081067 -221.973707) (xy 107.081067 -221.921773) (xy 107.089192 -221.870478) (xy 107.10524 -221.821085)
			(xy 107.128818 -221.774811) (xy 107.159344 -221.732795) (xy 107.196067 -221.696072) (xy 107.238083 -221.665546)
			(xy 107.284357 -221.641968) (xy 107.33375 -221.62592) (xy 107.385045 -221.617795) (xy 107.436979 -221.617795)
			(xy 107.488274 -221.62592) (xy 107.537667 -221.641968) (xy 107.583941 -221.665546) (xy 107.625957 -221.696072)
			(xy 107.66268 -221.732795) (xy 107.693206 -221.774811) (xy 107.716784 -221.821085) (xy 107.732832 -221.870478)
			(xy 107.740957 -221.921773) (xy 107.741466 -221.94774) (xy 108.020358 -221.94774) (xy 108.020781 -221.922287)
			(xy 108.028568 -221.87198) (xy 108.04398 -221.823463) (xy 108.066651 -221.777884) (xy 108.096045 -221.736322)
			(xy 108.131467 -221.699761) (xy 108.172078 -221.669066) (xy 108.216916 -221.644963) (xy 108.264921 -221.628023)
			(xy 108.289852 -221.622874) (xy 108.312712 -221.618556) (xy 108.516674 -221.264988) (xy 108.509054 -221.243144)
			(xy 108.500421 -221.216666) (xy 108.491093 -221.161767) (xy 108.490512 -221.133924) (xy 108.491021 -221.107957)
			(xy 108.499146 -221.056662) (xy 108.515194 -221.007269) (xy 108.538772 -220.960995) (xy 108.569298 -220.918979)
			(xy 108.606021 -220.882256) (xy 108.648037 -220.85173) (xy 108.694311 -220.828152) (xy 108.743704 -220.812104)
			(xy 108.794999 -220.803979) (xy 108.846933 -220.803979) (xy 108.898228 -220.812104) (xy 108.947621 -220.828152)
			(xy 108.993895 -220.85173) (xy 109.035911 -220.882256) (xy 109.072634 -220.918979) (xy 109.10316 -220.960995)
			(xy 109.126738 -221.007269) (xy 109.142786 -221.056662) (xy 109.150911 -221.107957) (xy 109.15142 -221.133924)
			(xy 109.150987 -221.159399) (xy 109.143163 -221.209746) (xy 109.127705 -221.258295) (xy 109.104978 -221.303896)
			(xy 109.075521 -221.345468) (xy 109.040032 -221.382027) (xy 108.999353 -221.412705) (xy 108.954446 -221.436776)
			(xy 108.906378 -221.453669) (xy 108.881418 -221.45879) (xy 108.858304 -221.463108) (xy 108.65485 -221.815914)
			(xy 108.66247 -221.838012) (xy 108.67121 -221.8646) (xy 108.680656 -221.919759) (xy 108.681266 -221.94774)
			(xy 108.680757 -221.973707) (xy 108.960667 -221.973707) (xy 108.960667 -221.921773) (xy 108.968792 -221.870478)
			(xy 108.98484 -221.821085) (xy 109.008418 -221.774811) (xy 109.038944 -221.732795) (xy 109.075667 -221.696072)
			(xy 109.117683 -221.665546) (xy 109.163957 -221.641968) (xy 109.21335 -221.62592) (xy 109.264645 -221.617795)
			(xy 109.316579 -221.617795) (xy 109.367874 -221.62592) (xy 109.417267 -221.641968) (xy 109.463541 -221.665546)
			(xy 109.505557 -221.696072) (xy 109.54228 -221.732795) (xy 109.572806 -221.774811) (xy 109.596384 -221.821085)
			(xy 109.612432 -221.870478) (xy 109.620557 -221.921773) (xy 109.621066 -221.94774) (xy 109.900212 -221.94774)
			(xy 109.900672 -221.922289) (xy 109.908458 -221.871985) (xy 109.923867 -221.823471) (xy 109.946535 -221.777895)
			(xy 109.975924 -221.736334) (xy 110.011341 -221.699773) (xy 110.051946 -221.669076) (xy 110.096778 -221.64497)
			(xy 110.144777 -221.628026) (xy 110.169706 -221.622874) (xy 110.192566 -221.618556) (xy 110.396528 -221.265242)
			(xy 110.388654 -221.243398) (xy 110.379991 -221.216863) (xy 110.370672 -221.161832) (xy 110.370112 -221.133924)
			(xy 110.370621 -221.107957) (xy 110.378746 -221.056662) (xy 110.394794 -221.007269) (xy 110.418372 -220.960995)
			(xy 110.448898 -220.918979) (xy 110.485621 -220.882256) (xy 110.527637 -220.85173) (xy 110.573911 -220.828152)
			(xy 110.623304 -220.812104) (xy 110.674599 -220.803979) (xy 110.726533 -220.803979) (xy 110.777828 -220.812104)
			(xy 110.827221 -220.828152) (xy 110.873495 -220.85173) (xy 110.915511 -220.882256) (xy 110.952234 -220.918979)
			(xy 110.98276 -220.960995) (xy 111.006338 -221.007269) (xy 111.022386 -221.056662) (xy 111.030511 -221.107957)
			(xy 111.03102 -221.133924) (xy 111.030544 -221.159386) (xy 111.022742 -221.209709) (xy 111.007312 -221.258239)
			(xy 110.984618 -221.303827) (xy 110.955199 -221.345393) (xy 110.91975 -221.381953) (xy 110.879111 -221.412642)
			(xy 110.834246 -221.436732) (xy 110.786215 -221.453652) (xy 110.761272 -221.45879) (xy 110.738158 -221.463108)
			(xy 110.534704 -221.815914) (xy 110.542324 -221.838012) (xy 110.551065 -221.864599) (xy 110.56051 -221.919759)
			(xy 110.56112 -221.94774) (xy 110.560611 -221.973707) (xy 110.840521 -221.973707) (xy 110.840521 -221.921773)
			(xy 110.848646 -221.870478) (xy 110.864694 -221.821085) (xy 110.888272 -221.774811) (xy 110.918798 -221.732795)
			(xy 110.955521 -221.696072) (xy 110.997537 -221.665546) (xy 111.043811 -221.641968) (xy 111.093204 -221.62592)
			(xy 111.144499 -221.617795) (xy 111.196433 -221.617795) (xy 111.247728 -221.62592) (xy 111.297121 -221.641968)
			(xy 111.343395 -221.665546) (xy 111.385411 -221.696072) (xy 111.422134 -221.732795) (xy 111.45266 -221.774811)
			(xy 111.476238 -221.821085) (xy 111.492286 -221.870478) (xy 111.500411 -221.921773) (xy 111.50092 -221.94774)
			(xy 111.779558 -221.94774) (xy 111.779981 -221.922287) (xy 111.787768 -221.87198) (xy 111.80318 -221.823463)
			(xy 111.825851 -221.777884) (xy 111.855245 -221.736322) (xy 111.890667 -221.699761) (xy 111.931278 -221.669066)
			(xy 111.976116 -221.644963) (xy 112.024121 -221.628023) (xy 112.049052 -221.622874) (xy 112.071912 -221.618556)
			(xy 112.275874 -221.264988) (xy 112.268254 -221.243144) (xy 112.259621 -221.216666) (xy 112.250293 -221.161767)
			(xy 112.249712 -221.133924) (xy 112.250221 -221.107957) (xy 112.258346 -221.056662) (xy 112.274394 -221.007269)
			(xy 112.297972 -220.960995) (xy 112.328498 -220.918979) (xy 112.365221 -220.882256) (xy 112.407237 -220.85173)
			(xy 112.453511 -220.828152) (xy 112.502904 -220.812104) (xy 112.554199 -220.803979) (xy 112.606133 -220.803979)
			(xy 112.657428 -220.812104) (xy 112.706821 -220.828152) (xy 112.753095 -220.85173) (xy 112.795111 -220.882256)
			(xy 112.831834 -220.918979) (xy 112.86236 -220.960995) (xy 112.885938 -221.007269) (xy 112.901986 -221.056662)
			(xy 112.910111 -221.107957) (xy 112.91062 -221.133924) (xy 112.910187 -221.159399) (xy 112.902363 -221.209746)
			(xy 112.886905 -221.258295) (xy 112.864178 -221.303896) (xy 112.834721 -221.345468) (xy 112.799232 -221.382027)
			(xy 112.758553 -221.412705) (xy 112.713646 -221.436776) (xy 112.665578 -221.453669) (xy 112.640618 -221.45879)
			(xy 112.617504 -221.463108) (xy 112.41405 -221.815914) (xy 112.42167 -221.838012) (xy 112.43041 -221.8646)
			(xy 112.439856 -221.919759) (xy 112.440466 -221.94774) (xy 112.439957 -221.973707) (xy 112.719867 -221.973707)
			(xy 112.719867 -221.921773) (xy 112.727992 -221.870478) (xy 112.74404 -221.821085) (xy 112.767618 -221.774811)
			(xy 112.798144 -221.732795) (xy 112.834867 -221.696072) (xy 112.876883 -221.665546) (xy 112.923157 -221.641968)
			(xy 112.97255 -221.62592) (xy 113.023845 -221.617795) (xy 113.075779 -221.617795) (xy 113.127074 -221.62592)
			(xy 113.176467 -221.641968) (xy 113.222741 -221.665546) (xy 113.264757 -221.696072) (xy 113.30148 -221.732795)
			(xy 113.332006 -221.774811) (xy 113.355584 -221.821085) (xy 113.371632 -221.870478) (xy 113.379757 -221.921773)
			(xy 113.380266 -221.94774) (xy 113.659412 -221.94774) (xy 113.659872 -221.922289) (xy 113.667658 -221.871985)
			(xy 113.683067 -221.823471) (xy 113.705735 -221.777895) (xy 113.735124 -221.736334) (xy 113.770541 -221.699773)
			(xy 113.811146 -221.669076) (xy 113.855978 -221.64497) (xy 113.903977 -221.628026) (xy 113.928906 -221.622874)
			(xy 113.951766 -221.618556) (xy 114.155728 -221.265242) (xy 114.147854 -221.243398) (xy 114.139191 -221.216863)
			(xy 114.129872 -221.161832) (xy 114.129312 -221.133924) (xy 114.129821 -221.107957) (xy 114.137946 -221.056662)
			(xy 114.153994 -221.007269) (xy 114.177572 -220.960995) (xy 114.208098 -220.918979) (xy 114.244821 -220.882256)
			(xy 114.286837 -220.85173) (xy 114.333111 -220.828152) (xy 114.382504 -220.812104) (xy 114.433799 -220.803979)
			(xy 114.485733 -220.803979) (xy 114.537028 -220.812104) (xy 114.586421 -220.828152) (xy 114.632695 -220.85173)
			(xy 114.674711 -220.882256) (xy 114.711434 -220.918979) (xy 114.74196 -220.960995) (xy 114.765538 -221.007269)
			(xy 114.781586 -221.056662) (xy 114.789711 -221.107957) (xy 114.79022 -221.133924) (xy 114.789744 -221.159386)
			(xy 114.781942 -221.209709) (xy 114.766512 -221.258239) (xy 114.743818 -221.303827) (xy 114.714399 -221.345393)
			(xy 114.67895 -221.381953) (xy 114.638311 -221.412642) (xy 114.593446 -221.436732) (xy 114.545415 -221.453652)
			(xy 114.520472 -221.45879) (xy 114.497358 -221.463108) (xy 114.293904 -221.815914) (xy 114.301524 -221.838012)
			(xy 114.310265 -221.864599) (xy 114.31971 -221.919759) (xy 114.32032 -221.94774) (xy 114.319811 -221.973707)
			(xy 114.599721 -221.973707) (xy 114.599721 -221.921773) (xy 114.607846 -221.870478) (xy 114.623894 -221.821085)
			(xy 114.647472 -221.774811) (xy 114.677998 -221.732795) (xy 114.714721 -221.696072) (xy 114.756737 -221.665546)
			(xy 114.803011 -221.641968) (xy 114.852404 -221.62592) (xy 114.903699 -221.617795) (xy 114.955633 -221.617795)
			(xy 115.006928 -221.62592) (xy 115.056321 -221.641968) (xy 115.102595 -221.665546) (xy 115.144611 -221.696072)
			(xy 115.181334 -221.732795) (xy 115.21186 -221.774811) (xy 115.235438 -221.821085) (xy 115.251486 -221.870478)
			(xy 115.259611 -221.921773) (xy 115.26012 -221.94774) (xy 115.538758 -221.94774) (xy 115.539181 -221.922287)
			(xy 115.546968 -221.87198) (xy 115.56238 -221.823463) (xy 115.585051 -221.777884) (xy 115.614445 -221.736322)
			(xy 115.649867 -221.699761) (xy 115.690478 -221.669066) (xy 115.735316 -221.644963) (xy 115.783321 -221.628023)
			(xy 115.808252 -221.622874) (xy 115.831112 -221.618556) (xy 116.035074 -221.264988) (xy 116.027454 -221.243144)
			(xy 116.018821 -221.216666) (xy 116.009493 -221.161767) (xy 116.008912 -221.133924) (xy 116.009421 -221.107957)
			(xy 116.017546 -221.056662) (xy 116.033594 -221.007269) (xy 116.057172 -220.960995) (xy 116.087698 -220.918979)
			(xy 116.124421 -220.882256) (xy 116.166437 -220.85173) (xy 116.212711 -220.828152) (xy 116.262104 -220.812104)
			(xy 116.313399 -220.803979) (xy 116.365333 -220.803979) (xy 116.416628 -220.812104) (xy 116.466021 -220.828152)
			(xy 116.512295 -220.85173) (xy 116.554311 -220.882256) (xy 116.591034 -220.918979) (xy 116.62156 -220.960995)
			(xy 116.645138 -221.007269) (xy 116.661186 -221.056662) (xy 116.669311 -221.107957) (xy 116.66982 -221.133924)
			(xy 116.669387 -221.159399) (xy 116.661563 -221.209746) (xy 116.646105 -221.258295) (xy 116.623378 -221.303896)
			(xy 116.593921 -221.345468) (xy 116.558432 -221.382027) (xy 116.517753 -221.412705) (xy 116.472846 -221.436776)
			(xy 116.424778 -221.453669) (xy 116.399818 -221.45879) (xy 116.376704 -221.463108) (xy 116.17325 -221.815914)
			(xy 116.18087 -221.838012) (xy 116.18961 -221.8646) (xy 116.199056 -221.919759) (xy 116.199666 -221.94774)
			(xy 117.418358 -221.94774) (xy 117.418781 -221.922287) (xy 117.426568 -221.87198) (xy 117.44198 -221.823463)
			(xy 117.464651 -221.777884) (xy 117.494045 -221.736322) (xy 117.529467 -221.699761) (xy 117.570078 -221.669066)
			(xy 117.614916 -221.644963) (xy 117.662921 -221.628023) (xy 117.687852 -221.622874) (xy 117.710712 -221.618556)
			(xy 117.914674 -221.264988) (xy 117.907054 -221.243144) (xy 117.898421 -221.216666) (xy 117.889093 -221.161767)
			(xy 117.888512 -221.133924) (xy 117.889021 -221.107957) (xy 117.897146 -221.056662) (xy 117.913194 -221.007269)
			(xy 117.936772 -220.960995) (xy 117.967298 -220.918979) (xy 118.004021 -220.882256) (xy 118.046037 -220.85173)
			(xy 118.092311 -220.828152) (xy 118.141704 -220.812104) (xy 118.192999 -220.803979) (xy 118.244933 -220.803979)
			(xy 118.296228 -220.812104) (xy 118.345621 -220.828152) (xy 118.391895 -220.85173) (xy 118.433911 -220.882256)
			(xy 118.470634 -220.918979) (xy 118.50116 -220.960995) (xy 118.524738 -221.007269) (xy 118.540786 -221.056662)
			(xy 118.548911 -221.107957) (xy 118.54942 -221.133924) (xy 118.548987 -221.159399) (xy 118.541163 -221.209746)
			(xy 118.525705 -221.258295) (xy 118.502978 -221.303896) (xy 118.473521 -221.345468) (xy 118.438032 -221.382027)
			(xy 118.397353 -221.412705) (xy 118.352446 -221.436776) (xy 118.304378 -221.453669) (xy 118.279418 -221.45879)
			(xy 118.256304 -221.463108) (xy 118.05285 -221.815914) (xy 118.06047 -221.838012) (xy 118.06921 -221.8646)
			(xy 118.078656 -221.919759) (xy 118.079266 -221.94774) (xy 118.078757 -221.973707) (xy 119.298721 -221.973707)
			(xy 119.298721 -221.921773) (xy 119.306846 -221.870478) (xy 119.322894 -221.821085) (xy 119.346472 -221.774811)
			(xy 119.376998 -221.732795) (xy 119.413721 -221.696072) (xy 119.455737 -221.665546) (xy 119.502011 -221.641968)
			(xy 119.551404 -221.62592) (xy 119.602699 -221.617795) (xy 119.654633 -221.617795) (xy 119.705928 -221.62592)
			(xy 119.755321 -221.641968) (xy 119.801595 -221.665546) (xy 119.843611 -221.696072) (xy 119.880334 -221.732795)
			(xy 119.91086 -221.774811) (xy 119.934438 -221.821085) (xy 119.950486 -221.870478) (xy 119.958611 -221.921773)
			(xy 119.95912 -221.94774) (xy 121.177558 -221.94774) (xy 121.177981 -221.922287) (xy 121.185768 -221.87198)
			(xy 121.20118 -221.823463) (xy 121.223851 -221.777884) (xy 121.253245 -221.736322) (xy 121.288667 -221.699761)
			(xy 121.329278 -221.669066) (xy 121.374116 -221.644963) (xy 121.422121 -221.628023) (xy 121.447052 -221.622874)
			(xy 121.469912 -221.618556) (xy 121.673874 -221.264988) (xy 121.666254 -221.243144) (xy 121.657621 -221.216666)
			(xy 121.648293 -221.161767) (xy 121.647712 -221.133924) (xy 121.648221 -221.107957) (xy 121.656346 -221.056662)
			(xy 121.672394 -221.007269) (xy 121.695972 -220.960995) (xy 121.726498 -220.918979) (xy 121.763221 -220.882256)
			(xy 121.805237 -220.85173) (xy 121.851511 -220.828152) (xy 121.900904 -220.812104) (xy 121.952199 -220.803979)
			(xy 122.004133 -220.803979) (xy 122.055428 -220.812104) (xy 122.104821 -220.828152) (xy 122.151095 -220.85173)
			(xy 122.193111 -220.882256) (xy 122.229834 -220.918979) (xy 122.26036 -220.960995) (xy 122.283938 -221.007269)
			(xy 122.299986 -221.056662) (xy 122.308111 -221.107957) (xy 122.30862 -221.133924) (xy 122.308187 -221.159399)
			(xy 122.300363 -221.209746) (xy 122.284905 -221.258295) (xy 122.262178 -221.303896) (xy 122.232721 -221.345468)
			(xy 122.197232 -221.382027) (xy 122.156553 -221.412705) (xy 122.111646 -221.436776) (xy 122.063578 -221.453669)
			(xy 122.038618 -221.45879) (xy 122.015504 -221.463108) (xy 121.81205 -221.815914) (xy 121.81967 -221.838012)
			(xy 121.82841 -221.8646) (xy 121.837856 -221.919759) (xy 121.838466 -221.94774) (xy 123.057158 -221.94774)
			(xy 123.057581 -221.922287) (xy 123.065368 -221.87198) (xy 123.08078 -221.823463) (xy 123.103451 -221.777884)
			(xy 123.132845 -221.736322) (xy 123.168267 -221.699761) (xy 123.208878 -221.669066) (xy 123.253716 -221.644963)
			(xy 123.301721 -221.628023) (xy 123.326652 -221.622874) (xy 123.349512 -221.618556) (xy 123.553474 -221.264988)
			(xy 123.545854 -221.243144) (xy 123.537221 -221.216666) (xy 123.527893 -221.161767) (xy 123.527312 -221.133924)
			(xy 123.527821 -221.107957) (xy 123.535946 -221.056662) (xy 123.551994 -221.007269) (xy 123.575572 -220.960995)
			(xy 123.606098 -220.918979) (xy 123.642821 -220.882256) (xy 123.684837 -220.85173) (xy 123.731111 -220.828152)
			(xy 123.780504 -220.812104) (xy 123.831799 -220.803979) (xy 123.883733 -220.803979) (xy 123.935028 -220.812104)
			(xy 123.984421 -220.828152) (xy 124.030695 -220.85173) (xy 124.072711 -220.882256) (xy 124.109434 -220.918979)
			(xy 124.13996 -220.960995) (xy 124.163538 -221.007269) (xy 124.179586 -221.056662) (xy 124.187711 -221.107957)
			(xy 124.18822 -221.133924) (xy 124.187787 -221.159399) (xy 124.179963 -221.209746) (xy 124.164505 -221.258295)
			(xy 124.141778 -221.303896) (xy 124.112321 -221.345468) (xy 124.076832 -221.382027) (xy 124.036153 -221.412705)
			(xy 123.991246 -221.436776) (xy 123.943178 -221.453669) (xy 123.918218 -221.45879) (xy 123.895104 -221.463108)
			(xy 123.69165 -221.815914) (xy 123.69927 -221.838012) (xy 123.70801 -221.8646) (xy 123.717456 -221.919759)
			(xy 123.718066 -221.94774) (xy 124.936758 -221.94774) (xy 124.937181 -221.922287) (xy 124.944968 -221.87198)
			(xy 124.96038 -221.823463) (xy 124.983051 -221.777884) (xy 125.012445 -221.736322) (xy 125.047867 -221.699761)
			(xy 125.088478 -221.669066) (xy 125.133316 -221.644963) (xy 125.181321 -221.628023) (xy 125.206252 -221.622874)
			(xy 125.229112 -221.618556) (xy 125.433074 -221.264988) (xy 125.425454 -221.243144) (xy 125.416821 -221.216666)
			(xy 125.407493 -221.161767) (xy 125.406912 -221.133924) (xy 125.407421 -221.107957) (xy 125.415546 -221.056662)
			(xy 125.431594 -221.007269) (xy 125.455172 -220.960995) (xy 125.485698 -220.918979) (xy 125.522421 -220.882256)
			(xy 125.564437 -220.85173) (xy 125.610711 -220.828152) (xy 125.660104 -220.812104) (xy 125.711399 -220.803979)
			(xy 125.763333 -220.803979) (xy 125.814628 -220.812104) (xy 125.864021 -220.828152) (xy 125.910295 -220.85173)
			(xy 125.952311 -220.882256) (xy 125.989034 -220.918979) (xy 126.01956 -220.960995) (xy 126.043138 -221.007269)
			(xy 126.059186 -221.056662) (xy 126.067311 -221.107957) (xy 126.06782 -221.133924) (xy 126.067387 -221.159399)
			(xy 126.059563 -221.209746) (xy 126.044105 -221.258295) (xy 126.021378 -221.303896) (xy 125.991921 -221.345468)
			(xy 125.956432 -221.382027) (xy 125.915753 -221.412705) (xy 125.870846 -221.436776) (xy 125.822778 -221.453669)
			(xy 125.797818 -221.45879) (xy 125.774704 -221.463108) (xy 125.57125 -221.815914) (xy 125.57887 -221.838012)
			(xy 125.58761 -221.8646) (xy 125.597056 -221.919759) (xy 125.597666 -221.94774) (xy 125.597157 -221.973707)
			(xy 125.589032 -222.025002) (xy 125.572984 -222.074395) (xy 125.549406 -222.120669) (xy 125.51888 -222.162685)
			(xy 125.482157 -222.199408) (xy 125.440141 -222.229934) (xy 125.393867 -222.253512) (xy 125.344474 -222.26956)
			(xy 125.293179 -222.277685) (xy 125.241245 -222.277685) (xy 125.18995 -222.26956) (xy 125.140557 -222.253512)
			(xy 125.094283 -222.229934) (xy 125.052267 -222.199408) (xy 125.015544 -222.162685) (xy 124.985018 -222.120669)
			(xy 124.96144 -222.074395) (xy 124.945392 -222.025002) (xy 124.937267 -221.973707) (xy 124.936758 -221.94774)
			(xy 123.718066 -221.94774) (xy 123.717557 -221.973707) (xy 123.709432 -222.025002) (xy 123.693384 -222.074395)
			(xy 123.669806 -222.120669) (xy 123.63928 -222.162685) (xy 123.602557 -222.199408) (xy 123.560541 -222.229934)
			(xy 123.514267 -222.253512) (xy 123.464874 -222.26956) (xy 123.413579 -222.277685) (xy 123.361645 -222.277685)
			(xy 123.31035 -222.26956) (xy 123.260957 -222.253512) (xy 123.214683 -222.229934) (xy 123.172667 -222.199408)
			(xy 123.135944 -222.162685) (xy 123.105418 -222.120669) (xy 123.08184 -222.074395) (xy 123.065792 -222.025002)
			(xy 123.057667 -221.973707) (xy 123.057158 -221.94774) (xy 121.838466 -221.94774) (xy 121.837957 -221.973707)
			(xy 121.829832 -222.025002) (xy 121.813784 -222.074395) (xy 121.790206 -222.120669) (xy 121.75968 -222.162685)
			(xy 121.722957 -222.199408) (xy 121.680941 -222.229934) (xy 121.634667 -222.253512) (xy 121.585274 -222.26956)
			(xy 121.533979 -222.277685) (xy 121.482045 -222.277685) (xy 121.43075 -222.26956) (xy 121.381357 -222.253512)
			(xy 121.335083 -222.229934) (xy 121.293067 -222.199408) (xy 121.256344 -222.162685) (xy 121.225818 -222.120669)
			(xy 121.20224 -222.074395) (xy 121.186192 -222.025002) (xy 121.178067 -221.973707) (xy 121.177558 -221.94774)
			(xy 119.95912 -221.94774) (xy 119.958611 -221.973707) (xy 119.950486 -222.025002) (xy 119.934438 -222.074395)
			(xy 119.91086 -222.120669) (xy 119.880334 -222.162685) (xy 119.843611 -222.199408) (xy 119.801595 -222.229934)
			(xy 119.755321 -222.253512) (xy 119.705928 -222.26956) (xy 119.654633 -222.277685) (xy 119.602699 -222.277685)
			(xy 119.551404 -222.26956) (xy 119.502011 -222.253512) (xy 119.455737 -222.229934) (xy 119.413721 -222.199408)
			(xy 119.376998 -222.162685) (xy 119.346472 -222.120669) (xy 119.322894 -222.074395) (xy 119.306846 -222.025002)
			(xy 119.298721 -221.973707) (xy 118.078757 -221.973707) (xy 118.070632 -222.025002) (xy 118.054584 -222.074395)
			(xy 118.031006 -222.120669) (xy 118.00048 -222.162685) (xy 117.963757 -222.199408) (xy 117.921741 -222.229934)
			(xy 117.875467 -222.253512) (xy 117.826074 -222.26956) (xy 117.774779 -222.277685) (xy 117.722845 -222.277685)
			(xy 117.67155 -222.26956) (xy 117.622157 -222.253512) (xy 117.575883 -222.229934) (xy 117.533867 -222.199408)
			(xy 117.497144 -222.162685) (xy 117.466618 -222.120669) (xy 117.44304 -222.074395) (xy 117.426992 -222.025002)
			(xy 117.418867 -221.973707) (xy 117.418358 -221.94774) (xy 116.199666 -221.94774) (xy 116.199157 -221.973707)
			(xy 116.191032 -222.025002) (xy 116.174984 -222.074395) (xy 116.151406 -222.120669) (xy 116.12088 -222.162685)
			(xy 116.084157 -222.199408) (xy 116.042141 -222.229934) (xy 115.995867 -222.253512) (xy 115.946474 -222.26956)
			(xy 115.895179 -222.277685) (xy 115.843245 -222.277685) (xy 115.79195 -222.26956) (xy 115.742557 -222.253512)
			(xy 115.696283 -222.229934) (xy 115.654267 -222.199408) (xy 115.617544 -222.162685) (xy 115.587018 -222.120669)
			(xy 115.56344 -222.074395) (xy 115.547392 -222.025002) (xy 115.539267 -221.973707) (xy 115.538758 -221.94774)
			(xy 115.26012 -221.94774) (xy 115.259611 -221.973707) (xy 115.251486 -222.025002) (xy 115.235438 -222.074395)
			(xy 115.21186 -222.120669) (xy 115.181334 -222.162685) (xy 115.144611 -222.199408) (xy 115.102595 -222.229934)
			(xy 115.056321 -222.253512) (xy 115.006928 -222.26956) (xy 114.955633 -222.277685) (xy 114.903699 -222.277685)
			(xy 114.852404 -222.26956) (xy 114.803011 -222.253512) (xy 114.756737 -222.229934) (xy 114.714721 -222.199408)
			(xy 114.677998 -222.162685) (xy 114.647472 -222.120669) (xy 114.623894 -222.074395) (xy 114.607846 -222.025002)
			(xy 114.599721 -221.973707) (xy 114.319811 -221.973707) (xy 114.311686 -222.025002) (xy 114.295638 -222.074395)
			(xy 114.27206 -222.120669) (xy 114.241534 -222.162685) (xy 114.204811 -222.199408) (xy 114.162795 -222.229934)
			(xy 114.116521 -222.253512) (xy 114.067128 -222.26956) (xy 114.015833 -222.277685) (xy 113.963899 -222.277685)
			(xy 113.912604 -222.26956) (xy 113.863211 -222.253512) (xy 113.816937 -222.229934) (xy 113.774921 -222.199408)
			(xy 113.738198 -222.162685) (xy 113.707672 -222.120669) (xy 113.684094 -222.074395) (xy 113.668046 -222.025002)
			(xy 113.659921 -221.973707) (xy 113.659412 -221.94774) (xy 113.380266 -221.94774) (xy 113.379757 -221.973707)
			(xy 113.371632 -222.025002) (xy 113.355584 -222.074395) (xy 113.332006 -222.120669) (xy 113.30148 -222.162685)
			(xy 113.264757 -222.199408) (xy 113.222741 -222.229934) (xy 113.176467 -222.253512) (xy 113.127074 -222.26956)
			(xy 113.075779 -222.277685) (xy 113.023845 -222.277685) (xy 112.97255 -222.26956) (xy 112.923157 -222.253512)
			(xy 112.876883 -222.229934) (xy 112.834867 -222.199408) (xy 112.798144 -222.162685) (xy 112.767618 -222.120669)
			(xy 112.74404 -222.074395) (xy 112.727992 -222.025002) (xy 112.719867 -221.973707) (xy 112.439957 -221.973707)
			(xy 112.431832 -222.025002) (xy 112.415784 -222.074395) (xy 112.392206 -222.120669) (xy 112.36168 -222.162685)
			(xy 112.324957 -222.199408) (xy 112.282941 -222.229934) (xy 112.236667 -222.253512) (xy 112.187274 -222.26956)
			(xy 112.135979 -222.277685) (xy 112.084045 -222.277685) (xy 112.03275 -222.26956) (xy 111.983357 -222.253512)
			(xy 111.937083 -222.229934) (xy 111.895067 -222.199408) (xy 111.858344 -222.162685) (xy 111.827818 -222.120669)
			(xy 111.80424 -222.074395) (xy 111.788192 -222.025002) (xy 111.780067 -221.973707) (xy 111.779558 -221.94774)
			(xy 111.50092 -221.94774) (xy 111.500411 -221.973707) (xy 111.492286 -222.025002) (xy 111.476238 -222.074395)
			(xy 111.45266 -222.120669) (xy 111.422134 -222.162685) (xy 111.385411 -222.199408) (xy 111.343395 -222.229934)
			(xy 111.297121 -222.253512) (xy 111.247728 -222.26956) (xy 111.196433 -222.277685) (xy 111.144499 -222.277685)
			(xy 111.093204 -222.26956) (xy 111.043811 -222.253512) (xy 110.997537 -222.229934) (xy 110.955521 -222.199408)
			(xy 110.918798 -222.162685) (xy 110.888272 -222.120669) (xy 110.864694 -222.074395) (xy 110.848646 -222.025002)
			(xy 110.840521 -221.973707) (xy 110.560611 -221.973707) (xy 110.552486 -222.025002) (xy 110.536438 -222.074395)
			(xy 110.51286 -222.120669) (xy 110.482334 -222.162685) (xy 110.445611 -222.199408) (xy 110.403595 -222.229934)
			(xy 110.357321 -222.253512) (xy 110.307928 -222.26956) (xy 110.256633 -222.277685) (xy 110.204699 -222.277685)
			(xy 110.153404 -222.26956) (xy 110.104011 -222.253512) (xy 110.057737 -222.229934) (xy 110.015721 -222.199408)
			(xy 109.978998 -222.162685) (xy 109.948472 -222.120669) (xy 109.924894 -222.074395) (xy 109.908846 -222.025002)
			(xy 109.900721 -221.973707) (xy 109.900212 -221.94774) (xy 109.621066 -221.94774) (xy 109.620557 -221.973707)
			(xy 109.612432 -222.025002) (xy 109.596384 -222.074395) (xy 109.572806 -222.120669) (xy 109.54228 -222.162685)
			(xy 109.505557 -222.199408) (xy 109.463541 -222.229934) (xy 109.417267 -222.253512) (xy 109.367874 -222.26956)
			(xy 109.316579 -222.277685) (xy 109.264645 -222.277685) (xy 109.21335 -222.26956) (xy 109.163957 -222.253512)
			(xy 109.117683 -222.229934) (xy 109.075667 -222.199408) (xy 109.038944 -222.162685) (xy 109.008418 -222.120669)
			(xy 108.98484 -222.074395) (xy 108.968792 -222.025002) (xy 108.960667 -221.973707) (xy 108.680757 -221.973707)
			(xy 108.672632 -222.025002) (xy 108.656584 -222.074395) (xy 108.633006 -222.120669) (xy 108.60248 -222.162685)
			(xy 108.565757 -222.199408) (xy 108.523741 -222.229934) (xy 108.477467 -222.253512) (xy 108.428074 -222.26956)
			(xy 108.376779 -222.277685) (xy 108.324845 -222.277685) (xy 108.27355 -222.26956) (xy 108.224157 -222.253512)
			(xy 108.177883 -222.229934) (xy 108.135867 -222.199408) (xy 108.099144 -222.162685) (xy 108.068618 -222.120669)
			(xy 108.04504 -222.074395) (xy 108.028992 -222.025002) (xy 108.020867 -221.973707) (xy 108.020358 -221.94774)
			(xy 107.741466 -221.94774) (xy 107.740957 -221.973707) (xy 107.732832 -222.025002) (xy 107.716784 -222.074395)
			(xy 107.693206 -222.120669) (xy 107.66268 -222.162685) (xy 107.625957 -222.199408) (xy 107.583941 -222.229934)
			(xy 107.537667 -222.253512) (xy 107.488274 -222.26956) (xy 107.436979 -222.277685) (xy 107.385045 -222.277685)
			(xy 107.33375 -222.26956) (xy 107.284357 -222.253512) (xy 107.238083 -222.229934) (xy 107.196067 -222.199408)
			(xy 107.159344 -222.162685) (xy 107.128818 -222.120669) (xy 107.10524 -222.074395) (xy 107.089192 -222.025002)
			(xy 107.081067 -221.973707) (xy 106.801157 -221.973707) (xy 106.793032 -222.025002) (xy 106.776984 -222.074395)
			(xy 106.753406 -222.120669) (xy 106.72288 -222.162685) (xy 106.686157 -222.199408) (xy 106.644141 -222.229934)
			(xy 106.597867 -222.253512) (xy 106.548474 -222.26956) (xy 106.497179 -222.277685) (xy 106.445245 -222.277685)
			(xy 106.39395 -222.26956) (xy 106.344557 -222.253512) (xy 106.298283 -222.229934) (xy 106.256267 -222.199408)
			(xy 106.219544 -222.162685) (xy 106.189018 -222.120669) (xy 106.16544 -222.074395) (xy 106.149392 -222.025002)
			(xy 106.141267 -221.973707) (xy 106.140758 -221.94774) (xy 105.861866 -221.94774) (xy 105.861357 -221.973707)
			(xy 105.853232 -222.025002) (xy 105.837184 -222.074395) (xy 105.813606 -222.120669) (xy 105.78308 -222.162685)
			(xy 105.746357 -222.199408) (xy 105.704341 -222.229934) (xy 105.658067 -222.253512) (xy 105.608674 -222.26956)
			(xy 105.557379 -222.277685) (xy 105.505445 -222.277685) (xy 105.45415 -222.26956) (xy 105.404757 -222.253512)
			(xy 105.358483 -222.229934) (xy 105.316467 -222.199408) (xy 105.279744 -222.162685) (xy 105.249218 -222.120669)
			(xy 105.22564 -222.074395) (xy 105.209592 -222.025002) (xy 105.201467 -221.973707) (xy 104.921557 -221.973707)
			(xy 104.913432 -222.025002) (xy 104.897384 -222.074395) (xy 104.873806 -222.120669) (xy 104.84328 -222.162685)
			(xy 104.806557 -222.199408) (xy 104.764541 -222.229934) (xy 104.718267 -222.253512) (xy 104.668874 -222.26956)
			(xy 104.617579 -222.277685) (xy 104.565645 -222.277685) (xy 104.51435 -222.26956) (xy 104.464957 -222.253512)
			(xy 104.418683 -222.229934) (xy 104.376667 -222.199408) (xy 104.339944 -222.162685) (xy 104.309418 -222.120669)
			(xy 104.28584 -222.074395) (xy 104.269792 -222.025002) (xy 104.261667 -221.973707) (xy 104.261158 -221.94774)
			(xy 103.982266 -221.94774) (xy 103.981757 -221.973707) (xy 103.973632 -222.025002) (xy 103.957584 -222.074395)
			(xy 103.934006 -222.120669) (xy 103.90348 -222.162685) (xy 103.866757 -222.199408) (xy 103.824741 -222.229934)
			(xy 103.778467 -222.253512) (xy 103.729074 -222.26956) (xy 103.677779 -222.277685) (xy 103.625845 -222.277685)
			(xy 103.57455 -222.26956) (xy 103.525157 -222.253512) (xy 103.478883 -222.229934) (xy 103.436867 -222.199408)
			(xy 103.400144 -222.162685) (xy 103.369618 -222.120669) (xy 103.34604 -222.074395) (xy 103.329992 -222.025002)
			(xy 103.321867 -221.973707) (xy 103.041957 -221.973707) (xy 103.033832 -222.025002) (xy 103.017784 -222.074395)
			(xy 102.994206 -222.120669) (xy 102.96368 -222.162685) (xy 102.926957 -222.199408) (xy 102.884941 -222.229934)
			(xy 102.838667 -222.253512) (xy 102.789274 -222.26956) (xy 102.737979 -222.277685) (xy 102.686045 -222.277685)
			(xy 102.63475 -222.26956) (xy 102.585357 -222.253512) (xy 102.539083 -222.229934) (xy 102.497067 -222.199408)
			(xy 102.460344 -222.162685) (xy 102.429818 -222.120669) (xy 102.40624 -222.074395) (xy 102.390192 -222.025002)
			(xy 102.382067 -221.973707) (xy 102.381558 -221.94774) (xy 102.382168 -221.919759) (xy 102.391615 -221.8646)
			(xy 102.400354 -221.838012) (xy 102.407974 -221.815914) (xy 102.35311 -221.720918) (xy 102.345264 -221.708366)
			(xy 102.323725 -221.688081) (xy 102.297276 -221.67482) (xy 102.268135 -221.669695) (xy 102.238749 -221.673137)
			(xy 102.211582 -221.684857) (xy 102.188913 -221.703872) (xy 102.172645 -221.728585) (xy 102.164142 -221.756925)
			(xy 102.163626 -221.771718) (xy 102.163626 -222.33001) (xy 102.164131 -222.34549) (xy 102.173332 -222.375048)
			(xy 102.190976 -222.400484) (xy 102.215438 -222.419457) (xy 102.244464 -222.430218) (xy 102.259892 -222.43161)
			(xy 102.284916 -222.433411) (xy 102.334035 -222.443624) (xy 102.381046 -222.461144) (xy 102.424868 -222.485569)
			(xy 102.464495 -222.516338) (xy 102.499015 -222.552742) (xy 102.527636 -222.593947) (xy 102.5497 -222.639005)
			(xy 102.564699 -222.686879) (xy 102.572289 -222.736471) (xy 102.57282 -222.761556) (xy 102.572317 -222.787523)
			(xy 102.852221 -222.787523) (xy 102.852221 -222.735589) (xy 102.860346 -222.684294) (xy 102.876394 -222.634901)
			(xy 102.899972 -222.588627) (xy 102.930498 -222.546611) (xy 102.967221 -222.509888) (xy 103.009237 -222.479362)
			(xy 103.055511 -222.455784) (xy 103.104904 -222.439736) (xy 103.156199 -222.431611) (xy 103.208133 -222.431611)
			(xy 103.259428 -222.439736) (xy 103.308821 -222.455784) (xy 103.355095 -222.479362) (xy 103.397111 -222.509888)
			(xy 103.433834 -222.546611) (xy 103.46436 -222.588627) (xy 103.487938 -222.634901) (xy 103.503986 -222.684294)
			(xy 103.512111 -222.735589) (xy 103.51262 -222.761556) (xy 103.512111 -222.787523) (xy 103.792021 -222.787523)
			(xy 103.792021 -222.735589) (xy 103.800146 -222.684294) (xy 103.816194 -222.634901) (xy 103.839772 -222.588627)
			(xy 103.870298 -222.546611) (xy 103.907021 -222.509888) (xy 103.949037 -222.479362) (xy 103.995311 -222.455784)
			(xy 104.044704 -222.439736) (xy 104.095999 -222.431611) (xy 104.147933 -222.431611) (xy 104.199228 -222.439736)
			(xy 104.248621 -222.455784) (xy 104.294895 -222.479362) (xy 104.336911 -222.509888) (xy 104.373634 -222.546611)
			(xy 104.40416 -222.588627) (xy 104.427738 -222.634901) (xy 104.443786 -222.684294) (xy 104.451911 -222.735589)
			(xy 104.45242 -222.761556) (xy 104.451911 -222.787523) (xy 104.731821 -222.787523) (xy 104.731821 -222.735589)
			(xy 104.739946 -222.684294) (xy 104.755994 -222.634901) (xy 104.779572 -222.588627) (xy 104.810098 -222.546611)
			(xy 104.846821 -222.509888) (xy 104.888837 -222.479362) (xy 104.935111 -222.455784) (xy 104.984504 -222.439736)
			(xy 105.035799 -222.431611) (xy 105.087733 -222.431611) (xy 105.139028 -222.439736) (xy 105.188421 -222.455784)
			(xy 105.234695 -222.479362) (xy 105.276711 -222.509888) (xy 105.313434 -222.546611) (xy 105.34396 -222.588627)
			(xy 105.367538 -222.634901) (xy 105.383586 -222.684294) (xy 105.391711 -222.735589) (xy 105.39222 -222.761556)
			(xy 105.391711 -222.787523) (xy 105.671621 -222.787523) (xy 105.671621 -222.735589) (xy 105.679746 -222.684294)
			(xy 105.695794 -222.634901) (xy 105.719372 -222.588627) (xy 105.749898 -222.546611) (xy 105.786621 -222.509888)
			(xy 105.828637 -222.479362) (xy 105.874911 -222.455784) (xy 105.924304 -222.439736) (xy 105.975599 -222.431611)
			(xy 106.027533 -222.431611) (xy 106.078828 -222.439736) (xy 106.128221 -222.455784) (xy 106.174495 -222.479362)
			(xy 106.216511 -222.509888) (xy 106.253234 -222.546611) (xy 106.28376 -222.588627) (xy 106.307338 -222.634901)
			(xy 106.323386 -222.684294) (xy 106.331511 -222.735589) (xy 106.33202 -222.761556) (xy 106.331511 -222.787523)
			(xy 106.611421 -222.787523) (xy 106.611421 -222.735589) (xy 106.619546 -222.684294) (xy 106.635594 -222.634901)
			(xy 106.659172 -222.588627) (xy 106.689698 -222.546611) (xy 106.726421 -222.509888) (xy 106.768437 -222.479362)
			(xy 106.814711 -222.455784) (xy 106.864104 -222.439736) (xy 106.915399 -222.431611) (xy 106.967333 -222.431611)
			(xy 107.018628 -222.439736) (xy 107.068021 -222.455784) (xy 107.114295 -222.479362) (xy 107.156311 -222.509888)
			(xy 107.193034 -222.546611) (xy 107.22356 -222.588627) (xy 107.247138 -222.634901) (xy 107.263186 -222.684294)
			(xy 107.271311 -222.735589) (xy 107.27182 -222.761556) (xy 107.271311 -222.787523) (xy 107.551221 -222.787523)
			(xy 107.551221 -222.735589) (xy 107.559346 -222.684294) (xy 107.575394 -222.634901) (xy 107.598972 -222.588627)
			(xy 107.629498 -222.546611) (xy 107.666221 -222.509888) (xy 107.708237 -222.479362) (xy 107.754511 -222.455784)
			(xy 107.803904 -222.439736) (xy 107.855199 -222.431611) (xy 107.907133 -222.431611) (xy 107.958428 -222.439736)
			(xy 108.007821 -222.455784) (xy 108.054095 -222.479362) (xy 108.096111 -222.509888) (xy 108.132834 -222.546611)
			(xy 108.16336 -222.588627) (xy 108.186938 -222.634901) (xy 108.202986 -222.684294) (xy 108.211111 -222.735589)
			(xy 108.21162 -222.761556) (xy 108.211111 -222.787523) (xy 108.491021 -222.787523) (xy 108.491021 -222.735589)
			(xy 108.499146 -222.684294) (xy 108.515194 -222.634901) (xy 108.538772 -222.588627) (xy 108.569298 -222.546611)
			(xy 108.606021 -222.509888) (xy 108.648037 -222.479362) (xy 108.694311 -222.455784) (xy 108.743704 -222.439736)
			(xy 108.794999 -222.431611) (xy 108.846933 -222.431611) (xy 108.898228 -222.439736) (xy 108.947621 -222.455784)
			(xy 108.993895 -222.479362) (xy 109.035911 -222.509888) (xy 109.072634 -222.546611) (xy 109.10316 -222.588627)
			(xy 109.126738 -222.634901) (xy 109.142786 -222.684294) (xy 109.150911 -222.735589) (xy 109.15142 -222.761556)
			(xy 109.150911 -222.787523) (xy 109.430821 -222.787523) (xy 109.430821 -222.735589) (xy 109.438946 -222.684294)
			(xy 109.454994 -222.634901) (xy 109.478572 -222.588627) (xy 109.509098 -222.546611) (xy 109.545821 -222.509888)
			(xy 109.587837 -222.479362) (xy 109.634111 -222.455784) (xy 109.683504 -222.439736) (xy 109.734799 -222.431611)
			(xy 109.786733 -222.431611) (xy 109.838028 -222.439736) (xy 109.887421 -222.455784) (xy 109.933695 -222.479362)
			(xy 109.975711 -222.509888) (xy 110.012434 -222.546611) (xy 110.04296 -222.588627) (xy 110.066538 -222.634901)
			(xy 110.082586 -222.684294) (xy 110.090711 -222.735589) (xy 110.09122 -222.761556) (xy 110.090711 -222.787523)
			(xy 110.370621 -222.787523) (xy 110.370621 -222.735589) (xy 110.378746 -222.684294) (xy 110.394794 -222.634901)
			(xy 110.418372 -222.588627) (xy 110.448898 -222.546611) (xy 110.485621 -222.509888) (xy 110.527637 -222.479362)
			(xy 110.573911 -222.455784) (xy 110.623304 -222.439736) (xy 110.674599 -222.431611) (xy 110.726533 -222.431611)
			(xy 110.777828 -222.439736) (xy 110.827221 -222.455784) (xy 110.873495 -222.479362) (xy 110.915511 -222.509888)
			(xy 110.952234 -222.546611) (xy 110.98276 -222.588627) (xy 111.006338 -222.634901) (xy 111.022386 -222.684294)
			(xy 111.030511 -222.735589) (xy 111.03102 -222.761556) (xy 111.030511 -222.787523) (xy 111.310421 -222.787523)
			(xy 111.310421 -222.735589) (xy 111.318546 -222.684294) (xy 111.334594 -222.634901) (xy 111.358172 -222.588627)
			(xy 111.388698 -222.546611) (xy 111.425421 -222.509888) (xy 111.467437 -222.479362) (xy 111.513711 -222.455784)
			(xy 111.563104 -222.439736) (xy 111.614399 -222.431611) (xy 111.666333 -222.431611) (xy 111.717628 -222.439736)
			(xy 111.767021 -222.455784) (xy 111.813295 -222.479362) (xy 111.855311 -222.509888) (xy 111.892034 -222.546611)
			(xy 111.92256 -222.588627) (xy 111.946138 -222.634901) (xy 111.962186 -222.684294) (xy 111.970311 -222.735589)
			(xy 111.97082 -222.761556) (xy 111.970311 -222.787523) (xy 112.250221 -222.787523) (xy 112.250221 -222.735589)
			(xy 112.258346 -222.684294) (xy 112.274394 -222.634901) (xy 112.297972 -222.588627) (xy 112.328498 -222.546611)
			(xy 112.365221 -222.509888) (xy 112.407237 -222.479362) (xy 112.453511 -222.455784) (xy 112.502904 -222.439736)
			(xy 112.554199 -222.431611) (xy 112.606133 -222.431611) (xy 112.657428 -222.439736) (xy 112.706821 -222.455784)
			(xy 112.753095 -222.479362) (xy 112.795111 -222.509888) (xy 112.831834 -222.546611) (xy 112.86236 -222.588627)
			(xy 112.885938 -222.634901) (xy 112.901986 -222.684294) (xy 112.910111 -222.735589) (xy 112.91062 -222.761556)
			(xy 112.910111 -222.787523) (xy 113.190021 -222.787523) (xy 113.190021 -222.735589) (xy 113.198146 -222.684294)
			(xy 113.214194 -222.634901) (xy 113.237772 -222.588627) (xy 113.268298 -222.546611) (xy 113.305021 -222.509888)
			(xy 113.347037 -222.479362) (xy 113.393311 -222.455784) (xy 113.442704 -222.439736) (xy 113.493999 -222.431611)
			(xy 113.545933 -222.431611) (xy 113.597228 -222.439736) (xy 113.646621 -222.455784) (xy 113.692895 -222.479362)
			(xy 113.734911 -222.509888) (xy 113.771634 -222.546611) (xy 113.80216 -222.588627) (xy 113.825738 -222.634901)
			(xy 113.841786 -222.684294) (xy 113.849911 -222.735589) (xy 113.85042 -222.761556) (xy 113.849911 -222.787523)
			(xy 114.129821 -222.787523) (xy 114.129821 -222.735589) (xy 114.137946 -222.684294) (xy 114.153994 -222.634901)
			(xy 114.177572 -222.588627) (xy 114.208098 -222.546611) (xy 114.244821 -222.509888) (xy 114.286837 -222.479362)
			(xy 114.333111 -222.455784) (xy 114.382504 -222.439736) (xy 114.433799 -222.431611) (xy 114.485733 -222.431611)
			(xy 114.537028 -222.439736) (xy 114.586421 -222.455784) (xy 114.632695 -222.479362) (xy 114.674711 -222.509888)
			(xy 114.711434 -222.546611) (xy 114.74196 -222.588627) (xy 114.765538 -222.634901) (xy 114.781586 -222.684294)
			(xy 114.789711 -222.735589) (xy 114.79022 -222.761556) (xy 114.789711 -222.787523) (xy 115.069621 -222.787523)
			(xy 115.069621 -222.735589) (xy 115.077746 -222.684294) (xy 115.093794 -222.634901) (xy 115.117372 -222.588627)
			(xy 115.147898 -222.546611) (xy 115.184621 -222.509888) (xy 115.226637 -222.479362) (xy 115.272911 -222.455784)
			(xy 115.322304 -222.439736) (xy 115.373599 -222.431611) (xy 115.425533 -222.431611) (xy 115.476828 -222.439736)
			(xy 115.526221 -222.455784) (xy 115.572495 -222.479362) (xy 115.614511 -222.509888) (xy 115.651234 -222.546611)
			(xy 115.68176 -222.588627) (xy 115.705338 -222.634901) (xy 115.721386 -222.684294) (xy 115.729511 -222.735589)
			(xy 115.73002 -222.761556) (xy 115.729511 -222.787523) (xy 116.009421 -222.787523) (xy 116.009421 -222.735589)
			(xy 116.017546 -222.684294) (xy 116.033594 -222.634901) (xy 116.057172 -222.588627) (xy 116.087698 -222.546611)
			(xy 116.124421 -222.509888) (xy 116.166437 -222.479362) (xy 116.212711 -222.455784) (xy 116.262104 -222.439736)
			(xy 116.313399 -222.431611) (xy 116.365333 -222.431611) (xy 116.416628 -222.439736) (xy 116.466021 -222.455784)
			(xy 116.512295 -222.479362) (xy 116.554311 -222.509888) (xy 116.591034 -222.546611) (xy 116.62156 -222.588627)
			(xy 116.645138 -222.634901) (xy 116.661186 -222.684294) (xy 116.669311 -222.735589) (xy 116.66982 -222.761556)
			(xy 116.669311 -222.787523) (xy 116.949221 -222.787523) (xy 116.949221 -222.735589) (xy 116.957346 -222.684294)
			(xy 116.973394 -222.634901) (xy 116.996972 -222.588627) (xy 117.027498 -222.546611) (xy 117.064221 -222.509888)
			(xy 117.106237 -222.479362) (xy 117.152511 -222.455784) (xy 117.201904 -222.439736) (xy 117.253199 -222.431611)
			(xy 117.305133 -222.431611) (xy 117.356428 -222.439736) (xy 117.405821 -222.455784) (xy 117.452095 -222.479362)
			(xy 117.494111 -222.509888) (xy 117.530834 -222.546611) (xy 117.56136 -222.588627) (xy 117.584938 -222.634901)
			(xy 117.600986 -222.684294) (xy 117.609111 -222.735589) (xy 117.60962 -222.761556) (xy 117.609111 -222.787523)
			(xy 117.889021 -222.787523) (xy 117.889021 -222.735589) (xy 117.897146 -222.684294) (xy 117.913194 -222.634901)
			(xy 117.936772 -222.588627) (xy 117.967298 -222.546611) (xy 118.004021 -222.509888) (xy 118.046037 -222.479362)
			(xy 118.092311 -222.455784) (xy 118.141704 -222.439736) (xy 118.192999 -222.431611) (xy 118.244933 -222.431611)
			(xy 118.296228 -222.439736) (xy 118.345621 -222.455784) (xy 118.391895 -222.479362) (xy 118.433911 -222.509888)
			(xy 118.470634 -222.546611) (xy 118.50116 -222.588627) (xy 118.524738 -222.634901) (xy 118.540786 -222.684294)
			(xy 118.548911 -222.735589) (xy 118.54942 -222.761556) (xy 118.548911 -222.787523) (xy 118.828821 -222.787523)
			(xy 118.828821 -222.735589) (xy 118.836946 -222.684294) (xy 118.852994 -222.634901) (xy 118.876572 -222.588627)
			(xy 118.907098 -222.546611) (xy 118.943821 -222.509888) (xy 118.985837 -222.479362) (xy 119.032111 -222.455784)
			(xy 119.081504 -222.439736) (xy 119.132799 -222.431611) (xy 119.184733 -222.431611) (xy 119.236028 -222.439736)
			(xy 119.285421 -222.455784) (xy 119.331695 -222.479362) (xy 119.373711 -222.509888) (xy 119.410434 -222.546611)
			(xy 119.44096 -222.588627) (xy 119.464538 -222.634901) (xy 119.480586 -222.684294) (xy 119.488711 -222.735589)
			(xy 119.48922 -222.761556) (xy 119.488711 -222.787523) (xy 119.768621 -222.787523) (xy 119.768621 -222.735589)
			(xy 119.776746 -222.684294) (xy 119.792794 -222.634901) (xy 119.816372 -222.588627) (xy 119.846898 -222.546611)
			(xy 119.883621 -222.509888) (xy 119.925637 -222.479362) (xy 119.971911 -222.455784) (xy 120.021304 -222.439736)
			(xy 120.072599 -222.431611) (xy 120.124533 -222.431611) (xy 120.175828 -222.439736) (xy 120.225221 -222.455784)
			(xy 120.271495 -222.479362) (xy 120.313511 -222.509888) (xy 120.350234 -222.546611) (xy 120.38076 -222.588627)
			(xy 120.404338 -222.634901) (xy 120.420386 -222.684294) (xy 120.428511 -222.735589) (xy 120.42902 -222.761556)
			(xy 120.428511 -222.787523) (xy 120.708421 -222.787523) (xy 120.708421 -222.735589) (xy 120.716546 -222.684294)
			(xy 120.732594 -222.634901) (xy 120.756172 -222.588627) (xy 120.786698 -222.546611) (xy 120.823421 -222.509888)
			(xy 120.865437 -222.479362) (xy 120.911711 -222.455784) (xy 120.961104 -222.439736) (xy 121.012399 -222.431611)
			(xy 121.064333 -222.431611) (xy 121.115628 -222.439736) (xy 121.165021 -222.455784) (xy 121.211295 -222.479362)
			(xy 121.253311 -222.509888) (xy 121.290034 -222.546611) (xy 121.32056 -222.588627) (xy 121.344138 -222.634901)
			(xy 121.360186 -222.684294) (xy 121.368311 -222.735589) (xy 121.36882 -222.761556) (xy 121.368311 -222.787523)
			(xy 121.648221 -222.787523) (xy 121.648221 -222.735589) (xy 121.656346 -222.684294) (xy 121.672394 -222.634901)
			(xy 121.695972 -222.588627) (xy 121.726498 -222.546611) (xy 121.763221 -222.509888) (xy 121.805237 -222.479362)
			(xy 121.851511 -222.455784) (xy 121.900904 -222.439736) (xy 121.952199 -222.431611) (xy 122.004133 -222.431611)
			(xy 122.055428 -222.439736) (xy 122.104821 -222.455784) (xy 122.151095 -222.479362) (xy 122.193111 -222.509888)
			(xy 122.229834 -222.546611) (xy 122.26036 -222.588627) (xy 122.283938 -222.634901) (xy 122.299986 -222.684294)
			(xy 122.308111 -222.735589) (xy 122.30862 -222.761556) (xy 122.308111 -222.787523) (xy 122.588021 -222.787523)
			(xy 122.588021 -222.735589) (xy 122.596146 -222.684294) (xy 122.612194 -222.634901) (xy 122.635772 -222.588627)
			(xy 122.666298 -222.546611) (xy 122.703021 -222.509888) (xy 122.745037 -222.479362) (xy 122.791311 -222.455784)
			(xy 122.840704 -222.439736) (xy 122.891999 -222.431611) (xy 122.943933 -222.431611) (xy 122.995228 -222.439736)
			(xy 123.044621 -222.455784) (xy 123.090895 -222.479362) (xy 123.132911 -222.509888) (xy 123.169634 -222.546611)
			(xy 123.20016 -222.588627) (xy 123.223738 -222.634901) (xy 123.239786 -222.684294) (xy 123.247911 -222.735589)
			(xy 123.24842 -222.761556) (xy 123.247911 -222.787523) (xy 123.527821 -222.787523) (xy 123.527821 -222.735589)
			(xy 123.535946 -222.684294) (xy 123.551994 -222.634901) (xy 123.575572 -222.588627) (xy 123.606098 -222.546611)
			(xy 123.642821 -222.509888) (xy 123.684837 -222.479362) (xy 123.731111 -222.455784) (xy 123.780504 -222.439736)
			(xy 123.831799 -222.431611) (xy 123.883733 -222.431611) (xy 123.935028 -222.439736) (xy 123.984421 -222.455784)
			(xy 124.030695 -222.479362) (xy 124.072711 -222.509888) (xy 124.109434 -222.546611) (xy 124.13996 -222.588627)
			(xy 124.163538 -222.634901) (xy 124.179586 -222.684294) (xy 124.187711 -222.735589) (xy 124.18822 -222.761556)
			(xy 124.187711 -222.787523) (xy 124.467621 -222.787523) (xy 124.467621 -222.735589) (xy 124.475746 -222.684294)
			(xy 124.491794 -222.634901) (xy 124.515372 -222.588627) (xy 124.545898 -222.546611) (xy 124.582621 -222.509888)
			(xy 124.624637 -222.479362) (xy 124.670911 -222.455784) (xy 124.720304 -222.439736) (xy 124.771599 -222.431611)
			(xy 124.823533 -222.431611) (xy 124.874828 -222.439736) (xy 124.924221 -222.455784) (xy 124.970495 -222.479362)
			(xy 125.012511 -222.509888) (xy 125.049234 -222.546611) (xy 125.07976 -222.588627) (xy 125.103338 -222.634901)
			(xy 125.119386 -222.684294) (xy 125.127511 -222.735589) (xy 125.12802 -222.761556) (xy 125.127511 -222.787523)
			(xy 125.407421 -222.787523) (xy 125.407421 -222.735589) (xy 125.415546 -222.684294) (xy 125.431594 -222.634901)
			(xy 125.455172 -222.588627) (xy 125.485698 -222.546611) (xy 125.522421 -222.509888) (xy 125.564437 -222.479362)
			(xy 125.610711 -222.455784) (xy 125.660104 -222.439736) (xy 125.711399 -222.431611) (xy 125.763333 -222.431611)
			(xy 125.814628 -222.439736) (xy 125.864021 -222.455784) (xy 125.910295 -222.479362) (xy 125.952311 -222.509888)
			(xy 125.989034 -222.546611) (xy 126.01956 -222.588627) (xy 126.043138 -222.634901) (xy 126.059186 -222.684294)
			(xy 126.067311 -222.735589) (xy 126.06782 -222.761556) (xy 126.067311 -222.787523) (xy 126.347221 -222.787523)
			(xy 126.347221 -222.735589) (xy 126.355346 -222.684294) (xy 126.371394 -222.634901) (xy 126.394972 -222.588627)
			(xy 126.425498 -222.546611) (xy 126.462221 -222.509888) (xy 126.504237 -222.479362) (xy 126.550511 -222.455784)
			(xy 126.599904 -222.439736) (xy 126.651199 -222.431611) (xy 126.703133 -222.431611) (xy 126.754428 -222.439736)
			(xy 126.803821 -222.455784) (xy 126.850095 -222.479362) (xy 126.892111 -222.509888) (xy 126.928834 -222.546611)
			(xy 126.95936 -222.588627) (xy 126.982938 -222.634901) (xy 126.998986 -222.684294) (xy 127.007111 -222.735589)
			(xy 127.00762 -222.761556) (xy 127.007111 -222.787523) (xy 126.998986 -222.838818) (xy 126.982938 -222.888211)
			(xy 126.95936 -222.934485) (xy 126.928834 -222.976501) (xy 126.892111 -223.013224) (xy 126.850095 -223.04375)
			(xy 126.803821 -223.067328) (xy 126.754428 -223.083376) (xy 126.703133 -223.091501) (xy 126.651199 -223.091501)
			(xy 126.599904 -223.083376) (xy 126.550511 -223.067328) (xy 126.504237 -223.04375) (xy 126.462221 -223.013224)
			(xy 126.425498 -222.976501) (xy 126.394972 -222.934485) (xy 126.371394 -222.888211) (xy 126.355346 -222.838818)
			(xy 126.347221 -222.787523) (xy 126.067311 -222.787523) (xy 126.059186 -222.838818) (xy 126.043138 -222.888211)
			(xy 126.01956 -222.934485) (xy 125.989034 -222.976501) (xy 125.952311 -223.013224) (xy 125.910295 -223.04375)
			(xy 125.864021 -223.067328) (xy 125.814628 -223.083376) (xy 125.763333 -223.091501) (xy 125.711399 -223.091501)
			(xy 125.660104 -223.083376) (xy 125.610711 -223.067328) (xy 125.564437 -223.04375) (xy 125.522421 -223.013224)
			(xy 125.485698 -222.976501) (xy 125.455172 -222.934485) (xy 125.431594 -222.888211) (xy 125.415546 -222.838818)
			(xy 125.407421 -222.787523) (xy 125.127511 -222.787523) (xy 125.119386 -222.838818) (xy 125.103338 -222.888211)
			(xy 125.07976 -222.934485) (xy 125.049234 -222.976501) (xy 125.012511 -223.013224) (xy 124.970495 -223.04375)
			(xy 124.924221 -223.067328) (xy 124.874828 -223.083376) (xy 124.823533 -223.091501) (xy 124.771599 -223.091501)
			(xy 124.720304 -223.083376) (xy 124.670911 -223.067328) (xy 124.624637 -223.04375) (xy 124.582621 -223.013224)
			(xy 124.545898 -222.976501) (xy 124.515372 -222.934485) (xy 124.491794 -222.888211) (xy 124.475746 -222.838818)
			(xy 124.467621 -222.787523) (xy 124.187711 -222.787523) (xy 124.179586 -222.838818) (xy 124.163538 -222.888211)
			(xy 124.13996 -222.934485) (xy 124.109434 -222.976501) (xy 124.072711 -223.013224) (xy 124.030695 -223.04375)
			(xy 123.984421 -223.067328) (xy 123.935028 -223.083376) (xy 123.883733 -223.091501) (xy 123.831799 -223.091501)
			(xy 123.780504 -223.083376) (xy 123.731111 -223.067328) (xy 123.684837 -223.04375) (xy 123.642821 -223.013224)
			(xy 123.606098 -222.976501) (xy 123.575572 -222.934485) (xy 123.551994 -222.888211) (xy 123.535946 -222.838818)
			(xy 123.527821 -222.787523) (xy 123.247911 -222.787523) (xy 123.239786 -222.838818) (xy 123.223738 -222.888211)
			(xy 123.20016 -222.934485) (xy 123.169634 -222.976501) (xy 123.132911 -223.013224) (xy 123.090895 -223.04375)
			(xy 123.044621 -223.067328) (xy 122.995228 -223.083376) (xy 122.943933 -223.091501) (xy 122.891999 -223.091501)
			(xy 122.840704 -223.083376) (xy 122.791311 -223.067328) (xy 122.745037 -223.04375) (xy 122.703021 -223.013224)
			(xy 122.666298 -222.976501) (xy 122.635772 -222.934485) (xy 122.612194 -222.888211) (xy 122.596146 -222.838818)
			(xy 122.588021 -222.787523) (xy 122.308111 -222.787523) (xy 122.299986 -222.838818) (xy 122.283938 -222.888211)
			(xy 122.26036 -222.934485) (xy 122.229834 -222.976501) (xy 122.193111 -223.013224) (xy 122.151095 -223.04375)
			(xy 122.104821 -223.067328) (xy 122.055428 -223.083376) (xy 122.004133 -223.091501) (xy 121.952199 -223.091501)
			(xy 121.900904 -223.083376) (xy 121.851511 -223.067328) (xy 121.805237 -223.04375) (xy 121.763221 -223.013224)
			(xy 121.726498 -222.976501) (xy 121.695972 -222.934485) (xy 121.672394 -222.888211) (xy 121.656346 -222.838818)
			(xy 121.648221 -222.787523) (xy 121.368311 -222.787523) (xy 121.360186 -222.838818) (xy 121.344138 -222.888211)
			(xy 121.32056 -222.934485) (xy 121.290034 -222.976501) (xy 121.253311 -223.013224) (xy 121.211295 -223.04375)
			(xy 121.165021 -223.067328) (xy 121.115628 -223.083376) (xy 121.064333 -223.091501) (xy 121.012399 -223.091501)
			(xy 120.961104 -223.083376) (xy 120.911711 -223.067328) (xy 120.865437 -223.04375) (xy 120.823421 -223.013224)
			(xy 120.786698 -222.976501) (xy 120.756172 -222.934485) (xy 120.732594 -222.888211) (xy 120.716546 -222.838818)
			(xy 120.708421 -222.787523) (xy 120.428511 -222.787523) (xy 120.420386 -222.838818) (xy 120.404338 -222.888211)
			(xy 120.38076 -222.934485) (xy 120.350234 -222.976501) (xy 120.313511 -223.013224) (xy 120.271495 -223.04375)
			(xy 120.225221 -223.067328) (xy 120.175828 -223.083376) (xy 120.124533 -223.091501) (xy 120.072599 -223.091501)
			(xy 120.021304 -223.083376) (xy 119.971911 -223.067328) (xy 119.925637 -223.04375) (xy 119.883621 -223.013224)
			(xy 119.846898 -222.976501) (xy 119.816372 -222.934485) (xy 119.792794 -222.888211) (xy 119.776746 -222.838818)
			(xy 119.768621 -222.787523) (xy 119.488711 -222.787523) (xy 119.480586 -222.838818) (xy 119.464538 -222.888211)
			(xy 119.44096 -222.934485) (xy 119.410434 -222.976501) (xy 119.373711 -223.013224) (xy 119.331695 -223.04375)
			(xy 119.285421 -223.067328) (xy 119.236028 -223.083376) (xy 119.184733 -223.091501) (xy 119.132799 -223.091501)
			(xy 119.081504 -223.083376) (xy 119.032111 -223.067328) (xy 118.985837 -223.04375) (xy 118.943821 -223.013224)
			(xy 118.907098 -222.976501) (xy 118.876572 -222.934485) (xy 118.852994 -222.888211) (xy 118.836946 -222.838818)
			(xy 118.828821 -222.787523) (xy 118.548911 -222.787523) (xy 118.540786 -222.838818) (xy 118.524738 -222.888211)
			(xy 118.50116 -222.934485) (xy 118.470634 -222.976501) (xy 118.433911 -223.013224) (xy 118.391895 -223.04375)
			(xy 118.345621 -223.067328) (xy 118.296228 -223.083376) (xy 118.244933 -223.091501) (xy 118.192999 -223.091501)
			(xy 118.141704 -223.083376) (xy 118.092311 -223.067328) (xy 118.046037 -223.04375) (xy 118.004021 -223.013224)
			(xy 117.967298 -222.976501) (xy 117.936772 -222.934485) (xy 117.913194 -222.888211) (xy 117.897146 -222.838818)
			(xy 117.889021 -222.787523) (xy 117.609111 -222.787523) (xy 117.600986 -222.838818) (xy 117.584938 -222.888211)
			(xy 117.56136 -222.934485) (xy 117.530834 -222.976501) (xy 117.494111 -223.013224) (xy 117.452095 -223.04375)
			(xy 117.405821 -223.067328) (xy 117.356428 -223.083376) (xy 117.305133 -223.091501) (xy 117.253199 -223.091501)
			(xy 117.201904 -223.083376) (xy 117.152511 -223.067328) (xy 117.106237 -223.04375) (xy 117.064221 -223.013224)
			(xy 117.027498 -222.976501) (xy 116.996972 -222.934485) (xy 116.973394 -222.888211) (xy 116.957346 -222.838818)
			(xy 116.949221 -222.787523) (xy 116.669311 -222.787523) (xy 116.661186 -222.838818) (xy 116.645138 -222.888211)
			(xy 116.62156 -222.934485) (xy 116.591034 -222.976501) (xy 116.554311 -223.013224) (xy 116.512295 -223.04375)
			(xy 116.466021 -223.067328) (xy 116.416628 -223.083376) (xy 116.365333 -223.091501) (xy 116.313399 -223.091501)
			(xy 116.262104 -223.083376) (xy 116.212711 -223.067328) (xy 116.166437 -223.04375) (xy 116.124421 -223.013224)
			(xy 116.087698 -222.976501) (xy 116.057172 -222.934485) (xy 116.033594 -222.888211) (xy 116.017546 -222.838818)
			(xy 116.009421 -222.787523) (xy 115.729511 -222.787523) (xy 115.721386 -222.838818) (xy 115.705338 -222.888211)
			(xy 115.68176 -222.934485) (xy 115.651234 -222.976501) (xy 115.614511 -223.013224) (xy 115.572495 -223.04375)
			(xy 115.526221 -223.067328) (xy 115.476828 -223.083376) (xy 115.425533 -223.091501) (xy 115.373599 -223.091501)
			(xy 115.322304 -223.083376) (xy 115.272911 -223.067328) (xy 115.226637 -223.04375) (xy 115.184621 -223.013224)
			(xy 115.147898 -222.976501) (xy 115.117372 -222.934485) (xy 115.093794 -222.888211) (xy 115.077746 -222.838818)
			(xy 115.069621 -222.787523) (xy 114.789711 -222.787523) (xy 114.781586 -222.838818) (xy 114.765538 -222.888211)
			(xy 114.74196 -222.934485) (xy 114.711434 -222.976501) (xy 114.674711 -223.013224) (xy 114.632695 -223.04375)
			(xy 114.586421 -223.067328) (xy 114.537028 -223.083376) (xy 114.485733 -223.091501) (xy 114.433799 -223.091501)
			(xy 114.382504 -223.083376) (xy 114.333111 -223.067328) (xy 114.286837 -223.04375) (xy 114.244821 -223.013224)
			(xy 114.208098 -222.976501) (xy 114.177572 -222.934485) (xy 114.153994 -222.888211) (xy 114.137946 -222.838818)
			(xy 114.129821 -222.787523) (xy 113.849911 -222.787523) (xy 113.841786 -222.838818) (xy 113.825738 -222.888211)
			(xy 113.80216 -222.934485) (xy 113.771634 -222.976501) (xy 113.734911 -223.013224) (xy 113.692895 -223.04375)
			(xy 113.646621 -223.067328) (xy 113.597228 -223.083376) (xy 113.545933 -223.091501) (xy 113.493999 -223.091501)
			(xy 113.442704 -223.083376) (xy 113.393311 -223.067328) (xy 113.347037 -223.04375) (xy 113.305021 -223.013224)
			(xy 113.268298 -222.976501) (xy 113.237772 -222.934485) (xy 113.214194 -222.888211) (xy 113.198146 -222.838818)
			(xy 113.190021 -222.787523) (xy 112.910111 -222.787523) (xy 112.901986 -222.838818) (xy 112.885938 -222.888211)
			(xy 112.86236 -222.934485) (xy 112.831834 -222.976501) (xy 112.795111 -223.013224) (xy 112.753095 -223.04375)
			(xy 112.706821 -223.067328) (xy 112.657428 -223.083376) (xy 112.606133 -223.091501) (xy 112.554199 -223.091501)
			(xy 112.502904 -223.083376) (xy 112.453511 -223.067328) (xy 112.407237 -223.04375) (xy 112.365221 -223.013224)
			(xy 112.328498 -222.976501) (xy 112.297972 -222.934485) (xy 112.274394 -222.888211) (xy 112.258346 -222.838818)
			(xy 112.250221 -222.787523) (xy 111.970311 -222.787523) (xy 111.962186 -222.838818) (xy 111.946138 -222.888211)
			(xy 111.92256 -222.934485) (xy 111.892034 -222.976501) (xy 111.855311 -223.013224) (xy 111.813295 -223.04375)
			(xy 111.767021 -223.067328) (xy 111.717628 -223.083376) (xy 111.666333 -223.091501) (xy 111.614399 -223.091501)
			(xy 111.563104 -223.083376) (xy 111.513711 -223.067328) (xy 111.467437 -223.04375) (xy 111.425421 -223.013224)
			(xy 111.388698 -222.976501) (xy 111.358172 -222.934485) (xy 111.334594 -222.888211) (xy 111.318546 -222.838818)
			(xy 111.310421 -222.787523) (xy 111.030511 -222.787523) (xy 111.022386 -222.838818) (xy 111.006338 -222.888211)
			(xy 110.98276 -222.934485) (xy 110.952234 -222.976501) (xy 110.915511 -223.013224) (xy 110.873495 -223.04375)
			(xy 110.827221 -223.067328) (xy 110.777828 -223.083376) (xy 110.726533 -223.091501) (xy 110.674599 -223.091501)
			(xy 110.623304 -223.083376) (xy 110.573911 -223.067328) (xy 110.527637 -223.04375) (xy 110.485621 -223.013224)
			(xy 110.448898 -222.976501) (xy 110.418372 -222.934485) (xy 110.394794 -222.888211) (xy 110.378746 -222.838818)
			(xy 110.370621 -222.787523) (xy 110.090711 -222.787523) (xy 110.082586 -222.838818) (xy 110.066538 -222.888211)
			(xy 110.04296 -222.934485) (xy 110.012434 -222.976501) (xy 109.975711 -223.013224) (xy 109.933695 -223.04375)
			(xy 109.887421 -223.067328) (xy 109.838028 -223.083376) (xy 109.786733 -223.091501) (xy 109.734799 -223.091501)
			(xy 109.683504 -223.083376) (xy 109.634111 -223.067328) (xy 109.587837 -223.04375) (xy 109.545821 -223.013224)
			(xy 109.509098 -222.976501) (xy 109.478572 -222.934485) (xy 109.454994 -222.888211) (xy 109.438946 -222.838818)
			(xy 109.430821 -222.787523) (xy 109.150911 -222.787523) (xy 109.142786 -222.838818) (xy 109.126738 -222.888211)
			(xy 109.10316 -222.934485) (xy 109.072634 -222.976501) (xy 109.035911 -223.013224) (xy 108.993895 -223.04375)
			(xy 108.947621 -223.067328) (xy 108.898228 -223.083376) (xy 108.846933 -223.091501) (xy 108.794999 -223.091501)
			(xy 108.743704 -223.083376) (xy 108.694311 -223.067328) (xy 108.648037 -223.04375) (xy 108.606021 -223.013224)
			(xy 108.569298 -222.976501) (xy 108.538772 -222.934485) (xy 108.515194 -222.888211) (xy 108.499146 -222.838818)
			(xy 108.491021 -222.787523) (xy 108.211111 -222.787523) (xy 108.202986 -222.838818) (xy 108.186938 -222.888211)
			(xy 108.16336 -222.934485) (xy 108.132834 -222.976501) (xy 108.096111 -223.013224) (xy 108.054095 -223.04375)
			(xy 108.007821 -223.067328) (xy 107.958428 -223.083376) (xy 107.907133 -223.091501) (xy 107.855199 -223.091501)
			(xy 107.803904 -223.083376) (xy 107.754511 -223.067328) (xy 107.708237 -223.04375) (xy 107.666221 -223.013224)
			(xy 107.629498 -222.976501) (xy 107.598972 -222.934485) (xy 107.575394 -222.888211) (xy 107.559346 -222.838818)
			(xy 107.551221 -222.787523) (xy 107.271311 -222.787523) (xy 107.263186 -222.838818) (xy 107.247138 -222.888211)
			(xy 107.22356 -222.934485) (xy 107.193034 -222.976501) (xy 107.156311 -223.013224) (xy 107.114295 -223.04375)
			(xy 107.068021 -223.067328) (xy 107.018628 -223.083376) (xy 106.967333 -223.091501) (xy 106.915399 -223.091501)
			(xy 106.864104 -223.083376) (xy 106.814711 -223.067328) (xy 106.768437 -223.04375) (xy 106.726421 -223.013224)
			(xy 106.689698 -222.976501) (xy 106.659172 -222.934485) (xy 106.635594 -222.888211) (xy 106.619546 -222.838818)
			(xy 106.611421 -222.787523) (xy 106.331511 -222.787523) (xy 106.323386 -222.838818) (xy 106.307338 -222.888211)
			(xy 106.28376 -222.934485) (xy 106.253234 -222.976501) (xy 106.216511 -223.013224) (xy 106.174495 -223.04375)
			(xy 106.128221 -223.067328) (xy 106.078828 -223.083376) (xy 106.027533 -223.091501) (xy 105.975599 -223.091501)
			(xy 105.924304 -223.083376) (xy 105.874911 -223.067328) (xy 105.828637 -223.04375) (xy 105.786621 -223.013224)
			(xy 105.749898 -222.976501) (xy 105.719372 -222.934485) (xy 105.695794 -222.888211) (xy 105.679746 -222.838818)
			(xy 105.671621 -222.787523) (xy 105.391711 -222.787523) (xy 105.383586 -222.838818) (xy 105.367538 -222.888211)
			(xy 105.34396 -222.934485) (xy 105.313434 -222.976501) (xy 105.276711 -223.013224) (xy 105.234695 -223.04375)
			(xy 105.188421 -223.067328) (xy 105.139028 -223.083376) (xy 105.087733 -223.091501) (xy 105.035799 -223.091501)
			(xy 104.984504 -223.083376) (xy 104.935111 -223.067328) (xy 104.888837 -223.04375) (xy 104.846821 -223.013224)
			(xy 104.810098 -222.976501) (xy 104.779572 -222.934485) (xy 104.755994 -222.888211) (xy 104.739946 -222.838818)
			(xy 104.731821 -222.787523) (xy 104.451911 -222.787523) (xy 104.443786 -222.838818) (xy 104.427738 -222.888211)
			(xy 104.40416 -222.934485) (xy 104.373634 -222.976501) (xy 104.336911 -223.013224) (xy 104.294895 -223.04375)
			(xy 104.248621 -223.067328) (xy 104.199228 -223.083376) (xy 104.147933 -223.091501) (xy 104.095999 -223.091501)
			(xy 104.044704 -223.083376) (xy 103.995311 -223.067328) (xy 103.949037 -223.04375) (xy 103.907021 -223.013224)
			(xy 103.870298 -222.976501) (xy 103.839772 -222.934485) (xy 103.816194 -222.888211) (xy 103.800146 -222.838818)
			(xy 103.792021 -222.787523) (xy 103.512111 -222.787523) (xy 103.503986 -222.838818) (xy 103.487938 -222.888211)
			(xy 103.46436 -222.934485) (xy 103.433834 -222.976501) (xy 103.397111 -223.013224) (xy 103.355095 -223.04375)
			(xy 103.308821 -223.067328) (xy 103.259428 -223.083376) (xy 103.208133 -223.091501) (xy 103.156199 -223.091501)
			(xy 103.104904 -223.083376) (xy 103.055511 -223.067328) (xy 103.009237 -223.04375) (xy 102.967221 -223.013224)
			(xy 102.930498 -222.976501) (xy 102.899972 -222.934485) (xy 102.876394 -222.888211) (xy 102.860346 -222.838818)
			(xy 102.852221 -222.787523) (xy 102.572317 -222.787523) (xy 102.572311 -222.787812) (xy 102.564002 -222.839662)
			(xy 102.547601 -222.889547) (xy 102.523521 -222.936212) (xy 102.492367 -222.978484) (xy 102.474014 -222.997268)
			(xy 102.467756 -223.003895) (xy 102.460004 -223.020375) (xy 102.458535 -223.038528) (xy 102.463536 -223.05604)
			(xy 102.46868 -223.063562) (xy 102.496422 -223.102444) (xy 102.544161 -223.185181) (xy 102.56393 -223.228662)
			(xy 102.567959 -223.236828) (xy 102.580673 -223.249847) (xy 102.597126 -223.257618) (xy 102.615257 -223.259168)
			(xy 102.624128 -223.25711) (xy 102.64573 -223.251512) (xy 102.689953 -223.245524) (xy 102.712266 -223.245172)
			(xy 102.738236 -223.245652) (xy 102.789538 -223.253773) (xy 102.838937 -223.26982) (xy 102.885218 -223.293399)
			(xy 102.92724 -223.323927) (xy 102.963967 -223.360654) (xy 102.994497 -223.402675) (xy 103.018076 -223.448955)
			(xy 103.034125 -223.498354) (xy 103.042247 -223.549656) (xy 103.04272 -223.575626) (xy 103.042098 -223.604361)
			(xy 103.032148 -223.660964) (xy 103.012553 -223.714992) (xy 102.998778 -223.740218) (xy 102.979474 -223.773746)
			(xy 103.095044 -223.889316) (xy 103.104786 -223.898435) (xy 103.127889 -223.911766) (xy 103.153654 -223.918668)
			(xy 103.180328 -223.91867) (xy 103.206094 -223.911773) (xy 103.2292 -223.898446) (xy 103.248072 -223.879597)
			(xy 103.255064 -223.868234) (xy 103.347774 -223.707198) (xy 103.340154 -223.685354) (xy 103.331357 -223.65878)
			(xy 103.321901 -223.603612) (xy 103.321358 -223.575626) (xy 103.321867 -223.549659) (xy 103.329992 -223.498364)
			(xy 103.34604 -223.448971) (xy 103.369618 -223.402697) (xy 103.400144 -223.360681) (xy 103.436867 -223.323958)
			(xy 103.478883 -223.293432) (xy 103.525157 -223.269854) (xy 103.57455 -223.253806) (xy 103.625845 -223.245681)
			(xy 103.677779 -223.245681) (xy 103.729074 -223.253806) (xy 103.778467 -223.269854) (xy 103.824741 -223.293432)
			(xy 103.866757 -223.323958) (xy 103.90348 -223.360681) (xy 103.934006 -223.402697) (xy 103.957584 -223.448971)
			(xy 103.973632 -223.498364) (xy 103.981757 -223.549659) (xy 103.982266 -223.575626) (xy 103.981796 -223.601076)
			(xy 103.981716 -223.601593) (xy 104.261921 -223.601593) (xy 104.261921 -223.549659) (xy 104.270046 -223.498364)
			(xy 104.286094 -223.448971) (xy 104.309672 -223.402697) (xy 104.340198 -223.360681) (xy 104.376921 -223.323958)
			(xy 104.418937 -223.293432) (xy 104.465211 -223.269854) (xy 104.514604 -223.253806) (xy 104.565899 -223.245681)
			(xy 104.617833 -223.245681) (xy 104.669128 -223.253806) (xy 104.718521 -223.269854) (xy 104.764795 -223.293432)
			(xy 104.806811 -223.323958) (xy 104.843534 -223.360681) (xy 104.87406 -223.402697) (xy 104.897638 -223.448971)
			(xy 104.913686 -223.498364) (xy 104.921811 -223.549659) (xy 104.92232 -223.575626) (xy 104.921811 -223.601593)
			(xy 104.913686 -223.652888) (xy 104.897638 -223.702281) (xy 104.87406 -223.748555) (xy 104.843534 -223.790571)
			(xy 104.806811 -223.827294) (xy 104.764795 -223.85782) (xy 104.718521 -223.881398) (xy 104.669128 -223.897446)
			(xy 104.617833 -223.905571) (xy 104.565899 -223.905571) (xy 104.514604 -223.897446) (xy 104.465211 -223.881398)
			(xy 104.418937 -223.85782) (xy 104.376921 -223.827294) (xy 104.340198 -223.790571) (xy 104.309672 -223.748555)
			(xy 104.286094 -223.702281) (xy 104.270046 -223.652888) (xy 104.261921 -223.601593) (xy 103.981716 -223.601593)
			(xy 103.973992 -223.651374) (xy 103.958572 -223.699882) (xy 103.935902 -223.745455) (xy 103.906515 -223.787015)
			(xy 103.871108 -223.823581) (xy 103.830514 -223.85429) (xy 103.785695 -223.878415) (xy 103.737708 -223.895387)
			(xy 103.712772 -223.900492) (xy 103.689658 -223.90481) (xy 103.486204 -224.257616) (xy 103.493824 -224.279714)
			(xy 103.494586 -224.281492) (xy 103.498396 -224.292668) (xy 103.62057 -224.414842) (xy 103.631038 -224.424623)
			(xy 103.65611 -224.438462) (xy 103.684037 -224.444805) (xy 103.712627 -224.443156) (xy 103.739638 -224.433643)
			(xy 103.762952 -224.417013) (xy 103.780741 -224.39457) (xy 103.791608 -224.368075) (xy 103.793544 -224.353882)
			(xy 103.796961 -224.327226) (xy 103.811317 -224.27544) (xy 103.833859 -224.226657) (xy 103.863995 -224.182164)
			(xy 103.90093 -224.14313) (xy 103.943693 -224.110585) (xy 103.991157 -224.085385) (xy 104.042072 -224.068194)
			(xy 104.095097 -224.059464) (xy 104.121966 -224.058988) (xy 104.147936 -224.059468) (xy 104.199237 -224.067589)
			(xy 104.248635 -224.083637) (xy 104.294914 -224.107215) (xy 104.336935 -224.137744) (xy 104.373661 -224.174471)
			(xy 104.404189 -224.216493) (xy 104.427766 -224.262772) (xy 104.443812 -224.312171) (xy 104.451932 -224.363472)
			(xy 104.45242 -224.389442) (xy 104.731312 -224.389442) (xy 104.731774 -224.363991) (xy 104.73956 -224.313687)
			(xy 104.754968 -224.265174) (xy 104.777636 -224.219597) (xy 104.807025 -224.178036) (xy 104.842441 -224.141475)
			(xy 104.883046 -224.110778) (xy 104.927878 -224.086672) (xy 104.975877 -224.069728) (xy 105.000806 -224.064576)
			(xy 105.023666 -224.060258) (xy 105.227374 -223.707198) (xy 105.219754 -223.685354) (xy 105.211031 -223.658761)
			(xy 105.201574 -223.603606) (xy 105.200958 -223.575626) (xy 105.201467 -223.549659) (xy 105.209592 -223.498364)
			(xy 105.22564 -223.448971) (xy 105.249218 -223.402697) (xy 105.279744 -223.360681) (xy 105.316467 -223.323958)
			(xy 105.358483 -223.293432) (xy 105.404757 -223.269854) (xy 105.45415 -223.253806) (xy 105.505445 -223.245681)
			(xy 105.557379 -223.245681) (xy 105.608674 -223.253806) (xy 105.658067 -223.269854) (xy 105.704341 -223.293432)
			(xy 105.746357 -223.323958) (xy 105.78308 -223.360681) (xy 105.813606 -223.402697) (xy 105.837184 -223.448971)
			(xy 105.853232 -223.498364) (xy 105.861357 -223.549659) (xy 105.861866 -223.575626) (xy 105.861393 -223.601077)
			(xy 105.861313 -223.601593) (xy 106.141521 -223.601593) (xy 106.141521 -223.549659) (xy 106.149646 -223.498364)
			(xy 106.165694 -223.448971) (xy 106.189272 -223.402697) (xy 106.219798 -223.360681) (xy 106.256521 -223.323958)
			(xy 106.298537 -223.293432) (xy 106.344811 -223.269854) (xy 106.394204 -223.253806) (xy 106.445499 -223.245681)
			(xy 106.497433 -223.245681) (xy 106.548728 -223.253806) (xy 106.598121 -223.269854) (xy 106.644395 -223.293432)
			(xy 106.686411 -223.323958) (xy 106.723134 -223.360681) (xy 106.75366 -223.402697) (xy 106.777238 -223.448971)
			(xy 106.793286 -223.498364) (xy 106.801411 -223.549659) (xy 106.80192 -223.575626) (xy 106.801411 -223.601593)
			(xy 106.793286 -223.652888) (xy 106.777238 -223.702281) (xy 106.75366 -223.748555) (xy 106.723134 -223.790571)
			(xy 106.686411 -223.827294) (xy 106.644395 -223.85782) (xy 106.598121 -223.881398) (xy 106.548728 -223.897446)
			(xy 106.497433 -223.905571) (xy 106.445499 -223.905571) (xy 106.394204 -223.897446) (xy 106.344811 -223.881398)
			(xy 106.298537 -223.85782) (xy 106.256521 -223.827294) (xy 106.219798 -223.790571) (xy 106.189272 -223.748555)
			(xy 106.165694 -223.702281) (xy 106.149646 -223.652888) (xy 106.141521 -223.601593) (xy 105.861313 -223.601593)
			(xy 105.853611 -223.651381) (xy 105.838206 -223.699896) (xy 105.815541 -223.745473) (xy 105.786153 -223.787035)
			(xy 105.750737 -223.823597) (xy 105.710133 -223.854293) (xy 105.6653 -223.878398) (xy 105.617301 -223.895341)
			(xy 105.592372 -223.900492) (xy 105.569258 -223.90481) (xy 105.365804 -224.257616) (xy 105.373424 -224.279714)
			(xy 105.382166 -224.306301) (xy 105.39161 -224.361461) (xy 105.39222 -224.389442) (xy 105.671112 -224.389442)
			(xy 105.671621 -224.363475) (xy 105.679746 -224.31218) (xy 105.695794 -224.262787) (xy 105.719372 -224.216513)
			(xy 105.749898 -224.174497) (xy 105.786621 -224.137774) (xy 105.828637 -224.107248) (xy 105.874911 -224.08367)
			(xy 105.924304 -224.067622) (xy 105.975599 -224.059497) (xy 106.027533 -224.059497) (xy 106.078828 -224.067622)
			(xy 106.128221 -224.08367) (xy 106.174495 -224.107248) (xy 106.216511 -224.137774) (xy 106.253234 -224.174497)
			(xy 106.28376 -224.216513) (xy 106.307338 -224.262787) (xy 106.323386 -224.31218) (xy 106.331511 -224.363475)
			(xy 106.33202 -224.389442) (xy 106.610912 -224.389442) (xy 106.611374 -224.363991) (xy 106.61916 -224.313687)
			(xy 106.634568 -224.265174) (xy 106.657236 -224.219597) (xy 106.686625 -224.178036) (xy 106.722041 -224.141475)
			(xy 106.762646 -224.110778) (xy 106.807478 -224.086672) (xy 106.855477 -224.069728) (xy 106.880406 -224.064576)
			(xy 106.903266 -224.060258) (xy 107.106974 -223.707198) (xy 107.099354 -223.685354) (xy 107.090631 -223.658761)
			(xy 107.081174 -223.603606) (xy 107.080558 -223.575626) (xy 107.081067 -223.549659) (xy 107.089192 -223.498364)
			(xy 107.10524 -223.448971) (xy 107.128818 -223.402697) (xy 107.159344 -223.360681) (xy 107.196067 -223.323958)
			(xy 107.238083 -223.293432) (xy 107.284357 -223.269854) (xy 107.33375 -223.253806) (xy 107.385045 -223.245681)
			(xy 107.436979 -223.245681) (xy 107.488274 -223.253806) (xy 107.537667 -223.269854) (xy 107.583941 -223.293432)
			(xy 107.625957 -223.323958) (xy 107.66268 -223.360681) (xy 107.693206 -223.402697) (xy 107.716784 -223.448971)
			(xy 107.732832 -223.498364) (xy 107.740957 -223.549659) (xy 107.741466 -223.575626) (xy 107.740993 -223.601077)
			(xy 107.740913 -223.601593) (xy 108.021121 -223.601593) (xy 108.021121 -223.549659) (xy 108.029246 -223.498364)
			(xy 108.045294 -223.448971) (xy 108.068872 -223.402697) (xy 108.099398 -223.360681) (xy 108.136121 -223.323958)
			(xy 108.178137 -223.293432) (xy 108.224411 -223.269854) (xy 108.273804 -223.253806) (xy 108.325099 -223.245681)
			(xy 108.377033 -223.245681) (xy 108.428328 -223.253806) (xy 108.477721 -223.269854) (xy 108.523995 -223.293432)
			(xy 108.566011 -223.323958) (xy 108.602734 -223.360681) (xy 108.63326 -223.402697) (xy 108.656838 -223.448971)
			(xy 108.672886 -223.498364) (xy 108.681011 -223.549659) (xy 108.68152 -223.575626) (xy 108.681011 -223.601593)
			(xy 108.672886 -223.652888) (xy 108.656838 -223.702281) (xy 108.63326 -223.748555) (xy 108.602734 -223.790571)
			(xy 108.566011 -223.827294) (xy 108.523995 -223.85782) (xy 108.477721 -223.881398) (xy 108.428328 -223.897446)
			(xy 108.377033 -223.905571) (xy 108.325099 -223.905571) (xy 108.273804 -223.897446) (xy 108.224411 -223.881398)
			(xy 108.178137 -223.85782) (xy 108.136121 -223.827294) (xy 108.099398 -223.790571) (xy 108.068872 -223.748555)
			(xy 108.045294 -223.702281) (xy 108.029246 -223.652888) (xy 108.021121 -223.601593) (xy 107.740913 -223.601593)
			(xy 107.733211 -223.651381) (xy 107.717806 -223.699896) (xy 107.695141 -223.745473) (xy 107.665753 -223.787035)
			(xy 107.630337 -223.823597) (xy 107.589733 -223.854293) (xy 107.5449 -223.878398) (xy 107.496901 -223.895341)
			(xy 107.471972 -223.900492) (xy 107.448858 -223.90481) (xy 107.245404 -224.257616) (xy 107.253024 -224.279714)
			(xy 107.261766 -224.306301) (xy 107.27121 -224.361461) (xy 107.27182 -224.389442) (xy 107.550712 -224.389442)
			(xy 107.551221 -224.363475) (xy 107.559346 -224.31218) (xy 107.575394 -224.262787) (xy 107.598972 -224.216513)
			(xy 107.629498 -224.174497) (xy 107.666221 -224.137774) (xy 107.708237 -224.107248) (xy 107.754511 -224.08367)
			(xy 107.803904 -224.067622) (xy 107.855199 -224.059497) (xy 107.907133 -224.059497) (xy 107.958428 -224.067622)
			(xy 108.007821 -224.08367) (xy 108.054095 -224.107248) (xy 108.096111 -224.137774) (xy 108.132834 -224.174497)
			(xy 108.16336 -224.216513) (xy 108.186938 -224.262787) (xy 108.202986 -224.31218) (xy 108.211111 -224.363475)
			(xy 108.21162 -224.389442) (xy 108.490512 -224.389442) (xy 108.490974 -224.363991) (xy 108.49876 -224.313687)
			(xy 108.514168 -224.265174) (xy 108.536836 -224.219597) (xy 108.566225 -224.178036) (xy 108.601641 -224.141475)
			(xy 108.642246 -224.110778) (xy 108.687078 -224.086672) (xy 108.735077 -224.069728) (xy 108.760006 -224.064576)
			(xy 108.782866 -224.060258) (xy 108.986574 -223.707198) (xy 108.978954 -223.685354) (xy 108.970231 -223.658761)
			(xy 108.960774 -223.603606) (xy 108.960158 -223.575626) (xy 108.960667 -223.549659) (xy 108.968792 -223.498364)
			(xy 108.98484 -223.448971) (xy 109.008418 -223.402697) (xy 109.038944 -223.360681) (xy 109.075667 -223.323958)
			(xy 109.117683 -223.293432) (xy 109.163957 -223.269854) (xy 109.21335 -223.253806) (xy 109.264645 -223.245681)
			(xy 109.316579 -223.245681) (xy 109.367874 -223.253806) (xy 109.417267 -223.269854) (xy 109.463541 -223.293432)
			(xy 109.505557 -223.323958) (xy 109.54228 -223.360681) (xy 109.572806 -223.402697) (xy 109.596384 -223.448971)
			(xy 109.612432 -223.498364) (xy 109.620557 -223.549659) (xy 109.621066 -223.575626) (xy 109.620593 -223.601077)
			(xy 109.620513 -223.601593) (xy 109.900721 -223.601593) (xy 109.900721 -223.549659) (xy 109.908846 -223.498364)
			(xy 109.924894 -223.448971) (xy 109.948472 -223.402697) (xy 109.978998 -223.360681) (xy 110.015721 -223.323958)
			(xy 110.057737 -223.293432) (xy 110.104011 -223.269854) (xy 110.153404 -223.253806) (xy 110.204699 -223.245681)
			(xy 110.256633 -223.245681) (xy 110.307928 -223.253806) (xy 110.357321 -223.269854) (xy 110.403595 -223.293432)
			(xy 110.445611 -223.323958) (xy 110.482334 -223.360681) (xy 110.51286 -223.402697) (xy 110.536438 -223.448971)
			(xy 110.552486 -223.498364) (xy 110.560611 -223.549659) (xy 110.56112 -223.575626) (xy 110.560611 -223.601593)
			(xy 110.552486 -223.652888) (xy 110.536438 -223.702281) (xy 110.51286 -223.748555) (xy 110.482334 -223.790571)
			(xy 110.445611 -223.827294) (xy 110.403595 -223.85782) (xy 110.357321 -223.881398) (xy 110.307928 -223.897446)
			(xy 110.256633 -223.905571) (xy 110.204699 -223.905571) (xy 110.153404 -223.897446) (xy 110.104011 -223.881398)
			(xy 110.057737 -223.85782) (xy 110.015721 -223.827294) (xy 109.978998 -223.790571) (xy 109.948472 -223.748555)
			(xy 109.924894 -223.702281) (xy 109.908846 -223.652888) (xy 109.900721 -223.601593) (xy 109.620513 -223.601593)
			(xy 109.612811 -223.651381) (xy 109.597406 -223.699896) (xy 109.574741 -223.745473) (xy 109.545353 -223.787035)
			(xy 109.509937 -223.823597) (xy 109.469333 -223.854293) (xy 109.4245 -223.878398) (xy 109.376501 -223.895341)
			(xy 109.351572 -223.900492) (xy 109.328458 -223.90481) (xy 109.125004 -224.257616) (xy 109.132624 -224.279714)
			(xy 109.141366 -224.306301) (xy 109.15081 -224.361461) (xy 109.15142 -224.389442) (xy 109.430312 -224.389442)
			(xy 109.430821 -224.363475) (xy 109.438946 -224.31218) (xy 109.454994 -224.262787) (xy 109.478572 -224.216513)
			(xy 109.509098 -224.174497) (xy 109.545821 -224.137774) (xy 109.587837 -224.107248) (xy 109.634111 -224.08367)
			(xy 109.683504 -224.067622) (xy 109.734799 -224.059497) (xy 109.786733 -224.059497) (xy 109.838028 -224.067622)
			(xy 109.887421 -224.08367) (xy 109.933695 -224.107248) (xy 109.975711 -224.137774) (xy 110.012434 -224.174497)
			(xy 110.04296 -224.216513) (xy 110.066538 -224.262787) (xy 110.082586 -224.31218) (xy 110.090711 -224.363475)
			(xy 110.09122 -224.389442) (xy 110.370112 -224.389442) (xy 110.370574 -224.363991) (xy 110.37836 -224.313687)
			(xy 110.393768 -224.265174) (xy 110.416436 -224.219597) (xy 110.445825 -224.178036) (xy 110.481241 -224.141475)
			(xy 110.521846 -224.110778) (xy 110.566678 -224.086672) (xy 110.614677 -224.069728) (xy 110.639606 -224.064576)
			(xy 110.662466 -224.060258) (xy 110.866174 -223.707198) (xy 110.858554 -223.685354) (xy 110.849831 -223.658761)
			(xy 110.840374 -223.603606) (xy 110.839758 -223.575626) (xy 110.840267 -223.549659) (xy 110.848392 -223.498364)
			(xy 110.86444 -223.448971) (xy 110.888018 -223.402697) (xy 110.918544 -223.360681) (xy 110.955267 -223.323958)
			(xy 110.997283 -223.293432) (xy 111.043557 -223.269854) (xy 111.09295 -223.253806) (xy 111.144245 -223.245681)
			(xy 111.196179 -223.245681) (xy 111.247474 -223.253806) (xy 111.296867 -223.269854) (xy 111.343141 -223.293432)
			(xy 111.385157 -223.323958) (xy 111.42188 -223.360681) (xy 111.452406 -223.402697) (xy 111.475984 -223.448971)
			(xy 111.492032 -223.498364) (xy 111.500157 -223.549659) (xy 111.500666 -223.575626) (xy 111.500193 -223.601077)
			(xy 111.500113 -223.601593) (xy 111.780321 -223.601593) (xy 111.780321 -223.549659) (xy 111.788446 -223.498364)
			(xy 111.804494 -223.448971) (xy 111.828072 -223.402697) (xy 111.858598 -223.360681) (xy 111.895321 -223.323958)
			(xy 111.937337 -223.293432) (xy 111.983611 -223.269854) (xy 112.033004 -223.253806) (xy 112.084299 -223.245681)
			(xy 112.136233 -223.245681) (xy 112.187528 -223.253806) (xy 112.236921 -223.269854) (xy 112.283195 -223.293432)
			(xy 112.325211 -223.323958) (xy 112.361934 -223.360681) (xy 112.39246 -223.402697) (xy 112.416038 -223.448971)
			(xy 112.432086 -223.498364) (xy 112.440211 -223.549659) (xy 112.44072 -223.575626) (xy 112.440211 -223.601593)
			(xy 112.432086 -223.652888) (xy 112.416038 -223.702281) (xy 112.39246 -223.748555) (xy 112.361934 -223.790571)
			(xy 112.325211 -223.827294) (xy 112.283195 -223.85782) (xy 112.236921 -223.881398) (xy 112.187528 -223.897446)
			(xy 112.136233 -223.905571) (xy 112.084299 -223.905571) (xy 112.033004 -223.897446) (xy 111.983611 -223.881398)
			(xy 111.937337 -223.85782) (xy 111.895321 -223.827294) (xy 111.858598 -223.790571) (xy 111.828072 -223.748555)
			(xy 111.804494 -223.702281) (xy 111.788446 -223.652888) (xy 111.780321 -223.601593) (xy 111.500113 -223.601593)
			(xy 111.492411 -223.651381) (xy 111.477006 -223.699896) (xy 111.454341 -223.745473) (xy 111.424953 -223.787035)
			(xy 111.389537 -223.823597) (xy 111.348933 -223.854293) (xy 111.3041 -223.878398) (xy 111.256101 -223.895341)
			(xy 111.231172 -223.900492) (xy 111.208058 -223.90481) (xy 111.004604 -224.257616) (xy 111.012224 -224.279714)
			(xy 111.020966 -224.306301) (xy 111.03041 -224.361461) (xy 111.03102 -224.389442) (xy 111.309912 -224.389442)
			(xy 111.310421 -224.363475) (xy 111.318546 -224.31218) (xy 111.334594 -224.262787) (xy 111.358172 -224.216513)
			(xy 111.388698 -224.174497) (xy 111.425421 -224.137774) (xy 111.467437 -224.107248) (xy 111.513711 -224.08367)
			(xy 111.563104 -224.067622) (xy 111.614399 -224.059497) (xy 111.666333 -224.059497) (xy 111.717628 -224.067622)
			(xy 111.767021 -224.08367) (xy 111.813295 -224.107248) (xy 111.855311 -224.137774) (xy 111.892034 -224.174497)
			(xy 111.92256 -224.216513) (xy 111.946138 -224.262787) (xy 111.962186 -224.31218) (xy 111.970311 -224.363475)
			(xy 111.97082 -224.389442) (xy 112.249712 -224.389442) (xy 112.250174 -224.363991) (xy 112.25796 -224.313687)
			(xy 112.273368 -224.265174) (xy 112.296036 -224.219597) (xy 112.325425 -224.178036) (xy 112.360841 -224.141475)
			(xy 112.401446 -224.110778) (xy 112.446278 -224.086672) (xy 112.494277 -224.069728) (xy 112.519206 -224.064576)
			(xy 112.542066 -224.060258) (xy 112.745774 -223.707198) (xy 112.738154 -223.685354) (xy 112.729431 -223.658761)
			(xy 112.719974 -223.603606) (xy 112.719358 -223.575626) (xy 112.719867 -223.549659) (xy 112.727992 -223.498364)
			(xy 112.74404 -223.448971) (xy 112.767618 -223.402697) (xy 112.798144 -223.360681) (xy 112.834867 -223.323958)
			(xy 112.876883 -223.293432) (xy 112.923157 -223.269854) (xy 112.97255 -223.253806) (xy 113.023845 -223.245681)
			(xy 113.075779 -223.245681) (xy 113.127074 -223.253806) (xy 113.176467 -223.269854) (xy 113.222741 -223.293432)
			(xy 113.264757 -223.323958) (xy 113.30148 -223.360681) (xy 113.332006 -223.402697) (xy 113.355584 -223.448971)
			(xy 113.371632 -223.498364) (xy 113.379757 -223.549659) (xy 113.380266 -223.575626) (xy 113.379793 -223.601077)
			(xy 113.379713 -223.601593) (xy 113.659921 -223.601593) (xy 113.659921 -223.549659) (xy 113.668046 -223.498364)
			(xy 113.684094 -223.448971) (xy 113.707672 -223.402697) (xy 113.738198 -223.360681) (xy 113.774921 -223.323958)
			(xy 113.816937 -223.293432) (xy 113.863211 -223.269854) (xy 113.912604 -223.253806) (xy 113.963899 -223.245681)
			(xy 114.015833 -223.245681) (xy 114.067128 -223.253806) (xy 114.116521 -223.269854) (xy 114.162795 -223.293432)
			(xy 114.204811 -223.323958) (xy 114.241534 -223.360681) (xy 114.27206 -223.402697) (xy 114.295638 -223.448971)
			(xy 114.311686 -223.498364) (xy 114.319811 -223.549659) (xy 114.32032 -223.575626) (xy 114.319811 -223.601593)
			(xy 114.311686 -223.652888) (xy 114.295638 -223.702281) (xy 114.27206 -223.748555) (xy 114.241534 -223.790571)
			(xy 114.204811 -223.827294) (xy 114.162795 -223.85782) (xy 114.116521 -223.881398) (xy 114.067128 -223.897446)
			(xy 114.015833 -223.905571) (xy 113.963899 -223.905571) (xy 113.912604 -223.897446) (xy 113.863211 -223.881398)
			(xy 113.816937 -223.85782) (xy 113.774921 -223.827294) (xy 113.738198 -223.790571) (xy 113.707672 -223.748555)
			(xy 113.684094 -223.702281) (xy 113.668046 -223.652888) (xy 113.659921 -223.601593) (xy 113.379713 -223.601593)
			(xy 113.372011 -223.651381) (xy 113.356606 -223.699896) (xy 113.333941 -223.745473) (xy 113.304553 -223.787035)
			(xy 113.269137 -223.823597) (xy 113.228533 -223.854293) (xy 113.1837 -223.878398) (xy 113.135701 -223.895341)
			(xy 113.110772 -223.900492) (xy 113.087658 -223.90481) (xy 112.884204 -224.257616) (xy 112.891824 -224.279714)
			(xy 112.900566 -224.306301) (xy 112.91001 -224.361461) (xy 112.91062 -224.389442) (xy 113.189512 -224.389442)
			(xy 113.190021 -224.363475) (xy 113.198146 -224.31218) (xy 113.214194 -224.262787) (xy 113.237772 -224.216513)
			(xy 113.268298 -224.174497) (xy 113.305021 -224.137774) (xy 113.347037 -224.107248) (xy 113.393311 -224.08367)
			(xy 113.442704 -224.067622) (xy 113.493999 -224.059497) (xy 113.545933 -224.059497) (xy 113.597228 -224.067622)
			(xy 113.646621 -224.08367) (xy 113.692895 -224.107248) (xy 113.734911 -224.137774) (xy 113.771634 -224.174497)
			(xy 113.80216 -224.216513) (xy 113.825738 -224.262787) (xy 113.841786 -224.31218) (xy 113.849911 -224.363475)
			(xy 113.85042 -224.389442) (xy 114.129312 -224.389442) (xy 114.129774 -224.363991) (xy 114.13756 -224.313687)
			(xy 114.152968 -224.265174) (xy 114.175636 -224.219597) (xy 114.205025 -224.178036) (xy 114.240441 -224.141475)
			(xy 114.281046 -224.110778) (xy 114.325878 -224.086672) (xy 114.373877 -224.069728) (xy 114.398806 -224.064576)
			(xy 114.421666 -224.060258) (xy 114.625628 -223.706944) (xy 114.617754 -223.6851) (xy 114.609091 -223.658565)
			(xy 114.599773 -223.603534) (xy 114.599212 -223.575626) (xy 114.599721 -223.549659) (xy 114.607846 -223.498364)
			(xy 114.623894 -223.448971) (xy 114.647472 -223.402697) (xy 114.677998 -223.360681) (xy 114.714721 -223.323958)
			(xy 114.756737 -223.293432) (xy 114.803011 -223.269854) (xy 114.852404 -223.253806) (xy 114.903699 -223.245681)
			(xy 114.955633 -223.245681) (xy 115.006928 -223.253806) (xy 115.056321 -223.269854) (xy 115.102595 -223.293432)
			(xy 115.144611 -223.323958) (xy 115.181334 -223.360681) (xy 115.21186 -223.402697) (xy 115.235438 -223.448971)
			(xy 115.251486 -223.498364) (xy 115.259611 -223.549659) (xy 115.26012 -223.575626) (xy 115.259646 -223.601088)
			(xy 115.259568 -223.601593) (xy 115.539521 -223.601593) (xy 115.539521 -223.549659) (xy 115.547646 -223.498364)
			(xy 115.563694 -223.448971) (xy 115.587272 -223.402697) (xy 115.617798 -223.360681) (xy 115.654521 -223.323958)
			(xy 115.696537 -223.293432) (xy 115.742811 -223.269854) (xy 115.792204 -223.253806) (xy 115.843499 -223.245681)
			(xy 115.895433 -223.245681) (xy 115.946728 -223.253806) (xy 115.996121 -223.269854) (xy 116.042395 -223.293432)
			(xy 116.084411 -223.323958) (xy 116.121134 -223.360681) (xy 116.15166 -223.402697) (xy 116.175238 -223.448971)
			(xy 116.191286 -223.498364) (xy 116.199411 -223.549659) (xy 116.19992 -223.575626) (xy 116.199411 -223.601593)
			(xy 116.191286 -223.652888) (xy 116.175238 -223.702281) (xy 116.15166 -223.748555) (xy 116.121134 -223.790571)
			(xy 116.084411 -223.827294) (xy 116.042395 -223.85782) (xy 115.996121 -223.881398) (xy 115.946728 -223.897446)
			(xy 115.895433 -223.905571) (xy 115.843499 -223.905571) (xy 115.792204 -223.897446) (xy 115.742811 -223.881398)
			(xy 115.696537 -223.85782) (xy 115.654521 -223.827294) (xy 115.617798 -223.790571) (xy 115.587272 -223.748555)
			(xy 115.563694 -223.702281) (xy 115.547646 -223.652888) (xy 115.539521 -223.601593) (xy 115.259568 -223.601593)
			(xy 115.251844 -223.651411) (xy 115.236413 -223.699941) (xy 115.213719 -223.745529) (xy 115.184299 -223.787095)
			(xy 115.14885 -223.823656) (xy 115.108212 -223.854344) (xy 115.063346 -223.878434) (xy 115.015315 -223.895354)
			(xy 114.990372 -223.900492) (xy 114.967258 -223.90481) (xy 114.763804 -224.257616) (xy 114.771424 -224.279714)
			(xy 114.780166 -224.306301) (xy 114.78961 -224.361461) (xy 114.79022 -224.389442) (xy 115.069112 -224.389442)
			(xy 115.069621 -224.363475) (xy 115.077746 -224.31218) (xy 115.093794 -224.262787) (xy 115.117372 -224.216513)
			(xy 115.147898 -224.174497) (xy 115.184621 -224.137774) (xy 115.226637 -224.107248) (xy 115.272911 -224.08367)
			(xy 115.322304 -224.067622) (xy 115.373599 -224.059497) (xy 115.425533 -224.059497) (xy 115.476828 -224.067622)
			(xy 115.526221 -224.08367) (xy 115.572495 -224.107248) (xy 115.614511 -224.137774) (xy 115.651234 -224.174497)
			(xy 115.68176 -224.216513) (xy 115.705338 -224.262787) (xy 115.721386 -224.31218) (xy 115.729511 -224.363475)
			(xy 115.73002 -224.389442) (xy 116.008912 -224.389442) (xy 116.009374 -224.363991) (xy 116.01716 -224.313687)
			(xy 116.032568 -224.265174) (xy 116.055236 -224.219597) (xy 116.084625 -224.178036) (xy 116.120041 -224.141475)
			(xy 116.160646 -224.110778) (xy 116.205478 -224.086672) (xy 116.253477 -224.069728) (xy 116.278406 -224.064576)
			(xy 116.301266 -224.060258) (xy 116.504974 -223.707198) (xy 116.497354 -223.685354) (xy 116.488631 -223.658761)
			(xy 116.479174 -223.603606) (xy 116.478558 -223.575626) (xy 116.479067 -223.549659) (xy 116.487192 -223.498364)
			(xy 116.50324 -223.448971) (xy 116.526818 -223.402697) (xy 116.557344 -223.360681) (xy 116.594067 -223.323958)
			(xy 116.636083 -223.293432) (xy 116.682357 -223.269854) (xy 116.73175 -223.253806) (xy 116.783045 -223.245681)
			(xy 116.834979 -223.245681) (xy 116.886274 -223.253806) (xy 116.935667 -223.269854) (xy 116.981941 -223.293432)
			(xy 117.023957 -223.323958) (xy 117.06068 -223.360681) (xy 117.091206 -223.402697) (xy 117.114784 -223.448971)
			(xy 117.130832 -223.498364) (xy 117.138957 -223.549659) (xy 117.139466 -223.575626) (xy 117.138993 -223.601077)
			(xy 117.138913 -223.601593) (xy 117.419121 -223.601593) (xy 117.419121 -223.549659) (xy 117.427246 -223.498364)
			(xy 117.443294 -223.448971) (xy 117.466872 -223.402697) (xy 117.497398 -223.360681) (xy 117.534121 -223.323958)
			(xy 117.576137 -223.293432) (xy 117.622411 -223.269854) (xy 117.671804 -223.253806) (xy 117.723099 -223.245681)
			(xy 117.775033 -223.245681) (xy 117.826328 -223.253806) (xy 117.875721 -223.269854) (xy 117.921995 -223.293432)
			(xy 117.964011 -223.323958) (xy 118.000734 -223.360681) (xy 118.03126 -223.402697) (xy 118.054838 -223.448971)
			(xy 118.070886 -223.498364) (xy 118.079011 -223.549659) (xy 118.07952 -223.575626) (xy 118.079011 -223.601593)
			(xy 118.070886 -223.652888) (xy 118.054838 -223.702281) (xy 118.03126 -223.748555) (xy 118.000734 -223.790571)
			(xy 117.964011 -223.827294) (xy 117.921995 -223.85782) (xy 117.875721 -223.881398) (xy 117.826328 -223.897446)
			(xy 117.775033 -223.905571) (xy 117.723099 -223.905571) (xy 117.671804 -223.897446) (xy 117.622411 -223.881398)
			(xy 117.576137 -223.85782) (xy 117.534121 -223.827294) (xy 117.497398 -223.790571) (xy 117.466872 -223.748555)
			(xy 117.443294 -223.702281) (xy 117.427246 -223.652888) (xy 117.419121 -223.601593) (xy 117.138913 -223.601593)
			(xy 117.131211 -223.651381) (xy 117.115806 -223.699896) (xy 117.093141 -223.745473) (xy 117.063753 -223.787035)
			(xy 117.028337 -223.823597) (xy 116.987733 -223.854293) (xy 116.9429 -223.878398) (xy 116.894901 -223.895341)
			(xy 116.869972 -223.900492) (xy 116.846858 -223.90481) (xy 116.643404 -224.257616) (xy 116.651024 -224.279714)
			(xy 116.659766 -224.306301) (xy 116.66921 -224.361461) (xy 116.66982 -224.389442) (xy 116.948712 -224.389442)
			(xy 116.949221 -224.363475) (xy 116.957346 -224.31218) (xy 116.973394 -224.262787) (xy 116.996972 -224.216513)
			(xy 117.027498 -224.174497) (xy 117.064221 -224.137774) (xy 117.106237 -224.107248) (xy 117.152511 -224.08367)
			(xy 117.201904 -224.067622) (xy 117.253199 -224.059497) (xy 117.305133 -224.059497) (xy 117.356428 -224.067622)
			(xy 117.405821 -224.08367) (xy 117.452095 -224.107248) (xy 117.494111 -224.137774) (xy 117.530834 -224.174497)
			(xy 117.56136 -224.216513) (xy 117.584938 -224.262787) (xy 117.600986 -224.31218) (xy 117.609111 -224.363475)
			(xy 117.60962 -224.389442) (xy 117.888512 -224.389442) (xy 117.888974 -224.363991) (xy 117.89676 -224.313687)
			(xy 117.912168 -224.265174) (xy 117.934836 -224.219597) (xy 117.964225 -224.178036) (xy 117.999641 -224.141475)
			(xy 118.040246 -224.110778) (xy 118.085078 -224.086672) (xy 118.133077 -224.069728) (xy 118.158006 -224.064576)
			(xy 118.180866 -224.060258) (xy 118.384574 -223.707198) (xy 118.376954 -223.685354) (xy 118.368231 -223.658761)
			(xy 118.358774 -223.603606) (xy 118.358158 -223.575626) (xy 118.358667 -223.549659) (xy 118.366792 -223.498364)
			(xy 118.38284 -223.448971) (xy 118.406418 -223.402697) (xy 118.436944 -223.360681) (xy 118.473667 -223.323958)
			(xy 118.515683 -223.293432) (xy 118.561957 -223.269854) (xy 118.61135 -223.253806) (xy 118.662645 -223.245681)
			(xy 118.714579 -223.245681) (xy 118.765874 -223.253806) (xy 118.815267 -223.269854) (xy 118.861541 -223.293432)
			(xy 118.903557 -223.323958) (xy 118.94028 -223.360681) (xy 118.970806 -223.402697) (xy 118.994384 -223.448971)
			(xy 119.010432 -223.498364) (xy 119.018557 -223.549659) (xy 119.019066 -223.575626) (xy 119.018593 -223.601077)
			(xy 119.018513 -223.601593) (xy 119.298721 -223.601593) (xy 119.298721 -223.549659) (xy 119.306846 -223.498364)
			(xy 119.322894 -223.448971) (xy 119.346472 -223.402697) (xy 119.376998 -223.360681) (xy 119.413721 -223.323958)
			(xy 119.455737 -223.293432) (xy 119.502011 -223.269854) (xy 119.551404 -223.253806) (xy 119.602699 -223.245681)
			(xy 119.654633 -223.245681) (xy 119.705928 -223.253806) (xy 119.755321 -223.269854) (xy 119.801595 -223.293432)
			(xy 119.843611 -223.323958) (xy 119.880334 -223.360681) (xy 119.91086 -223.402697) (xy 119.934438 -223.448971)
			(xy 119.950486 -223.498364) (xy 119.958611 -223.549659) (xy 119.95912 -223.575626) (xy 119.958611 -223.601593)
			(xy 119.950486 -223.652888) (xy 119.934438 -223.702281) (xy 119.91086 -223.748555) (xy 119.880334 -223.790571)
			(xy 119.843611 -223.827294) (xy 119.801595 -223.85782) (xy 119.755321 -223.881398) (xy 119.705928 -223.897446)
			(xy 119.654633 -223.905571) (xy 119.602699 -223.905571) (xy 119.551404 -223.897446) (xy 119.502011 -223.881398)
			(xy 119.455737 -223.85782) (xy 119.413721 -223.827294) (xy 119.376998 -223.790571) (xy 119.346472 -223.748555)
			(xy 119.322894 -223.702281) (xy 119.306846 -223.652888) (xy 119.298721 -223.601593) (xy 119.018513 -223.601593)
			(xy 119.010811 -223.651381) (xy 118.995406 -223.699896) (xy 118.972741 -223.745473) (xy 118.943353 -223.787035)
			(xy 118.907937 -223.823597) (xy 118.867333 -223.854293) (xy 118.8225 -223.878398) (xy 118.774501 -223.895341)
			(xy 118.749572 -223.900492) (xy 118.726458 -223.90481) (xy 118.523004 -224.257616) (xy 118.530624 -224.279714)
			(xy 118.539366 -224.306301) (xy 118.54881 -224.361461) (xy 118.54942 -224.389442) (xy 118.828312 -224.389442)
			(xy 118.828821 -224.363475) (xy 118.836946 -224.31218) (xy 118.852994 -224.262787) (xy 118.876572 -224.216513)
			(xy 118.907098 -224.174497) (xy 118.943821 -224.137774) (xy 118.985837 -224.107248) (xy 119.032111 -224.08367)
			(xy 119.081504 -224.067622) (xy 119.132799 -224.059497) (xy 119.184733 -224.059497) (xy 119.236028 -224.067622)
			(xy 119.285421 -224.08367) (xy 119.331695 -224.107248) (xy 119.373711 -224.137774) (xy 119.410434 -224.174497)
			(xy 119.44096 -224.216513) (xy 119.464538 -224.262787) (xy 119.480586 -224.31218) (xy 119.488711 -224.363475)
			(xy 119.48922 -224.389442) (xy 119.768112 -224.389442) (xy 119.768574 -224.363991) (xy 119.77636 -224.313687)
			(xy 119.791768 -224.265174) (xy 119.814436 -224.219597) (xy 119.843825 -224.178036) (xy 119.879241 -224.141475)
			(xy 119.919846 -224.110778) (xy 119.964678 -224.086672) (xy 120.012677 -224.069728) (xy 120.037606 -224.064576)
			(xy 120.060466 -224.060258) (xy 120.264174 -223.707198) (xy 120.256554 -223.685354) (xy 120.247831 -223.658761)
			(xy 120.238374 -223.603606) (xy 120.237758 -223.575626) (xy 120.238267 -223.549659) (xy 120.246392 -223.498364)
			(xy 120.26244 -223.448971) (xy 120.286018 -223.402697) (xy 120.316544 -223.360681) (xy 120.353267 -223.323958)
			(xy 120.395283 -223.293432) (xy 120.441557 -223.269854) (xy 120.49095 -223.253806) (xy 120.542245 -223.245681)
			(xy 120.594179 -223.245681) (xy 120.645474 -223.253806) (xy 120.694867 -223.269854) (xy 120.741141 -223.293432)
			(xy 120.783157 -223.323958) (xy 120.81988 -223.360681) (xy 120.850406 -223.402697) (xy 120.873984 -223.448971)
			(xy 120.890032 -223.498364) (xy 120.898157 -223.549659) (xy 120.898666 -223.575626) (xy 120.898193 -223.601077)
			(xy 120.898113 -223.601593) (xy 121.178321 -223.601593) (xy 121.178321 -223.549659) (xy 121.186446 -223.498364)
			(xy 121.202494 -223.448971) (xy 121.226072 -223.402697) (xy 121.256598 -223.360681) (xy 121.293321 -223.323958)
			(xy 121.335337 -223.293432) (xy 121.381611 -223.269854) (xy 121.431004 -223.253806) (xy 121.482299 -223.245681)
			(xy 121.534233 -223.245681) (xy 121.585528 -223.253806) (xy 121.634921 -223.269854) (xy 121.681195 -223.293432)
			(xy 121.723211 -223.323958) (xy 121.759934 -223.360681) (xy 121.79046 -223.402697) (xy 121.814038 -223.448971)
			(xy 121.830086 -223.498364) (xy 121.838211 -223.549659) (xy 121.83872 -223.575626) (xy 121.838211 -223.601593)
			(xy 121.830086 -223.652888) (xy 121.814038 -223.702281) (xy 121.79046 -223.748555) (xy 121.759934 -223.790571)
			(xy 121.723211 -223.827294) (xy 121.681195 -223.85782) (xy 121.634921 -223.881398) (xy 121.585528 -223.897446)
			(xy 121.534233 -223.905571) (xy 121.482299 -223.905571) (xy 121.431004 -223.897446) (xy 121.381611 -223.881398)
			(xy 121.335337 -223.85782) (xy 121.293321 -223.827294) (xy 121.256598 -223.790571) (xy 121.226072 -223.748555)
			(xy 121.202494 -223.702281) (xy 121.186446 -223.652888) (xy 121.178321 -223.601593) (xy 120.898113 -223.601593)
			(xy 120.890411 -223.651381) (xy 120.875006 -223.699896) (xy 120.852341 -223.745473) (xy 120.822953 -223.787035)
			(xy 120.787537 -223.823597) (xy 120.746933 -223.854293) (xy 120.7021 -223.878398) (xy 120.654101 -223.895341)
			(xy 120.629172 -223.900492) (xy 120.606058 -223.90481) (xy 120.402604 -224.257616) (xy 120.410224 -224.279714)
			(xy 120.418966 -224.306301) (xy 120.42841 -224.361461) (xy 120.42902 -224.389442) (xy 120.707912 -224.389442)
			(xy 120.708421 -224.363475) (xy 120.716546 -224.31218) (xy 120.732594 -224.262787) (xy 120.756172 -224.216513)
			(xy 120.786698 -224.174497) (xy 120.823421 -224.137774) (xy 120.865437 -224.107248) (xy 120.911711 -224.08367)
			(xy 120.961104 -224.067622) (xy 121.012399 -224.059497) (xy 121.064333 -224.059497) (xy 121.115628 -224.067622)
			(xy 121.165021 -224.08367) (xy 121.211295 -224.107248) (xy 121.253311 -224.137774) (xy 121.290034 -224.174497)
			(xy 121.32056 -224.216513) (xy 121.344138 -224.262787) (xy 121.360186 -224.31218) (xy 121.368311 -224.363475)
			(xy 121.36882 -224.389442) (xy 121.647712 -224.389442) (xy 121.648174 -224.363991) (xy 121.65596 -224.313687)
			(xy 121.671368 -224.265174) (xy 121.694036 -224.219597) (xy 121.723425 -224.178036) (xy 121.758841 -224.141475)
			(xy 121.799446 -224.110778) (xy 121.844278 -224.086672) (xy 121.892277 -224.069728) (xy 121.917206 -224.064576)
			(xy 121.940066 -224.060258) (xy 122.143774 -223.707198) (xy 122.136154 -223.685354) (xy 122.127431 -223.658761)
			(xy 122.117974 -223.603606) (xy 122.117358 -223.575626) (xy 122.117867 -223.549659) (xy 122.125992 -223.498364)
			(xy 122.14204 -223.448971) (xy 122.165618 -223.402697) (xy 122.196144 -223.360681) (xy 122.232867 -223.323958)
			(xy 122.274883 -223.293432) (xy 122.321157 -223.269854) (xy 122.37055 -223.253806) (xy 122.421845 -223.245681)
			(xy 122.473779 -223.245681) (xy 122.525074 -223.253806) (xy 122.574467 -223.269854) (xy 122.620741 -223.293432)
			(xy 122.662757 -223.323958) (xy 122.69948 -223.360681) (xy 122.730006 -223.402697) (xy 122.753584 -223.448971)
			(xy 122.769632 -223.498364) (xy 122.777757 -223.549659) (xy 122.778266 -223.575626) (xy 122.777793 -223.601077)
			(xy 122.777713 -223.601593) (xy 123.057921 -223.601593) (xy 123.057921 -223.549659) (xy 123.066046 -223.498364)
			(xy 123.082094 -223.448971) (xy 123.105672 -223.402697) (xy 123.136198 -223.360681) (xy 123.172921 -223.323958)
			(xy 123.214937 -223.293432) (xy 123.261211 -223.269854) (xy 123.310604 -223.253806) (xy 123.361899 -223.245681)
			(xy 123.413833 -223.245681) (xy 123.465128 -223.253806) (xy 123.514521 -223.269854) (xy 123.560795 -223.293432)
			(xy 123.602811 -223.323958) (xy 123.639534 -223.360681) (xy 123.67006 -223.402697) (xy 123.693638 -223.448971)
			(xy 123.709686 -223.498364) (xy 123.717811 -223.549659) (xy 123.71832 -223.575626) (xy 123.717811 -223.601593)
			(xy 123.709686 -223.652888) (xy 123.693638 -223.702281) (xy 123.67006 -223.748555) (xy 123.639534 -223.790571)
			(xy 123.602811 -223.827294) (xy 123.560795 -223.85782) (xy 123.514521 -223.881398) (xy 123.465128 -223.897446)
			(xy 123.413833 -223.905571) (xy 123.361899 -223.905571) (xy 123.310604 -223.897446) (xy 123.261211 -223.881398)
			(xy 123.214937 -223.85782) (xy 123.172921 -223.827294) (xy 123.136198 -223.790571) (xy 123.105672 -223.748555)
			(xy 123.082094 -223.702281) (xy 123.066046 -223.652888) (xy 123.057921 -223.601593) (xy 122.777713 -223.601593)
			(xy 122.770011 -223.651381) (xy 122.754606 -223.699896) (xy 122.731941 -223.745473) (xy 122.702553 -223.787035)
			(xy 122.667137 -223.823597) (xy 122.626533 -223.854293) (xy 122.5817 -223.878398) (xy 122.533701 -223.895341)
			(xy 122.508772 -223.900492) (xy 122.485658 -223.90481) (xy 122.282204 -224.257616) (xy 122.289824 -224.279714)
			(xy 122.298566 -224.306301) (xy 122.30801 -224.361461) (xy 122.30862 -224.389442) (xy 122.587512 -224.389442)
			(xy 122.588021 -224.363475) (xy 122.596146 -224.31218) (xy 122.612194 -224.262787) (xy 122.635772 -224.216513)
			(xy 122.666298 -224.174497) (xy 122.703021 -224.137774) (xy 122.745037 -224.107248) (xy 122.791311 -224.08367)
			(xy 122.840704 -224.067622) (xy 122.891999 -224.059497) (xy 122.943933 -224.059497) (xy 122.995228 -224.067622)
			(xy 123.044621 -224.08367) (xy 123.090895 -224.107248) (xy 123.132911 -224.137774) (xy 123.169634 -224.174497)
			(xy 123.20016 -224.216513) (xy 123.223738 -224.262787) (xy 123.239786 -224.31218) (xy 123.247911 -224.363475)
			(xy 123.24842 -224.389442) (xy 123.527312 -224.389442) (xy 123.527774 -224.363991) (xy 123.53556 -224.313687)
			(xy 123.550968 -224.265174) (xy 123.573636 -224.219597) (xy 123.603025 -224.178036) (xy 123.638441 -224.141475)
			(xy 123.679046 -224.110778) (xy 123.723878 -224.086672) (xy 123.771877 -224.069728) (xy 123.796806 -224.064576)
			(xy 123.819666 -224.060258) (xy 124.023374 -223.707198) (xy 124.015754 -223.685354) (xy 124.007031 -223.658761)
			(xy 123.997574 -223.603606) (xy 123.996958 -223.575626) (xy 123.997467 -223.549659) (xy 124.005592 -223.498364)
			(xy 124.02164 -223.448971) (xy 124.045218 -223.402697) (xy 124.075744 -223.360681) (xy 124.112467 -223.323958)
			(xy 124.154483 -223.293432) (xy 124.200757 -223.269854) (xy 124.25015 -223.253806) (xy 124.301445 -223.245681)
			(xy 124.353379 -223.245681) (xy 124.404674 -223.253806) (xy 124.454067 -223.269854) (xy 124.500341 -223.293432)
			(xy 124.542357 -223.323958) (xy 124.57908 -223.360681) (xy 124.609606 -223.402697) (xy 124.633184 -223.448971)
			(xy 124.649232 -223.498364) (xy 124.657357 -223.549659) (xy 124.657866 -223.575626) (xy 124.657393 -223.601077)
			(xy 124.657313 -223.601593) (xy 124.937521 -223.601593) (xy 124.937521 -223.549659) (xy 124.945646 -223.498364)
			(xy 124.961694 -223.448971) (xy 124.985272 -223.402697) (xy 125.015798 -223.360681) (xy 125.052521 -223.323958)
			(xy 125.094537 -223.293432) (xy 125.140811 -223.269854) (xy 125.190204 -223.253806) (xy 125.241499 -223.245681)
			(xy 125.293433 -223.245681) (xy 125.344728 -223.253806) (xy 125.394121 -223.269854) (xy 125.440395 -223.293432)
			(xy 125.482411 -223.323958) (xy 125.519134 -223.360681) (xy 125.54966 -223.402697) (xy 125.573238 -223.448971)
			(xy 125.589286 -223.498364) (xy 125.597411 -223.549659) (xy 125.59792 -223.575626) (xy 125.597411 -223.601593)
			(xy 125.589286 -223.652888) (xy 125.573238 -223.702281) (xy 125.54966 -223.748555) (xy 125.519134 -223.790571)
			(xy 125.482411 -223.827294) (xy 125.440395 -223.85782) (xy 125.394121 -223.881398) (xy 125.344728 -223.897446)
			(xy 125.293433 -223.905571) (xy 125.241499 -223.905571) (xy 125.190204 -223.897446) (xy 125.140811 -223.881398)
			(xy 125.094537 -223.85782) (xy 125.052521 -223.827294) (xy 125.015798 -223.790571) (xy 124.985272 -223.748555)
			(xy 124.961694 -223.702281) (xy 124.945646 -223.652888) (xy 124.937521 -223.601593) (xy 124.657313 -223.601593)
			(xy 124.649611 -223.651381) (xy 124.634206 -223.699896) (xy 124.611541 -223.745473) (xy 124.582153 -223.787035)
			(xy 124.546737 -223.823597) (xy 124.506133 -223.854293) (xy 124.4613 -223.878398) (xy 124.413301 -223.895341)
			(xy 124.388372 -223.900492) (xy 124.365258 -223.90481) (xy 124.161804 -224.257616) (xy 124.169424 -224.279714)
			(xy 124.178166 -224.306301) (xy 124.18761 -224.361461) (xy 124.18822 -224.389442) (xy 124.467112 -224.389442)
			(xy 124.467621 -224.363475) (xy 124.475746 -224.31218) (xy 124.491794 -224.262787) (xy 124.515372 -224.216513)
			(xy 124.545898 -224.174497) (xy 124.582621 -224.137774) (xy 124.624637 -224.107248) (xy 124.670911 -224.08367)
			(xy 124.720304 -224.067622) (xy 124.771599 -224.059497) (xy 124.823533 -224.059497) (xy 124.874828 -224.067622)
			(xy 124.924221 -224.08367) (xy 124.970495 -224.107248) (xy 125.012511 -224.137774) (xy 125.049234 -224.174497)
			(xy 125.07976 -224.216513) (xy 125.103338 -224.262787) (xy 125.119386 -224.31218) (xy 125.127511 -224.363475)
			(xy 125.12802 -224.389442) (xy 125.406912 -224.389442) (xy 125.407374 -224.363991) (xy 125.41516 -224.313687)
			(xy 125.430568 -224.265174) (xy 125.453236 -224.219597) (xy 125.482625 -224.178036) (xy 125.518041 -224.141475)
			(xy 125.558646 -224.110778) (xy 125.603478 -224.086672) (xy 125.651477 -224.069728) (xy 125.676406 -224.064576)
			(xy 125.699266 -224.060258) (xy 125.902974 -223.707198) (xy 125.895354 -223.685354) (xy 125.886631 -223.658761)
			(xy 125.877174 -223.603606) (xy 125.876558 -223.575626) (xy 125.877067 -223.549659) (xy 125.885192 -223.498364)
			(xy 125.90124 -223.448971) (xy 125.924818 -223.402697) (xy 125.955344 -223.360681) (xy 125.992067 -223.323958)
			(xy 126.034083 -223.293432) (xy 126.080357 -223.269854) (xy 126.12975 -223.253806) (xy 126.181045 -223.245681)
			(xy 126.232979 -223.245681) (xy 126.284274 -223.253806) (xy 126.333667 -223.269854) (xy 126.379941 -223.293432)
			(xy 126.421957 -223.323958) (xy 126.45868 -223.360681) (xy 126.489206 -223.402697) (xy 126.512784 -223.448971)
			(xy 126.528832 -223.498364) (xy 126.536957 -223.549659) (xy 126.537466 -223.575626) (xy 126.536993 -223.601077)
			(xy 126.536913 -223.601593) (xy 126.817121 -223.601593) (xy 126.817121 -223.549659) (xy 126.825246 -223.498364)
			(xy 126.841294 -223.448971) (xy 126.864872 -223.402697) (xy 126.895398 -223.360681) (xy 126.932121 -223.323958)
			(xy 126.974137 -223.293432) (xy 127.020411 -223.269854) (xy 127.069804 -223.253806) (xy 127.121099 -223.245681)
			(xy 127.173033 -223.245681) (xy 127.224328 -223.253806) (xy 127.273721 -223.269854) (xy 127.319995 -223.293432)
			(xy 127.362011 -223.323958) (xy 127.398734 -223.360681) (xy 127.42926 -223.402697) (xy 127.452838 -223.448971)
			(xy 127.468886 -223.498364) (xy 127.477011 -223.549659) (xy 127.47752 -223.575626) (xy 127.477011 -223.601593)
			(xy 127.468886 -223.652888) (xy 127.452838 -223.702281) (xy 127.42926 -223.748555) (xy 127.398734 -223.790571)
			(xy 127.362011 -223.827294) (xy 127.319995 -223.85782) (xy 127.273721 -223.881398) (xy 127.224328 -223.897446)
			(xy 127.173033 -223.905571) (xy 127.121099 -223.905571) (xy 127.069804 -223.897446) (xy 127.020411 -223.881398)
			(xy 126.974137 -223.85782) (xy 126.932121 -223.827294) (xy 126.895398 -223.790571) (xy 126.864872 -223.748555)
			(xy 126.841294 -223.702281) (xy 126.825246 -223.652888) (xy 126.817121 -223.601593) (xy 126.536913 -223.601593)
			(xy 126.529211 -223.651381) (xy 126.513806 -223.699896) (xy 126.491141 -223.745473) (xy 126.461753 -223.787035)
			(xy 126.426337 -223.823597) (xy 126.385733 -223.854293) (xy 126.3409 -223.878398) (xy 126.292901 -223.895341)
			(xy 126.267972 -223.900492) (xy 126.244858 -223.90481) (xy 126.041404 -224.257616) (xy 126.049024 -224.279714)
			(xy 126.057766 -224.306301) (xy 126.06721 -224.361461) (xy 126.06782 -224.389442) (xy 126.346712 -224.389442)
			(xy 126.347221 -224.363475) (xy 126.355346 -224.31218) (xy 126.371394 -224.262787) (xy 126.394972 -224.216513)
			(xy 126.425498 -224.174497) (xy 126.462221 -224.137774) (xy 126.504237 -224.107248) (xy 126.550511 -224.08367)
			(xy 126.599904 -224.067622) (xy 126.651199 -224.059497) (xy 126.703133 -224.059497) (xy 126.754428 -224.067622)
			(xy 126.803821 -224.08367) (xy 126.850095 -224.107248) (xy 126.892111 -224.137774) (xy 126.928834 -224.174497)
			(xy 126.95936 -224.216513) (xy 126.982938 -224.262787) (xy 126.998986 -224.31218) (xy 127.007111 -224.363475)
			(xy 127.00762 -224.389442) (xy 127.007077 -224.417428) (xy 126.99762 -224.472596) (xy 126.988824 -224.49917)
			(xy 126.981204 -224.521268) (xy 127.184912 -224.874074) (xy 127.207772 -224.878392) (xy 127.232704 -224.883512)
			(xy 127.28069 -224.900483) (xy 127.325509 -224.924607) (xy 127.366102 -224.955314) (xy 127.401509 -224.991878)
			(xy 127.430896 -225.033436) (xy 127.453568 -225.079006) (xy 127.468989 -225.127512) (xy 127.476794 -225.177809)
			(xy 127.477266 -225.203258) (xy 127.476757 -225.229225) (xy 127.468632 -225.28052) (xy 127.452584 -225.329913)
			(xy 127.429006 -225.376187) (xy 127.39848 -225.418203) (xy 127.361757 -225.454926) (xy 127.319741 -225.485452)
			(xy 127.273467 -225.50903) (xy 127.224074 -225.525078) (xy 127.172779 -225.533203) (xy 127.120845 -225.533203)
			(xy 127.06955 -225.525078) (xy 127.020157 -225.50903) (xy 126.973883 -225.485452) (xy 126.931867 -225.454926)
			(xy 126.895144 -225.418203) (xy 126.864618 -225.376187) (xy 126.84104 -225.329913) (xy 126.824992 -225.28052)
			(xy 126.816867 -225.229225) (xy 126.816358 -225.203258) (xy 126.816897 -225.175271) (xy 126.826356 -225.120104)
			(xy 126.835154 -225.09353) (xy 126.842774 -225.071432) (xy 126.639066 -224.718626) (xy 126.616206 -224.714308)
			(xy 126.591286 -224.709131) (xy 126.5433 -224.692171) (xy 126.49848 -224.668057) (xy 126.457885 -224.637359)
			(xy 126.422475 -224.600802) (xy 126.393086 -224.55925) (xy 126.370412 -224.513684) (xy 126.35499 -224.465182)
			(xy 126.347184 -224.414889) (xy 126.346712 -224.389442) (xy 126.06782 -224.389442) (xy 126.067311 -224.415409)
			(xy 126.059186 -224.466704) (xy 126.043138 -224.516097) (xy 126.01956 -224.562371) (xy 125.989034 -224.604387)
			(xy 125.952311 -224.64111) (xy 125.910295 -224.671636) (xy 125.864021 -224.695214) (xy 125.814628 -224.711262)
			(xy 125.763333 -224.719387) (xy 125.711399 -224.719387) (xy 125.660104 -224.711262) (xy 125.610711 -224.695214)
			(xy 125.564437 -224.671636) (xy 125.522421 -224.64111) (xy 125.485698 -224.604387) (xy 125.455172 -224.562371)
			(xy 125.431594 -224.516097) (xy 125.415546 -224.466704) (xy 125.407421 -224.415409) (xy 125.406912 -224.389442)
			(xy 125.12802 -224.389442) (xy 125.127477 -224.417428) (xy 125.11802 -224.472596) (xy 125.109224 -224.49917)
			(xy 125.101604 -224.521268) (xy 125.305312 -224.874074) (xy 125.328172 -224.878392) (xy 125.353104 -224.883512)
			(xy 125.40109 -224.900483) (xy 125.445909 -224.924607) (xy 125.486502 -224.955314) (xy 125.521909 -224.991878)
			(xy 125.551296 -225.033436) (xy 125.573968 -225.079006) (xy 125.589389 -225.127512) (xy 125.597194 -225.177809)
			(xy 125.597666 -225.203258) (xy 125.597157 -225.229225) (xy 125.589032 -225.28052) (xy 125.572984 -225.329913)
			(xy 125.549406 -225.376187) (xy 125.51888 -225.418203) (xy 125.482157 -225.454926) (xy 125.440141 -225.485452)
			(xy 125.393867 -225.50903) (xy 125.344474 -225.525078) (xy 125.293179 -225.533203) (xy 125.241245 -225.533203)
			(xy 125.18995 -225.525078) (xy 125.140557 -225.50903) (xy 125.094283 -225.485452) (xy 125.052267 -225.454926)
			(xy 125.015544 -225.418203) (xy 124.985018 -225.376187) (xy 124.96144 -225.329913) (xy 124.945392 -225.28052)
			(xy 124.937267 -225.229225) (xy 124.936758 -225.203258) (xy 124.937297 -225.175271) (xy 124.946756 -225.120104)
			(xy 124.955554 -225.09353) (xy 124.963174 -225.071432) (xy 124.759466 -224.718626) (xy 124.736606 -224.714308)
			(xy 124.711686 -224.709131) (xy 124.6637 -224.692171) (xy 124.61888 -224.668057) (xy 124.578285 -224.637359)
			(xy 124.542875 -224.600802) (xy 124.513486 -224.55925) (xy 124.490812 -224.513684) (xy 124.47539 -224.465182)
			(xy 124.467584 -224.414889) (xy 124.467112 -224.389442) (xy 124.18822 -224.389442) (xy 124.187711 -224.415409)
			(xy 124.179586 -224.466704) (xy 124.163538 -224.516097) (xy 124.13996 -224.562371) (xy 124.109434 -224.604387)
			(xy 124.072711 -224.64111) (xy 124.030695 -224.671636) (xy 123.984421 -224.695214) (xy 123.935028 -224.711262)
			(xy 123.883733 -224.719387) (xy 123.831799 -224.719387) (xy 123.780504 -224.711262) (xy 123.731111 -224.695214)
			(xy 123.684837 -224.671636) (xy 123.642821 -224.64111) (xy 123.606098 -224.604387) (xy 123.575572 -224.562371)
			(xy 123.551994 -224.516097) (xy 123.535946 -224.466704) (xy 123.527821 -224.415409) (xy 123.527312 -224.389442)
			(xy 123.24842 -224.389442) (xy 123.247877 -224.417428) (xy 123.23842 -224.472596) (xy 123.229624 -224.49917)
			(xy 123.222004 -224.521268) (xy 123.425712 -224.874074) (xy 123.448572 -224.878392) (xy 123.473504 -224.883512)
			(xy 123.52149 -224.900483) (xy 123.566309 -224.924607) (xy 123.606902 -224.955314) (xy 123.642309 -224.991878)
			(xy 123.671696 -225.033436) (xy 123.694368 -225.079006) (xy 123.709789 -225.127512) (xy 123.717594 -225.177809)
			(xy 123.718066 -225.203258) (xy 123.717557 -225.229225) (xy 123.709432 -225.28052) (xy 123.693384 -225.329913)
			(xy 123.669806 -225.376187) (xy 123.63928 -225.418203) (xy 123.602557 -225.454926) (xy 123.560541 -225.485452)
			(xy 123.514267 -225.50903) (xy 123.464874 -225.525078) (xy 123.413579 -225.533203) (xy 123.361645 -225.533203)
			(xy 123.31035 -225.525078) (xy 123.260957 -225.50903) (xy 123.214683 -225.485452) (xy 123.172667 -225.454926)
			(xy 123.135944 -225.418203) (xy 123.105418 -225.376187) (xy 123.08184 -225.329913) (xy 123.065792 -225.28052)
			(xy 123.057667 -225.229225) (xy 123.057158 -225.203258) (xy 123.057697 -225.175271) (xy 123.067156 -225.120104)
			(xy 123.075954 -225.09353) (xy 123.083574 -225.071432) (xy 122.879866 -224.718626) (xy 122.857006 -224.714308)
			(xy 122.832086 -224.709131) (xy 122.7841 -224.692171) (xy 122.73928 -224.668057) (xy 122.698685 -224.637359)
			(xy 122.663275 -224.600802) (xy 122.633886 -224.55925) (xy 122.611212 -224.513684) (xy 122.59579 -224.465182)
			(xy 122.587984 -224.414889) (xy 122.587512 -224.389442) (xy 122.30862 -224.389442) (xy 122.308111 -224.415409)
			(xy 122.299986 -224.466704) (xy 122.283938 -224.516097) (xy 122.26036 -224.562371) (xy 122.229834 -224.604387)
			(xy 122.193111 -224.64111) (xy 122.151095 -224.671636) (xy 122.104821 -224.695214) (xy 122.055428 -224.711262)
			(xy 122.004133 -224.719387) (xy 121.952199 -224.719387) (xy 121.900904 -224.711262) (xy 121.851511 -224.695214)
			(xy 121.805237 -224.671636) (xy 121.763221 -224.64111) (xy 121.726498 -224.604387) (xy 121.695972 -224.562371)
			(xy 121.672394 -224.516097) (xy 121.656346 -224.466704) (xy 121.648221 -224.415409) (xy 121.647712 -224.389442)
			(xy 121.36882 -224.389442) (xy 121.368277 -224.417428) (xy 121.35882 -224.472596) (xy 121.350024 -224.49917)
			(xy 121.342404 -224.521268) (xy 121.546112 -224.874074) (xy 121.568972 -224.878392) (xy 121.593904 -224.883512)
			(xy 121.64189 -224.900483) (xy 121.686709 -224.924607) (xy 121.727302 -224.955314) (xy 121.762709 -224.991878)
			(xy 121.792096 -225.033436) (xy 121.814768 -225.079006) (xy 121.830189 -225.127512) (xy 121.837994 -225.177809)
			(xy 121.838466 -225.203258) (xy 121.837957 -225.229225) (xy 121.829832 -225.28052) (xy 121.813784 -225.329913)
			(xy 121.790206 -225.376187) (xy 121.75968 -225.418203) (xy 121.722957 -225.454926) (xy 121.680941 -225.485452)
			(xy 121.634667 -225.50903) (xy 121.585274 -225.525078) (xy 121.533979 -225.533203) (xy 121.482045 -225.533203)
			(xy 121.43075 -225.525078) (xy 121.381357 -225.50903) (xy 121.335083 -225.485452) (xy 121.293067 -225.454926)
			(xy 121.256344 -225.418203) (xy 121.225818 -225.376187) (xy 121.20224 -225.329913) (xy 121.186192 -225.28052)
			(xy 121.178067 -225.229225) (xy 121.177558 -225.203258) (xy 121.178097 -225.175271) (xy 121.187556 -225.120104)
			(xy 121.196354 -225.09353) (xy 121.203974 -225.071432) (xy 121.000266 -224.718626) (xy 120.977406 -224.714308)
			(xy 120.952486 -224.709131) (xy 120.9045 -224.692171) (xy 120.85968 -224.668057) (xy 120.819085 -224.637359)
			(xy 120.783675 -224.600802) (xy 120.754286 -224.55925) (xy 120.731612 -224.513684) (xy 120.71619 -224.465182)
			(xy 120.708384 -224.414889) (xy 120.707912 -224.389442) (xy 120.42902 -224.389442) (xy 120.428511 -224.415409)
			(xy 120.420386 -224.466704) (xy 120.404338 -224.516097) (xy 120.38076 -224.562371) (xy 120.350234 -224.604387)
			(xy 120.313511 -224.64111) (xy 120.271495 -224.671636) (xy 120.225221 -224.695214) (xy 120.175828 -224.711262)
			(xy 120.124533 -224.719387) (xy 120.072599 -224.719387) (xy 120.021304 -224.711262) (xy 119.971911 -224.695214)
			(xy 119.925637 -224.671636) (xy 119.883621 -224.64111) (xy 119.846898 -224.604387) (xy 119.816372 -224.562371)
			(xy 119.792794 -224.516097) (xy 119.776746 -224.466704) (xy 119.768621 -224.415409) (xy 119.768112 -224.389442)
			(xy 119.48922 -224.389442) (xy 119.488677 -224.417428) (xy 119.47922 -224.472596) (xy 119.470424 -224.49917)
			(xy 119.462804 -224.521268) (xy 119.666512 -224.874074) (xy 119.689372 -224.878392) (xy 119.714304 -224.883512)
			(xy 119.76229 -224.900483) (xy 119.807109 -224.924607) (xy 119.847702 -224.955314) (xy 119.883109 -224.991878)
			(xy 119.912496 -225.033436) (xy 119.935168 -225.079006) (xy 119.950589 -225.127512) (xy 119.958394 -225.177809)
			(xy 119.958866 -225.203258) (xy 119.958357 -225.229225) (xy 119.950232 -225.28052) (xy 119.934184 -225.329913)
			(xy 119.910606 -225.376187) (xy 119.88008 -225.418203) (xy 119.843357 -225.454926) (xy 119.801341 -225.485452)
			(xy 119.755067 -225.50903) (xy 119.705674 -225.525078) (xy 119.654379 -225.533203) (xy 119.602445 -225.533203)
			(xy 119.55115 -225.525078) (xy 119.501757 -225.50903) (xy 119.455483 -225.485452) (xy 119.413467 -225.454926)
			(xy 119.376744 -225.418203) (xy 119.346218 -225.376187) (xy 119.32264 -225.329913) (xy 119.306592 -225.28052)
			(xy 119.298467 -225.229225) (xy 119.297958 -225.203258) (xy 119.298497 -225.175271) (xy 119.307956 -225.120104)
			(xy 119.316754 -225.09353) (xy 119.324374 -225.071432) (xy 119.120666 -224.718626) (xy 119.097806 -224.714308)
			(xy 119.072886 -224.709131) (xy 119.0249 -224.692171) (xy 118.98008 -224.668057) (xy 118.939485 -224.637359)
			(xy 118.904075 -224.600802) (xy 118.874686 -224.55925) (xy 118.852012 -224.513684) (xy 118.83659 -224.465182)
			(xy 118.828784 -224.414889) (xy 118.828312 -224.389442) (xy 118.54942 -224.389442) (xy 118.548911 -224.415409)
			(xy 118.540786 -224.466704) (xy 118.524738 -224.516097) (xy 118.50116 -224.562371) (xy 118.470634 -224.604387)
			(xy 118.433911 -224.64111) (xy 118.391895 -224.671636) (xy 118.345621 -224.695214) (xy 118.296228 -224.711262)
			(xy 118.244933 -224.719387) (xy 118.192999 -224.719387) (xy 118.141704 -224.711262) (xy 118.092311 -224.695214)
			(xy 118.046037 -224.671636) (xy 118.004021 -224.64111) (xy 117.967298 -224.604387) (xy 117.936772 -224.562371)
			(xy 117.913194 -224.516097) (xy 117.897146 -224.466704) (xy 117.889021 -224.415409) (xy 117.888512 -224.389442)
			(xy 117.60962 -224.389442) (xy 117.609077 -224.417428) (xy 117.59962 -224.472596) (xy 117.590824 -224.49917)
			(xy 117.583204 -224.521268) (xy 117.786912 -224.874074) (xy 117.809772 -224.878392) (xy 117.834704 -224.883512)
			(xy 117.88269 -224.900483) (xy 117.927509 -224.924607) (xy 117.968102 -224.955314) (xy 118.003509 -224.991878)
			(xy 118.032896 -225.033436) (xy 118.055568 -225.079006) (xy 118.070989 -225.127512) (xy 118.078794 -225.177809)
			(xy 118.079266 -225.203258) (xy 118.078757 -225.229225) (xy 118.070632 -225.28052) (xy 118.054584 -225.329913)
			(xy 118.031006 -225.376187) (xy 118.00048 -225.418203) (xy 117.963757 -225.454926) (xy 117.921741 -225.485452)
			(xy 117.875467 -225.50903) (xy 117.826074 -225.525078) (xy 117.774779 -225.533203) (xy 117.722845 -225.533203)
			(xy 117.67155 -225.525078) (xy 117.622157 -225.50903) (xy 117.575883 -225.485452) (xy 117.533867 -225.454926)
			(xy 117.497144 -225.418203) (xy 117.466618 -225.376187) (xy 117.44304 -225.329913) (xy 117.426992 -225.28052)
			(xy 117.418867 -225.229225) (xy 117.418358 -225.203258) (xy 117.418897 -225.175271) (xy 117.428356 -225.120104)
			(xy 117.437154 -225.09353) (xy 117.444774 -225.071432) (xy 117.241066 -224.718626) (xy 117.218206 -224.714308)
			(xy 117.193286 -224.709131) (xy 117.1453 -224.692171) (xy 117.10048 -224.668057) (xy 117.059885 -224.637359)
			(xy 117.024475 -224.600802) (xy 116.995086 -224.55925) (xy 116.972412 -224.513684) (xy 116.95699 -224.465182)
			(xy 116.949184 -224.414889) (xy 116.948712 -224.389442) (xy 116.66982 -224.389442) (xy 116.669311 -224.415409)
			(xy 116.661186 -224.466704) (xy 116.645138 -224.516097) (xy 116.62156 -224.562371) (xy 116.591034 -224.604387)
			(xy 116.554311 -224.64111) (xy 116.512295 -224.671636) (xy 116.466021 -224.695214) (xy 116.416628 -224.711262)
			(xy 116.365333 -224.719387) (xy 116.313399 -224.719387) (xy 116.262104 -224.711262) (xy 116.212711 -224.695214)
			(xy 116.166437 -224.671636) (xy 116.124421 -224.64111) (xy 116.087698 -224.604387) (xy 116.057172 -224.562371)
			(xy 116.033594 -224.516097) (xy 116.017546 -224.466704) (xy 116.009421 -224.415409) (xy 116.008912 -224.389442)
			(xy 115.73002 -224.389442) (xy 115.729477 -224.417428) (xy 115.72002 -224.472596) (xy 115.711224 -224.49917)
			(xy 115.703604 -224.521268) (xy 115.907312 -224.874074) (xy 115.930172 -224.878392) (xy 115.955104 -224.883512)
			(xy 116.00309 -224.900483) (xy 116.047909 -224.924607) (xy 116.088502 -224.955314) (xy 116.123909 -224.991878)
			(xy 116.153296 -225.033436) (xy 116.175968 -225.079006) (xy 116.191389 -225.127512) (xy 116.199194 -225.177809)
			(xy 116.199666 -225.203258) (xy 116.199157 -225.229225) (xy 116.191032 -225.28052) (xy 116.174984 -225.329913)
			(xy 116.151406 -225.376187) (xy 116.12088 -225.418203) (xy 116.084157 -225.454926) (xy 116.042141 -225.485452)
			(xy 115.995867 -225.50903) (xy 115.946474 -225.525078) (xy 115.895179 -225.533203) (xy 115.843245 -225.533203)
			(xy 115.79195 -225.525078) (xy 115.742557 -225.50903) (xy 115.696283 -225.485452) (xy 115.654267 -225.454926)
			(xy 115.617544 -225.418203) (xy 115.587018 -225.376187) (xy 115.56344 -225.329913) (xy 115.547392 -225.28052)
			(xy 115.539267 -225.229225) (xy 115.538758 -225.203258) (xy 115.539297 -225.175271) (xy 115.548756 -225.120104)
			(xy 115.557554 -225.09353) (xy 115.565174 -225.071432) (xy 115.361466 -224.718626) (xy 115.338606 -224.714308)
			(xy 115.313686 -224.709131) (xy 115.2657 -224.692171) (xy 115.22088 -224.668057) (xy 115.180285 -224.637359)
			(xy 115.144875 -224.600802) (xy 115.115486 -224.55925) (xy 115.092812 -224.513684) (xy 115.07739 -224.465182)
			(xy 115.069584 -224.414889) (xy 115.069112 -224.389442) (xy 114.79022 -224.389442) (xy 114.789711 -224.415409)
			(xy 114.781586 -224.466704) (xy 114.765538 -224.516097) (xy 114.74196 -224.562371) (xy 114.711434 -224.604387)
			(xy 114.674711 -224.64111) (xy 114.632695 -224.671636) (xy 114.586421 -224.695214) (xy 114.537028 -224.711262)
			(xy 114.485733 -224.719387) (xy 114.433799 -224.719387) (xy 114.382504 -224.711262) (xy 114.333111 -224.695214)
			(xy 114.286837 -224.671636) (xy 114.244821 -224.64111) (xy 114.208098 -224.604387) (xy 114.177572 -224.562371)
			(xy 114.153994 -224.516097) (xy 114.137946 -224.466704) (xy 114.129821 -224.415409) (xy 114.129312 -224.389442)
			(xy 113.85042 -224.389442) (xy 113.849877 -224.417428) (xy 113.84042 -224.472596) (xy 113.831624 -224.49917)
			(xy 113.824004 -224.521268) (xy 114.027712 -224.874074) (xy 114.050572 -224.878392) (xy 114.075504 -224.883512)
			(xy 114.12349 -224.900483) (xy 114.168309 -224.924607) (xy 114.208902 -224.955314) (xy 114.244309 -224.991878)
			(xy 114.273696 -225.033436) (xy 114.296368 -225.079006) (xy 114.311789 -225.127512) (xy 114.319594 -225.177809)
			(xy 114.320066 -225.203258) (xy 114.319557 -225.229225) (xy 114.311432 -225.28052) (xy 114.295384 -225.329913)
			(xy 114.271806 -225.376187) (xy 114.24128 -225.418203) (xy 114.204557 -225.454926) (xy 114.162541 -225.485452)
			(xy 114.116267 -225.50903) (xy 114.066874 -225.525078) (xy 114.015579 -225.533203) (xy 113.963645 -225.533203)
			(xy 113.91235 -225.525078) (xy 113.862957 -225.50903) (xy 113.816683 -225.485452) (xy 113.774667 -225.454926)
			(xy 113.737944 -225.418203) (xy 113.707418 -225.376187) (xy 113.68384 -225.329913) (xy 113.667792 -225.28052)
			(xy 113.659667 -225.229225) (xy 113.659158 -225.203258) (xy 113.659697 -225.175271) (xy 113.669156 -225.120104)
			(xy 113.677954 -225.09353) (xy 113.685574 -225.071432) (xy 113.481866 -224.718626) (xy 113.459006 -224.714308)
			(xy 113.434086 -224.709131) (xy 113.3861 -224.692171) (xy 113.34128 -224.668057) (xy 113.300685 -224.637359)
			(xy 113.265275 -224.600802) (xy 113.235886 -224.55925) (xy 113.213212 -224.513684) (xy 113.19779 -224.465182)
			(xy 113.189984 -224.414889) (xy 113.189512 -224.389442) (xy 112.91062 -224.389442) (xy 112.910111 -224.415409)
			(xy 112.901986 -224.466704) (xy 112.885938 -224.516097) (xy 112.86236 -224.562371) (xy 112.831834 -224.604387)
			(xy 112.795111 -224.64111) (xy 112.753095 -224.671636) (xy 112.706821 -224.695214) (xy 112.657428 -224.711262)
			(xy 112.606133 -224.719387) (xy 112.554199 -224.719387) (xy 112.502904 -224.711262) (xy 112.453511 -224.695214)
			(xy 112.407237 -224.671636) (xy 112.365221 -224.64111) (xy 112.328498 -224.604387) (xy 112.297972 -224.562371)
			(xy 112.274394 -224.516097) (xy 112.258346 -224.466704) (xy 112.250221 -224.415409) (xy 112.249712 -224.389442)
			(xy 111.97082 -224.389442) (xy 111.970277 -224.417428) (xy 111.96082 -224.472596) (xy 111.952024 -224.49917)
			(xy 111.944404 -224.521268) (xy 112.148112 -224.874074) (xy 112.170972 -224.878392) (xy 112.195904 -224.883512)
			(xy 112.24389 -224.900483) (xy 112.288709 -224.924607) (xy 112.329302 -224.955314) (xy 112.364709 -224.991878)
			(xy 112.394096 -225.033436) (xy 112.416768 -225.079006) (xy 112.432189 -225.127512) (xy 112.439994 -225.177809)
			(xy 112.440466 -225.203258) (xy 112.439957 -225.229225) (xy 112.431832 -225.28052) (xy 112.415784 -225.329913)
			(xy 112.392206 -225.376187) (xy 112.36168 -225.418203) (xy 112.324957 -225.454926) (xy 112.282941 -225.485452)
			(xy 112.236667 -225.50903) (xy 112.187274 -225.525078) (xy 112.135979 -225.533203) (xy 112.084045 -225.533203)
			(xy 112.03275 -225.525078) (xy 111.983357 -225.50903) (xy 111.937083 -225.485452) (xy 111.895067 -225.454926)
			(xy 111.858344 -225.418203) (xy 111.827818 -225.376187) (xy 111.80424 -225.329913) (xy 111.788192 -225.28052)
			(xy 111.780067 -225.229225) (xy 111.779558 -225.203258) (xy 111.780097 -225.175271) (xy 111.789556 -225.120104)
			(xy 111.798354 -225.09353) (xy 111.805974 -225.071432) (xy 111.602266 -224.718626) (xy 111.579406 -224.714308)
			(xy 111.554486 -224.709131) (xy 111.5065 -224.692171) (xy 111.46168 -224.668057) (xy 111.421085 -224.637359)
			(xy 111.385675 -224.600802) (xy 111.356286 -224.55925) (xy 111.333612 -224.513684) (xy 111.31819 -224.465182)
			(xy 111.310384 -224.414889) (xy 111.309912 -224.389442) (xy 111.03102 -224.389442) (xy 111.030511 -224.415409)
			(xy 111.022386 -224.466704) (xy 111.006338 -224.516097) (xy 110.98276 -224.562371) (xy 110.952234 -224.604387)
			(xy 110.915511 -224.64111) (xy 110.873495 -224.671636) (xy 110.827221 -224.695214) (xy 110.777828 -224.711262)
			(xy 110.726533 -224.719387) (xy 110.674599 -224.719387) (xy 110.623304 -224.711262) (xy 110.573911 -224.695214)
			(xy 110.527637 -224.671636) (xy 110.485621 -224.64111) (xy 110.448898 -224.604387) (xy 110.418372 -224.562371)
			(xy 110.394794 -224.516097) (xy 110.378746 -224.466704) (xy 110.370621 -224.415409) (xy 110.370112 -224.389442)
			(xy 110.09122 -224.389442) (xy 110.090677 -224.417428) (xy 110.08122 -224.472596) (xy 110.072424 -224.49917)
			(xy 110.064804 -224.521268) (xy 110.268512 -224.874074) (xy 110.291372 -224.878392) (xy 110.316304 -224.883512)
			(xy 110.36429 -224.900483) (xy 110.409109 -224.924607) (xy 110.449702 -224.955314) (xy 110.485109 -224.991878)
			(xy 110.514496 -225.033436) (xy 110.537168 -225.079006) (xy 110.552589 -225.127512) (xy 110.560394 -225.177809)
			(xy 110.560866 -225.203258) (xy 110.560357 -225.229225) (xy 110.840267 -225.229225) (xy 110.840267 -225.177291)
			(xy 110.848392 -225.125996) (xy 110.86444 -225.076603) (xy 110.888018 -225.030329) (xy 110.918544 -224.988313)
			(xy 110.955267 -224.95159) (xy 110.997283 -224.921064) (xy 111.043557 -224.897486) (xy 111.09295 -224.881438)
			(xy 111.144245 -224.873313) (xy 111.196179 -224.873313) (xy 111.247474 -224.881438) (xy 111.296867 -224.897486)
			(xy 111.343141 -224.921064) (xy 111.385157 -224.95159) (xy 111.42188 -224.988313) (xy 111.452406 -225.030329)
			(xy 111.475984 -225.076603) (xy 111.492032 -225.125996) (xy 111.500157 -225.177291) (xy 111.500666 -225.203258)
			(xy 111.500157 -225.229225) (xy 111.492032 -225.28052) (xy 111.475984 -225.329913) (xy 111.452406 -225.376187)
			(xy 111.42188 -225.418203) (xy 111.385157 -225.454926) (xy 111.343141 -225.485452) (xy 111.296867 -225.50903)
			(xy 111.247474 -225.525078) (xy 111.196179 -225.533203) (xy 111.144245 -225.533203) (xy 111.09295 -225.525078)
			(xy 111.043557 -225.50903) (xy 110.997283 -225.485452) (xy 110.955267 -225.454926) (xy 110.918544 -225.418203)
			(xy 110.888018 -225.376187) (xy 110.86444 -225.329913) (xy 110.848392 -225.28052) (xy 110.840267 -225.229225)
			(xy 110.560357 -225.229225) (xy 110.552232 -225.28052) (xy 110.536184 -225.329913) (xy 110.512606 -225.376187)
			(xy 110.48208 -225.418203) (xy 110.445357 -225.454926) (xy 110.403341 -225.485452) (xy 110.357067 -225.50903)
			(xy 110.307674 -225.525078) (xy 110.256379 -225.533203) (xy 110.204445 -225.533203) (xy 110.15315 -225.525078)
			(xy 110.103757 -225.50903) (xy 110.057483 -225.485452) (xy 110.015467 -225.454926) (xy 109.978744 -225.418203)
			(xy 109.948218 -225.376187) (xy 109.92464 -225.329913) (xy 109.908592 -225.28052) (xy 109.900467 -225.229225)
			(xy 109.899958 -225.203258) (xy 109.900497 -225.175271) (xy 109.909956 -225.120104) (xy 109.918754 -225.09353)
			(xy 109.926374 -225.071432) (xy 109.722666 -224.718626) (xy 109.699806 -224.714308) (xy 109.674886 -224.709131)
			(xy 109.6269 -224.692171) (xy 109.58208 -224.668057) (xy 109.541485 -224.637359) (xy 109.506075 -224.600802)
			(xy 109.476686 -224.55925) (xy 109.454012 -224.513684) (xy 109.43859 -224.465182) (xy 109.430784 -224.414889)
			(xy 109.430312 -224.389442) (xy 109.15142 -224.389442) (xy 109.150911 -224.415409) (xy 109.142786 -224.466704)
			(xy 109.126738 -224.516097) (xy 109.10316 -224.562371) (xy 109.072634 -224.604387) (xy 109.035911 -224.64111)
			(xy 108.993895 -224.671636) (xy 108.947621 -224.695214) (xy 108.898228 -224.711262) (xy 108.846933 -224.719387)
			(xy 108.794999 -224.719387) (xy 108.743704 -224.711262) (xy 108.694311 -224.695214) (xy 108.648037 -224.671636)
			(xy 108.606021 -224.64111) (xy 108.569298 -224.604387) (xy 108.538772 -224.562371) (xy 108.515194 -224.516097)
			(xy 108.499146 -224.466704) (xy 108.491021 -224.415409) (xy 108.490512 -224.389442) (xy 108.21162 -224.389442)
			(xy 108.211077 -224.417428) (xy 108.20162 -224.472596) (xy 108.192824 -224.49917) (xy 108.185204 -224.521268)
			(xy 108.388912 -224.874074) (xy 108.411772 -224.878392) (xy 108.436704 -224.883512) (xy 108.48469 -224.900483)
			(xy 108.529509 -224.924607) (xy 108.570102 -224.955314) (xy 108.605509 -224.991878) (xy 108.634896 -225.033436)
			(xy 108.657568 -225.079006) (xy 108.672989 -225.127512) (xy 108.680794 -225.177809) (xy 108.681266 -225.203258)
			(xy 108.680757 -225.229225) (xy 108.672632 -225.28052) (xy 108.656584 -225.329913) (xy 108.633006 -225.376187)
			(xy 108.60248 -225.418203) (xy 108.565757 -225.454926) (xy 108.523741 -225.485452) (xy 108.477467 -225.50903)
			(xy 108.428074 -225.525078) (xy 108.376779 -225.533203) (xy 108.324845 -225.533203) (xy 108.27355 -225.525078)
			(xy 108.224157 -225.50903) (xy 108.177883 -225.485452) (xy 108.135867 -225.454926) (xy 108.099144 -225.418203)
			(xy 108.068618 -225.376187) (xy 108.04504 -225.329913) (xy 108.028992 -225.28052) (xy 108.020867 -225.229225)
			(xy 108.020358 -225.203258) (xy 108.020897 -225.175271) (xy 108.030356 -225.120104) (xy 108.039154 -225.09353)
			(xy 108.046774 -225.071432) (xy 107.843066 -224.718626) (xy 107.820206 -224.714308) (xy 107.795286 -224.709131)
			(xy 107.7473 -224.692171) (xy 107.70248 -224.668057) (xy 107.661885 -224.637359) (xy 107.626475 -224.600802)
			(xy 107.597086 -224.55925) (xy 107.574412 -224.513684) (xy 107.55899 -224.465182) (xy 107.551184 -224.414889)
			(xy 107.550712 -224.389442) (xy 107.27182 -224.389442) (xy 107.271311 -224.415409) (xy 107.263186 -224.466704)
			(xy 107.247138 -224.516097) (xy 107.22356 -224.562371) (xy 107.193034 -224.604387) (xy 107.156311 -224.64111)
			(xy 107.114295 -224.671636) (xy 107.068021 -224.695214) (xy 107.018628 -224.711262) (xy 106.967333 -224.719387)
			(xy 106.915399 -224.719387) (xy 106.864104 -224.711262) (xy 106.814711 -224.695214) (xy 106.768437 -224.671636)
			(xy 106.726421 -224.64111) (xy 106.689698 -224.604387) (xy 106.659172 -224.562371) (xy 106.635594 -224.516097)
			(xy 106.619546 -224.466704) (xy 106.611421 -224.415409) (xy 106.610912 -224.389442) (xy 106.33202 -224.389442)
			(xy 106.331477 -224.417428) (xy 106.32202 -224.472596) (xy 106.313224 -224.49917) (xy 106.305604 -224.521268)
			(xy 106.509312 -224.874074) (xy 106.532172 -224.878392) (xy 106.557104 -224.883512) (xy 106.60509 -224.900483)
			(xy 106.649909 -224.924607) (xy 106.690502 -224.955314) (xy 106.725909 -224.991878) (xy 106.755296 -225.033436)
			(xy 106.777968 -225.079006) (xy 106.793389 -225.127512) (xy 106.801194 -225.177809) (xy 106.801666 -225.203258)
			(xy 106.801157 -225.229225) (xy 106.793032 -225.28052) (xy 106.776984 -225.329913) (xy 106.753406 -225.376187)
			(xy 106.72288 -225.418203) (xy 106.686157 -225.454926) (xy 106.644141 -225.485452) (xy 106.597867 -225.50903)
			(xy 106.548474 -225.525078) (xy 106.497179 -225.533203) (xy 106.445245 -225.533203) (xy 106.39395 -225.525078)
			(xy 106.344557 -225.50903) (xy 106.298283 -225.485452) (xy 106.256267 -225.454926) (xy 106.219544 -225.418203)
			(xy 106.189018 -225.376187) (xy 106.16544 -225.329913) (xy 106.149392 -225.28052) (xy 106.141267 -225.229225)
			(xy 106.140758 -225.203258) (xy 106.141297 -225.175271) (xy 106.150756 -225.120104) (xy 106.159554 -225.09353)
			(xy 106.167174 -225.071432) (xy 105.963466 -224.718626) (xy 105.940606 -224.714308) (xy 105.915686 -224.709131)
			(xy 105.8677 -224.692171) (xy 105.82288 -224.668057) (xy 105.782285 -224.637359) (xy 105.746875 -224.600802)
			(xy 105.717486 -224.55925) (xy 105.694812 -224.513684) (xy 105.67939 -224.465182) (xy 105.671584 -224.414889)
			(xy 105.671112 -224.389442) (xy 105.39222 -224.389442) (xy 105.391711 -224.415409) (xy 105.383586 -224.466704)
			(xy 105.367538 -224.516097) (xy 105.34396 -224.562371) (xy 105.313434 -224.604387) (xy 105.276711 -224.64111)
			(xy 105.234695 -224.671636) (xy 105.188421 -224.695214) (xy 105.139028 -224.711262) (xy 105.087733 -224.719387)
			(xy 105.035799 -224.719387) (xy 104.984504 -224.711262) (xy 104.935111 -224.695214) (xy 104.888837 -224.671636)
			(xy 104.846821 -224.64111) (xy 104.810098 -224.604387) (xy 104.779572 -224.562371) (xy 104.755994 -224.516097)
			(xy 104.739946 -224.466704) (xy 104.731821 -224.415409) (xy 104.731312 -224.389442) (xy 104.45242 -224.389442)
			(xy 104.451812 -224.417423) (xy 104.44237 -224.472584) (xy 104.433624 -224.49917) (xy 104.426004 -224.521268)
			(xy 104.629712 -224.874074) (xy 104.652572 -224.878392) (xy 104.677501 -224.883543) (xy 104.725502 -224.900485)
			(xy 104.770336 -224.92459) (xy 104.810942 -224.955286) (xy 104.846359 -224.991848) (xy 104.875749 -225.033409)
			(xy 104.898416 -225.078987) (xy 104.913823 -225.127502) (xy 104.921607 -225.177806) (xy 104.922066 -225.203258)
			(xy 104.921543 -225.22949) (xy 104.913218 -225.28129) (xy 104.896818 -225.331126) (xy 104.872753 -225.377747)
			(xy 104.841629 -225.419983) (xy 104.82326 -225.438716) (xy 104.816998 -225.445379) (xy 104.809246 -225.461925)
			(xy 104.807775 -225.480138) (xy 104.812772 -225.497713) (xy 104.817926 -225.505264) (xy 104.84576 -225.544122)
			(xy 104.893625 -225.626862) (xy 104.91343 -225.670364) (xy 104.917459 -225.67853) (xy 104.930173 -225.691548)
			(xy 104.946626 -225.699319) (xy 104.964757 -225.70087) (xy 104.973628 -225.698812) (xy 104.99523 -225.693214)
			(xy 105.039453 -225.687226) (xy 105.061766 -225.686874) (xy 105.086663 -225.687324) (xy 105.135895 -225.694793)
			(xy 105.183448 -225.709566) (xy 105.228244 -225.73131) (xy 105.269269 -225.759532) (xy 105.305594 -225.793591)
			(xy 105.336395 -225.832717) (xy 105.360975 -225.876022) (xy 105.378776 -225.922527) (xy 105.389395 -225.971176)
			(xy 105.391458 -225.995992) (xy 105.394506 -226.04349) (xy 105.668826 -226.04349) (xy 105.671874 -225.995992)
			(xy 105.673936 -225.971179) (xy 105.684577 -225.922541) (xy 105.702392 -225.876049) (xy 105.726979 -225.832755)
			(xy 105.757782 -225.793639) (xy 105.794103 -225.759585) (xy 105.835121 -225.731364) (xy 105.879907 -225.709615)
			(xy 105.92745 -225.694829) (xy 105.976672 -225.687341) (xy 106.001566 -225.686874) (xy 106.026259 -225.687338)
			(xy 106.075093 -225.694696) (xy 106.122288 -225.709237) (xy 106.166795 -225.730639) (xy 106.207622 -225.758425)
			(xy 106.24386 -225.791977) (xy 106.274703 -225.830546) (xy 106.299464 -225.873276) (xy 106.317591 -225.919214)
			(xy 106.323638 -225.94316) (xy 106.327358 -225.957148) (xy 106.341457 -225.982409) (xy 106.362073 -226.002704)
			(xy 106.387552 -226.016405) (xy 106.415851 -226.022413) (xy 106.430318 -226.0219) (xy 106.443632 -226.020948)
			(xy 106.47031 -226.019933) (xy 106.483658 -226.019868) (xy 106.502107 -226.019973) (xy 106.538956 -226.021881)
			(xy 106.557318 -226.023678) (xy 106.567265 -226.02424) (xy 106.586362 -226.018636) (xy 106.601904 -226.006203)
			(xy 106.611565 -225.988802) (xy 106.613198 -225.978974) (xy 106.616813 -225.9525) (xy 106.631479 -225.901122)
			(xy 106.654217 -225.852772) (xy 106.684437 -225.808709) (xy 106.721349 -225.77008) (xy 106.763995 -225.737891)
			(xy 106.811262 -225.71298) (xy 106.86192 -225.695996) (xy 106.914651 -225.687381) (xy 106.941366 -225.686874)
			(xy 106.967336 -225.687354) (xy 107.018638 -225.695475) (xy 107.068037 -225.711523) (xy 107.114317 -225.735101)
			(xy 107.156339 -225.765629) (xy 107.193067 -225.802356) (xy 107.223596 -225.844377) (xy 107.247175 -225.890657)
			(xy 107.263223 -225.940056) (xy 107.271345 -225.991358) (xy 107.27182 -226.017328) (xy 107.271411 -226.04102)
			(xy 107.271083 -226.043295) (xy 107.551221 -226.043295) (xy 107.551221 -225.991361) (xy 107.559346 -225.940066)
			(xy 107.575394 -225.890673) (xy 107.598972 -225.844399) (xy 107.629498 -225.802383) (xy 107.666221 -225.76566)
			(xy 107.708237 -225.735134) (xy 107.754511 -225.711556) (xy 107.803904 -225.695508) (xy 107.855199 -225.687383)
			(xy 107.907133 -225.687383) (xy 107.958428 -225.695508) (xy 108.007821 -225.711556) (xy 108.054095 -225.735134)
			(xy 108.096111 -225.76566) (xy 108.132834 -225.802383) (xy 108.16336 -225.844399) (xy 108.186938 -225.890673)
			(xy 108.202986 -225.940066) (xy 108.211111 -225.991361) (xy 108.21162 -226.017328) (xy 108.211111 -226.043295)
			(xy 108.491021 -226.043295) (xy 108.491021 -225.991361) (xy 108.499146 -225.940066) (xy 108.515194 -225.890673)
			(xy 108.538772 -225.844399) (xy 108.569298 -225.802383) (xy 108.606021 -225.76566) (xy 108.648037 -225.735134)
			(xy 108.694311 -225.711556) (xy 108.743704 -225.695508) (xy 108.794999 -225.687383) (xy 108.846933 -225.687383)
			(xy 108.898228 -225.695508) (xy 108.947621 -225.711556) (xy 108.993895 -225.735134) (xy 109.035911 -225.76566)
			(xy 109.072634 -225.802383) (xy 109.10316 -225.844399) (xy 109.126738 -225.890673) (xy 109.142786 -225.940066)
			(xy 109.150911 -225.991361) (xy 109.15142 -226.017328) (xy 109.150911 -226.043295) (xy 109.430821 -226.043295)
			(xy 109.430821 -225.991361) (xy 109.438946 -225.940066) (xy 109.454994 -225.890673) (xy 109.478572 -225.844399)
			(xy 109.509098 -225.802383) (xy 109.545821 -225.76566) (xy 109.587837 -225.735134) (xy 109.634111 -225.711556)
			(xy 109.683504 -225.695508) (xy 109.734799 -225.687383) (xy 109.786733 -225.687383) (xy 109.838028 -225.695508)
			(xy 109.887421 -225.711556) (xy 109.933695 -225.735134) (xy 109.975711 -225.76566) (xy 110.012434 -225.802383)
			(xy 110.04296 -225.844399) (xy 110.066538 -225.890673) (xy 110.082586 -225.940066) (xy 110.090711 -225.991361)
			(xy 110.09122 -226.017328) (xy 110.090711 -226.043295) (xy 110.370621 -226.043295) (xy 110.370621 -225.991361)
			(xy 110.378746 -225.940066) (xy 110.394794 -225.890673) (xy 110.418372 -225.844399) (xy 110.448898 -225.802383)
			(xy 110.485621 -225.76566) (xy 110.527637 -225.735134) (xy 110.573911 -225.711556) (xy 110.623304 -225.695508)
			(xy 110.674599 -225.687383) (xy 110.726533 -225.687383) (xy 110.777828 -225.695508) (xy 110.827221 -225.711556)
			(xy 110.873495 -225.735134) (xy 110.915511 -225.76566) (xy 110.952234 -225.802383) (xy 110.98276 -225.844399)
			(xy 111.006338 -225.890673) (xy 111.022386 -225.940066) (xy 111.030511 -225.991361) (xy 111.03102 -226.017328)
			(xy 111.030511 -226.043295) (xy 111.310421 -226.043295) (xy 111.310421 -225.991361) (xy 111.318546 -225.940066)
			(xy 111.334594 -225.890673) (xy 111.358172 -225.844399) (xy 111.388698 -225.802383) (xy 111.425421 -225.76566)
			(xy 111.467437 -225.735134) (xy 111.513711 -225.711556) (xy 111.563104 -225.695508) (xy 111.614399 -225.687383)
			(xy 111.666333 -225.687383) (xy 111.717628 -225.695508) (xy 111.767021 -225.711556) (xy 111.813295 -225.735134)
			(xy 111.855311 -225.76566) (xy 111.892034 -225.802383) (xy 111.92256 -225.844399) (xy 111.946138 -225.890673)
			(xy 111.962186 -225.940066) (xy 111.970311 -225.991361) (xy 111.97082 -226.017328) (xy 111.970311 -226.043295)
			(xy 112.250221 -226.043295) (xy 112.250221 -225.991361) (xy 112.258346 -225.940066) (xy 112.274394 -225.890673)
			(xy 112.297972 -225.844399) (xy 112.328498 -225.802383) (xy 112.365221 -225.76566) (xy 112.407237 -225.735134)
			(xy 112.453511 -225.711556) (xy 112.502904 -225.695508) (xy 112.554199 -225.687383) (xy 112.606133 -225.687383)
			(xy 112.657428 -225.695508) (xy 112.706821 -225.711556) (xy 112.753095 -225.735134) (xy 112.795111 -225.76566)
			(xy 112.831834 -225.802383) (xy 112.86236 -225.844399) (xy 112.885938 -225.890673) (xy 112.901986 -225.940066)
			(xy 112.910111 -225.991361) (xy 112.91062 -226.017328) (xy 112.910111 -226.043295) (xy 113.190021 -226.043295)
			(xy 113.190021 -225.991361) (xy 113.198146 -225.940066) (xy 113.214194 -225.890673) (xy 113.237772 -225.844399)
			(xy 113.268298 -225.802383) (xy 113.305021 -225.76566) (xy 113.347037 -225.735134) (xy 113.393311 -225.711556)
			(xy 113.442704 -225.695508) (xy 113.493999 -225.687383) (xy 113.545933 -225.687383) (xy 113.597228 -225.695508)
			(xy 113.646621 -225.711556) (xy 113.692895 -225.735134) (xy 113.734911 -225.76566) (xy 113.771634 -225.802383)
			(xy 113.80216 -225.844399) (xy 113.825738 -225.890673) (xy 113.841786 -225.940066) (xy 113.849911 -225.991361)
			(xy 113.85042 -226.017328) (xy 113.849911 -226.043295) (xy 114.129821 -226.043295) (xy 114.129821 -225.991361)
			(xy 114.137946 -225.940066) (xy 114.153994 -225.890673) (xy 114.177572 -225.844399) (xy 114.208098 -225.802383)
			(xy 114.244821 -225.76566) (xy 114.286837 -225.735134) (xy 114.333111 -225.711556) (xy 114.382504 -225.695508)
			(xy 114.433799 -225.687383) (xy 114.485733 -225.687383) (xy 114.537028 -225.695508) (xy 114.586421 -225.711556)
			(xy 114.632695 -225.735134) (xy 114.674711 -225.76566) (xy 114.711434 -225.802383) (xy 114.74196 -225.844399)
			(xy 114.765538 -225.890673) (xy 114.781586 -225.940066) (xy 114.789711 -225.991361) (xy 114.79022 -226.017328)
			(xy 114.789711 -226.043295) (xy 115.069621 -226.043295) (xy 115.069621 -225.991361) (xy 115.077746 -225.940066)
			(xy 115.093794 -225.890673) (xy 115.117372 -225.844399) (xy 115.147898 -225.802383) (xy 115.184621 -225.76566)
			(xy 115.226637 -225.735134) (xy 115.272911 -225.711556) (xy 115.322304 -225.695508) (xy 115.373599 -225.687383)
			(xy 115.425533 -225.687383) (xy 115.476828 -225.695508) (xy 115.526221 -225.711556) (xy 115.572495 -225.735134)
			(xy 115.614511 -225.76566) (xy 115.651234 -225.802383) (xy 115.68176 -225.844399) (xy 115.705338 -225.890673)
			(xy 115.721386 -225.940066) (xy 115.729511 -225.991361) (xy 115.73002 -226.017328) (xy 115.729511 -226.043295)
			(xy 116.009421 -226.043295) (xy 116.009421 -225.991361) (xy 116.017546 -225.940066) (xy 116.033594 -225.890673)
			(xy 116.057172 -225.844399) (xy 116.087698 -225.802383) (xy 116.124421 -225.76566) (xy 116.166437 -225.735134)
			(xy 116.212711 -225.711556) (xy 116.262104 -225.695508) (xy 116.313399 -225.687383) (xy 116.365333 -225.687383)
			(xy 116.416628 -225.695508) (xy 116.466021 -225.711556) (xy 116.512295 -225.735134) (xy 116.554311 -225.76566)
			(xy 116.591034 -225.802383) (xy 116.62156 -225.844399) (xy 116.645138 -225.890673) (xy 116.661186 -225.940066)
			(xy 116.669311 -225.991361) (xy 116.66982 -226.017328) (xy 116.669311 -226.043295) (xy 116.949221 -226.043295)
			(xy 116.949221 -225.991361) (xy 116.957346 -225.940066) (xy 116.973394 -225.890673) (xy 116.996972 -225.844399)
			(xy 117.027498 -225.802383) (xy 117.064221 -225.76566) (xy 117.106237 -225.735134) (xy 117.152511 -225.711556)
			(xy 117.201904 -225.695508) (xy 117.253199 -225.687383) (xy 117.305133 -225.687383) (xy 117.356428 -225.695508)
			(xy 117.405821 -225.711556) (xy 117.452095 -225.735134) (xy 117.494111 -225.76566) (xy 117.530834 -225.802383)
			(xy 117.56136 -225.844399) (xy 117.584938 -225.890673) (xy 117.600986 -225.940066) (xy 117.609111 -225.991361)
			(xy 117.60962 -226.017328) (xy 117.609111 -226.043295) (xy 117.889021 -226.043295) (xy 117.889021 -225.991361)
			(xy 117.897146 -225.940066) (xy 117.913194 -225.890673) (xy 117.936772 -225.844399) (xy 117.967298 -225.802383)
			(xy 118.004021 -225.76566) (xy 118.046037 -225.735134) (xy 118.092311 -225.711556) (xy 118.141704 -225.695508)
			(xy 118.192999 -225.687383) (xy 118.244933 -225.687383) (xy 118.296228 -225.695508) (xy 118.345621 -225.711556)
			(xy 118.391895 -225.735134) (xy 118.433911 -225.76566) (xy 118.470634 -225.802383) (xy 118.50116 -225.844399)
			(xy 118.524738 -225.890673) (xy 118.540786 -225.940066) (xy 118.548911 -225.991361) (xy 118.54942 -226.017328)
			(xy 118.548911 -226.043295) (xy 118.828821 -226.043295) (xy 118.828821 -225.991361) (xy 118.836946 -225.940066)
			(xy 118.852994 -225.890673) (xy 118.876572 -225.844399) (xy 118.907098 -225.802383) (xy 118.943821 -225.76566)
			(xy 118.985837 -225.735134) (xy 119.032111 -225.711556) (xy 119.081504 -225.695508) (xy 119.132799 -225.687383)
			(xy 119.184733 -225.687383) (xy 119.236028 -225.695508) (xy 119.285421 -225.711556) (xy 119.331695 -225.735134)
			(xy 119.373711 -225.76566) (xy 119.410434 -225.802383) (xy 119.44096 -225.844399) (xy 119.464538 -225.890673)
			(xy 119.480586 -225.940066) (xy 119.488711 -225.991361) (xy 119.48922 -226.017328) (xy 119.488711 -226.043295)
			(xy 119.768621 -226.043295) (xy 119.768621 -225.991361) (xy 119.776746 -225.940066) (xy 119.792794 -225.890673)
			(xy 119.816372 -225.844399) (xy 119.846898 -225.802383) (xy 119.883621 -225.76566) (xy 119.925637 -225.735134)
			(xy 119.971911 -225.711556) (xy 120.021304 -225.695508) (xy 120.072599 -225.687383) (xy 120.124533 -225.687383)
			(xy 120.175828 -225.695508) (xy 120.225221 -225.711556) (xy 120.271495 -225.735134) (xy 120.313511 -225.76566)
			(xy 120.350234 -225.802383) (xy 120.38076 -225.844399) (xy 120.404338 -225.890673) (xy 120.420386 -225.940066)
			(xy 120.428511 -225.991361) (xy 120.42902 -226.017328) (xy 120.428511 -226.043295) (xy 120.708421 -226.043295)
			(xy 120.708421 -225.991361) (xy 120.716546 -225.940066) (xy 120.732594 -225.890673) (xy 120.756172 -225.844399)
			(xy 120.786698 -225.802383) (xy 120.823421 -225.76566) (xy 120.865437 -225.735134) (xy 120.911711 -225.711556)
			(xy 120.961104 -225.695508) (xy 121.012399 -225.687383) (xy 121.064333 -225.687383) (xy 121.115628 -225.695508)
			(xy 121.165021 -225.711556) (xy 121.211295 -225.735134) (xy 121.253311 -225.76566) (xy 121.290034 -225.802383)
			(xy 121.32056 -225.844399) (xy 121.344138 -225.890673) (xy 121.360186 -225.940066) (xy 121.368311 -225.991361)
			(xy 121.36882 -226.017328) (xy 121.368311 -226.043295) (xy 121.648221 -226.043295) (xy 121.648221 -225.991361)
			(xy 121.656346 -225.940066) (xy 121.672394 -225.890673) (xy 121.695972 -225.844399) (xy 121.726498 -225.802383)
			(xy 121.763221 -225.76566) (xy 121.805237 -225.735134) (xy 121.851511 -225.711556) (xy 121.900904 -225.695508)
			(xy 121.952199 -225.687383) (xy 122.004133 -225.687383) (xy 122.055428 -225.695508) (xy 122.104821 -225.711556)
			(xy 122.151095 -225.735134) (xy 122.193111 -225.76566) (xy 122.229834 -225.802383) (xy 122.26036 -225.844399)
			(xy 122.283938 -225.890673) (xy 122.299986 -225.940066) (xy 122.308111 -225.991361) (xy 122.30862 -226.017328)
			(xy 122.308111 -226.043295) (xy 122.588021 -226.043295) (xy 122.588021 -225.991361) (xy 122.596146 -225.940066)
			(xy 122.612194 -225.890673) (xy 122.635772 -225.844399) (xy 122.666298 -225.802383) (xy 122.703021 -225.76566)
			(xy 122.745037 -225.735134) (xy 122.791311 -225.711556) (xy 122.840704 -225.695508) (xy 122.891999 -225.687383)
			(xy 122.943933 -225.687383) (xy 122.995228 -225.695508) (xy 123.044621 -225.711556) (xy 123.090895 -225.735134)
			(xy 123.132911 -225.76566) (xy 123.169634 -225.802383) (xy 123.20016 -225.844399) (xy 123.223738 -225.890673)
			(xy 123.239786 -225.940066) (xy 123.247911 -225.991361) (xy 123.24842 -226.017328) (xy 123.247911 -226.043295)
			(xy 123.527821 -226.043295) (xy 123.527821 -225.991361) (xy 123.535946 -225.940066) (xy 123.551994 -225.890673)
			(xy 123.575572 -225.844399) (xy 123.606098 -225.802383) (xy 123.642821 -225.76566) (xy 123.684837 -225.735134)
			(xy 123.731111 -225.711556) (xy 123.780504 -225.695508) (xy 123.831799 -225.687383) (xy 123.883733 -225.687383)
			(xy 123.935028 -225.695508) (xy 123.984421 -225.711556) (xy 124.030695 -225.735134) (xy 124.072711 -225.76566)
			(xy 124.109434 -225.802383) (xy 124.13996 -225.844399) (xy 124.163538 -225.890673) (xy 124.179586 -225.940066)
			(xy 124.187711 -225.991361) (xy 124.18822 -226.017328) (xy 124.187711 -226.043295) (xy 124.467621 -226.043295)
			(xy 124.467621 -225.991361) (xy 124.475746 -225.940066) (xy 124.491794 -225.890673) (xy 124.515372 -225.844399)
			(xy 124.545898 -225.802383) (xy 124.582621 -225.76566) (xy 124.624637 -225.735134) (xy 124.670911 -225.711556)
			(xy 124.720304 -225.695508) (xy 124.771599 -225.687383) (xy 124.823533 -225.687383) (xy 124.874828 -225.695508)
			(xy 124.924221 -225.711556) (xy 124.970495 -225.735134) (xy 125.012511 -225.76566) (xy 125.049234 -225.802383)
			(xy 125.07976 -225.844399) (xy 125.103338 -225.890673) (xy 125.119386 -225.940066) (xy 125.127511 -225.991361)
			(xy 125.12802 -226.017328) (xy 125.127511 -226.043295) (xy 125.407421 -226.043295) (xy 125.407421 -225.991361)
			(xy 125.415546 -225.940066) (xy 125.431594 -225.890673) (xy 125.455172 -225.844399) (xy 125.485698 -225.802383)
			(xy 125.522421 -225.76566) (xy 125.564437 -225.735134) (xy 125.610711 -225.711556) (xy 125.660104 -225.695508)
			(xy 125.711399 -225.687383) (xy 125.763333 -225.687383) (xy 125.814628 -225.695508) (xy 125.864021 -225.711556)
			(xy 125.910295 -225.735134) (xy 125.952311 -225.76566) (xy 125.989034 -225.802383) (xy 126.01956 -225.844399)
			(xy 126.043138 -225.890673) (xy 126.059186 -225.940066) (xy 126.067311 -225.991361) (xy 126.06782 -226.017328)
			(xy 126.067311 -226.043295) (xy 126.347221 -226.043295) (xy 126.347221 -225.991361) (xy 126.355346 -225.940066)
			(xy 126.371394 -225.890673) (xy 126.394972 -225.844399) (xy 126.425498 -225.802383) (xy 126.462221 -225.76566)
			(xy 126.504237 -225.735134) (xy 126.550511 -225.711556) (xy 126.599904 -225.695508) (xy 126.651199 -225.687383)
			(xy 126.703133 -225.687383) (xy 126.754428 -225.695508) (xy 126.803821 -225.711556) (xy 126.850095 -225.735134)
			(xy 126.892111 -225.76566) (xy 126.928834 -225.802383) (xy 126.95936 -225.844399) (xy 126.982938 -225.890673)
			(xy 126.998986 -225.940066) (xy 127.007111 -225.991361) (xy 127.00762 -226.017328) (xy 127.007111 -226.043295)
			(xy 126.998986 -226.09459) (xy 126.982938 -226.143983) (xy 126.95936 -226.190257) (xy 126.928834 -226.232273)
			(xy 126.892111 -226.268996) (xy 126.850095 -226.299522) (xy 126.803821 -226.3231) (xy 126.754428 -226.339148)
			(xy 126.703133 -226.347273) (xy 126.651199 -226.347273) (xy 126.599904 -226.339148) (xy 126.550511 -226.3231)
			(xy 126.504237 -226.299522) (xy 126.462221 -226.268996) (xy 126.425498 -226.232273) (xy 126.394972 -226.190257)
			(xy 126.371394 -226.143983) (xy 126.355346 -226.09459) (xy 126.347221 -226.043295) (xy 126.067311 -226.043295)
			(xy 126.059186 -226.09459) (xy 126.043138 -226.143983) (xy 126.01956 -226.190257) (xy 125.989034 -226.232273)
			(xy 125.952311 -226.268996) (xy 125.910295 -226.299522) (xy 125.864021 -226.3231) (xy 125.814628 -226.339148)
			(xy 125.763333 -226.347273) (xy 125.711399 -226.347273) (xy 125.660104 -226.339148) (xy 125.610711 -226.3231)
			(xy 125.564437 -226.299522) (xy 125.522421 -226.268996) (xy 125.485698 -226.232273) (xy 125.455172 -226.190257)
			(xy 125.431594 -226.143983) (xy 125.415546 -226.09459) (xy 125.407421 -226.043295) (xy 125.127511 -226.043295)
			(xy 125.119386 -226.09459) (xy 125.103338 -226.143983) (xy 125.07976 -226.190257) (xy 125.049234 -226.232273)
			(xy 125.012511 -226.268996) (xy 124.970495 -226.299522) (xy 124.924221 -226.3231) (xy 124.874828 -226.339148)
			(xy 124.823533 -226.347273) (xy 124.771599 -226.347273) (xy 124.720304 -226.339148) (xy 124.670911 -226.3231)
			(xy 124.624637 -226.299522) (xy 124.582621 -226.268996) (xy 124.545898 -226.232273) (xy 124.515372 -226.190257)
			(xy 124.491794 -226.143983) (xy 124.475746 -226.09459) (xy 124.467621 -226.043295) (xy 124.187711 -226.043295)
			(xy 124.179586 -226.09459) (xy 124.163538 -226.143983) (xy 124.13996 -226.190257) (xy 124.109434 -226.232273)
			(xy 124.072711 -226.268996) (xy 124.030695 -226.299522) (xy 123.984421 -226.3231) (xy 123.935028 -226.339148)
			(xy 123.883733 -226.347273) (xy 123.831799 -226.347273) (xy 123.780504 -226.339148) (xy 123.731111 -226.3231)
			(xy 123.684837 -226.299522) (xy 123.642821 -226.268996) (xy 123.606098 -226.232273) (xy 123.575572 -226.190257)
			(xy 123.551994 -226.143983) (xy 123.535946 -226.09459) (xy 123.527821 -226.043295) (xy 123.247911 -226.043295)
			(xy 123.239786 -226.09459) (xy 123.223738 -226.143983) (xy 123.20016 -226.190257) (xy 123.169634 -226.232273)
			(xy 123.132911 -226.268996) (xy 123.090895 -226.299522) (xy 123.044621 -226.3231) (xy 122.995228 -226.339148)
			(xy 122.943933 -226.347273) (xy 122.891999 -226.347273) (xy 122.840704 -226.339148) (xy 122.791311 -226.3231)
			(xy 122.745037 -226.299522) (xy 122.703021 -226.268996) (xy 122.666298 -226.232273) (xy 122.635772 -226.190257)
			(xy 122.612194 -226.143983) (xy 122.596146 -226.09459) (xy 122.588021 -226.043295) (xy 122.308111 -226.043295)
			(xy 122.299986 -226.09459) (xy 122.283938 -226.143983) (xy 122.26036 -226.190257) (xy 122.229834 -226.232273)
			(xy 122.193111 -226.268996) (xy 122.151095 -226.299522) (xy 122.104821 -226.3231) (xy 122.055428 -226.339148)
			(xy 122.004133 -226.347273) (xy 121.952199 -226.347273) (xy 121.900904 -226.339148) (xy 121.851511 -226.3231)
			(xy 121.805237 -226.299522) (xy 121.763221 -226.268996) (xy 121.726498 -226.232273) (xy 121.695972 -226.190257)
			(xy 121.672394 -226.143983) (xy 121.656346 -226.09459) (xy 121.648221 -226.043295) (xy 121.368311 -226.043295)
			(xy 121.360186 -226.09459) (xy 121.344138 -226.143983) (xy 121.32056 -226.190257) (xy 121.290034 -226.232273)
			(xy 121.253311 -226.268996) (xy 121.211295 -226.299522) (xy 121.165021 -226.3231) (xy 121.115628 -226.339148)
			(xy 121.064333 -226.347273) (xy 121.012399 -226.347273) (xy 120.961104 -226.339148) (xy 120.911711 -226.3231)
			(xy 120.865437 -226.299522) (xy 120.823421 -226.268996) (xy 120.786698 -226.232273) (xy 120.756172 -226.190257)
			(xy 120.732594 -226.143983) (xy 120.716546 -226.09459) (xy 120.708421 -226.043295) (xy 120.428511 -226.043295)
			(xy 120.420386 -226.09459) (xy 120.404338 -226.143983) (xy 120.38076 -226.190257) (xy 120.350234 -226.232273)
			(xy 120.313511 -226.268996) (xy 120.271495 -226.299522) (xy 120.225221 -226.3231) (xy 120.175828 -226.339148)
			(xy 120.124533 -226.347273) (xy 120.072599 -226.347273) (xy 120.021304 -226.339148) (xy 119.971911 -226.3231)
			(xy 119.925637 -226.299522) (xy 119.883621 -226.268996) (xy 119.846898 -226.232273) (xy 119.816372 -226.190257)
			(xy 119.792794 -226.143983) (xy 119.776746 -226.09459) (xy 119.768621 -226.043295) (xy 119.488711 -226.043295)
			(xy 119.480586 -226.09459) (xy 119.464538 -226.143983) (xy 119.44096 -226.190257) (xy 119.410434 -226.232273)
			(xy 119.373711 -226.268996) (xy 119.331695 -226.299522) (xy 119.285421 -226.3231) (xy 119.236028 -226.339148)
			(xy 119.184733 -226.347273) (xy 119.132799 -226.347273) (xy 119.081504 -226.339148) (xy 119.032111 -226.3231)
			(xy 118.985837 -226.299522) (xy 118.943821 -226.268996) (xy 118.907098 -226.232273) (xy 118.876572 -226.190257)
			(xy 118.852994 -226.143983) (xy 118.836946 -226.09459) (xy 118.828821 -226.043295) (xy 118.548911 -226.043295)
			(xy 118.540786 -226.09459) (xy 118.524738 -226.143983) (xy 118.50116 -226.190257) (xy 118.470634 -226.232273)
			(xy 118.433911 -226.268996) (xy 118.391895 -226.299522) (xy 118.345621 -226.3231) (xy 118.296228 -226.339148)
			(xy 118.244933 -226.347273) (xy 118.192999 -226.347273) (xy 118.141704 -226.339148) (xy 118.092311 -226.3231)
			(xy 118.046037 -226.299522) (xy 118.004021 -226.268996) (xy 117.967298 -226.232273) (xy 117.936772 -226.190257)
			(xy 117.913194 -226.143983) (xy 117.897146 -226.09459) (xy 117.889021 -226.043295) (xy 117.609111 -226.043295)
			(xy 117.600986 -226.09459) (xy 117.584938 -226.143983) (xy 117.56136 -226.190257) (xy 117.530834 -226.232273)
			(xy 117.494111 -226.268996) (xy 117.452095 -226.299522) (xy 117.405821 -226.3231) (xy 117.356428 -226.339148)
			(xy 117.305133 -226.347273) (xy 117.253199 -226.347273) (xy 117.201904 -226.339148) (xy 117.152511 -226.3231)
			(xy 117.106237 -226.299522) (xy 117.064221 -226.268996) (xy 117.027498 -226.232273) (xy 116.996972 -226.190257)
			(xy 116.973394 -226.143983) (xy 116.957346 -226.09459) (xy 116.949221 -226.043295) (xy 116.669311 -226.043295)
			(xy 116.661186 -226.09459) (xy 116.645138 -226.143983) (xy 116.62156 -226.190257) (xy 116.591034 -226.232273)
			(xy 116.554311 -226.268996) (xy 116.512295 -226.299522) (xy 116.466021 -226.3231) (xy 116.416628 -226.339148)
			(xy 116.365333 -226.347273) (xy 116.313399 -226.347273) (xy 116.262104 -226.339148) (xy 116.212711 -226.3231)
			(xy 116.166437 -226.299522) (xy 116.124421 -226.268996) (xy 116.087698 -226.232273) (xy 116.057172 -226.190257)
			(xy 116.033594 -226.143983) (xy 116.017546 -226.09459) (xy 116.009421 -226.043295) (xy 115.729511 -226.043295)
			(xy 115.721386 -226.09459) (xy 115.705338 -226.143983) (xy 115.68176 -226.190257) (xy 115.651234 -226.232273)
			(xy 115.614511 -226.268996) (xy 115.572495 -226.299522) (xy 115.526221 -226.3231) (xy 115.476828 -226.339148)
			(xy 115.425533 -226.347273) (xy 115.373599 -226.347273) (xy 115.322304 -226.339148) (xy 115.272911 -226.3231)
			(xy 115.226637 -226.299522) (xy 115.184621 -226.268996) (xy 115.147898 -226.232273) (xy 115.117372 -226.190257)
			(xy 115.093794 -226.143983) (xy 115.077746 -226.09459) (xy 115.069621 -226.043295) (xy 114.789711 -226.043295)
			(xy 114.781586 -226.09459) (xy 114.765538 -226.143983) (xy 114.74196 -226.190257) (xy 114.711434 -226.232273)
			(xy 114.674711 -226.268996) (xy 114.632695 -226.299522) (xy 114.586421 -226.3231) (xy 114.537028 -226.339148)
			(xy 114.485733 -226.347273) (xy 114.433799 -226.347273) (xy 114.382504 -226.339148) (xy 114.333111 -226.3231)
			(xy 114.286837 -226.299522) (xy 114.244821 -226.268996) (xy 114.208098 -226.232273) (xy 114.177572 -226.190257)
			(xy 114.153994 -226.143983) (xy 114.137946 -226.09459) (xy 114.129821 -226.043295) (xy 113.849911 -226.043295)
			(xy 113.841786 -226.09459) (xy 113.825738 -226.143983) (xy 113.80216 -226.190257) (xy 113.771634 -226.232273)
			(xy 113.734911 -226.268996) (xy 113.692895 -226.299522) (xy 113.646621 -226.3231) (xy 113.597228 -226.339148)
			(xy 113.545933 -226.347273) (xy 113.493999 -226.347273) (xy 113.442704 -226.339148) (xy 113.393311 -226.3231)
			(xy 113.347037 -226.299522) (xy 113.305021 -226.268996) (xy 113.268298 -226.232273) (xy 113.237772 -226.190257)
			(xy 113.214194 -226.143983) (xy 113.198146 -226.09459) (xy 113.190021 -226.043295) (xy 112.910111 -226.043295)
			(xy 112.901986 -226.09459) (xy 112.885938 -226.143983) (xy 112.86236 -226.190257) (xy 112.831834 -226.232273)
			(xy 112.795111 -226.268996) (xy 112.753095 -226.299522) (xy 112.706821 -226.3231) (xy 112.657428 -226.339148)
			(xy 112.606133 -226.347273) (xy 112.554199 -226.347273) (xy 112.502904 -226.339148) (xy 112.453511 -226.3231)
			(xy 112.407237 -226.299522) (xy 112.365221 -226.268996) (xy 112.328498 -226.232273) (xy 112.297972 -226.190257)
			(xy 112.274394 -226.143983) (xy 112.258346 -226.09459) (xy 112.250221 -226.043295) (xy 111.970311 -226.043295)
			(xy 111.962186 -226.09459) (xy 111.946138 -226.143983) (xy 111.92256 -226.190257) (xy 111.892034 -226.232273)
			(xy 111.855311 -226.268996) (xy 111.813295 -226.299522) (xy 111.767021 -226.3231) (xy 111.717628 -226.339148)
			(xy 111.666333 -226.347273) (xy 111.614399 -226.347273) (xy 111.563104 -226.339148) (xy 111.513711 -226.3231)
			(xy 111.467437 -226.299522) (xy 111.425421 -226.268996) (xy 111.388698 -226.232273) (xy 111.358172 -226.190257)
			(xy 111.334594 -226.143983) (xy 111.318546 -226.09459) (xy 111.310421 -226.043295) (xy 111.030511 -226.043295)
			(xy 111.022386 -226.09459) (xy 111.006338 -226.143983) (xy 110.98276 -226.190257) (xy 110.952234 -226.232273)
			(xy 110.915511 -226.268996) (xy 110.873495 -226.299522) (xy 110.827221 -226.3231) (xy 110.777828 -226.339148)
			(xy 110.726533 -226.347273) (xy 110.674599 -226.347273) (xy 110.623304 -226.339148) (xy 110.573911 -226.3231)
			(xy 110.527637 -226.299522) (xy 110.485621 -226.268996) (xy 110.448898 -226.232273) (xy 110.418372 -226.190257)
			(xy 110.394794 -226.143983) (xy 110.378746 -226.09459) (xy 110.370621 -226.043295) (xy 110.090711 -226.043295)
			(xy 110.082586 -226.09459) (xy 110.066538 -226.143983) (xy 110.04296 -226.190257) (xy 110.012434 -226.232273)
			(xy 109.975711 -226.268996) (xy 109.933695 -226.299522) (xy 109.887421 -226.3231) (xy 109.838028 -226.339148)
			(xy 109.786733 -226.347273) (xy 109.734799 -226.347273) (xy 109.683504 -226.339148) (xy 109.634111 -226.3231)
			(xy 109.587837 -226.299522) (xy 109.545821 -226.268996) (xy 109.509098 -226.232273) (xy 109.478572 -226.190257)
			(xy 109.454994 -226.143983) (xy 109.438946 -226.09459) (xy 109.430821 -226.043295) (xy 109.150911 -226.043295)
			(xy 109.142786 -226.09459) (xy 109.126738 -226.143983) (xy 109.10316 -226.190257) (xy 109.072634 -226.232273)
			(xy 109.035911 -226.268996) (xy 108.993895 -226.299522) (xy 108.947621 -226.3231) (xy 108.898228 -226.339148)
			(xy 108.846933 -226.347273) (xy 108.794999 -226.347273) (xy 108.743704 -226.339148) (xy 108.694311 -226.3231)
			(xy 108.648037 -226.299522) (xy 108.606021 -226.268996) (xy 108.569298 -226.232273) (xy 108.538772 -226.190257)
			(xy 108.515194 -226.143983) (xy 108.499146 -226.09459) (xy 108.491021 -226.043295) (xy 108.211111 -226.043295)
			(xy 108.202986 -226.09459) (xy 108.186938 -226.143983) (xy 108.16336 -226.190257) (xy 108.132834 -226.232273)
			(xy 108.096111 -226.268996) (xy 108.054095 -226.299522) (xy 108.007821 -226.3231) (xy 107.958428 -226.339148)
			(xy 107.907133 -226.347273) (xy 107.855199 -226.347273) (xy 107.803904 -226.339148) (xy 107.754511 -226.3231)
			(xy 107.708237 -226.299522) (xy 107.666221 -226.268996) (xy 107.629498 -226.232273) (xy 107.598972 -226.190257)
			(xy 107.575394 -226.143983) (xy 107.559346 -226.09459) (xy 107.551221 -226.043295) (xy 107.271083 -226.043295)
			(xy 107.264642 -226.087919) (xy 107.251248 -226.133371) (xy 107.231501 -226.176445) (xy 107.205808 -226.216259)
			(xy 107.174694 -226.251997) (xy 107.157012 -226.267772) (xy 107.146062 -226.277877) (xy 107.130048 -226.302985)
			(xy 107.121952 -226.331645) (xy 107.122463 -226.361422) (xy 107.131536 -226.389787) (xy 107.139486 -226.402392)
			(xy 107.156703 -226.427988) (xy 107.187601 -226.481387) (xy 107.201208 -226.509072) (xy 107.205987 -226.517833)
			(xy 107.220851 -226.53112) (xy 107.239647 -226.537768) (xy 107.259559 -226.536781) (xy 107.268772 -226.532948)
			(xy 107.29109 -226.522775) (xy 107.337984 -226.508406) (xy 107.386489 -226.501142) (xy 107.411012 -226.50069)
			(xy 107.436979 -226.501174) (xy 107.488275 -226.509301) (xy 107.537667 -226.525352) (xy 107.583939 -226.548933)
			(xy 107.625953 -226.579463) (xy 107.662674 -226.616189) (xy 107.693196 -226.658208) (xy 107.716769 -226.704485)
			(xy 107.732813 -226.75388) (xy 107.740931 -226.805176) (xy 107.741466 -226.831144) (xy 107.740999 -226.856523)
			(xy 107.740908 -226.857111) (xy 108.021121 -226.857111) (xy 108.021121 -226.805177) (xy 108.029246 -226.753882)
			(xy 108.045294 -226.704489) (xy 108.068872 -226.658215) (xy 108.099398 -226.616199) (xy 108.136121 -226.579476)
			(xy 108.178137 -226.54895) (xy 108.224411 -226.525372) (xy 108.273804 -226.509324) (xy 108.325099 -226.501199)
			(xy 108.377033 -226.501199) (xy 108.428328 -226.509324) (xy 108.477721 -226.525372) (xy 108.523995 -226.54895)
			(xy 108.566011 -226.579476) (xy 108.602734 -226.616199) (xy 108.63326 -226.658215) (xy 108.656838 -226.704489)
			(xy 108.672886 -226.753882) (xy 108.681011 -226.805177) (xy 108.68152 -226.831144) (xy 108.681011 -226.857111)
			(xy 108.960667 -226.857111) (xy 108.960667 -226.805177) (xy 108.968792 -226.753882) (xy 108.98484 -226.704489)
			(xy 109.008418 -226.658215) (xy 109.038944 -226.616199) (xy 109.075667 -226.579476) (xy 109.117683 -226.54895)
			(xy 109.163957 -226.525372) (xy 109.21335 -226.509324) (xy 109.264645 -226.501199) (xy 109.316579 -226.501199)
			(xy 109.367874 -226.509324) (xy 109.417267 -226.525372) (xy 109.463541 -226.54895) (xy 109.505557 -226.579476)
			(xy 109.54228 -226.616199) (xy 109.572806 -226.658215) (xy 109.596384 -226.704489) (xy 109.612432 -226.753882)
			(xy 109.620557 -226.805177) (xy 109.621066 -226.831144) (xy 109.620557 -226.857111) (xy 109.900721 -226.857111)
			(xy 109.900721 -226.805177) (xy 109.908846 -226.753882) (xy 109.924894 -226.704489) (xy 109.948472 -226.658215)
			(xy 109.978998 -226.616199) (xy 110.015721 -226.579476) (xy 110.057737 -226.54895) (xy 110.104011 -226.525372)
			(xy 110.153404 -226.509324) (xy 110.204699 -226.501199) (xy 110.256633 -226.501199) (xy 110.307928 -226.509324)
			(xy 110.357321 -226.525372) (xy 110.403595 -226.54895) (xy 110.445611 -226.579476) (xy 110.482334 -226.616199)
			(xy 110.51286 -226.658215) (xy 110.536438 -226.704489) (xy 110.552486 -226.753882) (xy 110.560611 -226.805177)
			(xy 110.56112 -226.831144) (xy 110.560611 -226.857111) (xy 110.840267 -226.857111) (xy 110.840267 -226.805177)
			(xy 110.848392 -226.753882) (xy 110.86444 -226.704489) (xy 110.888018 -226.658215) (xy 110.918544 -226.616199)
			(xy 110.955267 -226.579476) (xy 110.997283 -226.54895) (xy 111.043557 -226.525372) (xy 111.09295 -226.509324)
			(xy 111.144245 -226.501199) (xy 111.196179 -226.501199) (xy 111.247474 -226.509324) (xy 111.296867 -226.525372)
			(xy 111.343141 -226.54895) (xy 111.385157 -226.579476) (xy 111.42188 -226.616199) (xy 111.452406 -226.658215)
			(xy 111.475984 -226.704489) (xy 111.492032 -226.753882) (xy 111.500157 -226.805177) (xy 111.500666 -226.831144)
			(xy 111.500157 -226.857111) (xy 111.780321 -226.857111) (xy 111.780321 -226.805177) (xy 111.788446 -226.753882)
			(xy 111.804494 -226.704489) (xy 111.828072 -226.658215) (xy 111.858598 -226.616199) (xy 111.895321 -226.579476)
			(xy 111.937337 -226.54895) (xy 111.983611 -226.525372) (xy 112.033004 -226.509324) (xy 112.084299 -226.501199)
			(xy 112.136233 -226.501199) (xy 112.187528 -226.509324) (xy 112.236921 -226.525372) (xy 112.283195 -226.54895)
			(xy 112.325211 -226.579476) (xy 112.361934 -226.616199) (xy 112.39246 -226.658215) (xy 112.416038 -226.704489)
			(xy 112.432086 -226.753882) (xy 112.440211 -226.805177) (xy 112.44072 -226.831144) (xy 112.440211 -226.857111)
			(xy 112.719867 -226.857111) (xy 112.719867 -226.805177) (xy 112.727992 -226.753882) (xy 112.74404 -226.704489)
			(xy 112.767618 -226.658215) (xy 112.798144 -226.616199) (xy 112.834867 -226.579476) (xy 112.876883 -226.54895)
			(xy 112.923157 -226.525372) (xy 112.97255 -226.509324) (xy 113.023845 -226.501199) (xy 113.075779 -226.501199)
			(xy 113.127074 -226.509324) (xy 113.176467 -226.525372) (xy 113.222741 -226.54895) (xy 113.264757 -226.579476)
			(xy 113.30148 -226.616199) (xy 113.332006 -226.658215) (xy 113.355584 -226.704489) (xy 113.371632 -226.753882)
			(xy 113.379757 -226.805177) (xy 113.380266 -226.831144) (xy 113.379757 -226.857111) (xy 113.659921 -226.857111)
			(xy 113.659921 -226.805177) (xy 113.668046 -226.753882) (xy 113.684094 -226.704489) (xy 113.707672 -226.658215)
			(xy 113.738198 -226.616199) (xy 113.774921 -226.579476) (xy 113.816937 -226.54895) (xy 113.863211 -226.525372)
			(xy 113.912604 -226.509324) (xy 113.963899 -226.501199) (xy 114.015833 -226.501199) (xy 114.067128 -226.509324)
			(xy 114.116521 -226.525372) (xy 114.162795 -226.54895) (xy 114.204811 -226.579476) (xy 114.241534 -226.616199)
			(xy 114.27206 -226.658215) (xy 114.295638 -226.704489) (xy 114.311686 -226.753882) (xy 114.319811 -226.805177)
			(xy 114.32032 -226.831144) (xy 114.319811 -226.857111) (xy 114.599721 -226.857111) (xy 114.599721 -226.805177)
			(xy 114.607846 -226.753882) (xy 114.623894 -226.704489) (xy 114.647472 -226.658215) (xy 114.677998 -226.616199)
			(xy 114.714721 -226.579476) (xy 114.756737 -226.54895) (xy 114.803011 -226.525372) (xy 114.852404 -226.509324)
			(xy 114.903699 -226.501199) (xy 114.955633 -226.501199) (xy 115.006928 -226.509324) (xy 115.056321 -226.525372)
			(xy 115.102595 -226.54895) (xy 115.144611 -226.579476) (xy 115.181334 -226.616199) (xy 115.21186 -226.658215)
			(xy 115.235438 -226.704489) (xy 115.251486 -226.753882) (xy 115.259611 -226.805177) (xy 115.26012 -226.831144)
			(xy 115.259611 -226.857111) (xy 115.539521 -226.857111) (xy 115.539521 -226.805177) (xy 115.547646 -226.753882)
			(xy 115.563694 -226.704489) (xy 115.587272 -226.658215) (xy 115.617798 -226.616199) (xy 115.654521 -226.579476)
			(xy 115.696537 -226.54895) (xy 115.742811 -226.525372) (xy 115.792204 -226.509324) (xy 115.843499 -226.501199)
			(xy 115.895433 -226.501199) (xy 115.946728 -226.509324) (xy 115.996121 -226.525372) (xy 116.042395 -226.54895)
			(xy 116.084411 -226.579476) (xy 116.121134 -226.616199) (xy 116.15166 -226.658215) (xy 116.175238 -226.704489)
			(xy 116.191286 -226.753882) (xy 116.199411 -226.805177) (xy 116.19992 -226.831144) (xy 116.199411 -226.857111)
			(xy 116.479067 -226.857111) (xy 116.479067 -226.805177) (xy 116.487192 -226.753882) (xy 116.50324 -226.704489)
			(xy 116.526818 -226.658215) (xy 116.557344 -226.616199) (xy 116.594067 -226.579476) (xy 116.636083 -226.54895)
			(xy 116.682357 -226.525372) (xy 116.73175 -226.509324) (xy 116.783045 -226.501199) (xy 116.834979 -226.501199)
			(xy 116.886274 -226.509324) (xy 116.935667 -226.525372) (xy 116.981941 -226.54895) (xy 117.023957 -226.579476)
			(xy 117.06068 -226.616199) (xy 117.091206 -226.658215) (xy 117.114784 -226.704489) (xy 117.130832 -226.753882)
			(xy 117.138957 -226.805177) (xy 117.139466 -226.831144) (xy 117.138957 -226.857111) (xy 117.419121 -226.857111)
			(xy 117.419121 -226.805177) (xy 117.427246 -226.753882) (xy 117.443294 -226.704489) (xy 117.466872 -226.658215)
			(xy 117.497398 -226.616199) (xy 117.534121 -226.579476) (xy 117.576137 -226.54895) (xy 117.622411 -226.525372)
			(xy 117.671804 -226.509324) (xy 117.723099 -226.501199) (xy 117.775033 -226.501199) (xy 117.826328 -226.509324)
			(xy 117.875721 -226.525372) (xy 117.921995 -226.54895) (xy 117.964011 -226.579476) (xy 118.000734 -226.616199)
			(xy 118.03126 -226.658215) (xy 118.054838 -226.704489) (xy 118.070886 -226.753882) (xy 118.079011 -226.805177)
			(xy 118.07952 -226.831144) (xy 118.079011 -226.857111) (xy 118.358667 -226.857111) (xy 118.358667 -226.805177)
			(xy 118.366792 -226.753882) (xy 118.38284 -226.704489) (xy 118.406418 -226.658215) (xy 118.436944 -226.616199)
			(xy 118.473667 -226.579476) (xy 118.515683 -226.54895) (xy 118.561957 -226.525372) (xy 118.61135 -226.509324)
			(xy 118.662645 -226.501199) (xy 118.714579 -226.501199) (xy 118.765874 -226.509324) (xy 118.815267 -226.525372)
			(xy 118.861541 -226.54895) (xy 118.903557 -226.579476) (xy 118.94028 -226.616199) (xy 118.970806 -226.658215)
			(xy 118.994384 -226.704489) (xy 119.010432 -226.753882) (xy 119.018557 -226.805177) (xy 119.019066 -226.831144)
			(xy 119.018557 -226.857111) (xy 119.298721 -226.857111) (xy 119.298721 -226.805177) (xy 119.306846 -226.753882)
			(xy 119.322894 -226.704489) (xy 119.346472 -226.658215) (xy 119.376998 -226.616199) (xy 119.413721 -226.579476)
			(xy 119.455737 -226.54895) (xy 119.502011 -226.525372) (xy 119.551404 -226.509324) (xy 119.602699 -226.501199)
			(xy 119.654633 -226.501199) (xy 119.705928 -226.509324) (xy 119.755321 -226.525372) (xy 119.801595 -226.54895)
			(xy 119.843611 -226.579476) (xy 119.880334 -226.616199) (xy 119.91086 -226.658215) (xy 119.934438 -226.704489)
			(xy 119.950486 -226.753882) (xy 119.958611 -226.805177) (xy 119.95912 -226.831144) (xy 119.958611 -226.857111)
			(xy 120.238267 -226.857111) (xy 120.238267 -226.805177) (xy 120.246392 -226.753882) (xy 120.26244 -226.704489)
			(xy 120.286018 -226.658215) (xy 120.316544 -226.616199) (xy 120.353267 -226.579476) (xy 120.395283 -226.54895)
			(xy 120.441557 -226.525372) (xy 120.49095 -226.509324) (xy 120.542245 -226.501199) (xy 120.594179 -226.501199)
			(xy 120.645474 -226.509324) (xy 120.694867 -226.525372) (xy 120.741141 -226.54895) (xy 120.783157 -226.579476)
			(xy 120.81988 -226.616199) (xy 120.850406 -226.658215) (xy 120.873984 -226.704489) (xy 120.890032 -226.753882)
			(xy 120.898157 -226.805177) (xy 120.898666 -226.831144) (xy 120.898157 -226.857111) (xy 121.178321 -226.857111)
			(xy 121.178321 -226.805177) (xy 121.186446 -226.753882) (xy 121.202494 -226.704489) (xy 121.226072 -226.658215)
			(xy 121.256598 -226.616199) (xy 121.293321 -226.579476) (xy 121.335337 -226.54895) (xy 121.381611 -226.525372)
			(xy 121.431004 -226.509324) (xy 121.482299 -226.501199) (xy 121.534233 -226.501199) (xy 121.585528 -226.509324)
			(xy 121.634921 -226.525372) (xy 121.681195 -226.54895) (xy 121.723211 -226.579476) (xy 121.759934 -226.616199)
			(xy 121.79046 -226.658215) (xy 121.814038 -226.704489) (xy 121.830086 -226.753882) (xy 121.838211 -226.805177)
			(xy 121.83872 -226.831144) (xy 121.838211 -226.857111) (xy 122.117867 -226.857111) (xy 122.117867 -226.805177)
			(xy 122.125992 -226.753882) (xy 122.14204 -226.704489) (xy 122.165618 -226.658215) (xy 122.196144 -226.616199)
			(xy 122.232867 -226.579476) (xy 122.274883 -226.54895) (xy 122.321157 -226.525372) (xy 122.37055 -226.509324)
			(xy 122.421845 -226.501199) (xy 122.473779 -226.501199) (xy 122.525074 -226.509324) (xy 122.574467 -226.525372)
			(xy 122.620741 -226.54895) (xy 122.662757 -226.579476) (xy 122.69948 -226.616199) (xy 122.730006 -226.658215)
			(xy 122.753584 -226.704489) (xy 122.769632 -226.753882) (xy 122.777757 -226.805177) (xy 122.778266 -226.831144)
			(xy 122.777757 -226.857111) (xy 123.057667 -226.857111) (xy 123.057667 -226.805177) (xy 123.065792 -226.753882)
			(xy 123.08184 -226.704489) (xy 123.105418 -226.658215) (xy 123.135944 -226.616199) (xy 123.172667 -226.579476)
			(xy 123.214683 -226.54895) (xy 123.260957 -226.525372) (xy 123.31035 -226.509324) (xy 123.361645 -226.501199)
			(xy 123.413579 -226.501199) (xy 123.464874 -226.509324) (xy 123.514267 -226.525372) (xy 123.560541 -226.54895)
			(xy 123.602557 -226.579476) (xy 123.63928 -226.616199) (xy 123.669806 -226.658215) (xy 123.693384 -226.704489)
			(xy 123.709432 -226.753882) (xy 123.717557 -226.805177) (xy 123.718066 -226.831144) (xy 123.717557 -226.857111)
			(xy 123.997721 -226.857111) (xy 123.997721 -226.805177) (xy 124.005846 -226.753882) (xy 124.021894 -226.704489)
			(xy 124.045472 -226.658215) (xy 124.075998 -226.616199) (xy 124.112721 -226.579476) (xy 124.154737 -226.54895)
			(xy 124.201011 -226.525372) (xy 124.250404 -226.509324) (xy 124.301699 -226.501199) (xy 124.353633 -226.501199)
			(xy 124.404928 -226.509324) (xy 124.454321 -226.525372) (xy 124.500595 -226.54895) (xy 124.542611 -226.579476)
			(xy 124.579334 -226.616199) (xy 124.60986 -226.658215) (xy 124.633438 -226.704489) (xy 124.649486 -226.753882)
			(xy 124.657611 -226.805177) (xy 124.65812 -226.831144) (xy 124.657611 -226.857111) (xy 124.937267 -226.857111)
			(xy 124.937267 -226.805177) (xy 124.945392 -226.753882) (xy 124.96144 -226.704489) (xy 124.985018 -226.658215)
			(xy 125.015544 -226.616199) (xy 125.052267 -226.579476) (xy 125.094283 -226.54895) (xy 125.140557 -226.525372)
			(xy 125.18995 -226.509324) (xy 125.241245 -226.501199) (xy 125.293179 -226.501199) (xy 125.344474 -226.509324)
			(xy 125.393867 -226.525372) (xy 125.440141 -226.54895) (xy 125.482157 -226.579476) (xy 125.51888 -226.616199)
			(xy 125.549406 -226.658215) (xy 125.572984 -226.704489) (xy 125.589032 -226.753882) (xy 125.597157 -226.805177)
			(xy 125.597666 -226.831144) (xy 125.597157 -226.857111) (xy 125.877067 -226.857111) (xy 125.877067 -226.805177)
			(xy 125.885192 -226.753882) (xy 125.90124 -226.704489) (xy 125.924818 -226.658215) (xy 125.955344 -226.616199)
			(xy 125.992067 -226.579476) (xy 126.034083 -226.54895) (xy 126.080357 -226.525372) (xy 126.12975 -226.509324)
			(xy 126.181045 -226.501199) (xy 126.232979 -226.501199) (xy 126.284274 -226.509324) (xy 126.333667 -226.525372)
			(xy 126.379941 -226.54895) (xy 126.421957 -226.579476) (xy 126.45868 -226.616199) (xy 126.489206 -226.658215)
			(xy 126.512784 -226.704489) (xy 126.528832 -226.753882) (xy 126.536957 -226.805177) (xy 126.537466 -226.831144)
			(xy 126.536957 -226.857111) (xy 126.817121 -226.857111) (xy 126.817121 -226.805177) (xy 126.825246 -226.753882)
			(xy 126.841294 -226.704489) (xy 126.864872 -226.658215) (xy 126.895398 -226.616199) (xy 126.932121 -226.579476)
			(xy 126.974137 -226.54895) (xy 127.020411 -226.525372) (xy 127.069804 -226.509324) (xy 127.121099 -226.501199)
			(xy 127.173033 -226.501199) (xy 127.224328 -226.509324) (xy 127.273721 -226.525372) (xy 127.319995 -226.54895)
			(xy 127.362011 -226.579476) (xy 127.398734 -226.616199) (xy 127.42926 -226.658215) (xy 127.452838 -226.704489)
			(xy 127.468886 -226.753882) (xy 127.477011 -226.805177) (xy 127.47752 -226.831144) (xy 127.477011 -226.857111)
			(xy 127.468886 -226.908406) (xy 127.452838 -226.957799) (xy 127.42926 -227.004073) (xy 127.398734 -227.046089)
			(xy 127.362011 -227.082812) (xy 127.319995 -227.113338) (xy 127.273721 -227.136916) (xy 127.224328 -227.152964)
			(xy 127.173033 -227.161089) (xy 127.121099 -227.161089) (xy 127.069804 -227.152964) (xy 127.020411 -227.136916)
			(xy 126.974137 -227.113338) (xy 126.932121 -227.082812) (xy 126.895398 -227.046089) (xy 126.864872 -227.004073)
			(xy 126.841294 -226.957799) (xy 126.825246 -226.908406) (xy 126.817121 -226.857111) (xy 126.536957 -226.857111)
			(xy 126.528832 -226.908406) (xy 126.512784 -226.957799) (xy 126.489206 -227.004073) (xy 126.45868 -227.046089)
			(xy 126.421957 -227.082812) (xy 126.379941 -227.113338) (xy 126.333667 -227.136916) (xy 126.284274 -227.152964)
			(xy 126.232979 -227.161089) (xy 126.181045 -227.161089) (xy 126.12975 -227.152964) (xy 126.080357 -227.136916)
			(xy 126.034083 -227.113338) (xy 125.992067 -227.082812) (xy 125.955344 -227.046089) (xy 125.924818 -227.004073)
			(xy 125.90124 -226.957799) (xy 125.885192 -226.908406) (xy 125.877067 -226.857111) (xy 125.597157 -226.857111)
			(xy 125.589032 -226.908406) (xy 125.572984 -226.957799) (xy 125.549406 -227.004073) (xy 125.51888 -227.046089)
			(xy 125.482157 -227.082812) (xy 125.440141 -227.113338) (xy 125.393867 -227.136916) (xy 125.344474 -227.152964)
			(xy 125.293179 -227.161089) (xy 125.241245 -227.161089) (xy 125.18995 -227.152964) (xy 125.140557 -227.136916)
			(xy 125.094283 -227.113338) (xy 125.052267 -227.082812) (xy 125.015544 -227.046089) (xy 124.985018 -227.004073)
			(xy 124.96144 -226.957799) (xy 124.945392 -226.908406) (xy 124.937267 -226.857111) (xy 124.657611 -226.857111)
			(xy 124.649486 -226.908406) (xy 124.633438 -226.957799) (xy 124.60986 -227.004073) (xy 124.579334 -227.046089)
			(xy 124.542611 -227.082812) (xy 124.500595 -227.113338) (xy 124.454321 -227.136916) (xy 124.404928 -227.152964)
			(xy 124.353633 -227.161089) (xy 124.301699 -227.161089) (xy 124.250404 -227.152964) (xy 124.201011 -227.136916)
			(xy 124.154737 -227.113338) (xy 124.112721 -227.082812) (xy 124.075998 -227.046089) (xy 124.045472 -227.004073)
			(xy 124.021894 -226.957799) (xy 124.005846 -226.908406) (xy 123.997721 -226.857111) (xy 123.717557 -226.857111)
			(xy 123.709432 -226.908406) (xy 123.693384 -226.957799) (xy 123.669806 -227.004073) (xy 123.63928 -227.046089)
			(xy 123.602557 -227.082812) (xy 123.560541 -227.113338) (xy 123.514267 -227.136916) (xy 123.464874 -227.152964)
			(xy 123.413579 -227.161089) (xy 123.361645 -227.161089) (xy 123.31035 -227.152964) (xy 123.260957 -227.136916)
			(xy 123.214683 -227.113338) (xy 123.172667 -227.082812) (xy 123.135944 -227.046089) (xy 123.105418 -227.004073)
			(xy 123.08184 -226.957799) (xy 123.065792 -226.908406) (xy 123.057667 -226.857111) (xy 122.777757 -226.857111)
			(xy 122.769632 -226.908406) (xy 122.753584 -226.957799) (xy 122.730006 -227.004073) (xy 122.69948 -227.046089)
			(xy 122.662757 -227.082812) (xy 122.620741 -227.113338) (xy 122.574467 -227.136916) (xy 122.525074 -227.152964)
			(xy 122.473779 -227.161089) (xy 122.421845 -227.161089) (xy 122.37055 -227.152964) (xy 122.321157 -227.136916)
			(xy 122.274883 -227.113338) (xy 122.232867 -227.082812) (xy 122.196144 -227.046089) (xy 122.165618 -227.004073)
			(xy 122.14204 -226.957799) (xy 122.125992 -226.908406) (xy 122.117867 -226.857111) (xy 121.838211 -226.857111)
			(xy 121.830086 -226.908406) (xy 121.814038 -226.957799) (xy 121.79046 -227.004073) (xy 121.759934 -227.046089)
			(xy 121.723211 -227.082812) (xy 121.681195 -227.113338) (xy 121.634921 -227.136916) (xy 121.585528 -227.152964)
			(xy 121.534233 -227.161089) (xy 121.482299 -227.161089) (xy 121.431004 -227.152964) (xy 121.381611 -227.136916)
			(xy 121.335337 -227.113338) (xy 121.293321 -227.082812) (xy 121.256598 -227.046089) (xy 121.226072 -227.004073)
			(xy 121.202494 -226.957799) (xy 121.186446 -226.908406) (xy 121.178321 -226.857111) (xy 120.898157 -226.857111)
			(xy 120.890032 -226.908406) (xy 120.873984 -226.957799) (xy 120.850406 -227.004073) (xy 120.81988 -227.046089)
			(xy 120.783157 -227.082812) (xy 120.741141 -227.113338) (xy 120.694867 -227.136916) (xy 120.645474 -227.152964)
			(xy 120.594179 -227.161089) (xy 120.542245 -227.161089) (xy 120.49095 -227.152964) (xy 120.441557 -227.136916)
			(xy 120.395283 -227.113338) (xy 120.353267 -227.082812) (xy 120.316544 -227.046089) (xy 120.286018 -227.004073)
			(xy 120.26244 -226.957799) (xy 120.246392 -226.908406) (xy 120.238267 -226.857111) (xy 119.958611 -226.857111)
			(xy 119.950486 -226.908406) (xy 119.934438 -226.957799) (xy 119.91086 -227.004073) (xy 119.880334 -227.046089)
			(xy 119.843611 -227.082812) (xy 119.801595 -227.113338) (xy 119.755321 -227.136916) (xy 119.705928 -227.152964)
			(xy 119.654633 -227.161089) (xy 119.602699 -227.161089) (xy 119.551404 -227.152964) (xy 119.502011 -227.136916)
			(xy 119.455737 -227.113338) (xy 119.413721 -227.082812) (xy 119.376998 -227.046089) (xy 119.346472 -227.004073)
			(xy 119.322894 -226.957799) (xy 119.306846 -226.908406) (xy 119.298721 -226.857111) (xy 119.018557 -226.857111)
			(xy 119.010432 -226.908406) (xy 118.994384 -226.957799) (xy 118.970806 -227.004073) (xy 118.94028 -227.046089)
			(xy 118.903557 -227.082812) (xy 118.861541 -227.113338) (xy 118.815267 -227.136916) (xy 118.765874 -227.152964)
			(xy 118.714579 -227.161089) (xy 118.662645 -227.161089) (xy 118.61135 -227.152964) (xy 118.561957 -227.136916)
			(xy 118.515683 -227.113338) (xy 118.473667 -227.082812) (xy 118.436944 -227.046089) (xy 118.406418 -227.004073)
			(xy 118.38284 -226.957799) (xy 118.366792 -226.908406) (xy 118.358667 -226.857111) (xy 118.079011 -226.857111)
			(xy 118.070886 -226.908406) (xy 118.054838 -226.957799) (xy 118.03126 -227.004073) (xy 118.000734 -227.046089)
			(xy 117.964011 -227.082812) (xy 117.921995 -227.113338) (xy 117.875721 -227.136916) (xy 117.826328 -227.152964)
			(xy 117.775033 -227.161089) (xy 117.723099 -227.161089) (xy 117.671804 -227.152964) (xy 117.622411 -227.136916)
			(xy 117.576137 -227.113338) (xy 117.534121 -227.082812) (xy 117.497398 -227.046089) (xy 117.466872 -227.004073)
			(xy 117.443294 -226.957799) (xy 117.427246 -226.908406) (xy 117.419121 -226.857111) (xy 117.138957 -226.857111)
			(xy 117.130832 -226.908406) (xy 117.114784 -226.957799) (xy 117.091206 -227.004073) (xy 117.06068 -227.046089)
			(xy 117.023957 -227.082812) (xy 116.981941 -227.113338) (xy 116.935667 -227.136916) (xy 116.886274 -227.152964)
			(xy 116.834979 -227.161089) (xy 116.783045 -227.161089) (xy 116.73175 -227.152964) (xy 116.682357 -227.136916)
			(xy 116.636083 -227.113338) (xy 116.594067 -227.082812) (xy 116.557344 -227.046089) (xy 116.526818 -227.004073)
			(xy 116.50324 -226.957799) (xy 116.487192 -226.908406) (xy 116.479067 -226.857111) (xy 116.199411 -226.857111)
			(xy 116.191286 -226.908406) (xy 116.175238 -226.957799) (xy 116.15166 -227.004073) (xy 116.121134 -227.046089)
			(xy 116.084411 -227.082812) (xy 116.042395 -227.113338) (xy 115.996121 -227.136916) (xy 115.946728 -227.152964)
			(xy 115.895433 -227.161089) (xy 115.843499 -227.161089) (xy 115.792204 -227.152964) (xy 115.742811 -227.136916)
			(xy 115.696537 -227.113338) (xy 115.654521 -227.082812) (xy 115.617798 -227.046089) (xy 115.587272 -227.004073)
			(xy 115.563694 -226.957799) (xy 115.547646 -226.908406) (xy 115.539521 -226.857111) (xy 115.259611 -226.857111)
			(xy 115.251486 -226.908406) (xy 115.235438 -226.957799) (xy 115.21186 -227.004073) (xy 115.181334 -227.046089)
			(xy 115.144611 -227.082812) (xy 115.102595 -227.113338) (xy 115.056321 -227.136916) (xy 115.006928 -227.152964)
			(xy 114.955633 -227.161089) (xy 114.903699 -227.161089) (xy 114.852404 -227.152964) (xy 114.803011 -227.136916)
			(xy 114.756737 -227.113338) (xy 114.714721 -227.082812) (xy 114.677998 -227.046089) (xy 114.647472 -227.004073)
			(xy 114.623894 -226.957799) (xy 114.607846 -226.908406) (xy 114.599721 -226.857111) (xy 114.319811 -226.857111)
			(xy 114.311686 -226.908406) (xy 114.295638 -226.957799) (xy 114.27206 -227.004073) (xy 114.241534 -227.046089)
			(xy 114.204811 -227.082812) (xy 114.162795 -227.113338) (xy 114.116521 -227.136916) (xy 114.067128 -227.152964)
			(xy 114.015833 -227.161089) (xy 113.963899 -227.161089) (xy 113.912604 -227.152964) (xy 113.863211 -227.136916)
			(xy 113.816937 -227.113338) (xy 113.774921 -227.082812) (xy 113.738198 -227.046089) (xy 113.707672 -227.004073)
			(xy 113.684094 -226.957799) (xy 113.668046 -226.908406) (xy 113.659921 -226.857111) (xy 113.379757 -226.857111)
			(xy 113.371632 -226.908406) (xy 113.355584 -226.957799) (xy 113.332006 -227.004073) (xy 113.30148 -227.046089)
			(xy 113.264757 -227.082812) (xy 113.222741 -227.113338) (xy 113.176467 -227.136916) (xy 113.127074 -227.152964)
			(xy 113.075779 -227.161089) (xy 113.023845 -227.161089) (xy 112.97255 -227.152964) (xy 112.923157 -227.136916)
			(xy 112.876883 -227.113338) (xy 112.834867 -227.082812) (xy 112.798144 -227.046089) (xy 112.767618 -227.004073)
			(xy 112.74404 -226.957799) (xy 112.727992 -226.908406) (xy 112.719867 -226.857111) (xy 112.440211 -226.857111)
			(xy 112.432086 -226.908406) (xy 112.416038 -226.957799) (xy 112.39246 -227.004073) (xy 112.361934 -227.046089)
			(xy 112.325211 -227.082812) (xy 112.283195 -227.113338) (xy 112.236921 -227.136916) (xy 112.187528 -227.152964)
			(xy 112.136233 -227.161089) (xy 112.084299 -227.161089) (xy 112.033004 -227.152964) (xy 111.983611 -227.136916)
			(xy 111.937337 -227.113338) (xy 111.895321 -227.082812) (xy 111.858598 -227.046089) (xy 111.828072 -227.004073)
			(xy 111.804494 -226.957799) (xy 111.788446 -226.908406) (xy 111.780321 -226.857111) (xy 111.500157 -226.857111)
			(xy 111.492032 -226.908406) (xy 111.475984 -226.957799) (xy 111.452406 -227.004073) (xy 111.42188 -227.046089)
			(xy 111.385157 -227.082812) (xy 111.343141 -227.113338) (xy 111.296867 -227.136916) (xy 111.247474 -227.152964)
			(xy 111.196179 -227.161089) (xy 111.144245 -227.161089) (xy 111.09295 -227.152964) (xy 111.043557 -227.136916)
			(xy 110.997283 -227.113338) (xy 110.955267 -227.082812) (xy 110.918544 -227.046089) (xy 110.888018 -227.004073)
			(xy 110.86444 -226.957799) (xy 110.848392 -226.908406) (xy 110.840267 -226.857111) (xy 110.560611 -226.857111)
			(xy 110.552486 -226.908406) (xy 110.536438 -226.957799) (xy 110.51286 -227.004073) (xy 110.482334 -227.046089)
			(xy 110.445611 -227.082812) (xy 110.403595 -227.113338) (xy 110.357321 -227.136916) (xy 110.307928 -227.152964)
			(xy 110.256633 -227.161089) (xy 110.204699 -227.161089) (xy 110.153404 -227.152964) (xy 110.104011 -227.136916)
			(xy 110.057737 -227.113338) (xy 110.015721 -227.082812) (xy 109.978998 -227.046089) (xy 109.948472 -227.004073)
			(xy 109.924894 -226.957799) (xy 109.908846 -226.908406) (xy 109.900721 -226.857111) (xy 109.620557 -226.857111)
			(xy 109.612432 -226.908406) (xy 109.596384 -226.957799) (xy 109.572806 -227.004073) (xy 109.54228 -227.046089)
			(xy 109.505557 -227.082812) (xy 109.463541 -227.113338) (xy 109.417267 -227.136916) (xy 109.367874 -227.152964)
			(xy 109.316579 -227.161089) (xy 109.264645 -227.161089) (xy 109.21335 -227.152964) (xy 109.163957 -227.136916)
			(xy 109.117683 -227.113338) (xy 109.075667 -227.082812) (xy 109.038944 -227.046089) (xy 109.008418 -227.004073)
			(xy 108.98484 -226.957799) (xy 108.968792 -226.908406) (xy 108.960667 -226.857111) (xy 108.681011 -226.857111)
			(xy 108.672886 -226.908406) (xy 108.656838 -226.957799) (xy 108.63326 -227.004073) (xy 108.602734 -227.046089)
			(xy 108.566011 -227.082812) (xy 108.523995 -227.113338) (xy 108.477721 -227.136916) (xy 108.428328 -227.152964)
			(xy 108.377033 -227.161089) (xy 108.325099 -227.161089) (xy 108.273804 -227.152964) (xy 108.224411 -227.136916)
			(xy 108.178137 -227.113338) (xy 108.136121 -227.082812) (xy 108.099398 -227.046089) (xy 108.068872 -227.004073)
			(xy 108.045294 -226.957799) (xy 108.029246 -226.908406) (xy 108.021121 -226.857111) (xy 107.740908 -226.857111)
			(xy 107.733231 -226.906684) (xy 107.717884 -226.955067) (xy 107.69532 -227.000534) (xy 107.666068 -227.042017)
			(xy 107.630818 -227.078539) (xy 107.61091 -227.094288) (xy 107.599005 -227.103964) (xy 107.581159 -227.128902)
			(xy 107.571519 -227.158013) (xy 107.570955 -227.188673) (xy 107.579518 -227.218118) (xy 107.587542 -227.231194)
			(xy 107.597287 -227.246253) (xy 107.61533 -227.277258) (xy 107.62361 -227.29317) (xy 107.631118 -227.306384)
			(xy 107.652428 -227.32803) (xy 107.679147 -227.342479) (xy 107.708928 -227.348461) (xy 107.739154 -227.345452)
			(xy 107.753404 -227.34016) (xy 107.77371 -227.332027) (xy 107.815931 -227.320587) (xy 107.859294 -227.314834)
			(xy 107.881166 -227.314506) (xy 107.907136 -227.315013) (xy 107.958438 -227.323133) (xy 108.007837 -227.339178)
			(xy 108.054119 -227.362753) (xy 108.096143 -227.393278) (xy 108.132874 -227.430001) (xy 108.163408 -227.472018)
			(xy 108.186994 -227.518294) (xy 108.20305 -227.56769) (xy 108.211182 -227.61899) (xy 108.21162 -227.64496)
			(xy 108.211159 -227.670343) (xy 108.211069 -227.670927) (xy 108.491021 -227.670927) (xy 108.491021 -227.618993)
			(xy 108.499146 -227.567698) (xy 108.515194 -227.518305) (xy 108.538772 -227.472031) (xy 108.569298 -227.430015)
			(xy 108.606021 -227.393292) (xy 108.648037 -227.362766) (xy 108.694311 -227.339188) (xy 108.743704 -227.32314)
			(xy 108.794999 -227.315015) (xy 108.846933 -227.315015) (xy 108.898228 -227.32314) (xy 108.947621 -227.339188)
			(xy 108.993895 -227.362766) (xy 109.035911 -227.393292) (xy 109.072634 -227.430015) (xy 109.10316 -227.472031)
			(xy 109.126738 -227.518305) (xy 109.142786 -227.567698) (xy 109.150911 -227.618993) (xy 109.15142 -227.64496)
			(xy 109.150911 -227.670927) (xy 109.430821 -227.670927) (xy 109.430821 -227.618993) (xy 109.438946 -227.567698)
			(xy 109.454994 -227.518305) (xy 109.478572 -227.472031) (xy 109.509098 -227.430015) (xy 109.545821 -227.393292)
			(xy 109.587837 -227.362766) (xy 109.634111 -227.339188) (xy 109.683504 -227.32314) (xy 109.734799 -227.315015)
			(xy 109.786733 -227.315015) (xy 109.838028 -227.32314) (xy 109.887421 -227.339188) (xy 109.933695 -227.362766)
			(xy 109.975711 -227.393292) (xy 110.012434 -227.430015) (xy 110.04296 -227.472031) (xy 110.066538 -227.518305)
			(xy 110.082586 -227.567698) (xy 110.090711 -227.618993) (xy 110.09122 -227.64496) (xy 110.090711 -227.670927)
			(xy 110.370621 -227.670927) (xy 110.370621 -227.618993) (xy 110.378746 -227.567698) (xy 110.394794 -227.518305)
			(xy 110.418372 -227.472031) (xy 110.448898 -227.430015) (xy 110.485621 -227.393292) (xy 110.527637 -227.362766)
			(xy 110.573911 -227.339188) (xy 110.623304 -227.32314) (xy 110.674599 -227.315015) (xy 110.726533 -227.315015)
			(xy 110.777828 -227.32314) (xy 110.827221 -227.339188) (xy 110.873495 -227.362766) (xy 110.915511 -227.393292)
			(xy 110.952234 -227.430015) (xy 110.98276 -227.472031) (xy 111.006338 -227.518305) (xy 111.022386 -227.567698)
			(xy 111.030511 -227.618993) (xy 111.03102 -227.64496) (xy 111.030511 -227.670927) (xy 111.310421 -227.670927)
			(xy 111.310421 -227.618993) (xy 111.318546 -227.567698) (xy 111.334594 -227.518305) (xy 111.358172 -227.472031)
			(xy 111.388698 -227.430015) (xy 111.425421 -227.393292) (xy 111.467437 -227.362766) (xy 111.513711 -227.339188)
			(xy 111.563104 -227.32314) (xy 111.614399 -227.315015) (xy 111.666333 -227.315015) (xy 111.717628 -227.32314)
			(xy 111.767021 -227.339188) (xy 111.813295 -227.362766) (xy 111.855311 -227.393292) (xy 111.892034 -227.430015)
			(xy 111.92256 -227.472031) (xy 111.946138 -227.518305) (xy 111.962186 -227.567698) (xy 111.970311 -227.618993)
			(xy 111.97082 -227.64496) (xy 111.970311 -227.670927) (xy 112.250221 -227.670927) (xy 112.250221 -227.618993)
			(xy 112.258346 -227.567698) (xy 112.274394 -227.518305) (xy 112.297972 -227.472031) (xy 112.328498 -227.430015)
			(xy 112.365221 -227.393292) (xy 112.407237 -227.362766) (xy 112.453511 -227.339188) (xy 112.502904 -227.32314)
			(xy 112.554199 -227.315015) (xy 112.606133 -227.315015) (xy 112.657428 -227.32314) (xy 112.706821 -227.339188)
			(xy 112.753095 -227.362766) (xy 112.795111 -227.393292) (xy 112.831834 -227.430015) (xy 112.86236 -227.472031)
			(xy 112.885938 -227.518305) (xy 112.901986 -227.567698) (xy 112.910111 -227.618993) (xy 112.91062 -227.64496)
			(xy 112.910111 -227.670927) (xy 113.190021 -227.670927) (xy 113.190021 -227.618993) (xy 113.198146 -227.567698)
			(xy 113.214194 -227.518305) (xy 113.237772 -227.472031) (xy 113.268298 -227.430015) (xy 113.305021 -227.393292)
			(xy 113.347037 -227.362766) (xy 113.393311 -227.339188) (xy 113.442704 -227.32314) (xy 113.493999 -227.315015)
			(xy 113.545933 -227.315015) (xy 113.597228 -227.32314) (xy 113.646621 -227.339188) (xy 113.692895 -227.362766)
			(xy 113.734911 -227.393292) (xy 113.771634 -227.430015) (xy 113.80216 -227.472031) (xy 113.825738 -227.518305)
			(xy 113.841786 -227.567698) (xy 113.849911 -227.618993) (xy 113.85042 -227.64496) (xy 113.849911 -227.670927)
			(xy 114.130075 -227.670927) (xy 114.130075 -227.618993) (xy 114.1382 -227.567698) (xy 114.154248 -227.518305)
			(xy 114.177826 -227.472031) (xy 114.208352 -227.430015) (xy 114.245075 -227.393292) (xy 114.287091 -227.362766)
			(xy 114.333365 -227.339188) (xy 114.382758 -227.32314) (xy 114.434053 -227.315015) (xy 114.485987 -227.315015)
			(xy 114.537282 -227.32314) (xy 114.586675 -227.339188) (xy 114.632949 -227.362766) (xy 114.674965 -227.393292)
			(xy 114.711688 -227.430015) (xy 114.742214 -227.472031) (xy 114.765792 -227.518305) (xy 114.78184 -227.567698)
			(xy 114.789965 -227.618993) (xy 114.790474 -227.64496) (xy 114.789965 -227.670927) (xy 115.069621 -227.670927)
			(xy 115.069621 -227.618993) (xy 115.077746 -227.567698) (xy 115.093794 -227.518305) (xy 115.117372 -227.472031)
			(xy 115.147898 -227.430015) (xy 115.184621 -227.393292) (xy 115.226637 -227.362766) (xy 115.272911 -227.339188)
			(xy 115.322304 -227.32314) (xy 115.373599 -227.315015) (xy 115.425533 -227.315015) (xy 115.476828 -227.32314)
			(xy 115.526221 -227.339188) (xy 115.572495 -227.362766) (xy 115.614511 -227.393292) (xy 115.651234 -227.430015)
			(xy 115.68176 -227.472031) (xy 115.705338 -227.518305) (xy 115.721386 -227.567698) (xy 115.729511 -227.618993)
			(xy 115.73002 -227.64496) (xy 115.729511 -227.670927) (xy 116.009421 -227.670927) (xy 116.009421 -227.618993)
			(xy 116.017546 -227.567698) (xy 116.033594 -227.518305) (xy 116.057172 -227.472031) (xy 116.087698 -227.430015)
			(xy 116.124421 -227.393292) (xy 116.166437 -227.362766) (xy 116.212711 -227.339188) (xy 116.262104 -227.32314)
			(xy 116.313399 -227.315015) (xy 116.365333 -227.315015) (xy 116.416628 -227.32314) (xy 116.466021 -227.339188)
			(xy 116.512295 -227.362766) (xy 116.554311 -227.393292) (xy 116.591034 -227.430015) (xy 116.62156 -227.472031)
			(xy 116.645138 -227.518305) (xy 116.661186 -227.567698) (xy 116.669311 -227.618993) (xy 116.66982 -227.64496)
			(xy 116.669311 -227.670927) (xy 116.949221 -227.670927) (xy 116.949221 -227.618993) (xy 116.957346 -227.567698)
			(xy 116.973394 -227.518305) (xy 116.996972 -227.472031) (xy 117.027498 -227.430015) (xy 117.064221 -227.393292)
			(xy 117.106237 -227.362766) (xy 117.152511 -227.339188) (xy 117.201904 -227.32314) (xy 117.253199 -227.315015)
			(xy 117.305133 -227.315015) (xy 117.356428 -227.32314) (xy 117.405821 -227.339188) (xy 117.452095 -227.362766)
			(xy 117.494111 -227.393292) (xy 117.530834 -227.430015) (xy 117.56136 -227.472031) (xy 117.584938 -227.518305)
			(xy 117.600986 -227.567698) (xy 117.609111 -227.618993) (xy 117.60962 -227.64496) (xy 117.609111 -227.670927)
			(xy 117.889021 -227.670927) (xy 117.889021 -227.618993) (xy 117.897146 -227.567698) (xy 117.913194 -227.518305)
			(xy 117.936772 -227.472031) (xy 117.967298 -227.430015) (xy 118.004021 -227.393292) (xy 118.046037 -227.362766)
			(xy 118.092311 -227.339188) (xy 118.141704 -227.32314) (xy 118.192999 -227.315015) (xy 118.244933 -227.315015)
			(xy 118.296228 -227.32314) (xy 118.345621 -227.339188) (xy 118.391895 -227.362766) (xy 118.433911 -227.393292)
			(xy 118.470634 -227.430015) (xy 118.50116 -227.472031) (xy 118.524738 -227.518305) (xy 118.540786 -227.567698)
			(xy 118.548911 -227.618993) (xy 118.54942 -227.64496) (xy 118.548911 -227.670927) (xy 118.828821 -227.670927)
			(xy 118.828821 -227.618993) (xy 118.836946 -227.567698) (xy 118.852994 -227.518305) (xy 118.876572 -227.472031)
			(xy 118.907098 -227.430015) (xy 118.943821 -227.393292) (xy 118.985837 -227.362766) (xy 119.032111 -227.339188)
			(xy 119.081504 -227.32314) (xy 119.132799 -227.315015) (xy 119.184733 -227.315015) (xy 119.236028 -227.32314)
			(xy 119.285421 -227.339188) (xy 119.331695 -227.362766) (xy 119.373711 -227.393292) (xy 119.410434 -227.430015)
			(xy 119.44096 -227.472031) (xy 119.464538 -227.518305) (xy 119.480586 -227.567698) (xy 119.488711 -227.618993)
			(xy 119.48922 -227.64496) (xy 119.488711 -227.670927) (xy 119.768621 -227.670927) (xy 119.768621 -227.618993)
			(xy 119.776746 -227.567698) (xy 119.792794 -227.518305) (xy 119.816372 -227.472031) (xy 119.846898 -227.430015)
			(xy 119.883621 -227.393292) (xy 119.925637 -227.362766) (xy 119.971911 -227.339188) (xy 120.021304 -227.32314)
			(xy 120.072599 -227.315015) (xy 120.124533 -227.315015) (xy 120.175828 -227.32314) (xy 120.225221 -227.339188)
			(xy 120.271495 -227.362766) (xy 120.313511 -227.393292) (xy 120.350234 -227.430015) (xy 120.38076 -227.472031)
			(xy 120.404338 -227.518305) (xy 120.420386 -227.567698) (xy 120.428511 -227.618993) (xy 120.42902 -227.64496)
			(xy 120.428511 -227.670927) (xy 120.708421 -227.670927) (xy 120.708421 -227.618993) (xy 120.716546 -227.567698)
			(xy 120.732594 -227.518305) (xy 120.756172 -227.472031) (xy 120.786698 -227.430015) (xy 120.823421 -227.393292)
			(xy 120.865437 -227.362766) (xy 120.911711 -227.339188) (xy 120.961104 -227.32314) (xy 121.012399 -227.315015)
			(xy 121.064333 -227.315015) (xy 121.115628 -227.32314) (xy 121.165021 -227.339188) (xy 121.211295 -227.362766)
			(xy 121.253311 -227.393292) (xy 121.290034 -227.430015) (xy 121.32056 -227.472031) (xy 121.344138 -227.518305)
			(xy 121.360186 -227.567698) (xy 121.368311 -227.618993) (xy 121.36882 -227.64496) (xy 121.368311 -227.670927)
			(xy 121.647967 -227.670927) (xy 121.647967 -227.618993) (xy 121.656092 -227.567698) (xy 121.67214 -227.518305)
			(xy 121.695718 -227.472031) (xy 121.726244 -227.430015) (xy 121.762967 -227.393292) (xy 121.804983 -227.362766)
			(xy 121.851257 -227.339188) (xy 121.90065 -227.32314) (xy 121.951945 -227.315015) (xy 122.003879 -227.315015)
			(xy 122.055174 -227.32314) (xy 122.104567 -227.339188) (xy 122.150841 -227.362766) (xy 122.192857 -227.393292)
			(xy 122.22958 -227.430015) (xy 122.260106 -227.472031) (xy 122.283684 -227.518305) (xy 122.299732 -227.567698)
			(xy 122.307857 -227.618993) (xy 122.308366 -227.64496) (xy 122.307857 -227.670927) (xy 122.588021 -227.670927)
			(xy 122.588021 -227.618993) (xy 122.596146 -227.567698) (xy 122.612194 -227.518305) (xy 122.635772 -227.472031)
			(xy 122.666298 -227.430015) (xy 122.703021 -227.393292) (xy 122.745037 -227.362766) (xy 122.791311 -227.339188)
			(xy 122.840704 -227.32314) (xy 122.891999 -227.315015) (xy 122.943933 -227.315015) (xy 122.995228 -227.32314)
			(xy 123.044621 -227.339188) (xy 123.090895 -227.362766) (xy 123.132911 -227.393292) (xy 123.169634 -227.430015)
			(xy 123.20016 -227.472031) (xy 123.223738 -227.518305) (xy 123.239786 -227.567698) (xy 123.247911 -227.618993)
			(xy 123.24842 -227.64496) (xy 123.247911 -227.670927) (xy 123.527821 -227.670927) (xy 123.527821 -227.618993)
			(xy 123.535946 -227.567698) (xy 123.551994 -227.518305) (xy 123.575572 -227.472031) (xy 123.606098 -227.430015)
			(xy 123.642821 -227.393292) (xy 123.684837 -227.362766) (xy 123.731111 -227.339188) (xy 123.780504 -227.32314)
			(xy 123.831799 -227.315015) (xy 123.883733 -227.315015) (xy 123.935028 -227.32314) (xy 123.984421 -227.339188)
			(xy 124.030695 -227.362766) (xy 124.072711 -227.393292) (xy 124.109434 -227.430015) (xy 124.13996 -227.472031)
			(xy 124.163538 -227.518305) (xy 124.179586 -227.567698) (xy 124.187711 -227.618993) (xy 124.18822 -227.64496)
			(xy 124.187711 -227.670927) (xy 124.467621 -227.670927) (xy 124.467621 -227.618993) (xy 124.475746 -227.567698)
			(xy 124.491794 -227.518305) (xy 124.515372 -227.472031) (xy 124.545898 -227.430015) (xy 124.582621 -227.393292)
			(xy 124.624637 -227.362766) (xy 124.670911 -227.339188) (xy 124.720304 -227.32314) (xy 124.771599 -227.315015)
			(xy 124.823533 -227.315015) (xy 124.874828 -227.32314) (xy 124.924221 -227.339188) (xy 124.970495 -227.362766)
			(xy 125.012511 -227.393292) (xy 125.049234 -227.430015) (xy 125.07976 -227.472031) (xy 125.103338 -227.518305)
			(xy 125.119386 -227.567698) (xy 125.127511 -227.618993) (xy 125.12802 -227.64496) (xy 125.127511 -227.670927)
			(xy 125.407421 -227.670927) (xy 125.407421 -227.618993) (xy 125.415546 -227.567698) (xy 125.431594 -227.518305)
			(xy 125.455172 -227.472031) (xy 125.485698 -227.430015) (xy 125.522421 -227.393292) (xy 125.564437 -227.362766)
			(xy 125.610711 -227.339188) (xy 125.660104 -227.32314) (xy 125.711399 -227.315015) (xy 125.763333 -227.315015)
			(xy 125.814628 -227.32314) (xy 125.864021 -227.339188) (xy 125.910295 -227.362766) (xy 125.952311 -227.393292)
			(xy 125.989034 -227.430015) (xy 126.01956 -227.472031) (xy 126.043138 -227.518305) (xy 126.059186 -227.567698)
			(xy 126.067311 -227.618993) (xy 126.06782 -227.64496) (xy 126.067311 -227.670927) (xy 126.347221 -227.670927)
			(xy 126.347221 -227.618993) (xy 126.355346 -227.567698) (xy 126.371394 -227.518305) (xy 126.394972 -227.472031)
			(xy 126.425498 -227.430015) (xy 126.462221 -227.393292) (xy 126.504237 -227.362766) (xy 126.550511 -227.339188)
			(xy 126.599904 -227.32314) (xy 126.651199 -227.315015) (xy 126.703133 -227.315015) (xy 126.754428 -227.32314)
			(xy 126.803821 -227.339188) (xy 126.850095 -227.362766) (xy 126.892111 -227.393292) (xy 126.928834 -227.430015)
			(xy 126.95936 -227.472031) (xy 126.982938 -227.518305) (xy 126.998986 -227.567698) (xy 127.007111 -227.618993)
			(xy 127.00762 -227.64496) (xy 127.007111 -227.670927) (xy 126.998986 -227.722222) (xy 126.982938 -227.771615)
			(xy 126.95936 -227.817889) (xy 126.928834 -227.859905) (xy 126.892111 -227.896628) (xy 126.850095 -227.927154)
			(xy 126.803821 -227.950732) (xy 126.754428 -227.96678) (xy 126.703133 -227.974905) (xy 126.651199 -227.974905)
			(xy 126.599904 -227.96678) (xy 126.550511 -227.950732) (xy 126.504237 -227.927154) (xy 126.462221 -227.896628)
			(xy 126.425498 -227.859905) (xy 126.394972 -227.817889) (xy 126.371394 -227.771615) (xy 126.355346 -227.722222)
			(xy 126.347221 -227.670927) (xy 126.067311 -227.670927) (xy 126.059186 -227.722222) (xy 126.043138 -227.771615)
			(xy 126.01956 -227.817889) (xy 125.989034 -227.859905) (xy 125.952311 -227.896628) (xy 125.910295 -227.927154)
			(xy 125.864021 -227.950732) (xy 125.814628 -227.96678) (xy 125.763333 -227.974905) (xy 125.711399 -227.974905)
			(xy 125.660104 -227.96678) (xy 125.610711 -227.950732) (xy 125.564437 -227.927154) (xy 125.522421 -227.896628)
			(xy 125.485698 -227.859905) (xy 125.455172 -227.817889) (xy 125.431594 -227.771615) (xy 125.415546 -227.722222)
			(xy 125.407421 -227.670927) (xy 125.127511 -227.670927) (xy 125.119386 -227.722222) (xy 125.103338 -227.771615)
			(xy 125.07976 -227.817889) (xy 125.049234 -227.859905) (xy 125.012511 -227.896628) (xy 124.970495 -227.927154)
			(xy 124.924221 -227.950732) (xy 124.874828 -227.96678) (xy 124.823533 -227.974905) (xy 124.771599 -227.974905)
			(xy 124.720304 -227.96678) (xy 124.670911 -227.950732) (xy 124.624637 -227.927154) (xy 124.582621 -227.896628)
			(xy 124.545898 -227.859905) (xy 124.515372 -227.817889) (xy 124.491794 -227.771615) (xy 124.475746 -227.722222)
			(xy 124.467621 -227.670927) (xy 124.187711 -227.670927) (xy 124.179586 -227.722222) (xy 124.163538 -227.771615)
			(xy 124.13996 -227.817889) (xy 124.109434 -227.859905) (xy 124.072711 -227.896628) (xy 124.030695 -227.927154)
			(xy 123.984421 -227.950732) (xy 123.935028 -227.96678) (xy 123.883733 -227.974905) (xy 123.831799 -227.974905)
			(xy 123.780504 -227.96678) (xy 123.731111 -227.950732) (xy 123.684837 -227.927154) (xy 123.642821 -227.896628)
			(xy 123.606098 -227.859905) (xy 123.575572 -227.817889) (xy 123.551994 -227.771615) (xy 123.535946 -227.722222)
			(xy 123.527821 -227.670927) (xy 123.247911 -227.670927) (xy 123.239786 -227.722222) (xy 123.223738 -227.771615)
			(xy 123.20016 -227.817889) (xy 123.169634 -227.859905) (xy 123.132911 -227.896628) (xy 123.090895 -227.927154)
			(xy 123.044621 -227.950732) (xy 122.995228 -227.96678) (xy 122.943933 -227.974905) (xy 122.891999 -227.974905)
			(xy 122.840704 -227.96678) (xy 122.791311 -227.950732) (xy 122.745037 -227.927154) (xy 122.703021 -227.896628)
			(xy 122.666298 -227.859905) (xy 122.635772 -227.817889) (xy 122.612194 -227.771615) (xy 122.596146 -227.722222)
			(xy 122.588021 -227.670927) (xy 122.307857 -227.670927) (xy 122.299732 -227.722222) (xy 122.283684 -227.771615)
			(xy 122.260106 -227.817889) (xy 122.22958 -227.859905) (xy 122.192857 -227.896628) (xy 122.150841 -227.927154)
			(xy 122.104567 -227.950732) (xy 122.055174 -227.96678) (xy 122.003879 -227.974905) (xy 121.951945 -227.974905)
			(xy 121.90065 -227.96678) (xy 121.851257 -227.950732) (xy 121.804983 -227.927154) (xy 121.762967 -227.896628)
			(xy 121.726244 -227.859905) (xy 121.695718 -227.817889) (xy 121.67214 -227.771615) (xy 121.656092 -227.722222)
			(xy 121.647967 -227.670927) (xy 121.368311 -227.670927) (xy 121.360186 -227.722222) (xy 121.344138 -227.771615)
			(xy 121.32056 -227.817889) (xy 121.290034 -227.859905) (xy 121.253311 -227.896628) (xy 121.211295 -227.927154)
			(xy 121.165021 -227.950732) (xy 121.115628 -227.96678) (xy 121.064333 -227.974905) (xy 121.012399 -227.974905)
			(xy 120.961104 -227.96678) (xy 120.911711 -227.950732) (xy 120.865437 -227.927154) (xy 120.823421 -227.896628)
			(xy 120.786698 -227.859905) (xy 120.756172 -227.817889) (xy 120.732594 -227.771615) (xy 120.716546 -227.722222)
			(xy 120.708421 -227.670927) (xy 120.428511 -227.670927) (xy 120.420386 -227.722222) (xy 120.404338 -227.771615)
			(xy 120.38076 -227.817889) (xy 120.350234 -227.859905) (xy 120.313511 -227.896628) (xy 120.271495 -227.927154)
			(xy 120.225221 -227.950732) (xy 120.175828 -227.96678) (xy 120.124533 -227.974905) (xy 120.072599 -227.974905)
			(xy 120.021304 -227.96678) (xy 119.971911 -227.950732) (xy 119.925637 -227.927154) (xy 119.883621 -227.896628)
			(xy 119.846898 -227.859905) (xy 119.816372 -227.817889) (xy 119.792794 -227.771615) (xy 119.776746 -227.722222)
			(xy 119.768621 -227.670927) (xy 119.488711 -227.670927) (xy 119.480586 -227.722222) (xy 119.464538 -227.771615)
			(xy 119.44096 -227.817889) (xy 119.410434 -227.859905) (xy 119.373711 -227.896628) (xy 119.331695 -227.927154)
			(xy 119.285421 -227.950732) (xy 119.236028 -227.96678) (xy 119.184733 -227.974905) (xy 119.132799 -227.974905)
			(xy 119.081504 -227.96678) (xy 119.032111 -227.950732) (xy 118.985837 -227.927154) (xy 118.943821 -227.896628)
			(xy 118.907098 -227.859905) (xy 118.876572 -227.817889) (xy 118.852994 -227.771615) (xy 118.836946 -227.722222)
			(xy 118.828821 -227.670927) (xy 118.548911 -227.670927) (xy 118.540786 -227.722222) (xy 118.524738 -227.771615)
			(xy 118.50116 -227.817889) (xy 118.470634 -227.859905) (xy 118.433911 -227.896628) (xy 118.391895 -227.927154)
			(xy 118.345621 -227.950732) (xy 118.296228 -227.96678) (xy 118.244933 -227.974905) (xy 118.192999 -227.974905)
			(xy 118.141704 -227.96678) (xy 118.092311 -227.950732) (xy 118.046037 -227.927154) (xy 118.004021 -227.896628)
			(xy 117.967298 -227.859905) (xy 117.936772 -227.817889) (xy 117.913194 -227.771615) (xy 117.897146 -227.722222)
			(xy 117.889021 -227.670927) (xy 117.609111 -227.670927) (xy 117.600986 -227.722222) (xy 117.584938 -227.771615)
			(xy 117.56136 -227.817889) (xy 117.530834 -227.859905) (xy 117.494111 -227.896628) (xy 117.452095 -227.927154)
			(xy 117.405821 -227.950732) (xy 117.356428 -227.96678) (xy 117.305133 -227.974905) (xy 117.253199 -227.974905)
			(xy 117.201904 -227.96678) (xy 117.152511 -227.950732) (xy 117.106237 -227.927154) (xy 117.064221 -227.896628)
			(xy 117.027498 -227.859905) (xy 116.996972 -227.817889) (xy 116.973394 -227.771615) (xy 116.957346 -227.722222)
			(xy 116.949221 -227.670927) (xy 116.669311 -227.670927) (xy 116.661186 -227.722222) (xy 116.645138 -227.771615)
			(xy 116.62156 -227.817889) (xy 116.591034 -227.859905) (xy 116.554311 -227.896628) (xy 116.512295 -227.927154)
			(xy 116.466021 -227.950732) (xy 116.416628 -227.96678) (xy 116.365333 -227.974905) (xy 116.313399 -227.974905)
			(xy 116.262104 -227.96678) (xy 116.212711 -227.950732) (xy 116.166437 -227.927154) (xy 116.124421 -227.896628)
			(xy 116.087698 -227.859905) (xy 116.057172 -227.817889) (xy 116.033594 -227.771615) (xy 116.017546 -227.722222)
			(xy 116.009421 -227.670927) (xy 115.729511 -227.670927) (xy 115.721386 -227.722222) (xy 115.705338 -227.771615)
			(xy 115.68176 -227.817889) (xy 115.651234 -227.859905) (xy 115.614511 -227.896628) (xy 115.572495 -227.927154)
			(xy 115.526221 -227.950732) (xy 115.476828 -227.96678) (xy 115.425533 -227.974905) (xy 115.373599 -227.974905)
			(xy 115.322304 -227.96678) (xy 115.272911 -227.950732) (xy 115.226637 -227.927154) (xy 115.184621 -227.896628)
			(xy 115.147898 -227.859905) (xy 115.117372 -227.817889) (xy 115.093794 -227.771615) (xy 115.077746 -227.722222)
			(xy 115.069621 -227.670927) (xy 114.789965 -227.670927) (xy 114.78184 -227.722222) (xy 114.765792 -227.771615)
			(xy 114.742214 -227.817889) (xy 114.711688 -227.859905) (xy 114.674965 -227.896628) (xy 114.632949 -227.927154)
			(xy 114.586675 -227.950732) (xy 114.537282 -227.96678) (xy 114.485987 -227.974905) (xy 114.434053 -227.974905)
			(xy 114.382758 -227.96678) (xy 114.333365 -227.950732) (xy 114.287091 -227.927154) (xy 114.245075 -227.896628)
			(xy 114.208352 -227.859905) (xy 114.177826 -227.817889) (xy 114.154248 -227.771615) (xy 114.1382 -227.722222)
			(xy 114.130075 -227.670927) (xy 113.849911 -227.670927) (xy 113.841786 -227.722222) (xy 113.825738 -227.771615)
			(xy 113.80216 -227.817889) (xy 113.771634 -227.859905) (xy 113.734911 -227.896628) (xy 113.692895 -227.927154)
			(xy 113.646621 -227.950732) (xy 113.597228 -227.96678) (xy 113.545933 -227.974905) (xy 113.493999 -227.974905)
			(xy 113.442704 -227.96678) (xy 113.393311 -227.950732) (xy 113.347037 -227.927154) (xy 113.305021 -227.896628)
			(xy 113.268298 -227.859905) (xy 113.237772 -227.817889) (xy 113.214194 -227.771615) (xy 113.198146 -227.722222)
			(xy 113.190021 -227.670927) (xy 112.910111 -227.670927) (xy 112.901986 -227.722222) (xy 112.885938 -227.771615)
			(xy 112.86236 -227.817889) (xy 112.831834 -227.859905) (xy 112.795111 -227.896628) (xy 112.753095 -227.927154)
			(xy 112.706821 -227.950732) (xy 112.657428 -227.96678) (xy 112.606133 -227.974905) (xy 112.554199 -227.974905)
			(xy 112.502904 -227.96678) (xy 112.453511 -227.950732) (xy 112.407237 -227.927154) (xy 112.365221 -227.896628)
			(xy 112.328498 -227.859905) (xy 112.297972 -227.817889) (xy 112.274394 -227.771615) (xy 112.258346 -227.722222)
			(xy 112.250221 -227.670927) (xy 111.970311 -227.670927) (xy 111.962186 -227.722222) (xy 111.946138 -227.771615)
			(xy 111.92256 -227.817889) (xy 111.892034 -227.859905) (xy 111.855311 -227.896628) (xy 111.813295 -227.927154)
			(xy 111.767021 -227.950732) (xy 111.717628 -227.96678) (xy 111.666333 -227.974905) (xy 111.614399 -227.974905)
			(xy 111.563104 -227.96678) (xy 111.513711 -227.950732) (xy 111.467437 -227.927154) (xy 111.425421 -227.896628)
			(xy 111.388698 -227.859905) (xy 111.358172 -227.817889) (xy 111.334594 -227.771615) (xy 111.318546 -227.722222)
			(xy 111.310421 -227.670927) (xy 111.030511 -227.670927) (xy 111.022386 -227.722222) (xy 111.006338 -227.771615)
			(xy 110.98276 -227.817889) (xy 110.952234 -227.859905) (xy 110.915511 -227.896628) (xy 110.873495 -227.927154)
			(xy 110.827221 -227.950732) (xy 110.777828 -227.96678) (xy 110.726533 -227.974905) (xy 110.674599 -227.974905)
			(xy 110.623304 -227.96678) (xy 110.573911 -227.950732) (xy 110.527637 -227.927154) (xy 110.485621 -227.896628)
			(xy 110.448898 -227.859905) (xy 110.418372 -227.817889) (xy 110.394794 -227.771615) (xy 110.378746 -227.722222)
			(xy 110.370621 -227.670927) (xy 110.090711 -227.670927) (xy 110.082586 -227.722222) (xy 110.066538 -227.771615)
			(xy 110.04296 -227.817889) (xy 110.012434 -227.859905) (xy 109.975711 -227.896628) (xy 109.933695 -227.927154)
			(xy 109.887421 -227.950732) (xy 109.838028 -227.96678) (xy 109.786733 -227.974905) (xy 109.734799 -227.974905)
			(xy 109.683504 -227.96678) (xy 109.634111 -227.950732) (xy 109.587837 -227.927154) (xy 109.545821 -227.896628)
			(xy 109.509098 -227.859905) (xy 109.478572 -227.817889) (xy 109.454994 -227.771615) (xy 109.438946 -227.722222)
			(xy 109.430821 -227.670927) (xy 109.150911 -227.670927) (xy 109.142786 -227.722222) (xy 109.126738 -227.771615)
			(xy 109.10316 -227.817889) (xy 109.072634 -227.859905) (xy 109.035911 -227.896628) (xy 108.993895 -227.927154)
			(xy 108.947621 -227.950732) (xy 108.898228 -227.96678) (xy 108.846933 -227.974905) (xy 108.794999 -227.974905)
			(xy 108.743704 -227.96678) (xy 108.694311 -227.950732) (xy 108.648037 -227.927154) (xy 108.606021 -227.896628)
			(xy 108.569298 -227.859905) (xy 108.538772 -227.817889) (xy 108.515194 -227.771615) (xy 108.499146 -227.722222)
			(xy 108.491021 -227.670927) (xy 108.211069 -227.670927) (xy 108.203403 -227.720512) (xy 108.188067 -227.768905)
			(xy 108.165512 -227.814385) (xy 108.136268 -227.855881) (xy 108.101023 -227.892417) (xy 108.081064 -227.908104)
			(xy 108.069018 -227.917983) (xy 108.051072 -227.943428) (xy 108.041609 -227.973092) (xy 108.041504 -228.004229)
			(xy 108.050768 -228.033956) (xy 108.05922 -228.047042) (xy 108.069124 -228.061514) (xy 108.087299 -228.091508)
			(xy 108.095542 -228.106986) (xy 108.103023 -228.120112) (xy 108.124222 -228.141615) (xy 108.150781 -228.155984)
			(xy 108.180379 -228.161965) (xy 108.210432 -228.159036) (xy 108.224574 -228.153722) (xy 108.244662 -228.145778)
			(xy 108.286386 -228.134587) (xy 108.329213 -228.128938) (xy 108.350812 -228.128576) (xy 108.37678 -228.12906)
			(xy 108.428076 -228.137186) (xy 108.477469 -228.153238) (xy 108.523743 -228.176819) (xy 108.565758 -228.207348)
			(xy 108.602479 -228.244074) (xy 108.633003 -228.286093) (xy 108.656578 -228.33237) (xy 108.672623 -228.381765)
			(xy 108.680744 -228.433062) (xy 108.681266 -228.45903) (xy 108.680842 -228.483218) (xy 108.68058 -228.484997)
			(xy 108.960667 -228.484997) (xy 108.960667 -228.433063) (xy 108.968792 -228.381768) (xy 108.98484 -228.332375)
			(xy 109.008418 -228.286101) (xy 109.038944 -228.244085) (xy 109.075667 -228.207362) (xy 109.117683 -228.176836)
			(xy 109.163957 -228.153258) (xy 109.21335 -228.13721) (xy 109.264645 -228.129085) (xy 109.316579 -228.129085)
			(xy 109.367874 -228.13721) (xy 109.417267 -228.153258) (xy 109.463541 -228.176836) (xy 109.505557 -228.207362)
			(xy 109.54228 -228.244085) (xy 109.572806 -228.286101) (xy 109.596384 -228.332375) (xy 109.612432 -228.381768)
			(xy 109.620557 -228.433063) (xy 109.621066 -228.45903) (xy 109.620557 -228.484997) (xy 109.900467 -228.484997)
			(xy 109.900467 -228.433063) (xy 109.908592 -228.381768) (xy 109.92464 -228.332375) (xy 109.948218 -228.286101)
			(xy 109.978744 -228.244085) (xy 110.015467 -228.207362) (xy 110.057483 -228.176836) (xy 110.103757 -228.153258)
			(xy 110.15315 -228.13721) (xy 110.204445 -228.129085) (xy 110.256379 -228.129085) (xy 110.307674 -228.13721)
			(xy 110.357067 -228.153258) (xy 110.403341 -228.176836) (xy 110.445357 -228.207362) (xy 110.48208 -228.244085)
			(xy 110.512606 -228.286101) (xy 110.536184 -228.332375) (xy 110.552232 -228.381768) (xy 110.560357 -228.433063)
			(xy 110.560866 -228.45903) (xy 110.560357 -228.484997) (xy 110.840521 -228.484997) (xy 110.840521 -228.433063)
			(xy 110.848646 -228.381768) (xy 110.864694 -228.332375) (xy 110.888272 -228.286101) (xy 110.918798 -228.244085)
			(xy 110.955521 -228.207362) (xy 110.997537 -228.176836) (xy 111.043811 -228.153258) (xy 111.093204 -228.13721)
			(xy 111.144499 -228.129085) (xy 111.196433 -228.129085) (xy 111.247728 -228.13721) (xy 111.297121 -228.153258)
			(xy 111.343395 -228.176836) (xy 111.385411 -228.207362) (xy 111.422134 -228.244085) (xy 111.45266 -228.286101)
			(xy 111.476238 -228.332375) (xy 111.492286 -228.381768) (xy 111.500411 -228.433063) (xy 111.50092 -228.45903)
			(xy 111.500411 -228.484997) (xy 111.780067 -228.484997) (xy 111.780067 -228.433063) (xy 111.788192 -228.381768)
			(xy 111.80424 -228.332375) (xy 111.827818 -228.286101) (xy 111.858344 -228.244085) (xy 111.895067 -228.207362)
			(xy 111.937083 -228.176836) (xy 111.983357 -228.153258) (xy 112.03275 -228.13721) (xy 112.084045 -228.129085)
			(xy 112.135979 -228.129085) (xy 112.187274 -228.13721) (xy 112.236667 -228.153258) (xy 112.282941 -228.176836)
			(xy 112.324957 -228.207362) (xy 112.36168 -228.244085) (xy 112.392206 -228.286101) (xy 112.415784 -228.332375)
			(xy 112.431832 -228.381768) (xy 112.439957 -228.433063) (xy 112.440466 -228.45903) (xy 112.439957 -228.484997)
			(xy 112.719867 -228.484997) (xy 112.719867 -228.433063) (xy 112.727992 -228.381768) (xy 112.74404 -228.332375)
			(xy 112.767618 -228.286101) (xy 112.798144 -228.244085) (xy 112.834867 -228.207362) (xy 112.876883 -228.176836)
			(xy 112.923157 -228.153258) (xy 112.97255 -228.13721) (xy 113.023845 -228.129085) (xy 113.075779 -228.129085)
			(xy 113.127074 -228.13721) (xy 113.176467 -228.153258) (xy 113.222741 -228.176836) (xy 113.264757 -228.207362)
			(xy 113.30148 -228.244085) (xy 113.332006 -228.286101) (xy 113.355584 -228.332375) (xy 113.371632 -228.381768)
			(xy 113.379757 -228.433063) (xy 113.380266 -228.45903) (xy 113.379757 -228.484997) (xy 113.659667 -228.484997)
			(xy 113.659667 -228.433063) (xy 113.667792 -228.381768) (xy 113.68384 -228.332375) (xy 113.707418 -228.286101)
			(xy 113.737944 -228.244085) (xy 113.774667 -228.207362) (xy 113.816683 -228.176836) (xy 113.862957 -228.153258)
			(xy 113.91235 -228.13721) (xy 113.963645 -228.129085) (xy 114.015579 -228.129085) (xy 114.066874 -228.13721)
			(xy 114.116267 -228.153258) (xy 114.162541 -228.176836) (xy 114.204557 -228.207362) (xy 114.24128 -228.244085)
			(xy 114.271806 -228.286101) (xy 114.295384 -228.332375) (xy 114.311432 -228.381768) (xy 114.319557 -228.433063)
			(xy 114.320066 -228.45903) (xy 114.319557 -228.484997) (xy 115.539267 -228.484997) (xy 115.539267 -228.433063)
			(xy 115.547392 -228.381768) (xy 115.56344 -228.332375) (xy 115.587018 -228.286101) (xy 115.617544 -228.244085)
			(xy 115.654267 -228.207362) (xy 115.696283 -228.176836) (xy 115.742557 -228.153258) (xy 115.79195 -228.13721)
			(xy 115.843245 -228.129085) (xy 115.895179 -228.129085) (xy 115.946474 -228.13721) (xy 115.995867 -228.153258)
			(xy 116.042141 -228.176836) (xy 116.084157 -228.207362) (xy 116.12088 -228.244085) (xy 116.151406 -228.286101)
			(xy 116.174984 -228.332375) (xy 116.191032 -228.381768) (xy 116.199157 -228.433063) (xy 116.199666 -228.45903)
			(xy 116.199157 -228.484997) (xy 117.418867 -228.484997) (xy 117.418867 -228.433063) (xy 117.426992 -228.381768)
			(xy 117.44304 -228.332375) (xy 117.466618 -228.286101) (xy 117.497144 -228.244085) (xy 117.533867 -228.207362)
			(xy 117.575883 -228.176836) (xy 117.622157 -228.153258) (xy 117.67155 -228.13721) (xy 117.722845 -228.129085)
			(xy 117.774779 -228.129085) (xy 117.826074 -228.13721) (xy 117.875467 -228.153258) (xy 117.921741 -228.176836)
			(xy 117.963757 -228.207362) (xy 118.00048 -228.244085) (xy 118.031006 -228.286101) (xy 118.054584 -228.332375)
			(xy 118.070632 -228.381768) (xy 118.078757 -228.433063) (xy 118.079266 -228.45903) (xy 118.078757 -228.484997)
			(xy 119.298467 -228.484997) (xy 119.298467 -228.433063) (xy 119.306592 -228.381768) (xy 119.32264 -228.332375)
			(xy 119.346218 -228.286101) (xy 119.376744 -228.244085) (xy 119.413467 -228.207362) (xy 119.455483 -228.176836)
			(xy 119.501757 -228.153258) (xy 119.55115 -228.13721) (xy 119.602445 -228.129085) (xy 119.654379 -228.129085)
			(xy 119.705674 -228.13721) (xy 119.755067 -228.153258) (xy 119.801341 -228.176836) (xy 119.843357 -228.207362)
			(xy 119.88008 -228.244085) (xy 119.910606 -228.286101) (xy 119.934184 -228.332375) (xy 119.950232 -228.381768)
			(xy 119.958357 -228.433063) (xy 119.958866 -228.45903) (xy 119.958357 -228.484997) (xy 120.238267 -228.484997)
			(xy 120.238267 -228.433063) (xy 120.246392 -228.381768) (xy 120.26244 -228.332375) (xy 120.286018 -228.286101)
			(xy 120.316544 -228.244085) (xy 120.353267 -228.207362) (xy 120.395283 -228.176836) (xy 120.441557 -228.153258)
			(xy 120.49095 -228.13721) (xy 120.542245 -228.129085) (xy 120.594179 -228.129085) (xy 120.645474 -228.13721)
			(xy 120.694867 -228.153258) (xy 120.741141 -228.176836) (xy 120.783157 -228.207362) (xy 120.81988 -228.244085)
			(xy 120.850406 -228.286101) (xy 120.873984 -228.332375) (xy 120.890032 -228.381768) (xy 120.898157 -228.433063)
			(xy 120.898666 -228.45903) (xy 120.898157 -228.484997) (xy 121.178067 -228.484997) (xy 121.178067 -228.433063)
			(xy 121.186192 -228.381768) (xy 121.20224 -228.332375) (xy 121.225818 -228.286101) (xy 121.256344 -228.244085)
			(xy 121.293067 -228.207362) (xy 121.335083 -228.176836) (xy 121.381357 -228.153258) (xy 121.43075 -228.13721)
			(xy 121.482045 -228.129085) (xy 121.533979 -228.129085) (xy 121.585274 -228.13721) (xy 121.634667 -228.153258)
			(xy 121.680941 -228.176836) (xy 121.722957 -228.207362) (xy 121.75968 -228.244085) (xy 121.790206 -228.286101)
			(xy 121.813784 -228.332375) (xy 121.829832 -228.381768) (xy 121.837957 -228.433063) (xy 121.838466 -228.45903)
			(xy 121.837957 -228.484997) (xy 122.117867 -228.484997) (xy 122.117867 -228.433063) (xy 122.125992 -228.381768)
			(xy 122.14204 -228.332375) (xy 122.165618 -228.286101) (xy 122.196144 -228.244085) (xy 122.232867 -228.207362)
			(xy 122.274883 -228.176836) (xy 122.321157 -228.153258) (xy 122.37055 -228.13721) (xy 122.421845 -228.129085)
			(xy 122.473779 -228.129085) (xy 122.525074 -228.13721) (xy 122.574467 -228.153258) (xy 122.620741 -228.176836)
			(xy 122.662757 -228.207362) (xy 122.69948 -228.244085) (xy 122.730006 -228.286101) (xy 122.753584 -228.332375)
			(xy 122.769632 -228.381768) (xy 122.777757 -228.433063) (xy 122.778266 -228.45903) (xy 122.777757 -228.484997)
			(xy 123.057667 -228.484997) (xy 123.057667 -228.433063) (xy 123.065792 -228.381768) (xy 123.08184 -228.332375)
			(xy 123.105418 -228.286101) (xy 123.135944 -228.244085) (xy 123.172667 -228.207362) (xy 123.214683 -228.176836)
			(xy 123.260957 -228.153258) (xy 123.31035 -228.13721) (xy 123.361645 -228.129085) (xy 123.413579 -228.129085)
			(xy 123.464874 -228.13721) (xy 123.514267 -228.153258) (xy 123.560541 -228.176836) (xy 123.602557 -228.207362)
			(xy 123.63928 -228.244085) (xy 123.669806 -228.286101) (xy 123.693384 -228.332375) (xy 123.709432 -228.381768)
			(xy 123.717557 -228.433063) (xy 123.718066 -228.45903) (xy 123.717557 -228.484997) (xy 123.997467 -228.484997)
			(xy 123.997467 -228.433063) (xy 124.005592 -228.381768) (xy 124.02164 -228.332375) (xy 124.045218 -228.286101)
			(xy 124.075744 -228.244085) (xy 124.112467 -228.207362) (xy 124.154483 -228.176836) (xy 124.200757 -228.153258)
			(xy 124.25015 -228.13721) (xy 124.301445 -228.129085) (xy 124.353379 -228.129085) (xy 124.404674 -228.13721)
			(xy 124.454067 -228.153258) (xy 124.500341 -228.176836) (xy 124.542357 -228.207362) (xy 124.57908 -228.244085)
			(xy 124.609606 -228.286101) (xy 124.633184 -228.332375) (xy 124.649232 -228.381768) (xy 124.657357 -228.433063)
			(xy 124.657866 -228.45903) (xy 124.657357 -228.484997) (xy 124.937267 -228.484997) (xy 124.937267 -228.433063)
			(xy 124.945392 -228.381768) (xy 124.96144 -228.332375) (xy 124.985018 -228.286101) (xy 125.015544 -228.244085)
			(xy 125.052267 -228.207362) (xy 125.094283 -228.176836) (xy 125.140557 -228.153258) (xy 125.18995 -228.13721)
			(xy 125.241245 -228.129085) (xy 125.293179 -228.129085) (xy 125.344474 -228.13721) (xy 125.393867 -228.153258)
			(xy 125.440141 -228.176836) (xy 125.482157 -228.207362) (xy 125.51888 -228.244085) (xy 125.549406 -228.286101)
			(xy 125.572984 -228.332375) (xy 125.589032 -228.381768) (xy 125.597157 -228.433063) (xy 125.597666 -228.45903)
			(xy 125.597157 -228.484997) (xy 125.877321 -228.484997) (xy 125.877321 -228.433063) (xy 125.885446 -228.381768)
			(xy 125.901494 -228.332375) (xy 125.925072 -228.286101) (xy 125.955598 -228.244085) (xy 125.992321 -228.207362)
			(xy 126.034337 -228.176836) (xy 126.080611 -228.153258) (xy 126.130004 -228.13721) (xy 126.181299 -228.129085)
			(xy 126.233233 -228.129085) (xy 126.284528 -228.13721) (xy 126.333921 -228.153258) (xy 126.380195 -228.176836)
			(xy 126.422211 -228.207362) (xy 126.458934 -228.244085) (xy 126.48946 -228.286101) (xy 126.513038 -228.332375)
			(xy 126.529086 -228.381768) (xy 126.537211 -228.433063) (xy 126.53772 -228.45903) (xy 126.537211 -228.484997)
			(xy 126.816867 -228.484997) (xy 126.816867 -228.433063) (xy 126.824992 -228.381768) (xy 126.84104 -228.332375)
			(xy 126.864618 -228.286101) (xy 126.895144 -228.244085) (xy 126.931867 -228.207362) (xy 126.973883 -228.176836)
			(xy 127.020157 -228.153258) (xy 127.06955 -228.13721) (xy 127.120845 -228.129085) (xy 127.172779 -228.129085)
			(xy 127.224074 -228.13721) (xy 127.273467 -228.153258) (xy 127.319741 -228.176836) (xy 127.361757 -228.207362)
			(xy 127.39848 -228.244085) (xy 127.429006 -228.286101) (xy 127.452584 -228.332375) (xy 127.468632 -228.381768)
			(xy 127.476757 -228.433063) (xy 127.477266 -228.45903) (xy 127.476757 -228.484997) (xy 127.468632 -228.536292)
			(xy 127.452584 -228.585685) (xy 127.429006 -228.631959) (xy 127.39848 -228.673975) (xy 127.361757 -228.710698)
			(xy 127.319741 -228.741224) (xy 127.273467 -228.764802) (xy 127.224074 -228.78085) (xy 127.172779 -228.788975)
			(xy 127.120845 -228.788975) (xy 127.06955 -228.78085) (xy 127.020157 -228.764802) (xy 126.973883 -228.741224)
			(xy 126.931867 -228.710698) (xy 126.895144 -228.673975) (xy 126.864618 -228.631959) (xy 126.84104 -228.585685)
			(xy 126.824992 -228.536292) (xy 126.816867 -228.484997) (xy 126.537211 -228.484997) (xy 126.529086 -228.536292)
			(xy 126.513038 -228.585685) (xy 126.48946 -228.631959) (xy 126.458934 -228.673975) (xy 126.422211 -228.710698)
			(xy 126.380195 -228.741224) (xy 126.333921 -228.764802) (xy 126.284528 -228.78085) (xy 126.233233 -228.788975)
			(xy 126.181299 -228.788975) (xy 126.130004 -228.78085) (xy 126.080611 -228.764802) (xy 126.034337 -228.741224)
			(xy 125.992321 -228.710698) (xy 125.955598 -228.673975) (xy 125.925072 -228.631959) (xy 125.901494 -228.585685)
			(xy 125.885446 -228.536292) (xy 125.877321 -228.484997) (xy 125.597157 -228.484997) (xy 125.589032 -228.536292)
			(xy 125.572984 -228.585685) (xy 125.549406 -228.631959) (xy 125.51888 -228.673975) (xy 125.482157 -228.710698)
			(xy 125.440141 -228.741224) (xy 125.393867 -228.764802) (xy 125.344474 -228.78085) (xy 125.293179 -228.788975)
			(xy 125.241245 -228.788975) (xy 125.18995 -228.78085) (xy 125.140557 -228.764802) (xy 125.094283 -228.741224)
			(xy 125.052267 -228.710698) (xy 125.015544 -228.673975) (xy 124.985018 -228.631959) (xy 124.96144 -228.585685)
			(xy 124.945392 -228.536292) (xy 124.937267 -228.484997) (xy 124.657357 -228.484997) (xy 124.649232 -228.536292)
			(xy 124.633184 -228.585685) (xy 124.609606 -228.631959) (xy 124.57908 -228.673975) (xy 124.542357 -228.710698)
			(xy 124.500341 -228.741224) (xy 124.454067 -228.764802) (xy 124.404674 -228.78085) (xy 124.353379 -228.788975)
			(xy 124.301445 -228.788975) (xy 124.25015 -228.78085) (xy 124.200757 -228.764802) (xy 124.154483 -228.741224)
			(xy 124.112467 -228.710698) (xy 124.075744 -228.673975) (xy 124.045218 -228.631959) (xy 124.02164 -228.585685)
			(xy 124.005592 -228.536292) (xy 123.997467 -228.484997) (xy 123.717557 -228.484997) (xy 123.709432 -228.536292)
			(xy 123.693384 -228.585685) (xy 123.669806 -228.631959) (xy 123.63928 -228.673975) (xy 123.602557 -228.710698)
			(xy 123.560541 -228.741224) (xy 123.514267 -228.764802) (xy 123.464874 -228.78085) (xy 123.413579 -228.788975)
			(xy 123.361645 -228.788975) (xy 123.31035 -228.78085) (xy 123.260957 -228.764802) (xy 123.214683 -228.741224)
			(xy 123.172667 -228.710698) (xy 123.135944 -228.673975) (xy 123.105418 -228.631959) (xy 123.08184 -228.585685)
			(xy 123.065792 -228.536292) (xy 123.057667 -228.484997) (xy 122.777757 -228.484997) (xy 122.769632 -228.536292)
			(xy 122.753584 -228.585685) (xy 122.730006 -228.631959) (xy 122.69948 -228.673975) (xy 122.662757 -228.710698)
			(xy 122.620741 -228.741224) (xy 122.574467 -228.764802) (xy 122.525074 -228.78085) (xy 122.473779 -228.788975)
			(xy 122.421845 -228.788975) (xy 122.37055 -228.78085) (xy 122.321157 -228.764802) (xy 122.274883 -228.741224)
			(xy 122.232867 -228.710698) (xy 122.196144 -228.673975) (xy 122.165618 -228.631959) (xy 122.14204 -228.585685)
			(xy 122.125992 -228.536292) (xy 122.117867 -228.484997) (xy 121.837957 -228.484997) (xy 121.829832 -228.536292)
			(xy 121.813784 -228.585685) (xy 121.790206 -228.631959) (xy 121.75968 -228.673975) (xy 121.722957 -228.710698)
			(xy 121.680941 -228.741224) (xy 121.634667 -228.764802) (xy 121.585274 -228.78085) (xy 121.533979 -228.788975)
			(xy 121.482045 -228.788975) (xy 121.43075 -228.78085) (xy 121.381357 -228.764802) (xy 121.335083 -228.741224)
			(xy 121.293067 -228.710698) (xy 121.256344 -228.673975) (xy 121.225818 -228.631959) (xy 121.20224 -228.585685)
			(xy 121.186192 -228.536292) (xy 121.178067 -228.484997) (xy 120.898157 -228.484997) (xy 120.890032 -228.536292)
			(xy 120.873984 -228.585685) (xy 120.850406 -228.631959) (xy 120.81988 -228.673975) (xy 120.783157 -228.710698)
			(xy 120.741141 -228.741224) (xy 120.694867 -228.764802) (xy 120.645474 -228.78085) (xy 120.594179 -228.788975)
			(xy 120.542245 -228.788975) (xy 120.49095 -228.78085) (xy 120.441557 -228.764802) (xy 120.395283 -228.741224)
			(xy 120.353267 -228.710698) (xy 120.316544 -228.673975) (xy 120.286018 -228.631959) (xy 120.26244 -228.585685)
			(xy 120.246392 -228.536292) (xy 120.238267 -228.484997) (xy 119.958357 -228.484997) (xy 119.950232 -228.536292)
			(xy 119.934184 -228.585685) (xy 119.910606 -228.631959) (xy 119.88008 -228.673975) (xy 119.843357 -228.710698)
			(xy 119.801341 -228.741224) (xy 119.755067 -228.764802) (xy 119.705674 -228.78085) (xy 119.654379 -228.788975)
			(xy 119.602445 -228.788975) (xy 119.55115 -228.78085) (xy 119.501757 -228.764802) (xy 119.455483 -228.741224)
			(xy 119.413467 -228.710698) (xy 119.376744 -228.673975) (xy 119.346218 -228.631959) (xy 119.32264 -228.585685)
			(xy 119.306592 -228.536292) (xy 119.298467 -228.484997) (xy 118.078757 -228.484997) (xy 118.070632 -228.536292)
			(xy 118.054584 -228.585685) (xy 118.031006 -228.631959) (xy 118.00048 -228.673975) (xy 117.963757 -228.710698)
			(xy 117.921741 -228.741224) (xy 117.875467 -228.764802) (xy 117.826074 -228.78085) (xy 117.774779 -228.788975)
			(xy 117.722845 -228.788975) (xy 117.67155 -228.78085) (xy 117.622157 -228.764802) (xy 117.575883 -228.741224)
			(xy 117.533867 -228.710698) (xy 117.497144 -228.673975) (xy 117.466618 -228.631959) (xy 117.44304 -228.585685)
			(xy 117.426992 -228.536292) (xy 117.418867 -228.484997) (xy 116.199157 -228.484997) (xy 116.191032 -228.536292)
			(xy 116.174984 -228.585685) (xy 116.151406 -228.631959) (xy 116.12088 -228.673975) (xy 116.084157 -228.710698)
			(xy 116.042141 -228.741224) (xy 115.995867 -228.764802) (xy 115.946474 -228.78085) (xy 115.895179 -228.788975)
			(xy 115.843245 -228.788975) (xy 115.79195 -228.78085) (xy 115.742557 -228.764802) (xy 115.696283 -228.741224)
			(xy 115.654267 -228.710698) (xy 115.617544 -228.673975) (xy 115.587018 -228.631959) (xy 115.56344 -228.585685)
			(xy 115.547392 -228.536292) (xy 115.539267 -228.484997) (xy 114.319557 -228.484997) (xy 114.311432 -228.536292)
			(xy 114.295384 -228.585685) (xy 114.271806 -228.631959) (xy 114.24128 -228.673975) (xy 114.204557 -228.710698)
			(xy 114.162541 -228.741224) (xy 114.116267 -228.764802) (xy 114.066874 -228.78085) (xy 114.015579 -228.788975)
			(xy 113.963645 -228.788975) (xy 113.91235 -228.78085) (xy 113.862957 -228.764802) (xy 113.816683 -228.741224)
			(xy 113.774667 -228.710698) (xy 113.737944 -228.673975) (xy 113.707418 -228.631959) (xy 113.68384 -228.585685)
			(xy 113.667792 -228.536292) (xy 113.659667 -228.484997) (xy 113.379757 -228.484997) (xy 113.371632 -228.536292)
			(xy 113.355584 -228.585685) (xy 113.332006 -228.631959) (xy 113.30148 -228.673975) (xy 113.264757 -228.710698)
			(xy 113.222741 -228.741224) (xy 113.176467 -228.764802) (xy 113.127074 -228.78085) (xy 113.075779 -228.788975)
			(xy 113.023845 -228.788975) (xy 112.97255 -228.78085) (xy 112.923157 -228.764802) (xy 112.876883 -228.741224)
			(xy 112.834867 -228.710698) (xy 112.798144 -228.673975) (xy 112.767618 -228.631959) (xy 112.74404 -228.585685)
			(xy 112.727992 -228.536292) (xy 112.719867 -228.484997) (xy 112.439957 -228.484997) (xy 112.431832 -228.536292)
			(xy 112.415784 -228.585685) (xy 112.392206 -228.631959) (xy 112.36168 -228.673975) (xy 112.324957 -228.710698)
			(xy 112.282941 -228.741224) (xy 112.236667 -228.764802) (xy 112.187274 -228.78085) (xy 112.135979 -228.788975)
			(xy 112.084045 -228.788975) (xy 112.03275 -228.78085) (xy 111.983357 -228.764802) (xy 111.937083 -228.741224)
			(xy 111.895067 -228.710698) (xy 111.858344 -228.673975) (xy 111.827818 -228.631959) (xy 111.80424 -228.585685)
			(xy 111.788192 -228.536292) (xy 111.780067 -228.484997) (xy 111.500411 -228.484997) (xy 111.492286 -228.536292)
			(xy 111.476238 -228.585685) (xy 111.45266 -228.631959) (xy 111.422134 -228.673975) (xy 111.385411 -228.710698)
			(xy 111.343395 -228.741224) (xy 111.297121 -228.764802) (xy 111.247728 -228.78085) (xy 111.196433 -228.788975)
			(xy 111.144499 -228.788975) (xy 111.093204 -228.78085) (xy 111.043811 -228.764802) (xy 110.997537 -228.741224)
			(xy 110.955521 -228.710698) (xy 110.918798 -228.673975) (xy 110.888272 -228.631959) (xy 110.864694 -228.585685)
			(xy 110.848646 -228.536292) (xy 110.840521 -228.484997) (xy 110.560357 -228.484997) (xy 110.552232 -228.536292)
			(xy 110.536184 -228.585685) (xy 110.512606 -228.631959) (xy 110.48208 -228.673975) (xy 110.445357 -228.710698)
			(xy 110.403341 -228.741224) (xy 110.357067 -228.764802) (xy 110.307674 -228.78085) (xy 110.256379 -228.788975)
			(xy 110.204445 -228.788975) (xy 110.15315 -228.78085) (xy 110.103757 -228.764802) (xy 110.057483 -228.741224)
			(xy 110.015467 -228.710698) (xy 109.978744 -228.673975) (xy 109.948218 -228.631959) (xy 109.92464 -228.585685)
			(xy 109.908592 -228.536292) (xy 109.900467 -228.484997) (xy 109.620557 -228.484997) (xy 109.612432 -228.536292)
			(xy 109.596384 -228.585685) (xy 109.572806 -228.631959) (xy 109.54228 -228.673975) (xy 109.505557 -228.710698)
			(xy 109.463541 -228.741224) (xy 109.417267 -228.764802) (xy 109.367874 -228.78085) (xy 109.316579 -228.788975)
			(xy 109.264645 -228.788975) (xy 109.21335 -228.78085) (xy 109.163957 -228.764802) (xy 109.117683 -228.741224)
			(xy 109.075667 -228.710698) (xy 109.038944 -228.673975) (xy 109.008418 -228.631959) (xy 108.98484 -228.585685)
			(xy 108.968792 -228.536292) (xy 108.960667 -228.484997) (xy 108.68058 -228.484997) (xy 108.673785 -228.531076)
			(xy 108.659826 -228.577394) (xy 108.639264 -228.621181) (xy 108.612538 -228.661504) (xy 108.580218 -228.697499)
			(xy 108.561886 -228.713284) (xy 108.550443 -228.723439) (xy 108.533729 -228.749048) (xy 108.525352 -228.778459)
			(xy 108.526063 -228.809031) (xy 108.535798 -228.838021) (xy 108.54436 -228.850698) (xy 108.555168 -228.866058)
			(xy 108.574999 -228.897959) (xy 108.583984 -228.914452) (xy 108.591234 -228.927064) (xy 108.611588 -228.947833)
			(xy 108.636971 -228.962023) (xy 108.665325 -228.968482) (xy 108.69435 -228.966688) (xy 108.70819 -228.962204)
			(xy 108.735455 -228.952931) (xy 108.792173 -228.942975) (xy 108.820966 -228.942392) (xy 108.846936 -228.942872)
			(xy 108.898236 -228.950993) (xy 108.947634 -228.967041) (xy 108.993913 -228.990619) (xy 109.035933 -229.021148)
			(xy 109.072659 -229.057876) (xy 109.103187 -229.099897) (xy 109.126764 -229.146177) (xy 109.142809 -229.195575)
			(xy 109.150929 -229.246876) (xy 109.15142 -229.272846) (xy 109.150958 -229.298259) (xy 109.150872 -229.298813)
			(xy 109.430821 -229.298813) (xy 109.430821 -229.246879) (xy 109.438946 -229.195584) (xy 109.454994 -229.146191)
			(xy 109.478572 -229.099917) (xy 109.509098 -229.057901) (xy 109.545821 -229.021178) (xy 109.587837 -228.990652)
			(xy 109.634111 -228.967074) (xy 109.683504 -228.951026) (xy 109.734799 -228.942901) (xy 109.786733 -228.942901)
			(xy 109.838028 -228.951026) (xy 109.887421 -228.967074) (xy 109.933695 -228.990652) (xy 109.975711 -229.021178)
			(xy 110.012434 -229.057901) (xy 110.04296 -229.099917) (xy 110.066538 -229.146191) (xy 110.082586 -229.195584)
			(xy 110.090711 -229.246879) (xy 110.09122 -229.272846) (xy 110.090711 -229.298813) (xy 110.370621 -229.298813)
			(xy 110.370621 -229.246879) (xy 110.378746 -229.195584) (xy 110.394794 -229.146191) (xy 110.418372 -229.099917)
			(xy 110.448898 -229.057901) (xy 110.485621 -229.021178) (xy 110.527637 -228.990652) (xy 110.573911 -228.967074)
			(xy 110.623304 -228.951026) (xy 110.674599 -228.942901) (xy 110.726533 -228.942901) (xy 110.777828 -228.951026)
			(xy 110.827221 -228.967074) (xy 110.873495 -228.990652) (xy 110.915511 -229.021178) (xy 110.952234 -229.057901)
			(xy 110.98276 -229.099917) (xy 111.006338 -229.146191) (xy 111.022386 -229.195584) (xy 111.030511 -229.246879)
			(xy 111.03102 -229.272846) (xy 111.030511 -229.298813) (xy 111.310167 -229.298813) (xy 111.310167 -229.246879)
			(xy 111.318292 -229.195584) (xy 111.33434 -229.146191) (xy 111.357918 -229.099917) (xy 111.388444 -229.057901)
			(xy 111.425167 -229.021178) (xy 111.467183 -228.990652) (xy 111.513457 -228.967074) (xy 111.56285 -228.951026)
			(xy 111.614145 -228.942901) (xy 111.666079 -228.942901) (xy 111.717374 -228.951026) (xy 111.766767 -228.967074)
			(xy 111.813041 -228.990652) (xy 111.855057 -229.021178) (xy 111.89178 -229.057901) (xy 111.922306 -229.099917)
			(xy 111.945884 -229.146191) (xy 111.961932 -229.195584) (xy 111.970057 -229.246879) (xy 111.970566 -229.272846)
			(xy 111.970057 -229.298813) (xy 112.250221 -229.298813) (xy 112.250221 -229.246879) (xy 112.258346 -229.195584)
			(xy 112.274394 -229.146191) (xy 112.297972 -229.099917) (xy 112.328498 -229.057901) (xy 112.365221 -229.021178)
			(xy 112.407237 -228.990652) (xy 112.453511 -228.967074) (xy 112.502904 -228.951026) (xy 112.554199 -228.942901)
			(xy 112.606133 -228.942901) (xy 112.657428 -228.951026) (xy 112.706821 -228.967074) (xy 112.753095 -228.990652)
			(xy 112.795111 -229.021178) (xy 112.831834 -229.057901) (xy 112.86236 -229.099917) (xy 112.885938 -229.146191)
			(xy 112.901986 -229.195584) (xy 112.910111 -229.246879) (xy 112.91062 -229.272846) (xy 112.910111 -229.298813)
			(xy 113.190021 -229.298813) (xy 113.190021 -229.246879) (xy 113.198146 -229.195584) (xy 113.214194 -229.146191)
			(xy 113.237772 -229.099917) (xy 113.268298 -229.057901) (xy 113.305021 -229.021178) (xy 113.347037 -228.990652)
			(xy 113.393311 -228.967074) (xy 113.442704 -228.951026) (xy 113.493999 -228.942901) (xy 113.545933 -228.942901)
			(xy 113.597228 -228.951026) (xy 113.646621 -228.967074) (xy 113.692895 -228.990652) (xy 113.734911 -229.021178)
			(xy 113.771634 -229.057901) (xy 113.80216 -229.099917) (xy 113.825738 -229.146191) (xy 113.841786 -229.195584)
			(xy 113.849911 -229.246879) (xy 113.85042 -229.272846) (xy 113.849911 -229.298813) (xy 114.129821 -229.298813)
			(xy 114.129821 -229.246879) (xy 114.137946 -229.195584) (xy 114.153994 -229.146191) (xy 114.177572 -229.099917)
			(xy 114.208098 -229.057901) (xy 114.244821 -229.021178) (xy 114.286837 -228.990652) (xy 114.333111 -228.967074)
			(xy 114.382504 -228.951026) (xy 114.433799 -228.942901) (xy 114.485733 -228.942901) (xy 114.537028 -228.951026)
			(xy 114.586421 -228.967074) (xy 114.632695 -228.990652) (xy 114.674711 -229.021178) (xy 114.711434 -229.057901)
			(xy 114.74196 -229.099917) (xy 114.765538 -229.146191) (xy 114.781586 -229.195584) (xy 114.789711 -229.246879)
			(xy 114.79022 -229.272846) (xy 114.789711 -229.298813) (xy 115.069621 -229.298813) (xy 115.069621 -229.246879)
			(xy 115.077746 -229.195584) (xy 115.093794 -229.146191) (xy 115.117372 -229.099917) (xy 115.147898 -229.057901)
			(xy 115.184621 -229.021178) (xy 115.226637 -228.990652) (xy 115.272911 -228.967074) (xy 115.322304 -228.951026)
			(xy 115.373599 -228.942901) (xy 115.425533 -228.942901) (xy 115.476828 -228.951026) (xy 115.526221 -228.967074)
			(xy 115.572495 -228.990652) (xy 115.614511 -229.021178) (xy 115.651234 -229.057901) (xy 115.68176 -229.099917)
			(xy 115.705338 -229.146191) (xy 115.721386 -229.195584) (xy 115.729511 -229.246879) (xy 115.73002 -229.272846)
			(xy 115.729511 -229.298813) (xy 116.009421 -229.298813) (xy 116.009421 -229.246879) (xy 116.017546 -229.195584)
			(xy 116.033594 -229.146191) (xy 116.057172 -229.099917) (xy 116.087698 -229.057901) (xy 116.124421 -229.021178)
			(xy 116.166437 -228.990652) (xy 116.212711 -228.967074) (xy 116.262104 -228.951026) (xy 116.313399 -228.942901)
			(xy 116.365333 -228.942901) (xy 116.416628 -228.951026) (xy 116.466021 -228.967074) (xy 116.512295 -228.990652)
			(xy 116.554311 -229.021178) (xy 116.591034 -229.057901) (xy 116.62156 -229.099917) (xy 116.645138 -229.146191)
			(xy 116.661186 -229.195584) (xy 116.669311 -229.246879) (xy 116.66982 -229.272846) (xy 116.669311 -229.298813)
			(xy 116.949221 -229.298813) (xy 116.949221 -229.246879) (xy 116.957346 -229.195584) (xy 116.973394 -229.146191)
			(xy 116.996972 -229.099917) (xy 117.027498 -229.057901) (xy 117.064221 -229.021178) (xy 117.106237 -228.990652)
			(xy 117.152511 -228.967074) (xy 117.201904 -228.951026) (xy 117.253199 -228.942901) (xy 117.305133 -228.942901)
			(xy 117.356428 -228.951026) (xy 117.405821 -228.967074) (xy 117.452095 -228.990652) (xy 117.494111 -229.021178)
			(xy 117.530834 -229.057901) (xy 117.56136 -229.099917) (xy 117.584938 -229.146191) (xy 117.600986 -229.195584)
			(xy 117.609111 -229.246879) (xy 117.60962 -229.272846) (xy 117.609111 -229.298813) (xy 117.889021 -229.298813)
			(xy 117.889021 -229.246879) (xy 117.897146 -229.195584) (xy 117.913194 -229.146191) (xy 117.936772 -229.099917)
			(xy 117.967298 -229.057901) (xy 118.004021 -229.021178) (xy 118.046037 -228.990652) (xy 118.092311 -228.967074)
			(xy 118.141704 -228.951026) (xy 118.192999 -228.942901) (xy 118.244933 -228.942901) (xy 118.296228 -228.951026)
			(xy 118.345621 -228.967074) (xy 118.391895 -228.990652) (xy 118.433911 -229.021178) (xy 118.470634 -229.057901)
			(xy 118.50116 -229.099917) (xy 118.524738 -229.146191) (xy 118.540786 -229.195584) (xy 118.548911 -229.246879)
			(xy 118.54942 -229.272846) (xy 118.548911 -229.298813) (xy 118.828821 -229.298813) (xy 118.828821 -229.246879)
			(xy 118.836946 -229.195584) (xy 118.852994 -229.146191) (xy 118.876572 -229.099917) (xy 118.907098 -229.057901)
			(xy 118.943821 -229.021178) (xy 118.985837 -228.990652) (xy 119.032111 -228.967074) (xy 119.081504 -228.951026)
			(xy 119.132799 -228.942901) (xy 119.184733 -228.942901) (xy 119.236028 -228.951026) (xy 119.285421 -228.967074)
			(xy 119.331695 -228.990652) (xy 119.373711 -229.021178) (xy 119.410434 -229.057901) (xy 119.44096 -229.099917)
			(xy 119.464538 -229.146191) (xy 119.480586 -229.195584) (xy 119.488711 -229.246879) (xy 119.48922 -229.272846)
			(xy 119.488711 -229.298813) (xy 119.768621 -229.298813) (xy 119.768621 -229.246879) (xy 119.776746 -229.195584)
			(xy 119.792794 -229.146191) (xy 119.816372 -229.099917) (xy 119.846898 -229.057901) (xy 119.883621 -229.021178)
			(xy 119.925637 -228.990652) (xy 119.971911 -228.967074) (xy 120.021304 -228.951026) (xy 120.072599 -228.942901)
			(xy 120.124533 -228.942901) (xy 120.175828 -228.951026) (xy 120.225221 -228.967074) (xy 120.271495 -228.990652)
			(xy 120.313511 -229.021178) (xy 120.350234 -229.057901) (xy 120.38076 -229.099917) (xy 120.404338 -229.146191)
			(xy 120.420386 -229.195584) (xy 120.428511 -229.246879) (xy 120.42902 -229.272846) (xy 120.428511 -229.298813)
			(xy 120.708421 -229.298813) (xy 120.708421 -229.246879) (xy 120.716546 -229.195584) (xy 120.732594 -229.146191)
			(xy 120.756172 -229.099917) (xy 120.786698 -229.057901) (xy 120.823421 -229.021178) (xy 120.865437 -228.990652)
			(xy 120.911711 -228.967074) (xy 120.961104 -228.951026) (xy 121.012399 -228.942901) (xy 121.064333 -228.942901)
			(xy 121.115628 -228.951026) (xy 121.165021 -228.967074) (xy 121.211295 -228.990652) (xy 121.253311 -229.021178)
			(xy 121.290034 -229.057901) (xy 121.32056 -229.099917) (xy 121.344138 -229.146191) (xy 121.360186 -229.195584)
			(xy 121.368311 -229.246879) (xy 121.36882 -229.272846) (xy 121.368311 -229.298813) (xy 121.648221 -229.298813)
			(xy 121.648221 -229.246879) (xy 121.656346 -229.195584) (xy 121.672394 -229.146191) (xy 121.695972 -229.099917)
			(xy 121.726498 -229.057901) (xy 121.763221 -229.021178) (xy 121.805237 -228.990652) (xy 121.851511 -228.967074)
			(xy 121.900904 -228.951026) (xy 121.952199 -228.942901) (xy 122.004133 -228.942901) (xy 122.055428 -228.951026)
			(xy 122.104821 -228.967074) (xy 122.151095 -228.990652) (xy 122.193111 -229.021178) (xy 122.229834 -229.057901)
			(xy 122.26036 -229.099917) (xy 122.283938 -229.146191) (xy 122.299986 -229.195584) (xy 122.308111 -229.246879)
			(xy 122.30862 -229.272846) (xy 122.308111 -229.298813) (xy 122.587767 -229.298813) (xy 122.587767 -229.246879)
			(xy 122.595892 -229.195584) (xy 122.61194 -229.146191) (xy 122.635518 -229.099917) (xy 122.666044 -229.057901)
			(xy 122.702767 -229.021178) (xy 122.744783 -228.990652) (xy 122.791057 -228.967074) (xy 122.84045 -228.951026)
			(xy 122.891745 -228.942901) (xy 122.943679 -228.942901) (xy 122.994974 -228.951026) (xy 123.044367 -228.967074)
			(xy 123.090641 -228.990652) (xy 123.132657 -229.021178) (xy 123.16938 -229.057901) (xy 123.199906 -229.099917)
			(xy 123.223484 -229.146191) (xy 123.239532 -229.195584) (xy 123.247657 -229.246879) (xy 123.248166 -229.272846)
			(xy 123.247657 -229.298813) (xy 123.527821 -229.298813) (xy 123.527821 -229.246879) (xy 123.535946 -229.195584)
			(xy 123.551994 -229.146191) (xy 123.575572 -229.099917) (xy 123.606098 -229.057901) (xy 123.642821 -229.021178)
			(xy 123.684837 -228.990652) (xy 123.731111 -228.967074) (xy 123.780504 -228.951026) (xy 123.831799 -228.942901)
			(xy 123.883733 -228.942901) (xy 123.935028 -228.951026) (xy 123.984421 -228.967074) (xy 124.030695 -228.990652)
			(xy 124.072711 -229.021178) (xy 124.109434 -229.057901) (xy 124.13996 -229.099917) (xy 124.163538 -229.146191)
			(xy 124.179586 -229.195584) (xy 124.187711 -229.246879) (xy 124.18822 -229.272846) (xy 124.187711 -229.298813)
			(xy 124.467621 -229.298813) (xy 124.467621 -229.246879) (xy 124.475746 -229.195584) (xy 124.491794 -229.146191)
			(xy 124.515372 -229.099917) (xy 124.545898 -229.057901) (xy 124.582621 -229.021178) (xy 124.624637 -228.990652)
			(xy 124.670911 -228.967074) (xy 124.720304 -228.951026) (xy 124.771599 -228.942901) (xy 124.823533 -228.942901)
			(xy 124.874828 -228.951026) (xy 124.924221 -228.967074) (xy 124.970495 -228.990652) (xy 125.012511 -229.021178)
			(xy 125.049234 -229.057901) (xy 125.07976 -229.099917) (xy 125.103338 -229.146191) (xy 125.119386 -229.195584)
			(xy 125.127511 -229.246879) (xy 125.12802 -229.272846) (xy 125.127511 -229.298813) (xy 125.407421 -229.298813)
			(xy 125.407421 -229.246879) (xy 125.415546 -229.195584) (xy 125.431594 -229.146191) (xy 125.455172 -229.099917)
			(xy 125.485698 -229.057901) (xy 125.522421 -229.021178) (xy 125.564437 -228.990652) (xy 125.610711 -228.967074)
			(xy 125.660104 -228.951026) (xy 125.711399 -228.942901) (xy 125.763333 -228.942901) (xy 125.814628 -228.951026)
			(xy 125.864021 -228.967074) (xy 125.910295 -228.990652) (xy 125.952311 -229.021178) (xy 125.989034 -229.057901)
			(xy 126.01956 -229.099917) (xy 126.043138 -229.146191) (xy 126.059186 -229.195584) (xy 126.067311 -229.246879)
			(xy 126.06782 -229.272846) (xy 126.067311 -229.298813) (xy 126.347221 -229.298813) (xy 126.347221 -229.246879)
			(xy 126.355346 -229.195584) (xy 126.371394 -229.146191) (xy 126.394972 -229.099917) (xy 126.425498 -229.057901)
			(xy 126.462221 -229.021178) (xy 126.504237 -228.990652) (xy 126.550511 -228.967074) (xy 126.599904 -228.951026)
			(xy 126.651199 -228.942901) (xy 126.703133 -228.942901) (xy 126.754428 -228.951026) (xy 126.803821 -228.967074)
			(xy 126.850095 -228.990652) (xy 126.892111 -229.021178) (xy 126.928834 -229.057901) (xy 126.95936 -229.099917)
			(xy 126.982938 -229.146191) (xy 126.998986 -229.195584) (xy 127.007111 -229.246879) (xy 127.00762 -229.272846)
			(xy 127.007111 -229.298813) (xy 126.998986 -229.350108) (xy 126.982938 -229.399501) (xy 126.95936 -229.445775)
			(xy 126.928834 -229.487791) (xy 126.892111 -229.524514) (xy 126.850095 -229.55504) (xy 126.803821 -229.578618)
			(xy 126.754428 -229.594666) (xy 126.703133 -229.602791) (xy 126.651199 -229.602791) (xy 126.599904 -229.594666)
			(xy 126.550511 -229.578618) (xy 126.504237 -229.55504) (xy 126.462221 -229.524514) (xy 126.425498 -229.487791)
			(xy 126.394972 -229.445775) (xy 126.371394 -229.399501) (xy 126.355346 -229.350108) (xy 126.347221 -229.298813)
			(xy 126.067311 -229.298813) (xy 126.059186 -229.350108) (xy 126.043138 -229.399501) (xy 126.01956 -229.445775)
			(xy 125.989034 -229.487791) (xy 125.952311 -229.524514) (xy 125.910295 -229.55504) (xy 125.864021 -229.578618)
			(xy 125.814628 -229.594666) (xy 125.763333 -229.602791) (xy 125.711399 -229.602791) (xy 125.660104 -229.594666)
			(xy 125.610711 -229.578618) (xy 125.564437 -229.55504) (xy 125.522421 -229.524514) (xy 125.485698 -229.487791)
			(xy 125.455172 -229.445775) (xy 125.431594 -229.399501) (xy 125.415546 -229.350108) (xy 125.407421 -229.298813)
			(xy 125.127511 -229.298813) (xy 125.119386 -229.350108) (xy 125.103338 -229.399501) (xy 125.07976 -229.445775)
			(xy 125.049234 -229.487791) (xy 125.012511 -229.524514) (xy 124.970495 -229.55504) (xy 124.924221 -229.578618)
			(xy 124.874828 -229.594666) (xy 124.823533 -229.602791) (xy 124.771599 -229.602791) (xy 124.720304 -229.594666)
			(xy 124.670911 -229.578618) (xy 124.624637 -229.55504) (xy 124.582621 -229.524514) (xy 124.545898 -229.487791)
			(xy 124.515372 -229.445775) (xy 124.491794 -229.399501) (xy 124.475746 -229.350108) (xy 124.467621 -229.298813)
			(xy 124.187711 -229.298813) (xy 124.179586 -229.350108) (xy 124.163538 -229.399501) (xy 124.13996 -229.445775)
			(xy 124.109434 -229.487791) (xy 124.072711 -229.524514) (xy 124.030695 -229.55504) (xy 123.984421 -229.578618)
			(xy 123.935028 -229.594666) (xy 123.883733 -229.602791) (xy 123.831799 -229.602791) (xy 123.780504 -229.594666)
			(xy 123.731111 -229.578618) (xy 123.684837 -229.55504) (xy 123.642821 -229.524514) (xy 123.606098 -229.487791)
			(xy 123.575572 -229.445775) (xy 123.551994 -229.399501) (xy 123.535946 -229.350108) (xy 123.527821 -229.298813)
			(xy 123.247657 -229.298813) (xy 123.239532 -229.350108) (xy 123.223484 -229.399501) (xy 123.199906 -229.445775)
			(xy 123.16938 -229.487791) (xy 123.132657 -229.524514) (xy 123.090641 -229.55504) (xy 123.044367 -229.578618)
			(xy 122.994974 -229.594666) (xy 122.943679 -229.602791) (xy 122.891745 -229.602791) (xy 122.84045 -229.594666)
			(xy 122.791057 -229.578618) (xy 122.744783 -229.55504) (xy 122.702767 -229.524514) (xy 122.666044 -229.487791)
			(xy 122.635518 -229.445775) (xy 122.61194 -229.399501) (xy 122.595892 -229.350108) (xy 122.587767 -229.298813)
			(xy 122.308111 -229.298813) (xy 122.299986 -229.350108) (xy 122.283938 -229.399501) (xy 122.26036 -229.445775)
			(xy 122.229834 -229.487791) (xy 122.193111 -229.524514) (xy 122.151095 -229.55504) (xy 122.104821 -229.578618)
			(xy 122.055428 -229.594666) (xy 122.004133 -229.602791) (xy 121.952199 -229.602791) (xy 121.900904 -229.594666)
			(xy 121.851511 -229.578618) (xy 121.805237 -229.55504) (xy 121.763221 -229.524514) (xy 121.726498 -229.487791)
			(xy 121.695972 -229.445775) (xy 121.672394 -229.399501) (xy 121.656346 -229.350108) (xy 121.648221 -229.298813)
			(xy 121.368311 -229.298813) (xy 121.360186 -229.350108) (xy 121.344138 -229.399501) (xy 121.32056 -229.445775)
			(xy 121.290034 -229.487791) (xy 121.253311 -229.524514) (xy 121.211295 -229.55504) (xy 121.165021 -229.578618)
			(xy 121.115628 -229.594666) (xy 121.064333 -229.602791) (xy 121.012399 -229.602791) (xy 120.961104 -229.594666)
			(xy 120.911711 -229.578618) (xy 120.865437 -229.55504) (xy 120.823421 -229.524514) (xy 120.786698 -229.487791)
			(xy 120.756172 -229.445775) (xy 120.732594 -229.399501) (xy 120.716546 -229.350108) (xy 120.708421 -229.298813)
			(xy 120.428511 -229.298813) (xy 120.420386 -229.350108) (xy 120.404338 -229.399501) (xy 120.38076 -229.445775)
			(xy 120.350234 -229.487791) (xy 120.313511 -229.524514) (xy 120.271495 -229.55504) (xy 120.225221 -229.578618)
			(xy 120.175828 -229.594666) (xy 120.124533 -229.602791) (xy 120.072599 -229.602791) (xy 120.021304 -229.594666)
			(xy 119.971911 -229.578618) (xy 119.925637 -229.55504) (xy 119.883621 -229.524514) (xy 119.846898 -229.487791)
			(xy 119.816372 -229.445775) (xy 119.792794 -229.399501) (xy 119.776746 -229.350108) (xy 119.768621 -229.298813)
			(xy 119.488711 -229.298813) (xy 119.480586 -229.350108) (xy 119.464538 -229.399501) (xy 119.44096 -229.445775)
			(xy 119.410434 -229.487791) (xy 119.373711 -229.524514) (xy 119.331695 -229.55504) (xy 119.285421 -229.578618)
			(xy 119.236028 -229.594666) (xy 119.184733 -229.602791) (xy 119.132799 -229.602791) (xy 119.081504 -229.594666)
			(xy 119.032111 -229.578618) (xy 118.985837 -229.55504) (xy 118.943821 -229.524514) (xy 118.907098 -229.487791)
			(xy 118.876572 -229.445775) (xy 118.852994 -229.399501) (xy 118.836946 -229.350108) (xy 118.828821 -229.298813)
			(xy 118.548911 -229.298813) (xy 118.540786 -229.350108) (xy 118.524738 -229.399501) (xy 118.50116 -229.445775)
			(xy 118.470634 -229.487791) (xy 118.433911 -229.524514) (xy 118.391895 -229.55504) (xy 118.345621 -229.578618)
			(xy 118.296228 -229.594666) (xy 118.244933 -229.602791) (xy 118.192999 -229.602791) (xy 118.141704 -229.594666)
			(xy 118.092311 -229.578618) (xy 118.046037 -229.55504) (xy 118.004021 -229.524514) (xy 117.967298 -229.487791)
			(xy 117.936772 -229.445775) (xy 117.913194 -229.399501) (xy 117.897146 -229.350108) (xy 117.889021 -229.298813)
			(xy 117.609111 -229.298813) (xy 117.600986 -229.350108) (xy 117.584938 -229.399501) (xy 117.56136 -229.445775)
			(xy 117.530834 -229.487791) (xy 117.494111 -229.524514) (xy 117.452095 -229.55504) (xy 117.405821 -229.578618)
			(xy 117.356428 -229.594666) (xy 117.305133 -229.602791) (xy 117.253199 -229.602791) (xy 117.201904 -229.594666)
			(xy 117.152511 -229.578618) (xy 117.106237 -229.55504) (xy 117.064221 -229.524514) (xy 117.027498 -229.487791)
			(xy 116.996972 -229.445775) (xy 116.973394 -229.399501) (xy 116.957346 -229.350108) (xy 116.949221 -229.298813)
			(xy 116.669311 -229.298813) (xy 116.661186 -229.350108) (xy 116.645138 -229.399501) (xy 116.62156 -229.445775)
			(xy 116.591034 -229.487791) (xy 116.554311 -229.524514) (xy 116.512295 -229.55504) (xy 116.466021 -229.578618)
			(xy 116.416628 -229.594666) (xy 116.365333 -229.602791) (xy 116.313399 -229.602791) (xy 116.262104 -229.594666)
			(xy 116.212711 -229.578618) (xy 116.166437 -229.55504) (xy 116.124421 -229.524514) (xy 116.087698 -229.487791)
			(xy 116.057172 -229.445775) (xy 116.033594 -229.399501) (xy 116.017546 -229.350108) (xy 116.009421 -229.298813)
			(xy 115.729511 -229.298813) (xy 115.721386 -229.350108) (xy 115.705338 -229.399501) (xy 115.68176 -229.445775)
			(xy 115.651234 -229.487791) (xy 115.614511 -229.524514) (xy 115.572495 -229.55504) (xy 115.526221 -229.578618)
			(xy 115.476828 -229.594666) (xy 115.425533 -229.602791) (xy 115.373599 -229.602791) (xy 115.322304 -229.594666)
			(xy 115.272911 -229.578618) (xy 115.226637 -229.55504) (xy 115.184621 -229.524514) (xy 115.147898 -229.487791)
			(xy 115.117372 -229.445775) (xy 115.093794 -229.399501) (xy 115.077746 -229.350108) (xy 115.069621 -229.298813)
			(xy 114.789711 -229.298813) (xy 114.781586 -229.350108) (xy 114.765538 -229.399501) (xy 114.74196 -229.445775)
			(xy 114.711434 -229.487791) (xy 114.674711 -229.524514) (xy 114.632695 -229.55504) (xy 114.586421 -229.578618)
			(xy 114.537028 -229.594666) (xy 114.485733 -229.602791) (xy 114.433799 -229.602791) (xy 114.382504 -229.594666)
			(xy 114.333111 -229.578618) (xy 114.286837 -229.55504) (xy 114.244821 -229.524514) (xy 114.208098 -229.487791)
			(xy 114.177572 -229.445775) (xy 114.153994 -229.399501) (xy 114.137946 -229.350108) (xy 114.129821 -229.298813)
			(xy 113.849911 -229.298813) (xy 113.841786 -229.350108) (xy 113.825738 -229.399501) (xy 113.80216 -229.445775)
			(xy 113.771634 -229.487791) (xy 113.734911 -229.524514) (xy 113.692895 -229.55504) (xy 113.646621 -229.578618)
			(xy 113.597228 -229.594666) (xy 113.545933 -229.602791) (xy 113.493999 -229.602791) (xy 113.442704 -229.594666)
			(xy 113.393311 -229.578618) (xy 113.347037 -229.55504) (xy 113.305021 -229.524514) (xy 113.268298 -229.487791)
			(xy 113.237772 -229.445775) (xy 113.214194 -229.399501) (xy 113.198146 -229.350108) (xy 113.190021 -229.298813)
			(xy 112.910111 -229.298813) (xy 112.901986 -229.350108) (xy 112.885938 -229.399501) (xy 112.86236 -229.445775)
			(xy 112.831834 -229.487791) (xy 112.795111 -229.524514) (xy 112.753095 -229.55504) (xy 112.706821 -229.578618)
			(xy 112.657428 -229.594666) (xy 112.606133 -229.602791) (xy 112.554199 -229.602791) (xy 112.502904 -229.594666)
			(xy 112.453511 -229.578618) (xy 112.407237 -229.55504) (xy 112.365221 -229.524514) (xy 112.328498 -229.487791)
			(xy 112.297972 -229.445775) (xy 112.274394 -229.399501) (xy 112.258346 -229.350108) (xy 112.250221 -229.298813)
			(xy 111.970057 -229.298813) (xy 111.961932 -229.350108) (xy 111.945884 -229.399501) (xy 111.922306 -229.445775)
			(xy 111.89178 -229.487791) (xy 111.855057 -229.524514) (xy 111.813041 -229.55504) (xy 111.766767 -229.578618)
			(xy 111.717374 -229.594666) (xy 111.666079 -229.602791) (xy 111.614145 -229.602791) (xy 111.56285 -229.594666)
			(xy 111.513457 -229.578618) (xy 111.467183 -229.55504) (xy 111.425167 -229.524514) (xy 111.388444 -229.487791)
			(xy 111.357918 -229.445775) (xy 111.33434 -229.399501) (xy 111.318292 -229.350108) (xy 111.310167 -229.298813)
			(xy 111.030511 -229.298813) (xy 111.022386 -229.350108) (xy 111.006338 -229.399501) (xy 110.98276 -229.445775)
			(xy 110.952234 -229.487791) (xy 110.915511 -229.524514) (xy 110.873495 -229.55504) (xy 110.827221 -229.578618)
			(xy 110.777828 -229.594666) (xy 110.726533 -229.602791) (xy 110.674599 -229.602791) (xy 110.623304 -229.594666)
			(xy 110.573911 -229.578618) (xy 110.527637 -229.55504) (xy 110.485621 -229.524514) (xy 110.448898 -229.487791)
			(xy 110.418372 -229.445775) (xy 110.394794 -229.399501) (xy 110.378746 -229.350108) (xy 110.370621 -229.298813)
			(xy 110.090711 -229.298813) (xy 110.082586 -229.350108) (xy 110.066538 -229.399501) (xy 110.04296 -229.445775)
			(xy 110.012434 -229.487791) (xy 109.975711 -229.524514) (xy 109.933695 -229.55504) (xy 109.887421 -229.578618)
			(xy 109.838028 -229.594666) (xy 109.786733 -229.602791) (xy 109.734799 -229.602791) (xy 109.683504 -229.594666)
			(xy 109.634111 -229.578618) (xy 109.587837 -229.55504) (xy 109.545821 -229.524514) (xy 109.509098 -229.487791)
			(xy 109.478572 -229.445775) (xy 109.454994 -229.399501) (xy 109.438946 -229.350108) (xy 109.430821 -229.298813)
			(xy 109.150872 -229.298813) (xy 109.143186 -229.348486) (xy 109.127816 -229.396932) (xy 109.105211 -229.442454)
			(xy 109.075904 -229.483979) (xy 109.040586 -229.520528) (xy 109.02061 -229.536244) (xy 109.009272 -229.54539)
			(xy 108.991936 -229.568788) (xy 108.98193 -229.596134) (xy 108.980071 -229.625194) (xy 108.986511 -229.653593)
			(xy 108.993178 -229.666546) (xy 109.001801 -229.682329) (xy 109.017682 -229.714602) (xy 109.024928 -229.731062)
			(xy 109.0306 -229.743115) (xy 109.047179 -229.763956) (xy 109.06859 -229.779792) (xy 109.09337 -229.789544)
			(xy 109.119831 -229.792547) (xy 109.146167 -229.788596) (xy 109.158532 -229.78364) (xy 109.179452 -229.774941)
			(xy 109.223074 -229.762705) (xy 109.267959 -229.756544) (xy 109.290612 -229.756208) (xy 109.31658 -229.756718)
			(xy 109.367875 -229.764844) (xy 109.417269 -229.780893) (xy 109.463544 -229.804471) (xy 109.505561 -229.834997)
			(xy 109.542287 -229.871719) (xy 109.572816 -229.913734) (xy 109.596397 -229.960007) (xy 109.61245 -230.009399)
			(xy 109.62058 -230.060694) (xy 109.621066 -230.086662) (xy 109.620618 -230.111551) (xy 109.620455 -230.112629)
			(xy 109.900467 -230.112629) (xy 109.900467 -230.060695) (xy 109.908592 -230.0094) (xy 109.92464 -229.960007)
			(xy 109.948218 -229.913733) (xy 109.978744 -229.871717) (xy 110.015467 -229.834994) (xy 110.057483 -229.804468)
			(xy 110.103757 -229.78089) (xy 110.15315 -229.764842) (xy 110.204445 -229.756717) (xy 110.256379 -229.756717)
			(xy 110.307674 -229.764842) (xy 110.357067 -229.78089) (xy 110.403341 -229.804468) (xy 110.445357 -229.834994)
			(xy 110.48208 -229.871717) (xy 110.512606 -229.913733) (xy 110.536184 -229.960007) (xy 110.552232 -230.0094)
			(xy 110.560357 -230.060695) (xy 110.560866 -230.086662) (xy 110.560357 -230.112629) (xy 110.840521 -230.112629)
			(xy 110.840521 -230.060695) (xy 110.848646 -230.0094) (xy 110.864694 -229.960007) (xy 110.888272 -229.913733)
			(xy 110.918798 -229.871717) (xy 110.955521 -229.834994) (xy 110.997537 -229.804468) (xy 111.043811 -229.78089)
			(xy 111.093204 -229.764842) (xy 111.144499 -229.756717) (xy 111.196433 -229.756717) (xy 111.247728 -229.764842)
			(xy 111.297121 -229.78089) (xy 111.343395 -229.804468) (xy 111.385411 -229.834994) (xy 111.422134 -229.871717)
			(xy 111.45266 -229.913733) (xy 111.476238 -229.960007) (xy 111.492286 -230.0094) (xy 111.500411 -230.060695)
			(xy 111.50092 -230.086662) (xy 111.500411 -230.112629) (xy 111.780321 -230.112629) (xy 111.780321 -230.060695)
			(xy 111.788446 -230.0094) (xy 111.804494 -229.960007) (xy 111.828072 -229.913733) (xy 111.858598 -229.871717)
			(xy 111.895321 -229.834994) (xy 111.937337 -229.804468) (xy 111.983611 -229.78089) (xy 112.033004 -229.764842)
			(xy 112.084299 -229.756717) (xy 112.136233 -229.756717) (xy 112.187528 -229.764842) (xy 112.236921 -229.78089)
			(xy 112.283195 -229.804468) (xy 112.325211 -229.834994) (xy 112.361934 -229.871717) (xy 112.39246 -229.913733)
			(xy 112.416038 -229.960007) (xy 112.432086 -230.0094) (xy 112.440211 -230.060695) (xy 112.44072 -230.086662)
			(xy 112.440211 -230.112629) (xy 112.720121 -230.112629) (xy 112.720121 -230.060695) (xy 112.728246 -230.0094)
			(xy 112.744294 -229.960007) (xy 112.767872 -229.913733) (xy 112.798398 -229.871717) (xy 112.835121 -229.834994)
			(xy 112.877137 -229.804468) (xy 112.923411 -229.78089) (xy 112.972804 -229.764842) (xy 113.024099 -229.756717)
			(xy 113.076033 -229.756717) (xy 113.127328 -229.764842) (xy 113.176721 -229.78089) (xy 113.222995 -229.804468)
			(xy 113.265011 -229.834994) (xy 113.301734 -229.871717) (xy 113.33226 -229.913733) (xy 113.355838 -229.960007)
			(xy 113.371886 -230.0094) (xy 113.380011 -230.060695) (xy 113.38052 -230.086662) (xy 113.380011 -230.112629)
			(xy 113.659921 -230.112629) (xy 113.659921 -230.060695) (xy 113.668046 -230.0094) (xy 113.684094 -229.960007)
			(xy 113.707672 -229.913733) (xy 113.738198 -229.871717) (xy 113.774921 -229.834994) (xy 113.816937 -229.804468)
			(xy 113.863211 -229.78089) (xy 113.912604 -229.764842) (xy 113.963899 -229.756717) (xy 114.015833 -229.756717)
			(xy 114.067128 -229.764842) (xy 114.116521 -229.78089) (xy 114.162795 -229.804468) (xy 114.204811 -229.834994)
			(xy 114.241534 -229.871717) (xy 114.27206 -229.913733) (xy 114.295638 -229.960007) (xy 114.311686 -230.0094)
			(xy 114.319811 -230.060695) (xy 114.32032 -230.086662) (xy 114.319811 -230.112629) (xy 114.599721 -230.112629)
			(xy 114.599721 -230.060695) (xy 114.607846 -230.0094) (xy 114.623894 -229.960007) (xy 114.647472 -229.913733)
			(xy 114.677998 -229.871717) (xy 114.714721 -229.834994) (xy 114.756737 -229.804468) (xy 114.803011 -229.78089)
			(xy 114.852404 -229.764842) (xy 114.903699 -229.756717) (xy 114.955633 -229.756717) (xy 115.006928 -229.764842)
			(xy 115.056321 -229.78089) (xy 115.102595 -229.804468) (xy 115.144611 -229.834994) (xy 115.181334 -229.871717)
			(xy 115.21186 -229.913733) (xy 115.235438 -229.960007) (xy 115.251486 -230.0094) (xy 115.259611 -230.060695)
			(xy 115.26012 -230.086662) (xy 115.259611 -230.112629) (xy 115.539267 -230.112629) (xy 115.539267 -230.060695)
			(xy 115.547392 -230.0094) (xy 115.56344 -229.960007) (xy 115.587018 -229.913733) (xy 115.617544 -229.871717)
			(xy 115.654267 -229.834994) (xy 115.696283 -229.804468) (xy 115.742557 -229.78089) (xy 115.79195 -229.764842)
			(xy 115.843245 -229.756717) (xy 115.895179 -229.756717) (xy 115.946474 -229.764842) (xy 115.995867 -229.78089)
			(xy 116.042141 -229.804468) (xy 116.084157 -229.834994) (xy 116.12088 -229.871717) (xy 116.151406 -229.913733)
			(xy 116.174984 -229.960007) (xy 116.191032 -230.0094) (xy 116.199157 -230.060695) (xy 116.199666 -230.086662)
			(xy 116.199157 -230.112629) (xy 116.479067 -230.112629) (xy 116.479067 -230.060695) (xy 116.487192 -230.0094)
			(xy 116.50324 -229.960007) (xy 116.526818 -229.913733) (xy 116.557344 -229.871717) (xy 116.594067 -229.834994)
			(xy 116.636083 -229.804468) (xy 116.682357 -229.78089) (xy 116.73175 -229.764842) (xy 116.783045 -229.756717)
			(xy 116.834979 -229.756717) (xy 116.886274 -229.764842) (xy 116.935667 -229.78089) (xy 116.981941 -229.804468)
			(xy 117.023957 -229.834994) (xy 117.06068 -229.871717) (xy 117.091206 -229.913733) (xy 117.114784 -229.960007)
			(xy 117.130832 -230.0094) (xy 117.138957 -230.060695) (xy 117.139466 -230.086662) (xy 117.138957 -230.112629)
			(xy 117.418867 -230.112629) (xy 117.418867 -230.060695) (xy 117.426992 -230.0094) (xy 117.44304 -229.960007)
			(xy 117.466618 -229.913733) (xy 117.497144 -229.871717) (xy 117.533867 -229.834994) (xy 117.575883 -229.804468)
			(xy 117.622157 -229.78089) (xy 117.67155 -229.764842) (xy 117.722845 -229.756717) (xy 117.774779 -229.756717)
			(xy 117.826074 -229.764842) (xy 117.875467 -229.78089) (xy 117.921741 -229.804468) (xy 117.963757 -229.834994)
			(xy 118.00048 -229.871717) (xy 118.031006 -229.913733) (xy 118.054584 -229.960007) (xy 118.070632 -230.0094)
			(xy 118.078757 -230.060695) (xy 118.079266 -230.086662) (xy 118.078757 -230.112629) (xy 118.358667 -230.112629)
			(xy 118.358667 -230.060695) (xy 118.366792 -230.0094) (xy 118.38284 -229.960007) (xy 118.406418 -229.913733)
			(xy 118.436944 -229.871717) (xy 118.473667 -229.834994) (xy 118.515683 -229.804468) (xy 118.561957 -229.78089)
			(xy 118.61135 -229.764842) (xy 118.662645 -229.756717) (xy 118.714579 -229.756717) (xy 118.765874 -229.764842)
			(xy 118.815267 -229.78089) (xy 118.861541 -229.804468) (xy 118.903557 -229.834994) (xy 118.94028 -229.871717)
			(xy 118.970806 -229.913733) (xy 118.994384 -229.960007) (xy 119.010432 -230.0094) (xy 119.018557 -230.060695)
			(xy 119.019066 -230.086662) (xy 119.018557 -230.112629) (xy 119.298467 -230.112629) (xy 119.298467 -230.060695)
			(xy 119.306592 -230.0094) (xy 119.32264 -229.960007) (xy 119.346218 -229.913733) (xy 119.376744 -229.871717)
			(xy 119.413467 -229.834994) (xy 119.455483 -229.804468) (xy 119.501757 -229.78089) (xy 119.55115 -229.764842)
			(xy 119.602445 -229.756717) (xy 119.654379 -229.756717) (xy 119.705674 -229.764842) (xy 119.755067 -229.78089)
			(xy 119.801341 -229.804468) (xy 119.843357 -229.834994) (xy 119.88008 -229.871717) (xy 119.910606 -229.913733)
			(xy 119.934184 -229.960007) (xy 119.950232 -230.0094) (xy 119.958357 -230.060695) (xy 119.958866 -230.086662)
			(xy 119.958357 -230.112629) (xy 120.238267 -230.112629) (xy 120.238267 -230.060695) (xy 120.246392 -230.0094)
			(xy 120.26244 -229.960007) (xy 120.286018 -229.913733) (xy 120.316544 -229.871717) (xy 120.353267 -229.834994)
			(xy 120.395283 -229.804468) (xy 120.441557 -229.78089) (xy 120.49095 -229.764842) (xy 120.542245 -229.756717)
			(xy 120.594179 -229.756717) (xy 120.645474 -229.764842) (xy 120.694867 -229.78089) (xy 120.741141 -229.804468)
			(xy 120.783157 -229.834994) (xy 120.81988 -229.871717) (xy 120.850406 -229.913733) (xy 120.873984 -229.960007)
			(xy 120.890032 -230.0094) (xy 120.898157 -230.060695) (xy 120.898666 -230.086662) (xy 120.898157 -230.112629)
			(xy 121.178067 -230.112629) (xy 121.178067 -230.060695) (xy 121.186192 -230.0094) (xy 121.20224 -229.960007)
			(xy 121.225818 -229.913733) (xy 121.256344 -229.871717) (xy 121.293067 -229.834994) (xy 121.335083 -229.804468)
			(xy 121.381357 -229.78089) (xy 121.43075 -229.764842) (xy 121.482045 -229.756717) (xy 121.533979 -229.756717)
			(xy 121.585274 -229.764842) (xy 121.634667 -229.78089) (xy 121.680941 -229.804468) (xy 121.722957 -229.834994)
			(xy 121.75968 -229.871717) (xy 121.790206 -229.913733) (xy 121.813784 -229.960007) (xy 121.829832 -230.0094)
			(xy 121.837957 -230.060695) (xy 121.838466 -230.086662) (xy 121.837957 -230.112629) (xy 123.057667 -230.112629)
			(xy 123.057667 -230.060695) (xy 123.065792 -230.0094) (xy 123.08184 -229.960007) (xy 123.105418 -229.913733)
			(xy 123.135944 -229.871717) (xy 123.172667 -229.834994) (xy 123.214683 -229.804468) (xy 123.260957 -229.78089)
			(xy 123.31035 -229.764842) (xy 123.361645 -229.756717) (xy 123.413579 -229.756717) (xy 123.464874 -229.764842)
			(xy 123.514267 -229.78089) (xy 123.560541 -229.804468) (xy 123.602557 -229.834994) (xy 123.63928 -229.871717)
			(xy 123.669806 -229.913733) (xy 123.693384 -229.960007) (xy 123.709432 -230.0094) (xy 123.717557 -230.060695)
			(xy 123.718066 -230.086662) (xy 123.717557 -230.112629) (xy 123.997467 -230.112629) (xy 123.997467 -230.060695)
			(xy 124.005592 -230.0094) (xy 124.02164 -229.960007) (xy 124.045218 -229.913733) (xy 124.075744 -229.871717)
			(xy 124.112467 -229.834994) (xy 124.154483 -229.804468) (xy 124.200757 -229.78089) (xy 124.25015 -229.764842)
			(xy 124.301445 -229.756717) (xy 124.353379 -229.756717) (xy 124.404674 -229.764842) (xy 124.454067 -229.78089)
			(xy 124.500341 -229.804468) (xy 124.542357 -229.834994) (xy 124.57908 -229.871717) (xy 124.609606 -229.913733)
			(xy 124.633184 -229.960007) (xy 124.649232 -230.0094) (xy 124.657357 -230.060695) (xy 124.657866 -230.086662)
			(xy 124.657357 -230.112629) (xy 124.937521 -230.112629) (xy 124.937521 -230.060695) (xy 124.945646 -230.0094)
			(xy 124.961694 -229.960007) (xy 124.985272 -229.913733) (xy 125.015798 -229.871717) (xy 125.052521 -229.834994)
			(xy 125.094537 -229.804468) (xy 125.140811 -229.78089) (xy 125.190204 -229.764842) (xy 125.241499 -229.756717)
			(xy 125.293433 -229.756717) (xy 125.344728 -229.764842) (xy 125.394121 -229.78089) (xy 125.440395 -229.804468)
			(xy 125.482411 -229.834994) (xy 125.519134 -229.871717) (xy 125.54966 -229.913733) (xy 125.573238 -229.960007)
			(xy 125.589286 -230.0094) (xy 125.597411 -230.060695) (xy 125.59792 -230.086662) (xy 125.597411 -230.112629)
			(xy 125.877067 -230.112629) (xy 125.877067 -230.060695) (xy 125.885192 -230.0094) (xy 125.90124 -229.960007)
			(xy 125.924818 -229.913733) (xy 125.955344 -229.871717) (xy 125.992067 -229.834994) (xy 126.034083 -229.804468)
			(xy 126.080357 -229.78089) (xy 126.12975 -229.764842) (xy 126.181045 -229.756717) (xy 126.232979 -229.756717)
			(xy 126.284274 -229.764842) (xy 126.333667 -229.78089) (xy 126.379941 -229.804468) (xy 126.421957 -229.834994)
			(xy 126.45868 -229.871717) (xy 126.489206 -229.913733) (xy 126.512784 -229.960007) (xy 126.528832 -230.0094)
			(xy 126.536957 -230.060695) (xy 126.537466 -230.086662) (xy 126.536957 -230.112629) (xy 126.816867 -230.112629)
			(xy 126.816867 -230.060695) (xy 126.824992 -230.0094) (xy 126.84104 -229.960007) (xy 126.864618 -229.913733)
			(xy 126.895144 -229.871717) (xy 126.931867 -229.834994) (xy 126.973883 -229.804468) (xy 127.020157 -229.78089)
			(xy 127.06955 -229.764842) (xy 127.120845 -229.756717) (xy 127.172779 -229.756717) (xy 127.224074 -229.764842)
			(xy 127.273467 -229.78089) (xy 127.319741 -229.804468) (xy 127.361757 -229.834994) (xy 127.39848 -229.871717)
			(xy 127.429006 -229.913733) (xy 127.452584 -229.960007) (xy 127.468632 -230.0094) (xy 127.476757 -230.060695)
			(xy 127.477266 -230.086662) (xy 127.476757 -230.112629) (xy 127.468632 -230.163924) (xy 127.452584 -230.213317)
			(xy 127.429006 -230.259591) (xy 127.39848 -230.301607) (xy 127.361757 -230.33833) (xy 127.319741 -230.368856)
			(xy 127.273467 -230.392434) (xy 127.224074 -230.408482) (xy 127.172779 -230.416607) (xy 127.120845 -230.416607)
			(xy 127.06955 -230.408482) (xy 127.020157 -230.392434) (xy 126.973883 -230.368856) (xy 126.931867 -230.33833)
			(xy 126.895144 -230.301607) (xy 126.864618 -230.259591) (xy 126.84104 -230.213317) (xy 126.824992 -230.163924)
			(xy 126.816867 -230.112629) (xy 126.536957 -230.112629) (xy 126.528832 -230.163924) (xy 126.512784 -230.213317)
			(xy 126.489206 -230.259591) (xy 126.45868 -230.301607) (xy 126.421957 -230.33833) (xy 126.379941 -230.368856)
			(xy 126.333667 -230.392434) (xy 126.284274 -230.408482) (xy 126.232979 -230.416607) (xy 126.181045 -230.416607)
			(xy 126.12975 -230.408482) (xy 126.080357 -230.392434) (xy 126.034083 -230.368856) (xy 125.992067 -230.33833)
			(xy 125.955344 -230.301607) (xy 125.924818 -230.259591) (xy 125.90124 -230.213317) (xy 125.885192 -230.163924)
			(xy 125.877067 -230.112629) (xy 125.597411 -230.112629) (xy 125.589286 -230.163924) (xy 125.573238 -230.213317)
			(xy 125.54966 -230.259591) (xy 125.519134 -230.301607) (xy 125.482411 -230.33833) (xy 125.440395 -230.368856)
			(xy 125.394121 -230.392434) (xy 125.344728 -230.408482) (xy 125.293433 -230.416607) (xy 125.241499 -230.416607)
			(xy 125.190204 -230.408482) (xy 125.140811 -230.392434) (xy 125.094537 -230.368856) (xy 125.052521 -230.33833)
			(xy 125.015798 -230.301607) (xy 124.985272 -230.259591) (xy 124.961694 -230.213317) (xy 124.945646 -230.163924)
			(xy 124.937521 -230.112629) (xy 124.657357 -230.112629) (xy 124.649232 -230.163924) (xy 124.633184 -230.213317)
			(xy 124.609606 -230.259591) (xy 124.57908 -230.301607) (xy 124.542357 -230.33833) (xy 124.500341 -230.368856)
			(xy 124.454067 -230.392434) (xy 124.404674 -230.408482) (xy 124.353379 -230.416607) (xy 124.301445 -230.416607)
			(xy 124.25015 -230.408482) (xy 124.200757 -230.392434) (xy 124.154483 -230.368856) (xy 124.112467 -230.33833)
			(xy 124.075744 -230.301607) (xy 124.045218 -230.259591) (xy 124.02164 -230.213317) (xy 124.005592 -230.163924)
			(xy 123.997467 -230.112629) (xy 123.717557 -230.112629) (xy 123.709432 -230.163924) (xy 123.693384 -230.213317)
			(xy 123.669806 -230.259591) (xy 123.63928 -230.301607) (xy 123.602557 -230.33833) (xy 123.560541 -230.368856)
			(xy 123.514267 -230.392434) (xy 123.464874 -230.408482) (xy 123.413579 -230.416607) (xy 123.361645 -230.416607)
			(xy 123.31035 -230.408482) (xy 123.260957 -230.392434) (xy 123.214683 -230.368856) (xy 123.172667 -230.33833)
			(xy 123.135944 -230.301607) (xy 123.105418 -230.259591) (xy 123.08184 -230.213317) (xy 123.065792 -230.163924)
			(xy 123.057667 -230.112629) (xy 121.837957 -230.112629) (xy 121.829832 -230.163924) (xy 121.813784 -230.213317)
			(xy 121.790206 -230.259591) (xy 121.75968 -230.301607) (xy 121.722957 -230.33833) (xy 121.680941 -230.368856)
			(xy 121.634667 -230.392434) (xy 121.585274 -230.408482) (xy 121.533979 -230.416607) (xy 121.482045 -230.416607)
			(xy 121.43075 -230.408482) (xy 121.381357 -230.392434) (xy 121.335083 -230.368856) (xy 121.293067 -230.33833)
			(xy 121.256344 -230.301607) (xy 121.225818 -230.259591) (xy 121.20224 -230.213317) (xy 121.186192 -230.163924)
			(xy 121.178067 -230.112629) (xy 120.898157 -230.112629) (xy 120.890032 -230.163924) (xy 120.873984 -230.213317)
			(xy 120.850406 -230.259591) (xy 120.81988 -230.301607) (xy 120.783157 -230.33833) (xy 120.741141 -230.368856)
			(xy 120.694867 -230.392434) (xy 120.645474 -230.408482) (xy 120.594179 -230.416607) (xy 120.542245 -230.416607)
			(xy 120.49095 -230.408482) (xy 120.441557 -230.392434) (xy 120.395283 -230.368856) (xy 120.353267 -230.33833)
			(xy 120.316544 -230.301607) (xy 120.286018 -230.259591) (xy 120.26244 -230.213317) (xy 120.246392 -230.163924)
			(xy 120.238267 -230.112629) (xy 119.958357 -230.112629) (xy 119.950232 -230.163924) (xy 119.934184 -230.213317)
			(xy 119.910606 -230.259591) (xy 119.88008 -230.301607) (xy 119.843357 -230.33833) (xy 119.801341 -230.368856)
			(xy 119.755067 -230.392434) (xy 119.705674 -230.408482) (xy 119.654379 -230.416607) (xy 119.602445 -230.416607)
			(xy 119.55115 -230.408482) (xy 119.501757 -230.392434) (xy 119.455483 -230.368856) (xy 119.413467 -230.33833)
			(xy 119.376744 -230.301607) (xy 119.346218 -230.259591) (xy 119.32264 -230.213317) (xy 119.306592 -230.163924)
			(xy 119.298467 -230.112629) (xy 119.018557 -230.112629) (xy 119.010432 -230.163924) (xy 118.994384 -230.213317)
			(xy 118.970806 -230.259591) (xy 118.94028 -230.301607) (xy 118.903557 -230.33833) (xy 118.861541 -230.368856)
			(xy 118.815267 -230.392434) (xy 118.765874 -230.408482) (xy 118.714579 -230.416607) (xy 118.662645 -230.416607)
			(xy 118.61135 -230.408482) (xy 118.561957 -230.392434) (xy 118.515683 -230.368856) (xy 118.473667 -230.33833)
			(xy 118.436944 -230.301607) (xy 118.406418 -230.259591) (xy 118.38284 -230.213317) (xy 118.366792 -230.163924)
			(xy 118.358667 -230.112629) (xy 118.078757 -230.112629) (xy 118.070632 -230.163924) (xy 118.054584 -230.213317)
			(xy 118.031006 -230.259591) (xy 118.00048 -230.301607) (xy 117.963757 -230.33833) (xy 117.921741 -230.368856)
			(xy 117.875467 -230.392434) (xy 117.826074 -230.408482) (xy 117.774779 -230.416607) (xy 117.722845 -230.416607)
			(xy 117.67155 -230.408482) (xy 117.622157 -230.392434) (xy 117.575883 -230.368856) (xy 117.533867 -230.33833)
			(xy 117.497144 -230.301607) (xy 117.466618 -230.259591) (xy 117.44304 -230.213317) (xy 117.426992 -230.163924)
			(xy 117.418867 -230.112629) (xy 117.138957 -230.112629) (xy 117.130832 -230.163924) (xy 117.114784 -230.213317)
			(xy 117.091206 -230.259591) (xy 117.06068 -230.301607) (xy 117.023957 -230.33833) (xy 116.981941 -230.368856)
			(xy 116.935667 -230.392434) (xy 116.886274 -230.408482) (xy 116.834979 -230.416607) (xy 116.783045 -230.416607)
			(xy 116.73175 -230.408482) (xy 116.682357 -230.392434) (xy 116.636083 -230.368856) (xy 116.594067 -230.33833)
			(xy 116.557344 -230.301607) (xy 116.526818 -230.259591) (xy 116.50324 -230.213317) (xy 116.487192 -230.163924)
			(xy 116.479067 -230.112629) (xy 116.199157 -230.112629) (xy 116.191032 -230.163924) (xy 116.174984 -230.213317)
			(xy 116.151406 -230.259591) (xy 116.12088 -230.301607) (xy 116.084157 -230.33833) (xy 116.042141 -230.368856)
			(xy 115.995867 -230.392434) (xy 115.946474 -230.408482) (xy 115.895179 -230.416607) (xy 115.843245 -230.416607)
			(xy 115.79195 -230.408482) (xy 115.742557 -230.392434) (xy 115.696283 -230.368856) (xy 115.654267 -230.33833)
			(xy 115.617544 -230.301607) (xy 115.587018 -230.259591) (xy 115.56344 -230.213317) (xy 115.547392 -230.163924)
			(xy 115.539267 -230.112629) (xy 115.259611 -230.112629) (xy 115.251486 -230.163924) (xy 115.235438 -230.213317)
			(xy 115.21186 -230.259591) (xy 115.181334 -230.301607) (xy 115.144611 -230.33833) (xy 115.102595 -230.368856)
			(xy 115.056321 -230.392434) (xy 115.006928 -230.408482) (xy 114.955633 -230.416607) (xy 114.903699 -230.416607)
			(xy 114.852404 -230.408482) (xy 114.803011 -230.392434) (xy 114.756737 -230.368856) (xy 114.714721 -230.33833)
			(xy 114.677998 -230.301607) (xy 114.647472 -230.259591) (xy 114.623894 -230.213317) (xy 114.607846 -230.163924)
			(xy 114.599721 -230.112629) (xy 114.319811 -230.112629) (xy 114.311686 -230.163924) (xy 114.295638 -230.213317)
			(xy 114.27206 -230.259591) (xy 114.241534 -230.301607) (xy 114.204811 -230.33833) (xy 114.162795 -230.368856)
			(xy 114.116521 -230.392434) (xy 114.067128 -230.408482) (xy 114.015833 -230.416607) (xy 113.963899 -230.416607)
			(xy 113.912604 -230.408482) (xy 113.863211 -230.392434) (xy 113.816937 -230.368856) (xy 113.774921 -230.33833)
			(xy 113.738198 -230.301607) (xy 113.707672 -230.259591) (xy 113.684094 -230.213317) (xy 113.668046 -230.163924)
			(xy 113.659921 -230.112629) (xy 113.380011 -230.112629) (xy 113.371886 -230.163924) (xy 113.355838 -230.213317)
			(xy 113.33226 -230.259591) (xy 113.301734 -230.301607) (xy 113.265011 -230.33833) (xy 113.222995 -230.368856)
			(xy 113.176721 -230.392434) (xy 113.127328 -230.408482) (xy 113.076033 -230.416607) (xy 113.024099 -230.416607)
			(xy 112.972804 -230.408482) (xy 112.923411 -230.392434) (xy 112.877137 -230.368856) (xy 112.835121 -230.33833)
			(xy 112.798398 -230.301607) (xy 112.767872 -230.259591) (xy 112.744294 -230.213317) (xy 112.728246 -230.163924)
			(xy 112.720121 -230.112629) (xy 112.440211 -230.112629) (xy 112.432086 -230.163924) (xy 112.416038 -230.213317)
			(xy 112.39246 -230.259591) (xy 112.361934 -230.301607) (xy 112.325211 -230.33833) (xy 112.283195 -230.368856)
			(xy 112.236921 -230.392434) (xy 112.187528 -230.408482) (xy 112.136233 -230.416607) (xy 112.084299 -230.416607)
			(xy 112.033004 -230.408482) (xy 111.983611 -230.392434) (xy 111.937337 -230.368856) (xy 111.895321 -230.33833)
			(xy 111.858598 -230.301607) (xy 111.828072 -230.259591) (xy 111.804494 -230.213317) (xy 111.788446 -230.163924)
			(xy 111.780321 -230.112629) (xy 111.500411 -230.112629) (xy 111.492286 -230.163924) (xy 111.476238 -230.213317)
			(xy 111.45266 -230.259591) (xy 111.422134 -230.301607) (xy 111.385411 -230.33833) (xy 111.343395 -230.368856)
			(xy 111.297121 -230.392434) (xy 111.247728 -230.408482) (xy 111.196433 -230.416607) (xy 111.144499 -230.416607)
			(xy 111.093204 -230.408482) (xy 111.043811 -230.392434) (xy 110.997537 -230.368856) (xy 110.955521 -230.33833)
			(xy 110.918798 -230.301607) (xy 110.888272 -230.259591) (xy 110.864694 -230.213317) (xy 110.848646 -230.163924)
			(xy 110.840521 -230.112629) (xy 110.560357 -230.112629) (xy 110.552232 -230.163924) (xy 110.536184 -230.213317)
			(xy 110.512606 -230.259591) (xy 110.48208 -230.301607) (xy 110.445357 -230.33833) (xy 110.403341 -230.368856)
			(xy 110.357067 -230.392434) (xy 110.307674 -230.408482) (xy 110.256379 -230.416607) (xy 110.204445 -230.416607)
			(xy 110.15315 -230.408482) (xy 110.103757 -230.392434) (xy 110.057483 -230.368856) (xy 110.015467 -230.33833)
			(xy 109.978744 -230.301607) (xy 109.948218 -230.259591) (xy 109.92464 -230.213317) (xy 109.908592 -230.163924)
			(xy 109.900467 -230.112629) (xy 109.620455 -230.112629) (xy 109.613158 -230.160768) (xy 109.5984 -230.208309)
			(xy 109.576679 -230.253099) (xy 109.548486 -230.294124) (xy 109.514458 -230.330456) (xy 109.475366 -230.361274)
			(xy 109.453934 -230.373936) (xy 109.440895 -230.381948) (xy 109.419967 -230.404259) (xy 109.406571 -230.43176)
			(xy 109.401906 -230.461993) (xy 109.406389 -230.492253) (xy 109.412532 -230.50627) (xy 109.442504 -230.571802)
			(xy 109.44874 -230.584889) (xy 109.467274 -230.607164) (xy 109.491312 -230.623344) (xy 109.518925 -230.632129)
			(xy 109.547893 -230.632813) (xy 109.57589 -230.625342) (xy 109.588554 -230.618284) (xy 109.608059 -230.60683)
			(xy 109.649534 -230.588778) (xy 109.693085 -230.576553) (xy 109.737895 -230.570384) (xy 109.760512 -230.570024)
			(xy 109.78648 -230.570534) (xy 109.837777 -230.578661) (xy 109.887172 -230.594711) (xy 109.933447 -230.618291)
			(xy 109.975464 -230.64882) (xy 110.012188 -230.685545) (xy 110.042715 -230.727563) (xy 110.066293 -230.77384)
			(xy 110.082342 -230.823234) (xy 110.090467 -230.874532) (xy 110.090467 -230.926445) (xy 110.370621 -230.926445)
			(xy 110.370621 -230.874511) (xy 110.378746 -230.823216) (xy 110.394794 -230.773823) (xy 110.418372 -230.727549)
			(xy 110.448898 -230.685533) (xy 110.485621 -230.64881) (xy 110.527637 -230.618284) (xy 110.573911 -230.594706)
			(xy 110.623304 -230.578658) (xy 110.674599 -230.570533) (xy 110.726533 -230.570533) (xy 110.777828 -230.578658)
			(xy 110.827221 -230.594706) (xy 110.873495 -230.618284) (xy 110.915511 -230.64881) (xy 110.952234 -230.685533)
			(xy 110.98276 -230.727549) (xy 111.006338 -230.773823) (xy 111.022386 -230.823216) (xy 111.030511 -230.874511)
			(xy 111.03102 -230.900478) (xy 111.030511 -230.926445) (xy 111.310421 -230.926445) (xy 111.310421 -230.874511)
			(xy 111.318546 -230.823216) (xy 111.334594 -230.773823) (xy 111.358172 -230.727549) (xy 111.388698 -230.685533)
			(xy 111.425421 -230.64881) (xy 111.467437 -230.618284) (xy 111.513711 -230.594706) (xy 111.563104 -230.578658)
			(xy 111.614399 -230.570533) (xy 111.666333 -230.570533) (xy 111.717628 -230.578658) (xy 111.767021 -230.594706)
			(xy 111.813295 -230.618284) (xy 111.855311 -230.64881) (xy 111.892034 -230.685533) (xy 111.92256 -230.727549)
			(xy 111.946138 -230.773823) (xy 111.962186 -230.823216) (xy 111.970311 -230.874511) (xy 111.97082 -230.900478)
			(xy 111.970311 -230.926445) (xy 112.250221 -230.926445) (xy 112.250221 -230.874511) (xy 112.258346 -230.823216)
			(xy 112.274394 -230.773823) (xy 112.297972 -230.727549) (xy 112.328498 -230.685533) (xy 112.365221 -230.64881)
			(xy 112.407237 -230.618284) (xy 112.453511 -230.594706) (xy 112.502904 -230.578658) (xy 112.554199 -230.570533)
			(xy 112.606133 -230.570533) (xy 112.657428 -230.578658) (xy 112.706821 -230.594706) (xy 112.753095 -230.618284)
			(xy 112.795111 -230.64881) (xy 112.831834 -230.685533) (xy 112.86236 -230.727549) (xy 112.885938 -230.773823)
			(xy 112.901986 -230.823216) (xy 112.910111 -230.874511) (xy 112.91062 -230.900478) (xy 112.910111 -230.926445)
			(xy 113.190021 -230.926445) (xy 113.190021 -230.874511) (xy 113.198146 -230.823216) (xy 113.214194 -230.773823)
			(xy 113.237772 -230.727549) (xy 113.268298 -230.685533) (xy 113.305021 -230.64881) (xy 113.347037 -230.618284)
			(xy 113.393311 -230.594706) (xy 113.442704 -230.578658) (xy 113.493999 -230.570533) (xy 113.545933 -230.570533)
			(xy 113.597228 -230.578658) (xy 113.646621 -230.594706) (xy 113.692895 -230.618284) (xy 113.734911 -230.64881)
			(xy 113.771634 -230.685533) (xy 113.80216 -230.727549) (xy 113.825738 -230.773823) (xy 113.841786 -230.823216)
			(xy 113.849911 -230.874511) (xy 113.85042 -230.900478) (xy 113.849911 -230.926445) (xy 114.130075 -230.926445)
			(xy 114.130075 -230.874511) (xy 114.1382 -230.823216) (xy 114.154248 -230.773823) (xy 114.177826 -230.727549)
			(xy 114.208352 -230.685533) (xy 114.245075 -230.64881) (xy 114.287091 -230.618284) (xy 114.333365 -230.594706)
			(xy 114.382758 -230.578658) (xy 114.434053 -230.570533) (xy 114.485987 -230.570533) (xy 114.537282 -230.578658)
			(xy 114.586675 -230.594706) (xy 114.632949 -230.618284) (xy 114.674965 -230.64881) (xy 114.711688 -230.685533)
			(xy 114.742214 -230.727549) (xy 114.765792 -230.773823) (xy 114.78184 -230.823216) (xy 114.789965 -230.874511)
			(xy 114.790474 -230.900478) (xy 114.789965 -230.926445) (xy 115.069621 -230.926445) (xy 115.069621 -230.874511)
			(xy 115.077746 -230.823216) (xy 115.093794 -230.773823) (xy 115.117372 -230.727549) (xy 115.147898 -230.685533)
			(xy 115.184621 -230.64881) (xy 115.226637 -230.618284) (xy 115.272911 -230.594706) (xy 115.322304 -230.578658)
			(xy 115.373599 -230.570533) (xy 115.425533 -230.570533) (xy 115.476828 -230.578658) (xy 115.526221 -230.594706)
			(xy 115.572495 -230.618284) (xy 115.614511 -230.64881) (xy 115.651234 -230.685533) (xy 115.68176 -230.727549)
			(xy 115.705338 -230.773823) (xy 115.721386 -230.823216) (xy 115.729511 -230.874511) (xy 115.73002 -230.900478)
			(xy 115.729511 -230.926445) (xy 116.009421 -230.926445) (xy 116.009421 -230.874511) (xy 116.017546 -230.823216)
			(xy 116.033594 -230.773823) (xy 116.057172 -230.727549) (xy 116.087698 -230.685533) (xy 116.124421 -230.64881)
			(xy 116.166437 -230.618284) (xy 116.212711 -230.594706) (xy 116.262104 -230.578658) (xy 116.313399 -230.570533)
			(xy 116.365333 -230.570533) (xy 116.416628 -230.578658) (xy 116.466021 -230.594706) (xy 116.512295 -230.618284)
			(xy 116.554311 -230.64881) (xy 116.591034 -230.685533) (xy 116.62156 -230.727549) (xy 116.645138 -230.773823)
			(xy 116.661186 -230.823216) (xy 116.669311 -230.874511) (xy 116.66982 -230.900478) (xy 116.669311 -230.926445)
			(xy 116.949221 -230.926445) (xy 116.949221 -230.874511) (xy 116.957346 -230.823216) (xy 116.973394 -230.773823)
			(xy 116.996972 -230.727549) (xy 117.027498 -230.685533) (xy 117.064221 -230.64881) (xy 117.106237 -230.618284)
			(xy 117.152511 -230.594706) (xy 117.201904 -230.578658) (xy 117.253199 -230.570533) (xy 117.305133 -230.570533)
			(xy 117.356428 -230.578658) (xy 117.405821 -230.594706) (xy 117.452095 -230.618284) (xy 117.494111 -230.64881)
			(xy 117.530834 -230.685533) (xy 117.56136 -230.727549) (xy 117.584938 -230.773823) (xy 117.600986 -230.823216)
			(xy 117.609111 -230.874511) (xy 117.60962 -230.900478) (xy 117.609111 -230.926445) (xy 117.889021 -230.926445)
			(xy 117.889021 -230.874511) (xy 117.897146 -230.823216) (xy 117.913194 -230.773823) (xy 117.936772 -230.727549)
			(xy 117.967298 -230.685533) (xy 118.004021 -230.64881) (xy 118.046037 -230.618284) (xy 118.092311 -230.594706)
			(xy 118.141704 -230.578658) (xy 118.192999 -230.570533) (xy 118.244933 -230.570533) (xy 118.296228 -230.578658)
			(xy 118.345621 -230.594706) (xy 118.391895 -230.618284) (xy 118.433911 -230.64881) (xy 118.470634 -230.685533)
			(xy 118.50116 -230.727549) (xy 118.524738 -230.773823) (xy 118.540786 -230.823216) (xy 118.548911 -230.874511)
			(xy 118.54942 -230.900478) (xy 118.548911 -230.926445) (xy 118.828821 -230.926445) (xy 118.828821 -230.874511)
			(xy 118.836946 -230.823216) (xy 118.852994 -230.773823) (xy 118.876572 -230.727549) (xy 118.907098 -230.685533)
			(xy 118.943821 -230.64881) (xy 118.985837 -230.618284) (xy 119.032111 -230.594706) (xy 119.081504 -230.578658)
			(xy 119.132799 -230.570533) (xy 119.184733 -230.570533) (xy 119.236028 -230.578658) (xy 119.285421 -230.594706)
			(xy 119.331695 -230.618284) (xy 119.373711 -230.64881) (xy 119.410434 -230.685533) (xy 119.44096 -230.727549)
			(xy 119.464538 -230.773823) (xy 119.480586 -230.823216) (xy 119.488711 -230.874511) (xy 119.48922 -230.900478)
			(xy 119.488711 -230.926445) (xy 119.768621 -230.926445) (xy 119.768621 -230.874511) (xy 119.776746 -230.823216)
			(xy 119.792794 -230.773823) (xy 119.816372 -230.727549) (xy 119.846898 -230.685533) (xy 119.883621 -230.64881)
			(xy 119.925637 -230.618284) (xy 119.971911 -230.594706) (xy 120.021304 -230.578658) (xy 120.072599 -230.570533)
			(xy 120.124533 -230.570533) (xy 120.175828 -230.578658) (xy 120.225221 -230.594706) (xy 120.271495 -230.618284)
			(xy 120.313511 -230.64881) (xy 120.350234 -230.685533) (xy 120.38076 -230.727549) (xy 120.404338 -230.773823)
			(xy 120.420386 -230.823216) (xy 120.428511 -230.874511) (xy 120.42902 -230.900478) (xy 120.428511 -230.926445)
			(xy 120.708421 -230.926445) (xy 120.708421 -230.874511) (xy 120.716546 -230.823216) (xy 120.732594 -230.773823)
			(xy 120.756172 -230.727549) (xy 120.786698 -230.685533) (xy 120.823421 -230.64881) (xy 120.865437 -230.618284)
			(xy 120.911711 -230.594706) (xy 120.961104 -230.578658) (xy 121.012399 -230.570533) (xy 121.064333 -230.570533)
			(xy 121.115628 -230.578658) (xy 121.165021 -230.594706) (xy 121.211295 -230.618284) (xy 121.253311 -230.64881)
			(xy 121.290034 -230.685533) (xy 121.32056 -230.727549) (xy 121.344138 -230.773823) (xy 121.360186 -230.823216)
			(xy 121.368311 -230.874511) (xy 121.36882 -230.900478) (xy 121.368311 -230.926445) (xy 121.647967 -230.926445)
			(xy 121.647967 -230.874511) (xy 121.656092 -230.823216) (xy 121.67214 -230.773823) (xy 121.695718 -230.727549)
			(xy 121.726244 -230.685533) (xy 121.762967 -230.64881) (xy 121.804983 -230.618284) (xy 121.851257 -230.594706)
			(xy 121.90065 -230.578658) (xy 121.951945 -230.570533) (xy 122.003879 -230.570533) (xy 122.055174 -230.578658)
			(xy 122.104567 -230.594706) (xy 122.150841 -230.618284) (xy 122.192857 -230.64881) (xy 122.22958 -230.685533)
			(xy 122.260106 -230.727549) (xy 122.283684 -230.773823) (xy 122.299732 -230.823216) (xy 122.307857 -230.874511)
			(xy 122.308366 -230.900478) (xy 122.307857 -230.926445) (xy 122.588021 -230.926445) (xy 122.588021 -230.874511)
			(xy 122.596146 -230.823216) (xy 122.612194 -230.773823) (xy 122.635772 -230.727549) (xy 122.666298 -230.685533)
			(xy 122.703021 -230.64881) (xy 122.745037 -230.618284) (xy 122.791311 -230.594706) (xy 122.840704 -230.578658)
			(xy 122.891999 -230.570533) (xy 122.943933 -230.570533) (xy 122.995228 -230.578658) (xy 123.044621 -230.594706)
			(xy 123.090895 -230.618284) (xy 123.132911 -230.64881) (xy 123.169634 -230.685533) (xy 123.20016 -230.727549)
			(xy 123.223738 -230.773823) (xy 123.239786 -230.823216) (xy 123.247911 -230.874511) (xy 123.24842 -230.900478)
			(xy 123.247911 -230.926445) (xy 123.527821 -230.926445) (xy 123.527821 -230.874511) (xy 123.535946 -230.823216)
			(xy 123.551994 -230.773823) (xy 123.575572 -230.727549) (xy 123.606098 -230.685533) (xy 123.642821 -230.64881)
			(xy 123.684837 -230.618284) (xy 123.731111 -230.594706) (xy 123.780504 -230.578658) (xy 123.831799 -230.570533)
			(xy 123.883733 -230.570533) (xy 123.935028 -230.578658) (xy 123.984421 -230.594706) (xy 124.030695 -230.618284)
			(xy 124.072711 -230.64881) (xy 124.109434 -230.685533) (xy 124.13996 -230.727549) (xy 124.163538 -230.773823)
			(xy 124.179586 -230.823216) (xy 124.187711 -230.874511) (xy 124.18822 -230.900478) (xy 124.187711 -230.926445)
			(xy 124.467621 -230.926445) (xy 124.467621 -230.874511) (xy 124.475746 -230.823216) (xy 124.491794 -230.773823)
			(xy 124.515372 -230.727549) (xy 124.545898 -230.685533) (xy 124.582621 -230.64881) (xy 124.624637 -230.618284)
			(xy 124.670911 -230.594706) (xy 124.720304 -230.578658) (xy 124.771599 -230.570533) (xy 124.823533 -230.570533)
			(xy 124.874828 -230.578658) (xy 124.924221 -230.594706) (xy 124.970495 -230.618284) (xy 125.012511 -230.64881)
			(xy 125.049234 -230.685533) (xy 125.07976 -230.727549) (xy 125.103338 -230.773823) (xy 125.119386 -230.823216)
			(xy 125.127511 -230.874511) (xy 125.12802 -230.900478) (xy 125.127511 -230.926445) (xy 125.407421 -230.926445)
			(xy 125.407421 -230.874511) (xy 125.415546 -230.823216) (xy 125.431594 -230.773823) (xy 125.455172 -230.727549)
			(xy 125.485698 -230.685533) (xy 125.522421 -230.64881) (xy 125.564437 -230.618284) (xy 125.610711 -230.594706)
			(xy 125.660104 -230.578658) (xy 125.711399 -230.570533) (xy 125.763333 -230.570533) (xy 125.814628 -230.578658)
			(xy 125.864021 -230.594706) (xy 125.910295 -230.618284) (xy 125.952311 -230.64881) (xy 125.989034 -230.685533)
			(xy 126.01956 -230.727549) (xy 126.043138 -230.773823) (xy 126.059186 -230.823216) (xy 126.067311 -230.874511)
			(xy 126.06782 -230.900478) (xy 126.067311 -230.926445) (xy 126.347221 -230.926445) (xy 126.347221 -230.874511)
			(xy 126.355346 -230.823216) (xy 126.371394 -230.773823) (xy 126.394972 -230.727549) (xy 126.425498 -230.685533)
			(xy 126.462221 -230.64881) (xy 126.504237 -230.618284) (xy 126.550511 -230.594706) (xy 126.599904 -230.578658)
			(xy 126.651199 -230.570533) (xy 126.703133 -230.570533) (xy 126.754428 -230.578658) (xy 126.803821 -230.594706)
			(xy 126.850095 -230.618284) (xy 126.892111 -230.64881) (xy 126.928834 -230.685533) (xy 126.95936 -230.727549)
			(xy 126.982938 -230.773823) (xy 126.998986 -230.823216) (xy 127.007111 -230.874511) (xy 127.00762 -230.900478)
			(xy 127.007111 -230.926445) (xy 126.998986 -230.97774) (xy 126.982938 -231.027133) (xy 126.95936 -231.073407)
			(xy 126.928834 -231.115423) (xy 126.892111 -231.152146) (xy 126.850095 -231.182672) (xy 126.803821 -231.20625)
			(xy 126.754428 -231.222298) (xy 126.703133 -231.230423) (xy 126.651199 -231.230423) (xy 126.599904 -231.222298)
			(xy 126.550511 -231.20625) (xy 126.504237 -231.182672) (xy 126.462221 -231.152146) (xy 126.425498 -231.115423)
			(xy 126.394972 -231.073407) (xy 126.371394 -231.027133) (xy 126.355346 -230.97774) (xy 126.347221 -230.926445)
			(xy 126.067311 -230.926445) (xy 126.059186 -230.97774) (xy 126.043138 -231.027133) (xy 126.01956 -231.073407)
			(xy 125.989034 -231.115423) (xy 125.952311 -231.152146) (xy 125.910295 -231.182672) (xy 125.864021 -231.20625)
			(xy 125.814628 -231.222298) (xy 125.763333 -231.230423) (xy 125.711399 -231.230423) (xy 125.660104 -231.222298)
			(xy 125.610711 -231.20625) (xy 125.564437 -231.182672) (xy 125.522421 -231.152146) (xy 125.485698 -231.115423)
			(xy 125.455172 -231.073407) (xy 125.431594 -231.027133) (xy 125.415546 -230.97774) (xy 125.407421 -230.926445)
			(xy 125.127511 -230.926445) (xy 125.119386 -230.97774) (xy 125.103338 -231.027133) (xy 125.07976 -231.073407)
			(xy 125.049234 -231.115423) (xy 125.012511 -231.152146) (xy 124.970495 -231.182672) (xy 124.924221 -231.20625)
			(xy 124.874828 -231.222298) (xy 124.823533 -231.230423) (xy 124.771599 -231.230423) (xy 124.720304 -231.222298)
			(xy 124.670911 -231.20625) (xy 124.624637 -231.182672) (xy 124.582621 -231.152146) (xy 124.545898 -231.115423)
			(xy 124.515372 -231.073407) (xy 124.491794 -231.027133) (xy 124.475746 -230.97774) (xy 124.467621 -230.926445)
			(xy 124.187711 -230.926445) (xy 124.179586 -230.97774) (xy 124.163538 -231.027133) (xy 124.13996 -231.073407)
			(xy 124.109434 -231.115423) (xy 124.072711 -231.152146) (xy 124.030695 -231.182672) (xy 123.984421 -231.20625)
			(xy 123.935028 -231.222298) (xy 123.883733 -231.230423) (xy 123.831799 -231.230423) (xy 123.780504 -231.222298)
			(xy 123.731111 -231.20625) (xy 123.684837 -231.182672) (xy 123.642821 -231.152146) (xy 123.606098 -231.115423)
			(xy 123.575572 -231.073407) (xy 123.551994 -231.027133) (xy 123.535946 -230.97774) (xy 123.527821 -230.926445)
			(xy 123.247911 -230.926445) (xy 123.239786 -230.97774) (xy 123.223738 -231.027133) (xy 123.20016 -231.073407)
			(xy 123.169634 -231.115423) (xy 123.132911 -231.152146) (xy 123.090895 -231.182672) (xy 123.044621 -231.20625)
			(xy 122.995228 -231.222298) (xy 122.943933 -231.230423) (xy 122.891999 -231.230423) (xy 122.840704 -231.222298)
			(xy 122.791311 -231.20625) (xy 122.745037 -231.182672) (xy 122.703021 -231.152146) (xy 122.666298 -231.115423)
			(xy 122.635772 -231.073407) (xy 122.612194 -231.027133) (xy 122.596146 -230.97774) (xy 122.588021 -230.926445)
			(xy 122.307857 -230.926445) (xy 122.299732 -230.97774) (xy 122.283684 -231.027133) (xy 122.260106 -231.073407)
			(xy 122.22958 -231.115423) (xy 122.192857 -231.152146) (xy 122.150841 -231.182672) (xy 122.104567 -231.20625)
			(xy 122.055174 -231.222298) (xy 122.003879 -231.230423) (xy 121.951945 -231.230423) (xy 121.90065 -231.222298)
			(xy 121.851257 -231.20625) (xy 121.804983 -231.182672) (xy 121.762967 -231.152146) (xy 121.726244 -231.115423)
			(xy 121.695718 -231.073407) (xy 121.67214 -231.027133) (xy 121.656092 -230.97774) (xy 121.647967 -230.926445)
			(xy 121.368311 -230.926445) (xy 121.360186 -230.97774) (xy 121.344138 -231.027133) (xy 121.32056 -231.073407)
			(xy 121.290034 -231.115423) (xy 121.253311 -231.152146) (xy 121.211295 -231.182672) (xy 121.165021 -231.20625)
			(xy 121.115628 -231.222298) (xy 121.064333 -231.230423) (xy 121.012399 -231.230423) (xy 120.961104 -231.222298)
			(xy 120.911711 -231.20625) (xy 120.865437 -231.182672) (xy 120.823421 -231.152146) (xy 120.786698 -231.115423)
			(xy 120.756172 -231.073407) (xy 120.732594 -231.027133) (xy 120.716546 -230.97774) (xy 120.708421 -230.926445)
			(xy 120.428511 -230.926445) (xy 120.420386 -230.97774) (xy 120.404338 -231.027133) (xy 120.38076 -231.073407)
			(xy 120.350234 -231.115423) (xy 120.313511 -231.152146) (xy 120.271495 -231.182672) (xy 120.225221 -231.20625)
			(xy 120.175828 -231.222298) (xy 120.124533 -231.230423) (xy 120.072599 -231.230423) (xy 120.021304 -231.222298)
			(xy 119.971911 -231.20625) (xy 119.925637 -231.182672) (xy 119.883621 -231.152146) (xy 119.846898 -231.115423)
			(xy 119.816372 -231.073407) (xy 119.792794 -231.027133) (xy 119.776746 -230.97774) (xy 119.768621 -230.926445)
			(xy 119.488711 -230.926445) (xy 119.480586 -230.97774) (xy 119.464538 -231.027133) (xy 119.44096 -231.073407)
			(xy 119.410434 -231.115423) (xy 119.373711 -231.152146) (xy 119.331695 -231.182672) (xy 119.285421 -231.20625)
			(xy 119.236028 -231.222298) (xy 119.184733 -231.230423) (xy 119.132799 -231.230423) (xy 119.081504 -231.222298)
			(xy 119.032111 -231.20625) (xy 118.985837 -231.182672) (xy 118.943821 -231.152146) (xy 118.907098 -231.115423)
			(xy 118.876572 -231.073407) (xy 118.852994 -231.027133) (xy 118.836946 -230.97774) (xy 118.828821 -230.926445)
			(xy 118.548911 -230.926445) (xy 118.540786 -230.97774) (xy 118.524738 -231.027133) (xy 118.50116 -231.073407)
			(xy 118.470634 -231.115423) (xy 118.433911 -231.152146) (xy 118.391895 -231.182672) (xy 118.345621 -231.20625)
			(xy 118.296228 -231.222298) (xy 118.244933 -231.230423) (xy 118.192999 -231.230423) (xy 118.141704 -231.222298)
			(xy 118.092311 -231.20625) (xy 118.046037 -231.182672) (xy 118.004021 -231.152146) (xy 117.967298 -231.115423)
			(xy 117.936772 -231.073407) (xy 117.913194 -231.027133) (xy 117.897146 -230.97774) (xy 117.889021 -230.926445)
			(xy 117.609111 -230.926445) (xy 117.600986 -230.97774) (xy 117.584938 -231.027133) (xy 117.56136 -231.073407)
			(xy 117.530834 -231.115423) (xy 117.494111 -231.152146) (xy 117.452095 -231.182672) (xy 117.405821 -231.20625)
			(xy 117.356428 -231.222298) (xy 117.305133 -231.230423) (xy 117.253199 -231.230423) (xy 117.201904 -231.222298)
			(xy 117.152511 -231.20625) (xy 117.106237 -231.182672) (xy 117.064221 -231.152146) (xy 117.027498 -231.115423)
			(xy 116.996972 -231.073407) (xy 116.973394 -231.027133) (xy 116.957346 -230.97774) (xy 116.949221 -230.926445)
			(xy 116.669311 -230.926445) (xy 116.661186 -230.97774) (xy 116.645138 -231.027133) (xy 116.62156 -231.073407)
			(xy 116.591034 -231.115423) (xy 116.554311 -231.152146) (xy 116.512295 -231.182672) (xy 116.466021 -231.20625)
			(xy 116.416628 -231.222298) (xy 116.365333 -231.230423) (xy 116.313399 -231.230423) (xy 116.262104 -231.222298)
			(xy 116.212711 -231.20625) (xy 116.166437 -231.182672) (xy 116.124421 -231.152146) (xy 116.087698 -231.115423)
			(xy 116.057172 -231.073407) (xy 116.033594 -231.027133) (xy 116.017546 -230.97774) (xy 116.009421 -230.926445)
			(xy 115.729511 -230.926445) (xy 115.721386 -230.97774) (xy 115.705338 -231.027133) (xy 115.68176 -231.073407)
			(xy 115.651234 -231.115423) (xy 115.614511 -231.152146) (xy 115.572495 -231.182672) (xy 115.526221 -231.20625)
			(xy 115.476828 -231.222298) (xy 115.425533 -231.230423) (xy 115.373599 -231.230423) (xy 115.322304 -231.222298)
			(xy 115.272911 -231.20625) (xy 115.226637 -231.182672) (xy 115.184621 -231.152146) (xy 115.147898 -231.115423)
			(xy 115.117372 -231.073407) (xy 115.093794 -231.027133) (xy 115.077746 -230.97774) (xy 115.069621 -230.926445)
			(xy 114.789965 -230.926445) (xy 114.78184 -230.97774) (xy 114.765792 -231.027133) (xy 114.742214 -231.073407)
			(xy 114.711688 -231.115423) (xy 114.674965 -231.152146) (xy 114.632949 -231.182672) (xy 114.586675 -231.20625)
			(xy 114.537282 -231.222298) (xy 114.485987 -231.230423) (xy 114.434053 -231.230423) (xy 114.382758 -231.222298)
			(xy 114.333365 -231.20625) (xy 114.287091 -231.182672) (xy 114.245075 -231.152146) (xy 114.208352 -231.115423)
			(xy 114.177826 -231.073407) (xy 114.154248 -231.027133) (xy 114.1382 -230.97774) (xy 114.130075 -230.926445)
			(xy 113.849911 -230.926445) (xy 113.841786 -230.97774) (xy 113.825738 -231.027133) (xy 113.80216 -231.073407)
			(xy 113.771634 -231.115423) (xy 113.734911 -231.152146) (xy 113.692895 -231.182672) (xy 113.646621 -231.20625)
			(xy 113.597228 -231.222298) (xy 113.545933 -231.230423) (xy 113.493999 -231.230423) (xy 113.442704 -231.222298)
			(xy 113.393311 -231.20625) (xy 113.347037 -231.182672) (xy 113.305021 -231.152146) (xy 113.268298 -231.115423)
			(xy 113.237772 -231.073407) (xy 113.214194 -231.027133) (xy 113.198146 -230.97774) (xy 113.190021 -230.926445)
			(xy 112.910111 -230.926445) (xy 112.901986 -230.97774) (xy 112.885938 -231.027133) (xy 112.86236 -231.073407)
			(xy 112.831834 -231.115423) (xy 112.795111 -231.152146) (xy 112.753095 -231.182672) (xy 112.706821 -231.20625)
			(xy 112.657428 -231.222298) (xy 112.606133 -231.230423) (xy 112.554199 -231.230423) (xy 112.502904 -231.222298)
			(xy 112.453511 -231.20625) (xy 112.407237 -231.182672) (xy 112.365221 -231.152146) (xy 112.328498 -231.115423)
			(xy 112.297972 -231.073407) (xy 112.274394 -231.027133) (xy 112.258346 -230.97774) (xy 112.250221 -230.926445)
			(xy 111.970311 -230.926445) (xy 111.962186 -230.97774) (xy 111.946138 -231.027133) (xy 111.92256 -231.073407)
			(xy 111.892034 -231.115423) (xy 111.855311 -231.152146) (xy 111.813295 -231.182672) (xy 111.767021 -231.20625)
			(xy 111.717628 -231.222298) (xy 111.666333 -231.230423) (xy 111.614399 -231.230423) (xy 111.563104 -231.222298)
			(xy 111.513711 -231.20625) (xy 111.467437 -231.182672) (xy 111.425421 -231.152146) (xy 111.388698 -231.115423)
			(xy 111.358172 -231.073407) (xy 111.334594 -231.027133) (xy 111.318546 -230.97774) (xy 111.310421 -230.926445)
			(xy 111.030511 -230.926445) (xy 111.022386 -230.97774) (xy 111.006338 -231.027133) (xy 110.98276 -231.073407)
			(xy 110.952234 -231.115423) (xy 110.915511 -231.152146) (xy 110.873495 -231.182672) (xy 110.827221 -231.20625)
			(xy 110.777828 -231.222298) (xy 110.726533 -231.230423) (xy 110.674599 -231.230423) (xy 110.623304 -231.222298)
			(xy 110.573911 -231.20625) (xy 110.527637 -231.182672) (xy 110.485621 -231.152146) (xy 110.448898 -231.115423)
			(xy 110.418372 -231.073407) (xy 110.394794 -231.027133) (xy 110.378746 -230.97774) (xy 110.370621 -230.926445)
			(xy 110.090467 -230.926445) (xy 110.090467 -230.926468) (xy 110.082342 -230.977766) (xy 110.066293 -231.02716)
			(xy 110.042715 -231.073437) (xy 110.012188 -231.115455) (xy 109.975464 -231.15218) (xy 109.933447 -231.182709)
			(xy 109.887172 -231.206289) (xy 109.837777 -231.222339) (xy 109.78648 -231.230466) (xy 109.760512 -231.230932)
			(xy 109.73394 -231.230384) (xy 109.681487 -231.221838) (xy 109.656118 -231.213914) (xy 109.646778 -231.211261)
			(xy 109.627413 -231.212418) (xy 109.609863 -231.220688) (xy 109.596642 -231.234885) (xy 109.589642 -231.252978)
			(xy 109.589316 -231.262682) (xy 109.589316 -231.48036) (xy 109.733116 -231.740515) (xy 109.900721 -231.740515)
			(xy 109.900721 -231.688581) (xy 109.908846 -231.637286) (xy 109.924894 -231.587893) (xy 109.948472 -231.541619)
			(xy 109.978998 -231.499603) (xy 110.015721 -231.46288) (xy 110.057737 -231.432354) (xy 110.104011 -231.408776)
			(xy 110.153404 -231.392728) (xy 110.204699 -231.384603) (xy 110.256633 -231.384603) (xy 110.307928 -231.392728)
			(xy 110.357321 -231.408776) (xy 110.403595 -231.432354) (xy 110.445611 -231.46288) (xy 110.482334 -231.499603)
			(xy 110.51286 -231.541619) (xy 110.536438 -231.587893) (xy 110.552486 -231.637286) (xy 110.560611 -231.688581)
			(xy 110.56112 -231.714548) (xy 110.560611 -231.740515) (xy 110.840267 -231.740515) (xy 110.840267 -231.688581)
			(xy 110.848392 -231.637286) (xy 110.86444 -231.587893) (xy 110.888018 -231.541619) (xy 110.918544 -231.499603)
			(xy 110.955267 -231.46288) (xy 110.997283 -231.432354) (xy 111.043557 -231.408776) (xy 111.09295 -231.392728)
			(xy 111.144245 -231.384603) (xy 111.196179 -231.384603) (xy 111.247474 -231.392728) (xy 111.296867 -231.408776)
			(xy 111.343141 -231.432354) (xy 111.385157 -231.46288) (xy 111.42188 -231.499603) (xy 111.452406 -231.541619)
			(xy 111.475984 -231.587893) (xy 111.492032 -231.637286) (xy 111.500157 -231.688581) (xy 111.500666 -231.714548)
			(xy 111.500157 -231.740515) (xy 111.780575 -231.740515) (xy 111.780575 -231.688581) (xy 111.7887 -231.637286)
			(xy 111.804748 -231.587893) (xy 111.828326 -231.541619) (xy 111.858852 -231.499603) (xy 111.895575 -231.46288)
			(xy 111.937591 -231.432354) (xy 111.983865 -231.408776) (xy 112.033258 -231.392728) (xy 112.084553 -231.384603)
			(xy 112.136487 -231.384603) (xy 112.187782 -231.392728) (xy 112.237175 -231.408776) (xy 112.283449 -231.432354)
			(xy 112.325465 -231.46288) (xy 112.362188 -231.499603) (xy 112.392714 -231.541619) (xy 112.416292 -231.587893)
			(xy 112.43234 -231.637286) (xy 112.440465 -231.688581) (xy 112.440974 -231.714548) (xy 112.440465 -231.740515)
			(xy 112.720375 -231.740515) (xy 112.720375 -231.688581) (xy 112.7285 -231.637286) (xy 112.744548 -231.587893)
			(xy 112.768126 -231.541619) (xy 112.798652 -231.499603) (xy 112.835375 -231.46288) (xy 112.877391 -231.432354)
			(xy 112.923665 -231.408776) (xy 112.973058 -231.392728) (xy 113.024353 -231.384603) (xy 113.076287 -231.384603)
			(xy 113.127582 -231.392728) (xy 113.176975 -231.408776) (xy 113.223249 -231.432354) (xy 113.265265 -231.46288)
			(xy 113.301988 -231.499603) (xy 113.332514 -231.541619) (xy 113.356092 -231.587893) (xy 113.37214 -231.637286)
			(xy 113.380265 -231.688581) (xy 113.380774 -231.714548) (xy 113.380265 -231.740515) (xy 113.660175 -231.740515)
			(xy 113.660175 -231.688581) (xy 113.6683 -231.637286) (xy 113.684348 -231.587893) (xy 113.707926 -231.541619)
			(xy 113.738452 -231.499603) (xy 113.775175 -231.46288) (xy 113.817191 -231.432354) (xy 113.863465 -231.408776)
			(xy 113.912858 -231.392728) (xy 113.964153 -231.384603) (xy 114.016087 -231.384603) (xy 114.067382 -231.392728)
			(xy 114.116775 -231.408776) (xy 114.163049 -231.432354) (xy 114.205065 -231.46288) (xy 114.241788 -231.499603)
			(xy 114.272314 -231.541619) (xy 114.295892 -231.587893) (xy 114.31194 -231.637286) (xy 114.320065 -231.688581)
			(xy 114.320574 -231.714548) (xy 114.320065 -231.740515) (xy 114.599467 -231.740515) (xy 114.599467 -231.688581)
			(xy 114.607592 -231.637286) (xy 114.62364 -231.587893) (xy 114.647218 -231.541619) (xy 114.677744 -231.499603)
			(xy 114.714467 -231.46288) (xy 114.756483 -231.432354) (xy 114.802757 -231.408776) (xy 114.85215 -231.392728)
			(xy 114.903445 -231.384603) (xy 114.955379 -231.384603) (xy 115.006674 -231.392728) (xy 115.056067 -231.408776)
			(xy 115.102341 -231.432354) (xy 115.144357 -231.46288) (xy 115.18108 -231.499603) (xy 115.211606 -231.541619)
			(xy 115.235184 -231.587893) (xy 115.251232 -231.637286) (xy 115.259357 -231.688581) (xy 115.259866 -231.714548)
			(xy 115.259357 -231.740515) (xy 115.539267 -231.740515) (xy 115.539267 -231.688581) (xy 115.547392 -231.637286)
			(xy 115.56344 -231.587893) (xy 115.587018 -231.541619) (xy 115.617544 -231.499603) (xy 115.654267 -231.46288)
			(xy 115.696283 -231.432354) (xy 115.742557 -231.408776) (xy 115.79195 -231.392728) (xy 115.843245 -231.384603)
			(xy 115.895179 -231.384603) (xy 115.946474 -231.392728) (xy 115.995867 -231.408776) (xy 116.042141 -231.432354)
			(xy 116.084157 -231.46288) (xy 116.12088 -231.499603) (xy 116.151406 -231.541619) (xy 116.174984 -231.587893)
			(xy 116.191032 -231.637286) (xy 116.199157 -231.688581) (xy 116.199666 -231.714548) (xy 116.199157 -231.740515)
			(xy 116.479067 -231.740515) (xy 116.479067 -231.688581) (xy 116.487192 -231.637286) (xy 116.50324 -231.587893)
			(xy 116.526818 -231.541619) (xy 116.557344 -231.499603) (xy 116.594067 -231.46288) (xy 116.636083 -231.432354)
			(xy 116.682357 -231.408776) (xy 116.73175 -231.392728) (xy 116.783045 -231.384603) (xy 116.834979 -231.384603)
			(xy 116.886274 -231.392728) (xy 116.935667 -231.408776) (xy 116.981941 -231.432354) (xy 117.023957 -231.46288)
			(xy 117.06068 -231.499603) (xy 117.091206 -231.541619) (xy 117.114784 -231.587893) (xy 117.130832 -231.637286)
			(xy 117.138957 -231.688581) (xy 117.139466 -231.714548) (xy 117.138957 -231.740515) (xy 117.418867 -231.740515)
			(xy 117.418867 -231.688581) (xy 117.426992 -231.637286) (xy 117.44304 -231.587893) (xy 117.466618 -231.541619)
			(xy 117.497144 -231.499603) (xy 117.533867 -231.46288) (xy 117.575883 -231.432354) (xy 117.622157 -231.408776)
			(xy 117.67155 -231.392728) (xy 117.722845 -231.384603) (xy 117.774779 -231.384603) (xy 117.826074 -231.392728)
			(xy 117.875467 -231.408776) (xy 117.921741 -231.432354) (xy 117.963757 -231.46288) (xy 118.00048 -231.499603)
			(xy 118.031006 -231.541619) (xy 118.054584 -231.587893) (xy 118.070632 -231.637286) (xy 118.078757 -231.688581)
			(xy 118.079266 -231.714548) (xy 118.078757 -231.740515) (xy 118.358667 -231.740515) (xy 118.358667 -231.688581)
			(xy 118.366792 -231.637286) (xy 118.38284 -231.587893) (xy 118.406418 -231.541619) (xy 118.436944 -231.499603)
			(xy 118.473667 -231.46288) (xy 118.515683 -231.432354) (xy 118.561957 -231.408776) (xy 118.61135 -231.392728)
			(xy 118.662645 -231.384603) (xy 118.714579 -231.384603) (xy 118.765874 -231.392728) (xy 118.815267 -231.408776)
			(xy 118.861541 -231.432354) (xy 118.903557 -231.46288) (xy 118.94028 -231.499603) (xy 118.970806 -231.541619)
			(xy 118.994384 -231.587893) (xy 119.010432 -231.637286) (xy 119.018557 -231.688581) (xy 119.019066 -231.714548)
			(xy 119.018557 -231.740515) (xy 119.298975 -231.740515) (xy 119.298975 -231.688581) (xy 119.3071 -231.637286)
			(xy 119.323148 -231.587893) (xy 119.346726 -231.541619) (xy 119.377252 -231.499603) (xy 119.413975 -231.46288)
			(xy 119.455991 -231.432354) (xy 119.502265 -231.408776) (xy 119.551658 -231.392728) (xy 119.602953 -231.384603)
			(xy 119.654887 -231.384603) (xy 119.706182 -231.392728) (xy 119.755575 -231.408776) (xy 119.801849 -231.432354)
			(xy 119.843865 -231.46288) (xy 119.880588 -231.499603) (xy 119.911114 -231.541619) (xy 119.934692 -231.587893)
			(xy 119.95074 -231.637286) (xy 119.958865 -231.688581) (xy 119.959374 -231.714548) (xy 119.958865 -231.740515)
			(xy 120.238267 -231.740515) (xy 120.238267 -231.688581) (xy 120.246392 -231.637286) (xy 120.26244 -231.587893)
			(xy 120.286018 -231.541619) (xy 120.316544 -231.499603) (xy 120.353267 -231.46288) (xy 120.395283 -231.432354)
			(xy 120.441557 -231.408776) (xy 120.49095 -231.392728) (xy 120.542245 -231.384603) (xy 120.594179 -231.384603)
			(xy 120.645474 -231.392728) (xy 120.694867 -231.408776) (xy 120.741141 -231.432354) (xy 120.783157 -231.46288)
			(xy 120.81988 -231.499603) (xy 120.850406 -231.541619) (xy 120.873984 -231.587893) (xy 120.890032 -231.637286)
			(xy 120.898157 -231.688581) (xy 120.898666 -231.714548) (xy 120.898157 -231.740515) (xy 121.178575 -231.740515)
			(xy 121.178575 -231.688581) (xy 121.1867 -231.637286) (xy 121.202748 -231.587893) (xy 121.226326 -231.541619)
			(xy 121.256852 -231.499603) (xy 121.293575 -231.46288) (xy 121.335591 -231.432354) (xy 121.381865 -231.408776)
			(xy 121.431258 -231.392728) (xy 121.482553 -231.384603) (xy 121.534487 -231.384603) (xy 121.585782 -231.392728)
			(xy 121.635175 -231.408776) (xy 121.681449 -231.432354) (xy 121.723465 -231.46288) (xy 121.760188 -231.499603)
			(xy 121.790714 -231.541619) (xy 121.814292 -231.587893) (xy 121.83034 -231.637286) (xy 121.838465 -231.688581)
			(xy 121.838974 -231.714548) (xy 121.838465 -231.740515) (xy 122.118121 -231.740515) (xy 122.118121 -231.688581)
			(xy 122.126246 -231.637286) (xy 122.142294 -231.587893) (xy 122.165872 -231.541619) (xy 122.196398 -231.499603)
			(xy 122.233121 -231.46288) (xy 122.275137 -231.432354) (xy 122.321411 -231.408776) (xy 122.370804 -231.392728)
			(xy 122.422099 -231.384603) (xy 122.474033 -231.384603) (xy 122.525328 -231.392728) (xy 122.574721 -231.408776)
			(xy 122.620995 -231.432354) (xy 122.663011 -231.46288) (xy 122.699734 -231.499603) (xy 122.73026 -231.541619)
			(xy 122.753838 -231.587893) (xy 122.769886 -231.637286) (xy 122.778011 -231.688581) (xy 122.77852 -231.714548)
			(xy 122.778011 -231.740515) (xy 123.057667 -231.740515) (xy 123.057667 -231.688581) (xy 123.065792 -231.637286)
			(xy 123.08184 -231.587893) (xy 123.105418 -231.541619) (xy 123.135944 -231.499603) (xy 123.172667 -231.46288)
			(xy 123.214683 -231.432354) (xy 123.260957 -231.408776) (xy 123.31035 -231.392728) (xy 123.361645 -231.384603)
			(xy 123.413579 -231.384603) (xy 123.464874 -231.392728) (xy 123.514267 -231.408776) (xy 123.560541 -231.432354)
			(xy 123.602557 -231.46288) (xy 123.63928 -231.499603) (xy 123.669806 -231.541619) (xy 123.693384 -231.587893)
			(xy 123.709432 -231.637286) (xy 123.717557 -231.688581) (xy 123.718066 -231.714548) (xy 123.717557 -231.740515)
			(xy 123.997467 -231.740515) (xy 123.997467 -231.688581) (xy 124.005592 -231.637286) (xy 124.02164 -231.587893)
			(xy 124.045218 -231.541619) (xy 124.075744 -231.499603) (xy 124.112467 -231.46288) (xy 124.154483 -231.432354)
			(xy 124.200757 -231.408776) (xy 124.25015 -231.392728) (xy 124.301445 -231.384603) (xy 124.353379 -231.384603)
			(xy 124.404674 -231.392728) (xy 124.454067 -231.408776) (xy 124.500341 -231.432354) (xy 124.542357 -231.46288)
			(xy 124.57908 -231.499603) (xy 124.609606 -231.541619) (xy 124.633184 -231.587893) (xy 124.649232 -231.637286)
			(xy 124.657357 -231.688581) (xy 124.657866 -231.714548) (xy 124.657357 -231.740515) (xy 124.937267 -231.740515)
			(xy 124.937267 -231.688581) (xy 124.945392 -231.637286) (xy 124.96144 -231.587893) (xy 124.985018 -231.541619)
			(xy 125.015544 -231.499603) (xy 125.052267 -231.46288) (xy 125.094283 -231.432354) (xy 125.140557 -231.408776)
			(xy 125.18995 -231.392728) (xy 125.241245 -231.384603) (xy 125.293179 -231.384603) (xy 125.344474 -231.392728)
			(xy 125.393867 -231.408776) (xy 125.440141 -231.432354) (xy 125.482157 -231.46288) (xy 125.51888 -231.499603)
			(xy 125.549406 -231.541619) (xy 125.572984 -231.587893) (xy 125.589032 -231.637286) (xy 125.597157 -231.688581)
			(xy 125.597666 -231.714548) (xy 125.597157 -231.740515) (xy 125.877067 -231.740515) (xy 125.877067 -231.688581)
			(xy 125.885192 -231.637286) (xy 125.90124 -231.587893) (xy 125.924818 -231.541619) (xy 125.955344 -231.499603)
			(xy 125.992067 -231.46288) (xy 126.034083 -231.432354) (xy 126.080357 -231.408776) (xy 126.12975 -231.392728)
			(xy 126.181045 -231.384603) (xy 126.232979 -231.384603) (xy 126.284274 -231.392728) (xy 126.333667 -231.408776)
			(xy 126.379941 -231.432354) (xy 126.421957 -231.46288) (xy 126.45868 -231.499603) (xy 126.489206 -231.541619)
			(xy 126.512784 -231.587893) (xy 126.528832 -231.637286) (xy 126.536957 -231.688581) (xy 126.537466 -231.714548)
			(xy 126.536957 -231.740515) (xy 126.816867 -231.740515) (xy 126.816867 -231.688581) (xy 126.824992 -231.637286)
			(xy 126.84104 -231.587893) (xy 126.864618 -231.541619) (xy 126.895144 -231.499603) (xy 126.931867 -231.46288)
			(xy 126.973883 -231.432354) (xy 127.020157 -231.408776) (xy 127.06955 -231.392728) (xy 127.120845 -231.384603)
			(xy 127.172779 -231.384603) (xy 127.224074 -231.392728) (xy 127.273467 -231.408776) (xy 127.319741 -231.432354)
			(xy 127.361757 -231.46288) (xy 127.39848 -231.499603) (xy 127.429006 -231.541619) (xy 127.452584 -231.587893)
			(xy 127.468632 -231.637286) (xy 127.476757 -231.688581) (xy 127.477266 -231.714548) (xy 127.476757 -231.740515)
			(xy 127.468632 -231.79181) (xy 127.452584 -231.841203) (xy 127.429006 -231.887477) (xy 127.39848 -231.929493)
			(xy 127.361757 -231.966216) (xy 127.319741 -231.996742) (xy 127.273467 -232.02032) (xy 127.224074 -232.036368)
			(xy 127.172779 -232.044493) (xy 127.120845 -232.044493) (xy 127.06955 -232.036368) (xy 127.020157 -232.02032)
			(xy 126.973883 -231.996742) (xy 126.931867 -231.966216) (xy 126.895144 -231.929493) (xy 126.864618 -231.887477)
			(xy 126.84104 -231.841203) (xy 126.824992 -231.79181) (xy 126.816867 -231.740515) (xy 126.536957 -231.740515)
			(xy 126.528832 -231.79181) (xy 126.512784 -231.841203) (xy 126.489206 -231.887477) (xy 126.45868 -231.929493)
			(xy 126.421957 -231.966216) (xy 126.379941 -231.996742) (xy 126.333667 -232.02032) (xy 126.284274 -232.036368)
			(xy 126.232979 -232.044493) (xy 126.181045 -232.044493) (xy 126.12975 -232.036368) (xy 126.080357 -232.02032)
			(xy 126.034083 -231.996742) (xy 125.992067 -231.966216) (xy 125.955344 -231.929493) (xy 125.924818 -231.887477)
			(xy 125.90124 -231.841203) (xy 125.885192 -231.79181) (xy 125.877067 -231.740515) (xy 125.597157 -231.740515)
			(xy 125.589032 -231.79181) (xy 125.572984 -231.841203) (xy 125.549406 -231.887477) (xy 125.51888 -231.929493)
			(xy 125.482157 -231.966216) (xy 125.440141 -231.996742) (xy 125.393867 -232.02032) (xy 125.344474 -232.036368)
			(xy 125.293179 -232.044493) (xy 125.241245 -232.044493) (xy 125.18995 -232.036368) (xy 125.140557 -232.02032)
			(xy 125.094283 -231.996742) (xy 125.052267 -231.966216) (xy 125.015544 -231.929493) (xy 124.985018 -231.887477)
			(xy 124.96144 -231.841203) (xy 124.945392 -231.79181) (xy 124.937267 -231.740515) (xy 124.657357 -231.740515)
			(xy 124.649232 -231.79181) (xy 124.633184 -231.841203) (xy 124.609606 -231.887477) (xy 124.57908 -231.929493)
			(xy 124.542357 -231.966216) (xy 124.500341 -231.996742) (xy 124.454067 -232.02032) (xy 124.404674 -232.036368)
			(xy 124.353379 -232.044493) (xy 124.301445 -232.044493) (xy 124.25015 -232.036368) (xy 124.200757 -232.02032)
			(xy 124.154483 -231.996742) (xy 124.112467 -231.966216) (xy 124.075744 -231.929493) (xy 124.045218 -231.887477)
			(xy 124.02164 -231.841203) (xy 124.005592 -231.79181) (xy 123.997467 -231.740515) (xy 123.717557 -231.740515)
			(xy 123.709432 -231.79181) (xy 123.693384 -231.841203) (xy 123.669806 -231.887477) (xy 123.63928 -231.929493)
			(xy 123.602557 -231.966216) (xy 123.560541 -231.996742) (xy 123.514267 -232.02032) (xy 123.464874 -232.036368)
			(xy 123.413579 -232.044493) (xy 123.361645 -232.044493) (xy 123.31035 -232.036368) (xy 123.260957 -232.02032)
			(xy 123.214683 -231.996742) (xy 123.172667 -231.966216) (xy 123.135944 -231.929493) (xy 123.105418 -231.887477)
			(xy 123.08184 -231.841203) (xy 123.065792 -231.79181) (xy 123.057667 -231.740515) (xy 122.778011 -231.740515)
			(xy 122.769886 -231.79181) (xy 122.753838 -231.841203) (xy 122.73026 -231.887477) (xy 122.699734 -231.929493)
			(xy 122.663011 -231.966216) (xy 122.620995 -231.996742) (xy 122.574721 -232.02032) (xy 122.525328 -232.036368)
			(xy 122.474033 -232.044493) (xy 122.422099 -232.044493) (xy 122.370804 -232.036368) (xy 122.321411 -232.02032)
			(xy 122.275137 -231.996742) (xy 122.233121 -231.966216) (xy 122.196398 -231.929493) (xy 122.165872 -231.887477)
			(xy 122.142294 -231.841203) (xy 122.126246 -231.79181) (xy 122.118121 -231.740515) (xy 121.838465 -231.740515)
			(xy 121.83034 -231.79181) (xy 121.814292 -231.841203) (xy 121.790714 -231.887477) (xy 121.760188 -231.929493)
			(xy 121.723465 -231.966216) (xy 121.681449 -231.996742) (xy 121.635175 -232.02032) (xy 121.585782 -232.036368)
			(xy 121.534487 -232.044493) (xy 121.482553 -232.044493) (xy 121.431258 -232.036368) (xy 121.381865 -232.02032)
			(xy 121.335591 -231.996742) (xy 121.293575 -231.966216) (xy 121.256852 -231.929493) (xy 121.226326 -231.887477)
			(xy 121.202748 -231.841203) (xy 121.1867 -231.79181) (xy 121.178575 -231.740515) (xy 120.898157 -231.740515)
			(xy 120.890032 -231.79181) (xy 120.873984 -231.841203) (xy 120.850406 -231.887477) (xy 120.81988 -231.929493)
			(xy 120.783157 -231.966216) (xy 120.741141 -231.996742) (xy 120.694867 -232.02032) (xy 120.645474 -232.036368)
			(xy 120.594179 -232.044493) (xy 120.542245 -232.044493) (xy 120.49095 -232.036368) (xy 120.441557 -232.02032)
			(xy 120.395283 -231.996742) (xy 120.353267 -231.966216) (xy 120.316544 -231.929493) (xy 120.286018 -231.887477)
			(xy 120.26244 -231.841203) (xy 120.246392 -231.79181) (xy 120.238267 -231.740515) (xy 119.958865 -231.740515)
			(xy 119.95074 -231.79181) (xy 119.934692 -231.841203) (xy 119.911114 -231.887477) (xy 119.880588 -231.929493)
			(xy 119.843865 -231.966216) (xy 119.801849 -231.996742) (xy 119.755575 -232.02032) (xy 119.706182 -232.036368)
			(xy 119.654887 -232.044493) (xy 119.602953 -232.044493) (xy 119.551658 -232.036368) (xy 119.502265 -232.02032)
			(xy 119.455991 -231.996742) (xy 119.413975 -231.966216) (xy 119.377252 -231.929493) (xy 119.346726 -231.887477)
			(xy 119.323148 -231.841203) (xy 119.3071 -231.79181) (xy 119.298975 -231.740515) (xy 119.018557 -231.740515)
			(xy 119.010432 -231.79181) (xy 118.994384 -231.841203) (xy 118.970806 -231.887477) (xy 118.94028 -231.929493)
			(xy 118.903557 -231.966216) (xy 118.861541 -231.996742) (xy 118.815267 -232.02032) (xy 118.765874 -232.036368)
			(xy 118.714579 -232.044493) (xy 118.662645 -232.044493) (xy 118.61135 -232.036368) (xy 118.561957 -232.02032)
			(xy 118.515683 -231.996742) (xy 118.473667 -231.966216) (xy 118.436944 -231.929493) (xy 118.406418 -231.887477)
			(xy 118.38284 -231.841203) (xy 118.366792 -231.79181) (xy 118.358667 -231.740515) (xy 118.078757 -231.740515)
			(xy 118.070632 -231.79181) (xy 118.054584 -231.841203) (xy 118.031006 -231.887477) (xy 118.00048 -231.929493)
			(xy 117.963757 -231.966216) (xy 117.921741 -231.996742) (xy 117.875467 -232.02032) (xy 117.826074 -232.036368)
			(xy 117.774779 -232.044493) (xy 117.722845 -232.044493) (xy 117.67155 -232.036368) (xy 117.622157 -232.02032)
			(xy 117.575883 -231.996742) (xy 117.533867 -231.966216) (xy 117.497144 -231.929493) (xy 117.466618 -231.887477)
			(xy 117.44304 -231.841203) (xy 117.426992 -231.79181) (xy 117.418867 -231.740515) (xy 117.138957 -231.740515)
			(xy 117.130832 -231.79181) (xy 117.114784 -231.841203) (xy 117.091206 -231.887477) (xy 117.06068 -231.929493)
			(xy 117.023957 -231.966216) (xy 116.981941 -231.996742) (xy 116.935667 -232.02032) (xy 116.886274 -232.036368)
			(xy 116.834979 -232.044493) (xy 116.783045 -232.044493) (xy 116.73175 -232.036368) (xy 116.682357 -232.02032)
			(xy 116.636083 -231.996742) (xy 116.594067 -231.966216) (xy 116.557344 -231.929493) (xy 116.526818 -231.887477)
			(xy 116.50324 -231.841203) (xy 116.487192 -231.79181) (xy 116.479067 -231.740515) (xy 116.199157 -231.740515)
			(xy 116.191032 -231.79181) (xy 116.174984 -231.841203) (xy 116.151406 -231.887477) (xy 116.12088 -231.929493)
			(xy 116.084157 -231.966216) (xy 116.042141 -231.996742) (xy 115.995867 -232.02032) (xy 115.946474 -232.036368)
			(xy 115.895179 -232.044493) (xy 115.843245 -232.044493) (xy 115.79195 -232.036368) (xy 115.742557 -232.02032)
			(xy 115.696283 -231.996742) (xy 115.654267 -231.966216) (xy 115.617544 -231.929493) (xy 115.587018 -231.887477)
			(xy 115.56344 -231.841203) (xy 115.547392 -231.79181) (xy 115.539267 -231.740515) (xy 115.259357 -231.740515)
			(xy 115.251232 -231.79181) (xy 115.235184 -231.841203) (xy 115.211606 -231.887477) (xy 115.18108 -231.929493)
			(xy 115.144357 -231.966216) (xy 115.102341 -231.996742) (xy 115.056067 -232.02032) (xy 115.006674 -232.036368)
			(xy 114.955379 -232.044493) (xy 114.903445 -232.044493) (xy 114.85215 -232.036368) (xy 114.802757 -232.02032)
			(xy 114.756483 -231.996742) (xy 114.714467 -231.966216) (xy 114.677744 -231.929493) (xy 114.647218 -231.887477)
			(xy 114.62364 -231.841203) (xy 114.607592 -231.79181) (xy 114.599467 -231.740515) (xy 114.320065 -231.740515)
			(xy 114.31194 -231.79181) (xy 114.295892 -231.841203) (xy 114.272314 -231.887477) (xy 114.241788 -231.929493)
			(xy 114.205065 -231.966216) (xy 114.163049 -231.996742) (xy 114.116775 -232.02032) (xy 114.067382 -232.036368)
			(xy 114.016087 -232.044493) (xy 113.964153 -232.044493) (xy 113.912858 -232.036368) (xy 113.863465 -232.02032)
			(xy 113.817191 -231.996742) (xy 113.775175 -231.966216) (xy 113.738452 -231.929493) (xy 113.707926 -231.887477)
			(xy 113.684348 -231.841203) (xy 113.6683 -231.79181) (xy 113.660175 -231.740515) (xy 113.380265 -231.740515)
			(xy 113.37214 -231.79181) (xy 113.356092 -231.841203) (xy 113.332514 -231.887477) (xy 113.301988 -231.929493)
			(xy 113.265265 -231.966216) (xy 113.223249 -231.996742) (xy 113.176975 -232.02032) (xy 113.127582 -232.036368)
			(xy 113.076287 -232.044493) (xy 113.024353 -232.044493) (xy 112.973058 -232.036368) (xy 112.923665 -232.02032)
			(xy 112.877391 -231.996742) (xy 112.835375 -231.966216) (xy 112.798652 -231.929493) (xy 112.768126 -231.887477)
			(xy 112.744548 -231.841203) (xy 112.7285 -231.79181) (xy 112.720375 -231.740515) (xy 112.440465 -231.740515)
			(xy 112.43234 -231.79181) (xy 112.416292 -231.841203) (xy 112.392714 -231.887477) (xy 112.362188 -231.929493)
			(xy 112.325465 -231.966216) (xy 112.283449 -231.996742) (xy 112.237175 -232.02032) (xy 112.187782 -232.036368)
			(xy 112.136487 -232.044493) (xy 112.084553 -232.044493) (xy 112.033258 -232.036368) (xy 111.983865 -232.02032)
			(xy 111.937591 -231.996742) (xy 111.895575 -231.966216) (xy 111.858852 -231.929493) (xy 111.828326 -231.887477)
			(xy 111.804748 -231.841203) (xy 111.7887 -231.79181) (xy 111.780575 -231.740515) (xy 111.500157 -231.740515)
			(xy 111.492032 -231.79181) (xy 111.475984 -231.841203) (xy 111.452406 -231.887477) (xy 111.42188 -231.929493)
			(xy 111.385157 -231.966216) (xy 111.343141 -231.996742) (xy 111.296867 -232.02032) (xy 111.247474 -232.036368)
			(xy 111.196179 -232.044493) (xy 111.144245 -232.044493) (xy 111.09295 -232.036368) (xy 111.043557 -232.02032)
			(xy 110.997283 -231.996742) (xy 110.955267 -231.966216) (xy 110.918544 -231.929493) (xy 110.888018 -231.887477)
			(xy 110.86444 -231.841203) (xy 110.848392 -231.79181) (xy 110.840267 -231.740515) (xy 110.560611 -231.740515)
			(xy 110.552486 -231.79181) (xy 110.536438 -231.841203) (xy 110.51286 -231.887477) (xy 110.482334 -231.929493)
			(xy 110.445611 -231.966216) (xy 110.403595 -231.996742) (xy 110.357321 -232.02032) (xy 110.307928 -232.036368)
			(xy 110.256633 -232.044493) (xy 110.204699 -232.044493) (xy 110.153404 -232.036368) (xy 110.104011 -232.02032)
			(xy 110.057737 -231.996742) (xy 110.015721 -231.966216) (xy 109.978998 -231.929493) (xy 109.948472 -231.887477)
			(xy 109.924894 -231.841203) (xy 109.908846 -231.79181) (xy 109.900721 -231.740515) (xy 109.733116 -231.740515)
			(xy 110.182952 -232.554331) (xy 110.370621 -232.554331) (xy 110.370621 -232.502397) (xy 110.378746 -232.451102)
			(xy 110.394794 -232.401709) (xy 110.418372 -232.355435) (xy 110.448898 -232.313419) (xy 110.485621 -232.276696)
			(xy 110.527637 -232.24617) (xy 110.573911 -232.222592) (xy 110.623304 -232.206544) (xy 110.674599 -232.198419)
			(xy 110.726533 -232.198419) (xy 110.777828 -232.206544) (xy 110.827221 -232.222592) (xy 110.873495 -232.24617)
			(xy 110.915511 -232.276696) (xy 110.952234 -232.313419) (xy 110.98276 -232.355435) (xy 111.006338 -232.401709)
			(xy 111.022386 -232.451102) (xy 111.030511 -232.502397) (xy 111.03102 -232.528364) (xy 111.030511 -232.554331)
			(xy 111.310421 -232.554331) (xy 111.310421 -232.502397) (xy 111.318546 -232.451102) (xy 111.334594 -232.401709)
			(xy 111.358172 -232.355435) (xy 111.388698 -232.313419) (xy 111.425421 -232.276696) (xy 111.467437 -232.24617)
			(xy 111.513711 -232.222592) (xy 111.563104 -232.206544) (xy 111.614399 -232.198419) (xy 111.666333 -232.198419)
			(xy 111.717628 -232.206544) (xy 111.767021 -232.222592) (xy 111.813295 -232.24617) (xy 111.855311 -232.276696)
			(xy 111.892034 -232.313419) (xy 111.92256 -232.355435) (xy 111.946138 -232.401709) (xy 111.962186 -232.451102)
			(xy 111.970311 -232.502397) (xy 111.97082 -232.528364) (xy 111.970311 -232.554331) (xy 112.250221 -232.554331)
			(xy 112.250221 -232.502397) (xy 112.258346 -232.451102) (xy 112.274394 -232.401709) (xy 112.297972 -232.355435)
			(xy 112.328498 -232.313419) (xy 112.365221 -232.276696) (xy 112.407237 -232.24617) (xy 112.453511 -232.222592)
			(xy 112.502904 -232.206544) (xy 112.554199 -232.198419) (xy 112.606133 -232.198419) (xy 112.657428 -232.206544)
			(xy 112.706821 -232.222592) (xy 112.753095 -232.24617) (xy 112.795111 -232.276696) (xy 112.831834 -232.313419)
			(xy 112.86236 -232.355435) (xy 112.885938 -232.401709) (xy 112.901986 -232.451102) (xy 112.910111 -232.502397)
			(xy 112.91062 -232.528364) (xy 112.910111 -232.554331) (xy 113.190021 -232.554331) (xy 113.190021 -232.502397)
			(xy 113.198146 -232.451102) (xy 113.214194 -232.401709) (xy 113.237772 -232.355435) (xy 113.268298 -232.313419)
			(xy 113.305021 -232.276696) (xy 113.347037 -232.24617) (xy 113.393311 -232.222592) (xy 113.442704 -232.206544)
			(xy 113.493999 -232.198419) (xy 113.545933 -232.198419) (xy 113.597228 -232.206544) (xy 113.646621 -232.222592)
			(xy 113.692895 -232.24617) (xy 113.734911 -232.276696) (xy 113.771634 -232.313419) (xy 113.80216 -232.355435)
			(xy 113.825738 -232.401709) (xy 113.841786 -232.451102) (xy 113.849911 -232.502397) (xy 113.85042 -232.528364)
			(xy 113.849911 -232.554331) (xy 114.129821 -232.554331) (xy 114.129821 -232.502397) (xy 114.137946 -232.451102)
			(xy 114.153994 -232.401709) (xy 114.177572 -232.355435) (xy 114.208098 -232.313419) (xy 114.244821 -232.276696)
			(xy 114.286837 -232.24617) (xy 114.333111 -232.222592) (xy 114.382504 -232.206544) (xy 114.433799 -232.198419)
			(xy 114.485733 -232.198419) (xy 114.537028 -232.206544) (xy 114.586421 -232.222592) (xy 114.632695 -232.24617)
			(xy 114.674711 -232.276696) (xy 114.711434 -232.313419) (xy 114.74196 -232.355435) (xy 114.765538 -232.401709)
			(xy 114.781586 -232.451102) (xy 114.789711 -232.502397) (xy 114.79022 -232.528364) (xy 114.789711 -232.554331)
			(xy 115.069621 -232.554331) (xy 115.069621 -232.502397) (xy 115.077746 -232.451102) (xy 115.093794 -232.401709)
			(xy 115.117372 -232.355435) (xy 115.147898 -232.313419) (xy 115.184621 -232.276696) (xy 115.226637 -232.24617)
			(xy 115.272911 -232.222592) (xy 115.322304 -232.206544) (xy 115.373599 -232.198419) (xy 115.425533 -232.198419)
			(xy 115.476828 -232.206544) (xy 115.526221 -232.222592) (xy 115.572495 -232.24617) (xy 115.614511 -232.276696)
			(xy 115.651234 -232.313419) (xy 115.68176 -232.355435) (xy 115.705338 -232.401709) (xy 115.721386 -232.451102)
			(xy 115.729511 -232.502397) (xy 115.73002 -232.528364) (xy 115.729511 -232.554331) (xy 116.009421 -232.554331)
			(xy 116.009421 -232.502397) (xy 116.017546 -232.451102) (xy 116.033594 -232.401709) (xy 116.057172 -232.355435)
			(xy 116.087698 -232.313419) (xy 116.124421 -232.276696) (xy 116.166437 -232.24617) (xy 116.212711 -232.222592)
			(xy 116.262104 -232.206544) (xy 116.313399 -232.198419) (xy 116.365333 -232.198419) (xy 116.416628 -232.206544)
			(xy 116.466021 -232.222592) (xy 116.512295 -232.24617) (xy 116.554311 -232.276696) (xy 116.591034 -232.313419)
			(xy 116.62156 -232.355435) (xy 116.645138 -232.401709) (xy 116.661186 -232.451102) (xy 116.669311 -232.502397)
			(xy 116.66982 -232.528364) (xy 116.669311 -232.554331) (xy 116.949221 -232.554331) (xy 116.949221 -232.502397)
			(xy 116.957346 -232.451102) (xy 116.973394 -232.401709) (xy 116.996972 -232.355435) (xy 117.027498 -232.313419)
			(xy 117.064221 -232.276696) (xy 117.106237 -232.24617) (xy 117.152511 -232.222592) (xy 117.201904 -232.206544)
			(xy 117.253199 -232.198419) (xy 117.305133 -232.198419) (xy 117.356428 -232.206544) (xy 117.405821 -232.222592)
			(xy 117.452095 -232.24617) (xy 117.494111 -232.276696) (xy 117.530834 -232.313419) (xy 117.56136 -232.355435)
			(xy 117.584938 -232.401709) (xy 117.600986 -232.451102) (xy 117.609111 -232.502397) (xy 117.60962 -232.528364)
			(xy 117.609111 -232.554331) (xy 117.889021 -232.554331) (xy 117.889021 -232.502397) (xy 117.897146 -232.451102)
			(xy 117.913194 -232.401709) (xy 117.936772 -232.355435) (xy 117.967298 -232.313419) (xy 118.004021 -232.276696)
			(xy 118.046037 -232.24617) (xy 118.092311 -232.222592) (xy 118.141704 -232.206544) (xy 118.192999 -232.198419)
			(xy 118.244933 -232.198419) (xy 118.296228 -232.206544) (xy 118.345621 -232.222592) (xy 118.391895 -232.24617)
			(xy 118.433911 -232.276696) (xy 118.470634 -232.313419) (xy 118.50116 -232.355435) (xy 118.524738 -232.401709)
			(xy 118.540786 -232.451102) (xy 118.548911 -232.502397) (xy 118.54942 -232.528364) (xy 118.548911 -232.554331)
			(xy 118.828821 -232.554331) (xy 118.828821 -232.502397) (xy 118.836946 -232.451102) (xy 118.852994 -232.401709)
			(xy 118.876572 -232.355435) (xy 118.907098 -232.313419) (xy 118.943821 -232.276696) (xy 118.985837 -232.24617)
			(xy 119.032111 -232.222592) (xy 119.081504 -232.206544) (xy 119.132799 -232.198419) (xy 119.184733 -232.198419)
			(xy 119.236028 -232.206544) (xy 119.285421 -232.222592) (xy 119.331695 -232.24617) (xy 119.373711 -232.276696)
			(xy 119.410434 -232.313419) (xy 119.44096 -232.355435) (xy 119.464538 -232.401709) (xy 119.480586 -232.451102)
			(xy 119.488711 -232.502397) (xy 119.48922 -232.528364) (xy 119.488711 -232.554331) (xy 119.768367 -232.554331)
			(xy 119.768367 -232.502397) (xy 119.776492 -232.451102) (xy 119.79254 -232.401709) (xy 119.816118 -232.355435)
			(xy 119.846644 -232.313419) (xy 119.883367 -232.276696) (xy 119.925383 -232.24617) (xy 119.971657 -232.222592)
			(xy 120.02105 -232.206544) (xy 120.072345 -232.198419) (xy 120.124279 -232.198419) (xy 120.175574 -232.206544)
			(xy 120.224967 -232.222592) (xy 120.271241 -232.24617) (xy 120.313257 -232.276696) (xy 120.34998 -232.313419)
			(xy 120.380506 -232.355435) (xy 120.404084 -232.401709) (xy 120.420132 -232.451102) (xy 120.428257 -232.502397)
			(xy 120.428766 -232.528364) (xy 120.428257 -232.554331) (xy 120.708421 -232.554331) (xy 120.708421 -232.502397)
			(xy 120.716546 -232.451102) (xy 120.732594 -232.401709) (xy 120.756172 -232.355435) (xy 120.786698 -232.313419)
			(xy 120.823421 -232.276696) (xy 120.865437 -232.24617) (xy 120.911711 -232.222592) (xy 120.961104 -232.206544)
			(xy 121.012399 -232.198419) (xy 121.064333 -232.198419) (xy 121.115628 -232.206544) (xy 121.165021 -232.222592)
			(xy 121.211295 -232.24617) (xy 121.253311 -232.276696) (xy 121.290034 -232.313419) (xy 121.32056 -232.355435)
			(xy 121.344138 -232.401709) (xy 121.360186 -232.451102) (xy 121.368311 -232.502397) (xy 121.36882 -232.528364)
			(xy 121.368311 -232.554331) (xy 121.648221 -232.554331) (xy 121.648221 -232.502397) (xy 121.656346 -232.451102)
			(xy 121.672394 -232.401709) (xy 121.695972 -232.355435) (xy 121.726498 -232.313419) (xy 121.763221 -232.276696)
			(xy 121.805237 -232.24617) (xy 121.851511 -232.222592) (xy 121.900904 -232.206544) (xy 121.952199 -232.198419)
			(xy 122.004133 -232.198419) (xy 122.055428 -232.206544) (xy 122.104821 -232.222592) (xy 122.151095 -232.24617)
			(xy 122.193111 -232.276696) (xy 122.229834 -232.313419) (xy 122.26036 -232.355435) (xy 122.283938 -232.401709)
			(xy 122.299986 -232.451102) (xy 122.308111 -232.502397) (xy 122.30862 -232.528364) (xy 122.308111 -232.554331)
			(xy 122.588021 -232.554331) (xy 122.588021 -232.502397) (xy 122.596146 -232.451102) (xy 122.612194 -232.401709)
			(xy 122.635772 -232.355435) (xy 122.666298 -232.313419) (xy 122.703021 -232.276696) (xy 122.745037 -232.24617)
			(xy 122.791311 -232.222592) (xy 122.840704 -232.206544) (xy 122.891999 -232.198419) (xy 122.943933 -232.198419)
			(xy 122.995228 -232.206544) (xy 123.044621 -232.222592) (xy 123.090895 -232.24617) (xy 123.132911 -232.276696)
			(xy 123.169634 -232.313419) (xy 123.20016 -232.355435) (xy 123.223738 -232.401709) (xy 123.239786 -232.451102)
			(xy 123.247911 -232.502397) (xy 123.24842 -232.528364) (xy 123.247911 -232.554331) (xy 123.527821 -232.554331)
			(xy 123.527821 -232.502397) (xy 123.535946 -232.451102) (xy 123.551994 -232.401709) (xy 123.575572 -232.355435)
			(xy 123.606098 -232.313419) (xy 123.642821 -232.276696) (xy 123.684837 -232.24617) (xy 123.731111 -232.222592)
			(xy 123.780504 -232.206544) (xy 123.831799 -232.198419) (xy 123.883733 -232.198419) (xy 123.935028 -232.206544)
			(xy 123.984421 -232.222592) (xy 124.030695 -232.24617) (xy 124.072711 -232.276696) (xy 124.109434 -232.313419)
			(xy 124.13996 -232.355435) (xy 124.163538 -232.401709) (xy 124.179586 -232.451102) (xy 124.187711 -232.502397)
			(xy 124.18822 -232.528364) (xy 124.187711 -232.554331) (xy 124.467621 -232.554331) (xy 124.467621 -232.502397)
			(xy 124.475746 -232.451102) (xy 124.491794 -232.401709) (xy 124.515372 -232.355435) (xy 124.545898 -232.313419)
			(xy 124.582621 -232.276696) (xy 124.624637 -232.24617) (xy 124.670911 -232.222592) (xy 124.720304 -232.206544)
			(xy 124.771599 -232.198419) (xy 124.823533 -232.198419) (xy 124.874828 -232.206544) (xy 124.924221 -232.222592)
			(xy 124.970495 -232.24617) (xy 125.012511 -232.276696) (xy 125.049234 -232.313419) (xy 125.07976 -232.355435)
			(xy 125.103338 -232.401709) (xy 125.119386 -232.451102) (xy 125.127511 -232.502397) (xy 125.12802 -232.528364)
			(xy 125.127511 -232.554331) (xy 125.407421 -232.554331) (xy 125.407421 -232.502397) (xy 125.415546 -232.451102)
			(xy 125.431594 -232.401709) (xy 125.455172 -232.355435) (xy 125.485698 -232.313419) (xy 125.522421 -232.276696)
			(xy 125.564437 -232.24617) (xy 125.610711 -232.222592) (xy 125.660104 -232.206544) (xy 125.711399 -232.198419)
			(xy 125.763333 -232.198419) (xy 125.814628 -232.206544) (xy 125.864021 -232.222592) (xy 125.910295 -232.24617)
			(xy 125.952311 -232.276696) (xy 125.989034 -232.313419) (xy 126.01956 -232.355435) (xy 126.043138 -232.401709)
			(xy 126.059186 -232.451102) (xy 126.067311 -232.502397) (xy 126.06782 -232.528364) (xy 126.067311 -232.554331)
			(xy 126.346967 -232.554331) (xy 126.346967 -232.502397) (xy 126.355092 -232.451102) (xy 126.37114 -232.401709)
			(xy 126.394718 -232.355435) (xy 126.425244 -232.313419) (xy 126.461967 -232.276696) (xy 126.503983 -232.24617)
			(xy 126.550257 -232.222592) (xy 126.59965 -232.206544) (xy 126.650945 -232.198419) (xy 126.702879 -232.198419)
			(xy 126.754174 -232.206544) (xy 126.803567 -232.222592) (xy 126.849841 -232.24617) (xy 126.891857 -232.276696)
			(xy 126.92858 -232.313419) (xy 126.959106 -232.355435) (xy 126.982684 -232.401709) (xy 126.998732 -232.451102)
			(xy 127.006857 -232.502397) (xy 127.007366 -232.528364) (xy 127.006857 -232.554331) (xy 126.998732 -232.605626)
			(xy 126.982684 -232.655019) (xy 126.959106 -232.701293) (xy 126.92858 -232.743309) (xy 126.891857 -232.780032)
			(xy 126.849841 -232.810558) (xy 126.803567 -232.834136) (xy 126.754174 -232.850184) (xy 126.702879 -232.858309)
			(xy 126.650945 -232.858309) (xy 126.59965 -232.850184) (xy 126.550257 -232.834136) (xy 126.503983 -232.810558)
			(xy 126.461967 -232.780032) (xy 126.425244 -232.743309) (xy 126.394718 -232.701293) (xy 126.37114 -232.655019)
			(xy 126.355092 -232.605626) (xy 126.346967 -232.554331) (xy 126.067311 -232.554331) (xy 126.059186 -232.605626)
			(xy 126.043138 -232.655019) (xy 126.01956 -232.701293) (xy 125.989034 -232.743309) (xy 125.952311 -232.780032)
			(xy 125.910295 -232.810558) (xy 125.864021 -232.834136) (xy 125.814628 -232.850184) (xy 125.763333 -232.858309)
			(xy 125.711399 -232.858309) (xy 125.660104 -232.850184) (xy 125.610711 -232.834136) (xy 125.564437 -232.810558)
			(xy 125.522421 -232.780032) (xy 125.485698 -232.743309) (xy 125.455172 -232.701293) (xy 125.431594 -232.655019)
			(xy 125.415546 -232.605626) (xy 125.407421 -232.554331) (xy 125.127511 -232.554331) (xy 125.119386 -232.605626)
			(xy 125.103338 -232.655019) (xy 125.07976 -232.701293) (xy 125.049234 -232.743309) (xy 125.012511 -232.780032)
			(xy 124.970495 -232.810558) (xy 124.924221 -232.834136) (xy 124.874828 -232.850184) (xy 124.823533 -232.858309)
			(xy 124.771599 -232.858309) (xy 124.720304 -232.850184) (xy 124.670911 -232.834136) (xy 124.624637 -232.810558)
			(xy 124.582621 -232.780032) (xy 124.545898 -232.743309) (xy 124.515372 -232.701293) (xy 124.491794 -232.655019)
			(xy 124.475746 -232.605626) (xy 124.467621 -232.554331) (xy 124.187711 -232.554331) (xy 124.179586 -232.605626)
			(xy 124.163538 -232.655019) (xy 124.13996 -232.701293) (xy 124.109434 -232.743309) (xy 124.072711 -232.780032)
			(xy 124.030695 -232.810558) (xy 123.984421 -232.834136) (xy 123.935028 -232.850184) (xy 123.883733 -232.858309)
			(xy 123.831799 -232.858309) (xy 123.780504 -232.850184) (xy 123.731111 -232.834136) (xy 123.684837 -232.810558)
			(xy 123.642821 -232.780032) (xy 123.606098 -232.743309) (xy 123.575572 -232.701293) (xy 123.551994 -232.655019)
			(xy 123.535946 -232.605626) (xy 123.527821 -232.554331) (xy 123.247911 -232.554331) (xy 123.239786 -232.605626)
			(xy 123.223738 -232.655019) (xy 123.20016 -232.701293) (xy 123.169634 -232.743309) (xy 123.132911 -232.780032)
			(xy 123.090895 -232.810558) (xy 123.044621 -232.834136) (xy 122.995228 -232.850184) (xy 122.943933 -232.858309)
			(xy 122.891999 -232.858309) (xy 122.840704 -232.850184) (xy 122.791311 -232.834136) (xy 122.745037 -232.810558)
			(xy 122.703021 -232.780032) (xy 122.666298 -232.743309) (xy 122.635772 -232.701293) (xy 122.612194 -232.655019)
			(xy 122.596146 -232.605626) (xy 122.588021 -232.554331) (xy 122.308111 -232.554331) (xy 122.299986 -232.605626)
			(xy 122.283938 -232.655019) (xy 122.26036 -232.701293) (xy 122.229834 -232.743309) (xy 122.193111 -232.780032)
			(xy 122.151095 -232.810558) (xy 122.104821 -232.834136) (xy 122.055428 -232.850184) (xy 122.004133 -232.858309)
			(xy 121.952199 -232.858309) (xy 121.900904 -232.850184) (xy 121.851511 -232.834136) (xy 121.805237 -232.810558)
			(xy 121.763221 -232.780032) (xy 121.726498 -232.743309) (xy 121.695972 -232.701293) (xy 121.672394 -232.655019)
			(xy 121.656346 -232.605626) (xy 121.648221 -232.554331) (xy 121.368311 -232.554331) (xy 121.360186 -232.605626)
			(xy 121.344138 -232.655019) (xy 121.32056 -232.701293) (xy 121.290034 -232.743309) (xy 121.253311 -232.780032)
			(xy 121.211295 -232.810558) (xy 121.165021 -232.834136) (xy 121.115628 -232.850184) (xy 121.064333 -232.858309)
			(xy 121.012399 -232.858309) (xy 120.961104 -232.850184) (xy 120.911711 -232.834136) (xy 120.865437 -232.810558)
			(xy 120.823421 -232.780032) (xy 120.786698 -232.743309) (xy 120.756172 -232.701293) (xy 120.732594 -232.655019)
			(xy 120.716546 -232.605626) (xy 120.708421 -232.554331) (xy 120.428257 -232.554331) (xy 120.420132 -232.605626)
			(xy 120.404084 -232.655019) (xy 120.380506 -232.701293) (xy 120.34998 -232.743309) (xy 120.313257 -232.780032)
			(xy 120.271241 -232.810558) (xy 120.224967 -232.834136) (xy 120.175574 -232.850184) (xy 120.124279 -232.858309)
			(xy 120.072345 -232.858309) (xy 120.02105 -232.850184) (xy 119.971657 -232.834136) (xy 119.925383 -232.810558)
			(xy 119.883367 -232.780032) (xy 119.846644 -232.743309) (xy 119.816118 -232.701293) (xy 119.79254 -232.655019)
			(xy 119.776492 -232.605626) (xy 119.768367 -232.554331) (xy 119.488711 -232.554331) (xy 119.480586 -232.605626)
			(xy 119.464538 -232.655019) (xy 119.44096 -232.701293) (xy 119.410434 -232.743309) (xy 119.373711 -232.780032)
			(xy 119.331695 -232.810558) (xy 119.285421 -232.834136) (xy 119.236028 -232.850184) (xy 119.184733 -232.858309)
			(xy 119.132799 -232.858309) (xy 119.081504 -232.850184) (xy 119.032111 -232.834136) (xy 118.985837 -232.810558)
			(xy 118.943821 -232.780032) (xy 118.907098 -232.743309) (xy 118.876572 -232.701293) (xy 118.852994 -232.655019)
			(xy 118.836946 -232.605626) (xy 118.828821 -232.554331) (xy 118.548911 -232.554331) (xy 118.540786 -232.605626)
			(xy 118.524738 -232.655019) (xy 118.50116 -232.701293) (xy 118.470634 -232.743309) (xy 118.433911 -232.780032)
			(xy 118.391895 -232.810558) (xy 118.345621 -232.834136) (xy 118.296228 -232.850184) (xy 118.244933 -232.858309)
			(xy 118.192999 -232.858309) (xy 118.141704 -232.850184) (xy 118.092311 -232.834136) (xy 118.046037 -232.810558)
			(xy 118.004021 -232.780032) (xy 117.967298 -232.743309) (xy 117.936772 -232.701293) (xy 117.913194 -232.655019)
			(xy 117.897146 -232.605626) (xy 117.889021 -232.554331) (xy 117.609111 -232.554331) (xy 117.600986 -232.605626)
			(xy 117.584938 -232.655019) (xy 117.56136 -232.701293) (xy 117.530834 -232.743309) (xy 117.494111 -232.780032)
			(xy 117.452095 -232.810558) (xy 117.405821 -232.834136) (xy 117.356428 -232.850184) (xy 117.305133 -232.858309)
			(xy 117.253199 -232.858309) (xy 117.201904 -232.850184) (xy 117.152511 -232.834136) (xy 117.106237 -232.810558)
			(xy 117.064221 -232.780032) (xy 117.027498 -232.743309) (xy 116.996972 -232.701293) (xy 116.973394 -232.655019)
			(xy 116.957346 -232.605626) (xy 116.949221 -232.554331) (xy 116.669311 -232.554331) (xy 116.661186 -232.605626)
			(xy 116.645138 -232.655019) (xy 116.62156 -232.701293) (xy 116.591034 -232.743309) (xy 116.554311 -232.780032)
			(xy 116.512295 -232.810558) (xy 116.466021 -232.834136) (xy 116.416628 -232.850184) (xy 116.365333 -232.858309)
			(xy 116.313399 -232.858309) (xy 116.262104 -232.850184) (xy 116.212711 -232.834136) (xy 116.166437 -232.810558)
			(xy 116.124421 -232.780032) (xy 116.087698 -232.743309) (xy 116.057172 -232.701293) (xy 116.033594 -232.655019)
			(xy 116.017546 -232.605626) (xy 116.009421 -232.554331) (xy 115.729511 -232.554331) (xy 115.721386 -232.605626)
			(xy 115.705338 -232.655019) (xy 115.68176 -232.701293) (xy 115.651234 -232.743309) (xy 115.614511 -232.780032)
			(xy 115.572495 -232.810558) (xy 115.526221 -232.834136) (xy 115.476828 -232.850184) (xy 115.425533 -232.858309)
			(xy 115.373599 -232.858309) (xy 115.322304 -232.850184) (xy 115.272911 -232.834136) (xy 115.226637 -232.810558)
			(xy 115.184621 -232.780032) (xy 115.147898 -232.743309) (xy 115.117372 -232.701293) (xy 115.093794 -232.655019)
			(xy 115.077746 -232.605626) (xy 115.069621 -232.554331) (xy 114.789711 -232.554331) (xy 114.781586 -232.605626)
			(xy 114.765538 -232.655019) (xy 114.74196 -232.701293) (xy 114.711434 -232.743309) (xy 114.674711 -232.780032)
			(xy 114.632695 -232.810558) (xy 114.586421 -232.834136) (xy 114.537028 -232.850184) (xy 114.485733 -232.858309)
			(xy 114.433799 -232.858309) (xy 114.382504 -232.850184) (xy 114.333111 -232.834136) (xy 114.286837 -232.810558)
			(xy 114.244821 -232.780032) (xy 114.208098 -232.743309) (xy 114.177572 -232.701293) (xy 114.153994 -232.655019)
			(xy 114.137946 -232.605626) (xy 114.129821 -232.554331) (xy 113.849911 -232.554331) (xy 113.841786 -232.605626)
			(xy 113.825738 -232.655019) (xy 113.80216 -232.701293) (xy 113.771634 -232.743309) (xy 113.734911 -232.780032)
			(xy 113.692895 -232.810558) (xy 113.646621 -232.834136) (xy 113.597228 -232.850184) (xy 113.545933 -232.858309)
			(xy 113.493999 -232.858309) (xy 113.442704 -232.850184) (xy 113.393311 -232.834136) (xy 113.347037 -232.810558)
			(xy 113.305021 -232.780032) (xy 113.268298 -232.743309) (xy 113.237772 -232.701293) (xy 113.214194 -232.655019)
			(xy 113.198146 -232.605626) (xy 113.190021 -232.554331) (xy 112.910111 -232.554331) (xy 112.901986 -232.605626)
			(xy 112.885938 -232.655019) (xy 112.86236 -232.701293) (xy 112.831834 -232.743309) (xy 112.795111 -232.780032)
			(xy 112.753095 -232.810558) (xy 112.706821 -232.834136) (xy 112.657428 -232.850184) (xy 112.606133 -232.858309)
			(xy 112.554199 -232.858309) (xy 112.502904 -232.850184) (xy 112.453511 -232.834136) (xy 112.407237 -232.810558)
			(xy 112.365221 -232.780032) (xy 112.328498 -232.743309) (xy 112.297972 -232.701293) (xy 112.274394 -232.655019)
			(xy 112.258346 -232.605626) (xy 112.250221 -232.554331) (xy 111.970311 -232.554331) (xy 111.962186 -232.605626)
			(xy 111.946138 -232.655019) (xy 111.92256 -232.701293) (xy 111.892034 -232.743309) (xy 111.855311 -232.780032)
			(xy 111.813295 -232.810558) (xy 111.767021 -232.834136) (xy 111.717628 -232.850184) (xy 111.666333 -232.858309)
			(xy 111.614399 -232.858309) (xy 111.563104 -232.850184) (xy 111.513711 -232.834136) (xy 111.467437 -232.810558)
			(xy 111.425421 -232.780032) (xy 111.388698 -232.743309) (xy 111.358172 -232.701293) (xy 111.334594 -232.655019)
			(xy 111.318546 -232.605626) (xy 111.310421 -232.554331) (xy 111.030511 -232.554331) (xy 111.022386 -232.605626)
			(xy 111.006338 -232.655019) (xy 110.98276 -232.701293) (xy 110.952234 -232.743309) (xy 110.915511 -232.780032)
			(xy 110.873495 -232.810558) (xy 110.827221 -232.834136) (xy 110.777828 -232.850184) (xy 110.726533 -232.858309)
			(xy 110.674599 -232.858309) (xy 110.623304 -232.850184) (xy 110.573911 -232.834136) (xy 110.527637 -232.810558)
			(xy 110.485621 -232.780032) (xy 110.448898 -232.743309) (xy 110.418372 -232.701293) (xy 110.394794 -232.655019)
			(xy 110.378746 -232.605626) (xy 110.370621 -232.554331) (xy 110.182952 -232.554331) (xy 110.189518 -232.56621)
			(xy 110.189518 -232.960926) (xy 110.18998 -232.970772) (xy 110.19741 -232.989008) (xy 110.211166 -233.003099)
			(xy 110.229218 -233.010968) (xy 110.239048 -233.011726) (xy 110.264588 -233.012848) (xy 110.314884 -233.021991)
			(xy 110.363174 -233.038767) (xy 110.408305 -233.062777) (xy 110.449202 -233.093448) (xy 110.48489 -233.130049)
			(xy 110.514519 -233.171708) (xy 110.537381 -233.217431) (xy 110.552933 -233.266128) (xy 110.560802 -233.316639)
			(xy 110.560802 -233.36776) (xy 110.560742 -233.368147) (xy 110.840267 -233.368147) (xy 110.840267 -233.316213)
			(xy 110.848392 -233.264918) (xy 110.86444 -233.215525) (xy 110.888018 -233.169251) (xy 110.918544 -233.127235)
			(xy 110.955267 -233.090512) (xy 110.997283 -233.059986) (xy 111.043557 -233.036408) (xy 111.09295 -233.02036)
			(xy 111.144245 -233.012235) (xy 111.196179 -233.012235) (xy 111.247474 -233.02036) (xy 111.296867 -233.036408)
			(xy 111.343141 -233.059986) (xy 111.385157 -233.090512) (xy 111.42188 -233.127235) (xy 111.452406 -233.169251)
			(xy 111.475984 -233.215525) (xy 111.492032 -233.264918) (xy 111.500157 -233.316213) (xy 111.500666 -233.34218)
			(xy 111.500157 -233.368147) (xy 111.780067 -233.368147) (xy 111.780067 -233.316213) (xy 111.788192 -233.264918)
			(xy 111.80424 -233.215525) (xy 111.827818 -233.169251) (xy 111.858344 -233.127235) (xy 111.895067 -233.090512)
			(xy 111.937083 -233.059986) (xy 111.983357 -233.036408) (xy 112.03275 -233.02036) (xy 112.084045 -233.012235)
			(xy 112.135979 -233.012235) (xy 112.187274 -233.02036) (xy 112.236667 -233.036408) (xy 112.282941 -233.059986)
			(xy 112.324957 -233.090512) (xy 112.36168 -233.127235) (xy 112.392206 -233.169251) (xy 112.415784 -233.215525)
			(xy 112.431832 -233.264918) (xy 112.439957 -233.316213) (xy 112.440466 -233.34218) (xy 112.439957 -233.368147)
			(xy 112.719867 -233.368147) (xy 112.719867 -233.316213) (xy 112.727992 -233.264918) (xy 112.74404 -233.215525)
			(xy 112.767618 -233.169251) (xy 112.798144 -233.127235) (xy 112.834867 -233.090512) (xy 112.876883 -233.059986)
			(xy 112.923157 -233.036408) (xy 112.97255 -233.02036) (xy 113.023845 -233.012235) (xy 113.075779 -233.012235)
			(xy 113.127074 -233.02036) (xy 113.176467 -233.036408) (xy 113.222741 -233.059986) (xy 113.264757 -233.090512)
			(xy 113.30148 -233.127235) (xy 113.332006 -233.169251) (xy 113.355584 -233.215525) (xy 113.371632 -233.264918)
			(xy 113.379757 -233.316213) (xy 113.380266 -233.34218) (xy 113.379757 -233.368147) (xy 113.659921 -233.368147)
			(xy 113.659921 -233.316213) (xy 113.668046 -233.264918) (xy 113.684094 -233.215525) (xy 113.707672 -233.169251)
			(xy 113.738198 -233.127235) (xy 113.774921 -233.090512) (xy 113.816937 -233.059986) (xy 113.863211 -233.036408)
			(xy 113.912604 -233.02036) (xy 113.963899 -233.012235) (xy 114.015833 -233.012235) (xy 114.067128 -233.02036)
			(xy 114.116521 -233.036408) (xy 114.162795 -233.059986) (xy 114.204811 -233.090512) (xy 114.241534 -233.127235)
			(xy 114.27206 -233.169251) (xy 114.295638 -233.215525) (xy 114.311686 -233.264918) (xy 114.319811 -233.316213)
			(xy 114.32032 -233.34218) (xy 114.319811 -233.368147) (xy 114.599467 -233.368147) (xy 114.599467 -233.316213)
			(xy 114.607592 -233.264918) (xy 114.62364 -233.215525) (xy 114.647218 -233.169251) (xy 114.677744 -233.127235)
			(xy 114.714467 -233.090512) (xy 114.756483 -233.059986) (xy 114.802757 -233.036408) (xy 114.85215 -233.02036)
			(xy 114.903445 -233.012235) (xy 114.955379 -233.012235) (xy 115.006674 -233.02036) (xy 115.056067 -233.036408)
			(xy 115.102341 -233.059986) (xy 115.144357 -233.090512) (xy 115.18108 -233.127235) (xy 115.211606 -233.169251)
			(xy 115.235184 -233.215525) (xy 115.251232 -233.264918) (xy 115.259357 -233.316213) (xy 115.259866 -233.34218)
			(xy 115.259357 -233.368147) (xy 115.539267 -233.368147) (xy 115.539267 -233.316213) (xy 115.547392 -233.264918)
			(xy 115.56344 -233.215525) (xy 115.587018 -233.169251) (xy 115.617544 -233.127235) (xy 115.654267 -233.090512)
			(xy 115.696283 -233.059986) (xy 115.742557 -233.036408) (xy 115.79195 -233.02036) (xy 115.843245 -233.012235)
			(xy 115.895179 -233.012235) (xy 115.946474 -233.02036) (xy 115.995867 -233.036408) (xy 116.042141 -233.059986)
			(xy 116.084157 -233.090512) (xy 116.12088 -233.127235) (xy 116.151406 -233.169251) (xy 116.174984 -233.215525)
			(xy 116.191032 -233.264918) (xy 116.199157 -233.316213) (xy 116.199666 -233.34218) (xy 116.199157 -233.368147)
			(xy 116.479067 -233.368147) (xy 116.479067 -233.316213) (xy 116.487192 -233.264918) (xy 116.50324 -233.215525)
			(xy 116.526818 -233.169251) (xy 116.557344 -233.127235) (xy 116.594067 -233.090512) (xy 116.636083 -233.059986)
			(xy 116.682357 -233.036408) (xy 116.73175 -233.02036) (xy 116.783045 -233.012235) (xy 116.834979 -233.012235)
			(xy 116.886274 -233.02036) (xy 116.935667 -233.036408) (xy 116.981941 -233.059986) (xy 117.023957 -233.090512)
			(xy 117.06068 -233.127235) (xy 117.091206 -233.169251) (xy 117.114784 -233.215525) (xy 117.130832 -233.264918)
			(xy 117.138957 -233.316213) (xy 117.139466 -233.34218) (xy 117.138957 -233.368147) (xy 117.418867 -233.368147)
			(xy 117.418867 -233.316213) (xy 117.426992 -233.264918) (xy 117.44304 -233.215525) (xy 117.466618 -233.169251)
			(xy 117.497144 -233.127235) (xy 117.533867 -233.090512) (xy 117.575883 -233.059986) (xy 117.622157 -233.036408)
			(xy 117.67155 -233.02036) (xy 117.722845 -233.012235) (xy 117.774779 -233.012235) (xy 117.826074 -233.02036)
			(xy 117.875467 -233.036408) (xy 117.921741 -233.059986) (xy 117.963757 -233.090512) (xy 118.00048 -233.127235)
			(xy 118.031006 -233.169251) (xy 118.054584 -233.215525) (xy 118.070632 -233.264918) (xy 118.078757 -233.316213)
			(xy 118.079266 -233.34218) (xy 118.078757 -233.368147) (xy 118.358667 -233.368147) (xy 118.358667 -233.316213)
			(xy 118.366792 -233.264918) (xy 118.38284 -233.215525) (xy 118.406418 -233.169251) (xy 118.436944 -233.127235)
			(xy 118.473667 -233.090512) (xy 118.515683 -233.059986) (xy 118.561957 -233.036408) (xy 118.61135 -233.02036)
			(xy 118.662645 -233.012235) (xy 118.714579 -233.012235) (xy 118.765874 -233.02036) (xy 118.815267 -233.036408)
			(xy 118.861541 -233.059986) (xy 118.903557 -233.090512) (xy 118.94028 -233.127235) (xy 118.970806 -233.169251)
			(xy 118.994384 -233.215525) (xy 119.010432 -233.264918) (xy 119.018557 -233.316213) (xy 119.019066 -233.34218)
			(xy 119.018557 -233.368147) (xy 119.298467 -233.368147) (xy 119.298467 -233.316213) (xy 119.306592 -233.264918)
			(xy 119.32264 -233.215525) (xy 119.346218 -233.169251) (xy 119.376744 -233.127235) (xy 119.413467 -233.090512)
			(xy 119.455483 -233.059986) (xy 119.501757 -233.036408) (xy 119.55115 -233.02036) (xy 119.602445 -233.012235)
			(xy 119.654379 -233.012235) (xy 119.705674 -233.02036) (xy 119.755067 -233.036408) (xy 119.801341 -233.059986)
			(xy 119.843357 -233.090512) (xy 119.88008 -233.127235) (xy 119.910606 -233.169251) (xy 119.934184 -233.215525)
			(xy 119.950232 -233.264918) (xy 119.958357 -233.316213) (xy 119.958866 -233.34218) (xy 119.958357 -233.368147)
			(xy 120.238267 -233.368147) (xy 120.238267 -233.316213) (xy 120.246392 -233.264918) (xy 120.26244 -233.215525)
			(xy 120.286018 -233.169251) (xy 120.316544 -233.127235) (xy 120.353267 -233.090512) (xy 120.395283 -233.059986)
			(xy 120.441557 -233.036408) (xy 120.49095 -233.02036) (xy 120.542245 -233.012235) (xy 120.594179 -233.012235)
			(xy 120.645474 -233.02036) (xy 120.694867 -233.036408) (xy 120.741141 -233.059986) (xy 120.783157 -233.090512)
			(xy 120.81988 -233.127235) (xy 120.850406 -233.169251) (xy 120.873984 -233.215525) (xy 120.890032 -233.264918)
			(xy 120.898157 -233.316213) (xy 120.898666 -233.34218) (xy 120.898157 -233.368147) (xy 121.178321 -233.368147)
			(xy 121.178321 -233.316213) (xy 121.186446 -233.264918) (xy 121.202494 -233.215525) (xy 121.226072 -233.169251)
			(xy 121.256598 -233.127235) (xy 121.293321 -233.090512) (xy 121.335337 -233.059986) (xy 121.381611 -233.036408)
			(xy 121.431004 -233.02036) (xy 121.482299 -233.012235) (xy 121.534233 -233.012235) (xy 121.585528 -233.02036)
			(xy 121.634921 -233.036408) (xy 121.681195 -233.059986) (xy 121.723211 -233.090512) (xy 121.759934 -233.127235)
			(xy 121.79046 -233.169251) (xy 121.814038 -233.215525) (xy 121.830086 -233.264918) (xy 121.838211 -233.316213)
			(xy 121.83872 -233.34218) (xy 121.838211 -233.368147) (xy 122.117867 -233.368147) (xy 122.117867 -233.316213)
			(xy 122.125992 -233.264918) (xy 122.14204 -233.215525) (xy 122.165618 -233.169251) (xy 122.196144 -233.127235)
			(xy 122.232867 -233.090512) (xy 122.274883 -233.059986) (xy 122.321157 -233.036408) (xy 122.37055 -233.02036)
			(xy 122.421845 -233.012235) (xy 122.473779 -233.012235) (xy 122.525074 -233.02036) (xy 122.574467 -233.036408)
			(xy 122.620741 -233.059986) (xy 122.662757 -233.090512) (xy 122.69948 -233.127235) (xy 122.730006 -233.169251)
			(xy 122.753584 -233.215525) (xy 122.769632 -233.264918) (xy 122.777757 -233.316213) (xy 122.778266 -233.34218)
			(xy 122.777757 -233.368147) (xy 123.057667 -233.368147) (xy 123.057667 -233.316213) (xy 123.065792 -233.264918)
			(xy 123.08184 -233.215525) (xy 123.105418 -233.169251) (xy 123.135944 -233.127235) (xy 123.172667 -233.090512)
			(xy 123.214683 -233.059986) (xy 123.260957 -233.036408) (xy 123.31035 -233.02036) (xy 123.361645 -233.012235)
			(xy 123.413579 -233.012235) (xy 123.464874 -233.02036) (xy 123.514267 -233.036408) (xy 123.560541 -233.059986)
			(xy 123.602557 -233.090512) (xy 123.63928 -233.127235) (xy 123.669806 -233.169251) (xy 123.693384 -233.215525)
			(xy 123.709432 -233.264918) (xy 123.717557 -233.316213) (xy 123.718066 -233.34218) (xy 123.717557 -233.368147)
			(xy 123.997467 -233.368147) (xy 123.997467 -233.316213) (xy 124.005592 -233.264918) (xy 124.02164 -233.215525)
			(xy 124.045218 -233.169251) (xy 124.075744 -233.127235) (xy 124.112467 -233.090512) (xy 124.154483 -233.059986)
			(xy 124.200757 -233.036408) (xy 124.25015 -233.02036) (xy 124.301445 -233.012235) (xy 124.353379 -233.012235)
			(xy 124.404674 -233.02036) (xy 124.454067 -233.036408) (xy 124.500341 -233.059986) (xy 124.542357 -233.090512)
			(xy 124.57908 -233.127235) (xy 124.609606 -233.169251) (xy 124.633184 -233.215525) (xy 124.649232 -233.264918)
			(xy 124.657357 -233.316213) (xy 124.657866 -233.34218) (xy 124.657357 -233.368147) (xy 124.937267 -233.368147)
			(xy 124.937267 -233.316213) (xy 124.945392 -233.264918) (xy 124.96144 -233.215525) (xy 124.985018 -233.169251)
			(xy 125.015544 -233.127235) (xy 125.052267 -233.090512) (xy 125.094283 -233.059986) (xy 125.140557 -233.036408)
			(xy 125.18995 -233.02036) (xy 125.241245 -233.012235) (xy 125.293179 -233.012235) (xy 125.344474 -233.02036)
			(xy 125.393867 -233.036408) (xy 125.440141 -233.059986) (xy 125.482157 -233.090512) (xy 125.51888 -233.127235)
			(xy 125.549406 -233.169251) (xy 125.572984 -233.215525) (xy 125.589032 -233.264918) (xy 125.597157 -233.316213)
			(xy 125.597666 -233.34218) (xy 125.597157 -233.368147) (xy 125.877321 -233.368147) (xy 125.877321 -233.316213)
			(xy 125.885446 -233.264918) (xy 125.901494 -233.215525) (xy 125.925072 -233.169251) (xy 125.955598 -233.127235)
			(xy 125.992321 -233.090512) (xy 126.034337 -233.059986) (xy 126.080611 -233.036408) (xy 126.130004 -233.02036)
			(xy 126.181299 -233.012235) (xy 126.233233 -233.012235) (xy 126.284528 -233.02036) (xy 126.333921 -233.036408)
			(xy 126.380195 -233.059986) (xy 126.422211 -233.090512) (xy 126.458934 -233.127235) (xy 126.48946 -233.169251)
			(xy 126.513038 -233.215525) (xy 126.529086 -233.264918) (xy 126.537211 -233.316213) (xy 126.53772 -233.34218)
			(xy 126.537211 -233.368147) (xy 126.816867 -233.368147) (xy 126.816867 -233.316213) (xy 126.824992 -233.264918)
			(xy 126.84104 -233.215525) (xy 126.864618 -233.169251) (xy 126.895144 -233.127235) (xy 126.931867 -233.090512)
			(xy 126.973883 -233.059986) (xy 127.020157 -233.036408) (xy 127.06955 -233.02036) (xy 127.120845 -233.012235)
			(xy 127.172779 -233.012235) (xy 127.224074 -233.02036) (xy 127.273467 -233.036408) (xy 127.319741 -233.059986)
			(xy 127.361757 -233.090512) (xy 127.39848 -233.127235) (xy 127.429006 -233.169251) (xy 127.452584 -233.215525)
			(xy 127.468632 -233.264918) (xy 127.476757 -233.316213) (xy 127.477266 -233.34218) (xy 127.476757 -233.368147)
			(xy 127.468632 -233.419442) (xy 127.452584 -233.468835) (xy 127.429006 -233.515109) (xy 127.39848 -233.557125)
			(xy 127.361757 -233.593848) (xy 127.319741 -233.624374) (xy 127.273467 -233.647952) (xy 127.224074 -233.664)
			(xy 127.172779 -233.672125) (xy 127.120845 -233.672125) (xy 127.06955 -233.664) (xy 127.020157 -233.647952)
			(xy 126.973883 -233.624374) (xy 126.931867 -233.593848) (xy 126.895144 -233.557125) (xy 126.864618 -233.515109)
			(xy 126.84104 -233.468835) (xy 126.824992 -233.419442) (xy 126.816867 -233.368147) (xy 126.537211 -233.368147)
			(xy 126.529086 -233.419442) (xy 126.513038 -233.468835) (xy 126.48946 -233.515109) (xy 126.458934 -233.557125)
			(xy 126.422211 -233.593848) (xy 126.380195 -233.624374) (xy 126.333921 -233.647952) (xy 126.284528 -233.664)
			(xy 126.233233 -233.672125) (xy 126.181299 -233.672125) (xy 126.130004 -233.664) (xy 126.080611 -233.647952)
			(xy 126.034337 -233.624374) (xy 125.992321 -233.593848) (xy 125.955598 -233.557125) (xy 125.925072 -233.515109)
			(xy 125.901494 -233.468835) (xy 125.885446 -233.419442) (xy 125.877321 -233.368147) (xy 125.597157 -233.368147)
			(xy 125.589032 -233.419442) (xy 125.572984 -233.468835) (xy 125.549406 -233.515109) (xy 125.51888 -233.557125)
			(xy 125.482157 -233.593848) (xy 125.440141 -233.624374) (xy 125.393867 -233.647952) (xy 125.344474 -233.664)
			(xy 125.293179 -233.672125) (xy 125.241245 -233.672125) (xy 125.18995 -233.664) (xy 125.140557 -233.647952)
			(xy 125.094283 -233.624374) (xy 125.052267 -233.593848) (xy 125.015544 -233.557125) (xy 124.985018 -233.515109)
			(xy 124.96144 -233.468835) (xy 124.945392 -233.419442) (xy 124.937267 -233.368147) (xy 124.657357 -233.368147)
			(xy 124.649232 -233.419442) (xy 124.633184 -233.468835) (xy 124.609606 -233.515109) (xy 124.57908 -233.557125)
			(xy 124.542357 -233.593848) (xy 124.500341 -233.624374) (xy 124.454067 -233.647952) (xy 124.404674 -233.664)
			(xy 124.353379 -233.672125) (xy 124.301445 -233.672125) (xy 124.25015 -233.664) (xy 124.200757 -233.647952)
			(xy 124.154483 -233.624374) (xy 124.112467 -233.593848) (xy 124.075744 -233.557125) (xy 124.045218 -233.515109)
			(xy 124.02164 -233.468835) (xy 124.005592 -233.419442) (xy 123.997467 -233.368147) (xy 123.717557 -233.368147)
			(xy 123.709432 -233.419442) (xy 123.693384 -233.468835) (xy 123.669806 -233.515109) (xy 123.63928 -233.557125)
			(xy 123.602557 -233.593848) (xy 123.560541 -233.624374) (xy 123.514267 -233.647952) (xy 123.464874 -233.664)
			(xy 123.413579 -233.672125) (xy 123.361645 -233.672125) (xy 123.31035 -233.664) (xy 123.260957 -233.647952)
			(xy 123.214683 -233.624374) (xy 123.172667 -233.593848) (xy 123.135944 -233.557125) (xy 123.105418 -233.515109)
			(xy 123.08184 -233.468835) (xy 123.065792 -233.419442) (xy 123.057667 -233.368147) (xy 122.777757 -233.368147)
			(xy 122.769632 -233.419442) (xy 122.753584 -233.468835) (xy 122.730006 -233.515109) (xy 122.69948 -233.557125)
			(xy 122.662757 -233.593848) (xy 122.620741 -233.624374) (xy 122.574467 -233.647952) (xy 122.525074 -233.664)
			(xy 122.473779 -233.672125) (xy 122.421845 -233.672125) (xy 122.37055 -233.664) (xy 122.321157 -233.647952)
			(xy 122.274883 -233.624374) (xy 122.232867 -233.593848) (xy 122.196144 -233.557125) (xy 122.165618 -233.515109)
			(xy 122.14204 -233.468835) (xy 122.125992 -233.419442) (xy 122.117867 -233.368147) (xy 121.838211 -233.368147)
			(xy 121.830086 -233.419442) (xy 121.814038 -233.468835) (xy 121.79046 -233.515109) (xy 121.759934 -233.557125)
			(xy 121.723211 -233.593848) (xy 121.681195 -233.624374) (xy 121.634921 -233.647952) (xy 121.585528 -233.664)
			(xy 121.534233 -233.672125) (xy 121.482299 -233.672125) (xy 121.431004 -233.664) (xy 121.381611 -233.647952)
			(xy 121.335337 -233.624374) (xy 121.293321 -233.593848) (xy 121.256598 -233.557125) (xy 121.226072 -233.515109)
			(xy 121.202494 -233.468835) (xy 121.186446 -233.419442) (xy 121.178321 -233.368147) (xy 120.898157 -233.368147)
			(xy 120.890032 -233.419442) (xy 120.873984 -233.468835) (xy 120.850406 -233.515109) (xy 120.81988 -233.557125)
			(xy 120.783157 -233.593848) (xy 120.741141 -233.624374) (xy 120.694867 -233.647952) (xy 120.645474 -233.664)
			(xy 120.594179 -233.672125) (xy 120.542245 -233.672125) (xy 120.49095 -233.664) (xy 120.441557 -233.647952)
			(xy 120.395283 -233.624374) (xy 120.353267 -233.593848) (xy 120.316544 -233.557125) (xy 120.286018 -233.515109)
			(xy 120.26244 -233.468835) (xy 120.246392 -233.419442) (xy 120.238267 -233.368147) (xy 119.958357 -233.368147)
			(xy 119.950232 -233.419442) (xy 119.934184 -233.468835) (xy 119.910606 -233.515109) (xy 119.88008 -233.557125)
			(xy 119.843357 -233.593848) (xy 119.801341 -233.624374) (xy 119.755067 -233.647952) (xy 119.705674 -233.664)
			(xy 119.654379 -233.672125) (xy 119.602445 -233.672125) (xy 119.55115 -233.664) (xy 119.501757 -233.647952)
			(xy 119.455483 -233.624374) (xy 119.413467 -233.593848) (xy 119.376744 -233.557125) (xy 119.346218 -233.515109)
			(xy 119.32264 -233.468835) (xy 119.306592 -233.419442) (xy 119.298467 -233.368147) (xy 119.018557 -233.368147)
			(xy 119.010432 -233.419442) (xy 118.994384 -233.468835) (xy 118.970806 -233.515109) (xy 118.94028 -233.557125)
			(xy 118.903557 -233.593848) (xy 118.861541 -233.624374) (xy 118.815267 -233.647952) (xy 118.765874 -233.664)
			(xy 118.714579 -233.672125) (xy 118.662645 -233.672125) (xy 118.61135 -233.664) (xy 118.561957 -233.647952)
			(xy 118.515683 -233.624374) (xy 118.473667 -233.593848) (xy 118.436944 -233.557125) (xy 118.406418 -233.515109)
			(xy 118.38284 -233.468835) (xy 118.366792 -233.419442) (xy 118.358667 -233.368147) (xy 118.078757 -233.368147)
			(xy 118.070632 -233.419442) (xy 118.054584 -233.468835) (xy 118.031006 -233.515109) (xy 118.00048 -233.557125)
			(xy 117.963757 -233.593848) (xy 117.921741 -233.624374) (xy 117.875467 -233.647952) (xy 117.826074 -233.664)
			(xy 117.774779 -233.672125) (xy 117.722845 -233.672125) (xy 117.67155 -233.664) (xy 117.622157 -233.647952)
			(xy 117.575883 -233.624374) (xy 117.533867 -233.593848) (xy 117.497144 -233.557125) (xy 117.466618 -233.515109)
			(xy 117.44304 -233.468835) (xy 117.426992 -233.419442) (xy 117.418867 -233.368147) (xy 117.138957 -233.368147)
			(xy 117.130832 -233.419442) (xy 117.114784 -233.468835) (xy 117.091206 -233.515109) (xy 117.06068 -233.557125)
			(xy 117.023957 -233.593848) (xy 116.981941 -233.624374) (xy 116.935667 -233.647952) (xy 116.886274 -233.664)
			(xy 116.834979 -233.672125) (xy 116.783045 -233.672125) (xy 116.73175 -233.664) (xy 116.682357 -233.647952)
			(xy 116.636083 -233.624374) (xy 116.594067 -233.593848) (xy 116.557344 -233.557125) (xy 116.526818 -233.515109)
			(xy 116.50324 -233.468835) (xy 116.487192 -233.419442) (xy 116.479067 -233.368147) (xy 116.199157 -233.368147)
			(xy 116.191032 -233.419442) (xy 116.174984 -233.468835) (xy 116.151406 -233.515109) (xy 116.12088 -233.557125)
			(xy 116.084157 -233.593848) (xy 116.042141 -233.624374) (xy 115.995867 -233.647952) (xy 115.946474 -233.664)
			(xy 115.895179 -233.672125) (xy 115.843245 -233.672125) (xy 115.79195 -233.664) (xy 115.742557 -233.647952)
			(xy 115.696283 -233.624374) (xy 115.654267 -233.593848) (xy 115.617544 -233.557125) (xy 115.587018 -233.515109)
			(xy 115.56344 -233.468835) (xy 115.547392 -233.419442) (xy 115.539267 -233.368147) (xy 115.259357 -233.368147)
			(xy 115.251232 -233.419442) (xy 115.235184 -233.468835) (xy 115.211606 -233.515109) (xy 115.18108 -233.557125)
			(xy 115.144357 -233.593848) (xy 115.102341 -233.624374) (xy 115.056067 -233.647952) (xy 115.006674 -233.664)
			(xy 114.955379 -233.672125) (xy 114.903445 -233.672125) (xy 114.85215 -233.664) (xy 114.802757 -233.647952)
			(xy 114.756483 -233.624374) (xy 114.714467 -233.593848) (xy 114.677744 -233.557125) (xy 114.647218 -233.515109)
			(xy 114.62364 -233.468835) (xy 114.607592 -233.419442) (xy 114.599467 -233.368147) (xy 114.319811 -233.368147)
			(xy 114.311686 -233.419442) (xy 114.295638 -233.468835) (xy 114.27206 -233.515109) (xy 114.241534 -233.557125)
			(xy 114.204811 -233.593848) (xy 114.162795 -233.624374) (xy 114.116521 -233.647952) (xy 114.067128 -233.664)
			(xy 114.015833 -233.672125) (xy 113.963899 -233.672125) (xy 113.912604 -233.664) (xy 113.863211 -233.647952)
			(xy 113.816937 -233.624374) (xy 113.774921 -233.593848) (xy 113.738198 -233.557125) (xy 113.707672 -233.515109)
			(xy 113.684094 -233.468835) (xy 113.668046 -233.419442) (xy 113.659921 -233.368147) (xy 113.379757 -233.368147)
			(xy 113.371632 -233.419442) (xy 113.355584 -233.468835) (xy 113.332006 -233.515109) (xy 113.30148 -233.557125)
			(xy 113.264757 -233.593848) (xy 113.222741 -233.624374) (xy 113.176467 -233.647952) (xy 113.127074 -233.664)
			(xy 113.075779 -233.672125) (xy 113.023845 -233.672125) (xy 112.97255 -233.664) (xy 112.923157 -233.647952)
			(xy 112.876883 -233.624374) (xy 112.834867 -233.593848) (xy 112.798144 -233.557125) (xy 112.767618 -233.515109)
			(xy 112.74404 -233.468835) (xy 112.727992 -233.419442) (xy 112.719867 -233.368147) (xy 112.439957 -233.368147)
			(xy 112.431832 -233.419442) (xy 112.415784 -233.468835) (xy 112.392206 -233.515109) (xy 112.36168 -233.557125)
			(xy 112.324957 -233.593848) (xy 112.282941 -233.624374) (xy 112.236667 -233.647952) (xy 112.187274 -233.664)
			(xy 112.135979 -233.672125) (xy 112.084045 -233.672125) (xy 112.03275 -233.664) (xy 111.983357 -233.647952)
			(xy 111.937083 -233.624374) (xy 111.895067 -233.593848) (xy 111.858344 -233.557125) (xy 111.827818 -233.515109)
			(xy 111.80424 -233.468835) (xy 111.788192 -233.419442) (xy 111.780067 -233.368147) (xy 111.500157 -233.368147)
			(xy 111.492032 -233.419442) (xy 111.475984 -233.468835) (xy 111.452406 -233.515109) (xy 111.42188 -233.557125)
			(xy 111.385157 -233.593848) (xy 111.343141 -233.624374) (xy 111.296867 -233.647952) (xy 111.247474 -233.664)
			(xy 111.196179 -233.672125) (xy 111.144245 -233.672125) (xy 111.09295 -233.664) (xy 111.043557 -233.647952)
			(xy 110.997283 -233.624374) (xy 110.955267 -233.593848) (xy 110.918544 -233.557125) (xy 110.888018 -233.515109)
			(xy 110.86444 -233.468835) (xy 110.848392 -233.419442) (xy 110.840267 -233.368147) (xy 110.560742 -233.368147)
			(xy 110.552933 -233.418271) (xy 110.537382 -233.466968) (xy 110.514519 -233.512692) (xy 110.484891 -233.55435)
			(xy 110.449203 -233.590952) (xy 110.408306 -233.621623) (xy 110.363175 -233.645633) (xy 110.314885 -233.662409)
			(xy 110.264589 -233.671551) (xy 110.239048 -233.672634) (xy 110.229209 -233.673335) (xy 110.211147 -233.681215)
			(xy 110.19739 -233.695324) (xy 110.18997 -233.713581) (xy 110.189518 -233.723434) (xy 110.189518 -234.182217)
			(xy 110.370621 -234.182217) (xy 110.370621 -234.130283) (xy 110.378746 -234.078988) (xy 110.394794 -234.029595)
			(xy 110.418372 -233.983321) (xy 110.448898 -233.941305) (xy 110.485621 -233.904582) (xy 110.527637 -233.874056)
			(xy 110.573911 -233.850478) (xy 110.623304 -233.83443) (xy 110.674599 -233.826305) (xy 110.726533 -233.826305)
			(xy 110.777828 -233.83443) (xy 110.827221 -233.850478) (xy 110.873495 -233.874056) (xy 110.915511 -233.904582)
			(xy 110.952234 -233.941305) (xy 110.98276 -233.983321) (xy 111.006338 -234.029595) (xy 111.022386 -234.078988)
			(xy 111.030511 -234.130283) (xy 111.03102 -234.15625) (xy 111.030511 -234.182217) (xy 111.310421 -234.182217)
			(xy 111.310421 -234.130283) (xy 111.318546 -234.078988) (xy 111.334594 -234.029595) (xy 111.358172 -233.983321)
			(xy 111.388698 -233.941305) (xy 111.425421 -233.904582) (xy 111.467437 -233.874056) (xy 111.513711 -233.850478)
			(xy 111.563104 -233.83443) (xy 111.614399 -233.826305) (xy 111.666333 -233.826305) (xy 111.717628 -233.83443)
			(xy 111.767021 -233.850478) (xy 111.813295 -233.874056) (xy 111.855311 -233.904582) (xy 111.892034 -233.941305)
			(xy 111.92256 -233.983321) (xy 111.946138 -234.029595) (xy 111.962186 -234.078988) (xy 111.970311 -234.130283)
			(xy 111.97082 -234.15625) (xy 111.970311 -234.182217) (xy 112.250221 -234.182217) (xy 112.250221 -234.130283)
			(xy 112.258346 -234.078988) (xy 112.274394 -234.029595) (xy 112.297972 -233.983321) (xy 112.328498 -233.941305)
			(xy 112.365221 -233.904582) (xy 112.407237 -233.874056) (xy 112.453511 -233.850478) (xy 112.502904 -233.83443)
			(xy 112.554199 -233.826305) (xy 112.606133 -233.826305) (xy 112.657428 -233.83443) (xy 112.706821 -233.850478)
			(xy 112.753095 -233.874056) (xy 112.795111 -233.904582) (xy 112.831834 -233.941305) (xy 112.86236 -233.983321)
			(xy 112.885938 -234.029595) (xy 112.901986 -234.078988) (xy 112.910111 -234.130283) (xy 112.91062 -234.15625)
			(xy 112.910111 -234.182217) (xy 113.190021 -234.182217) (xy 113.190021 -234.130283) (xy 113.198146 -234.078988)
			(xy 113.214194 -234.029595) (xy 113.237772 -233.983321) (xy 113.268298 -233.941305) (xy 113.305021 -233.904582)
			(xy 113.347037 -233.874056) (xy 113.393311 -233.850478) (xy 113.442704 -233.83443) (xy 113.493999 -233.826305)
			(xy 113.545933 -233.826305) (xy 113.597228 -233.83443) (xy 113.646621 -233.850478) (xy 113.692895 -233.874056)
			(xy 113.734911 -233.904582) (xy 113.771634 -233.941305) (xy 113.80216 -233.983321) (xy 113.825738 -234.029595)
			(xy 113.841786 -234.078988) (xy 113.849911 -234.130283) (xy 113.85042 -234.15625) (xy 113.849911 -234.182217)
			(xy 114.129821 -234.182217) (xy 114.129821 -234.130283) (xy 114.137946 -234.078988) (xy 114.153994 -234.029595)
			(xy 114.177572 -233.983321) (xy 114.208098 -233.941305) (xy 114.244821 -233.904582) (xy 114.286837 -233.874056)
			(xy 114.333111 -233.850478) (xy 114.382504 -233.83443) (xy 114.433799 -233.826305) (xy 114.485733 -233.826305)
			(xy 114.537028 -233.83443) (xy 114.586421 -233.850478) (xy 114.632695 -233.874056) (xy 114.674711 -233.904582)
			(xy 114.711434 -233.941305) (xy 114.74196 -233.983321) (xy 114.765538 -234.029595) (xy 114.781586 -234.078988)
			(xy 114.789711 -234.130283) (xy 114.79022 -234.15625) (xy 114.789711 -234.182217) (xy 115.069621 -234.182217)
			(xy 115.069621 -234.130283) (xy 115.077746 -234.078988) (xy 115.093794 -234.029595) (xy 115.117372 -233.983321)
			(xy 115.147898 -233.941305) (xy 115.184621 -233.904582) (xy 115.226637 -233.874056) (xy 115.272911 -233.850478)
			(xy 115.322304 -233.83443) (xy 115.373599 -233.826305) (xy 115.425533 -233.826305) (xy 115.476828 -233.83443)
			(xy 115.526221 -233.850478) (xy 115.572495 -233.874056) (xy 115.614511 -233.904582) (xy 115.651234 -233.941305)
			(xy 115.68176 -233.983321) (xy 115.705338 -234.029595) (xy 115.721386 -234.078988) (xy 115.729511 -234.130283)
			(xy 115.73002 -234.15625) (xy 115.729511 -234.182217) (xy 116.009421 -234.182217) (xy 116.009421 -234.130283)
			(xy 116.017546 -234.078988) (xy 116.033594 -234.029595) (xy 116.057172 -233.983321) (xy 116.087698 -233.941305)
			(xy 116.124421 -233.904582) (xy 116.166437 -233.874056) (xy 116.212711 -233.850478) (xy 116.262104 -233.83443)
			(xy 116.313399 -233.826305) (xy 116.365333 -233.826305) (xy 116.416628 -233.83443) (xy 116.466021 -233.850478)
			(xy 116.512295 -233.874056) (xy 116.554311 -233.904582) (xy 116.591034 -233.941305) (xy 116.62156 -233.983321)
			(xy 116.645138 -234.029595) (xy 116.661186 -234.078988) (xy 116.669311 -234.130283) (xy 116.66982 -234.15625)
			(xy 116.669311 -234.182217) (xy 116.949221 -234.182217) (xy 116.949221 -234.130283) (xy 116.957346 -234.078988)
			(xy 116.973394 -234.029595) (xy 116.996972 -233.983321) (xy 117.027498 -233.941305) (xy 117.064221 -233.904582)
			(xy 117.106237 -233.874056) (xy 117.152511 -233.850478) (xy 117.201904 -233.83443) (xy 117.253199 -233.826305)
			(xy 117.305133 -233.826305) (xy 117.356428 -233.83443) (xy 117.405821 -233.850478) (xy 117.452095 -233.874056)
			(xy 117.494111 -233.904582) (xy 117.530834 -233.941305) (xy 117.56136 -233.983321) (xy 117.584938 -234.029595)
			(xy 117.600986 -234.078988) (xy 117.609111 -234.130283) (xy 117.60962 -234.15625) (xy 117.609111 -234.182217)
			(xy 117.889021 -234.182217) (xy 117.889021 -234.130283) (xy 117.897146 -234.078988) (xy 117.913194 -234.029595)
			(xy 117.936772 -233.983321) (xy 117.967298 -233.941305) (xy 118.004021 -233.904582) (xy 118.046037 -233.874056)
			(xy 118.092311 -233.850478) (xy 118.141704 -233.83443) (xy 118.192999 -233.826305) (xy 118.244933 -233.826305)
			(xy 118.296228 -233.83443) (xy 118.345621 -233.850478) (xy 118.391895 -233.874056) (xy 118.433911 -233.904582)
			(xy 118.470634 -233.941305) (xy 118.50116 -233.983321) (xy 118.524738 -234.029595) (xy 118.540786 -234.078988)
			(xy 118.548911 -234.130283) (xy 118.54942 -234.15625) (xy 118.548911 -234.182217) (xy 118.828821 -234.182217)
			(xy 118.828821 -234.130283) (xy 118.836946 -234.078988) (xy 118.852994 -234.029595) (xy 118.876572 -233.983321)
			(xy 118.907098 -233.941305) (xy 118.943821 -233.904582) (xy 118.985837 -233.874056) (xy 119.032111 -233.850478)
			(xy 119.081504 -233.83443) (xy 119.132799 -233.826305) (xy 119.184733 -233.826305) (xy 119.236028 -233.83443)
			(xy 119.285421 -233.850478) (xy 119.331695 -233.874056) (xy 119.373711 -233.904582) (xy 119.410434 -233.941305)
			(xy 119.44096 -233.983321) (xy 119.464538 -234.029595) (xy 119.480586 -234.078988) (xy 119.488711 -234.130283)
			(xy 119.48922 -234.15625) (xy 119.488711 -234.182217) (xy 119.768621 -234.182217) (xy 119.768621 -234.130283)
			(xy 119.776746 -234.078988) (xy 119.792794 -234.029595) (xy 119.816372 -233.983321) (xy 119.846898 -233.941305)
			(xy 119.883621 -233.904582) (xy 119.925637 -233.874056) (xy 119.971911 -233.850478) (xy 120.021304 -233.83443)
			(xy 120.072599 -233.826305) (xy 120.124533 -233.826305) (xy 120.175828 -233.83443) (xy 120.225221 -233.850478)
			(xy 120.271495 -233.874056) (xy 120.313511 -233.904582) (xy 120.350234 -233.941305) (xy 120.38076 -233.983321)
			(xy 120.404338 -234.029595) (xy 120.420386 -234.078988) (xy 120.428511 -234.130283) (xy 120.42902 -234.15625)
			(xy 120.428511 -234.182217) (xy 120.708167 -234.182217) (xy 120.708167 -234.130283) (xy 120.716292 -234.078988)
			(xy 120.73234 -234.029595) (xy 120.755918 -233.983321) (xy 120.786444 -233.941305) (xy 120.823167 -233.904582)
			(xy 120.865183 -233.874056) (xy 120.911457 -233.850478) (xy 120.96085 -233.83443) (xy 121.012145 -233.826305)
			(xy 121.064079 -233.826305) (xy 121.115374 -233.83443) (xy 121.164767 -233.850478) (xy 121.211041 -233.874056)
			(xy 121.253057 -233.904582) (xy 121.28978 -233.941305) (xy 121.320306 -233.983321) (xy 121.343884 -234.029595)
			(xy 121.359932 -234.078988) (xy 121.368057 -234.130283) (xy 121.368566 -234.15625) (xy 121.368057 -234.182217)
			(xy 121.648221 -234.182217) (xy 121.648221 -234.130283) (xy 121.656346 -234.078988) (xy 121.672394 -234.029595)
			(xy 121.695972 -233.983321) (xy 121.726498 -233.941305) (xy 121.763221 -233.904582) (xy 121.805237 -233.874056)
			(xy 121.851511 -233.850478) (xy 121.900904 -233.83443) (xy 121.952199 -233.826305) (xy 122.004133 -233.826305)
			(xy 122.055428 -233.83443) (xy 122.104821 -233.850478) (xy 122.151095 -233.874056) (xy 122.193111 -233.904582)
			(xy 122.229834 -233.941305) (xy 122.26036 -233.983321) (xy 122.283938 -234.029595) (xy 122.299986 -234.078988)
			(xy 122.308111 -234.130283) (xy 122.30862 -234.15625) (xy 122.308111 -234.182217) (xy 122.587767 -234.182217)
			(xy 122.587767 -234.130283) (xy 122.595892 -234.078988) (xy 122.61194 -234.029595) (xy 122.635518 -233.983321)
			(xy 122.666044 -233.941305) (xy 122.702767 -233.904582) (xy 122.744783 -233.874056) (xy 122.791057 -233.850478)
			(xy 122.84045 -233.83443) (xy 122.891745 -233.826305) (xy 122.943679 -233.826305) (xy 122.994974 -233.83443)
			(xy 123.044367 -233.850478) (xy 123.090641 -233.874056) (xy 123.132657 -233.904582) (xy 123.16938 -233.941305)
			(xy 123.199906 -233.983321) (xy 123.223484 -234.029595) (xy 123.239532 -234.078988) (xy 123.247657 -234.130283)
			(xy 123.248166 -234.15625) (xy 123.247657 -234.182217) (xy 123.527821 -234.182217) (xy 123.527821 -234.130283)
			(xy 123.535946 -234.078988) (xy 123.551994 -234.029595) (xy 123.575572 -233.983321) (xy 123.606098 -233.941305)
			(xy 123.642821 -233.904582) (xy 123.684837 -233.874056) (xy 123.731111 -233.850478) (xy 123.780504 -233.83443)
			(xy 123.831799 -233.826305) (xy 123.883733 -233.826305) (xy 123.935028 -233.83443) (xy 123.984421 -233.850478)
			(xy 124.030695 -233.874056) (xy 124.072711 -233.904582) (xy 124.109434 -233.941305) (xy 124.13996 -233.983321)
			(xy 124.163538 -234.029595) (xy 124.179586 -234.078988) (xy 124.187711 -234.130283) (xy 124.18822 -234.15625)
			(xy 124.187711 -234.182217) (xy 124.467621 -234.182217) (xy 124.467621 -234.130283) (xy 124.475746 -234.078988)
			(xy 124.491794 -234.029595) (xy 124.515372 -233.983321) (xy 124.545898 -233.941305) (xy 124.582621 -233.904582)
			(xy 124.624637 -233.874056) (xy 124.670911 -233.850478) (xy 124.720304 -233.83443) (xy 124.771599 -233.826305)
			(xy 124.823533 -233.826305) (xy 124.874828 -233.83443) (xy 124.924221 -233.850478) (xy 124.970495 -233.874056)
			(xy 125.012511 -233.904582) (xy 125.049234 -233.941305) (xy 125.07976 -233.983321) (xy 125.103338 -234.029595)
			(xy 125.119386 -234.078988) (xy 125.127511 -234.130283) (xy 125.12802 -234.15625) (xy 125.127511 -234.182217)
			(xy 125.407421 -234.182217) (xy 125.407421 -234.130283) (xy 125.415546 -234.078988) (xy 125.431594 -234.029595)
			(xy 125.455172 -233.983321) (xy 125.485698 -233.941305) (xy 125.522421 -233.904582) (xy 125.564437 -233.874056)
			(xy 125.610711 -233.850478) (xy 125.660104 -233.83443) (xy 125.711399 -233.826305) (xy 125.763333 -233.826305)
			(xy 125.814628 -233.83443) (xy 125.864021 -233.850478) (xy 125.910295 -233.874056) (xy 125.952311 -233.904582)
			(xy 125.989034 -233.941305) (xy 126.01956 -233.983321) (xy 126.043138 -234.029595) (xy 126.059186 -234.078988)
			(xy 126.067311 -234.130283) (xy 126.06782 -234.15625) (xy 126.067311 -234.182217) (xy 126.347221 -234.182217)
			(xy 126.347221 -234.130283) (xy 126.355346 -234.078988) (xy 126.371394 -234.029595) (xy 126.394972 -233.983321)
			(xy 126.425498 -233.941305) (xy 126.462221 -233.904582) (xy 126.504237 -233.874056) (xy 126.550511 -233.850478)
			(xy 126.599904 -233.83443) (xy 126.651199 -233.826305) (xy 126.703133 -233.826305) (xy 126.754428 -233.83443)
			(xy 126.803821 -233.850478) (xy 126.850095 -233.874056) (xy 126.892111 -233.904582) (xy 126.928834 -233.941305)
			(xy 126.95936 -233.983321) (xy 126.982938 -234.029595) (xy 126.998986 -234.078988) (xy 127.007111 -234.130283)
			(xy 127.00762 -234.15625) (xy 127.007111 -234.182217) (xy 126.998986 -234.233512) (xy 126.982938 -234.282905)
			(xy 126.95936 -234.329179) (xy 126.928834 -234.371195) (xy 126.892111 -234.407918) (xy 126.850095 -234.438444)
			(xy 126.803821 -234.462022) (xy 126.754428 -234.47807) (xy 126.703133 -234.486195) (xy 126.651199 -234.486195)
			(xy 126.599904 -234.47807) (xy 126.550511 -234.462022) (xy 126.504237 -234.438444) (xy 126.462221 -234.407918)
			(xy 126.425498 -234.371195) (xy 126.394972 -234.329179) (xy 126.371394 -234.282905) (xy 126.355346 -234.233512)
			(xy 126.347221 -234.182217) (xy 126.067311 -234.182217) (xy 126.059186 -234.233512) (xy 126.043138 -234.282905)
			(xy 126.01956 -234.329179) (xy 125.989034 -234.371195) (xy 125.952311 -234.407918) (xy 125.910295 -234.438444)
			(xy 125.864021 -234.462022) (xy 125.814628 -234.47807) (xy 125.763333 -234.486195) (xy 125.711399 -234.486195)
			(xy 125.660104 -234.47807) (xy 125.610711 -234.462022) (xy 125.564437 -234.438444) (xy 125.522421 -234.407918)
			(xy 125.485698 -234.371195) (xy 125.455172 -234.329179) (xy 125.431594 -234.282905) (xy 125.415546 -234.233512)
			(xy 125.407421 -234.182217) (xy 125.127511 -234.182217) (xy 125.119386 -234.233512) (xy 125.103338 -234.282905)
			(xy 125.07976 -234.329179) (xy 125.049234 -234.371195) (xy 125.012511 -234.407918) (xy 124.970495 -234.438444)
			(xy 124.924221 -234.462022) (xy 124.874828 -234.47807) (xy 124.823533 -234.486195) (xy 124.771599 -234.486195)
			(xy 124.720304 -234.47807) (xy 124.670911 -234.462022) (xy 124.624637 -234.438444) (xy 124.582621 -234.407918)
			(xy 124.545898 -234.371195) (xy 124.515372 -234.329179) (xy 124.491794 -234.282905) (xy 124.475746 -234.233512)
			(xy 124.467621 -234.182217) (xy 124.187711 -234.182217) (xy 124.179586 -234.233512) (xy 124.163538 -234.282905)
			(xy 124.13996 -234.329179) (xy 124.109434 -234.371195) (xy 124.072711 -234.407918) (xy 124.030695 -234.438444)
			(xy 123.984421 -234.462022) (xy 123.935028 -234.47807) (xy 123.883733 -234.486195) (xy 123.831799 -234.486195)
			(xy 123.780504 -234.47807) (xy 123.731111 -234.462022) (xy 123.684837 -234.438444) (xy 123.642821 -234.407918)
			(xy 123.606098 -234.371195) (xy 123.575572 -234.329179) (xy 123.551994 -234.282905) (xy 123.535946 -234.233512)
			(xy 123.527821 -234.182217) (xy 123.247657 -234.182217) (xy 123.239532 -234.233512) (xy 123.223484 -234.282905)
			(xy 123.199906 -234.329179) (xy 123.16938 -234.371195) (xy 123.132657 -234.407918) (xy 123.090641 -234.438444)
			(xy 123.044367 -234.462022) (xy 122.994974 -234.47807) (xy 122.943679 -234.486195) (xy 122.891745 -234.486195)
			(xy 122.84045 -234.47807) (xy 122.791057 -234.462022) (xy 122.744783 -234.438444) (xy 122.702767 -234.407918)
			(xy 122.666044 -234.371195) (xy 122.635518 -234.329179) (xy 122.61194 -234.282905) (xy 122.595892 -234.233512)
			(xy 122.587767 -234.182217) (xy 122.308111 -234.182217) (xy 122.299986 -234.233512) (xy 122.283938 -234.282905)
			(xy 122.26036 -234.329179) (xy 122.229834 -234.371195) (xy 122.193111 -234.407918) (xy 122.151095 -234.438444)
			(xy 122.104821 -234.462022) (xy 122.055428 -234.47807) (xy 122.004133 -234.486195) (xy 121.952199 -234.486195)
			(xy 121.900904 -234.47807) (xy 121.851511 -234.462022) (xy 121.805237 -234.438444) (xy 121.763221 -234.407918)
			(xy 121.726498 -234.371195) (xy 121.695972 -234.329179) (xy 121.672394 -234.282905) (xy 121.656346 -234.233512)
			(xy 121.648221 -234.182217) (xy 121.368057 -234.182217) (xy 121.359932 -234.233512) (xy 121.343884 -234.282905)
			(xy 121.320306 -234.329179) (xy 121.28978 -234.371195) (xy 121.253057 -234.407918) (xy 121.211041 -234.438444)
			(xy 121.164767 -234.462022) (xy 121.115374 -234.47807) (xy 121.064079 -234.486195) (xy 121.012145 -234.486195)
			(xy 120.96085 -234.47807) (xy 120.911457 -234.462022) (xy 120.865183 -234.438444) (xy 120.823167 -234.407918)
			(xy 120.786444 -234.371195) (xy 120.755918 -234.329179) (xy 120.73234 -234.282905) (xy 120.716292 -234.233512)
			(xy 120.708167 -234.182217) (xy 120.428511 -234.182217) (xy 120.420386 -234.233512) (xy 120.404338 -234.282905)
			(xy 120.38076 -234.329179) (xy 120.350234 -234.371195) (xy 120.313511 -234.407918) (xy 120.271495 -234.438444)
			(xy 120.225221 -234.462022) (xy 120.175828 -234.47807) (xy 120.124533 -234.486195) (xy 120.072599 -234.486195)
			(xy 120.021304 -234.47807) (xy 119.971911 -234.462022) (xy 119.925637 -234.438444) (xy 119.883621 -234.407918)
			(xy 119.846898 -234.371195) (xy 119.816372 -234.329179) (xy 119.792794 -234.282905) (xy 119.776746 -234.233512)
			(xy 119.768621 -234.182217) (xy 119.488711 -234.182217) (xy 119.480586 -234.233512) (xy 119.464538 -234.282905)
			(xy 119.44096 -234.329179) (xy 119.410434 -234.371195) (xy 119.373711 -234.407918) (xy 119.331695 -234.438444)
			(xy 119.285421 -234.462022) (xy 119.236028 -234.47807) (xy 119.184733 -234.486195) (xy 119.132799 -234.486195)
			(xy 119.081504 -234.47807) (xy 119.032111 -234.462022) (xy 118.985837 -234.438444) (xy 118.943821 -234.407918)
			(xy 118.907098 -234.371195) (xy 118.876572 -234.329179) (xy 118.852994 -234.282905) (xy 118.836946 -234.233512)
			(xy 118.828821 -234.182217) (xy 118.548911 -234.182217) (xy 118.540786 -234.233512) (xy 118.524738 -234.282905)
			(xy 118.50116 -234.329179) (xy 118.470634 -234.371195) (xy 118.433911 -234.407918) (xy 118.391895 -234.438444)
			(xy 118.345621 -234.462022) (xy 118.296228 -234.47807) (xy 118.244933 -234.486195) (xy 118.192999 -234.486195)
			(xy 118.141704 -234.47807) (xy 118.092311 -234.462022) (xy 118.046037 -234.438444) (xy 118.004021 -234.407918)
			(xy 117.967298 -234.371195) (xy 117.936772 -234.329179) (xy 117.913194 -234.282905) (xy 117.897146 -234.233512)
			(xy 117.889021 -234.182217) (xy 117.609111 -234.182217) (xy 117.600986 -234.233512) (xy 117.584938 -234.282905)
			(xy 117.56136 -234.329179) (xy 117.530834 -234.371195) (xy 117.494111 -234.407918) (xy 117.452095 -234.438444)
			(xy 117.405821 -234.462022) (xy 117.356428 -234.47807) (xy 117.305133 -234.486195) (xy 117.253199 -234.486195)
			(xy 117.201904 -234.47807) (xy 117.152511 -234.462022) (xy 117.106237 -234.438444) (xy 117.064221 -234.407918)
			(xy 117.027498 -234.371195) (xy 116.996972 -234.329179) (xy 116.973394 -234.282905) (xy 116.957346 -234.233512)
			(xy 116.949221 -234.182217) (xy 116.669311 -234.182217) (xy 116.661186 -234.233512) (xy 116.645138 -234.282905)
			(xy 116.62156 -234.329179) (xy 116.591034 -234.371195) (xy 116.554311 -234.407918) (xy 116.512295 -234.438444)
			(xy 116.466021 -234.462022) (xy 116.416628 -234.47807) (xy 116.365333 -234.486195) (xy 116.313399 -234.486195)
			(xy 116.262104 -234.47807) (xy 116.212711 -234.462022) (xy 116.166437 -234.438444) (xy 116.124421 -234.407918)
			(xy 116.087698 -234.371195) (xy 116.057172 -234.329179) (xy 116.033594 -234.282905) (xy 116.017546 -234.233512)
			(xy 116.009421 -234.182217) (xy 115.729511 -234.182217) (xy 115.721386 -234.233512) (xy 115.705338 -234.282905)
			(xy 115.68176 -234.329179) (xy 115.651234 -234.371195) (xy 115.614511 -234.407918) (xy 115.572495 -234.438444)
			(xy 115.526221 -234.462022) (xy 115.476828 -234.47807) (xy 115.425533 -234.486195) (xy 115.373599 -234.486195)
			(xy 115.322304 -234.47807) (xy 115.272911 -234.462022) (xy 115.226637 -234.438444) (xy 115.184621 -234.407918)
			(xy 115.147898 -234.371195) (xy 115.117372 -234.329179) (xy 115.093794 -234.282905) (xy 115.077746 -234.233512)
			(xy 115.069621 -234.182217) (xy 114.789711 -234.182217) (xy 114.781586 -234.233512) (xy 114.765538 -234.282905)
			(xy 114.74196 -234.329179) (xy 114.711434 -234.371195) (xy 114.674711 -234.407918) (xy 114.632695 -234.438444)
			(xy 114.586421 -234.462022) (xy 114.537028 -234.47807) (xy 114.485733 -234.486195) (xy 114.433799 -234.486195)
			(xy 114.382504 -234.47807) (xy 114.333111 -234.462022) (xy 114.286837 -234.438444) (xy 114.244821 -234.407918)
			(xy 114.208098 -234.371195) (xy 114.177572 -234.329179) (xy 114.153994 -234.282905) (xy 114.137946 -234.233512)
			(xy 114.129821 -234.182217) (xy 113.849911 -234.182217) (xy 113.841786 -234.233512) (xy 113.825738 -234.282905)
			(xy 113.80216 -234.329179) (xy 113.771634 -234.371195) (xy 113.734911 -234.407918) (xy 113.692895 -234.438444)
			(xy 113.646621 -234.462022) (xy 113.597228 -234.47807) (xy 113.545933 -234.486195) (xy 113.493999 -234.486195)
			(xy 113.442704 -234.47807) (xy 113.393311 -234.462022) (xy 113.347037 -234.438444) (xy 113.305021 -234.407918)
			(xy 113.268298 -234.371195) (xy 113.237772 -234.329179) (xy 113.214194 -234.282905) (xy 113.198146 -234.233512)
			(xy 113.190021 -234.182217) (xy 112.910111 -234.182217) (xy 112.901986 -234.233512) (xy 112.885938 -234.282905)
			(xy 112.86236 -234.329179) (xy 112.831834 -234.371195) (xy 112.795111 -234.407918) (xy 112.753095 -234.438444)
			(xy 112.706821 -234.462022) (xy 112.657428 -234.47807) (xy 112.606133 -234.486195) (xy 112.554199 -234.486195)
			(xy 112.502904 -234.47807) (xy 112.453511 -234.462022) (xy 112.407237 -234.438444) (xy 112.365221 -234.407918)
			(xy 112.328498 -234.371195) (xy 112.297972 -234.329179) (xy 112.274394 -234.282905) (xy 112.258346 -234.233512)
			(xy 112.250221 -234.182217) (xy 111.970311 -234.182217) (xy 111.962186 -234.233512) (xy 111.946138 -234.282905)
			(xy 111.92256 -234.329179) (xy 111.892034 -234.371195) (xy 111.855311 -234.407918) (xy 111.813295 -234.438444)
			(xy 111.767021 -234.462022) (xy 111.717628 -234.47807) (xy 111.666333 -234.486195) (xy 111.614399 -234.486195)
			(xy 111.563104 -234.47807) (xy 111.513711 -234.462022) (xy 111.467437 -234.438444) (xy 111.425421 -234.407918)
			(xy 111.388698 -234.371195) (xy 111.358172 -234.329179) (xy 111.334594 -234.282905) (xy 111.318546 -234.233512)
			(xy 111.310421 -234.182217) (xy 111.030511 -234.182217) (xy 111.022386 -234.233512) (xy 111.006338 -234.282905)
			(xy 110.98276 -234.329179) (xy 110.952234 -234.371195) (xy 110.915511 -234.407918) (xy 110.873495 -234.438444)
			(xy 110.827221 -234.462022) (xy 110.777828 -234.47807) (xy 110.726533 -234.486195) (xy 110.674599 -234.486195)
			(xy 110.623304 -234.47807) (xy 110.573911 -234.462022) (xy 110.527637 -234.438444) (xy 110.485621 -234.407918)
			(xy 110.448898 -234.371195) (xy 110.418372 -234.329179) (xy 110.394794 -234.282905) (xy 110.378746 -234.233512)
			(xy 110.370621 -234.182217) (xy 110.189518 -234.182217) (xy 110.189518 -234.588812) (xy 110.189977 -234.59866)
			(xy 110.197405 -234.616901) (xy 110.211161 -234.630996) (xy 110.229216 -234.638867) (xy 110.239048 -234.639612)
			(xy 110.264599 -234.64072) (xy 110.314922 -234.649839) (xy 110.363239 -234.666599) (xy 110.4084 -234.690599)
			(xy 110.449325 -234.721268) (xy 110.485039 -234.757874) (xy 110.51469 -234.799543) (xy 110.537571 -234.845281)
			(xy 110.553135 -234.893997) (xy 110.56101 -234.944528) (xy 110.561011 -234.99567) (xy 110.560954 -234.996033)
			(xy 110.840521 -234.996033) (xy 110.840521 -234.944099) (xy 110.848646 -234.892804) (xy 110.864694 -234.843411)
			(xy 110.888272 -234.797137) (xy 110.918798 -234.755121) (xy 110.955521 -234.718398) (xy 110.997537 -234.687872)
			(xy 111.043811 -234.664294) (xy 111.093204 -234.648246) (xy 111.144499 -234.640121) (xy 111.196433 -234.640121)
			(xy 111.247728 -234.648246) (xy 111.297121 -234.664294) (xy 111.343395 -234.687872) (xy 111.385411 -234.718398)
			(xy 111.422134 -234.755121) (xy 111.45266 -234.797137) (xy 111.476238 -234.843411) (xy 111.492286 -234.892804)
			(xy 111.500411 -234.944099) (xy 111.50092 -234.970066) (xy 111.500411 -234.996033) (xy 111.780321 -234.996033)
			(xy 111.780321 -234.944099) (xy 111.788446 -234.892804) (xy 111.804494 -234.843411) (xy 111.828072 -234.797137)
			(xy 111.858598 -234.755121) (xy 111.895321 -234.718398) (xy 111.937337 -234.687872) (xy 111.983611 -234.664294)
			(xy 112.033004 -234.648246) (xy 112.084299 -234.640121) (xy 112.136233 -234.640121) (xy 112.187528 -234.648246)
			(xy 112.236921 -234.664294) (xy 112.283195 -234.687872) (xy 112.325211 -234.718398) (xy 112.361934 -234.755121)
			(xy 112.39246 -234.797137) (xy 112.416038 -234.843411) (xy 112.432086 -234.892804) (xy 112.440211 -234.944099)
			(xy 112.44072 -234.970066) (xy 112.440211 -234.996033) (xy 112.720121 -234.996033) (xy 112.720121 -234.944099)
			(xy 112.728246 -234.892804) (xy 112.744294 -234.843411) (xy 112.767872 -234.797137) (xy 112.798398 -234.755121)
			(xy 112.835121 -234.718398) (xy 112.877137 -234.687872) (xy 112.923411 -234.664294) (xy 112.972804 -234.648246)
			(xy 113.024099 -234.640121) (xy 113.076033 -234.640121) (xy 113.127328 -234.648246) (xy 113.176721 -234.664294)
			(xy 113.222995 -234.687872) (xy 113.265011 -234.718398) (xy 113.301734 -234.755121) (xy 113.33226 -234.797137)
			(xy 113.355838 -234.843411) (xy 113.371886 -234.892804) (xy 113.380011 -234.944099) (xy 113.38052 -234.970066)
			(xy 113.380011 -234.996033) (xy 113.660175 -234.996033) (xy 113.660175 -234.944099) (xy 113.6683 -234.892804)
			(xy 113.684348 -234.843411) (xy 113.707926 -234.797137) (xy 113.738452 -234.755121) (xy 113.775175 -234.718398)
			(xy 113.817191 -234.687872) (xy 113.863465 -234.664294) (xy 113.912858 -234.648246) (xy 113.964153 -234.640121)
			(xy 114.016087 -234.640121) (xy 114.067382 -234.648246) (xy 114.116775 -234.664294) (xy 114.163049 -234.687872)
			(xy 114.205065 -234.718398) (xy 114.241788 -234.755121) (xy 114.272314 -234.797137) (xy 114.295892 -234.843411)
			(xy 114.31194 -234.892804) (xy 114.320065 -234.944099) (xy 114.320574 -234.970066) (xy 114.320065 -234.996033)
			(xy 121.178067 -234.996033) (xy 121.178067 -234.944099) (xy 121.186192 -234.892804) (xy 121.20224 -234.843411)
			(xy 121.225818 -234.797137) (xy 121.256344 -234.755121) (xy 121.293067 -234.718398) (xy 121.335083 -234.687872)
			(xy 121.381357 -234.664294) (xy 121.43075 -234.648246) (xy 121.482045 -234.640121) (xy 121.533979 -234.640121)
			(xy 121.585274 -234.648246) (xy 121.634667 -234.664294) (xy 121.680941 -234.687872) (xy 121.722957 -234.718398)
			(xy 121.75968 -234.755121) (xy 121.790206 -234.797137) (xy 121.813784 -234.843411) (xy 121.829832 -234.892804)
			(xy 121.837957 -234.944099) (xy 121.838466 -234.970066) (xy 121.837957 -234.996033) (xy 122.117867 -234.996033)
			(xy 122.117867 -234.944099) (xy 122.125992 -234.892804) (xy 122.14204 -234.843411) (xy 122.165618 -234.797137)
			(xy 122.196144 -234.755121) (xy 122.232867 -234.718398) (xy 122.274883 -234.687872) (xy 122.321157 -234.664294)
			(xy 122.37055 -234.648246) (xy 122.421845 -234.640121) (xy 122.473779 -234.640121) (xy 122.525074 -234.648246)
			(xy 122.574467 -234.664294) (xy 122.620741 -234.687872) (xy 122.662757 -234.718398) (xy 122.69948 -234.755121)
			(xy 122.730006 -234.797137) (xy 122.753584 -234.843411) (xy 122.769632 -234.892804) (xy 122.777757 -234.944099)
			(xy 122.778266 -234.970066) (xy 122.777757 -234.996033) (xy 123.057667 -234.996033) (xy 123.057667 -234.944099)
			(xy 123.065792 -234.892804) (xy 123.08184 -234.843411) (xy 123.105418 -234.797137) (xy 123.135944 -234.755121)
			(xy 123.172667 -234.718398) (xy 123.214683 -234.687872) (xy 123.260957 -234.664294) (xy 123.31035 -234.648246)
			(xy 123.361645 -234.640121) (xy 123.413579 -234.640121) (xy 123.464874 -234.648246) (xy 123.514267 -234.664294)
			(xy 123.560541 -234.687872) (xy 123.602557 -234.718398) (xy 123.63928 -234.755121) (xy 123.669806 -234.797137)
			(xy 123.693384 -234.843411) (xy 123.709432 -234.892804) (xy 123.717557 -234.944099) (xy 123.718066 -234.970066)
			(xy 123.717557 -234.996033) (xy 123.997467 -234.996033) (xy 123.997467 -234.944099) (xy 124.005592 -234.892804)
			(xy 124.02164 -234.843411) (xy 124.045218 -234.797137) (xy 124.075744 -234.755121) (xy 124.112467 -234.718398)
			(xy 124.154483 -234.687872) (xy 124.200757 -234.664294) (xy 124.25015 -234.648246) (xy 124.301445 -234.640121)
			(xy 124.353379 -234.640121) (xy 124.404674 -234.648246) (xy 124.454067 -234.664294) (xy 124.500341 -234.687872)
			(xy 124.542357 -234.718398) (xy 124.57908 -234.755121) (xy 124.609606 -234.797137) (xy 124.633184 -234.843411)
			(xy 124.649232 -234.892804) (xy 124.657357 -234.944099) (xy 124.657866 -234.970066) (xy 124.657357 -234.996033)
			(xy 124.937521 -234.996033) (xy 124.937521 -234.944099) (xy 124.945646 -234.892804) (xy 124.961694 -234.843411)
			(xy 124.985272 -234.797137) (xy 125.015798 -234.755121) (xy 125.052521 -234.718398) (xy 125.094537 -234.687872)
			(xy 125.140811 -234.664294) (xy 125.190204 -234.648246) (xy 125.241499 -234.640121) (xy 125.293433 -234.640121)
			(xy 125.344728 -234.648246) (xy 125.394121 -234.664294) (xy 125.440395 -234.687872) (xy 125.482411 -234.718398)
			(xy 125.519134 -234.755121) (xy 125.54966 -234.797137) (xy 125.573238 -234.843411) (xy 125.589286 -234.892804)
			(xy 125.597411 -234.944099) (xy 125.59792 -234.970066) (xy 125.597411 -234.996033) (xy 125.877067 -234.996033)
			(xy 125.877067 -234.944099) (xy 125.885192 -234.892804) (xy 125.90124 -234.843411) (xy 125.924818 -234.797137)
			(xy 125.955344 -234.755121) (xy 125.992067 -234.718398) (xy 126.034083 -234.687872) (xy 126.080357 -234.664294)
			(xy 126.12975 -234.648246) (xy 126.181045 -234.640121) (xy 126.232979 -234.640121) (xy 126.284274 -234.648246)
			(xy 126.333667 -234.664294) (xy 126.379941 -234.687872) (xy 126.421957 -234.718398) (xy 126.45868 -234.755121)
			(xy 126.489206 -234.797137) (xy 126.512784 -234.843411) (xy 126.528832 -234.892804) (xy 126.536957 -234.944099)
			(xy 126.537466 -234.970066) (xy 126.536957 -234.996033) (xy 126.816867 -234.996033) (xy 126.816867 -234.944099)
			(xy 126.824992 -234.892804) (xy 126.84104 -234.843411) (xy 126.864618 -234.797137) (xy 126.895144 -234.755121)
			(xy 126.931867 -234.718398) (xy 126.973883 -234.687872) (xy 127.020157 -234.664294) (xy 127.06955 -234.648246)
			(xy 127.120845 -234.640121) (xy 127.172779 -234.640121) (xy 127.224074 -234.648246) (xy 127.273467 -234.664294)
			(xy 127.319741 -234.687872) (xy 127.361757 -234.718398) (xy 127.39848 -234.755121) (xy 127.429006 -234.797137)
			(xy 127.452584 -234.843411) (xy 127.468632 -234.892804) (xy 127.476757 -234.944099) (xy 127.477266 -234.970066)
			(xy 127.476757 -234.996033) (xy 127.468632 -235.047328) (xy 127.452584 -235.096721) (xy 127.429006 -235.142995)
			(xy 127.39848 -235.185011) (xy 127.361757 -235.221734) (xy 127.319741 -235.25226) (xy 127.273467 -235.275838)
			(xy 127.224074 -235.291886) (xy 127.172779 -235.300011) (xy 127.120845 -235.300011) (xy 127.06955 -235.291886)
			(xy 127.020157 -235.275838) (xy 126.973883 -235.25226) (xy 126.931867 -235.221734) (xy 126.895144 -235.185011)
			(xy 126.864618 -235.142995) (xy 126.84104 -235.096721) (xy 126.824992 -235.047328) (xy 126.816867 -234.996033)
			(xy 126.536957 -234.996033) (xy 126.528832 -235.047328) (xy 126.512784 -235.096721) (xy 126.489206 -235.142995)
			(xy 126.45868 -235.185011) (xy 126.421957 -235.221734) (xy 126.379941 -235.25226) (xy 126.333667 -235.275838)
			(xy 126.284274 -235.291886) (xy 126.232979 -235.300011) (xy 126.181045 -235.300011) (xy 126.12975 -235.291886)
			(xy 126.080357 -235.275838) (xy 126.034083 -235.25226) (xy 125.992067 -235.221734) (xy 125.955344 -235.185011)
			(xy 125.924818 -235.142995) (xy 125.90124 -235.096721) (xy 125.885192 -235.047328) (xy 125.877067 -234.996033)
			(xy 125.597411 -234.996033) (xy 125.589286 -235.047328) (xy 125.573238 -235.096721) (xy 125.54966 -235.142995)
			(xy 125.519134 -235.185011) (xy 125.482411 -235.221734) (xy 125.440395 -235.25226) (xy 125.394121 -235.275838)
			(xy 125.344728 -235.291886) (xy 125.293433 -235.300011) (xy 125.241499 -235.300011) (xy 125.190204 -235.291886)
			(xy 125.140811 -235.275838) (xy 125.094537 -235.25226) (xy 125.052521 -235.221734) (xy 125.015798 -235.185011)
			(xy 124.985272 -235.142995) (xy 124.961694 -235.096721) (xy 124.945646 -235.047328) (xy 124.937521 -234.996033)
			(xy 124.657357 -234.996033) (xy 124.649232 -235.047328) (xy 124.633184 -235.096721) (xy 124.609606 -235.142995)
			(xy 124.57908 -235.185011) (xy 124.542357 -235.221734) (xy 124.500341 -235.25226) (xy 124.454067 -235.275838)
			(xy 124.404674 -235.291886) (xy 124.353379 -235.300011) (xy 124.301445 -235.300011) (xy 124.25015 -235.291886)
			(xy 124.200757 -235.275838) (xy 124.154483 -235.25226) (xy 124.112467 -235.221734) (xy 124.075744 -235.185011)
			(xy 124.045218 -235.142995) (xy 124.02164 -235.096721) (xy 124.005592 -235.047328) (xy 123.997467 -234.996033)
			(xy 123.717557 -234.996033) (xy 123.709432 -235.047328) (xy 123.693384 -235.096721) (xy 123.669806 -235.142995)
			(xy 123.63928 -235.185011) (xy 123.602557 -235.221734) (xy 123.560541 -235.25226) (xy 123.514267 -235.275838)
			(xy 123.464874 -235.291886) (xy 123.413579 -235.300011) (xy 123.361645 -235.300011) (xy 123.31035 -235.291886)
			(xy 123.260957 -235.275838) (xy 123.214683 -235.25226) (xy 123.172667 -235.221734) (xy 123.135944 -235.185011)
			(xy 123.105418 -235.142995) (xy 123.08184 -235.096721) (xy 123.065792 -235.047328) (xy 123.057667 -234.996033)
			(xy 122.777757 -234.996033) (xy 122.769632 -235.047328) (xy 122.753584 -235.096721) (xy 122.730006 -235.142995)
			(xy 122.69948 -235.185011) (xy 122.662757 -235.221734) (xy 122.620741 -235.25226) (xy 122.574467 -235.275838)
			(xy 122.525074 -235.291886) (xy 122.473779 -235.300011) (xy 122.421845 -235.300011) (xy 122.37055 -235.291886)
			(xy 122.321157 -235.275838) (xy 122.274883 -235.25226) (xy 122.232867 -235.221734) (xy 122.196144 -235.185011)
			(xy 122.165618 -235.142995) (xy 122.14204 -235.096721) (xy 122.125992 -235.047328) (xy 122.117867 -234.996033)
			(xy 121.837957 -234.996033) (xy 121.829832 -235.047328) (xy 121.813784 -235.096721) (xy 121.790206 -235.142995)
			(xy 121.75968 -235.185011) (xy 121.722957 -235.221734) (xy 121.680941 -235.25226) (xy 121.634667 -235.275838)
			(xy 121.585274 -235.291886) (xy 121.533979 -235.300011) (xy 121.482045 -235.300011) (xy 121.43075 -235.291886)
			(xy 121.381357 -235.275838) (xy 121.335083 -235.25226) (xy 121.293067 -235.221734) (xy 121.256344 -235.185011)
			(xy 121.225818 -235.142995) (xy 121.20224 -235.096721) (xy 121.186192 -235.047328) (xy 121.178067 -234.996033)
			(xy 114.320065 -234.996033) (xy 114.31194 -235.047328) (xy 114.295892 -235.096721) (xy 114.272314 -235.142995)
			(xy 114.241788 -235.185011) (xy 114.205065 -235.221734) (xy 114.163049 -235.25226) (xy 114.116775 -235.275838)
			(xy 114.067382 -235.291886) (xy 114.016087 -235.300011) (xy 113.964153 -235.300011) (xy 113.912858 -235.291886)
			(xy 113.863465 -235.275838) (xy 113.817191 -235.25226) (xy 113.775175 -235.221734) (xy 113.738452 -235.185011)
			(xy 113.707926 -235.142995) (xy 113.684348 -235.096721) (xy 113.6683 -235.047328) (xy 113.660175 -234.996033)
			(xy 113.380011 -234.996033) (xy 113.371886 -235.047328) (xy 113.355838 -235.096721) (xy 113.33226 -235.142995)
			(xy 113.301734 -235.185011) (xy 113.265011 -235.221734) (xy 113.222995 -235.25226) (xy 113.176721 -235.275838)
			(xy 113.127328 -235.291886) (xy 113.076033 -235.300011) (xy 113.024099 -235.300011) (xy 112.972804 -235.291886)
			(xy 112.923411 -235.275838) (xy 112.877137 -235.25226) (xy 112.835121 -235.221734) (xy 112.798398 -235.185011)
			(xy 112.767872 -235.142995) (xy 112.744294 -235.096721) (xy 112.728246 -235.047328) (xy 112.720121 -234.996033)
			(xy 112.440211 -234.996033) (xy 112.432086 -235.047328) (xy 112.416038 -235.096721) (xy 112.39246 -235.142995)
			(xy 112.361934 -235.185011) (xy 112.325211 -235.221734) (xy 112.283195 -235.25226) (xy 112.236921 -235.275838)
			(xy 112.187528 -235.291886) (xy 112.136233 -235.300011) (xy 112.084299 -235.300011) (xy 112.033004 -235.291886)
			(xy 111.983611 -235.275838) (xy 111.937337 -235.25226) (xy 111.895321 -235.221734) (xy 111.858598 -235.185011)
			(xy 111.828072 -235.142995) (xy 111.804494 -235.096721) (xy 111.788446 -235.047328) (xy 111.780321 -234.996033)
			(xy 111.500411 -234.996033) (xy 111.492286 -235.047328) (xy 111.476238 -235.096721) (xy 111.45266 -235.142995)
			(xy 111.422134 -235.185011) (xy 111.385411 -235.221734) (xy 111.343395 -235.25226) (xy 111.297121 -235.275838)
			(xy 111.247728 -235.291886) (xy 111.196433 -235.300011) (xy 111.144499 -235.300011) (xy 111.093204 -235.291886)
			(xy 111.043811 -235.275838) (xy 110.997537 -235.25226) (xy 110.955521 -235.221734) (xy 110.918798 -235.185011)
			(xy 110.888272 -235.142995) (xy 110.864694 -235.096721) (xy 110.848646 -235.047328) (xy 110.840521 -234.996033)
			(xy 110.560954 -234.996033) (xy 110.553135 -235.046202) (xy 110.537571 -235.094918) (xy 110.514691 -235.140656)
			(xy 110.48504 -235.182325) (xy 110.449326 -235.218931) (xy 110.408401 -235.2496) (xy 110.363241 -235.273601)
			(xy 110.314923 -235.290361) (xy 110.264601 -235.29948) (xy 110.239048 -235.30052) (xy 110.229208 -235.301221)
			(xy 110.211143 -235.3091) (xy 110.197383 -235.323209) (xy 110.189959 -235.341466) (xy 110.189518 -235.35132)
			(xy 110.189518 -235.809849) (xy 110.370875 -235.809849) (xy 110.370875 -235.757915) (xy 110.379 -235.70662)
			(xy 110.395048 -235.657227) (xy 110.418626 -235.610953) (xy 110.449152 -235.568937) (xy 110.485875 -235.532214)
			(xy 110.527891 -235.501688) (xy 110.574165 -235.47811) (xy 110.623558 -235.462062) (xy 110.674853 -235.453937)
			(xy 110.726787 -235.453937) (xy 110.778082 -235.462062) (xy 110.827475 -235.47811) (xy 110.873749 -235.501688)
			(xy 110.915765 -235.532214) (xy 110.952488 -235.568937) (xy 110.983014 -235.610953) (xy 111.006592 -235.657227)
			(xy 111.02264 -235.70662) (xy 111.030765 -235.757915) (xy 111.031274 -235.783882) (xy 111.030765 -235.809849)
			(xy 111.310675 -235.809849) (xy 111.310675 -235.757915) (xy 111.3188 -235.70662) (xy 111.334848 -235.657227)
			(xy 111.358426 -235.610953) (xy 111.388952 -235.568937) (xy 111.425675 -235.532214) (xy 111.467691 -235.501688)
			(xy 111.513965 -235.47811) (xy 111.563358 -235.462062) (xy 111.614653 -235.453937) (xy 111.666587 -235.453937)
			(xy 111.717882 -235.462062) (xy 111.767275 -235.47811) (xy 111.813549 -235.501688) (xy 111.855565 -235.532214)
			(xy 111.892288 -235.568937) (xy 111.922814 -235.610953) (xy 111.946392 -235.657227) (xy 111.96244 -235.70662)
			(xy 111.970565 -235.757915) (xy 111.971074 -235.783882) (xy 111.970565 -235.809849) (xy 112.250475 -235.809849)
			(xy 112.250475 -235.757915) (xy 112.2586 -235.70662) (xy 112.274648 -235.657227) (xy 112.298226 -235.610953)
			(xy 112.328752 -235.568937) (xy 112.365475 -235.532214) (xy 112.407491 -235.501688) (xy 112.453765 -235.47811)
			(xy 112.503158 -235.462062) (xy 112.554453 -235.453937) (xy 112.606387 -235.453937) (xy 112.657682 -235.462062)
			(xy 112.707075 -235.47811) (xy 112.753349 -235.501688) (xy 112.795365 -235.532214) (xy 112.832088 -235.568937)
			(xy 112.862614 -235.610953) (xy 112.886192 -235.657227) (xy 112.90224 -235.70662) (xy 112.910365 -235.757915)
			(xy 112.910874 -235.783882) (xy 112.910365 -235.809849) (xy 113.190275 -235.809849) (xy 113.190275 -235.757915)
			(xy 113.1984 -235.70662) (xy 113.214448 -235.657227) (xy 113.238026 -235.610953) (xy 113.268552 -235.568937)
			(xy 113.305275 -235.532214) (xy 113.347291 -235.501688) (xy 113.393565 -235.47811) (xy 113.442958 -235.462062)
			(xy 113.494253 -235.453937) (xy 113.546187 -235.453937) (xy 113.597482 -235.462062) (xy 113.646875 -235.47811)
			(xy 113.693149 -235.501688) (xy 113.735165 -235.532214) (xy 113.771888 -235.568937) (xy 113.802414 -235.610953)
			(xy 113.825992 -235.657227) (xy 113.84204 -235.70662) (xy 113.850165 -235.757915) (xy 113.850674 -235.783882)
			(xy 113.850165 -235.809849) (xy 114.130075 -235.809849) (xy 114.130075 -235.757915) (xy 114.1382 -235.70662)
			(xy 114.154248 -235.657227) (xy 114.177826 -235.610953) (xy 114.208352 -235.568937) (xy 114.245075 -235.532214)
			(xy 114.287091 -235.501688) (xy 114.333365 -235.47811) (xy 114.382758 -235.462062) (xy 114.434053 -235.453937)
			(xy 114.485987 -235.453937) (xy 114.537282 -235.462062) (xy 114.586675 -235.47811) (xy 114.632949 -235.501688)
			(xy 114.674965 -235.532214) (xy 114.711688 -235.568937) (xy 114.742214 -235.610953) (xy 114.765792 -235.657227)
			(xy 114.78184 -235.70662) (xy 114.789965 -235.757915) (xy 114.790474 -235.783882) (xy 114.789965 -235.809849)
			(xy 121.648221 -235.809849) (xy 121.648221 -235.757915) (xy 121.656346 -235.70662) (xy 121.672394 -235.657227)
			(xy 121.695972 -235.610953) (xy 121.726498 -235.568937) (xy 121.763221 -235.532214) (xy 121.805237 -235.501688)
			(xy 121.851511 -235.47811) (xy 121.900904 -235.462062) (xy 121.952199 -235.453937) (xy 122.004133 -235.453937)
			(xy 122.055428 -235.462062) (xy 122.104821 -235.47811) (xy 122.151095 -235.501688) (xy 122.193111 -235.532214)
			(xy 122.229834 -235.568937) (xy 122.26036 -235.610953) (xy 122.283938 -235.657227) (xy 122.299986 -235.70662)
			(xy 122.308111 -235.757915) (xy 122.30862 -235.783882) (xy 122.308111 -235.809849) (xy 122.588021 -235.809849)
			(xy 122.588021 -235.757915) (xy 122.596146 -235.70662) (xy 122.612194 -235.657227) (xy 122.635772 -235.610953)
			(xy 122.666298 -235.568937) (xy 122.703021 -235.532214) (xy 122.745037 -235.501688) (xy 122.791311 -235.47811)
			(xy 122.840704 -235.462062) (xy 122.891999 -235.453937) (xy 122.943933 -235.453937) (xy 122.995228 -235.462062)
			(xy 123.044621 -235.47811) (xy 123.090895 -235.501688) (xy 123.132911 -235.532214) (xy 123.169634 -235.568937)
			(xy 123.20016 -235.610953) (xy 123.223738 -235.657227) (xy 123.239786 -235.70662) (xy 123.247911 -235.757915)
			(xy 123.24842 -235.783882) (xy 123.247911 -235.809849) (xy 123.527821 -235.809849) (xy 123.527821 -235.757915)
			(xy 123.535946 -235.70662) (xy 123.551994 -235.657227) (xy 123.575572 -235.610953) (xy 123.606098 -235.568937)
			(xy 123.642821 -235.532214) (xy 123.684837 -235.501688) (xy 123.731111 -235.47811) (xy 123.780504 -235.462062)
			(xy 123.831799 -235.453937) (xy 123.883733 -235.453937) (xy 123.935028 -235.462062) (xy 123.984421 -235.47811)
			(xy 124.030695 -235.501688) (xy 124.072711 -235.532214) (xy 124.109434 -235.568937) (xy 124.13996 -235.610953)
			(xy 124.163538 -235.657227) (xy 124.179586 -235.70662) (xy 124.187711 -235.757915) (xy 124.18822 -235.783882)
			(xy 124.187711 -235.809849) (xy 124.467621 -235.809849) (xy 124.467621 -235.757915) (xy 124.475746 -235.70662)
			(xy 124.491794 -235.657227) (xy 124.515372 -235.610953) (xy 124.545898 -235.568937) (xy 124.582621 -235.532214)
			(xy 124.624637 -235.501688) (xy 124.670911 -235.47811) (xy 124.720304 -235.462062) (xy 124.771599 -235.453937)
			(xy 124.823533 -235.453937) (xy 124.874828 -235.462062) (xy 124.924221 -235.47811) (xy 124.970495 -235.501688)
			(xy 125.012511 -235.532214) (xy 125.049234 -235.568937) (xy 125.07976 -235.610953) (xy 125.103338 -235.657227)
			(xy 125.119386 -235.70662) (xy 125.127511 -235.757915) (xy 125.12802 -235.783882) (xy 125.127511 -235.809849)
			(xy 125.407167 -235.809849) (xy 125.407167 -235.757915) (xy 125.415292 -235.70662) (xy 125.43134 -235.657227)
			(xy 125.454918 -235.610953) (xy 125.485444 -235.568937) (xy 125.522167 -235.532214) (xy 125.564183 -235.501688)
			(xy 125.610457 -235.47811) (xy 125.65985 -235.462062) (xy 125.711145 -235.453937) (xy 125.763079 -235.453937)
			(xy 125.814374 -235.462062) (xy 125.863767 -235.47811) (xy 125.910041 -235.501688) (xy 125.952057 -235.532214)
			(xy 125.98878 -235.568937) (xy 126.019306 -235.610953) (xy 126.042884 -235.657227) (xy 126.058932 -235.70662)
			(xy 126.067057 -235.757915) (xy 126.067566 -235.783882) (xy 126.067057 -235.809849) (xy 126.347221 -235.809849)
			(xy 126.347221 -235.757915) (xy 126.355346 -235.70662) (xy 126.371394 -235.657227) (xy 126.394972 -235.610953)
			(xy 126.425498 -235.568937) (xy 126.462221 -235.532214) (xy 126.504237 -235.501688) (xy 126.550511 -235.47811)
			(xy 126.599904 -235.462062) (xy 126.651199 -235.453937) (xy 126.703133 -235.453937) (xy 126.754428 -235.462062)
			(xy 126.803821 -235.47811) (xy 126.850095 -235.501688) (xy 126.892111 -235.532214) (xy 126.928834 -235.568937)
			(xy 126.95936 -235.610953) (xy 126.982938 -235.657227) (xy 126.998986 -235.70662) (xy 127.007111 -235.757915)
			(xy 127.00762 -235.783882) (xy 127.007111 -235.809849) (xy 126.998986 -235.861144) (xy 126.982938 -235.910537)
			(xy 126.95936 -235.956811) (xy 126.928834 -235.998827) (xy 126.892111 -236.03555) (xy 126.850095 -236.066076)
			(xy 126.803821 -236.089654) (xy 126.754428 -236.105702) (xy 126.703133 -236.113827) (xy 126.651199 -236.113827)
			(xy 126.599904 -236.105702) (xy 126.550511 -236.089654) (xy 126.504237 -236.066076) (xy 126.462221 -236.03555)
			(xy 126.425498 -235.998827) (xy 126.394972 -235.956811) (xy 126.371394 -235.910537) (xy 126.355346 -235.861144)
			(xy 126.347221 -235.809849) (xy 126.067057 -235.809849) (xy 126.058932 -235.861144) (xy 126.042884 -235.910537)
			(xy 126.019306 -235.956811) (xy 125.98878 -235.998827) (xy 125.952057 -236.03555) (xy 125.910041 -236.066076)
			(xy 125.863767 -236.089654) (xy 125.814374 -236.105702) (xy 125.763079 -236.113827) (xy 125.711145 -236.113827)
			(xy 125.65985 -236.105702) (xy 125.610457 -236.089654) (xy 125.564183 -236.066076) (xy 125.522167 -236.03555)
			(xy 125.485444 -235.998827) (xy 125.454918 -235.956811) (xy 125.43134 -235.910537) (xy 125.415292 -235.861144)
			(xy 125.407167 -235.809849) (xy 125.127511 -235.809849) (xy 125.119386 -235.861144) (xy 125.103338 -235.910537)
			(xy 125.07976 -235.956811) (xy 125.049234 -235.998827) (xy 125.012511 -236.03555) (xy 124.970495 -236.066076)
			(xy 124.924221 -236.089654) (xy 124.874828 -236.105702) (xy 124.823533 -236.113827) (xy 124.771599 -236.113827)
			(xy 124.720304 -236.105702) (xy 124.670911 -236.089654) (xy 124.624637 -236.066076) (xy 124.582621 -236.03555)
			(xy 124.545898 -235.998827) (xy 124.515372 -235.956811) (xy 124.491794 -235.910537) (xy 124.475746 -235.861144)
			(xy 124.467621 -235.809849) (xy 124.187711 -235.809849) (xy 124.179586 -235.861144) (xy 124.163538 -235.910537)
			(xy 124.13996 -235.956811) (xy 124.109434 -235.998827) (xy 124.072711 -236.03555) (xy 124.030695 -236.066076)
			(xy 123.984421 -236.089654) (xy 123.935028 -236.105702) (xy 123.883733 -236.113827) (xy 123.831799 -236.113827)
			(xy 123.780504 -236.105702) (xy 123.731111 -236.089654) (xy 123.684837 -236.066076) (xy 123.642821 -236.03555)
			(xy 123.606098 -235.998827) (xy 123.575572 -235.956811) (xy 123.551994 -235.910537) (xy 123.535946 -235.861144)
			(xy 123.527821 -235.809849) (xy 123.247911 -235.809849) (xy 123.239786 -235.861144) (xy 123.223738 -235.910537)
			(xy 123.20016 -235.956811) (xy 123.169634 -235.998827) (xy 123.132911 -236.03555) (xy 123.090895 -236.066076)
			(xy 123.044621 -236.089654) (xy 122.995228 -236.105702) (xy 122.943933 -236.113827) (xy 122.891999 -236.113827)
			(xy 122.840704 -236.105702) (xy 122.791311 -236.089654) (xy 122.745037 -236.066076) (xy 122.703021 -236.03555)
			(xy 122.666298 -235.998827) (xy 122.635772 -235.956811) (xy 122.612194 -235.910537) (xy 122.596146 -235.861144)
			(xy 122.588021 -235.809849) (xy 122.308111 -235.809849) (xy 122.299986 -235.861144) (xy 122.283938 -235.910537)
			(xy 122.26036 -235.956811) (xy 122.229834 -235.998827) (xy 122.193111 -236.03555) (xy 122.151095 -236.066076)
			(xy 122.104821 -236.089654) (xy 122.055428 -236.105702) (xy 122.004133 -236.113827) (xy 121.952199 -236.113827)
			(xy 121.900904 -236.105702) (xy 121.851511 -236.089654) (xy 121.805237 -236.066076) (xy 121.763221 -236.03555)
			(xy 121.726498 -235.998827) (xy 121.695972 -235.956811) (xy 121.672394 -235.910537) (xy 121.656346 -235.861144)
			(xy 121.648221 -235.809849) (xy 114.789965 -235.809849) (xy 114.78184 -235.861144) (xy 114.765792 -235.910537)
			(xy 114.742214 -235.956811) (xy 114.711688 -235.998827) (xy 114.674965 -236.03555) (xy 114.632949 -236.066076)
			(xy 114.586675 -236.089654) (xy 114.537282 -236.105702) (xy 114.485987 -236.113827) (xy 114.434053 -236.113827)
			(xy 114.382758 -236.105702) (xy 114.333365 -236.089654) (xy 114.287091 -236.066076) (xy 114.245075 -236.03555)
			(xy 114.208352 -235.998827) (xy 114.177826 -235.956811) (xy 114.154248 -235.910537) (xy 114.1382 -235.861144)
			(xy 114.130075 -235.809849) (xy 113.850165 -235.809849) (xy 113.84204 -235.861144) (xy 113.825992 -235.910537)
			(xy 113.802414 -235.956811) (xy 113.771888 -235.998827) (xy 113.735165 -236.03555) (xy 113.693149 -236.066076)
			(xy 113.646875 -236.089654) (xy 113.597482 -236.105702) (xy 113.546187 -236.113827) (xy 113.494253 -236.113827)
			(xy 113.442958 -236.105702) (xy 113.393565 -236.089654) (xy 113.347291 -236.066076) (xy 113.305275 -236.03555)
			(xy 113.268552 -235.998827) (xy 113.238026 -235.956811) (xy 113.214448 -235.910537) (xy 113.1984 -235.861144)
			(xy 113.190275 -235.809849) (xy 112.910365 -235.809849) (xy 112.90224 -235.861144) (xy 112.886192 -235.910537)
			(xy 112.862614 -235.956811) (xy 112.832088 -235.998827) (xy 112.795365 -236.03555) (xy 112.753349 -236.066076)
			(xy 112.707075 -236.089654) (xy 112.657682 -236.105702) (xy 112.606387 -236.113827) (xy 112.554453 -236.113827)
			(xy 112.503158 -236.105702) (xy 112.453765 -236.089654) (xy 112.407491 -236.066076) (xy 112.365475 -236.03555)
			(xy 112.328752 -235.998827) (xy 112.298226 -235.956811) (xy 112.274648 -235.910537) (xy 112.2586 -235.861144)
			(xy 112.250475 -235.809849) (xy 111.970565 -235.809849) (xy 111.96244 -235.861144) (xy 111.946392 -235.910537)
			(xy 111.922814 -235.956811) (xy 111.892288 -235.998827) (xy 111.855565 -236.03555) (xy 111.813549 -236.066076)
			(xy 111.767275 -236.089654) (xy 111.717882 -236.105702) (xy 111.666587 -236.113827) (xy 111.614653 -236.113827)
			(xy 111.563358 -236.105702) (xy 111.513965 -236.089654) (xy 111.467691 -236.066076) (xy 111.425675 -236.03555)
			(xy 111.388952 -235.998827) (xy 111.358426 -235.956811) (xy 111.334848 -235.910537) (xy 111.3188 -235.861144)
			(xy 111.310675 -235.809849) (xy 111.030765 -235.809849) (xy 111.02264 -235.861144) (xy 111.006592 -235.910537)
			(xy 110.983014 -235.956811) (xy 110.952488 -235.998827) (xy 110.915765 -236.03555) (xy 110.873749 -236.066076)
			(xy 110.827475 -236.089654) (xy 110.778082 -236.105702) (xy 110.726787 -236.113827) (xy 110.674853 -236.113827)
			(xy 110.623558 -236.105702) (xy 110.574165 -236.089654) (xy 110.527891 -236.066076) (xy 110.485875 -236.03555)
			(xy 110.449152 -235.998827) (xy 110.418626 -235.956811) (xy 110.395048 -235.910537) (xy 110.379 -235.861144)
			(xy 110.370875 -235.809849) (xy 110.189518 -235.809849) (xy 110.189518 -236.216444) (xy 110.189983 -236.226287)
			(xy 110.197417 -236.244518) (xy 110.211172 -236.258603) (xy 110.22922 -236.266468) (xy 110.239048 -236.267244)
			(xy 110.264596 -236.268345) (xy 110.314913 -236.277453) (xy 110.363226 -236.294205) (xy 110.408381 -236.318201)
			(xy 110.449299 -236.348869) (xy 110.485002 -236.385475) (xy 110.514639 -236.427146) (xy 110.537501 -236.472885)
			(xy 110.553042 -236.521601) (xy 110.560891 -236.57213) (xy 110.561374 -236.597698) (xy 110.560942 -236.621445)
			(xy 110.560619 -236.623665) (xy 110.840521 -236.623665) (xy 110.840521 -236.571731) (xy 110.848646 -236.520436)
			(xy 110.864694 -236.471043) (xy 110.888272 -236.424769) (xy 110.918798 -236.382753) (xy 110.955521 -236.34603)
			(xy 110.997537 -236.315504) (xy 111.043811 -236.291926) (xy 111.093204 -236.275878) (xy 111.144499 -236.267753)
			(xy 111.196433 -236.267753) (xy 111.247728 -236.275878) (xy 111.297121 -236.291926) (xy 111.343395 -236.315504)
			(xy 111.385411 -236.34603) (xy 111.422134 -236.382753) (xy 111.45266 -236.424769) (xy 111.476238 -236.471043)
			(xy 111.492286 -236.520436) (xy 111.500411 -236.571731) (xy 111.50092 -236.597698) (xy 111.500411 -236.623665)
			(xy 111.780321 -236.623665) (xy 111.780321 -236.571731) (xy 111.788446 -236.520436) (xy 111.804494 -236.471043)
			(xy 111.828072 -236.424769) (xy 111.858598 -236.382753) (xy 111.895321 -236.34603) (xy 111.937337 -236.315504)
			(xy 111.983611 -236.291926) (xy 112.033004 -236.275878) (xy 112.084299 -236.267753) (xy 112.136233 -236.267753)
			(xy 112.187528 -236.275878) (xy 112.236921 -236.291926) (xy 112.283195 -236.315504) (xy 112.325211 -236.34603)
			(xy 112.361934 -236.382753) (xy 112.39246 -236.424769) (xy 112.416038 -236.471043) (xy 112.432086 -236.520436)
			(xy 112.440211 -236.571731) (xy 112.44072 -236.597698) (xy 112.440211 -236.623665) (xy 112.720121 -236.623665)
			(xy 112.720121 -236.571731) (xy 112.728246 -236.520436) (xy 112.744294 -236.471043) (xy 112.767872 -236.424769)
			(xy 112.798398 -236.382753) (xy 112.835121 -236.34603) (xy 112.877137 -236.315504) (xy 112.923411 -236.291926)
			(xy 112.972804 -236.275878) (xy 113.024099 -236.267753) (xy 113.076033 -236.267753) (xy 113.127328 -236.275878)
			(xy 113.176721 -236.291926) (xy 113.222995 -236.315504) (xy 113.265011 -236.34603) (xy 113.301734 -236.382753)
			(xy 113.33226 -236.424769) (xy 113.355838 -236.471043) (xy 113.371886 -236.520436) (xy 113.380011 -236.571731)
			(xy 113.38052 -236.597698) (xy 113.380011 -236.623665) (xy 113.660175 -236.623665) (xy 113.660175 -236.571731)
			(xy 113.6683 -236.520436) (xy 113.684348 -236.471043) (xy 113.707926 -236.424769) (xy 113.738452 -236.382753)
			(xy 113.775175 -236.34603) (xy 113.817191 -236.315504) (xy 113.863465 -236.291926) (xy 113.912858 -236.275878)
			(xy 113.964153 -236.267753) (xy 114.016087 -236.267753) (xy 114.067382 -236.275878) (xy 114.116775 -236.291926)
			(xy 114.163049 -236.315504) (xy 114.205065 -236.34603) (xy 114.241788 -236.382753) (xy 114.272314 -236.424769)
			(xy 114.295892 -236.471043) (xy 114.31194 -236.520436) (xy 114.320065 -236.571731) (xy 114.320574 -236.597698)
			(xy 114.320065 -236.623665) (xy 114.31194 -236.67496) (xy 114.295892 -236.724353) (xy 114.272314 -236.770627)
			(xy 114.241788 -236.812643) (xy 114.205065 -236.849366) (xy 114.163049 -236.879892) (xy 114.116775 -236.90347)
			(xy 114.067382 -236.919518) (xy 114.016087 -236.927643) (xy 113.964153 -236.927643) (xy 113.912858 -236.919518)
			(xy 113.863465 -236.90347) (xy 113.817191 -236.879892) (xy 113.775175 -236.849366) (xy 113.738452 -236.812643)
			(xy 113.707926 -236.770627) (xy 113.684348 -236.724353) (xy 113.6683 -236.67496) (xy 113.660175 -236.623665)
			(xy 113.380011 -236.623665) (xy 113.371886 -236.67496) (xy 113.355838 -236.724353) (xy 113.33226 -236.770627)
			(xy 113.301734 -236.812643) (xy 113.265011 -236.849366) (xy 113.222995 -236.879892) (xy 113.176721 -236.90347)
			(xy 113.127328 -236.919518) (xy 113.076033 -236.927643) (xy 113.024099 -236.927643) (xy 112.972804 -236.919518)
			(xy 112.923411 -236.90347) (xy 112.877137 -236.879892) (xy 112.835121 -236.849366) (xy 112.798398 -236.812643)
			(xy 112.767872 -236.770627) (xy 112.744294 -236.724353) (xy 112.728246 -236.67496) (xy 112.720121 -236.623665)
			(xy 112.440211 -236.623665) (xy 112.432086 -236.67496) (xy 112.416038 -236.724353) (xy 112.39246 -236.770627)
			(xy 112.361934 -236.812643) (xy 112.325211 -236.849366) (xy 112.283195 -236.879892) (xy 112.236921 -236.90347)
			(xy 112.187528 -236.919518) (xy 112.136233 -236.927643) (xy 112.084299 -236.927643) (xy 112.033004 -236.919518)
			(xy 111.983611 -236.90347) (xy 111.937337 -236.879892) (xy 111.895321 -236.849366) (xy 111.858598 -236.812643)
			(xy 111.828072 -236.770627) (xy 111.804494 -236.724353) (xy 111.788446 -236.67496) (xy 111.780321 -236.623665)
			(xy 111.500411 -236.623665) (xy 111.492286 -236.67496) (xy 111.476238 -236.724353) (xy 111.45266 -236.770627)
			(xy 111.422134 -236.812643) (xy 111.385411 -236.849366) (xy 111.343395 -236.879892) (xy 111.297121 -236.90347)
			(xy 111.247728 -236.919518) (xy 111.196433 -236.927643) (xy 111.144499 -236.927643) (xy 111.093204 -236.919518)
			(xy 111.043811 -236.90347) (xy 110.997537 -236.879892) (xy 110.955521 -236.849366) (xy 110.918798 -236.812643)
			(xy 110.888272 -236.770627) (xy 110.864694 -236.724353) (xy 110.848646 -236.67496) (xy 110.840521 -236.623665)
			(xy 110.560619 -236.623665) (xy 110.554105 -236.668445) (xy 110.540614 -236.713983) (xy 110.520746 -236.757123)
			(xy 110.494911 -236.796977) (xy 110.479586 -236.815122) (xy 110.448344 -236.850936) (xy 110.678722 -237.081314)
			(xy 110.699804 -237.081314) (xy 110.725876 -237.081726) (xy 110.777395 -237.089759) (xy 110.827014 -237.105781)
			(xy 110.873501 -237.129396) (xy 110.915704 -237.160018) (xy 110.952574 -237.196887) (xy 110.983197 -237.239089)
			(xy 111.006814 -237.285575) (xy 111.022839 -237.335193) (xy 111.030873 -237.386712) (xy 111.031274 -237.412784)
			(xy 111.031274 -237.433866) (xy 111.035143 -237.437735) (xy 111.310675 -237.437735) (xy 111.310675 -237.385801)
			(xy 111.3188 -237.334506) (xy 111.334848 -237.285113) (xy 111.358426 -237.238839) (xy 111.388952 -237.196823)
			(xy 111.425675 -237.1601) (xy 111.467691 -237.129574) (xy 111.513965 -237.105996) (xy 111.563358 -237.089948)
			(xy 111.614653 -237.081823) (xy 111.666587 -237.081823) (xy 111.717882 -237.089948) (xy 111.767275 -237.105996)
			(xy 111.813549 -237.129574) (xy 111.855565 -237.1601) (xy 111.892288 -237.196823) (xy 111.922814 -237.238839)
			(xy 111.946392 -237.285113) (xy 111.96244 -237.334506) (xy 111.970565 -237.385801) (xy 111.971074 -237.411768)
			(xy 111.970565 -237.437735) (xy 112.250475 -237.437735) (xy 112.250475 -237.385801) (xy 112.2586 -237.334506)
			(xy 112.274648 -237.285113) (xy 112.298226 -237.238839) (xy 112.328752 -237.196823) (xy 112.365475 -237.1601)
			(xy 112.407491 -237.129574) (xy 112.453765 -237.105996) (xy 112.503158 -237.089948) (xy 112.554453 -237.081823)
			(xy 112.606387 -237.081823) (xy 112.657682 -237.089948) (xy 112.707075 -237.105996) (xy 112.753349 -237.129574)
			(xy 112.795365 -237.1601) (xy 112.832088 -237.196823) (xy 112.862614 -237.238839) (xy 112.886192 -237.285113)
			(xy 112.90224 -237.334506) (xy 112.910365 -237.385801) (xy 112.910874 -237.411768) (xy 112.910365 -237.437735)
			(xy 113.190275 -237.437735) (xy 113.190275 -237.385801) (xy 113.1984 -237.334506) (xy 113.214448 -237.285113)
			(xy 113.238026 -237.238839) (xy 113.268552 -237.196823) (xy 113.305275 -237.1601) (xy 113.347291 -237.129574)
			(xy 113.393565 -237.105996) (xy 113.442958 -237.089948) (xy 113.494253 -237.081823) (xy 113.546187 -237.081823)
			(xy 113.597482 -237.089948) (xy 113.646875 -237.105996) (xy 113.693149 -237.129574) (xy 113.720418 -237.149386)
			(xy 115.011708 -237.149386) (xy 115.01216 -237.124834) (xy 115.019396 -237.076267) (xy 115.033737 -237.029305)
			(xy 115.054866 -236.984981) (xy 115.08232 -236.94427) (xy 115.098576 -236.925866) (xy 115.108393 -236.914388)
			(xy 115.121405 -236.887147) (xy 115.125871 -236.85729) (xy 115.121399 -236.827434) (xy 115.108381 -236.800195)
			(xy 115.098576 -236.788706) (xy 115.082294 -236.770322) (xy 115.05483 -236.729611) (xy 115.033697 -236.685283)
			(xy 115.019359 -236.638314) (xy 115.012134 -236.589741) (xy 115.011708 -236.565186) (xy 115.012217 -236.539219)
			(xy 115.020342 -236.487924) (xy 115.03639 -236.438531) (xy 115.059968 -236.392257) (xy 115.090494 -236.350241)
			(xy 115.127217 -236.313518) (xy 115.169233 -236.282992) (xy 115.215507 -236.259414) (xy 115.2649 -236.243366)
			(xy 115.316195 -236.235241) (xy 115.368129 -236.235241) (xy 115.419424 -236.243366) (xy 115.468817 -236.259414)
			(xy 115.505227 -236.277966) (xy 120.646459 -236.277966) (xy 120.646459 -236.226034) (xy 120.654583 -236.17474)
			(xy 120.670631 -236.125349) (xy 120.694208 -236.079076) (xy 120.724732 -236.037061) (xy 120.761454 -236.000339)
			(xy 120.803468 -235.969813) (xy 120.84974 -235.946235) (xy 120.89913 -235.930185) (xy 120.950424 -235.92206)
			(xy 120.97639 -235.92155) (xy 121.002115 -235.922104) (xy 121.052941 -235.930091) (xy 121.101915 -235.945858)
			(xy 121.147855 -235.969023) (xy 121.18965 -235.999028) (xy 121.22629 -236.035147) (xy 121.25689 -236.076507)
			(xy 121.280711 -236.12211) (xy 121.297178 -236.170854) (xy 121.302018 -236.196124) (xy 121.304804 -236.209847)
			(xy 121.316774 -236.235149) (xy 121.335172 -236.256244) (xy 121.358613 -236.271542) (xy 121.385329 -236.27989)
			(xy 121.413309 -236.280661) (xy 121.426986 -236.277658) (xy 121.446905 -236.272909) (xy 121.487537 -236.267819)
			(xy 121.508012 -236.267498) (xy 121.533975 -236.268104) (xy 121.585261 -236.276229) (xy 121.634645 -236.292276)
			(xy 121.68091 -236.315851) (xy 121.722918 -236.346373) (xy 121.759635 -236.383091) (xy 121.790155 -236.4251)
			(xy 121.813729 -236.471366) (xy 121.829774 -236.520751) (xy 121.837897 -236.572037) (xy 121.837897 -236.623919)
			(xy 122.118121 -236.623919) (xy 122.118121 -236.571985) (xy 122.126246 -236.52069) (xy 122.142294 -236.471297)
			(xy 122.165872 -236.425023) (xy 122.196398 -236.383007) (xy 122.233121 -236.346284) (xy 122.275137 -236.315758)
			(xy 122.321411 -236.29218) (xy 122.370804 -236.276132) (xy 122.422099 -236.268007) (xy 122.474033 -236.268007)
			(xy 122.525328 -236.276132) (xy 122.574721 -236.29218) (xy 122.620995 -236.315758) (xy 122.663011 -236.346284)
			(xy 122.699734 -236.383007) (xy 122.73026 -236.425023) (xy 122.753838 -236.471297) (xy 122.769886 -236.52069)
			(xy 122.778011 -236.571985) (xy 122.77852 -236.597952) (xy 122.778011 -236.623919) (xy 123.057667 -236.623919)
			(xy 123.057667 -236.571985) (xy 123.065792 -236.52069) (xy 123.08184 -236.471297) (xy 123.105418 -236.425023)
			(xy 123.135944 -236.383007) (xy 123.172667 -236.346284) (xy 123.214683 -236.315758) (xy 123.260957 -236.29218)
			(xy 123.31035 -236.276132) (xy 123.361645 -236.268007) (xy 123.413579 -236.268007) (xy 123.464874 -236.276132)
			(xy 123.514267 -236.29218) (xy 123.560541 -236.315758) (xy 123.602557 -236.346284) (xy 123.63928 -236.383007)
			(xy 123.669806 -236.425023) (xy 123.693384 -236.471297) (xy 123.709432 -236.52069) (xy 123.717557 -236.571985)
			(xy 123.718066 -236.597952) (xy 123.717557 -236.623919) (xy 123.997467 -236.623919) (xy 123.997467 -236.571985)
			(xy 124.005592 -236.52069) (xy 124.02164 -236.471297) (xy 124.045218 -236.425023) (xy 124.075744 -236.383007)
			(xy 124.112467 -236.346284) (xy 124.154483 -236.315758) (xy 124.200757 -236.29218) (xy 124.25015 -236.276132)
			(xy 124.301445 -236.268007) (xy 124.353379 -236.268007) (xy 124.404674 -236.276132) (xy 124.454067 -236.29218)
			(xy 124.500341 -236.315758) (xy 124.542357 -236.346284) (xy 124.57908 -236.383007) (xy 124.609606 -236.425023)
			(xy 124.633184 -236.471297) (xy 124.649232 -236.52069) (xy 124.657357 -236.571985) (xy 124.657866 -236.597952)
			(xy 124.657357 -236.623919) (xy 124.937267 -236.623919) (xy 124.937267 -236.571985) (xy 124.945392 -236.52069)
			(xy 124.96144 -236.471297) (xy 124.985018 -236.425023) (xy 125.015544 -236.383007) (xy 125.052267 -236.346284)
			(xy 125.094283 -236.315758) (xy 125.140557 -236.29218) (xy 125.18995 -236.276132) (xy 125.241245 -236.268007)
			(xy 125.293179 -236.268007) (xy 125.344474 -236.276132) (xy 125.393867 -236.29218) (xy 125.440141 -236.315758)
			(xy 125.482157 -236.346284) (xy 125.51888 -236.383007) (xy 125.549406 -236.425023) (xy 125.572984 -236.471297)
			(xy 125.589032 -236.52069) (xy 125.597157 -236.571985) (xy 125.597666 -236.597952) (xy 125.597157 -236.623919)
			(xy 125.877067 -236.623919) (xy 125.877067 -236.571985) (xy 125.885192 -236.52069) (xy 125.90124 -236.471297)
			(xy 125.924818 -236.425023) (xy 125.955344 -236.383007) (xy 125.992067 -236.346284) (xy 126.034083 -236.315758)
			(xy 126.080357 -236.29218) (xy 126.12975 -236.276132) (xy 126.181045 -236.268007) (xy 126.232979 -236.268007)
			(xy 126.284274 -236.276132) (xy 126.333667 -236.29218) (xy 126.379941 -236.315758) (xy 126.421957 -236.346284)
			(xy 126.45868 -236.383007) (xy 126.489206 -236.425023) (xy 126.512784 -236.471297) (xy 126.528832 -236.52069)
			(xy 126.536957 -236.571985) (xy 126.537466 -236.597952) (xy 126.536957 -236.623919) (xy 126.816867 -236.623919)
			(xy 126.816867 -236.571985) (xy 126.824992 -236.52069) (xy 126.84104 -236.471297) (xy 126.864618 -236.425023)
			(xy 126.895144 -236.383007) (xy 126.931867 -236.346284) (xy 126.973883 -236.315758) (xy 127.020157 -236.29218)
			(xy 127.06955 -236.276132) (xy 127.120845 -236.268007) (xy 127.172779 -236.268007) (xy 127.224074 -236.276132)
			(xy 127.273467 -236.29218) (xy 127.319741 -236.315758) (xy 127.361757 -236.346284) (xy 127.39848 -236.383007)
			(xy 127.429006 -236.425023) (xy 127.452584 -236.471297) (xy 127.468632 -236.52069) (xy 127.476757 -236.571985)
			(xy 127.477266 -236.597952) (xy 127.476757 -236.623919) (xy 127.468632 -236.675214) (xy 127.452584 -236.724607)
			(xy 127.429006 -236.770881) (xy 127.39848 -236.812897) (xy 127.361757 -236.84962) (xy 127.319741 -236.880146)
			(xy 127.273467 -236.903724) (xy 127.224074 -236.919772) (xy 127.172779 -236.927897) (xy 127.120845 -236.927897)
			(xy 127.06955 -236.919772) (xy 127.020157 -236.903724) (xy 126.973883 -236.880146) (xy 126.931867 -236.84962)
			(xy 126.895144 -236.812897) (xy 126.864618 -236.770881) (xy 126.84104 -236.724607) (xy 126.824992 -236.675214)
			(xy 126.816867 -236.623919) (xy 126.536957 -236.623919) (xy 126.528832 -236.675214) (xy 126.512784 -236.724607)
			(xy 126.489206 -236.770881) (xy 126.45868 -236.812897) (xy 126.421957 -236.84962) (xy 126.379941 -236.880146)
			(xy 126.333667 -236.903724) (xy 126.284274 -236.919772) (xy 126.232979 -236.927897) (xy 126.181045 -236.927897)
			(xy 126.12975 -236.919772) (xy 126.080357 -236.903724) (xy 126.034083 -236.880146) (xy 125.992067 -236.84962)
			(xy 125.955344 -236.812897) (xy 125.924818 -236.770881) (xy 125.90124 -236.724607) (xy 125.885192 -236.675214)
			(xy 125.877067 -236.623919) (xy 125.597157 -236.623919) (xy 125.589032 -236.675214) (xy 125.572984 -236.724607)
			(xy 125.549406 -236.770881) (xy 125.51888 -236.812897) (xy 125.482157 -236.84962) (xy 125.440141 -236.880146)
			(xy 125.393867 -236.903724) (xy 125.344474 -236.919772) (xy 125.293179 -236.927897) (xy 125.241245 -236.927897)
			(xy 125.18995 -236.919772) (xy 125.140557 -236.903724) (xy 125.094283 -236.880146) (xy 125.052267 -236.84962)
			(xy 125.015544 -236.812897) (xy 124.985018 -236.770881) (xy 124.96144 -236.724607) (xy 124.945392 -236.675214)
			(xy 124.937267 -236.623919) (xy 124.657357 -236.623919) (xy 124.649232 -236.675214) (xy 124.633184 -236.724607)
			(xy 124.609606 -236.770881) (xy 124.57908 -236.812897) (xy 124.542357 -236.84962) (xy 124.500341 -236.880146)
			(xy 124.454067 -236.903724) (xy 124.404674 -236.919772) (xy 124.353379 -236.927897) (xy 124.301445 -236.927897)
			(xy 124.25015 -236.919772) (xy 124.200757 -236.903724) (xy 124.154483 -236.880146) (xy 124.112467 -236.84962)
			(xy 124.075744 -236.812897) (xy 124.045218 -236.770881) (xy 124.02164 -236.724607) (xy 124.005592 -236.675214)
			(xy 123.997467 -236.623919) (xy 123.717557 -236.623919) (xy 123.709432 -236.675214) (xy 123.693384 -236.724607)
			(xy 123.669806 -236.770881) (xy 123.63928 -236.812897) (xy 123.602557 -236.84962) (xy 123.560541 -236.880146)
			(xy 123.514267 -236.903724) (xy 123.464874 -236.919772) (xy 123.413579 -236.927897) (xy 123.361645 -236.927897)
			(xy 123.31035 -236.919772) (xy 123.260957 -236.903724) (xy 123.214683 -236.880146) (xy 123.172667 -236.84962)
			(xy 123.135944 -236.812897) (xy 123.105418 -236.770881) (xy 123.08184 -236.724607) (xy 123.065792 -236.675214)
			(xy 123.057667 -236.623919) (xy 122.778011 -236.623919) (xy 122.769886 -236.675214) (xy 122.753838 -236.724607)
			(xy 122.73026 -236.770881) (xy 122.699734 -236.812897) (xy 122.663011 -236.84962) (xy 122.620995 -236.880146)
			(xy 122.574721 -236.903724) (xy 122.525328 -236.919772) (xy 122.474033 -236.927897) (xy 122.422099 -236.927897)
			(xy 122.370804 -236.919772) (xy 122.321411 -236.903724) (xy 122.275137 -236.880146) (xy 122.233121 -236.84962)
			(xy 122.196398 -236.812897) (xy 122.165872 -236.770881) (xy 122.142294 -236.724607) (xy 122.126246 -236.675214)
			(xy 122.118121 -236.623919) (xy 121.837897 -236.623919) (xy 121.837897 -236.623963) (xy 121.829774 -236.675249)
			(xy 121.813729 -236.724634) (xy 121.790155 -236.7709) (xy 121.759635 -236.812909) (xy 121.722918 -236.849627)
			(xy 121.68091 -236.880149) (xy 121.634645 -236.903724) (xy 121.585261 -236.919771) (xy 121.533975 -236.927896)
			(xy 121.508012 -236.928406) (xy 121.482285 -236.927886) (xy 121.431456 -236.919898) (xy 121.382479 -236.90413)
			(xy 121.336537 -236.880961) (xy 121.294741 -236.850952) (xy 121.258101 -236.814828) (xy 121.227502 -236.773462)
			(xy 121.203683 -236.727853) (xy 121.187221 -236.679105) (xy 121.182384 -236.653832) (xy 121.179559 -236.640117)
			(xy 121.167602 -236.614813) (xy 121.149213 -236.593715) (xy 121.125779 -236.578415) (xy 121.099067 -236.570064)
			(xy 121.07109 -236.569294) (xy 121.057416 -236.572298) (xy 121.037497 -236.577046) (xy 120.996865 -236.582137)
			(xy 120.97639 -236.582458) (xy 120.950424 -236.58194) (xy 120.89913 -236.573815) (xy 120.84974 -236.557765)
			(xy 120.803468 -236.534187) (xy 120.761454 -236.503661) (xy 120.724732 -236.466939) (xy 120.694208 -236.424924)
			(xy 120.670631 -236.378651) (xy 120.654583 -236.32926) (xy 120.646459 -236.277966) (xy 115.505227 -236.277966)
			(xy 115.515091 -236.282992) (xy 115.557107 -236.313518) (xy 115.59383 -236.350241) (xy 115.624356 -236.392257)
			(xy 115.647934 -236.438531) (xy 115.663982 -236.487924) (xy 115.672107 -236.539219) (xy 115.672616 -236.565186)
			(xy 115.672201 -236.589739) (xy 115.664955 -236.638307) (xy 115.650606 -236.68527) (xy 115.629468 -236.729593)
			(xy 115.602007 -236.770303) (xy 115.585748 -236.788706) (xy 115.575956 -236.800205) (xy 115.562938 -236.827438)
			(xy 115.558466 -236.85729) (xy 115.562932 -236.887142) (xy 115.575945 -236.914378) (xy 115.585748 -236.925866)
			(xy 115.602004 -236.944272) (xy 115.629475 -236.984975) (xy 115.650614 -237.029298) (xy 115.664958 -237.076262)
			(xy 115.672187 -237.124833) (xy 115.672616 -237.149386) (xy 115.672107 -237.175353) (xy 115.663982 -237.226648)
			(xy 115.647934 -237.276041) (xy 115.624356 -237.322315) (xy 115.59383 -237.364331) (xy 115.557107 -237.401054)
			(xy 115.515091 -237.43158) (xy 115.486062 -237.446371) (xy 120.646445 -237.446371) (xy 120.646445 -237.394437)
			(xy 120.65457 -237.343142) (xy 120.670618 -237.293749) (xy 120.694196 -237.247475) (xy 120.724722 -237.205459)
			(xy 120.761445 -237.168736) (xy 120.803461 -237.13821) (xy 120.849735 -237.114632) (xy 120.899128 -237.098584)
			(xy 120.950423 -237.090459) (xy 121.002357 -237.090459) (xy 121.053652 -237.098584) (xy 121.103045 -237.114632)
			(xy 121.149319 -237.13821) (xy 121.191335 -237.168736) (xy 121.228058 -237.205459) (xy 121.258584 -237.247475)
			(xy 121.282162 -237.293749) (xy 121.29821 -237.343142) (xy 121.306335 -237.394437) (xy 121.306844 -237.420404)
			(xy 121.306509 -237.437481) (xy 121.648221 -237.437481) (xy 121.648221 -237.385547) (xy 121.656346 -237.334252)
			(xy 121.672394 -237.284859) (xy 121.695972 -237.238585) (xy 121.726498 -237.196569) (xy 121.763221 -237.159846)
			(xy 121.805237 -237.12932) (xy 121.851511 -237.105742) (xy 121.900904 -237.089694) (xy 121.952199 -237.081569)
			(xy 122.004133 -237.081569) (xy 122.055428 -237.089694) (xy 122.104821 -237.105742) (xy 122.151095 -237.12932)
			(xy 122.193111 -237.159846) (xy 122.229834 -237.196569) (xy 122.26036 -237.238585) (xy 122.283938 -237.284859)
			(xy 122.299986 -237.334252) (xy 122.308111 -237.385547) (xy 122.30862 -237.411514) (xy 122.308111 -237.437481)
			(xy 122.588021 -237.437481) (xy 122.588021 -237.385547) (xy 122.596146 -237.334252) (xy 122.612194 -237.284859)
			(xy 122.635772 -237.238585) (xy 122.666298 -237.196569) (xy 122.703021 -237.159846) (xy 122.745037 -237.12932)
			(xy 122.791311 -237.105742) (xy 122.840704 -237.089694) (xy 122.891999 -237.081569) (xy 122.943933 -237.081569)
			(xy 122.995228 -237.089694) (xy 123.044621 -237.105742) (xy 123.090895 -237.12932) (xy 123.132911 -237.159846)
			(xy 123.169634 -237.196569) (xy 123.20016 -237.238585) (xy 123.223738 -237.284859) (xy 123.239786 -237.334252)
			(xy 123.247911 -237.385547) (xy 123.24842 -237.411514) (xy 123.247911 -237.437481) (xy 123.527821 -237.437481)
			(xy 123.527821 -237.385547) (xy 123.535946 -237.334252) (xy 123.551994 -237.284859) (xy 123.575572 -237.238585)
			(xy 123.606098 -237.196569) (xy 123.642821 -237.159846) (xy 123.684837 -237.12932) (xy 123.731111 -237.105742)
			(xy 123.780504 -237.089694) (xy 123.831799 -237.081569) (xy 123.883733 -237.081569) (xy 123.935028 -237.089694)
			(xy 123.984421 -237.105742) (xy 124.030695 -237.12932) (xy 124.072711 -237.159846) (xy 124.109434 -237.196569)
			(xy 124.13996 -237.238585) (xy 124.163538 -237.284859) (xy 124.179586 -237.334252) (xy 124.187711 -237.385547)
			(xy 124.18822 -237.411514) (xy 124.187711 -237.437481) (xy 124.467621 -237.437481) (xy 124.467621 -237.385547)
			(xy 124.475746 -237.334252) (xy 124.491794 -237.284859) (xy 124.515372 -237.238585) (xy 124.545898 -237.196569)
			(xy 124.582621 -237.159846) (xy 124.624637 -237.12932) (xy 124.670911 -237.105742) (xy 124.720304 -237.089694)
			(xy 124.771599 -237.081569) (xy 124.823533 -237.081569) (xy 124.874828 -237.089694) (xy 124.924221 -237.105742)
			(xy 124.970495 -237.12932) (xy 125.012511 -237.159846) (xy 125.049234 -237.196569) (xy 125.07976 -237.238585)
			(xy 125.103338 -237.284859) (xy 125.119386 -237.334252) (xy 125.127511 -237.385547) (xy 125.12802 -237.411514)
			(xy 125.127511 -237.437481) (xy 125.407421 -237.437481) (xy 125.407421 -237.385547) (xy 125.415546 -237.334252)
			(xy 125.431594 -237.284859) (xy 125.455172 -237.238585) (xy 125.485698 -237.196569) (xy 125.522421 -237.159846)
			(xy 125.564437 -237.12932) (xy 125.610711 -237.105742) (xy 125.660104 -237.089694) (xy 125.711399 -237.081569)
			(xy 125.763333 -237.081569) (xy 125.814628 -237.089694) (xy 125.864021 -237.105742) (xy 125.910295 -237.12932)
			(xy 125.952311 -237.159846) (xy 125.989034 -237.196569) (xy 126.01956 -237.238585) (xy 126.043138 -237.284859)
			(xy 126.059186 -237.334252) (xy 126.067311 -237.385547) (xy 126.06782 -237.411514) (xy 126.067311 -237.437481)
			(xy 126.347221 -237.437481) (xy 126.347221 -237.385547) (xy 126.355346 -237.334252) (xy 126.371394 -237.284859)
			(xy 126.394972 -237.238585) (xy 126.425498 -237.196569) (xy 126.462221 -237.159846) (xy 126.504237 -237.12932)
			(xy 126.550511 -237.105742) (xy 126.599904 -237.089694) (xy 126.651199 -237.081569) (xy 126.703133 -237.081569)
			(xy 126.754428 -237.089694) (xy 126.803821 -237.105742) (xy 126.850095 -237.12932) (xy 126.892111 -237.159846)
			(xy 126.928834 -237.196569) (xy 126.95936 -237.238585) (xy 126.982938 -237.284859) (xy 126.998986 -237.334252)
			(xy 127.007111 -237.385547) (xy 127.00762 -237.411514) (xy 127.007111 -237.437481) (xy 126.998986 -237.488776)
			(xy 126.982938 -237.538169) (xy 126.95936 -237.584443) (xy 126.928834 -237.626459) (xy 126.892111 -237.663182)
			(xy 126.850095 -237.693708) (xy 126.803821 -237.717286) (xy 126.754428 -237.733334) (xy 126.703133 -237.741459)
			(xy 126.651199 -237.741459) (xy 126.599904 -237.733334) (xy 126.550511 -237.717286) (xy 126.504237 -237.693708)
			(xy 126.462221 -237.663182) (xy 126.425498 -237.626459) (xy 126.394972 -237.584443) (xy 126.371394 -237.538169)
			(xy 126.355346 -237.488776) (xy 126.347221 -237.437481) (xy 126.067311 -237.437481) (xy 126.059186 -237.488776)
			(xy 126.043138 -237.538169) (xy 126.01956 -237.584443) (xy 125.989034 -237.626459) (xy 125.952311 -237.663182)
			(xy 125.910295 -237.693708) (xy 125.864021 -237.717286) (xy 125.814628 -237.733334) (xy 125.763333 -237.741459)
			(xy 125.711399 -237.741459) (xy 125.660104 -237.733334) (xy 125.610711 -237.717286) (xy 125.564437 -237.693708)
			(xy 125.522421 -237.663182) (xy 125.485698 -237.626459) (xy 125.455172 -237.584443) (xy 125.431594 -237.538169)
			(xy 125.415546 -237.488776) (xy 125.407421 -237.437481) (xy 125.127511 -237.437481) (xy 125.119386 -237.488776)
			(xy 125.103338 -237.538169) (xy 125.07976 -237.584443) (xy 125.049234 -237.626459) (xy 125.012511 -237.663182)
			(xy 124.970495 -237.693708) (xy 124.924221 -237.717286) (xy 124.874828 -237.733334) (xy 124.823533 -237.741459)
			(xy 124.771599 -237.741459) (xy 124.720304 -237.733334) (xy 124.670911 -237.717286) (xy 124.624637 -237.693708)
			(xy 124.582621 -237.663182) (xy 124.545898 -237.626459) (xy 124.515372 -237.584443) (xy 124.491794 -237.538169)
			(xy 124.475746 -237.488776) (xy 124.467621 -237.437481) (xy 124.187711 -237.437481) (xy 124.179586 -237.488776)
			(xy 124.163538 -237.538169) (xy 124.13996 -237.584443) (xy 124.109434 -237.626459) (xy 124.072711 -237.663182)
			(xy 124.030695 -237.693708) (xy 123.984421 -237.717286) (xy 123.935028 -237.733334) (xy 123.883733 -237.741459)
			(xy 123.831799 -237.741459) (xy 123.780504 -237.733334) (xy 123.731111 -237.717286) (xy 123.684837 -237.693708)
			(xy 123.642821 -237.663182) (xy 123.606098 -237.626459) (xy 123.575572 -237.584443) (xy 123.551994 -237.538169)
			(xy 123.535946 -237.488776) (xy 123.527821 -237.437481) (xy 123.247911 -237.437481) (xy 123.239786 -237.488776)
			(xy 123.223738 -237.538169) (xy 123.20016 -237.584443) (xy 123.169634 -237.626459) (xy 123.132911 -237.663182)
			(xy 123.090895 -237.693708) (xy 123.044621 -237.717286) (xy 122.995228 -237.733334) (xy 122.943933 -237.741459)
			(xy 122.891999 -237.741459) (xy 122.840704 -237.733334) (xy 122.791311 -237.717286) (xy 122.745037 -237.693708)
			(xy 122.703021 -237.663182) (xy 122.666298 -237.626459) (xy 122.635772 -237.584443) (xy 122.612194 -237.538169)
			(xy 122.596146 -237.488776) (xy 122.588021 -237.437481) (xy 122.308111 -237.437481) (xy 122.299986 -237.488776)
			(xy 122.283938 -237.538169) (xy 122.26036 -237.584443) (xy 122.229834 -237.626459) (xy 122.193111 -237.663182)
			(xy 122.151095 -237.693708) (xy 122.104821 -237.717286) (xy 122.055428 -237.733334) (xy 122.004133 -237.741459)
			(xy 121.952199 -237.741459) (xy 121.900904 -237.733334) (xy 121.851511 -237.717286) (xy 121.805237 -237.693708)
			(xy 121.763221 -237.663182) (xy 121.726498 -237.626459) (xy 121.695972 -237.584443) (xy 121.672394 -237.538169)
			(xy 121.656346 -237.488776) (xy 121.648221 -237.437481) (xy 121.306509 -237.437481) (xy 121.306335 -237.446371)
			(xy 121.29821 -237.497666) (xy 121.282162 -237.547059) (xy 121.258584 -237.593333) (xy 121.228058 -237.635349)
			(xy 121.191335 -237.672072) (xy 121.149319 -237.702598) (xy 121.103045 -237.726176) (xy 121.053652 -237.742224)
			(xy 121.002357 -237.750349) (xy 120.950423 -237.750349) (xy 120.899128 -237.742224) (xy 120.849735 -237.726176)
			(xy 120.803461 -237.702598) (xy 120.761445 -237.672072) (xy 120.724722 -237.635349) (xy 120.694196 -237.593333)
			(xy 120.670618 -237.547059) (xy 120.65457 -237.497666) (xy 120.646445 -237.446371) (xy 115.486062 -237.446371)
			(xy 115.468817 -237.455158) (xy 115.419424 -237.471206) (xy 115.368129 -237.479331) (xy 115.316195 -237.479331)
			(xy 115.2649 -237.471206) (xy 115.215507 -237.455158) (xy 115.169233 -237.43158) (xy 115.127217 -237.401054)
			(xy 115.090494 -237.364331) (xy 115.059968 -237.322315) (xy 115.03639 -237.276041) (xy 115.020342 -237.226648)
			(xy 115.012217 -237.175353) (xy 115.011708 -237.149386) (xy 113.720418 -237.149386) (xy 113.735165 -237.1601)
			(xy 113.771888 -237.196823) (xy 113.802414 -237.238839) (xy 113.825992 -237.285113) (xy 113.84204 -237.334506)
			(xy 113.850165 -237.385801) (xy 113.850674 -237.411768) (xy 113.850165 -237.437735) (xy 113.84204 -237.48903)
			(xy 113.825992 -237.538423) (xy 113.802414 -237.584697) (xy 113.771888 -237.626713) (xy 113.735165 -237.663436)
			(xy 113.693149 -237.693962) (xy 113.646875 -237.71754) (xy 113.597482 -237.733588) (xy 113.546187 -237.741713)
			(xy 113.494253 -237.741713) (xy 113.442958 -237.733588) (xy 113.393565 -237.71754) (xy 113.347291 -237.693962)
			(xy 113.305275 -237.663436) (xy 113.268552 -237.626713) (xy 113.238026 -237.584697) (xy 113.214448 -237.538423)
			(xy 113.1984 -237.48903) (xy 113.190275 -237.437735) (xy 112.910365 -237.437735) (xy 112.90224 -237.48903)
			(xy 112.886192 -237.538423) (xy 112.862614 -237.584697) (xy 112.832088 -237.626713) (xy 112.795365 -237.663436)
			(xy 112.753349 -237.693962) (xy 112.707075 -237.71754) (xy 112.657682 -237.733588) (xy 112.606387 -237.741713)
			(xy 112.554453 -237.741713) (xy 112.503158 -237.733588) (xy 112.453765 -237.71754) (xy 112.407491 -237.693962)
			(xy 112.365475 -237.663436) (xy 112.328752 -237.626713) (xy 112.298226 -237.584697) (xy 112.274648 -237.538423)
			(xy 112.2586 -237.48903) (xy 112.250475 -237.437735) (xy 111.970565 -237.437735) (xy 111.96244 -237.48903)
			(xy 111.946392 -237.538423) (xy 111.922814 -237.584697) (xy 111.892288 -237.626713) (xy 111.855565 -237.663436)
			(xy 111.813549 -237.693962) (xy 111.767275 -237.71754) (xy 111.717882 -237.733588) (xy 111.666587 -237.741713)
			(xy 111.614653 -237.741713) (xy 111.563358 -237.733588) (xy 111.513965 -237.71754) (xy 111.467691 -237.693962)
			(xy 111.425675 -237.663436) (xy 111.388952 -237.626713) (xy 111.358426 -237.584697) (xy 111.334848 -237.538423)
			(xy 111.3188 -237.48903) (xy 111.310675 -237.437735) (xy 111.035143 -237.437735) (xy 111.503968 -237.90656)
			(xy 112.024922 -237.90656) (xy 112.030764 -237.905036) (xy 112.050327 -237.90051) (xy 112.090189 -237.895672)
			(xy 112.110266 -237.895384) (xy 112.130344 -237.895661) (xy 112.170208 -237.900496) (xy 112.189768 -237.905036)
			(xy 112.19561 -237.90656) (xy 112.964722 -237.90656) (xy 112.970564 -237.905036) (xy 112.990127 -237.90051)
			(xy 113.029989 -237.895672) (xy 113.050066 -237.895384) (xy 113.070144 -237.895661) (xy 113.110008 -237.900496)
			(xy 113.129568 -237.905036) (xy 113.13541 -237.90656) (xy 113.904522 -237.90656) (xy 113.910364 -237.905036)
			(xy 113.929927 -237.90051) (xy 113.969789 -237.895672) (xy 113.989866 -237.895384) (xy 114.009944 -237.895661)
			(xy 114.049808 -237.900496) (xy 114.069368 -237.905036) (xy 114.07521 -237.90656) (xy 115.694206 -237.90656)
			(xy 116.039197 -238.251551) (xy 121.178067 -238.251551) (xy 121.178067 -238.199617) (xy 121.186192 -238.148322)
			(xy 121.20224 -238.098929) (xy 121.225818 -238.052655) (xy 121.256344 -238.010639) (xy 121.293067 -237.973916)
			(xy 121.335083 -237.94339) (xy 121.381357 -237.919812) (xy 121.43075 -237.903764) (xy 121.482045 -237.895639)
			(xy 121.533979 -237.895639) (xy 121.585274 -237.903764) (xy 121.634667 -237.919812) (xy 121.680941 -237.94339)
			(xy 121.722957 -237.973916) (xy 121.75968 -238.010639) (xy 121.790206 -238.052655) (xy 121.813784 -238.098929)
			(xy 121.829832 -238.148322) (xy 121.837957 -238.199617) (xy 121.838466 -238.225584) (xy 121.837957 -238.251551)
			(xy 122.117867 -238.251551) (xy 122.117867 -238.199617) (xy 122.125992 -238.148322) (xy 122.14204 -238.098929)
			(xy 122.165618 -238.052655) (xy 122.196144 -238.010639) (xy 122.232867 -237.973916) (xy 122.274883 -237.94339)
			(xy 122.321157 -237.919812) (xy 122.37055 -237.903764) (xy 122.421845 -237.895639) (xy 122.473779 -237.895639)
			(xy 122.525074 -237.903764) (xy 122.574467 -237.919812) (xy 122.620741 -237.94339) (xy 122.662757 -237.973916)
			(xy 122.69948 -238.010639) (xy 122.730006 -238.052655) (xy 122.753584 -238.098929) (xy 122.769632 -238.148322)
			(xy 122.777757 -238.199617) (xy 122.778266 -238.225584) (xy 122.777757 -238.251551) (xy 123.057667 -238.251551)
			(xy 123.057667 -238.199617) (xy 123.065792 -238.148322) (xy 123.08184 -238.098929) (xy 123.105418 -238.052655)
			(xy 123.135944 -238.010639) (xy 123.172667 -237.973916) (xy 123.214683 -237.94339) (xy 123.260957 -237.919812)
			(xy 123.31035 -237.903764) (xy 123.361645 -237.895639) (xy 123.413579 -237.895639) (xy 123.464874 -237.903764)
			(xy 123.514267 -237.919812) (xy 123.560541 -237.94339) (xy 123.602557 -237.973916) (xy 123.63928 -238.010639)
			(xy 123.669806 -238.052655) (xy 123.693384 -238.098929) (xy 123.709432 -238.148322) (xy 123.717557 -238.199617)
			(xy 123.718066 -238.225584) (xy 123.717557 -238.251551) (xy 123.997467 -238.251551) (xy 123.997467 -238.199617)
			(xy 124.005592 -238.148322) (xy 124.02164 -238.098929) (xy 124.045218 -238.052655) (xy 124.075744 -238.010639)
			(xy 124.112467 -237.973916) (xy 124.154483 -237.94339) (xy 124.200757 -237.919812) (xy 124.25015 -237.903764)
			(xy 124.301445 -237.895639) (xy 124.353379 -237.895639) (xy 124.404674 -237.903764) (xy 124.454067 -237.919812)
			(xy 124.500341 -237.94339) (xy 124.542357 -237.973916) (xy 124.57908 -238.010639) (xy 124.609606 -238.052655)
			(xy 124.633184 -238.098929) (xy 124.649232 -238.148322) (xy 124.657357 -238.199617) (xy 124.657866 -238.225584)
			(xy 124.657357 -238.251551) (xy 124.937267 -238.251551) (xy 124.937267 -238.199617) (xy 124.945392 -238.148322)
			(xy 124.96144 -238.098929) (xy 124.985018 -238.052655) (xy 125.015544 -238.010639) (xy 125.052267 -237.973916)
			(xy 125.094283 -237.94339) (xy 125.140557 -237.919812) (xy 125.18995 -237.903764) (xy 125.241245 -237.895639)
			(xy 125.293179 -237.895639) (xy 125.344474 -237.903764) (xy 125.393867 -237.919812) (xy 125.440141 -237.94339)
			(xy 125.482157 -237.973916) (xy 125.51888 -238.010639) (xy 125.549406 -238.052655) (xy 125.572984 -238.098929)
			(xy 125.589032 -238.148322) (xy 125.597157 -238.199617) (xy 125.597666 -238.225584) (xy 125.597157 -238.251551)
			(xy 125.877321 -238.251551) (xy 125.877321 -238.199617) (xy 125.885446 -238.148322) (xy 125.901494 -238.098929)
			(xy 125.925072 -238.052655) (xy 125.955598 -238.010639) (xy 125.992321 -237.973916) (xy 126.034337 -237.94339)
			(xy 126.080611 -237.919812) (xy 126.130004 -237.903764) (xy 126.181299 -237.895639) (xy 126.233233 -237.895639)
			(xy 126.284528 -237.903764) (xy 126.333921 -237.919812) (xy 126.380195 -237.94339) (xy 126.422211 -237.973916)
			(xy 126.458934 -238.010639) (xy 126.48946 -238.052655) (xy 126.513038 -238.098929) (xy 126.529086 -238.148322)
			(xy 126.537211 -238.199617) (xy 126.53772 -238.225584) (xy 126.537211 -238.251551) (xy 126.816867 -238.251551)
			(xy 126.816867 -238.199617) (xy 126.824992 -238.148322) (xy 126.84104 -238.098929) (xy 126.864618 -238.052655)
			(xy 126.895144 -238.010639) (xy 126.931867 -237.973916) (xy 126.973883 -237.94339) (xy 127.020157 -237.919812)
			(xy 127.06955 -237.903764) (xy 127.120845 -237.895639) (xy 127.172779 -237.895639) (xy 127.224074 -237.903764)
			(xy 127.273467 -237.919812) (xy 127.319741 -237.94339) (xy 127.361757 -237.973916) (xy 127.39848 -238.010639)
			(xy 127.429006 -238.052655) (xy 127.452584 -238.098929) (xy 127.468632 -238.148322) (xy 127.476757 -238.199617)
			(xy 127.477266 -238.225584) (xy 127.476757 -238.251551) (xy 127.468632 -238.302846) (xy 127.452584 -238.352239)
			(xy 127.429006 -238.398513) (xy 127.39848 -238.440529) (xy 127.361757 -238.477252) (xy 127.319741 -238.507778)
			(xy 127.273467 -238.531356) (xy 127.224074 -238.547404) (xy 127.172779 -238.555529) (xy 127.120845 -238.555529)
			(xy 127.06955 -238.547404) (xy 127.020157 -238.531356) (xy 126.973883 -238.507778) (xy 126.931867 -238.477252)
			(xy 126.895144 -238.440529) (xy 126.864618 -238.398513) (xy 126.84104 -238.352239) (xy 126.824992 -238.302846)
			(xy 126.816867 -238.251551) (xy 126.537211 -238.251551) (xy 126.529086 -238.302846) (xy 126.513038 -238.352239)
			(xy 126.48946 -238.398513) (xy 126.458934 -238.440529) (xy 126.422211 -238.477252) (xy 126.380195 -238.507778)
			(xy 126.333921 -238.531356) (xy 126.284528 -238.547404) (xy 126.233233 -238.555529) (xy 126.181299 -238.555529)
			(xy 126.130004 -238.547404) (xy 126.080611 -238.531356) (xy 126.034337 -238.507778) (xy 125.992321 -238.477252)
			(xy 125.955598 -238.440529) (xy 125.925072 -238.398513) (xy 125.901494 -238.352239) (xy 125.885446 -238.302846)
			(xy 125.877321 -238.251551) (xy 125.597157 -238.251551) (xy 125.589032 -238.302846) (xy 125.572984 -238.352239)
			(xy 125.549406 -238.398513) (xy 125.51888 -238.440529) (xy 125.482157 -238.477252) (xy 125.440141 -238.507778)
			(xy 125.393867 -238.531356) (xy 125.344474 -238.547404) (xy 125.293179 -238.555529) (xy 125.241245 -238.555529)
			(xy 125.18995 -238.547404) (xy 125.140557 -238.531356) (xy 125.094283 -238.507778) (xy 125.052267 -238.477252)
			(xy 125.015544 -238.440529) (xy 124.985018 -238.398513) (xy 124.96144 -238.352239) (xy 124.945392 -238.302846)
			(xy 124.937267 -238.251551) (xy 124.657357 -238.251551) (xy 124.649232 -238.302846) (xy 124.633184 -238.352239)
			(xy 124.609606 -238.398513) (xy 124.57908 -238.440529) (xy 124.542357 -238.477252) (xy 124.500341 -238.507778)
			(xy 124.454067 -238.531356) (xy 124.404674 -238.547404) (xy 124.353379 -238.555529) (xy 124.301445 -238.555529)
			(xy 124.25015 -238.547404) (xy 124.200757 -238.531356) (xy 124.154483 -238.507778) (xy 124.112467 -238.477252)
			(xy 124.075744 -238.440529) (xy 124.045218 -238.398513) (xy 124.02164 -238.352239) (xy 124.005592 -238.302846)
			(xy 123.997467 -238.251551) (xy 123.717557 -238.251551) (xy 123.709432 -238.302846) (xy 123.693384 -238.352239)
			(xy 123.669806 -238.398513) (xy 123.63928 -238.440529) (xy 123.602557 -238.477252) (xy 123.560541 -238.507778)
			(xy 123.514267 -238.531356) (xy 123.464874 -238.547404) (xy 123.413579 -238.555529) (xy 123.361645 -238.555529)
			(xy 123.31035 -238.547404) (xy 123.260957 -238.531356) (xy 123.214683 -238.507778) (xy 123.172667 -238.477252)
			(xy 123.135944 -238.440529) (xy 123.105418 -238.398513) (xy 123.08184 -238.352239) (xy 123.065792 -238.302846)
			(xy 123.057667 -238.251551) (xy 122.777757 -238.251551) (xy 122.769632 -238.302846) (xy 122.753584 -238.352239)
			(xy 122.730006 -238.398513) (xy 122.69948 -238.440529) (xy 122.662757 -238.477252) (xy 122.620741 -238.507778)
			(xy 122.574467 -238.531356) (xy 122.525074 -238.547404) (xy 122.473779 -238.555529) (xy 122.421845 -238.555529)
			(xy 122.37055 -238.547404) (xy 122.321157 -238.531356) (xy 122.274883 -238.507778) (xy 122.232867 -238.477252)
			(xy 122.196144 -238.440529) (xy 122.165618 -238.398513) (xy 122.14204 -238.352239) (xy 122.125992 -238.302846)
			(xy 122.117867 -238.251551) (xy 121.837957 -238.251551) (xy 121.829832 -238.302846) (xy 121.813784 -238.352239)
			(xy 121.790206 -238.398513) (xy 121.75968 -238.440529) (xy 121.722957 -238.477252) (xy 121.680941 -238.507778)
			(xy 121.634667 -238.531356) (xy 121.585274 -238.547404) (xy 121.533979 -238.555529) (xy 121.482045 -238.555529)
			(xy 121.43075 -238.547404) (xy 121.381357 -238.531356) (xy 121.335083 -238.507778) (xy 121.293067 -238.477252)
			(xy 121.256344 -238.440529) (xy 121.225818 -238.398513) (xy 121.20224 -238.352239) (xy 121.186192 -238.302846)
			(xy 121.178067 -238.251551) (xy 116.039197 -238.251551) (xy 116.181886 -238.39424) (xy 116.181886 -239.332566)
			(xy 117.084363 -239.332566) (xy 117.084363 -239.280634) (xy 117.092487 -239.22934) (xy 117.108535 -239.17995)
			(xy 117.132112 -239.133677) (xy 117.162637 -239.091663) (xy 117.199358 -239.05494) (xy 117.241372 -239.024415)
			(xy 117.287644 -239.000837) (xy 117.337035 -238.984789) (xy 117.388328 -238.976664) (xy 117.414294 -238.976154)
			(xy 117.438847 -238.976572) (xy 117.487415 -238.983818) (xy 117.534377 -238.998168) (xy 117.5787 -239.019304)
			(xy 117.61941 -239.046763) (xy 117.637814 -239.063022) (xy 117.649303 -239.072825) (xy 117.67654 -239.085839)
			(xy 117.706394 -239.090307) (xy 117.736248 -239.085839) (xy 117.763485 -239.072825) (xy 117.774974 -239.063022)
			(xy 117.793373 -239.046757) (xy 117.834079 -239.019289) (xy 117.878403 -238.998151) (xy 117.925369 -238.98381)
			(xy 117.97394 -238.976582) (xy 117.998494 -238.976154) (xy 118.023047 -238.976572) (xy 118.071615 -238.983818)
			(xy 118.118577 -238.998168) (xy 118.1629 -239.019304) (xy 118.20361 -239.046763) (xy 118.222014 -239.063022)
			(xy 118.233503 -239.072825) (xy 118.26074 -239.085839) (xy 118.290594 -239.090307) (xy 118.320448 -239.085839)
			(xy 118.347685 -239.072825) (xy 118.359174 -239.063022) (xy 118.377573 -239.046757) (xy 118.418279 -239.019289)
			(xy 118.462603 -238.998151) (xy 118.509569 -238.98381) (xy 118.55814 -238.976582) (xy 118.582694 -238.976154)
			(xy 118.609772 -238.976723) (xy 118.663199 -238.985575) (xy 118.714466 -239.003025) (xy 118.762199 -239.028607)
			(xy 118.805119 -239.061634) (xy 118.823994 -239.081056) (xy 118.83334 -239.090417) (xy 118.85576 -239.104432)
			(xy 118.881028 -239.112218) (xy 118.907449 -239.113253) (xy 118.933248 -239.107467) (xy 118.956696 -239.095249)
			(xy 118.966742 -239.086644) (xy 118.985098 -239.070422) (xy 119.02573 -239.04306) (xy 119.069957 -239.021997)
			(xy 119.11681 -239.007697) (xy 119.165261 -239.000471) (xy 119.189754 -239.00003) (xy 119.212959 -239.000479)
			(xy 119.258909 -239.007009) (xy 119.303497 -239.019891) (xy 119.34585 -239.038873) (xy 119.385137 -239.063583)
			(xy 119.403114 -239.078262) (xy 119.415014 -239.087632) (xy 119.442867 -239.099501) (xy 119.472974 -239.102697)
			(xy 119.502698 -239.09694) (xy 119.529434 -239.082735) (xy 119.540528 -239.07242) (xy 119.559233 -239.054504)
			(xy 119.601192 -239.024141) (xy 119.647373 -239.000693) (xy 119.696645 -238.984735) (xy 119.747804 -238.976657)
			(xy 119.7737 -238.976154) (xy 119.799632 -238.976673) (xy 119.850861 -238.984763) (xy 119.900196 -239.00076)
			(xy 119.946425 -239.02427) (xy 119.988411 -239.054716) (xy 120.007126 -239.072674) (xy 120.018254 -239.082959)
			(xy 120.044994 -239.097169) (xy 120.074729 -239.102891) (xy 120.104833 -239.099621) (xy 120.132645 -239.087646)
			(xy 120.14454 -239.078262) (xy 120.162547 -239.063576) (xy 120.201871 -239.038825) (xy 120.244272 -239.01982)
			(xy 120.288915 -239.006936) (xy 120.334922 -239.000427) (xy 120.358154 -239.00003) (xy 120.384124 -239.000541)
			(xy 120.435427 -239.00866) (xy 120.484827 -239.024705) (xy 120.531109 -239.048281) (xy 120.554629 -239.065367)
			(xy 121.648221 -239.065367) (xy 121.648221 -239.013433) (xy 121.656346 -238.962138) (xy 121.672394 -238.912745)
			(xy 121.695972 -238.866471) (xy 121.726498 -238.824455) (xy 121.763221 -238.787732) (xy 121.805237 -238.757206)
			(xy 121.851511 -238.733628) (xy 121.900904 -238.71758) (xy 121.952199 -238.709455) (xy 122.004133 -238.709455)
			(xy 122.055428 -238.71758) (xy 122.104821 -238.733628) (xy 122.151095 -238.757206) (xy 122.193111 -238.787732)
			(xy 122.229834 -238.824455) (xy 122.26036 -238.866471) (xy 122.283938 -238.912745) (xy 122.299986 -238.962138)
			(xy 122.308111 -239.013433) (xy 122.30862 -239.0394) (xy 122.308111 -239.065367) (xy 122.587767 -239.065367)
			(xy 122.587767 -239.013433) (xy 122.595892 -238.962138) (xy 122.61194 -238.912745) (xy 122.635518 -238.866471)
			(xy 122.666044 -238.824455) (xy 122.702767 -238.787732) (xy 122.744783 -238.757206) (xy 122.791057 -238.733628)
			(xy 122.84045 -238.71758) (xy 122.891745 -238.709455) (xy 122.943679 -238.709455) (xy 122.994974 -238.71758)
			(xy 123.044367 -238.733628) (xy 123.090641 -238.757206) (xy 123.132657 -238.787732) (xy 123.16938 -238.824455)
			(xy 123.199906 -238.866471) (xy 123.223484 -238.912745) (xy 123.239532 -238.962138) (xy 123.247657 -239.013433)
			(xy 123.248166 -239.0394) (xy 123.247657 -239.065367) (xy 123.527821 -239.065367) (xy 123.527821 -239.013433)
			(xy 123.535946 -238.962138) (xy 123.551994 -238.912745) (xy 123.575572 -238.866471) (xy 123.606098 -238.824455)
			(xy 123.642821 -238.787732) (xy 123.684837 -238.757206) (xy 123.731111 -238.733628) (xy 123.780504 -238.71758)
			(xy 123.831799 -238.709455) (xy 123.883733 -238.709455) (xy 123.935028 -238.71758) (xy 123.984421 -238.733628)
			(xy 124.030695 -238.757206) (xy 124.072711 -238.787732) (xy 124.109434 -238.824455) (xy 124.13996 -238.866471)
			(xy 124.163538 -238.912745) (xy 124.179586 -238.962138) (xy 124.187711 -239.013433) (xy 124.18822 -239.0394)
			(xy 124.187711 -239.065367) (xy 124.467621 -239.065367) (xy 124.467621 -239.013433) (xy 124.475746 -238.962138)
			(xy 124.491794 -238.912745) (xy 124.515372 -238.866471) (xy 124.545898 -238.824455) (xy 124.582621 -238.787732)
			(xy 124.624637 -238.757206) (xy 124.670911 -238.733628) (xy 124.720304 -238.71758) (xy 124.771599 -238.709455)
			(xy 124.823533 -238.709455) (xy 124.874828 -238.71758) (xy 124.924221 -238.733628) (xy 124.970495 -238.757206)
			(xy 125.012511 -238.787732) (xy 125.049234 -238.824455) (xy 125.07976 -238.866471) (xy 125.103338 -238.912745)
			(xy 125.119386 -238.962138) (xy 125.127511 -239.013433) (xy 125.12802 -239.0394) (xy 125.127511 -239.065367)
			(xy 125.407421 -239.065367) (xy 125.407421 -239.013433) (xy 125.415546 -238.962138) (xy 125.431594 -238.912745)
			(xy 125.455172 -238.866471) (xy 125.485698 -238.824455) (xy 125.522421 -238.787732) (xy 125.564437 -238.757206)
			(xy 125.610711 -238.733628) (xy 125.660104 -238.71758) (xy 125.711399 -238.709455) (xy 125.763333 -238.709455)
			(xy 125.814628 -238.71758) (xy 125.864021 -238.733628) (xy 125.910295 -238.757206) (xy 125.952311 -238.787732)
			(xy 125.989034 -238.824455) (xy 126.01956 -238.866471) (xy 126.043138 -238.912745) (xy 126.059186 -238.962138)
			(xy 126.067311 -239.013433) (xy 126.06782 -239.0394) (xy 126.067311 -239.065367) (xy 126.347221 -239.065367)
			(xy 126.347221 -239.013433) (xy 126.355346 -238.962138) (xy 126.371394 -238.912745) (xy 126.394972 -238.866471)
			(xy 126.425498 -238.824455) (xy 126.462221 -238.787732) (xy 126.504237 -238.757206) (xy 126.550511 -238.733628)
			(xy 126.599904 -238.71758) (xy 126.651199 -238.709455) (xy 126.703133 -238.709455) (xy 126.754428 -238.71758)
			(xy 126.803821 -238.733628) (xy 126.850095 -238.757206) (xy 126.892111 -238.787732) (xy 126.928834 -238.824455)
			(xy 126.95936 -238.866471) (xy 126.982938 -238.912745) (xy 126.998986 -238.962138) (xy 127.007111 -239.013433)
			(xy 127.00762 -239.0394) (xy 127.007111 -239.065367) (xy 126.998986 -239.116662) (xy 126.982938 -239.166055)
			(xy 126.95936 -239.212329) (xy 126.928834 -239.254345) (xy 126.892111 -239.291068) (xy 126.850095 -239.321594)
			(xy 126.803821 -239.345172) (xy 126.754428 -239.36122) (xy 126.703133 -239.369345) (xy 126.651199 -239.369345)
			(xy 126.599904 -239.36122) (xy 126.550511 -239.345172) (xy 126.504237 -239.321594) (xy 126.462221 -239.291068)
			(xy 126.425498 -239.254345) (xy 126.394972 -239.212329) (xy 126.371394 -239.166055) (xy 126.355346 -239.116662)
			(xy 126.347221 -239.065367) (xy 126.067311 -239.065367) (xy 126.059186 -239.116662) (xy 126.043138 -239.166055)
			(xy 126.01956 -239.212329) (xy 125.989034 -239.254345) (xy 125.952311 -239.291068) (xy 125.910295 -239.321594)
			(xy 125.864021 -239.345172) (xy 125.814628 -239.36122) (xy 125.763333 -239.369345) (xy 125.711399 -239.369345)
			(xy 125.660104 -239.36122) (xy 125.610711 -239.345172) (xy 125.564437 -239.321594) (xy 125.522421 -239.291068)
			(xy 125.485698 -239.254345) (xy 125.455172 -239.212329) (xy 125.431594 -239.166055) (xy 125.415546 -239.116662)
			(xy 125.407421 -239.065367) (xy 125.127511 -239.065367) (xy 125.119386 -239.116662) (xy 125.103338 -239.166055)
			(xy 125.07976 -239.212329) (xy 125.049234 -239.254345) (xy 125.012511 -239.291068) (xy 124.970495 -239.321594)
			(xy 124.924221 -239.345172) (xy 124.874828 -239.36122) (xy 124.823533 -239.369345) (xy 124.771599 -239.369345)
			(xy 124.720304 -239.36122) (xy 124.670911 -239.345172) (xy 124.624637 -239.321594) (xy 124.582621 -239.291068)
			(xy 124.545898 -239.254345) (xy 124.515372 -239.212329) (xy 124.491794 -239.166055) (xy 124.475746 -239.116662)
			(xy 124.467621 -239.065367) (xy 124.187711 -239.065367) (xy 124.179586 -239.116662) (xy 124.163538 -239.166055)
			(xy 124.13996 -239.212329) (xy 124.109434 -239.254345) (xy 124.072711 -239.291068) (xy 124.030695 -239.321594)
			(xy 123.984421 -239.345172) (xy 123.935028 -239.36122) (xy 123.883733 -239.369345) (xy 123.831799 -239.369345)
			(xy 123.780504 -239.36122) (xy 123.731111 -239.345172) (xy 123.684837 -239.321594) (xy 123.642821 -239.291068)
			(xy 123.606098 -239.254345) (xy 123.575572 -239.212329) (xy 123.551994 -239.166055) (xy 123.535946 -239.116662)
			(xy 123.527821 -239.065367) (xy 123.247657 -239.065367) (xy 123.239532 -239.116662) (xy 123.223484 -239.166055)
			(xy 123.199906 -239.212329) (xy 123.16938 -239.254345) (xy 123.132657 -239.291068) (xy 123.090641 -239.321594)
			(xy 123.044367 -239.345172) (xy 122.994974 -239.36122) (xy 122.943679 -239.369345) (xy 122.891745 -239.369345)
			(xy 122.84045 -239.36122) (xy 122.791057 -239.345172) (xy 122.744783 -239.321594) (xy 122.702767 -239.291068)
			(xy 122.666044 -239.254345) (xy 122.635518 -239.212329) (xy 122.61194 -239.166055) (xy 122.595892 -239.116662)
			(xy 122.587767 -239.065367) (xy 122.308111 -239.065367) (xy 122.299986 -239.116662) (xy 122.283938 -239.166055)
			(xy 122.26036 -239.212329) (xy 122.229834 -239.254345) (xy 122.193111 -239.291068) (xy 122.151095 -239.321594)
			(xy 122.104821 -239.345172) (xy 122.055428 -239.36122) (xy 122.004133 -239.369345) (xy 121.952199 -239.369345)
			(xy 121.900904 -239.36122) (xy 121.851511 -239.345172) (xy 121.805237 -239.321594) (xy 121.763221 -239.291068)
			(xy 121.726498 -239.254345) (xy 121.695972 -239.212329) (xy 121.672394 -239.166055) (xy 121.656346 -239.116662)
			(xy 121.648221 -239.065367) (xy 120.554629 -239.065367) (xy 120.573132 -239.078808) (xy 120.609862 -239.115533)
			(xy 120.640395 -239.157552) (xy 120.663977 -239.203831) (xy 120.680029 -239.253229) (xy 120.688155 -239.30453)
			(xy 120.688155 -239.35647) (xy 120.680029 -239.407771) (xy 120.663977 -239.457169) (xy 120.640395 -239.503448)
			(xy 120.609862 -239.545467) (xy 120.573132 -239.582192) (xy 120.531109 -239.612719) (xy 120.484827 -239.636295)
			(xy 120.435427 -239.65234) (xy 120.384124 -239.660459) (xy 120.358154 -239.660938) (xy 120.332221 -239.660451)
			(xy 120.28099 -239.652353) (xy 120.231655 -239.63635) (xy 120.185426 -239.612832) (xy 120.143441 -239.582379)
			(xy 120.124728 -239.564418) (xy 120.113637 -239.55409) (xy 120.086884 -239.539885) (xy 120.057138 -239.534171)
			(xy 120.027027 -239.537453) (xy 119.999209 -239.549439) (xy 119.987314 -239.55883) (xy 119.969323 -239.573536)
			(xy 119.929995 -239.598285) (xy 119.88759 -239.617286) (xy 119.842943 -239.630165) (xy 119.796934 -239.636669)
			(xy 119.7737 -239.637062) (xy 119.750494 -239.636642) (xy 119.704542 -239.630105) (xy 119.659954 -239.617216)
			(xy 119.617602 -239.598228) (xy 119.578317 -239.573512) (xy 119.56034 -239.55883) (xy 119.5484 -239.549516)
			(xy 119.520562 -239.537641) (xy 119.490468 -239.534434) (xy 119.460753 -239.540177) (xy 119.43402 -239.554366)
			(xy 119.422926 -239.564672) (xy 119.404212 -239.582578) (xy 119.362254 -239.612939) (xy 119.316075 -239.636387)
			(xy 119.266805 -239.652347) (xy 119.215649 -239.660431) (xy 119.189754 -239.660938) (xy 119.162675 -239.660405)
			(xy 119.109245 -239.651545) (xy 119.057978 -239.634086) (xy 119.010245 -239.608497) (xy 118.967328 -239.575462)
			(xy 118.948454 -239.556036) (xy 118.939155 -239.546626) (xy 118.916721 -239.532614) (xy 118.891441 -239.524835)
			(xy 118.865011 -239.523809) (xy 118.839204 -239.529606) (xy 118.815752 -239.541837) (xy 118.805706 -239.550448)
			(xy 118.78733 -239.566646) (xy 118.746703 -239.594012) (xy 118.702481 -239.615079) (xy 118.655633 -239.629386)
			(xy 118.607186 -239.636618) (xy 118.582694 -239.637062) (xy 118.558143 -239.636587) (xy 118.509578 -239.629354)
			(xy 118.462617 -239.615018) (xy 118.418293 -239.593894) (xy 118.37758 -239.566447) (xy 118.359174 -239.550194)
			(xy 118.347685 -239.540391) (xy 118.320448 -239.527377) (xy 118.290594 -239.522909) (xy 118.26074 -239.527377)
			(xy 118.233503 -239.540391) (xy 118.222014 -239.550194) (xy 118.203622 -239.566467) (xy 118.162914 -239.593933)
			(xy 118.118588 -239.615069) (xy 118.071621 -239.629409) (xy 118.023048 -239.636635) (xy 117.998494 -239.637062)
			(xy 117.973943 -239.636587) (xy 117.925378 -239.629354) (xy 117.878417 -239.615018) (xy 117.834093 -239.593894)
			(xy 117.79338 -239.566447) (xy 117.774974 -239.550194) (xy 117.763485 -239.540391) (xy 117.736248 -239.527377)
			(xy 117.706394 -239.522909) (xy 117.67654 -239.527377) (xy 117.649303 -239.540391) (xy 117.637814 -239.550194)
			(xy 117.619422 -239.566467) (xy 117.578714 -239.593933) (xy 117.534388 -239.615069) (xy 117.487421 -239.629409)
			(xy 117.438848 -239.636635) (xy 117.414294 -239.637062) (xy 117.388328 -239.636536) (xy 117.337035 -239.628411)
			(xy 117.287644 -239.612363) (xy 117.241372 -239.588785) (xy 117.199358 -239.55826) (xy 117.162637 -239.521537)
			(xy 117.132112 -239.479523) (xy 117.108535 -239.43325) (xy 117.092487 -239.38386) (xy 117.084363 -239.332566)
			(xy 116.181886 -239.332566) (xy 116.181886 -240.1062) (xy 116.780056 -240.70437) (xy 120.619266 -240.70437)
			(xy 120.619719 -240.679818) (xy 120.626957 -240.631252) (xy 120.641298 -240.58429) (xy 120.662426 -240.539966)
			(xy 120.689879 -240.499255) (xy 120.706134 -240.48085) (xy 120.71597 -240.469385) (xy 120.728986 -240.44214)
			(xy 120.733451 -240.412278) (xy 120.728973 -240.382417) (xy 120.715945 -240.355178) (xy 120.706134 -240.34369)
			(xy 120.689854 -240.325304) (xy 120.662388 -240.284595) (xy 120.641253 -240.240267) (xy 120.626915 -240.193299)
			(xy 120.619691 -240.144725) (xy 120.619266 -240.12017) (xy 120.619728 -240.094201) (xy 120.627857 -240.042903)
			(xy 120.643911 -239.993508) (xy 120.667494 -239.947233) (xy 120.698026 -239.905217) (xy 120.734755 -239.868493)
			(xy 120.776776 -239.837968) (xy 120.823055 -239.814392) (xy 120.872452 -239.798345) (xy 120.923751 -239.790224)
			(xy 120.94972 -239.789716) (xy 120.978853 -239.790327) (xy 121.036214 -239.800552) (xy 121.063766 -239.810036)
			(xy 121.076632 -239.814262) (xy 121.103602 -239.816582) (xy 121.130235 -239.81174) (xy 121.154663 -239.800075)
			(xy 121.175171 -239.782407) (xy 121.19032 -239.759974) (xy 121.195084 -239.747298) (xy 121.203795 -239.723102)
			(xy 121.227622 -239.677533) (xy 121.25822 -239.636204) (xy 121.294851 -239.600115) (xy 121.336631 -239.570135)
			(xy 121.38255 -239.54699) (xy 121.431501 -239.531238) (xy 121.482301 -239.523258) (xy 121.508012 -239.522762)
			(xy 121.53398 -239.52324) (xy 121.585276 -239.531366) (xy 121.634669 -239.547417) (xy 121.680944 -239.570996)
			(xy 121.72296 -239.601524) (xy 121.759683 -239.638249) (xy 121.79021 -239.680266) (xy 121.813788 -239.726542)
			(xy 121.829836 -239.775936) (xy 121.837961 -239.827232) (xy 121.837961 -239.879168) (xy 121.837959 -239.879183)
			(xy 122.118121 -239.879183) (xy 122.118121 -239.827249) (xy 122.126246 -239.775954) (xy 122.142294 -239.726561)
			(xy 122.165872 -239.680287) (xy 122.196398 -239.638271) (xy 122.233121 -239.601548) (xy 122.275137 -239.571022)
			(xy 122.321411 -239.547444) (xy 122.370804 -239.531396) (xy 122.422099 -239.523271) (xy 122.474033 -239.523271)
			(xy 122.525328 -239.531396) (xy 122.574721 -239.547444) (xy 122.620995 -239.571022) (xy 122.663011 -239.601548)
			(xy 122.699734 -239.638271) (xy 122.73026 -239.680287) (xy 122.753838 -239.726561) (xy 122.769886 -239.775954)
			(xy 122.778011 -239.827249) (xy 122.77852 -239.853216) (xy 122.778011 -239.879183) (xy 123.057667 -239.879183)
			(xy 123.057667 -239.827249) (xy 123.065792 -239.775954) (xy 123.08184 -239.726561) (xy 123.105418 -239.680287)
			(xy 123.135944 -239.638271) (xy 123.172667 -239.601548) (xy 123.214683 -239.571022) (xy 123.260957 -239.547444)
			(xy 123.31035 -239.531396) (xy 123.361645 -239.523271) (xy 123.413579 -239.523271) (xy 123.464874 -239.531396)
			(xy 123.514267 -239.547444) (xy 123.560541 -239.571022) (xy 123.602557 -239.601548) (xy 123.63928 -239.638271)
			(xy 123.669806 -239.680287) (xy 123.693384 -239.726561) (xy 123.709432 -239.775954) (xy 123.717557 -239.827249)
			(xy 123.718066 -239.853216) (xy 123.717557 -239.879183) (xy 123.997467 -239.879183) (xy 123.997467 -239.827249)
			(xy 124.005592 -239.775954) (xy 124.02164 -239.726561) (xy 124.045218 -239.680287) (xy 124.075744 -239.638271)
			(xy 124.112467 -239.601548) (xy 124.154483 -239.571022) (xy 124.200757 -239.547444) (xy 124.25015 -239.531396)
			(xy 124.301445 -239.523271) (xy 124.353379 -239.523271) (xy 124.404674 -239.531396) (xy 124.454067 -239.547444)
			(xy 124.500341 -239.571022) (xy 124.542357 -239.601548) (xy 124.57908 -239.638271) (xy 124.609606 -239.680287)
			(xy 124.633184 -239.726561) (xy 124.649232 -239.775954) (xy 124.657357 -239.827249) (xy 124.657866 -239.853216)
			(xy 124.657357 -239.879183) (xy 124.937521 -239.879183) (xy 124.937521 -239.827249) (xy 124.945646 -239.775954)
			(xy 124.961694 -239.726561) (xy 124.985272 -239.680287) (xy 125.015798 -239.638271) (xy 125.052521 -239.601548)
			(xy 125.094537 -239.571022) (xy 125.140811 -239.547444) (xy 125.190204 -239.531396) (xy 125.241499 -239.523271)
			(xy 125.293433 -239.523271) (xy 125.344728 -239.531396) (xy 125.394121 -239.547444) (xy 125.440395 -239.571022)
			(xy 125.482411 -239.601548) (xy 125.519134 -239.638271) (xy 125.54966 -239.680287) (xy 125.573238 -239.726561)
			(xy 125.589286 -239.775954) (xy 125.597411 -239.827249) (xy 125.59792 -239.853216) (xy 125.597411 -239.879183)
			(xy 125.877067 -239.879183) (xy 125.877067 -239.827249) (xy 125.885192 -239.775954) (xy 125.90124 -239.726561)
			(xy 125.924818 -239.680287) (xy 125.955344 -239.638271) (xy 125.992067 -239.601548) (xy 126.034083 -239.571022)
			(xy 126.080357 -239.547444) (xy 126.12975 -239.531396) (xy 126.181045 -239.523271) (xy 126.232979 -239.523271)
			(xy 126.284274 -239.531396) (xy 126.333667 -239.547444) (xy 126.379941 -239.571022) (xy 126.421957 -239.601548)
			(xy 126.45868 -239.638271) (xy 126.489206 -239.680287) (xy 126.512784 -239.726561) (xy 126.528832 -239.775954)
			(xy 126.536957 -239.827249) (xy 126.537466 -239.853216) (xy 126.536957 -239.879183) (xy 126.816867 -239.879183)
			(xy 126.816867 -239.827249) (xy 126.824992 -239.775954) (xy 126.84104 -239.726561) (xy 126.864618 -239.680287)
			(xy 126.895144 -239.638271) (xy 126.931867 -239.601548) (xy 126.973883 -239.571022) (xy 127.020157 -239.547444)
			(xy 127.06955 -239.531396) (xy 127.120845 -239.523271) (xy 127.172779 -239.523271) (xy 127.224074 -239.531396)
			(xy 127.273467 -239.547444) (xy 127.319741 -239.571022) (xy 127.361757 -239.601548) (xy 127.39848 -239.638271)
			(xy 127.429006 -239.680287) (xy 127.452584 -239.726561) (xy 127.468632 -239.775954) (xy 127.476757 -239.827249)
			(xy 127.477266 -239.853216) (xy 127.476757 -239.879183) (xy 127.468632 -239.930478) (xy 127.452584 -239.979871)
			(xy 127.429006 -240.026145) (xy 127.39848 -240.068161) (xy 127.361757 -240.104884) (xy 127.319741 -240.13541)
			(xy 127.273467 -240.158988) (xy 127.224074 -240.175036) (xy 127.172779 -240.183161) (xy 127.120845 -240.183161)
			(xy 127.06955 -240.175036) (xy 127.020157 -240.158988) (xy 126.973883 -240.13541) (xy 126.931867 -240.104884)
			(xy 126.895144 -240.068161) (xy 126.864618 -240.026145) (xy 126.84104 -239.979871) (xy 126.824992 -239.930478)
			(xy 126.816867 -239.879183) (xy 126.536957 -239.879183) (xy 126.528832 -239.930478) (xy 126.512784 -239.979871)
			(xy 126.489206 -240.026145) (xy 126.45868 -240.068161) (xy 126.421957 -240.104884) (xy 126.379941 -240.13541)
			(xy 126.333667 -240.158988) (xy 126.284274 -240.175036) (xy 126.232979 -240.183161) (xy 126.181045 -240.183161)
			(xy 126.12975 -240.175036) (xy 126.080357 -240.158988) (xy 126.034083 -240.13541) (xy 125.992067 -240.104884)
			(xy 125.955344 -240.068161) (xy 125.924818 -240.026145) (xy 125.90124 -239.979871) (xy 125.885192 -239.930478)
			(xy 125.877067 -239.879183) (xy 125.597411 -239.879183) (xy 125.589286 -239.930478) (xy 125.573238 -239.979871)
			(xy 125.54966 -240.026145) (xy 125.519134 -240.068161) (xy 125.482411 -240.104884) (xy 125.440395 -240.13541)
			(xy 125.394121 -240.158988) (xy 125.344728 -240.175036) (xy 125.293433 -240.183161) (xy 125.241499 -240.183161)
			(xy 125.190204 -240.175036) (xy 125.140811 -240.158988) (xy 125.094537 -240.13541) (xy 125.052521 -240.104884)
			(xy 125.015798 -240.068161) (xy 124.985272 -240.026145) (xy 124.961694 -239.979871) (xy 124.945646 -239.930478)
			(xy 124.937521 -239.879183) (xy 124.657357 -239.879183) (xy 124.649232 -239.930478) (xy 124.633184 -239.979871)
			(xy 124.609606 -240.026145) (xy 124.57908 -240.068161) (xy 124.542357 -240.104884) (xy 124.500341 -240.13541)
			(xy 124.454067 -240.158988) (xy 124.404674 -240.175036) (xy 124.353379 -240.183161) (xy 124.301445 -240.183161)
			(xy 124.25015 -240.175036) (xy 124.200757 -240.158988) (xy 124.154483 -240.13541) (xy 124.112467 -240.104884)
			(xy 124.075744 -240.068161) (xy 124.045218 -240.026145) (xy 124.02164 -239.979871) (xy 124.005592 -239.930478)
			(xy 123.997467 -239.879183) (xy 123.717557 -239.879183) (xy 123.709432 -239.930478) (xy 123.693384 -239.979871)
			(xy 123.669806 -240.026145) (xy 123.63928 -240.068161) (xy 123.602557 -240.104884) (xy 123.560541 -240.13541)
			(xy 123.514267 -240.158988) (xy 123.464874 -240.175036) (xy 123.413579 -240.183161) (xy 123.361645 -240.183161)
			(xy 123.31035 -240.175036) (xy 123.260957 -240.158988) (xy 123.214683 -240.13541) (xy 123.172667 -240.104884)
			(xy 123.135944 -240.068161) (xy 123.105418 -240.026145) (xy 123.08184 -239.979871) (xy 123.065792 -239.930478)
			(xy 123.057667 -239.879183) (xy 122.778011 -239.879183) (xy 122.769886 -239.930478) (xy 122.753838 -239.979871)
			(xy 122.73026 -240.026145) (xy 122.699734 -240.068161) (xy 122.663011 -240.104884) (xy 122.620995 -240.13541)
			(xy 122.574721 -240.158988) (xy 122.525328 -240.175036) (xy 122.474033 -240.183161) (xy 122.422099 -240.183161)
			(xy 122.370804 -240.175036) (xy 122.321411 -240.158988) (xy 122.275137 -240.13541) (xy 122.233121 -240.104884)
			(xy 122.196398 -240.068161) (xy 122.165872 -240.026145) (xy 122.142294 -239.979871) (xy 122.126246 -239.930478)
			(xy 122.118121 -239.879183) (xy 121.837959 -239.879183) (xy 121.829836 -239.930464) (xy 121.813788 -239.979858)
			(xy 121.79021 -240.026134) (xy 121.759683 -240.068151) (xy 121.72296 -240.104876) (xy 121.680944 -240.135404)
			(xy 121.634669 -240.158983) (xy 121.585276 -240.175034) (xy 121.53398 -240.18316) (xy 121.508012 -240.18367)
			(xy 121.47888 -240.183045) (xy 121.421519 -240.172829) (xy 121.393966 -240.16335) (xy 121.38112 -240.159057)
			(xy 121.354141 -240.156751) (xy 121.327502 -240.161608) (xy 121.303071 -240.173285) (xy 121.282562 -240.190965)
			(xy 121.267412 -240.213408) (xy 121.262648 -240.226088) (xy 121.25497 -240.247696) (xy 121.234467 -240.288715)
			(xy 121.208492 -240.326507) (xy 121.193306 -240.34369) (xy 121.183533 -240.355203) (xy 121.170519 -240.382432)
			(xy 121.166046 -240.412278) (xy 121.170506 -240.442126) (xy 121.183508 -240.46936) (xy 121.193306 -240.48085)
			(xy 121.209564 -240.499255) (xy 121.237032 -240.539959) (xy 121.258171 -240.584282) (xy 121.272513 -240.631247)
			(xy 121.279744 -240.679817) (xy 121.279979 -240.693253) (xy 121.648221 -240.693253) (xy 121.648221 -240.641319)
			(xy 121.656346 -240.590024) (xy 121.672394 -240.540631) (xy 121.695972 -240.494357) (xy 121.726498 -240.452341)
			(xy 121.763221 -240.415618) (xy 121.805237 -240.385092) (xy 121.851511 -240.361514) (xy 121.900904 -240.345466)
			(xy 121.952199 -240.337341) (xy 122.004133 -240.337341) (xy 122.055428 -240.345466) (xy 122.104821 -240.361514)
			(xy 122.151095 -240.385092) (xy 122.193111 -240.415618) (xy 122.229834 -240.452341) (xy 122.26036 -240.494357)
			(xy 122.283938 -240.540631) (xy 122.299986 -240.590024) (xy 122.308111 -240.641319) (xy 122.30862 -240.667286)
			(xy 122.308111 -240.693253) (xy 122.587767 -240.693253) (xy 122.587767 -240.641319) (xy 122.595892 -240.590024)
			(xy 122.61194 -240.540631) (xy 122.635518 -240.494357) (xy 122.666044 -240.452341) (xy 122.702767 -240.415618)
			(xy 122.744783 -240.385092) (xy 122.791057 -240.361514) (xy 122.84045 -240.345466) (xy 122.891745 -240.337341)
			(xy 122.943679 -240.337341) (xy 122.994974 -240.345466) (xy 123.044367 -240.361514) (xy 123.090641 -240.385092)
			(xy 123.132657 -240.415618) (xy 123.16938 -240.452341) (xy 123.199906 -240.494357) (xy 123.223484 -240.540631)
			(xy 123.239532 -240.590024) (xy 123.247657 -240.641319) (xy 123.248166 -240.667286) (xy 123.247657 -240.693253)
			(xy 123.527821 -240.693253) (xy 123.527821 -240.641319) (xy 123.535946 -240.590024) (xy 123.551994 -240.540631)
			(xy 123.575572 -240.494357) (xy 123.606098 -240.452341) (xy 123.642821 -240.415618) (xy 123.684837 -240.385092)
			(xy 123.731111 -240.361514) (xy 123.780504 -240.345466) (xy 123.831799 -240.337341) (xy 123.883733 -240.337341)
			(xy 123.935028 -240.345466) (xy 123.984421 -240.361514) (xy 124.030695 -240.385092) (xy 124.072711 -240.415618)
			(xy 124.109434 -240.452341) (xy 124.13996 -240.494357) (xy 124.163538 -240.540631) (xy 124.179586 -240.590024)
			(xy 124.187711 -240.641319) (xy 124.18822 -240.667286) (xy 124.187711 -240.693253) (xy 124.467621 -240.693253)
			(xy 124.467621 -240.641319) (xy 124.475746 -240.590024) (xy 124.491794 -240.540631) (xy 124.515372 -240.494357)
			(xy 124.545898 -240.452341) (xy 124.582621 -240.415618) (xy 124.624637 -240.385092) (xy 124.670911 -240.361514)
			(xy 124.720304 -240.345466) (xy 124.771599 -240.337341) (xy 124.823533 -240.337341) (xy 124.874828 -240.345466)
			(xy 124.924221 -240.361514) (xy 124.970495 -240.385092) (xy 125.012511 -240.415618) (xy 125.049234 -240.452341)
			(xy 125.07976 -240.494357) (xy 125.103338 -240.540631) (xy 125.119386 -240.590024) (xy 125.127511 -240.641319)
			(xy 125.12802 -240.667286) (xy 125.127511 -240.693253) (xy 125.407167 -240.693253) (xy 125.407167 -240.641319)
			(xy 125.415292 -240.590024) (xy 125.43134 -240.540631) (xy 125.454918 -240.494357) (xy 125.485444 -240.452341)
			(xy 125.522167 -240.415618) (xy 125.564183 -240.385092) (xy 125.610457 -240.361514) (xy 125.65985 -240.345466)
			(xy 125.711145 -240.337341) (xy 125.763079 -240.337341) (xy 125.814374 -240.345466) (xy 125.863767 -240.361514)
			(xy 125.910041 -240.385092) (xy 125.952057 -240.415618) (xy 125.98878 -240.452341) (xy 126.019306 -240.494357)
			(xy 126.042884 -240.540631) (xy 126.058932 -240.590024) (xy 126.067057 -240.641319) (xy 126.067566 -240.667286)
			(xy 126.067057 -240.693253) (xy 126.347221 -240.693253) (xy 126.347221 -240.641319) (xy 126.355346 -240.590024)
			(xy 126.371394 -240.540631) (xy 126.394972 -240.494357) (xy 126.425498 -240.452341) (xy 126.462221 -240.415618)
			(xy 126.504237 -240.385092) (xy 126.550511 -240.361514) (xy 126.599904 -240.345466) (xy 126.651199 -240.337341)
			(xy 126.703133 -240.337341) (xy 126.754428 -240.345466) (xy 126.803821 -240.361514) (xy 126.850095 -240.385092)
			(xy 126.892111 -240.415618) (xy 126.928834 -240.452341) (xy 126.95936 -240.494357) (xy 126.982938 -240.540631)
			(xy 126.998986 -240.590024) (xy 127.007111 -240.641319) (xy 127.00762 -240.667286) (xy 127.007111 -240.693253)
			(xy 126.998986 -240.744548) (xy 126.982938 -240.793941) (xy 126.95936 -240.840215) (xy 126.928834 -240.882231)
			(xy 126.892111 -240.918954) (xy 126.850095 -240.94948) (xy 126.803821 -240.973058) (xy 126.754428 -240.989106)
			(xy 126.703133 -240.997231) (xy 126.651199 -240.997231) (xy 126.599904 -240.989106) (xy 126.550511 -240.973058)
			(xy 126.504237 -240.94948) (xy 126.462221 -240.918954) (xy 126.425498 -240.882231) (xy 126.394972 -240.840215)
			(xy 126.371394 -240.793941) (xy 126.355346 -240.744548) (xy 126.347221 -240.693253) (xy 126.067057 -240.693253)
			(xy 126.058932 -240.744548) (xy 126.042884 -240.793941) (xy 126.019306 -240.840215) (xy 125.98878 -240.882231)
			(xy 125.952057 -240.918954) (xy 125.910041 -240.94948) (xy 125.863767 -240.973058) (xy 125.814374 -240.989106)
			(xy 125.763079 -240.997231) (xy 125.711145 -240.997231) (xy 125.65985 -240.989106) (xy 125.610457 -240.973058)
			(xy 125.564183 -240.94948) (xy 125.522167 -240.918954) (xy 125.485444 -240.882231) (xy 125.454918 -240.840215)
			(xy 125.43134 -240.793941) (xy 125.415292 -240.744548) (xy 125.407167 -240.693253) (xy 125.127511 -240.693253)
			(xy 125.119386 -240.744548) (xy 125.103338 -240.793941) (xy 125.07976 -240.840215) (xy 125.049234 -240.882231)
			(xy 125.012511 -240.918954) (xy 124.970495 -240.94948) (xy 124.924221 -240.973058) (xy 124.874828 -240.989106)
			(xy 124.823533 -240.997231) (xy 124.771599 -240.997231) (xy 124.720304 -240.989106) (xy 124.670911 -240.973058)
			(xy 124.624637 -240.94948) (xy 124.582621 -240.918954) (xy 124.545898 -240.882231) (xy 124.515372 -240.840215)
			(xy 124.491794 -240.793941) (xy 124.475746 -240.744548) (xy 124.467621 -240.693253) (xy 124.187711 -240.693253)
			(xy 124.179586 -240.744548) (xy 124.163538 -240.793941) (xy 124.13996 -240.840215) (xy 124.109434 -240.882231)
			(xy 124.072711 -240.918954) (xy 124.030695 -240.94948) (xy 123.984421 -240.973058) (xy 123.935028 -240.989106)
			(xy 123.883733 -240.997231) (xy 123.831799 -240.997231) (xy 123.780504 -240.989106) (xy 123.731111 -240.973058)
			(xy 123.684837 -240.94948) (xy 123.642821 -240.918954) (xy 123.606098 -240.882231) (xy 123.575572 -240.840215)
			(xy 123.551994 -240.793941) (xy 123.535946 -240.744548) (xy 123.527821 -240.693253) (xy 123.247657 -240.693253)
			(xy 123.239532 -240.744548) (xy 123.223484 -240.793941) (xy 123.199906 -240.840215) (xy 123.16938 -240.882231)
			(xy 123.132657 -240.918954) (xy 123.090641 -240.94948) (xy 123.044367 -240.973058) (xy 122.994974 -240.989106)
			(xy 122.943679 -240.997231) (xy 122.891745 -240.997231) (xy 122.84045 -240.989106) (xy 122.791057 -240.973058)
			(xy 122.744783 -240.94948) (xy 122.702767 -240.918954) (xy 122.666044 -240.882231) (xy 122.635518 -240.840215)
			(xy 122.61194 -240.793941) (xy 122.595892 -240.744548) (xy 122.587767 -240.693253) (xy 122.308111 -240.693253)
			(xy 122.299986 -240.744548) (xy 122.283938 -240.793941) (xy 122.26036 -240.840215) (xy 122.229834 -240.882231)
			(xy 122.193111 -240.918954) (xy 122.151095 -240.94948) (xy 122.104821 -240.973058) (xy 122.055428 -240.989106)
			(xy 122.004133 -240.997231) (xy 121.952199 -240.997231) (xy 121.900904 -240.989106) (xy 121.851511 -240.973058)
			(xy 121.805237 -240.94948) (xy 121.763221 -240.918954) (xy 121.726498 -240.882231) (xy 121.695972 -240.840215)
			(xy 121.672394 -240.793941) (xy 121.656346 -240.744548) (xy 121.648221 -240.693253) (xy 121.279979 -240.693253)
			(xy 121.280174 -240.70437) (xy 121.279665 -240.730337) (xy 121.27154 -240.781632) (xy 121.255492 -240.831025)
			(xy 121.231914 -240.877299) (xy 121.201388 -240.919315) (xy 121.164665 -240.956038) (xy 121.122649 -240.986564)
			(xy 121.076375 -241.010142) (xy 121.026982 -241.02619) (xy 120.975687 -241.034315) (xy 120.923753 -241.034315)
			(xy 120.872458 -241.02619) (xy 120.823065 -241.010142) (xy 120.776791 -240.986564) (xy 120.734775 -240.956038)
			(xy 120.698052 -240.919315) (xy 120.667526 -240.877299) (xy 120.643948 -240.831025) (xy 120.6279 -240.781632)
			(xy 120.619775 -240.730337) (xy 120.619266 -240.70437) (xy 116.780056 -240.70437) (xy 117.582755 -241.507069)
			(xy 121.178067 -241.507069) (xy 121.178067 -241.455135) (xy 121.186192 -241.40384) (xy 121.20224 -241.354447)
			(xy 121.225818 -241.308173) (xy 121.256344 -241.266157) (xy 121.293067 -241.229434) (xy 121.335083 -241.198908)
			(xy 121.381357 -241.17533) (xy 121.43075 -241.159282) (xy 121.482045 -241.151157) (xy 121.533979 -241.151157)
			(xy 121.585274 -241.159282) (xy 121.634667 -241.17533) (xy 121.680941 -241.198908) (xy 121.722957 -241.229434)
			(xy 121.75968 -241.266157) (xy 121.790206 -241.308173) (xy 121.813784 -241.354447) (xy 121.829832 -241.40384)
			(xy 121.837957 -241.455135) (xy 121.838466 -241.481102) (xy 121.837957 -241.507069) (xy 122.118121 -241.507069)
			(xy 122.118121 -241.455135) (xy 122.126246 -241.40384) (xy 122.142294 -241.354447) (xy 122.165872 -241.308173)
			(xy 122.196398 -241.266157) (xy 122.233121 -241.229434) (xy 122.275137 -241.198908) (xy 122.321411 -241.17533)
			(xy 122.370804 -241.159282) (xy 122.422099 -241.151157) (xy 122.474033 -241.151157) (xy 122.525328 -241.159282)
			(xy 122.574721 -241.17533) (xy 122.620995 -241.198908) (xy 122.663011 -241.229434) (xy 122.699734 -241.266157)
			(xy 122.73026 -241.308173) (xy 122.753838 -241.354447) (xy 122.769886 -241.40384) (xy 122.778011 -241.455135)
			(xy 122.77852 -241.481102) (xy 122.778011 -241.507069) (xy 123.057667 -241.507069) (xy 123.057667 -241.455135)
			(xy 123.065792 -241.40384) (xy 123.08184 -241.354447) (xy 123.105418 -241.308173) (xy 123.135944 -241.266157)
			(xy 123.172667 -241.229434) (xy 123.214683 -241.198908) (xy 123.260957 -241.17533) (xy 123.31035 -241.159282)
			(xy 123.361645 -241.151157) (xy 123.413579 -241.151157) (xy 123.464874 -241.159282) (xy 123.514267 -241.17533)
			(xy 123.560541 -241.198908) (xy 123.602557 -241.229434) (xy 123.63928 -241.266157) (xy 123.669806 -241.308173)
			(xy 123.693384 -241.354447) (xy 123.709432 -241.40384) (xy 123.717557 -241.455135) (xy 123.718066 -241.481102)
			(xy 123.717557 -241.507069) (xy 123.997467 -241.507069) (xy 123.997467 -241.455135) (xy 124.005592 -241.40384)
			(xy 124.02164 -241.354447) (xy 124.045218 -241.308173) (xy 124.075744 -241.266157) (xy 124.112467 -241.229434)
			(xy 124.154483 -241.198908) (xy 124.200757 -241.17533) (xy 124.25015 -241.159282) (xy 124.301445 -241.151157)
			(xy 124.353379 -241.151157) (xy 124.404674 -241.159282) (xy 124.454067 -241.17533) (xy 124.500341 -241.198908)
			(xy 124.542357 -241.229434) (xy 124.57908 -241.266157) (xy 124.609606 -241.308173) (xy 124.633184 -241.354447)
			(xy 124.649232 -241.40384) (xy 124.657357 -241.455135) (xy 124.657866 -241.481102) (xy 124.657357 -241.507069)
			(xy 124.937267 -241.507069) (xy 124.937267 -241.455135) (xy 124.945392 -241.40384) (xy 124.96144 -241.354447)
			(xy 124.985018 -241.308173) (xy 125.015544 -241.266157) (xy 125.052267 -241.229434) (xy 125.094283 -241.198908)
			(xy 125.140557 -241.17533) (xy 125.18995 -241.159282) (xy 125.241245 -241.151157) (xy 125.293179 -241.151157)
			(xy 125.344474 -241.159282) (xy 125.393867 -241.17533) (xy 125.440141 -241.198908) (xy 125.482157 -241.229434)
			(xy 125.51888 -241.266157) (xy 125.549406 -241.308173) (xy 125.572984 -241.354447) (xy 125.589032 -241.40384)
			(xy 125.597157 -241.455135) (xy 125.597666 -241.481102) (xy 125.597157 -241.507069) (xy 125.877067 -241.507069)
			(xy 125.877067 -241.455135) (xy 125.885192 -241.40384) (xy 125.90124 -241.354447) (xy 125.924818 -241.308173)
			(xy 125.955344 -241.266157) (xy 125.992067 -241.229434) (xy 126.034083 -241.198908) (xy 126.080357 -241.17533)
			(xy 126.12975 -241.159282) (xy 126.181045 -241.151157) (xy 126.232979 -241.151157) (xy 126.284274 -241.159282)
			(xy 126.333667 -241.17533) (xy 126.379941 -241.198908) (xy 126.421957 -241.229434) (xy 126.45868 -241.266157)
			(xy 126.489206 -241.308173) (xy 126.512784 -241.354447) (xy 126.528832 -241.40384) (xy 126.536957 -241.455135)
			(xy 126.537466 -241.481102) (xy 126.536957 -241.507069) (xy 126.816867 -241.507069) (xy 126.816867 -241.455135)
			(xy 126.824992 -241.40384) (xy 126.84104 -241.354447) (xy 126.864618 -241.308173) (xy 126.895144 -241.266157)
			(xy 126.931867 -241.229434) (xy 126.973883 -241.198908) (xy 127.020157 -241.17533) (xy 127.06955 -241.159282)
			(xy 127.120845 -241.151157) (xy 127.172779 -241.151157) (xy 127.224074 -241.159282) (xy 127.273467 -241.17533)
			(xy 127.319741 -241.198908) (xy 127.361757 -241.229434) (xy 127.39848 -241.266157) (xy 127.429006 -241.308173)
			(xy 127.452584 -241.354447) (xy 127.468632 -241.40384) (xy 127.476757 -241.455135) (xy 127.477266 -241.481102)
			(xy 127.476757 -241.507069) (xy 127.468632 -241.558364) (xy 127.452584 -241.607757) (xy 127.429006 -241.654031)
			(xy 127.39848 -241.696047) (xy 127.361757 -241.73277) (xy 127.319741 -241.763296) (xy 127.273467 -241.786874)
			(xy 127.224074 -241.802922) (xy 127.172779 -241.811047) (xy 127.120845 -241.811047) (xy 127.06955 -241.802922)
			(xy 127.020157 -241.786874) (xy 126.973883 -241.763296) (xy 126.931867 -241.73277) (xy 126.895144 -241.696047)
			(xy 126.864618 -241.654031) (xy 126.84104 -241.607757) (xy 126.824992 -241.558364) (xy 126.816867 -241.507069)
			(xy 126.536957 -241.507069) (xy 126.528832 -241.558364) (xy 126.512784 -241.607757) (xy 126.489206 -241.654031)
			(xy 126.45868 -241.696047) (xy 126.421957 -241.73277) (xy 126.379941 -241.763296) (xy 126.333667 -241.786874)
			(xy 126.284274 -241.802922) (xy 126.232979 -241.811047) (xy 126.181045 -241.811047) (xy 126.12975 -241.802922)
			(xy 126.080357 -241.786874) (xy 126.034083 -241.763296) (xy 125.992067 -241.73277) (xy 125.955344 -241.696047)
			(xy 125.924818 -241.654031) (xy 125.90124 -241.607757) (xy 125.885192 -241.558364) (xy 125.877067 -241.507069)
			(xy 125.597157 -241.507069) (xy 125.589032 -241.558364) (xy 125.572984 -241.607757) (xy 125.549406 -241.654031)
			(xy 125.51888 -241.696047) (xy 125.482157 -241.73277) (xy 125.440141 -241.763296) (xy 125.393867 -241.786874)
			(xy 125.344474 -241.802922) (xy 125.293179 -241.811047) (xy 125.241245 -241.811047) (xy 125.18995 -241.802922)
			(xy 125.140557 -241.786874) (xy 125.094283 -241.763296) (xy 125.052267 -241.73277) (xy 125.015544 -241.696047)
			(xy 124.985018 -241.654031) (xy 124.96144 -241.607757) (xy 124.945392 -241.558364) (xy 124.937267 -241.507069)
			(xy 124.657357 -241.507069) (xy 124.649232 -241.558364) (xy 124.633184 -241.607757) (xy 124.609606 -241.654031)
			(xy 124.57908 -241.696047) (xy 124.542357 -241.73277) (xy 124.500341 -241.763296) (xy 124.454067 -241.786874)
			(xy 124.404674 -241.802922) (xy 124.353379 -241.811047) (xy 124.301445 -241.811047) (xy 124.25015 -241.802922)
			(xy 124.200757 -241.786874) (xy 124.154483 -241.763296) (xy 124.112467 -241.73277) (xy 124.075744 -241.696047)
			(xy 124.045218 -241.654031) (xy 124.02164 -241.607757) (xy 124.005592 -241.558364) (xy 123.997467 -241.507069)
			(xy 123.717557 -241.507069) (xy 123.709432 -241.558364) (xy 123.693384 -241.607757) (xy 123.669806 -241.654031)
			(xy 123.63928 -241.696047) (xy 123.602557 -241.73277) (xy 123.560541 -241.763296) (xy 123.514267 -241.786874)
			(xy 123.464874 -241.802922) (xy 123.413579 -241.811047) (xy 123.361645 -241.811047) (xy 123.31035 -241.802922)
			(xy 123.260957 -241.786874) (xy 123.214683 -241.763296) (xy 123.172667 -241.73277) (xy 123.135944 -241.696047)
			(xy 123.105418 -241.654031) (xy 123.08184 -241.607757) (xy 123.065792 -241.558364) (xy 123.057667 -241.507069)
			(xy 122.778011 -241.507069) (xy 122.769886 -241.558364) (xy 122.753838 -241.607757) (xy 122.73026 -241.654031)
			(xy 122.699734 -241.696047) (xy 122.663011 -241.73277) (xy 122.620995 -241.763296) (xy 122.574721 -241.786874)
			(xy 122.525328 -241.802922) (xy 122.474033 -241.811047) (xy 122.422099 -241.811047) (xy 122.370804 -241.802922)
			(xy 122.321411 -241.786874) (xy 122.275137 -241.763296) (xy 122.233121 -241.73277) (xy 122.196398 -241.696047)
			(xy 122.165872 -241.654031) (xy 122.142294 -241.607757) (xy 122.126246 -241.558364) (xy 122.118121 -241.507069)
			(xy 121.837957 -241.507069) (xy 121.829832 -241.558364) (xy 121.813784 -241.607757) (xy 121.790206 -241.654031)
			(xy 121.75968 -241.696047) (xy 121.722957 -241.73277) (xy 121.680941 -241.763296) (xy 121.634667 -241.786874)
			(xy 121.585274 -241.802922) (xy 121.533979 -241.811047) (xy 121.482045 -241.811047) (xy 121.43075 -241.802922)
			(xy 121.381357 -241.786874) (xy 121.335083 -241.763296) (xy 121.293067 -241.73277) (xy 121.256344 -241.696047)
			(xy 121.225818 -241.654031) (xy 121.20224 -241.607757) (xy 121.186192 -241.558364) (xy 121.178067 -241.507069)
			(xy 117.582755 -241.507069) (xy 118.396571 -242.320885) (xy 121.648221 -242.320885) (xy 121.648221 -242.268951)
			(xy 121.656346 -242.217656) (xy 121.672394 -242.168263) (xy 121.695972 -242.121989) (xy 121.726498 -242.079973)
			(xy 121.763221 -242.04325) (xy 121.805237 -242.012724) (xy 121.851511 -241.989146) (xy 121.900904 -241.973098)
			(xy 121.952199 -241.964973) (xy 122.004133 -241.964973) (xy 122.055428 -241.973098) (xy 122.104821 -241.989146)
			(xy 122.151095 -242.012724) (xy 122.193111 -242.04325) (xy 122.229834 -242.079973) (xy 122.26036 -242.121989)
			(xy 122.283938 -242.168263) (xy 122.299986 -242.217656) (xy 122.308111 -242.268951) (xy 122.30862 -242.294918)
			(xy 122.308111 -242.320885) (xy 122.588021 -242.320885) (xy 122.588021 -242.268951) (xy 122.596146 -242.217656)
			(xy 122.612194 -242.168263) (xy 122.635772 -242.121989) (xy 122.666298 -242.079973) (xy 122.703021 -242.04325)
			(xy 122.745037 -242.012724) (xy 122.791311 -241.989146) (xy 122.840704 -241.973098) (xy 122.891999 -241.964973)
			(xy 122.943933 -241.964973) (xy 122.995228 -241.973098) (xy 123.044621 -241.989146) (xy 123.090895 -242.012724)
			(xy 123.132911 -242.04325) (xy 123.169634 -242.079973) (xy 123.20016 -242.121989) (xy 123.223738 -242.168263)
			(xy 123.239786 -242.217656) (xy 123.247911 -242.268951) (xy 123.24842 -242.294918) (xy 123.247911 -242.320885)
			(xy 123.527821 -242.320885) (xy 123.527821 -242.268951) (xy 123.535946 -242.217656) (xy 123.551994 -242.168263)
			(xy 123.575572 -242.121989) (xy 123.606098 -242.079973) (xy 123.642821 -242.04325) (xy 123.684837 -242.012724)
			(xy 123.731111 -241.989146) (xy 123.780504 -241.973098) (xy 123.831799 -241.964973) (xy 123.883733 -241.964973)
			(xy 123.935028 -241.973098) (xy 123.984421 -241.989146) (xy 124.030695 -242.012724) (xy 124.072711 -242.04325)
			(xy 124.109434 -242.079973) (xy 124.13996 -242.121989) (xy 124.163538 -242.168263) (xy 124.179586 -242.217656)
			(xy 124.187711 -242.268951) (xy 124.18822 -242.294918) (xy 124.187711 -242.320885) (xy 124.467621 -242.320885)
			(xy 124.467621 -242.268951) (xy 124.475746 -242.217656) (xy 124.491794 -242.168263) (xy 124.515372 -242.121989)
			(xy 124.545898 -242.079973) (xy 124.582621 -242.04325) (xy 124.624637 -242.012724) (xy 124.670911 -241.989146)
			(xy 124.720304 -241.973098) (xy 124.771599 -241.964973) (xy 124.823533 -241.964973) (xy 124.874828 -241.973098)
			(xy 124.924221 -241.989146) (xy 124.970495 -242.012724) (xy 125.012511 -242.04325) (xy 125.049234 -242.079973)
			(xy 125.07976 -242.121989) (xy 125.103338 -242.168263) (xy 125.119386 -242.217656) (xy 125.127511 -242.268951)
			(xy 125.12802 -242.294918) (xy 125.127511 -242.320885) (xy 125.407421 -242.320885) (xy 125.407421 -242.268951)
			(xy 125.415546 -242.217656) (xy 125.431594 -242.168263) (xy 125.455172 -242.121989) (xy 125.485698 -242.079973)
			(xy 125.522421 -242.04325) (xy 125.564437 -242.012724) (xy 125.610711 -241.989146) (xy 125.660104 -241.973098)
			(xy 125.711399 -241.964973) (xy 125.763333 -241.964973) (xy 125.814628 -241.973098) (xy 125.864021 -241.989146)
			(xy 125.910295 -242.012724) (xy 125.952311 -242.04325) (xy 125.989034 -242.079973) (xy 126.01956 -242.121989)
			(xy 126.043138 -242.168263) (xy 126.059186 -242.217656) (xy 126.067311 -242.268951) (xy 126.06782 -242.294918)
			(xy 126.067311 -242.320885) (xy 126.347221 -242.320885) (xy 126.347221 -242.268951) (xy 126.355346 -242.217656)
			(xy 126.371394 -242.168263) (xy 126.394972 -242.121989) (xy 126.425498 -242.079973) (xy 126.462221 -242.04325)
			(xy 126.504237 -242.012724) (xy 126.550511 -241.989146) (xy 126.599904 -241.973098) (xy 126.651199 -241.964973)
			(xy 126.703133 -241.964973) (xy 126.754428 -241.973098) (xy 126.803821 -241.989146) (xy 126.850095 -242.012724)
			(xy 126.892111 -242.04325) (xy 126.928834 -242.079973) (xy 126.95936 -242.121989) (xy 126.982938 -242.168263)
			(xy 126.998986 -242.217656) (xy 127.007111 -242.268951) (xy 127.00762 -242.294918) (xy 127.007111 -242.320885)
			(xy 126.998986 -242.37218) (xy 126.982938 -242.421573) (xy 126.95936 -242.467847) (xy 126.928834 -242.509863)
			(xy 126.892111 -242.546586) (xy 126.850095 -242.577112) (xy 126.803821 -242.60069) (xy 126.754428 -242.616738)
			(xy 126.703133 -242.624863) (xy 126.651199 -242.624863) (xy 126.599904 -242.616738) (xy 126.550511 -242.60069)
			(xy 126.504237 -242.577112) (xy 126.462221 -242.546586) (xy 126.425498 -242.509863) (xy 126.394972 -242.467847)
			(xy 126.371394 -242.421573) (xy 126.355346 -242.37218) (xy 126.347221 -242.320885) (xy 126.067311 -242.320885)
			(xy 126.059186 -242.37218) (xy 126.043138 -242.421573) (xy 126.01956 -242.467847) (xy 125.989034 -242.509863)
			(xy 125.952311 -242.546586) (xy 125.910295 -242.577112) (xy 125.864021 -242.60069) (xy 125.814628 -242.616738)
			(xy 125.763333 -242.624863) (xy 125.711399 -242.624863) (xy 125.660104 -242.616738) (xy 125.610711 -242.60069)
			(xy 125.564437 -242.577112) (xy 125.522421 -242.546586) (xy 125.485698 -242.509863) (xy 125.455172 -242.467847)
			(xy 125.431594 -242.421573) (xy 125.415546 -242.37218) (xy 125.407421 -242.320885) (xy 125.127511 -242.320885)
			(xy 125.119386 -242.37218) (xy 125.103338 -242.421573) (xy 125.07976 -242.467847) (xy 125.049234 -242.509863)
			(xy 125.012511 -242.546586) (xy 124.970495 -242.577112) (xy 124.924221 -242.60069) (xy 124.874828 -242.616738)
			(xy 124.823533 -242.624863) (xy 124.771599 -242.624863) (xy 124.720304 -242.616738) (xy 124.670911 -242.60069)
			(xy 124.624637 -242.577112) (xy 124.582621 -242.546586) (xy 124.545898 -242.509863) (xy 124.515372 -242.467847)
			(xy 124.491794 -242.421573) (xy 124.475746 -242.37218) (xy 124.467621 -242.320885) (xy 124.187711 -242.320885)
			(xy 124.179586 -242.37218) (xy 124.163538 -242.421573) (xy 124.13996 -242.467847) (xy 124.109434 -242.509863)
			(xy 124.072711 -242.546586) (xy 124.030695 -242.577112) (xy 123.984421 -242.60069) (xy 123.935028 -242.616738)
			(xy 123.883733 -242.624863) (xy 123.831799 -242.624863) (xy 123.780504 -242.616738) (xy 123.731111 -242.60069)
			(xy 123.684837 -242.577112) (xy 123.642821 -242.546586) (xy 123.606098 -242.509863) (xy 123.575572 -242.467847)
			(xy 123.551994 -242.421573) (xy 123.535946 -242.37218) (xy 123.527821 -242.320885) (xy 123.247911 -242.320885)
			(xy 123.239786 -242.37218) (xy 123.223738 -242.421573) (xy 123.20016 -242.467847) (xy 123.169634 -242.509863)
			(xy 123.132911 -242.546586) (xy 123.090895 -242.577112) (xy 123.044621 -242.60069) (xy 122.995228 -242.616738)
			(xy 122.943933 -242.624863) (xy 122.891999 -242.624863) (xy 122.840704 -242.616738) (xy 122.791311 -242.60069)
			(xy 122.745037 -242.577112) (xy 122.703021 -242.546586) (xy 122.666298 -242.509863) (xy 122.635772 -242.467847)
			(xy 122.612194 -242.421573) (xy 122.596146 -242.37218) (xy 122.588021 -242.320885) (xy 122.308111 -242.320885)
			(xy 122.299986 -242.37218) (xy 122.283938 -242.421573) (xy 122.26036 -242.467847) (xy 122.229834 -242.509863)
			(xy 122.193111 -242.546586) (xy 122.151095 -242.577112) (xy 122.104821 -242.60069) (xy 122.055428 -242.616738)
			(xy 122.004133 -242.624863) (xy 121.952199 -242.624863) (xy 121.900904 -242.616738) (xy 121.851511 -242.60069)
			(xy 121.805237 -242.577112) (xy 121.763221 -242.546586) (xy 121.726498 -242.509863) (xy 121.695972 -242.467847)
			(xy 121.672394 -242.421573) (xy 121.656346 -242.37218) (xy 121.648221 -242.320885) (xy 118.396571 -242.320885)
			(xy 118.844314 -242.768628) (xy 118.880128 -242.73637) (xy 118.898442 -242.72041) (xy 118.938867 -242.693473)
			(xy 118.982794 -242.672733) (xy 119.02928 -242.658635) (xy 119.077328 -242.651481) (xy 119.101616 -242.651026)
			(xy 119.128913 -242.651589) (xy 119.182763 -242.66057) (xy 119.234404 -242.678285) (xy 119.282428 -242.70425)
			(xy 119.325528 -242.73776) (xy 119.34444 -242.757452) (xy 119.354273 -242.767432) (xy 119.378157 -242.782058)
			(xy 119.405113 -242.789657) (xy 119.433119 -242.789657) (xy 119.460075 -242.782058) (xy 119.483959 -242.767432)
			(xy 119.493792 -242.757452) (xy 119.512704 -242.737759) (xy 119.555801 -242.704244) (xy 119.603825 -242.678275)
			(xy 119.655466 -242.66056) (xy 119.709318 -242.651581) (xy 119.736616 -242.651026) (xy 119.762584 -242.651537)
			(xy 119.81388 -242.659663) (xy 119.863274 -242.675714) (xy 119.909548 -242.699294) (xy 119.951564 -242.729823)
			(xy 119.988288 -242.766548) (xy 120.018814 -242.808566) (xy 120.042392 -242.854841) (xy 120.05844 -242.904235)
			(xy 120.066565 -242.955532) (xy 120.066565 -243.007468) (xy 120.05844 -243.058765) (xy 120.042392 -243.108159)
			(xy 120.028739 -243.134955) (xy 121.178067 -243.134955) (xy 121.178067 -243.083021) (xy 121.186192 -243.031726)
			(xy 121.20224 -242.982333) (xy 121.225818 -242.936059) (xy 121.256344 -242.894043) (xy 121.293067 -242.85732)
			(xy 121.335083 -242.826794) (xy 121.381357 -242.803216) (xy 121.43075 -242.787168) (xy 121.482045 -242.779043)
			(xy 121.533979 -242.779043) (xy 121.585274 -242.787168) (xy 121.634667 -242.803216) (xy 121.680941 -242.826794)
			(xy 121.722957 -242.85732) (xy 121.75968 -242.894043) (xy 121.790206 -242.936059) (xy 121.813784 -242.982333)
			(xy 121.829832 -243.031726) (xy 121.837957 -243.083021) (xy 121.838466 -243.108988) (xy 121.837957 -243.134955)
			(xy 122.117867 -243.134955) (xy 122.117867 -243.083021) (xy 122.125992 -243.031726) (xy 122.14204 -242.982333)
			(xy 122.165618 -242.936059) (xy 122.196144 -242.894043) (xy 122.232867 -242.85732) (xy 122.274883 -242.826794)
			(xy 122.321157 -242.803216) (xy 122.37055 -242.787168) (xy 122.421845 -242.779043) (xy 122.473779 -242.779043)
			(xy 122.525074 -242.787168) (xy 122.574467 -242.803216) (xy 122.620741 -242.826794) (xy 122.662757 -242.85732)
			(xy 122.69948 -242.894043) (xy 122.730006 -242.936059) (xy 122.753584 -242.982333) (xy 122.769632 -243.031726)
			(xy 122.777757 -243.083021) (xy 122.778266 -243.108988) (xy 122.777757 -243.134955) (xy 123.057667 -243.134955)
			(xy 123.057667 -243.083021) (xy 123.065792 -243.031726) (xy 123.08184 -242.982333) (xy 123.105418 -242.936059)
			(xy 123.135944 -242.894043) (xy 123.172667 -242.85732) (xy 123.214683 -242.826794) (xy 123.260957 -242.803216)
			(xy 123.31035 -242.787168) (xy 123.361645 -242.779043) (xy 123.413579 -242.779043) (xy 123.464874 -242.787168)
			(xy 123.514267 -242.803216) (xy 123.560541 -242.826794) (xy 123.602557 -242.85732) (xy 123.63928 -242.894043)
			(xy 123.669806 -242.936059) (xy 123.693384 -242.982333) (xy 123.709432 -243.031726) (xy 123.717557 -243.083021)
			(xy 123.718066 -243.108988) (xy 123.717557 -243.134955) (xy 123.997467 -243.134955) (xy 123.997467 -243.083021)
			(xy 124.005592 -243.031726) (xy 124.02164 -242.982333) (xy 124.045218 -242.936059) (xy 124.075744 -242.894043)
			(xy 124.112467 -242.85732) (xy 124.154483 -242.826794) (xy 124.200757 -242.803216) (xy 124.25015 -242.787168)
			(xy 124.301445 -242.779043) (xy 124.353379 -242.779043) (xy 124.404674 -242.787168) (xy 124.454067 -242.803216)
			(xy 124.500341 -242.826794) (xy 124.542357 -242.85732) (xy 124.57908 -242.894043) (xy 124.609606 -242.936059)
			(xy 124.633184 -242.982333) (xy 124.649232 -243.031726) (xy 124.657357 -243.083021) (xy 124.657866 -243.108988)
			(xy 124.657357 -243.134955) (xy 124.937267 -243.134955) (xy 124.937267 -243.083021) (xy 124.945392 -243.031726)
			(xy 124.96144 -242.982333) (xy 124.985018 -242.936059) (xy 125.015544 -242.894043) (xy 125.052267 -242.85732)
			(xy 125.094283 -242.826794) (xy 125.140557 -242.803216) (xy 125.18995 -242.787168) (xy 125.241245 -242.779043)
			(xy 125.293179 -242.779043) (xy 125.344474 -242.787168) (xy 125.393867 -242.803216) (xy 125.440141 -242.826794)
			(xy 125.482157 -242.85732) (xy 125.51888 -242.894043) (xy 125.549406 -242.936059) (xy 125.572984 -242.982333)
			(xy 125.589032 -243.031726) (xy 125.597157 -243.083021) (xy 125.597666 -243.108988) (xy 125.597157 -243.134955)
			(xy 125.877321 -243.134955) (xy 125.877321 -243.083021) (xy 125.885446 -243.031726) (xy 125.901494 -242.982333)
			(xy 125.925072 -242.936059) (xy 125.955598 -242.894043) (xy 125.992321 -242.85732) (xy 126.034337 -242.826794)
			(xy 126.080611 -242.803216) (xy 126.130004 -242.787168) (xy 126.181299 -242.779043) (xy 126.233233 -242.779043)
			(xy 126.284528 -242.787168) (xy 126.333921 -242.803216) (xy 126.380195 -242.826794) (xy 126.422211 -242.85732)
			(xy 126.458934 -242.894043) (xy 126.48946 -242.936059) (xy 126.513038 -242.982333) (xy 126.529086 -243.031726)
			(xy 126.537211 -243.083021) (xy 126.53772 -243.108988) (xy 126.537211 -243.134955) (xy 126.816867 -243.134955)
			(xy 126.816867 -243.083021) (xy 126.824992 -243.031726) (xy 126.84104 -242.982333) (xy 126.864618 -242.936059)
			(xy 126.895144 -242.894043) (xy 126.931867 -242.85732) (xy 126.973883 -242.826794) (xy 127.020157 -242.803216)
			(xy 127.06955 -242.787168) (xy 127.120845 -242.779043) (xy 127.172779 -242.779043) (xy 127.224074 -242.787168)
			(xy 127.273467 -242.803216) (xy 127.319741 -242.826794) (xy 127.361757 -242.85732) (xy 127.39848 -242.894043)
			(xy 127.429006 -242.936059) (xy 127.452584 -242.982333) (xy 127.468632 -243.031726) (xy 127.476757 -243.083021)
			(xy 127.477266 -243.108988) (xy 127.476757 -243.134955) (xy 127.468632 -243.18625) (xy 127.452584 -243.235643)
			(xy 127.429006 -243.281917) (xy 127.39848 -243.323933) (xy 127.361757 -243.360656) (xy 127.319741 -243.391182)
			(xy 127.273467 -243.41476) (xy 127.224074 -243.430808) (xy 127.172779 -243.438933) (xy 127.120845 -243.438933)
			(xy 127.06955 -243.430808) (xy 127.020157 -243.41476) (xy 126.973883 -243.391182) (xy 126.931867 -243.360656)
			(xy 126.895144 -243.323933) (xy 126.864618 -243.281917) (xy 126.84104 -243.235643) (xy 126.824992 -243.18625)
			(xy 126.816867 -243.134955) (xy 126.537211 -243.134955) (xy 126.529086 -243.18625) (xy 126.513038 -243.235643)
			(xy 126.48946 -243.281917) (xy 126.458934 -243.323933) (xy 126.422211 -243.360656) (xy 126.380195 -243.391182)
			(xy 126.333921 -243.41476) (xy 126.284528 -243.430808) (xy 126.233233 -243.438933) (xy 126.181299 -243.438933)
			(xy 126.130004 -243.430808) (xy 126.080611 -243.41476) (xy 126.034337 -243.391182) (xy 125.992321 -243.360656)
			(xy 125.955598 -243.323933) (xy 125.925072 -243.281917) (xy 125.901494 -243.235643) (xy 125.885446 -243.18625)
			(xy 125.877321 -243.134955) (xy 125.597157 -243.134955) (xy 125.589032 -243.18625) (xy 125.572984 -243.235643)
			(xy 125.549406 -243.281917) (xy 125.51888 -243.323933) (xy 125.482157 -243.360656) (xy 125.440141 -243.391182)
			(xy 125.393867 -243.41476) (xy 125.344474 -243.430808) (xy 125.293179 -243.438933) (xy 125.241245 -243.438933)
			(xy 125.18995 -243.430808) (xy 125.140557 -243.41476) (xy 125.094283 -243.391182) (xy 125.052267 -243.360656)
			(xy 125.015544 -243.323933) (xy 124.985018 -243.281917) (xy 124.96144 -243.235643) (xy 124.945392 -243.18625)
			(xy 124.937267 -243.134955) (xy 124.657357 -243.134955) (xy 124.649232 -243.18625) (xy 124.633184 -243.235643)
			(xy 124.609606 -243.281917) (xy 124.57908 -243.323933) (xy 124.542357 -243.360656) (xy 124.500341 -243.391182)
			(xy 124.454067 -243.41476) (xy 124.404674 -243.430808) (xy 124.353379 -243.438933) (xy 124.301445 -243.438933)
			(xy 124.25015 -243.430808) (xy 124.200757 -243.41476) (xy 124.154483 -243.391182) (xy 124.112467 -243.360656)
			(xy 124.075744 -243.323933) (xy 124.045218 -243.281917) (xy 124.02164 -243.235643) (xy 124.005592 -243.18625)
			(xy 123.997467 -243.134955) (xy 123.717557 -243.134955) (xy 123.709432 -243.18625) (xy 123.693384 -243.235643)
			(xy 123.669806 -243.281917) (xy 123.63928 -243.323933) (xy 123.602557 -243.360656) (xy 123.560541 -243.391182)
			(xy 123.514267 -243.41476) (xy 123.464874 -243.430808) (xy 123.413579 -243.438933) (xy 123.361645 -243.438933)
			(xy 123.31035 -243.430808) (xy 123.260957 -243.41476) (xy 123.214683 -243.391182) (xy 123.172667 -243.360656)
			(xy 123.135944 -243.323933) (xy 123.105418 -243.281917) (xy 123.08184 -243.235643) (xy 123.065792 -243.18625)
			(xy 123.057667 -243.134955) (xy 122.777757 -243.134955) (xy 122.769632 -243.18625) (xy 122.753584 -243.235643)
			(xy 122.730006 -243.281917) (xy 122.69948 -243.323933) (xy 122.662757 -243.360656) (xy 122.620741 -243.391182)
			(xy 122.574467 -243.41476) (xy 122.525074 -243.430808) (xy 122.473779 -243.438933) (xy 122.421845 -243.438933)
			(xy 122.37055 -243.430808) (xy 122.321157 -243.41476) (xy 122.274883 -243.391182) (xy 122.232867 -243.360656)
			(xy 122.196144 -243.323933) (xy 122.165618 -243.281917) (xy 122.14204 -243.235643) (xy 122.125992 -243.18625)
			(xy 122.117867 -243.134955) (xy 121.837957 -243.134955) (xy 121.829832 -243.18625) (xy 121.813784 -243.235643)
			(xy 121.790206 -243.281917) (xy 121.75968 -243.323933) (xy 121.722957 -243.360656) (xy 121.680941 -243.391182)
			(xy 121.634667 -243.41476) (xy 121.585274 -243.430808) (xy 121.533979 -243.438933) (xy 121.482045 -243.438933)
			(xy 121.43075 -243.430808) (xy 121.381357 -243.41476) (xy 121.335083 -243.391182) (xy 121.293067 -243.360656)
			(xy 121.256344 -243.323933) (xy 121.225818 -243.281917) (xy 121.20224 -243.235643) (xy 121.186192 -243.18625)
			(xy 121.178067 -243.134955) (xy 120.028739 -243.134955) (xy 120.018814 -243.154434) (xy 119.988288 -243.196452)
			(xy 119.951564 -243.233177) (xy 119.909548 -243.263706) (xy 119.863274 -243.287286) (xy 119.81388 -243.303337)
			(xy 119.762584 -243.311463) (xy 119.736616 -243.311934) (xy 119.709504 -243.311388) (xy 119.656009 -243.302529)
			(xy 119.604681 -243.285048) (xy 119.556899 -243.259414) (xy 119.513949 -243.226317) (xy 119.476984 -243.186646)
			(xy 119.461534 -243.16436) (xy 119.455604 -243.156207) (xy 119.438871 -243.144991) (xy 119.419116 -243.141052)
			(xy 119.399361 -243.144991) (xy 119.382628 -243.156207) (xy 119.376698 -243.16436) (xy 119.369848 -243.174495)
			(xy 119.354847 -243.19382) (xy 119.346726 -243.202968) (xy 119.340555 -243.210432) (xy 119.33383 -243.228577)
			(xy 119.33431 -243.247923) (xy 119.341928 -243.265712) (xy 119.348504 -243.272818) (xy 120.370346 -244.29466)
			(xy 120.370346 -245.599204) (xy 120.645936 -245.599204) (xy 120.646357 -245.574651) (xy 120.653604 -245.526084)
			(xy 120.667952 -245.479122) (xy 120.689088 -245.434799) (xy 120.716546 -245.394088) (xy 120.732804 -245.375684)
			(xy 120.742601 -245.364191) (xy 120.755612 -245.336955) (xy 120.760079 -245.307103) (xy 120.755613 -245.277251)
			(xy 120.742604 -245.250014) (xy 120.732804 -245.238524) (xy 120.716535 -245.220128) (xy 120.689068 -245.179422)
			(xy 120.667932 -245.135096) (xy 120.653591 -245.08813) (xy 120.646364 -245.039558) (xy 120.645936 -245.015004)
			(xy 120.646357 -244.990451) (xy 120.653604 -244.941884) (xy 120.667952 -244.894922) (xy 120.689088 -244.850599)
			(xy 120.716546 -244.809888) (xy 120.732804 -244.791484) (xy 120.742601 -244.779991) (xy 120.755612 -244.752755)
			(xy 120.760079 -244.722903) (xy 120.755613 -244.693051) (xy 120.742604 -244.665814) (xy 120.732804 -244.654324)
			(xy 120.716535 -244.635928) (xy 120.689068 -244.595222) (xy 120.667932 -244.550896) (xy 120.653591 -244.50393)
			(xy 120.646364 -244.455358) (xy 120.645936 -244.430804) (xy 120.646357 -244.406251) (xy 120.653604 -244.357684)
			(xy 120.667952 -244.310722) (xy 120.689088 -244.266399) (xy 120.716546 -244.225688) (xy 120.732804 -244.207284)
			(xy 120.742601 -244.195791) (xy 120.755612 -244.168555) (xy 120.760079 -244.138703) (xy 120.755613 -244.108851)
			(xy 120.742604 -244.081614) (xy 120.732804 -244.070124) (xy 120.716535 -244.051728) (xy 120.689068 -244.011022)
			(xy 120.667932 -243.966696) (xy 120.653591 -243.91973) (xy 120.646364 -243.871158) (xy 120.645936 -243.846604)
			(xy 120.646445 -243.820637) (xy 120.65457 -243.769342) (xy 120.670618 -243.719949) (xy 120.694196 -243.673675)
			(xy 120.724722 -243.631659) (xy 120.761445 -243.594936) (xy 120.803461 -243.56441) (xy 120.849735 -243.540832)
			(xy 120.899128 -243.524784) (xy 120.950423 -243.516659) (xy 121.002357 -243.516659) (xy 121.053652 -243.524784)
			(xy 121.103045 -243.540832) (xy 121.149319 -243.56441) (xy 121.191335 -243.594936) (xy 121.228058 -243.631659)
			(xy 121.258584 -243.673675) (xy 121.282162 -243.719949) (xy 121.29821 -243.769342) (xy 121.306335 -243.820637)
			(xy 121.306844 -243.846604) (xy 121.306433 -243.871157) (xy 121.299185 -243.919725) (xy 121.290309 -243.948771)
			(xy 121.647967 -243.948771) (xy 121.647967 -243.896837) (xy 121.656092 -243.845542) (xy 121.67214 -243.796149)
			(xy 121.695718 -243.749875) (xy 121.726244 -243.707859) (xy 121.762967 -243.671136) (xy 121.804983 -243.64061)
			(xy 121.851257 -243.617032) (xy 121.90065 -243.600984) (xy 121.951945 -243.592859) (xy 122.003879 -243.592859)
			(xy 122.055174 -243.600984) (xy 122.104567 -243.617032) (xy 122.150841 -243.64061) (xy 122.192857 -243.671136)
			(xy 122.22958 -243.707859) (xy 122.260106 -243.749875) (xy 122.283684 -243.796149) (xy 122.299732 -243.845542)
			(xy 122.307857 -243.896837) (xy 122.308366 -243.922804) (xy 122.307857 -243.948771) (xy 122.587767 -243.948771)
			(xy 122.587767 -243.896837) (xy 122.595892 -243.845542) (xy 122.61194 -243.796149) (xy 122.635518 -243.749875)
			(xy 122.666044 -243.707859) (xy 122.702767 -243.671136) (xy 122.744783 -243.64061) (xy 122.791057 -243.617032)
			(xy 122.84045 -243.600984) (xy 122.891745 -243.592859) (xy 122.943679 -243.592859) (xy 122.994974 -243.600984)
			(xy 123.044367 -243.617032) (xy 123.090641 -243.64061) (xy 123.132657 -243.671136) (xy 123.16938 -243.707859)
			(xy 123.199906 -243.749875) (xy 123.223484 -243.796149) (xy 123.239532 -243.845542) (xy 123.247657 -243.896837)
			(xy 123.248166 -243.922804) (xy 123.247657 -243.948771) (xy 123.527821 -243.948771) (xy 123.527821 -243.896837)
			(xy 123.535946 -243.845542) (xy 123.551994 -243.796149) (xy 123.575572 -243.749875) (xy 123.606098 -243.707859)
			(xy 123.642821 -243.671136) (xy 123.684837 -243.64061) (xy 123.731111 -243.617032) (xy 123.780504 -243.600984)
			(xy 123.831799 -243.592859) (xy 123.883733 -243.592859) (xy 123.935028 -243.600984) (xy 123.984421 -243.617032)
			(xy 124.030695 -243.64061) (xy 124.072711 -243.671136) (xy 124.109434 -243.707859) (xy 124.13996 -243.749875)
			(xy 124.163538 -243.796149) (xy 124.179586 -243.845542) (xy 124.187711 -243.896837) (xy 124.18822 -243.922804)
			(xy 124.187711 -243.948771) (xy 124.467621 -243.948771) (xy 124.467621 -243.896837) (xy 124.475746 -243.845542)
			(xy 124.491794 -243.796149) (xy 124.515372 -243.749875) (xy 124.545898 -243.707859) (xy 124.582621 -243.671136)
			(xy 124.624637 -243.64061) (xy 124.670911 -243.617032) (xy 124.720304 -243.600984) (xy 124.771599 -243.592859)
			(xy 124.823533 -243.592859) (xy 124.874828 -243.600984) (xy 124.924221 -243.617032) (xy 124.970495 -243.64061)
			(xy 125.012511 -243.671136) (xy 125.049234 -243.707859) (xy 125.07976 -243.749875) (xy 125.103338 -243.796149)
			(xy 125.119386 -243.845542) (xy 125.127511 -243.896837) (xy 125.12802 -243.922804) (xy 125.127511 -243.948771)
			(xy 125.407421 -243.948771) (xy 125.407421 -243.896837) (xy 125.415546 -243.845542) (xy 125.431594 -243.796149)
			(xy 125.455172 -243.749875) (xy 125.485698 -243.707859) (xy 125.522421 -243.671136) (xy 125.564437 -243.64061)
			(xy 125.610711 -243.617032) (xy 125.660104 -243.600984) (xy 125.711399 -243.592859) (xy 125.763333 -243.592859)
			(xy 125.814628 -243.600984) (xy 125.864021 -243.617032) (xy 125.910295 -243.64061) (xy 125.952311 -243.671136)
			(xy 125.989034 -243.707859) (xy 126.01956 -243.749875) (xy 126.043138 -243.796149) (xy 126.059186 -243.845542)
			(xy 126.067311 -243.896837) (xy 126.06782 -243.922804) (xy 126.067311 -243.948771) (xy 126.347221 -243.948771)
			(xy 126.347221 -243.896837) (xy 126.355346 -243.845542) (xy 126.371394 -243.796149) (xy 126.394972 -243.749875)
			(xy 126.425498 -243.707859) (xy 126.462221 -243.671136) (xy 126.504237 -243.64061) (xy 126.550511 -243.617032)
			(xy 126.599904 -243.600984) (xy 126.651199 -243.592859) (xy 126.703133 -243.592859) (xy 126.754428 -243.600984)
			(xy 126.803821 -243.617032) (xy 126.850095 -243.64061) (xy 126.892111 -243.671136) (xy 126.928834 -243.707859)
			(xy 126.95936 -243.749875) (xy 126.982938 -243.796149) (xy 126.998986 -243.845542) (xy 127.007111 -243.896837)
			(xy 127.00762 -243.922804) (xy 127.007111 -243.948771) (xy 126.998986 -244.000066) (xy 126.982938 -244.049459)
			(xy 126.95936 -244.095733) (xy 126.928834 -244.137749) (xy 126.892111 -244.174472) (xy 126.850095 -244.204998)
			(xy 126.803821 -244.228576) (xy 126.754428 -244.244624) (xy 126.703133 -244.252749) (xy 126.651199 -244.252749)
			(xy 126.599904 -244.244624) (xy 126.550511 -244.228576) (xy 126.504237 -244.204998) (xy 126.462221 -244.174472)
			(xy 126.425498 -244.137749) (xy 126.394972 -244.095733) (xy 126.371394 -244.049459) (xy 126.355346 -244.000066)
			(xy 126.347221 -243.948771) (xy 126.067311 -243.948771) (xy 126.059186 -244.000066) (xy 126.043138 -244.049459)
			(xy 126.01956 -244.095733) (xy 125.989034 -244.137749) (xy 125.952311 -244.174472) (xy 125.910295 -244.204998)
			(xy 125.864021 -244.228576) (xy 125.814628 -244.244624) (xy 125.763333 -244.252749) (xy 125.711399 -244.252749)
			(xy 125.660104 -244.244624) (xy 125.610711 -244.228576) (xy 125.564437 -244.204998) (xy 125.522421 -244.174472)
			(xy 125.485698 -244.137749) (xy 125.455172 -244.095733) (xy 125.431594 -244.049459) (xy 125.415546 -244.000066)
			(xy 125.407421 -243.948771) (xy 125.127511 -243.948771) (xy 125.119386 -244.000066) (xy 125.103338 -244.049459)
			(xy 125.07976 -244.095733) (xy 125.049234 -244.137749) (xy 125.012511 -244.174472) (xy 124.970495 -244.204998)
			(xy 124.924221 -244.228576) (xy 124.874828 -244.244624) (xy 124.823533 -244.252749) (xy 124.771599 -244.252749)
			(xy 124.720304 -244.244624) (xy 124.670911 -244.228576) (xy 124.624637 -244.204998) (xy 124.582621 -244.174472)
			(xy 124.545898 -244.137749) (xy 124.515372 -244.095733) (xy 124.491794 -244.049459) (xy 124.475746 -244.000066)
			(xy 124.467621 -243.948771) (xy 124.187711 -243.948771) (xy 124.179586 -244.000066) (xy 124.163538 -244.049459)
			(xy 124.13996 -244.095733) (xy 124.109434 -244.137749) (xy 124.072711 -244.174472) (xy 124.030695 -244.204998)
			(xy 123.984421 -244.228576) (xy 123.935028 -244.244624) (xy 123.883733 -244.252749) (xy 123.831799 -244.252749)
			(xy 123.780504 -244.244624) (xy 123.731111 -244.228576) (xy 123.684837 -244.204998) (xy 123.642821 -244.174472)
			(xy 123.606098 -244.137749) (xy 123.575572 -244.095733) (xy 123.551994 -244.049459) (xy 123.535946 -244.000066)
			(xy 123.527821 -243.948771) (xy 123.247657 -243.948771) (xy 123.239532 -244.000066) (xy 123.223484 -244.049459)
			(xy 123.199906 -244.095733) (xy 123.16938 -244.137749) (xy 123.132657 -244.174472) (xy 123.090641 -244.204998)
			(xy 123.044367 -244.228576) (xy 122.994974 -244.244624) (xy 122.943679 -244.252749) (xy 122.891745 -244.252749)
			(xy 122.84045 -244.244624) (xy 122.791057 -244.228576) (xy 122.744783 -244.204998) (xy 122.702767 -244.174472)
			(xy 122.666044 -244.137749) (xy 122.635518 -244.095733) (xy 122.61194 -244.049459) (xy 122.595892 -244.000066)
			(xy 122.587767 -243.948771) (xy 122.307857 -243.948771) (xy 122.299732 -244.000066) (xy 122.283684 -244.049459)
			(xy 122.260106 -244.095733) (xy 122.22958 -244.137749) (xy 122.192857 -244.174472) (xy 122.150841 -244.204998)
			(xy 122.104567 -244.228576) (xy 122.055174 -244.244624) (xy 122.003879 -244.252749) (xy 121.951945 -244.252749)
			(xy 121.90065 -244.244624) (xy 121.851257 -244.228576) (xy 121.804983 -244.204998) (xy 121.762967 -244.174472)
			(xy 121.726244 -244.137749) (xy 121.695718 -244.095733) (xy 121.67214 -244.049459) (xy 121.656092 -244.000066)
			(xy 121.647967 -243.948771) (xy 121.290309 -243.948771) (xy 121.284834 -243.966687) (xy 121.263696 -244.011011)
			(xy 121.236235 -244.051721) (xy 121.219976 -244.070124) (xy 121.210172 -244.081612) (xy 121.197165 -244.10885)
			(xy 121.1927 -244.138703) (xy 121.197167 -244.168555) (xy 121.210176 -244.195793) (xy 121.219976 -244.207284)
			(xy 121.237573 -244.227248) (xy 121.266744 -244.271756) (xy 121.288394 -244.320369) (xy 121.295668 -244.345968)
			(xy 121.299529 -244.358806) (xy 121.312935 -244.382011) (xy 121.331911 -244.400934) (xy 121.355152 -244.414278)
			(xy 121.381062 -244.421123) (xy 121.40786 -244.421002) (xy 121.42089 -244.41785) (xy 121.442256 -244.412391)
			(xy 121.485963 -244.40653) (xy 121.508012 -244.406166) (xy 121.53398 -244.406636) (xy 121.585277 -244.414763)
			(xy 121.634671 -244.430813) (xy 121.680946 -244.454393) (xy 121.722963 -244.484921) (xy 121.759686 -244.521647)
			(xy 121.790213 -244.563664) (xy 121.813791 -244.60994) (xy 121.82984 -244.659335) (xy 121.837965 -244.710632)
			(xy 121.837965 -244.762333) (xy 122.117867 -244.762333) (xy 122.117867 -244.710399) (xy 122.125992 -244.659104)
			(xy 122.14204 -244.609711) (xy 122.165618 -244.563437) (xy 122.196144 -244.521421) (xy 122.232867 -244.484698)
			(xy 122.274883 -244.454172) (xy 122.321157 -244.430594) (xy 122.37055 -244.414546) (xy 122.421845 -244.406421)
			(xy 122.473779 -244.406421) (xy 122.525074 -244.414546) (xy 122.574467 -244.430594) (xy 122.620741 -244.454172)
			(xy 122.662757 -244.484698) (xy 122.69948 -244.521421) (xy 122.730006 -244.563437) (xy 122.753584 -244.609711)
			(xy 122.769632 -244.659104) (xy 122.777757 -244.710399) (xy 122.778266 -244.736366) (xy 122.777757 -244.762333)
			(xy 122.777717 -244.762587) (xy 123.057667 -244.762587) (xy 123.057667 -244.710653) (xy 123.065792 -244.659358)
			(xy 123.08184 -244.609965) (xy 123.105418 -244.563691) (xy 123.135944 -244.521675) (xy 123.172667 -244.484952)
			(xy 123.214683 -244.454426) (xy 123.260957 -244.430848) (xy 123.31035 -244.4148) (xy 123.361645 -244.406675)
			(xy 123.413579 -244.406675) (xy 123.464874 -244.4148) (xy 123.514267 -244.430848) (xy 123.560541 -244.454426)
			(xy 123.602557 -244.484952) (xy 123.63928 -244.521675) (xy 123.669806 -244.563691) (xy 123.693384 -244.609965)
			(xy 123.709432 -244.659358) (xy 123.717557 -244.710653) (xy 123.718066 -244.73662) (xy 123.717557 -244.762587)
			(xy 123.997467 -244.762587) (xy 123.997467 -244.710653) (xy 124.005592 -244.659358) (xy 124.02164 -244.609965)
			(xy 124.045218 -244.563691) (xy 124.075744 -244.521675) (xy 124.112467 -244.484952) (xy 124.154483 -244.454426)
			(xy 124.200757 -244.430848) (xy 124.25015 -244.4148) (xy 124.301445 -244.406675) (xy 124.353379 -244.406675)
			(xy 124.404674 -244.4148) (xy 124.454067 -244.430848) (xy 124.500341 -244.454426) (xy 124.542357 -244.484952)
			(xy 124.57908 -244.521675) (xy 124.609606 -244.563691) (xy 124.633184 -244.609965) (xy 124.649232 -244.659358)
			(xy 124.657357 -244.710653) (xy 124.657866 -244.73662) (xy 124.657357 -244.762587) (xy 124.937521 -244.762587)
			(xy 124.937521 -244.710653) (xy 124.945646 -244.659358) (xy 124.961694 -244.609965) (xy 124.985272 -244.563691)
			(xy 125.015798 -244.521675) (xy 125.052521 -244.484952) (xy 125.094537 -244.454426) (xy 125.140811 -244.430848)
			(xy 125.190204 -244.4148) (xy 125.241499 -244.406675) (xy 125.293433 -244.406675) (xy 125.344728 -244.4148)
			(xy 125.394121 -244.430848) (xy 125.440395 -244.454426) (xy 125.482411 -244.484952) (xy 125.519134 -244.521675)
			(xy 125.54966 -244.563691) (xy 125.573238 -244.609965) (xy 125.589286 -244.659358) (xy 125.597411 -244.710653)
			(xy 125.59792 -244.73662) (xy 125.597411 -244.762587) (xy 125.877067 -244.762587) (xy 125.877067 -244.710653)
			(xy 125.885192 -244.659358) (xy 125.90124 -244.609965) (xy 125.924818 -244.563691) (xy 125.955344 -244.521675)
			(xy 125.992067 -244.484952) (xy 126.034083 -244.454426) (xy 126.080357 -244.430848) (xy 126.12975 -244.4148)
			(xy 126.181045 -244.406675) (xy 126.232979 -244.406675) (xy 126.284274 -244.4148) (xy 126.333667 -244.430848)
			(xy 126.379941 -244.454426) (xy 126.421957 -244.484952) (xy 126.45868 -244.521675) (xy 126.489206 -244.563691)
			(xy 126.512784 -244.609965) (xy 126.528832 -244.659358) (xy 126.536957 -244.710653) (xy 126.537466 -244.73662)
			(xy 126.536957 -244.762587) (xy 126.817121 -244.762587) (xy 126.817121 -244.710653) (xy 126.825246 -244.659358)
			(xy 126.841294 -244.609965) (xy 126.864872 -244.563691) (xy 126.895398 -244.521675) (xy 126.932121 -244.484952)
			(xy 126.974137 -244.454426) (xy 127.020411 -244.430848) (xy 127.069804 -244.4148) (xy 127.121099 -244.406675)
			(xy 127.173033 -244.406675) (xy 127.224328 -244.4148) (xy 127.273721 -244.430848) (xy 127.319995 -244.454426)
			(xy 127.362011 -244.484952) (xy 127.398734 -244.521675) (xy 127.42926 -244.563691) (xy 127.452838 -244.609965)
			(xy 127.468886 -244.659358) (xy 127.477011 -244.710653) (xy 127.47752 -244.73662) (xy 127.477011 -244.762587)
			(xy 127.468886 -244.813882) (xy 127.452838 -244.863275) (xy 127.42926 -244.909549) (xy 127.398734 -244.951565)
			(xy 127.362011 -244.988288) (xy 127.319995 -245.018814) (xy 127.273721 -245.042392) (xy 127.224328 -245.05844)
			(xy 127.173033 -245.066565) (xy 127.121099 -245.066565) (xy 127.069804 -245.05844) (xy 127.020411 -245.042392)
			(xy 126.974137 -245.018814) (xy 126.932121 -244.988288) (xy 126.895398 -244.951565) (xy 126.864872 -244.909549)
			(xy 126.841294 -244.863275) (xy 126.825246 -244.813882) (xy 126.817121 -244.762587) (xy 126.536957 -244.762587)
			(xy 126.528832 -244.813882) (xy 126.512784 -244.863275) (xy 126.489206 -244.909549) (xy 126.45868 -244.951565)
			(xy 126.421957 -244.988288) (xy 126.379941 -245.018814) (xy 126.333667 -245.042392) (xy 126.284274 -245.05844)
			(xy 126.232979 -245.066565) (xy 126.181045 -245.066565) (xy 126.12975 -245.05844) (xy 126.080357 -245.042392)
			(xy 126.034083 -245.018814) (xy 125.992067 -244.988288) (xy 125.955344 -244.951565) (xy 125.924818 -244.909549)
			(xy 125.90124 -244.863275) (xy 125.885192 -244.813882) (xy 125.877067 -244.762587) (xy 125.597411 -244.762587)
			(xy 125.589286 -244.813882) (xy 125.573238 -244.863275) (xy 125.54966 -244.909549) (xy 125.519134 -244.951565)
			(xy 125.482411 -244.988288) (xy 125.440395 -245.018814) (xy 125.394121 -245.042392) (xy 125.344728 -245.05844)
			(xy 125.293433 -245.066565) (xy 125.241499 -245.066565) (xy 125.190204 -245.05844) (xy 125.140811 -245.042392)
			(xy 125.094537 -245.018814) (xy 125.052521 -244.988288) (xy 125.015798 -244.951565) (xy 124.985272 -244.909549)
			(xy 124.961694 -244.863275) (xy 124.945646 -244.813882) (xy 124.937521 -244.762587) (xy 124.657357 -244.762587)
			(xy 124.649232 -244.813882) (xy 124.633184 -244.863275) (xy 124.609606 -244.909549) (xy 124.57908 -244.951565)
			(xy 124.542357 -244.988288) (xy 124.500341 -245.018814) (xy 124.454067 -245.042392) (xy 124.404674 -245.05844)
			(xy 124.353379 -245.066565) (xy 124.301445 -245.066565) (xy 124.25015 -245.05844) (xy 124.200757 -245.042392)
			(xy 124.154483 -245.018814) (xy 124.112467 -244.988288) (xy 124.075744 -244.951565) (xy 124.045218 -244.909549)
			(xy 124.02164 -244.863275) (xy 124.005592 -244.813882) (xy 123.997467 -244.762587) (xy 123.717557 -244.762587)
			(xy 123.709432 -244.813882) (xy 123.693384 -244.863275) (xy 123.669806 -244.909549) (xy 123.63928 -244.951565)
			(xy 123.602557 -244.988288) (xy 123.560541 -245.018814) (xy 123.514267 -245.042392) (xy 123.464874 -245.05844)
			(xy 123.413579 -245.066565) (xy 123.361645 -245.066565) (xy 123.31035 -245.05844) (xy 123.260957 -245.042392)
			(xy 123.214683 -245.018814) (xy 123.172667 -244.988288) (xy 123.135944 -244.951565) (xy 123.105418 -244.909549)
			(xy 123.08184 -244.863275) (xy 123.065792 -244.813882) (xy 123.057667 -244.762587) (xy 122.777717 -244.762587)
			(xy 122.769632 -244.813628) (xy 122.753584 -244.863021) (xy 122.730006 -244.909295) (xy 122.69948 -244.951311)
			(xy 122.662757 -244.988034) (xy 122.620741 -245.01856) (xy 122.574467 -245.042138) (xy 122.525074 -245.058186)
			(xy 122.473779 -245.066311) (xy 122.421845 -245.066311) (xy 122.37055 -245.058186) (xy 122.321157 -245.042138)
			(xy 122.274883 -245.01856) (xy 122.232867 -244.988034) (xy 122.196144 -244.951311) (xy 122.165618 -244.909295)
			(xy 122.14204 -244.863021) (xy 122.125992 -244.813628) (xy 122.117867 -244.762333) (xy 121.837965 -244.762333)
			(xy 121.837965 -244.762568) (xy 121.82984 -244.813865) (xy 121.813791 -244.86326) (xy 121.790213 -244.909536)
			(xy 121.759686 -244.951553) (xy 121.722963 -244.988279) (xy 121.680946 -245.018807) (xy 121.634671 -245.042387)
			(xy 121.585277 -245.058437) (xy 121.53398 -245.066564) (xy 121.508012 -245.067074) (xy 121.484437 -245.066661)
			(xy 121.437773 -245.059901) (xy 121.415048 -245.053612) (xy 121.399894 -245.049703) (xy 121.368619 -245.050398)
			(xy 121.339019 -245.060523) (xy 121.31387 -245.079128) (xy 121.295529 -245.104471) (xy 121.29008 -245.119144)
			(xy 121.282396 -245.141098) (xy 121.261713 -245.182759) (xy 121.235399 -245.221113) (xy 121.219976 -245.238524)
			(xy 121.210172 -245.250012) (xy 121.197165 -245.27725) (xy 121.1927 -245.307103) (xy 121.197167 -245.336955)
			(xy 121.210176 -245.364193) (xy 121.219976 -245.375684) (xy 121.236245 -245.394079) (xy 121.263713 -245.434786)
			(xy 121.28485 -245.479111) (xy 121.29919 -245.526078) (xy 121.306417 -245.57465) (xy 121.306452 -245.576657)
			(xy 121.648221 -245.576657) (xy 121.648221 -245.524723) (xy 121.656346 -245.473428) (xy 121.672394 -245.424035)
			(xy 121.695972 -245.377761) (xy 121.726498 -245.335745) (xy 121.763221 -245.299022) (xy 121.805237 -245.268496)
			(xy 121.851511 -245.244918) (xy 121.900904 -245.22887) (xy 121.952199 -245.220745) (xy 122.004133 -245.220745)
			(xy 122.055428 -245.22887) (xy 122.104821 -245.244918) (xy 122.151095 -245.268496) (xy 122.193111 -245.299022)
			(xy 122.229834 -245.335745) (xy 122.26036 -245.377761) (xy 122.283938 -245.424035) (xy 122.299986 -245.473428)
			(xy 122.308111 -245.524723) (xy 122.30862 -245.55069) (xy 122.308111 -245.576657) (xy 122.588021 -245.576657)
			(xy 122.588021 -245.524723) (xy 122.596146 -245.473428) (xy 122.612194 -245.424035) (xy 122.635772 -245.377761)
			(xy 122.666298 -245.335745) (xy 122.703021 -245.299022) (xy 122.745037 -245.268496) (xy 122.791311 -245.244918)
			(xy 122.840704 -245.22887) (xy 122.891999 -245.220745) (xy 122.943933 -245.220745) (xy 122.995228 -245.22887)
			(xy 123.044621 -245.244918) (xy 123.090895 -245.268496) (xy 123.132911 -245.299022) (xy 123.169634 -245.335745)
			(xy 123.20016 -245.377761) (xy 123.223738 -245.424035) (xy 123.239786 -245.473428) (xy 123.247911 -245.524723)
			(xy 123.24842 -245.55069) (xy 123.247911 -245.576657) (xy 123.527821 -245.576657) (xy 123.527821 -245.524723)
			(xy 123.535946 -245.473428) (xy 123.551994 -245.424035) (xy 123.575572 -245.377761) (xy 123.606098 -245.335745)
			(xy 123.642821 -245.299022) (xy 123.684837 -245.268496) (xy 123.731111 -245.244918) (xy 123.780504 -245.22887)
			(xy 123.831799 -245.220745) (xy 123.883733 -245.220745) (xy 123.935028 -245.22887) (xy 123.984421 -245.244918)
			(xy 124.030695 -245.268496) (xy 124.072711 -245.299022) (xy 124.109434 -245.335745) (xy 124.13996 -245.377761)
			(xy 124.163538 -245.424035) (xy 124.179586 -245.473428) (xy 124.187711 -245.524723) (xy 124.18822 -245.55069)
			(xy 124.187711 -245.576657) (xy 124.467621 -245.576657) (xy 124.467621 -245.524723) (xy 124.475746 -245.473428)
			(xy 124.491794 -245.424035) (xy 124.515372 -245.377761) (xy 124.545898 -245.335745) (xy 124.582621 -245.299022)
			(xy 124.624637 -245.268496) (xy 124.670911 -245.244918) (xy 124.720304 -245.22887) (xy 124.771599 -245.220745)
			(xy 124.823533 -245.220745) (xy 124.874828 -245.22887) (xy 124.924221 -245.244918) (xy 124.970495 -245.268496)
			(xy 125.012511 -245.299022) (xy 125.049234 -245.335745) (xy 125.07976 -245.377761) (xy 125.103338 -245.424035)
			(xy 125.119386 -245.473428) (xy 125.127511 -245.524723) (xy 125.12802 -245.55069) (xy 125.127511 -245.576657)
			(xy 125.407167 -245.576657) (xy 125.407167 -245.524723) (xy 125.415292 -245.473428) (xy 125.43134 -245.424035)
			(xy 125.454918 -245.377761) (xy 125.485444 -245.335745) (xy 125.522167 -245.299022) (xy 125.564183 -245.268496)
			(xy 125.610457 -245.244918) (xy 125.65985 -245.22887) (xy 125.711145 -245.220745) (xy 125.763079 -245.220745)
			(xy 125.814374 -245.22887) (xy 125.863767 -245.244918) (xy 125.910041 -245.268496) (xy 125.952057 -245.299022)
			(xy 125.98878 -245.335745) (xy 126.019306 -245.377761) (xy 126.042884 -245.424035) (xy 126.058932 -245.473428)
			(xy 126.067057 -245.524723) (xy 126.067566 -245.55069) (xy 126.067057 -245.576657) (xy 126.347221 -245.576657)
			(xy 126.347221 -245.524723) (xy 126.355346 -245.473428) (xy 126.371394 -245.424035) (xy 126.394972 -245.377761)
			(xy 126.425498 -245.335745) (xy 126.462221 -245.299022) (xy 126.504237 -245.268496) (xy 126.550511 -245.244918)
			(xy 126.599904 -245.22887) (xy 126.651199 -245.220745) (xy 126.703133 -245.220745) (xy 126.754428 -245.22887)
			(xy 126.803821 -245.244918) (xy 126.850095 -245.268496) (xy 126.892111 -245.299022) (xy 126.928834 -245.335745)
			(xy 126.95936 -245.377761) (xy 126.982938 -245.424035) (xy 126.998986 -245.473428) (xy 127.007111 -245.524723)
			(xy 127.00762 -245.55069) (xy 127.007111 -245.576657) (xy 126.998986 -245.627952) (xy 126.982938 -245.677345)
			(xy 126.95936 -245.723619) (xy 126.928834 -245.765635) (xy 126.892111 -245.802358) (xy 126.850095 -245.832884)
			(xy 126.803821 -245.856462) (xy 126.754428 -245.87251) (xy 126.703133 -245.880635) (xy 126.651199 -245.880635)
			(xy 126.599904 -245.87251) (xy 126.550511 -245.856462) (xy 126.504237 -245.832884) (xy 126.462221 -245.802358)
			(xy 126.425498 -245.765635) (xy 126.394972 -245.723619) (xy 126.371394 -245.677345) (xy 126.355346 -245.627952)
			(xy 126.347221 -245.576657) (xy 126.067057 -245.576657) (xy 126.058932 -245.627952) (xy 126.042884 -245.677345)
			(xy 126.019306 -245.723619) (xy 125.98878 -245.765635) (xy 125.952057 -245.802358) (xy 125.910041 -245.832884)
			(xy 125.863767 -245.856462) (xy 125.814374 -245.87251) (xy 125.763079 -245.880635) (xy 125.711145 -245.880635)
			(xy 125.65985 -245.87251) (xy 125.610457 -245.856462) (xy 125.564183 -245.832884) (xy 125.522167 -245.802358)
			(xy 125.485444 -245.765635) (xy 125.454918 -245.723619) (xy 125.43134 -245.677345) (xy 125.415292 -245.627952)
			(xy 125.407167 -245.576657) (xy 125.127511 -245.576657) (xy 125.119386 -245.627952) (xy 125.103338 -245.677345)
			(xy 125.07976 -245.723619) (xy 125.049234 -245.765635) (xy 125.012511 -245.802358) (xy 124.970495 -245.832884)
			(xy 124.924221 -245.856462) (xy 124.874828 -245.87251) (xy 124.823533 -245.880635) (xy 124.771599 -245.880635)
			(xy 124.720304 -245.87251) (xy 124.670911 -245.856462) (xy 124.624637 -245.832884) (xy 124.582621 -245.802358)
			(xy 124.545898 -245.765635) (xy 124.515372 -245.723619) (xy 124.491794 -245.677345) (xy 124.475746 -245.627952)
			(xy 124.467621 -245.576657) (xy 124.187711 -245.576657) (xy 124.179586 -245.627952) (xy 124.163538 -245.677345)
			(xy 124.13996 -245.723619) (xy 124.109434 -245.765635) (xy 124.072711 -245.802358) (xy 124.030695 -245.832884)
			(xy 123.984421 -245.856462) (xy 123.935028 -245.87251) (xy 123.883733 -245.880635) (xy 123.831799 -245.880635)
			(xy 123.780504 -245.87251) (xy 123.731111 -245.856462) (xy 123.684837 -245.832884) (xy 123.642821 -245.802358)
			(xy 123.606098 -245.765635) (xy 123.575572 -245.723619) (xy 123.551994 -245.677345) (xy 123.535946 -245.627952)
			(xy 123.527821 -245.576657) (xy 123.247911 -245.576657) (xy 123.239786 -245.627952) (xy 123.223738 -245.677345)
			(xy 123.20016 -245.723619) (xy 123.169634 -245.765635) (xy 123.132911 -245.802358) (xy 123.090895 -245.832884)
			(xy 123.044621 -245.856462) (xy 122.995228 -245.87251) (xy 122.943933 -245.880635) (xy 122.891999 -245.880635)
			(xy 122.840704 -245.87251) (xy 122.791311 -245.856462) (xy 122.745037 -245.832884) (xy 122.703021 -245.802358)
			(xy 122.666298 -245.765635) (xy 122.635772 -245.723619) (xy 122.612194 -245.677345) (xy 122.596146 -245.627952)
			(xy 122.588021 -245.576657) (xy 122.308111 -245.576657) (xy 122.299986 -245.627952) (xy 122.283938 -245.677345)
			(xy 122.26036 -245.723619) (xy 122.229834 -245.765635) (xy 122.193111 -245.802358) (xy 122.151095 -245.832884)
			(xy 122.104821 -245.856462) (xy 122.055428 -245.87251) (xy 122.004133 -245.880635) (xy 121.952199 -245.880635)
			(xy 121.900904 -245.87251) (xy 121.851511 -245.856462) (xy 121.805237 -245.832884) (xy 121.763221 -245.802358)
			(xy 121.726498 -245.765635) (xy 121.695972 -245.723619) (xy 121.672394 -245.677345) (xy 121.656346 -245.627952)
			(xy 121.648221 -245.576657) (xy 121.306452 -245.576657) (xy 121.306844 -245.599204) (xy 121.306335 -245.625171)
			(xy 121.29821 -245.676466) (xy 121.282162 -245.725859) (xy 121.258584 -245.772133) (xy 121.228058 -245.814149)
			(xy 121.191335 -245.850872) (xy 121.149319 -245.881398) (xy 121.103045 -245.904976) (xy 121.053652 -245.921024)
			(xy 121.002357 -245.929149) (xy 120.950423 -245.929149) (xy 120.899128 -245.921024) (xy 120.849735 -245.904976)
			(xy 120.803461 -245.881398) (xy 120.761445 -245.850872) (xy 120.724722 -245.814149) (xy 120.694196 -245.772133)
			(xy 120.670618 -245.725859) (xy 120.65457 -245.676466) (xy 120.646445 -245.625171) (xy 120.645936 -245.599204)
			(xy 120.370346 -245.599204) (xy 120.370346 -246.325898) (xy 120.414542 -246.33174) (xy 120.441943 -246.335871)
			(xy 120.494928 -246.352086) (xy 120.544462 -246.37692) (xy 120.589155 -246.409675) (xy 120.627751 -246.449433)
			(xy 120.643904 -246.471948) (xy 120.651827 -246.482798) (xy 120.672253 -246.500235) (xy 120.696522 -246.511737)
			(xy 120.722952 -246.516508) (xy 120.74971 -246.514216) (xy 120.774944 -246.50502) (xy 120.786144 -246.497602)
			(xy 120.807134 -246.483359) (xy 120.852563 -246.460792) (xy 120.900906 -246.44543) (xy 120.951028 -246.437634)
			(xy 120.97639 -246.43715) (xy 120.995745 -246.437399) (xy 121.034198 -246.44186) (xy 121.053098 -246.44604)
			(xy 121.067781 -246.449023) (xy 121.097677 -246.447262) (xy 121.12577 -246.436888) (xy 121.149636 -246.418797)
			(xy 121.167213 -246.39455) (xy 121.176985 -246.366242) (xy 121.178066 -246.351298) (xy 121.17956 -246.326033)
			(xy 121.18927 -246.276363) (xy 121.206442 -246.228756) (xy 121.230674 -246.184324) (xy 121.261398 -246.144107)
			(xy 121.297896 -246.109047) (xy 121.339314 -246.079962) (xy 121.384683 -246.057535) (xy 121.432942 -246.042288)
			(xy 121.482961 -246.03458) (xy 121.508266 -246.034052) (xy 121.534237 -246.034532) (xy 121.585539 -246.042653)
			(xy 121.634939 -246.058699) (xy 121.681221 -246.082277) (xy 121.723244 -246.112804) (xy 121.759973 -246.14953)
			(xy 121.790505 -246.19155) (xy 121.814087 -246.237829) (xy 121.830139 -246.287228) (xy 121.838265 -246.338529)
			(xy 121.838265 -246.390471) (xy 121.838265 -246.390473) (xy 122.118121 -246.390473) (xy 122.118121 -246.338539)
			(xy 122.126246 -246.287244) (xy 122.142294 -246.237851) (xy 122.165872 -246.191577) (xy 122.196398 -246.149561)
			(xy 122.233121 -246.112838) (xy 122.275137 -246.082312) (xy 122.321411 -246.058734) (xy 122.370804 -246.042686)
			(xy 122.422099 -246.034561) (xy 122.474033 -246.034561) (xy 122.525328 -246.042686) (xy 122.574721 -246.058734)
			(xy 122.620995 -246.082312) (xy 122.663011 -246.112838) (xy 122.699734 -246.149561) (xy 122.73026 -246.191577)
			(xy 122.753838 -246.237851) (xy 122.769886 -246.287244) (xy 122.778011 -246.338539) (xy 122.77852 -246.364506)
			(xy 122.778011 -246.390473) (xy 123.057667 -246.390473) (xy 123.057667 -246.338539) (xy 123.065792 -246.287244)
			(xy 123.08184 -246.237851) (xy 123.105418 -246.191577) (xy 123.135944 -246.149561) (xy 123.172667 -246.112838)
			(xy 123.214683 -246.082312) (xy 123.260957 -246.058734) (xy 123.31035 -246.042686) (xy 123.361645 -246.034561)
			(xy 123.413579 -246.034561) (xy 123.464874 -246.042686) (xy 123.514267 -246.058734) (xy 123.560541 -246.082312)
			(xy 123.602557 -246.112838) (xy 123.63928 -246.149561) (xy 123.669806 -246.191577) (xy 123.693384 -246.237851)
			(xy 123.709432 -246.287244) (xy 123.717557 -246.338539) (xy 123.718066 -246.364506) (xy 123.717557 -246.390473)
			(xy 123.997467 -246.390473) (xy 123.997467 -246.338539) (xy 124.005592 -246.287244) (xy 124.02164 -246.237851)
			(xy 124.045218 -246.191577) (xy 124.075744 -246.149561) (xy 124.112467 -246.112838) (xy 124.154483 -246.082312)
			(xy 124.200757 -246.058734) (xy 124.25015 -246.042686) (xy 124.301445 -246.034561) (xy 124.353379 -246.034561)
			(xy 124.404674 -246.042686) (xy 124.454067 -246.058734) (xy 124.500341 -246.082312) (xy 124.542357 -246.112838)
			(xy 124.57908 -246.149561) (xy 124.609606 -246.191577) (xy 124.633184 -246.237851) (xy 124.649232 -246.287244)
			(xy 124.657357 -246.338539) (xy 124.657866 -246.364506) (xy 124.657357 -246.390473) (xy 124.937267 -246.390473)
			(xy 124.937267 -246.338539) (xy 124.945392 -246.287244) (xy 124.96144 -246.237851) (xy 124.985018 -246.191577)
			(xy 125.015544 -246.149561) (xy 125.052267 -246.112838) (xy 125.094283 -246.082312) (xy 125.140557 -246.058734)
			(xy 125.18995 -246.042686) (xy 125.241245 -246.034561) (xy 125.293179 -246.034561) (xy 125.344474 -246.042686)
			(xy 125.393867 -246.058734) (xy 125.440141 -246.082312) (xy 125.482157 -246.112838) (xy 125.51888 -246.149561)
			(xy 125.549406 -246.191577) (xy 125.572984 -246.237851) (xy 125.589032 -246.287244) (xy 125.597157 -246.338539)
			(xy 125.597666 -246.364506) (xy 125.597157 -246.390473) (xy 125.589032 -246.441768) (xy 125.572984 -246.491161)
			(xy 125.549406 -246.537435) (xy 125.51888 -246.579451) (xy 125.482157 -246.616174) (xy 125.440141 -246.6467)
			(xy 125.393867 -246.670278) (xy 125.344474 -246.686326) (xy 125.293179 -246.694451) (xy 125.241245 -246.694451)
			(xy 125.18995 -246.686326) (xy 125.140557 -246.670278) (xy 125.094283 -246.6467) (xy 125.052267 -246.616174)
			(xy 125.015544 -246.579451) (xy 124.985018 -246.537435) (xy 124.96144 -246.491161) (xy 124.945392 -246.441768)
			(xy 124.937267 -246.390473) (xy 124.657357 -246.390473) (xy 124.649232 -246.441768) (xy 124.633184 -246.491161)
			(xy 124.609606 -246.537435) (xy 124.57908 -246.579451) (xy 124.542357 -246.616174) (xy 124.500341 -246.6467)
			(xy 124.454067 -246.670278) (xy 124.404674 -246.686326) (xy 124.353379 -246.694451) (xy 124.301445 -246.694451)
			(xy 124.25015 -246.686326) (xy 124.200757 -246.670278) (xy 124.154483 -246.6467) (xy 124.112467 -246.616174)
			(xy 124.075744 -246.579451) (xy 124.045218 -246.537435) (xy 124.02164 -246.491161) (xy 124.005592 -246.441768)
			(xy 123.997467 -246.390473) (xy 123.717557 -246.390473) (xy 123.709432 -246.441768) (xy 123.693384 -246.491161)
			(xy 123.669806 -246.537435) (xy 123.63928 -246.579451) (xy 123.602557 -246.616174) (xy 123.560541 -246.6467)
			(xy 123.514267 -246.670278) (xy 123.464874 -246.686326) (xy 123.413579 -246.694451) (xy 123.361645 -246.694451)
			(xy 123.31035 -246.686326) (xy 123.260957 -246.670278) (xy 123.214683 -246.6467) (xy 123.172667 -246.616174)
			(xy 123.135944 -246.579451) (xy 123.105418 -246.537435) (xy 123.08184 -246.491161) (xy 123.065792 -246.441768)
			(xy 123.057667 -246.390473) (xy 122.778011 -246.390473) (xy 122.769886 -246.441768) (xy 122.753838 -246.491161)
			(xy 122.73026 -246.537435) (xy 122.699734 -246.579451) (xy 122.663011 -246.616174) (xy 122.620995 -246.6467)
			(xy 122.574721 -246.670278) (xy 122.525328 -246.686326) (xy 122.474033 -246.694451) (xy 122.422099 -246.694451)
			(xy 122.370804 -246.686326) (xy 122.321411 -246.670278) (xy 122.275137 -246.6467) (xy 122.233121 -246.616174)
			(xy 122.196398 -246.579451) (xy 122.165872 -246.537435) (xy 122.142294 -246.491161) (xy 122.126246 -246.441768)
			(xy 122.118121 -246.390473) (xy 121.838265 -246.390473) (xy 121.830139 -246.441772) (xy 121.814087 -246.491171)
			(xy 121.790505 -246.53745) (xy 121.759973 -246.57947) (xy 121.723244 -246.616196) (xy 121.681221 -246.646723)
			(xy 121.634939 -246.670301) (xy 121.585539 -246.686347) (xy 121.534237 -246.694468) (xy 121.508266 -246.69496)
			(xy 121.48891 -246.694714) (xy 121.450456 -246.69026) (xy 121.431558 -246.68607) (xy 121.416879 -246.683093)
			(xy 121.386994 -246.684865) (xy 121.358914 -246.695243) (xy 121.335062 -246.713334) (xy 121.317496 -246.737576)
			(xy 121.307732 -246.765876) (xy 121.30659 -246.780812) (xy 121.305287 -246.80401) (xy 121.296981 -246.849723)
			(xy 121.28235 -246.89382) (xy 121.261683 -246.935432) (xy 121.235387 -246.973736) (xy 121.219976 -246.991124)
			(xy 121.210177 -247.002615) (xy 121.197171 -247.029852) (xy 121.192705 -247.059703) (xy 121.197172 -247.089554)
			(xy 121.21018 -247.11679) (xy 121.219976 -247.128284) (xy 121.236235 -247.146688) (xy 121.263694 -247.187398)
			(xy 121.271749 -247.204289) (xy 121.648221 -247.204289) (xy 121.648221 -247.152355) (xy 121.656346 -247.10106)
			(xy 121.672394 -247.051667) (xy 121.695972 -247.005393) (xy 121.726498 -246.963377) (xy 121.763221 -246.926654)
			(xy 121.805237 -246.896128) (xy 121.851511 -246.87255) (xy 121.900904 -246.856502) (xy 121.952199 -246.848377)
			(xy 122.004133 -246.848377) (xy 122.055428 -246.856502) (xy 122.104821 -246.87255) (xy 122.151095 -246.896128)
			(xy 122.193111 -246.926654) (xy 122.229834 -246.963377) (xy 122.26036 -247.005393) (xy 122.283938 -247.051667)
			(xy 122.299986 -247.10106) (xy 122.308111 -247.152355) (xy 122.30862 -247.178322) (xy 122.308111 -247.204289)
			(xy 122.588021 -247.204289) (xy 122.588021 -247.152355) (xy 122.596146 -247.10106) (xy 122.612194 -247.051667)
			(xy 122.635772 -247.005393) (xy 122.666298 -246.963377) (xy 122.703021 -246.926654) (xy 122.745037 -246.896128)
			(xy 122.791311 -246.87255) (xy 122.840704 -246.856502) (xy 122.891999 -246.848377) (xy 122.943933 -246.848377)
			(xy 122.995228 -246.856502) (xy 123.044621 -246.87255) (xy 123.090895 -246.896128) (xy 123.132911 -246.926654)
			(xy 123.169634 -246.963377) (xy 123.20016 -247.005393) (xy 123.223738 -247.051667) (xy 123.239786 -247.10106)
			(xy 123.247911 -247.152355) (xy 123.24842 -247.178322) (xy 123.247911 -247.204289) (xy 123.527821 -247.204289)
			(xy 123.527821 -247.152355) (xy 123.535946 -247.10106) (xy 123.551994 -247.051667) (xy 123.575572 -247.005393)
			(xy 123.606098 -246.963377) (xy 123.642821 -246.926654) (xy 123.684837 -246.896128) (xy 123.731111 -246.87255)
			(xy 123.780504 -246.856502) (xy 123.831799 -246.848377) (xy 123.883733 -246.848377) (xy 123.935028 -246.856502)
			(xy 123.984421 -246.87255) (xy 124.030695 -246.896128) (xy 124.072711 -246.926654) (xy 124.109434 -246.963377)
			(xy 124.13996 -247.005393) (xy 124.163538 -247.051667) (xy 124.179586 -247.10106) (xy 124.187711 -247.152355)
			(xy 124.18822 -247.178322) (xy 124.187711 -247.204289) (xy 124.467621 -247.204289) (xy 124.467621 -247.152355)
			(xy 124.475746 -247.10106) (xy 124.491794 -247.051667) (xy 124.515372 -247.005393) (xy 124.545898 -246.963377)
			(xy 124.582621 -246.926654) (xy 124.624637 -246.896128) (xy 124.670911 -246.87255) (xy 124.720304 -246.856502)
			(xy 124.771599 -246.848377) (xy 124.823533 -246.848377) (xy 124.874828 -246.856502) (xy 124.924221 -246.87255)
			(xy 124.970495 -246.896128) (xy 125.012511 -246.926654) (xy 125.049234 -246.963377) (xy 125.07976 -247.005393)
			(xy 125.103338 -247.051667) (xy 125.119386 -247.10106) (xy 125.127511 -247.152355) (xy 125.12802 -247.178322)
			(xy 125.127511 -247.204289) (xy 125.119386 -247.255584) (xy 125.103338 -247.304977) (xy 125.07976 -247.351251)
			(xy 125.049234 -247.393267) (xy 125.012511 -247.42999) (xy 124.970495 -247.460516) (xy 124.924221 -247.484094)
			(xy 124.874828 -247.500142) (xy 124.823533 -247.508267) (xy 124.771599 -247.508267) (xy 124.720304 -247.500142)
			(xy 124.670911 -247.484094) (xy 124.624637 -247.460516) (xy 124.582621 -247.42999) (xy 124.545898 -247.393267)
			(xy 124.515372 -247.351251) (xy 124.491794 -247.304977) (xy 124.475746 -247.255584) (xy 124.467621 -247.204289)
			(xy 124.187711 -247.204289) (xy 124.179586 -247.255584) (xy 124.163538 -247.304977) (xy 124.13996 -247.351251)
			(xy 124.109434 -247.393267) (xy 124.072711 -247.42999) (xy 124.030695 -247.460516) (xy 123.984421 -247.484094)
			(xy 123.935028 -247.500142) (xy 123.883733 -247.508267) (xy 123.831799 -247.508267) (xy 123.780504 -247.500142)
			(xy 123.731111 -247.484094) (xy 123.684837 -247.460516) (xy 123.642821 -247.42999) (xy 123.606098 -247.393267)
			(xy 123.575572 -247.351251) (xy 123.551994 -247.304977) (xy 123.535946 -247.255584) (xy 123.527821 -247.204289)
			(xy 123.247911 -247.204289) (xy 123.239786 -247.255584) (xy 123.223738 -247.304977) (xy 123.20016 -247.351251)
			(xy 123.169634 -247.393267) (xy 123.132911 -247.42999) (xy 123.090895 -247.460516) (xy 123.044621 -247.484094)
			(xy 122.995228 -247.500142) (xy 122.943933 -247.508267) (xy 122.891999 -247.508267) (xy 122.840704 -247.500142)
			(xy 122.791311 -247.484094) (xy 122.745037 -247.460516) (xy 122.703021 -247.42999) (xy 122.666298 -247.393267)
			(xy 122.635772 -247.351251) (xy 122.612194 -247.304977) (xy 122.596146 -247.255584) (xy 122.588021 -247.204289)
			(xy 122.308111 -247.204289) (xy 122.299986 -247.255584) (xy 122.283938 -247.304977) (xy 122.26036 -247.351251)
			(xy 122.229834 -247.393267) (xy 122.193111 -247.42999) (xy 122.151095 -247.460516) (xy 122.104821 -247.484094)
			(xy 122.055428 -247.500142) (xy 122.004133 -247.508267) (xy 121.952199 -247.508267) (xy 121.900904 -247.500142)
			(xy 121.851511 -247.484094) (xy 121.805237 -247.460516) (xy 121.763221 -247.42999) (xy 121.726498 -247.393267)
			(xy 121.695972 -247.351251) (xy 121.672394 -247.304977) (xy 121.656346 -247.255584) (xy 121.648221 -247.204289)
			(xy 121.271749 -247.204289) (xy 121.284831 -247.231721) (xy 121.299181 -247.278683) (xy 121.306428 -247.327251)
			(xy 121.306844 -247.351804) (xy 121.306335 -247.377771) (xy 121.29821 -247.429066) (xy 121.282162 -247.478459)
			(xy 121.258584 -247.524733) (xy 121.228058 -247.566749) (xy 121.191335 -247.603472) (xy 121.149319 -247.633998)
			(xy 121.103045 -247.657576) (xy 121.053652 -247.673624) (xy 121.002357 -247.681749) (xy 120.950423 -247.681749)
			(xy 120.899128 -247.673624) (xy 120.849735 -247.657576) (xy 120.803461 -247.633998) (xy 120.761445 -247.603472)
			(xy 120.724722 -247.566749) (xy 120.694196 -247.524733) (xy 120.670618 -247.478459) (xy 120.65457 -247.429066)
			(xy 120.646445 -247.377771) (xy 120.645936 -247.351804) (xy 120.646363 -247.32725) (xy 120.65359 -247.278677)
			(xy 120.667929 -247.23171) (xy 120.689065 -247.187384) (xy 120.716532 -247.146676) (xy 120.732804 -247.128284)
			(xy 120.742606 -247.116794) (xy 120.755617 -247.089556) (xy 120.760085 -247.059703) (xy 120.755618 -247.02985)
			(xy 120.742609 -247.002611) (xy 120.732804 -246.991124) (xy 120.725084 -246.982554) (xy 120.710718 -246.964505)
			(xy 120.704102 -246.955056) (xy 120.69618 -246.944205) (xy 120.675753 -246.926766) (xy 120.651484 -246.915261)
			(xy 120.625053 -246.91049) (xy 120.598293 -246.912781) (xy 120.573057 -246.921976) (xy 120.561862 -246.929402)
			(xy 120.539785 -246.944319) (xy 120.491892 -246.967661) (xy 120.440881 -246.983039) (xy 120.414542 -246.98706)
			(xy 120.370346 -246.992902) (xy 120.370346 -248.354167) (xy 120.622835 -248.354167) (xy 120.622835 -248.302233)
			(xy 120.630959 -248.250938) (xy 120.647007 -248.201545) (xy 120.670583 -248.15527) (xy 120.701108 -248.113253)
			(xy 120.737829 -248.076528) (xy 120.779843 -248.046) (xy 120.826115 -248.022419) (xy 120.875507 -248.006367)
			(xy 120.926801 -247.998238) (xy 120.952768 -247.997726) (xy 120.978001 -247.998156) (xy 121.027881 -248.005812)
			(xy 121.052082 -248.012966) (xy 121.06597 -248.016894) (xy 121.094811 -248.017583) (xy 121.12269 -248.010161)
			(xy 121.147371 -247.995222) (xy 121.166876 -247.973964) (xy 121.17964 -247.948091) (xy 121.182638 -247.933972)
			(xy 121.187658 -247.90886) (xy 121.204355 -247.860452) (xy 121.228316 -247.815196) (xy 121.258967 -247.774176)
			(xy 121.295577 -247.738372) (xy 121.33727 -247.708642) (xy 121.383047 -247.685694) (xy 121.431816 -247.67008)
			(xy 121.482409 -247.662171) (xy 121.508012 -247.661684) (xy 121.533982 -247.662118) (xy 121.585281 -247.670245)
			(xy 121.634678 -247.686297) (xy 121.680955 -247.709878) (xy 121.722974 -247.740408) (xy 121.7597 -247.777135)
			(xy 121.790229 -247.819155) (xy 121.813808 -247.865433) (xy 121.829858 -247.914831) (xy 121.837983 -247.96613)
			(xy 121.837983 -248.01807) (xy 121.837977 -248.018105) (xy 122.117867 -248.018105) (xy 122.117867 -247.966171)
			(xy 122.125992 -247.914876) (xy 122.14204 -247.865483) (xy 122.165618 -247.819209) (xy 122.196144 -247.777193)
			(xy 122.232867 -247.74047) (xy 122.274883 -247.709944) (xy 122.321157 -247.686366) (xy 122.37055 -247.670318)
			(xy 122.421845 -247.662193) (xy 122.473779 -247.662193) (xy 122.525074 -247.670318) (xy 122.574467 -247.686366)
			(xy 122.620741 -247.709944) (xy 122.662757 -247.74047) (xy 122.69948 -247.777193) (xy 122.730006 -247.819209)
			(xy 122.753584 -247.865483) (xy 122.769632 -247.914876) (xy 122.777757 -247.966171) (xy 122.778266 -247.992138)
			(xy 122.777757 -248.018105) (xy 123.057667 -248.018105) (xy 123.057667 -247.966171) (xy 123.065792 -247.914876)
			(xy 123.08184 -247.865483) (xy 123.105418 -247.819209) (xy 123.135944 -247.777193) (xy 123.172667 -247.74047)
			(xy 123.214683 -247.709944) (xy 123.260957 -247.686366) (xy 123.31035 -247.670318) (xy 123.361645 -247.662193)
			(xy 123.413579 -247.662193) (xy 123.464874 -247.670318) (xy 123.514267 -247.686366) (xy 123.560541 -247.709944)
			(xy 123.602557 -247.74047) (xy 123.63928 -247.777193) (xy 123.669806 -247.819209) (xy 123.693384 -247.865483)
			(xy 123.709432 -247.914876) (xy 123.717557 -247.966171) (xy 123.718066 -247.992138) (xy 123.717557 -248.018105)
			(xy 123.997467 -248.018105) (xy 123.997467 -247.966171) (xy 124.005592 -247.914876) (xy 124.02164 -247.865483)
			(xy 124.045218 -247.819209) (xy 124.075744 -247.777193) (xy 124.112467 -247.74047) (xy 124.154483 -247.709944)
			(xy 124.200757 -247.686366) (xy 124.25015 -247.670318) (xy 124.301445 -247.662193) (xy 124.353379 -247.662193)
			(xy 124.404674 -247.670318) (xy 124.454067 -247.686366) (xy 124.500341 -247.709944) (xy 124.542357 -247.74047)
			(xy 124.57908 -247.777193) (xy 124.609606 -247.819209) (xy 124.633184 -247.865483) (xy 124.649232 -247.914876)
			(xy 124.657357 -247.966171) (xy 124.657866 -247.992138) (xy 124.657357 -248.018105) (xy 124.649232 -248.0694)
			(xy 124.633184 -248.118793) (xy 124.609606 -248.165067) (xy 124.57908 -248.207083) (xy 124.542357 -248.243806)
			(xy 124.500341 -248.274332) (xy 124.454067 -248.29791) (xy 124.404674 -248.313958) (xy 124.353379 -248.322083)
			(xy 124.301445 -248.322083) (xy 124.25015 -248.313958) (xy 124.200757 -248.29791) (xy 124.154483 -248.274332)
			(xy 124.112467 -248.243806) (xy 124.075744 -248.207083) (xy 124.045218 -248.165067) (xy 124.02164 -248.118793)
			(xy 124.005592 -248.0694) (xy 123.997467 -248.018105) (xy 123.717557 -248.018105) (xy 123.709432 -248.0694)
			(xy 123.693384 -248.118793) (xy 123.669806 -248.165067) (xy 123.63928 -248.207083) (xy 123.602557 -248.243806)
			(xy 123.560541 -248.274332) (xy 123.514267 -248.29791) (xy 123.464874 -248.313958) (xy 123.413579 -248.322083)
			(xy 123.361645 -248.322083) (xy 123.31035 -248.313958) (xy 123.260957 -248.29791) (xy 123.214683 -248.274332)
			(xy 123.172667 -248.243806) (xy 123.135944 -248.207083) (xy 123.105418 -248.165067) (xy 123.08184 -248.118793)
			(xy 123.065792 -248.0694) (xy 123.057667 -248.018105) (xy 122.777757 -248.018105) (xy 122.769632 -248.0694)
			(xy 122.753584 -248.118793) (xy 122.730006 -248.165067) (xy 122.69948 -248.207083) (xy 122.662757 -248.243806)
			(xy 122.620741 -248.274332) (xy 122.574467 -248.29791) (xy 122.525074 -248.313958) (xy 122.473779 -248.322083)
			(xy 122.421845 -248.322083) (xy 122.37055 -248.313958) (xy 122.321157 -248.29791) (xy 122.274883 -248.274332)
			(xy 122.232867 -248.243806) (xy 122.196144 -248.207083) (xy 122.165618 -248.165067) (xy 122.14204 -248.118793)
			(xy 122.125992 -248.0694) (xy 122.117867 -248.018105) (xy 121.837977 -248.018105) (xy 121.829858 -248.069369)
			(xy 121.813808 -248.118767) (xy 121.790229 -248.165045) (xy 121.7597 -248.207065) (xy 121.722974 -248.243792)
			(xy 121.680955 -248.274322) (xy 121.634678 -248.297903) (xy 121.585281 -248.313955) (xy 121.533982 -248.322082)
			(xy 121.508012 -248.322592) (xy 121.482779 -248.322166) (xy 121.432899 -248.314507) (xy 121.408698 -248.307352)
			(xy 121.394802 -248.303466) (xy 121.365971 -248.302784) (xy 121.338102 -248.310205) (xy 121.313428 -248.325135)
			(xy 121.293923 -248.346378) (xy 121.281148 -248.372234) (xy 121.278142 -248.386346) (xy 121.273154 -248.411465)
			(xy 121.256453 -248.459875) (xy 121.232488 -248.505131) (xy 121.201832 -248.546151) (xy 121.165218 -248.581955)
			(xy 121.123522 -248.611684) (xy 121.077741 -248.63463) (xy 121.028969 -248.650242) (xy 120.978373 -248.658148)
			(xy 120.952768 -248.658634) (xy 120.926801 -248.658162) (xy 120.875507 -248.650033) (xy 120.826115 -248.633981)
			(xy 120.779843 -248.6104) (xy 120.737829 -248.579872) (xy 120.701108 -248.543147) (xy 120.670583 -248.50113)
			(xy 120.647007 -248.454855) (xy 120.630959 -248.405462) (xy 120.622835 -248.354167) (xy 120.370346 -248.354167)
			(xy 120.370346 -249.13316) (xy 120.659165 -249.13316) (xy 120.659166 -249.081228) (xy 120.667291 -249.029935)
			(xy 120.683339 -248.980544) (xy 120.706917 -248.934273) (xy 120.737443 -248.892259) (xy 120.774165 -248.855537)
			(xy 120.816179 -248.825013) (xy 120.862452 -248.801436) (xy 120.911843 -248.785389) (xy 120.963136 -248.777265)
			(xy 121.015068 -248.777265) (xy 121.066361 -248.78539) (xy 121.115752 -248.801438) (xy 121.162024 -248.825015)
			(xy 121.171879 -248.832175) (xy 121.648221 -248.832175) (xy 121.648221 -248.780241) (xy 121.656346 -248.728946)
			(xy 121.672394 -248.679553) (xy 121.695972 -248.633279) (xy 121.726498 -248.591263) (xy 121.763221 -248.55454)
			(xy 121.805237 -248.524014) (xy 121.851511 -248.500436) (xy 121.900904 -248.484388) (xy 121.952199 -248.476263)
			(xy 122.004133 -248.476263) (xy 122.055428 -248.484388) (xy 122.104821 -248.500436) (xy 122.151095 -248.524014)
			(xy 122.193111 -248.55454) (xy 122.229834 -248.591263) (xy 122.26036 -248.633279) (xy 122.283938 -248.679553)
			(xy 122.299986 -248.728946) (xy 122.308111 -248.780241) (xy 122.30862 -248.806208) (xy 122.308111 -248.832175)
			(xy 122.587767 -248.832175) (xy 122.587767 -248.780241) (xy 122.595892 -248.728946) (xy 122.61194 -248.679553)
			(xy 122.635518 -248.633279) (xy 122.666044 -248.591263) (xy 122.702767 -248.55454) (xy 122.744783 -248.524014)
			(xy 122.791057 -248.500436) (xy 122.84045 -248.484388) (xy 122.891745 -248.476263) (xy 122.943679 -248.476263)
			(xy 122.994974 -248.484388) (xy 123.044367 -248.500436) (xy 123.090641 -248.524014) (xy 123.132657 -248.55454)
			(xy 123.16938 -248.591263) (xy 123.199906 -248.633279) (xy 123.223484 -248.679553) (xy 123.239532 -248.728946)
			(xy 123.247657 -248.780241) (xy 123.248166 -248.806208) (xy 123.247657 -248.832175) (xy 123.239532 -248.88347)
			(xy 123.223484 -248.932863) (xy 123.199906 -248.979137) (xy 123.16938 -249.021153) (xy 123.132657 -249.057876)
			(xy 123.090641 -249.088402) (xy 123.044367 -249.11198) (xy 122.994974 -249.128028) (xy 122.943679 -249.136153)
			(xy 122.891745 -249.136153) (xy 122.84045 -249.128028) (xy 122.791057 -249.11198) (xy 122.744783 -249.088402)
			(xy 122.702767 -249.057876) (xy 122.666044 -249.021153) (xy 122.635518 -248.979137) (xy 122.61194 -248.932863)
			(xy 122.595892 -248.88347) (xy 122.587767 -248.832175) (xy 122.308111 -248.832175) (xy 122.299986 -248.88347)
			(xy 122.283938 -248.932863) (xy 122.26036 -248.979137) (xy 122.229834 -249.021153) (xy 122.193111 -249.057876)
			(xy 122.151095 -249.088402) (xy 122.104821 -249.11198) (xy 122.055428 -249.128028) (xy 122.004133 -249.136153)
			(xy 121.952199 -249.136153) (xy 121.900904 -249.128028) (xy 121.851511 -249.11198) (xy 121.805237 -249.088402)
			(xy 121.763221 -249.057876) (xy 121.726498 -249.021153) (xy 121.695972 -248.979137) (xy 121.672394 -248.932863)
			(xy 121.656346 -248.88347) (xy 121.648221 -248.832175) (xy 121.171879 -248.832175) (xy 121.204038 -248.85554)
			(xy 121.24076 -248.892262) (xy 121.271285 -248.934276) (xy 121.294862 -248.980548) (xy 121.31091 -249.029939)
			(xy 121.319035 -249.081232) (xy 121.319544 -249.107198) (xy 121.319287 -249.124865) (xy 121.315473 -249.159993)
			(xy 121.311924 -249.177302) (xy 121.309216 -249.191699) (xy 121.311359 -249.220909) (xy 121.321695 -249.248312)
			(xy 121.339377 -249.27166) (xy 121.362952 -249.289038) (xy 121.390487 -249.299018) (xy 121.419722 -249.300782)
			(xy 121.434098 -249.297952) (xy 121.452325 -249.294031) (xy 121.48937 -249.289827) (xy 121.508012 -249.28957)
			(xy 121.533978 -249.290068) (xy 121.585269 -249.298194) (xy 121.634659 -249.314243) (xy 121.680929 -249.33782)
			(xy 121.722942 -249.368346) (xy 121.759662 -249.405067) (xy 121.790186 -249.447081) (xy 121.813762 -249.493353)
			(xy 121.829809 -249.542742) (xy 121.837933 -249.594034) (xy 121.837933 -249.645966) (xy 121.837929 -249.645991)
			(xy 122.117867 -249.645991) (xy 122.117867 -249.594057) (xy 122.125992 -249.542762) (xy 122.14204 -249.493369)
			(xy 122.165618 -249.447095) (xy 122.196144 -249.405079) (xy 122.232867 -249.368356) (xy 122.274883 -249.33783)
			(xy 122.321157 -249.314252) (xy 122.37055 -249.298204) (xy 122.421845 -249.290079) (xy 122.473779 -249.290079)
			(xy 122.525074 -249.298204) (xy 122.574467 -249.314252) (xy 122.620741 -249.33783) (xy 122.662757 -249.368356)
			(xy 122.69948 -249.405079) (xy 122.730006 -249.447095) (xy 122.753584 -249.493369) (xy 122.769632 -249.542762)
			(xy 122.777757 -249.594057) (xy 122.778266 -249.620024) (xy 122.777757 -249.645991) (xy 123.057667 -249.645991)
			(xy 123.057667 -249.594057) (xy 123.065792 -249.542762) (xy 123.08184 -249.493369) (xy 123.105418 -249.447095)
			(xy 123.135944 -249.405079) (xy 123.172667 -249.368356) (xy 123.214683 -249.33783) (xy 123.260957 -249.314252)
			(xy 123.31035 -249.298204) (xy 123.361645 -249.290079) (xy 123.413579 -249.290079) (xy 123.464874 -249.298204)
			(xy 123.514267 -249.314252) (xy 123.560541 -249.33783) (xy 123.602557 -249.368356) (xy 123.63928 -249.405079)
			(xy 123.669806 -249.447095) (xy 123.693384 -249.493369) (xy 123.709432 -249.542762) (xy 123.717557 -249.594057)
			(xy 123.718066 -249.620024) (xy 123.717557 -249.645991) (xy 123.709432 -249.697286) (xy 123.693384 -249.746679)
			(xy 123.669806 -249.792953) (xy 123.63928 -249.834969) (xy 123.602557 -249.871692) (xy 123.560541 -249.902218)
			(xy 123.514267 -249.925796) (xy 123.464874 -249.941844) (xy 123.413579 -249.949969) (xy 123.361645 -249.949969)
			(xy 123.31035 -249.941844) (xy 123.260957 -249.925796) (xy 123.214683 -249.902218) (xy 123.172667 -249.871692)
			(xy 123.135944 -249.834969) (xy 123.105418 -249.792953) (xy 123.08184 -249.746679) (xy 123.065792 -249.697286)
			(xy 123.057667 -249.645991) (xy 122.777757 -249.645991) (xy 122.769632 -249.697286) (xy 122.753584 -249.746679)
			(xy 122.730006 -249.792953) (xy 122.69948 -249.834969) (xy 122.662757 -249.871692) (xy 122.620741 -249.902218)
			(xy 122.574467 -249.925796) (xy 122.525074 -249.941844) (xy 122.473779 -249.949969) (xy 122.421845 -249.949969)
			(xy 122.37055 -249.941844) (xy 122.321157 -249.925796) (xy 122.274883 -249.902218) (xy 122.232867 -249.871692)
			(xy 122.196144 -249.834969) (xy 122.165618 -249.792953) (xy 122.14204 -249.746679) (xy 122.125992 -249.697286)
			(xy 122.117867 -249.645991) (xy 121.837929 -249.645991) (xy 121.829809 -249.697258) (xy 121.813762 -249.746647)
			(xy 121.790186 -249.792919) (xy 121.759662 -249.834933) (xy 121.722942 -249.871654) (xy 121.680929 -249.90218)
			(xy 121.634659 -249.925757) (xy 121.585269 -249.941806) (xy 121.533978 -249.949932) (xy 121.482046 -249.949934)
			(xy 121.430754 -249.941812) (xy 121.381364 -249.925766) (xy 121.335091 -249.902192) (xy 121.293076 -249.87167)
			(xy 121.256353 -249.834951) (xy 121.225827 -249.792939) (xy 121.202247 -249.74667) (xy 121.186196 -249.697281)
			(xy 121.178069 -249.64599) (xy 121.177558 -249.620024) (xy 121.177803 -249.602357) (xy 121.181625 -249.567228)
			(xy 121.185178 -249.54992) (xy 121.187861 -249.535519) (xy 121.185723 -249.506312) (xy 121.175392 -249.47891)
			(xy 121.157714 -249.455562) (xy 121.134142 -249.438184) (xy 121.10661 -249.428204) (xy 121.077378 -249.426439)
			(xy 121.063004 -249.42927) (xy 121.044777 -249.433191) (xy 121.007732 -249.437395) (xy 120.98909 -249.437652)
			(xy 120.963124 -249.437134) (xy 120.911831 -249.429008) (xy 120.862441 -249.412959) (xy 120.816169 -249.389381)
			(xy 120.774156 -249.358855) (xy 120.737435 -249.322132) (xy 120.706911 -249.280117) (xy 120.683335 -249.233845)
			(xy 120.667288 -249.184453) (xy 120.659165 -249.13316) (xy 120.370346 -249.13316) (xy 120.370346 -251.441204)
			(xy 120.645936 -251.441204) (xy 120.646357 -251.416651) (xy 120.653604 -251.368084) (xy 120.667952 -251.321122)
			(xy 120.689088 -251.276799) (xy 120.716546 -251.236088) (xy 120.732804 -251.217684) (xy 120.742601 -251.206191)
			(xy 120.755612 -251.178955) (xy 120.760079 -251.149103) (xy 120.755613 -251.119251) (xy 120.742604 -251.092014)
			(xy 120.732804 -251.080524) (xy 120.716535 -251.062128) (xy 120.689068 -251.021422) (xy 120.667932 -250.977096)
			(xy 120.653591 -250.93013) (xy 120.646364 -250.881558) (xy 120.645936 -250.857004) (xy 120.646445 -250.831037)
			(xy 120.65457 -250.779742) (xy 120.670618 -250.730349) (xy 120.694196 -250.684075) (xy 120.724722 -250.642059)
			(xy 120.761445 -250.605336) (xy 120.803461 -250.57481) (xy 120.849735 -250.551232) (xy 120.899128 -250.535184)
			(xy 120.950423 -250.527059) (xy 121.002357 -250.527059) (xy 121.053652 -250.535184) (xy 121.103045 -250.551232)
			(xy 121.149319 -250.57481) (xy 121.191335 -250.605336) (xy 121.228058 -250.642059) (xy 121.258584 -250.684075)
			(xy 121.282162 -250.730349) (xy 121.29821 -250.779742) (xy 121.306335 -250.831037) (xy 121.306844 -250.857004)
			(xy 121.306433 -250.881557) (xy 121.299185 -250.930125) (xy 121.284834 -250.977087) (xy 121.263696 -251.021411)
			(xy 121.236235 -251.062121) (xy 121.219976 -251.080524) (xy 121.210172 -251.092012) (xy 121.197165 -251.11925)
			(xy 121.1927 -251.149103) (xy 121.197167 -251.178955) (xy 121.210176 -251.206193) (xy 121.219976 -251.217684)
			(xy 121.236245 -251.236079) (xy 121.263713 -251.276786) (xy 121.28485 -251.321111) (xy 121.29919 -251.368078)
			(xy 121.306417 -251.41665) (xy 121.306844 -251.441204) (xy 121.306335 -251.467171) (xy 121.29821 -251.518466)
			(xy 121.282162 -251.567859) (xy 121.258584 -251.614133) (xy 121.228058 -251.656149) (xy 121.191335 -251.692872)
			(xy 121.149319 -251.723398) (xy 121.103045 -251.746976) (xy 121.053652 -251.763024) (xy 121.002357 -251.771149)
			(xy 120.950423 -251.771149) (xy 120.899128 -251.763024) (xy 120.849735 -251.746976) (xy 120.803461 -251.723398)
			(xy 120.761445 -251.692872) (xy 120.724722 -251.656149) (xy 120.694196 -251.614133) (xy 120.670618 -251.567859)
			(xy 120.65457 -251.518466) (xy 120.646445 -251.467171) (xy 120.645936 -251.441204) (xy 120.370346 -251.441204)
			(xy 120.370346 -253.193804) (xy 120.645936 -253.193804) (xy 120.646357 -253.169251) (xy 120.653604 -253.120684)
			(xy 120.667952 -253.073722) (xy 120.689088 -253.029399) (xy 120.716546 -252.988688) (xy 120.732804 -252.970284)
			(xy 120.742601 -252.958791) (xy 120.755612 -252.931555) (xy 120.760079 -252.901703) (xy 120.755613 -252.871851)
			(xy 120.742604 -252.844614) (xy 120.732804 -252.833124) (xy 120.716535 -252.814728) (xy 120.689068 -252.774022)
			(xy 120.667932 -252.729696) (xy 120.653591 -252.68273) (xy 120.646364 -252.634158) (xy 120.645936 -252.609604)
			(xy 120.646445 -252.583637) (xy 120.65457 -252.532342) (xy 120.670618 -252.482949) (xy 120.694196 -252.436675)
			(xy 120.724722 -252.394659) (xy 120.761445 -252.357936) (xy 120.803461 -252.32741) (xy 120.849735 -252.303832)
			(xy 120.899128 -252.287784) (xy 120.950423 -252.279659) (xy 121.002357 -252.279659) (xy 121.053652 -252.287784)
			(xy 121.103045 -252.303832) (xy 121.149319 -252.32741) (xy 121.191335 -252.357936) (xy 121.228058 -252.394659)
			(xy 121.258584 -252.436675) (xy 121.282162 -252.482949) (xy 121.29821 -252.532342) (xy 121.306335 -252.583637)
			(xy 121.306844 -252.609604) (xy 121.306433 -252.634157) (xy 121.299185 -252.682725) (xy 121.284834 -252.729687)
			(xy 121.263696 -252.774011) (xy 121.236235 -252.814721) (xy 121.219976 -252.833124) (xy 121.210172 -252.844612)
			(xy 121.197165 -252.87185) (xy 121.1927 -252.901703) (xy 121.197167 -252.931555) (xy 121.210176 -252.958793)
			(xy 121.219976 -252.970284) (xy 121.236245 -252.988679) (xy 121.263713 -253.029386) (xy 121.28485 -253.073711)
			(xy 121.29919 -253.120678) (xy 121.306417 -253.16925) (xy 121.306844 -253.193804) (xy 121.306335 -253.219771)
			(xy 121.29821 -253.271066) (xy 121.282162 -253.320459) (xy 121.258584 -253.366733) (xy 121.228058 -253.408749)
			(xy 121.191335 -253.445472) (xy 121.149319 -253.475998) (xy 121.103045 -253.499576) (xy 121.053652 -253.515624)
			(xy 121.002357 -253.523749) (xy 120.950423 -253.523749) (xy 120.899128 -253.515624) (xy 120.849735 -253.499576)
			(xy 120.803461 -253.475998) (xy 120.761445 -253.445472) (xy 120.724722 -253.408749) (xy 120.694196 -253.366733)
			(xy 120.670618 -253.320459) (xy 120.65457 -253.271066) (xy 120.646445 -253.219771) (xy 120.645936 -253.193804)
			(xy 120.370346 -253.193804) (xy 120.370346 -253.945703) (xy 121.758203 -253.945703) (xy 121.758203 -253.893769)
			(xy 121.766328 -253.842474) (xy 121.782376 -253.793081) (xy 121.805954 -253.746807) (xy 121.83648 -253.704791)
			(xy 121.873203 -253.668068) (xy 121.915219 -253.637542) (xy 121.961493 -253.613964) (xy 122.010886 -253.597916)
			(xy 122.062181 -253.589791) (xy 122.114115 -253.589791) (xy 122.16541 -253.597916) (xy 122.214803 -253.613964)
			(xy 122.261077 -253.637542) (xy 122.303093 -253.668068) (xy 122.339816 -253.704791) (xy 122.370342 -253.746807)
			(xy 122.39392 -253.793081) (xy 122.409968 -253.842474) (xy 122.418093 -253.893769) (xy 122.418602 -253.919736)
			(xy 122.418093 -253.945703) (xy 122.697749 -253.945703) (xy 122.697749 -253.893769) (xy 122.705874 -253.842474)
			(xy 122.721922 -253.793081) (xy 122.7455 -253.746807) (xy 122.776026 -253.704791) (xy 122.812749 -253.668068)
			(xy 122.854765 -253.637542) (xy 122.901039 -253.613964) (xy 122.950432 -253.597916) (xy 123.001727 -253.589791)
			(xy 123.053661 -253.589791) (xy 123.104956 -253.597916) (xy 123.154349 -253.613964) (xy 123.200623 -253.637542)
			(xy 123.242639 -253.668068) (xy 123.279362 -253.704791) (xy 123.309888 -253.746807) (xy 123.333466 -253.793081)
			(xy 123.349514 -253.842474) (xy 123.357639 -253.893769) (xy 123.358148 -253.919736) (xy 123.357639 -253.945703)
			(xy 123.637803 -253.945703) (xy 123.637803 -253.893769) (xy 123.645928 -253.842474) (xy 123.661976 -253.793081)
			(xy 123.685554 -253.746807) (xy 123.71608 -253.704791) (xy 123.752803 -253.668068) (xy 123.794819 -253.637542)
			(xy 123.841093 -253.613964) (xy 123.890486 -253.597916) (xy 123.941781 -253.589791) (xy 123.993715 -253.589791)
			(xy 124.04501 -253.597916) (xy 124.094403 -253.613964) (xy 124.140677 -253.637542) (xy 124.182693 -253.668068)
			(xy 124.219416 -253.704791) (xy 124.249942 -253.746807) (xy 124.27352 -253.793081) (xy 124.289568 -253.842474)
			(xy 124.297693 -253.893769) (xy 124.298202 -253.919736) (xy 124.297693 -253.945703) (xy 124.577603 -253.945703)
			(xy 124.577603 -253.893769) (xy 124.585728 -253.842474) (xy 124.601776 -253.793081) (xy 124.625354 -253.746807)
			(xy 124.65588 -253.704791) (xy 124.692603 -253.668068) (xy 124.734619 -253.637542) (xy 124.780893 -253.613964)
			(xy 124.830286 -253.597916) (xy 124.881581 -253.589791) (xy 124.933515 -253.589791) (xy 124.98481 -253.597916)
			(xy 125.034203 -253.613964) (xy 125.080477 -253.637542) (xy 125.122493 -253.668068) (xy 125.159216 -253.704791)
			(xy 125.189742 -253.746807) (xy 125.21332 -253.793081) (xy 125.229368 -253.842474) (xy 125.237493 -253.893769)
			(xy 125.238002 -253.919736) (xy 125.237493 -253.945703) (xy 125.229368 -253.996998) (xy 125.21332 -254.046391)
			(xy 125.189742 -254.092665) (xy 125.159216 -254.134681) (xy 125.122493 -254.171404) (xy 125.080477 -254.20193)
			(xy 125.034203 -254.225508) (xy 124.98481 -254.241556) (xy 124.933515 -254.249681) (xy 124.881581 -254.249681)
			(xy 124.830286 -254.241556) (xy 124.780893 -254.225508) (xy 124.734619 -254.20193) (xy 124.692603 -254.171404)
			(xy 124.65588 -254.134681) (xy 124.625354 -254.092665) (xy 124.601776 -254.046391) (xy 124.585728 -253.996998)
			(xy 124.577603 -253.945703) (xy 124.297693 -253.945703) (xy 124.289568 -253.996998) (xy 124.27352 -254.046391)
			(xy 124.249942 -254.092665) (xy 124.219416 -254.134681) (xy 124.182693 -254.171404) (xy 124.140677 -254.20193)
			(xy 124.094403 -254.225508) (xy 124.04501 -254.241556) (xy 123.993715 -254.249681) (xy 123.941781 -254.249681)
			(xy 123.890486 -254.241556) (xy 123.841093 -254.225508) (xy 123.794819 -254.20193) (xy 123.752803 -254.171404)
			(xy 123.71608 -254.134681) (xy 123.685554 -254.092665) (xy 123.661976 -254.046391) (xy 123.645928 -253.996998)
			(xy 123.637803 -253.945703) (xy 123.357639 -253.945703) (xy 123.349514 -253.996998) (xy 123.333466 -254.046391)
			(xy 123.309888 -254.092665) (xy 123.279362 -254.134681) (xy 123.242639 -254.171404) (xy 123.200623 -254.20193)
			(xy 123.154349 -254.225508) (xy 123.104956 -254.241556) (xy 123.053661 -254.249681) (xy 123.001727 -254.249681)
			(xy 122.950432 -254.241556) (xy 122.901039 -254.225508) (xy 122.854765 -254.20193) (xy 122.812749 -254.171404)
			(xy 122.776026 -254.134681) (xy 122.7455 -254.092665) (xy 122.721922 -254.046391) (xy 122.705874 -253.996998)
			(xy 122.697749 -253.945703) (xy 122.418093 -253.945703) (xy 122.409968 -253.996998) (xy 122.39392 -254.046391)
			(xy 122.370342 -254.092665) (xy 122.339816 -254.134681) (xy 122.303093 -254.171404) (xy 122.261077 -254.20193)
			(xy 122.214803 -254.225508) (xy 122.16541 -254.241556) (xy 122.114115 -254.249681) (xy 122.062181 -254.249681)
			(xy 122.010886 -254.241556) (xy 121.961493 -254.225508) (xy 121.915219 -254.20193) (xy 121.873203 -254.171404)
			(xy 121.83648 -254.134681) (xy 121.805954 -254.092665) (xy 121.782376 -254.046391) (xy 121.766328 -253.996998)
			(xy 121.758203 -253.945703) (xy 120.370346 -253.945703) (xy 120.370346 -255.530604) (xy 120.645936 -255.530604)
			(xy 120.646357 -255.506051) (xy 120.653604 -255.457484) (xy 120.667952 -255.410522) (xy 120.689088 -255.366199)
			(xy 120.716546 -255.325488) (xy 120.732804 -255.307084) (xy 120.742601 -255.295591) (xy 120.755612 -255.268355)
			(xy 120.760079 -255.238503) (xy 120.755613 -255.208651) (xy 120.742604 -255.181414) (xy 120.732804 -255.169924)
			(xy 120.716535 -255.151528) (xy 120.689068 -255.110822) (xy 120.667932 -255.066496) (xy 120.653591 -255.01953)
			(xy 120.646364 -254.970958) (xy 120.645936 -254.946404) (xy 120.646459 -254.920437) (xy 120.654582 -254.869143)
			(xy 120.67063 -254.819752) (xy 120.694206 -254.773479) (xy 120.724731 -254.731463) (xy 120.761452 -254.69474)
			(xy 120.803467 -254.664213) (xy 120.849739 -254.640635) (xy 120.89913 -254.624586) (xy 120.950423 -254.61646)
			(xy 120.97639 -254.61595) (xy 121.00028 -254.616339) (xy 121.047563 -254.62321) (xy 121.093366 -254.636811)
			(xy 121.136737 -254.656858) (xy 121.156984 -254.669544) (xy 121.17003 -254.677435) (xy 121.199343 -254.685783)
			(xy 121.229814 -254.685127) (xy 121.25874 -254.675525) (xy 121.283554 -254.657828) (xy 121.302055 -254.633608)
			(xy 121.30786 -254.619506) (xy 121.317012 -254.596047) (xy 121.341353 -254.55197) (xy 121.372099 -254.512096)
			(xy 121.40854 -254.477349) (xy 121.449831 -254.448533) (xy 121.495017 -254.426316) (xy 121.54305 -254.411212)
			(xy 121.592818 -254.403572) (xy 121.617994 -254.403098) (xy 121.64396 -254.403676) (xy 121.695252 -254.411799)
			(xy 121.744642 -254.427846) (xy 121.790914 -254.451422) (xy 121.832928 -254.481946) (xy 121.86965 -254.518667)
			(xy 121.900175 -254.560681) (xy 121.923751 -254.606952) (xy 121.939799 -254.656342) (xy 121.947923 -254.707634)
			(xy 121.947923 -254.759519) (xy 122.227849 -254.759519) (xy 122.227849 -254.707585) (xy 122.235974 -254.65629)
			(xy 122.252022 -254.606897) (xy 122.2756 -254.560623) (xy 122.306126 -254.518607) (xy 122.342849 -254.481884)
			(xy 122.384865 -254.451358) (xy 122.431139 -254.42778) (xy 122.480532 -254.411732) (xy 122.531827 -254.403607)
			(xy 122.583761 -254.403607) (xy 122.635056 -254.411732) (xy 122.684449 -254.42778) (xy 122.730723 -254.451358)
			(xy 122.772739 -254.481884) (xy 122.809462 -254.518607) (xy 122.839988 -254.560623) (xy 122.863566 -254.606897)
			(xy 122.879614 -254.65629) (xy 122.887739 -254.707585) (xy 122.888248 -254.733552) (xy 122.887739 -254.759519)
			(xy 123.167649 -254.759519) (xy 123.167649 -254.707585) (xy 123.175774 -254.65629) (xy 123.191822 -254.606897)
			(xy 123.2154 -254.560623) (xy 123.245926 -254.518607) (xy 123.282649 -254.481884) (xy 123.324665 -254.451358)
			(xy 123.370939 -254.42778) (xy 123.420332 -254.411732) (xy 123.471627 -254.403607) (xy 123.523561 -254.403607)
			(xy 123.574856 -254.411732) (xy 123.624249 -254.42778) (xy 123.670523 -254.451358) (xy 123.712539 -254.481884)
			(xy 123.749262 -254.518607) (xy 123.779788 -254.560623) (xy 123.803366 -254.606897) (xy 123.819414 -254.65629)
			(xy 123.827539 -254.707585) (xy 123.828048 -254.733552) (xy 123.827539 -254.759519) (xy 124.107703 -254.759519)
			(xy 124.107703 -254.707585) (xy 124.115828 -254.65629) (xy 124.131876 -254.606897) (xy 124.155454 -254.560623)
			(xy 124.18598 -254.518607) (xy 124.222703 -254.481884) (xy 124.264719 -254.451358) (xy 124.310993 -254.42778)
			(xy 124.360386 -254.411732) (xy 124.411681 -254.403607) (xy 124.463615 -254.403607) (xy 124.51491 -254.411732)
			(xy 124.564303 -254.42778) (xy 124.610577 -254.451358) (xy 124.652593 -254.481884) (xy 124.689316 -254.518607)
			(xy 124.719842 -254.560623) (xy 124.74342 -254.606897) (xy 124.759468 -254.65629) (xy 124.767593 -254.707585)
			(xy 124.768102 -254.733552) (xy 124.767593 -254.759519) (xy 124.759468 -254.810814) (xy 124.74342 -254.860207)
			(xy 124.719842 -254.906481) (xy 124.689316 -254.948497) (xy 124.652593 -254.98522) (xy 124.610577 -255.015746)
			(xy 124.564303 -255.039324) (xy 124.51491 -255.055372) (xy 124.463615 -255.063497) (xy 124.411681 -255.063497)
			(xy 124.360386 -255.055372) (xy 124.310993 -255.039324) (xy 124.264719 -255.015746) (xy 124.222703 -254.98522)
			(xy 124.18598 -254.948497) (xy 124.155454 -254.906481) (xy 124.131876 -254.860207) (xy 124.115828 -254.810814)
			(xy 124.107703 -254.759519) (xy 123.827539 -254.759519) (xy 123.819414 -254.810814) (xy 123.803366 -254.860207)
			(xy 123.779788 -254.906481) (xy 123.749262 -254.948497) (xy 123.712539 -254.98522) (xy 123.670523 -255.015746)
			(xy 123.624249 -255.039324) (xy 123.574856 -255.055372) (xy 123.523561 -255.063497) (xy 123.471627 -255.063497)
			(xy 123.420332 -255.055372) (xy 123.370939 -255.039324) (xy 123.324665 -255.015746) (xy 123.282649 -254.98522)
			(xy 123.245926 -254.948497) (xy 123.2154 -254.906481) (xy 123.191822 -254.860207) (xy 123.175774 -254.810814)
			(xy 123.167649 -254.759519) (xy 122.887739 -254.759519) (xy 122.879614 -254.810814) (xy 122.863566 -254.860207)
			(xy 122.839988 -254.906481) (xy 122.809462 -254.948497) (xy 122.772739 -254.98522) (xy 122.730723 -255.015746)
			(xy 122.684449 -255.039324) (xy 122.635056 -255.055372) (xy 122.583761 -255.063497) (xy 122.531827 -255.063497)
			(xy 122.480532 -255.055372) (xy 122.431139 -255.039324) (xy 122.384865 -255.015746) (xy 122.342849 -254.98522)
			(xy 122.306126 -254.948497) (xy 122.2756 -254.906481) (xy 122.252022 -254.860207) (xy 122.235974 -254.810814)
			(xy 122.227849 -254.759519) (xy 121.947923 -254.759519) (xy 121.947923 -254.759566) (xy 121.939799 -254.810858)
			(xy 121.923751 -254.860248) (xy 121.900175 -254.906519) (xy 121.86965 -254.948533) (xy 121.832928 -254.985254)
			(xy 121.790914 -255.015778) (xy 121.744642 -255.039354) (xy 121.695252 -255.055401) (xy 121.64396 -255.063524)
			(xy 121.617994 -255.064006) (xy 121.594106 -255.063568) (xy 121.546825 -255.05671) (xy 121.501022 -255.043124)
			(xy 121.457649 -255.023091) (xy 121.4374 -255.010412) (xy 121.424288 -255.002643) (xy 121.395001 -254.994287)
			(xy 121.364553 -254.994926) (xy 121.335643 -255.004505) (xy 121.310836 -255.022173) (xy 121.292334 -255.046363)
			(xy 121.286524 -255.06045) (xy 121.278805 -255.080516) (xy 121.258914 -255.118631) (xy 121.23424 -255.153838)
			(xy 121.219976 -255.169924) (xy 121.210172 -255.181412) (xy 121.197165 -255.20865) (xy 121.1927 -255.238503)
			(xy 121.197167 -255.268355) (xy 121.210176 -255.295593) (xy 121.219976 -255.307084) (xy 121.236245 -255.325479)
			(xy 121.263713 -255.366186) (xy 121.28485 -255.410511) (xy 121.29919 -255.457478) (xy 121.306417 -255.50605)
			(xy 121.306844 -255.530604) (xy 121.306335 -255.556571) (xy 121.303639 -255.573589) (xy 122.698003 -255.573589)
			(xy 122.698003 -255.521655) (xy 122.706128 -255.47036) (xy 122.722176 -255.420967) (xy 122.745754 -255.374693)
			(xy 122.77628 -255.332677) (xy 122.813003 -255.295954) (xy 122.855019 -255.265428) (xy 122.901293 -255.24185)
			(xy 122.950686 -255.225802) (xy 123.001981 -255.217677) (xy 123.053915 -255.217677) (xy 123.10521 -255.225802)
			(xy 123.154603 -255.24185) (xy 123.200877 -255.265428) (xy 123.242893 -255.295954) (xy 123.279616 -255.332677)
			(xy 123.310142 -255.374693) (xy 123.33372 -255.420967) (xy 123.349768 -255.47036) (xy 123.357893 -255.521655)
			(xy 123.358402 -255.547622) (xy 123.357893 -255.573589) (xy 123.637803 -255.573589) (xy 123.637803 -255.521655)
			(xy 123.645928 -255.47036) (xy 123.661976 -255.420967) (xy 123.685554 -255.374693) (xy 123.71608 -255.332677)
			(xy 123.752803 -255.295954) (xy 123.794819 -255.265428) (xy 123.841093 -255.24185) (xy 123.890486 -255.225802)
			(xy 123.941781 -255.217677) (xy 123.993715 -255.217677) (xy 124.04501 -255.225802) (xy 124.094403 -255.24185)
			(xy 124.140677 -255.265428) (xy 124.182693 -255.295954) (xy 124.219416 -255.332677) (xy 124.249942 -255.374693)
			(xy 124.27352 -255.420967) (xy 124.289568 -255.47036) (xy 124.297693 -255.521655) (xy 124.298202 -255.547622)
			(xy 124.297693 -255.573589) (xy 124.577349 -255.573589) (xy 124.577349 -255.521655) (xy 124.585474 -255.47036)
			(xy 124.601522 -255.420967) (xy 124.6251 -255.374693) (xy 124.655626 -255.332677) (xy 124.692349 -255.295954)
			(xy 124.734365 -255.265428) (xy 124.780639 -255.24185) (xy 124.830032 -255.225802) (xy 124.881327 -255.217677)
			(xy 124.933261 -255.217677) (xy 124.984556 -255.225802) (xy 125.033949 -255.24185) (xy 125.080223 -255.265428)
			(xy 125.122239 -255.295954) (xy 125.158962 -255.332677) (xy 125.189488 -255.374693) (xy 125.213066 -255.420967)
			(xy 125.229114 -255.47036) (xy 125.237239 -255.521655) (xy 125.237748 -255.547622) (xy 125.237239 -255.573589)
			(xy 125.229114 -255.624884) (xy 125.213066 -255.674277) (xy 125.189488 -255.720551) (xy 125.158962 -255.762567)
			(xy 125.122239 -255.79929) (xy 125.080223 -255.829816) (xy 125.033949 -255.853394) (xy 124.984556 -255.869442)
			(xy 124.933261 -255.877567) (xy 124.881327 -255.877567) (xy 124.830032 -255.869442) (xy 124.780639 -255.853394)
			(xy 124.734365 -255.829816) (xy 124.692349 -255.79929) (xy 124.655626 -255.762567) (xy 124.6251 -255.720551)
			(xy 124.601522 -255.674277) (xy 124.585474 -255.624884) (xy 124.577349 -255.573589) (xy 124.297693 -255.573589)
			(xy 124.289568 -255.624884) (xy 124.27352 -255.674277) (xy 124.249942 -255.720551) (xy 124.219416 -255.762567)
			(xy 124.182693 -255.79929) (xy 124.140677 -255.829816) (xy 124.094403 -255.853394) (xy 124.04501 -255.869442)
			(xy 123.993715 -255.877567) (xy 123.941781 -255.877567) (xy 123.890486 -255.869442) (xy 123.841093 -255.853394)
			(xy 123.794819 -255.829816) (xy 123.752803 -255.79929) (xy 123.71608 -255.762567) (xy 123.685554 -255.720551)
			(xy 123.661976 -255.674277) (xy 123.645928 -255.624884) (xy 123.637803 -255.573589) (xy 123.357893 -255.573589)
			(xy 123.349768 -255.624884) (xy 123.33372 -255.674277) (xy 123.310142 -255.720551) (xy 123.279616 -255.762567)
			(xy 123.242893 -255.79929) (xy 123.200877 -255.829816) (xy 123.154603 -255.853394) (xy 123.10521 -255.869442)
			(xy 123.053915 -255.877567) (xy 123.001981 -255.877567) (xy 122.950686 -255.869442) (xy 122.901293 -255.853394)
			(xy 122.855019 -255.829816) (xy 122.813003 -255.79929) (xy 122.77628 -255.762567) (xy 122.745754 -255.720551)
			(xy 122.722176 -255.674277) (xy 122.706128 -255.624884) (xy 122.698003 -255.573589) (xy 121.303639 -255.573589)
			(xy 121.29821 -255.607866) (xy 121.282162 -255.657259) (xy 121.258584 -255.703533) (xy 121.228058 -255.745549)
			(xy 121.191335 -255.782272) (xy 121.149319 -255.812798) (xy 121.103045 -255.836376) (xy 121.053652 -255.852424)
			(xy 121.002357 -255.860549) (xy 120.950423 -255.860549) (xy 120.899128 -255.852424) (xy 120.849735 -255.836376)
			(xy 120.803461 -255.812798) (xy 120.761445 -255.782272) (xy 120.724722 -255.745549) (xy 120.694196 -255.703533)
			(xy 120.670618 -255.657259) (xy 120.65457 -255.607866) (xy 120.646445 -255.556571) (xy 120.645936 -255.530604)
			(xy 120.370346 -255.530604) (xy 120.370346 -257.283204) (xy 120.645936 -257.283204) (xy 120.646466 -257.256805)
			(xy 120.654867 -257.204678) (xy 120.67144 -257.154547) (xy 120.695763 -257.107685) (xy 120.727221 -257.06528)
			(xy 120.745758 -257.046476) (xy 120.755065 -257.036749) (xy 120.768745 -257.013578) (xy 120.775884 -256.987634)
			(xy 120.775985 -256.960726) (xy 120.769041 -256.934729) (xy 120.755536 -256.911455) (xy 120.746266 -256.901696)
			(xy 120.728055 -256.882974) (xy 120.697221 -256.840818) (xy 120.673399 -256.794339) (xy 120.657181 -256.744693)
			(xy 120.648969 -256.693114) (xy 120.648476 -256.667) (xy 120.648929 -256.641029) (xy 120.657055 -256.589727)
			(xy 120.673107 -256.540328) (xy 120.696689 -256.494048) (xy 120.727221 -256.452028) (xy 120.763951 -256.415301)
			(xy 120.805974 -256.384773) (xy 120.852256 -256.361195) (xy 120.901656 -256.345148) (xy 120.952959 -256.337027)
			(xy 120.97893 -256.336546) (xy 121.007325 -256.337155) (xy 121.063279 -256.346857) (xy 121.116748 -256.365988)
			(xy 121.141744 -256.379472) (xy 121.15412 -256.385973) (xy 121.181255 -256.392649) (xy 121.209183 -256.391703)
			(xy 121.235803 -256.383205) (xy 121.259115 -256.367796) (xy 121.277363 -256.346633) (xy 121.289177 -256.32131)
			(xy 121.291858 -256.30759) (xy 121.296638 -256.282184) (xy 121.312914 -256.233121) (xy 121.336629 -256.18719)
			(xy 121.367202 -256.145509) (xy 121.40389 -256.109094) (xy 121.445799 -256.078833) (xy 121.491906 -256.055462)
			(xy 121.541089 -256.039553) (xy 121.592148 -256.031492) (xy 121.617994 -256.030984) (xy 121.643967 -256.031391)
			(xy 121.695272 -256.039516) (xy 121.744675 -256.055567) (xy 121.790959 -256.079149) (xy 121.832984 -256.109681)
			(xy 121.869715 -256.146411) (xy 121.900248 -256.188436) (xy 121.923831 -256.234719) (xy 121.939883 -256.284122)
			(xy 121.948009 -256.335427) (xy 121.948009 -256.387373) (xy 121.948004 -256.387405) (xy 122.228103 -256.387405)
			(xy 122.228103 -256.335471) (xy 122.236228 -256.284176) (xy 122.252276 -256.234783) (xy 122.275854 -256.188509)
			(xy 122.30638 -256.146493) (xy 122.343103 -256.10977) (xy 122.385119 -256.079244) (xy 122.431393 -256.055666)
			(xy 122.480786 -256.039618) (xy 122.532081 -256.031493) (xy 122.584015 -256.031493) (xy 122.63531 -256.039618)
			(xy 122.684703 -256.055666) (xy 122.730977 -256.079244) (xy 122.772993 -256.10977) (xy 122.809716 -256.146493)
			(xy 122.840242 -256.188509) (xy 122.86382 -256.234783) (xy 122.879868 -256.284176) (xy 122.887993 -256.335471)
			(xy 122.888502 -256.361438) (xy 122.887993 -256.387405) (xy 123.167649 -256.387405) (xy 123.167649 -256.335471)
			(xy 123.175774 -256.284176) (xy 123.191822 -256.234783) (xy 123.2154 -256.188509) (xy 123.245926 -256.146493)
			(xy 123.282649 -256.10977) (xy 123.324665 -256.079244) (xy 123.370939 -256.055666) (xy 123.420332 -256.039618)
			(xy 123.471627 -256.031493) (xy 123.523561 -256.031493) (xy 123.574856 -256.039618) (xy 123.624249 -256.055666)
			(xy 123.670523 -256.079244) (xy 123.712539 -256.10977) (xy 123.749262 -256.146493) (xy 123.779788 -256.188509)
			(xy 123.803366 -256.234783) (xy 123.819414 -256.284176) (xy 123.827539 -256.335471) (xy 123.828048 -256.361438)
			(xy 123.827539 -256.387405) (xy 124.107449 -256.387405) (xy 124.107449 -256.335471) (xy 124.115574 -256.284176)
			(xy 124.131622 -256.234783) (xy 124.1552 -256.188509) (xy 124.185726 -256.146493) (xy 124.222449 -256.10977)
			(xy 124.264465 -256.079244) (xy 124.310739 -256.055666) (xy 124.360132 -256.039618) (xy 124.411427 -256.031493)
			(xy 124.463361 -256.031493) (xy 124.514656 -256.039618) (xy 124.564049 -256.055666) (xy 124.610323 -256.079244)
			(xy 124.652339 -256.10977) (xy 124.689062 -256.146493) (xy 124.719588 -256.188509) (xy 124.743166 -256.234783)
			(xy 124.759214 -256.284176) (xy 124.767339 -256.335471) (xy 124.767848 -256.361438) (xy 124.767339 -256.387405)
			(xy 124.759214 -256.4387) (xy 124.743166 -256.488093) (xy 124.719588 -256.534367) (xy 124.689062 -256.576383)
			(xy 124.652339 -256.613106) (xy 124.610323 -256.643632) (xy 124.564049 -256.66721) (xy 124.514656 -256.683258)
			(xy 124.463361 -256.691383) (xy 124.411427 -256.691383) (xy 124.360132 -256.683258) (xy 124.310739 -256.66721)
			(xy 124.264465 -256.643632) (xy 124.222449 -256.613106) (xy 124.185726 -256.576383) (xy 124.1552 -256.534367)
			(xy 124.131622 -256.488093) (xy 124.115574 -256.4387) (xy 124.107449 -256.387405) (xy 123.827539 -256.387405)
			(xy 123.819414 -256.4387) (xy 123.803366 -256.488093) (xy 123.779788 -256.534367) (xy 123.749262 -256.576383)
			(xy 123.712539 -256.613106) (xy 123.670523 -256.643632) (xy 123.624249 -256.66721) (xy 123.574856 -256.683258)
			(xy 123.523561 -256.691383) (xy 123.471627 -256.691383) (xy 123.420332 -256.683258) (xy 123.370939 -256.66721)
			(xy 123.324665 -256.643632) (xy 123.282649 -256.613106) (xy 123.245926 -256.576383) (xy 123.2154 -256.534367)
			(xy 123.191822 -256.488093) (xy 123.175774 -256.4387) (xy 123.167649 -256.387405) (xy 122.887993 -256.387405)
			(xy 122.879868 -256.4387) (xy 122.86382 -256.488093) (xy 122.840242 -256.534367) (xy 122.809716 -256.576383)
			(xy 122.772993 -256.613106) (xy 122.730977 -256.643632) (xy 122.684703 -256.66721) (xy 122.63531 -256.683258)
			(xy 122.584015 -256.691383) (xy 122.532081 -256.691383) (xy 122.480786 -256.683258) (xy 122.431393 -256.66721)
			(xy 122.385119 -256.643632) (xy 122.343103 -256.613106) (xy 122.30638 -256.576383) (xy 122.275854 -256.534367)
			(xy 122.252276 -256.488093) (xy 122.236228 -256.4387) (xy 122.228103 -256.387405) (xy 121.948004 -256.387405)
			(xy 121.939883 -256.438678) (xy 121.923831 -256.488081) (xy 121.900248 -256.534364) (xy 121.869715 -256.576389)
			(xy 121.832984 -256.613119) (xy 121.790959 -256.643651) (xy 121.744675 -256.667233) (xy 121.695272 -256.683284)
			(xy 121.643967 -256.691409) (xy 121.617994 -256.691892) (xy 121.589598 -256.691309) (xy 121.533644 -256.681595)
			(xy 121.480175 -256.662454) (xy 121.45518 -256.648966) (xy 121.442831 -256.642415) (xy 121.415689 -256.635759)
			(xy 121.387759 -256.636721) (xy 121.361138 -256.645228) (xy 121.337827 -256.660642) (xy 121.319575 -256.681805)
			(xy 121.307753 -256.707128) (xy 121.305066 -256.720848) (xy 121.300271 -256.746652) (xy 121.283623 -256.796424)
			(xy 121.259331 -256.842946) (xy 121.228002 -256.885052) (xy 121.209562 -256.903728) (xy 121.200249 -256.91345)
			(xy 121.186567 -256.936622) (xy 121.179427 -256.962568) (xy 121.179327 -256.989478) (xy 121.186273 -257.015476)
			(xy 121.199781 -257.03875) (xy 121.209054 -257.048508) (xy 121.22727 -257.067225) (xy 121.258102 -257.109383)
			(xy 121.281923 -257.155863) (xy 121.29674 -257.201221) (xy 121.758203 -257.201221) (xy 121.758203 -257.149287)
			(xy 121.766328 -257.097992) (xy 121.782376 -257.048599) (xy 121.805954 -257.002325) (xy 121.83648 -256.960309)
			(xy 121.873203 -256.923586) (xy 121.915219 -256.89306) (xy 121.961493 -256.869482) (xy 122.010886 -256.853434)
			(xy 122.062181 -256.845309) (xy 122.114115 -256.845309) (xy 122.16541 -256.853434) (xy 122.214803 -256.869482)
			(xy 122.261077 -256.89306) (xy 122.303093 -256.923586) (xy 122.339816 -256.960309) (xy 122.370342 -257.002325)
			(xy 122.39392 -257.048599) (xy 122.409968 -257.097992) (xy 122.418093 -257.149287) (xy 122.418602 -257.175254)
			(xy 122.418093 -257.201221) (xy 122.698003 -257.201221) (xy 122.698003 -257.149287) (xy 122.706128 -257.097992)
			(xy 122.722176 -257.048599) (xy 122.745754 -257.002325) (xy 122.77628 -256.960309) (xy 122.813003 -256.923586)
			(xy 122.855019 -256.89306) (xy 122.901293 -256.869482) (xy 122.950686 -256.853434) (xy 123.001981 -256.845309)
			(xy 123.053915 -256.845309) (xy 123.10521 -256.853434) (xy 123.154603 -256.869482) (xy 123.200877 -256.89306)
			(xy 123.242893 -256.923586) (xy 123.279616 -256.960309) (xy 123.310142 -257.002325) (xy 123.33372 -257.048599)
			(xy 123.349768 -257.097992) (xy 123.357893 -257.149287) (xy 123.358402 -257.175254) (xy 123.357893 -257.201221)
			(xy 123.637803 -257.201221) (xy 123.637803 -257.149287) (xy 123.645928 -257.097992) (xy 123.661976 -257.048599)
			(xy 123.685554 -257.002325) (xy 123.71608 -256.960309) (xy 123.752803 -256.923586) (xy 123.794819 -256.89306)
			(xy 123.841093 -256.869482) (xy 123.890486 -256.853434) (xy 123.941781 -256.845309) (xy 123.993715 -256.845309)
			(xy 124.04501 -256.853434) (xy 124.094403 -256.869482) (xy 124.140677 -256.89306) (xy 124.182693 -256.923586)
			(xy 124.219416 -256.960309) (xy 124.249942 -257.002325) (xy 124.27352 -257.048599) (xy 124.289568 -257.097992)
			(xy 124.297693 -257.149287) (xy 124.298202 -257.175254) (xy 124.297693 -257.201221) (xy 124.577349 -257.201221)
			(xy 124.577349 -257.149287) (xy 124.585474 -257.097992) (xy 124.601522 -257.048599) (xy 124.6251 -257.002325)
			(xy 124.655626 -256.960309) (xy 124.692349 -256.923586) (xy 124.734365 -256.89306) (xy 124.780639 -256.869482)
			(xy 124.830032 -256.853434) (xy 124.881327 -256.845309) (xy 124.933261 -256.845309) (xy 124.984556 -256.853434)
			(xy 125.033949 -256.869482) (xy 125.080223 -256.89306) (xy 125.122239 -256.923586) (xy 125.158962 -256.960309)
			(xy 125.189488 -257.002325) (xy 125.213066 -257.048599) (xy 125.229114 -257.097992) (xy 125.237239 -257.149287)
			(xy 125.237748 -257.175254) (xy 125.237239 -257.201221) (xy 125.229114 -257.252516) (xy 125.213066 -257.301909)
			(xy 125.189488 -257.348183) (xy 125.158962 -257.390199) (xy 125.122239 -257.426922) (xy 125.080223 -257.457448)
			(xy 125.033949 -257.481026) (xy 124.984556 -257.497074) (xy 124.933261 -257.505199) (xy 124.881327 -257.505199)
			(xy 124.830032 -257.497074) (xy 124.780639 -257.481026) (xy 124.734365 -257.457448) (xy 124.692349 -257.426922)
			(xy 124.655626 -257.390199) (xy 124.6251 -257.348183) (xy 124.601522 -257.301909) (xy 124.585474 -257.252516)
			(xy 124.577349 -257.201221) (xy 124.297693 -257.201221) (xy 124.289568 -257.252516) (xy 124.27352 -257.301909)
			(xy 124.249942 -257.348183) (xy 124.219416 -257.390199) (xy 124.182693 -257.426922) (xy 124.140677 -257.457448)
			(xy 124.094403 -257.481026) (xy 124.04501 -257.497074) (xy 123.993715 -257.505199) (xy 123.941781 -257.505199)
			(xy 123.890486 -257.497074) (xy 123.841093 -257.481026) (xy 123.794819 -257.457448) (xy 123.752803 -257.426922)
			(xy 123.71608 -257.390199) (xy 123.685554 -257.348183) (xy 123.661976 -257.301909) (xy 123.645928 -257.252516)
			(xy 123.637803 -257.201221) (xy 123.357893 -257.201221) (xy 123.349768 -257.252516) (xy 123.33372 -257.301909)
			(xy 123.310142 -257.348183) (xy 123.279616 -257.390199) (xy 123.242893 -257.426922) (xy 123.200877 -257.457448)
			(xy 123.154603 -257.481026) (xy 123.10521 -257.497074) (xy 123.053915 -257.505199) (xy 123.001981 -257.505199)
			(xy 122.950686 -257.497074) (xy 122.901293 -257.481026) (xy 122.855019 -257.457448) (xy 122.813003 -257.426922)
			(xy 122.77628 -257.390199) (xy 122.745754 -257.348183) (xy 122.722176 -257.301909) (xy 122.706128 -257.252516)
			(xy 122.698003 -257.201221) (xy 122.418093 -257.201221) (xy 122.409968 -257.252516) (xy 122.39392 -257.301909)
			(xy 122.370342 -257.348183) (xy 122.339816 -257.390199) (xy 122.303093 -257.426922) (xy 122.261077 -257.457448)
			(xy 122.214803 -257.481026) (xy 122.16541 -257.497074) (xy 122.114115 -257.505199) (xy 122.062181 -257.505199)
			(xy 122.010886 -257.497074) (xy 121.961493 -257.481026) (xy 121.915219 -257.457448) (xy 121.873203 -257.426922)
			(xy 121.83648 -257.390199) (xy 121.805954 -257.348183) (xy 121.782376 -257.301909) (xy 121.766328 -257.252516)
			(xy 121.758203 -257.201221) (xy 121.29674 -257.201221) (xy 121.298141 -257.20551) (xy 121.306351 -257.25709)
			(xy 121.306844 -257.283204) (xy 121.306335 -257.309171) (xy 121.29821 -257.360466) (xy 121.282162 -257.409859)
			(xy 121.258584 -257.456133) (xy 121.228058 -257.498149) (xy 121.191335 -257.534872) (xy 121.149319 -257.565398)
			(xy 121.103045 -257.588976) (xy 121.053652 -257.605024) (xy 121.002357 -257.613149) (xy 120.950423 -257.613149)
			(xy 120.899128 -257.605024) (xy 120.849735 -257.588976) (xy 120.803461 -257.565398) (xy 120.761445 -257.534872)
			(xy 120.724722 -257.498149) (xy 120.694196 -257.456133) (xy 120.670618 -257.409859) (xy 120.65457 -257.360466)
			(xy 120.646445 -257.309171) (xy 120.645936 -257.283204) (xy 120.370346 -257.283204) (xy 120.370346 -258.015037)
			(xy 121.288049 -258.015037) (xy 121.288049 -257.963103) (xy 121.296174 -257.911808) (xy 121.312222 -257.862415)
			(xy 121.3358 -257.816141) (xy 121.366326 -257.774125) (xy 121.403049 -257.737402) (xy 121.445065 -257.706876)
			(xy 121.491339 -257.683298) (xy 121.540732 -257.66725) (xy 121.592027 -257.659125) (xy 121.643961 -257.659125)
			(xy 121.695256 -257.66725) (xy 121.744649 -257.683298) (xy 121.790923 -257.706876) (xy 121.832939 -257.737402)
			(xy 121.869662 -257.774125) (xy 121.900188 -257.816141) (xy 121.923766 -257.862415) (xy 121.939814 -257.911808)
			(xy 121.947939 -257.963103) (xy 121.948448 -257.98907) (xy 121.947939 -258.015037) (xy 122.227849 -258.015037)
			(xy 122.227849 -257.963103) (xy 122.235974 -257.911808) (xy 122.252022 -257.862415) (xy 122.2756 -257.816141)
			(xy 122.306126 -257.774125) (xy 122.342849 -257.737402) (xy 122.384865 -257.706876) (xy 122.431139 -257.683298)
			(xy 122.480532 -257.66725) (xy 122.531827 -257.659125) (xy 122.583761 -257.659125) (xy 122.635056 -257.66725)
			(xy 122.684449 -257.683298) (xy 122.730723 -257.706876) (xy 122.772739 -257.737402) (xy 122.809462 -257.774125)
			(xy 122.839988 -257.816141) (xy 122.863566 -257.862415) (xy 122.879614 -257.911808) (xy 122.887739 -257.963103)
			(xy 122.888248 -257.98907) (xy 122.887739 -258.015037) (xy 123.167649 -258.015037) (xy 123.167649 -257.963103)
			(xy 123.175774 -257.911808) (xy 123.191822 -257.862415) (xy 123.2154 -257.816141) (xy 123.245926 -257.774125)
			(xy 123.282649 -257.737402) (xy 123.324665 -257.706876) (xy 123.370939 -257.683298) (xy 123.420332 -257.66725)
			(xy 123.471627 -257.659125) (xy 123.523561 -257.659125) (xy 123.574856 -257.66725) (xy 123.624249 -257.683298)
			(xy 123.670523 -257.706876) (xy 123.712539 -257.737402) (xy 123.749262 -257.774125) (xy 123.779788 -257.816141)
			(xy 123.803366 -257.862415) (xy 123.819414 -257.911808) (xy 123.827539 -257.963103) (xy 123.828048 -257.98907)
			(xy 123.827539 -258.015037) (xy 124.107449 -258.015037) (xy 124.107449 -257.963103) (xy 124.115574 -257.911808)
			(xy 124.131622 -257.862415) (xy 124.1552 -257.816141) (xy 124.185726 -257.774125) (xy 124.222449 -257.737402)
			(xy 124.264465 -257.706876) (xy 124.310739 -257.683298) (xy 124.360132 -257.66725) (xy 124.411427 -257.659125)
			(xy 124.463361 -257.659125) (xy 124.514656 -257.66725) (xy 124.564049 -257.683298) (xy 124.610323 -257.706876)
			(xy 124.652339 -257.737402) (xy 124.689062 -257.774125) (xy 124.719588 -257.816141) (xy 124.743166 -257.862415)
			(xy 124.759214 -257.911808) (xy 124.767339 -257.963103) (xy 124.767848 -257.98907) (xy 124.767339 -258.015037)
			(xy 124.759214 -258.066332) (xy 124.743166 -258.115725) (xy 124.719588 -258.161999) (xy 124.689062 -258.204015)
			(xy 124.652339 -258.240738) (xy 124.610323 -258.271264) (xy 124.564049 -258.294842) (xy 124.514656 -258.31089)
			(xy 124.463361 -258.319015) (xy 124.411427 -258.319015) (xy 124.360132 -258.31089) (xy 124.310739 -258.294842)
			(xy 124.264465 -258.271264) (xy 124.222449 -258.240738) (xy 124.185726 -258.204015) (xy 124.1552 -258.161999)
			(xy 124.131622 -258.115725) (xy 124.115574 -258.066332) (xy 124.107449 -258.015037) (xy 123.827539 -258.015037)
			(xy 123.819414 -258.066332) (xy 123.803366 -258.115725) (xy 123.779788 -258.161999) (xy 123.749262 -258.204015)
			(xy 123.712539 -258.240738) (xy 123.670523 -258.271264) (xy 123.624249 -258.294842) (xy 123.574856 -258.31089)
			(xy 123.523561 -258.319015) (xy 123.471627 -258.319015) (xy 123.420332 -258.31089) (xy 123.370939 -258.294842)
			(xy 123.324665 -258.271264) (xy 123.282649 -258.240738) (xy 123.245926 -258.204015) (xy 123.2154 -258.161999)
			(xy 123.191822 -258.115725) (xy 123.175774 -258.066332) (xy 123.167649 -258.015037) (xy 122.887739 -258.015037)
			(xy 122.879614 -258.066332) (xy 122.863566 -258.115725) (xy 122.839988 -258.161999) (xy 122.809462 -258.204015)
			(xy 122.772739 -258.240738) (xy 122.730723 -258.271264) (xy 122.684449 -258.294842) (xy 122.635056 -258.31089)
			(xy 122.583761 -258.319015) (xy 122.531827 -258.319015) (xy 122.480532 -258.31089) (xy 122.431139 -258.294842)
			(xy 122.384865 -258.271264) (xy 122.342849 -258.240738) (xy 122.306126 -258.204015) (xy 122.2756 -258.161999)
			(xy 122.252022 -258.115725) (xy 122.235974 -258.066332) (xy 122.227849 -258.015037) (xy 121.947939 -258.015037)
			(xy 121.939814 -258.066332) (xy 121.923766 -258.115725) (xy 121.900188 -258.161999) (xy 121.869662 -258.204015)
			(xy 121.832939 -258.240738) (xy 121.790923 -258.271264) (xy 121.744649 -258.294842) (xy 121.695256 -258.31089)
			(xy 121.643961 -258.319015) (xy 121.592027 -258.319015) (xy 121.540732 -258.31089) (xy 121.491339 -258.294842)
			(xy 121.445065 -258.271264) (xy 121.403049 -258.240738) (xy 121.366326 -258.204015) (xy 121.3358 -258.161999)
			(xy 121.312222 -258.115725) (xy 121.296174 -258.066332) (xy 121.288049 -258.015037) (xy 120.370346 -258.015037)
			(xy 120.370346 -258.477571) (xy 120.646445 -258.477571) (xy 120.646445 -258.425637) (xy 120.65457 -258.374342)
			(xy 120.670618 -258.324949) (xy 120.694196 -258.278675) (xy 120.724722 -258.236659) (xy 120.761445 -258.199936)
			(xy 120.803461 -258.16941) (xy 120.849735 -258.145832) (xy 120.899128 -258.129784) (xy 120.950423 -258.121659)
			(xy 121.002357 -258.121659) (xy 121.053652 -258.129784) (xy 121.103045 -258.145832) (xy 121.149319 -258.16941)
			(xy 121.191335 -258.199936) (xy 121.228058 -258.236659) (xy 121.258584 -258.278675) (xy 121.282162 -258.324949)
			(xy 121.29821 -258.374342) (xy 121.306335 -258.425637) (xy 121.306844 -258.451604) (xy 121.306335 -258.477571)
			(xy 121.29821 -258.528866) (xy 121.282162 -258.578259) (xy 121.258584 -258.624533) (xy 121.228058 -258.666549)
			(xy 121.191335 -258.703272) (xy 121.149319 -258.733798) (xy 121.103045 -258.757376) (xy 121.053652 -258.773424)
			(xy 121.002357 -258.781549) (xy 120.950423 -258.781549) (xy 120.899128 -258.773424) (xy 120.849735 -258.757376)
			(xy 120.803461 -258.733798) (xy 120.761445 -258.703272) (xy 120.724722 -258.666549) (xy 120.694196 -258.624533)
			(xy 120.670618 -258.578259) (xy 120.65457 -258.528866) (xy 120.646445 -258.477571) (xy 120.370346 -258.477571)
			(xy 120.370346 -258.829107) (xy 121.757949 -258.829107) (xy 121.757949 -258.777173) (xy 121.766074 -258.725878)
			(xy 121.782122 -258.676485) (xy 121.8057 -258.630211) (xy 121.836226 -258.588195) (xy 121.872949 -258.551472)
			(xy 121.914965 -258.520946) (xy 121.961239 -258.497368) (xy 122.010632 -258.48132) (xy 122.061927 -258.473195)
			(xy 122.113861 -258.473195) (xy 122.165156 -258.48132) (xy 122.214549 -258.497368) (xy 122.260823 -258.520946)
			(xy 122.302839 -258.551472) (xy 122.339562 -258.588195) (xy 122.370088 -258.630211) (xy 122.393666 -258.676485)
			(xy 122.409714 -258.725878) (xy 122.417839 -258.777173) (xy 122.418348 -258.80314) (xy 122.417839 -258.829107)
			(xy 122.697749 -258.829107) (xy 122.697749 -258.777173) (xy 122.705874 -258.725878) (xy 122.721922 -258.676485)
			(xy 122.7455 -258.630211) (xy 122.776026 -258.588195) (xy 122.812749 -258.551472) (xy 122.854765 -258.520946)
			(xy 122.901039 -258.497368) (xy 122.950432 -258.48132) (xy 123.001727 -258.473195) (xy 123.053661 -258.473195)
			(xy 123.104956 -258.48132) (xy 123.154349 -258.497368) (xy 123.200623 -258.520946) (xy 123.242639 -258.551472)
			(xy 123.279362 -258.588195) (xy 123.309888 -258.630211) (xy 123.333466 -258.676485) (xy 123.349514 -258.725878)
			(xy 123.357639 -258.777173) (xy 123.358148 -258.80314) (xy 123.357639 -258.829107) (xy 123.637803 -258.829107)
			(xy 123.637803 -258.777173) (xy 123.645928 -258.725878) (xy 123.661976 -258.676485) (xy 123.685554 -258.630211)
			(xy 123.71608 -258.588195) (xy 123.752803 -258.551472) (xy 123.794819 -258.520946) (xy 123.841093 -258.497368)
			(xy 123.890486 -258.48132) (xy 123.941781 -258.473195) (xy 123.993715 -258.473195) (xy 124.04501 -258.48132)
			(xy 124.094403 -258.497368) (xy 124.140677 -258.520946) (xy 124.182693 -258.551472) (xy 124.219416 -258.588195)
			(xy 124.249942 -258.630211) (xy 124.27352 -258.676485) (xy 124.289568 -258.725878) (xy 124.297693 -258.777173)
			(xy 124.298202 -258.80314) (xy 124.297693 -258.829107) (xy 124.577603 -258.829107) (xy 124.577603 -258.777173)
			(xy 124.585728 -258.725878) (xy 124.601776 -258.676485) (xy 124.625354 -258.630211) (xy 124.65588 -258.588195)
			(xy 124.692603 -258.551472) (xy 124.734619 -258.520946) (xy 124.780893 -258.497368) (xy 124.830286 -258.48132)
			(xy 124.881581 -258.473195) (xy 124.933515 -258.473195) (xy 124.98481 -258.48132) (xy 125.034203 -258.497368)
			(xy 125.080477 -258.520946) (xy 125.122493 -258.551472) (xy 125.159216 -258.588195) (xy 125.189742 -258.630211)
			(xy 125.21332 -258.676485) (xy 125.229368 -258.725878) (xy 125.237493 -258.777173) (xy 125.238002 -258.80314)
			(xy 125.237493 -258.829107) (xy 125.229368 -258.880402) (xy 125.21332 -258.929795) (xy 125.189742 -258.976069)
			(xy 125.159216 -259.018085) (xy 125.122493 -259.054808) (xy 125.080477 -259.085334) (xy 125.034203 -259.108912)
			(xy 124.98481 -259.12496) (xy 124.933515 -259.133085) (xy 124.881581 -259.133085) (xy 124.830286 -259.12496)
			(xy 124.780893 -259.108912) (xy 124.734619 -259.085334) (xy 124.692603 -259.054808) (xy 124.65588 -259.018085)
			(xy 124.625354 -258.976069) (xy 124.601776 -258.929795) (xy 124.585728 -258.880402) (xy 124.577603 -258.829107)
			(xy 124.297693 -258.829107) (xy 124.289568 -258.880402) (xy 124.27352 -258.929795) (xy 124.249942 -258.976069)
			(xy 124.219416 -259.018085) (xy 124.182693 -259.054808) (xy 124.140677 -259.085334) (xy 124.094403 -259.108912)
			(xy 124.04501 -259.12496) (xy 123.993715 -259.133085) (xy 123.941781 -259.133085) (xy 123.890486 -259.12496)
			(xy 123.841093 -259.108912) (xy 123.794819 -259.085334) (xy 123.752803 -259.054808) (xy 123.71608 -259.018085)
			(xy 123.685554 -258.976069) (xy 123.661976 -258.929795) (xy 123.645928 -258.880402) (xy 123.637803 -258.829107)
			(xy 123.357639 -258.829107) (xy 123.349514 -258.880402) (xy 123.333466 -258.929795) (xy 123.309888 -258.976069)
			(xy 123.279362 -259.018085) (xy 123.242639 -259.054808) (xy 123.200623 -259.085334) (xy 123.154349 -259.108912)
			(xy 123.104956 -259.12496) (xy 123.053661 -259.133085) (xy 123.001727 -259.133085) (xy 122.950432 -259.12496)
			(xy 122.901039 -259.108912) (xy 122.854765 -259.085334) (xy 122.812749 -259.054808) (xy 122.776026 -259.018085)
			(xy 122.7455 -258.976069) (xy 122.721922 -258.929795) (xy 122.705874 -258.880402) (xy 122.697749 -258.829107)
			(xy 122.417839 -258.829107) (xy 122.409714 -258.880402) (xy 122.393666 -258.929795) (xy 122.370088 -258.976069)
			(xy 122.339562 -259.018085) (xy 122.302839 -259.054808) (xy 122.260823 -259.085334) (xy 122.214549 -259.108912)
			(xy 122.165156 -259.12496) (xy 122.113861 -259.133085) (xy 122.061927 -259.133085) (xy 122.010632 -259.12496)
			(xy 121.961239 -259.108912) (xy 121.914965 -259.085334) (xy 121.872949 -259.054808) (xy 121.836226 -259.018085)
			(xy 121.8057 -258.976069) (xy 121.782122 -258.929795) (xy 121.766074 -258.880402) (xy 121.757949 -258.829107)
			(xy 120.370346 -258.829107) (xy 120.370346 -259.775461) (xy 120.643999 -259.775461) (xy 120.643999 -259.723539)
			(xy 120.652121 -259.672255) (xy 120.668164 -259.622874) (xy 120.691734 -259.576609) (xy 120.722251 -259.534601)
			(xy 120.758963 -259.497884) (xy 120.800966 -259.46736) (xy 120.847227 -259.443783) (xy 120.896607 -259.427732)
			(xy 120.947889 -259.419603) (xy 120.97385 -259.41909) (xy 121.001224 -259.419636) (xy 121.055224 -259.428653)
			(xy 121.106999 -259.446447) (xy 121.155132 -259.472532) (xy 121.17705 -259.48894) (xy 121.188904 -259.497579)
			(xy 121.216236 -259.508204) (xy 121.245459 -259.510649) (xy 121.274177 -259.504714) (xy 121.300036 -259.490885)
			(xy 121.320918 -259.470297) (xy 121.328434 -259.457698) (xy 121.341003 -259.435827) (xy 121.37175 -259.39584)
			(xy 121.408216 -259.360989) (xy 121.449555 -259.332084) (xy 121.494805 -259.309797) (xy 121.542917 -259.294644)
			(xy 121.592773 -259.286978) (xy 121.617994 -259.286502) (xy 121.64396 -259.287072) (xy 121.695253 -259.295195)
			(xy 121.744644 -259.311243) (xy 121.790916 -259.334819) (xy 121.832931 -259.365343) (xy 121.869653 -259.402065)
			(xy 121.900178 -259.444079) (xy 121.923755 -259.49035) (xy 121.939803 -259.539741) (xy 121.947927 -259.591034)
			(xy 121.947927 -259.642923) (xy 122.227849 -259.642923) (xy 122.227849 -259.590989) (xy 122.235974 -259.539694)
			(xy 122.252022 -259.490301) (xy 122.2756 -259.444027) (xy 122.306126 -259.402011) (xy 122.342849 -259.365288)
			(xy 122.384865 -259.334762) (xy 122.431139 -259.311184) (xy 122.480532 -259.295136) (xy 122.531827 -259.287011)
			(xy 122.583761 -259.287011) (xy 122.635056 -259.295136) (xy 122.684449 -259.311184) (xy 122.730723 -259.334762)
			(xy 122.772739 -259.365288) (xy 122.809462 -259.402011) (xy 122.839988 -259.444027) (xy 122.863566 -259.490301)
			(xy 122.879614 -259.539694) (xy 122.887739 -259.590989) (xy 122.888248 -259.616956) (xy 122.887739 -259.642923)
			(xy 123.167649 -259.642923) (xy 123.167649 -259.590989) (xy 123.175774 -259.539694) (xy 123.191822 -259.490301)
			(xy 123.2154 -259.444027) (xy 123.245926 -259.402011) (xy 123.282649 -259.365288) (xy 123.324665 -259.334762)
			(xy 123.370939 -259.311184) (xy 123.420332 -259.295136) (xy 123.471627 -259.287011) (xy 123.523561 -259.287011)
			(xy 123.574856 -259.295136) (xy 123.624249 -259.311184) (xy 123.670523 -259.334762) (xy 123.712539 -259.365288)
			(xy 123.749262 -259.402011) (xy 123.779788 -259.444027) (xy 123.803366 -259.490301) (xy 123.819414 -259.539694)
			(xy 123.827539 -259.590989) (xy 123.828048 -259.616956) (xy 123.827539 -259.642923) (xy 124.107449 -259.642923)
			(xy 124.107449 -259.590989) (xy 124.115574 -259.539694) (xy 124.131622 -259.490301) (xy 124.1552 -259.444027)
			(xy 124.185726 -259.402011) (xy 124.222449 -259.365288) (xy 124.264465 -259.334762) (xy 124.310739 -259.311184)
			(xy 124.360132 -259.295136) (xy 124.411427 -259.287011) (xy 124.463361 -259.287011) (xy 124.514656 -259.295136)
			(xy 124.564049 -259.311184) (xy 124.610323 -259.334762) (xy 124.652339 -259.365288) (xy 124.689062 -259.402011)
			(xy 124.719588 -259.444027) (xy 124.743166 -259.490301) (xy 124.759214 -259.539694) (xy 124.767339 -259.590989)
			(xy 124.767848 -259.616956) (xy 124.767339 -259.642923) (xy 124.759214 -259.694218) (xy 124.743166 -259.743611)
			(xy 124.719588 -259.789885) (xy 124.689062 -259.831901) (xy 124.652339 -259.868624) (xy 124.610323 -259.89915)
			(xy 124.564049 -259.922728) (xy 124.514656 -259.938776) (xy 124.463361 -259.946901) (xy 124.411427 -259.946901)
			(xy 124.360132 -259.938776) (xy 124.310739 -259.922728) (xy 124.264465 -259.89915) (xy 124.222449 -259.868624)
			(xy 124.185726 -259.831901) (xy 124.1552 -259.789885) (xy 124.131622 -259.743611) (xy 124.115574 -259.694218)
			(xy 124.107449 -259.642923) (xy 123.827539 -259.642923) (xy 123.819414 -259.694218) (xy 123.803366 -259.743611)
			(xy 123.779788 -259.789885) (xy 123.749262 -259.831901) (xy 123.712539 -259.868624) (xy 123.670523 -259.89915)
			(xy 123.624249 -259.922728) (xy 123.574856 -259.938776) (xy 123.523561 -259.946901) (xy 123.471627 -259.946901)
			(xy 123.420332 -259.938776) (xy 123.370939 -259.922728) (xy 123.324665 -259.89915) (xy 123.282649 -259.868624)
			(xy 123.245926 -259.831901) (xy 123.2154 -259.789885) (xy 123.191822 -259.743611) (xy 123.175774 -259.694218)
			(xy 123.167649 -259.642923) (xy 122.887739 -259.642923) (xy 122.879614 -259.694218) (xy 122.863566 -259.743611)
			(xy 122.839988 -259.789885) (xy 122.809462 -259.831901) (xy 122.772739 -259.868624) (xy 122.730723 -259.89915)
			(xy 122.684449 -259.922728) (xy 122.635056 -259.938776) (xy 122.583761 -259.946901) (xy 122.531827 -259.946901)
			(xy 122.480532 -259.938776) (xy 122.431139 -259.922728) (xy 122.384865 -259.89915) (xy 122.342849 -259.868624)
			(xy 122.306126 -259.831901) (xy 122.2756 -259.789885) (xy 122.252022 -259.743611) (xy 122.235974 -259.694218)
			(xy 122.227849 -259.642923) (xy 121.947927 -259.642923) (xy 121.947927 -259.642966) (xy 121.939803 -259.694259)
			(xy 121.923755 -259.74365) (xy 121.900178 -259.789921) (xy 121.869653 -259.831935) (xy 121.832931 -259.868657)
			(xy 121.790916 -259.899181) (xy 121.744644 -259.922757) (xy 121.695253 -259.938805) (xy 121.64396 -259.946928)
			(xy 121.617994 -259.94741) (xy 121.590619 -259.946893) (xy 121.536618 -259.937868) (xy 121.484843 -259.920065)
			(xy 121.43671 -259.893972) (xy 121.414794 -259.87756) (xy 121.402906 -259.868971) (xy 121.375586 -259.858341)
			(xy 121.346373 -259.855888) (xy 121.317662 -259.861814) (xy 121.291807 -259.875631) (xy 121.270927 -259.896209)
			(xy 121.26341 -259.908802) (xy 121.250809 -259.930654) (xy 121.220067 -259.970641) (xy 121.183606 -260.005492)
			(xy 121.142273 -260.034399) (xy 121.097028 -260.05669) (xy 121.048921 -260.071847) (xy 120.999069 -260.079519)
			(xy 120.97385 -260.079998) (xy 120.947889 -260.079397) (xy 120.896607 -260.071268) (xy 120.847227 -260.055217)
			(xy 120.800967 -260.03164) (xy 120.758963 -260.001116) (xy 120.722251 -259.964399) (xy 120.691734 -259.922391)
			(xy 120.668164 -259.876126) (xy 120.652121 -259.826745) (xy 120.643999 -259.775461) (xy 120.370346 -259.775461)
			(xy 120.370346 -260.19506) (xy 120.108667 -260.456739) (xy 121.758203 -260.456739) (xy 121.758203 -260.404805)
			(xy 121.766328 -260.35351) (xy 121.782376 -260.304117) (xy 121.805954 -260.257843) (xy 121.83648 -260.215827)
			(xy 121.873203 -260.179104) (xy 121.915219 -260.148578) (xy 121.961493 -260.125) (xy 122.010886 -260.108952)
			(xy 122.062181 -260.100827) (xy 122.114115 -260.100827) (xy 122.16541 -260.108952) (xy 122.214803 -260.125)
			(xy 122.261077 -260.148578) (xy 122.303093 -260.179104) (xy 122.339816 -260.215827) (xy 122.370342 -260.257843)
			(xy 122.39392 -260.304117) (xy 122.409968 -260.35351) (xy 122.418093 -260.404805) (xy 122.418602 -260.430772)
			(xy 122.418093 -260.456739) (xy 122.698003 -260.456739) (xy 122.698003 -260.404805) (xy 122.706128 -260.35351)
			(xy 122.722176 -260.304117) (xy 122.745754 -260.257843) (xy 122.77628 -260.215827) (xy 122.813003 -260.179104)
			(xy 122.855019 -260.148578) (xy 122.901293 -260.125) (xy 122.950686 -260.108952) (xy 123.001981 -260.100827)
			(xy 123.053915 -260.100827) (xy 123.10521 -260.108952) (xy 123.154603 -260.125) (xy 123.200877 -260.148578)
			(xy 123.242893 -260.179104) (xy 123.279616 -260.215827) (xy 123.310142 -260.257843) (xy 123.33372 -260.304117)
			(xy 123.349768 -260.35351) (xy 123.357893 -260.404805) (xy 123.358402 -260.430772) (xy 123.357893 -260.456739)
			(xy 123.637803 -260.456739) (xy 123.637803 -260.404805) (xy 123.645928 -260.35351) (xy 123.661976 -260.304117)
			(xy 123.685554 -260.257843) (xy 123.71608 -260.215827) (xy 123.752803 -260.179104) (xy 123.794819 -260.148578)
			(xy 123.841093 -260.125) (xy 123.890486 -260.108952) (xy 123.941781 -260.100827) (xy 123.993715 -260.100827)
			(xy 124.04501 -260.108952) (xy 124.094403 -260.125) (xy 124.140677 -260.148578) (xy 124.182693 -260.179104)
			(xy 124.219416 -260.215827) (xy 124.249942 -260.257843) (xy 124.27352 -260.304117) (xy 124.289568 -260.35351)
			(xy 124.297693 -260.404805) (xy 124.298202 -260.430772) (xy 124.297693 -260.456739) (xy 124.577603 -260.456739)
			(xy 124.577603 -260.404805) (xy 124.585728 -260.35351) (xy 124.601776 -260.304117) (xy 124.625354 -260.257843)
			(xy 124.65588 -260.215827) (xy 124.692603 -260.179104) (xy 124.734619 -260.148578) (xy 124.780893 -260.125)
			(xy 124.830286 -260.108952) (xy 124.881581 -260.100827) (xy 124.933515 -260.100827) (xy 124.98481 -260.108952)
			(xy 125.034203 -260.125) (xy 125.080477 -260.148578) (xy 125.122493 -260.179104) (xy 125.159216 -260.215827)
			(xy 125.189742 -260.257843) (xy 125.21332 -260.304117) (xy 125.229368 -260.35351) (xy 125.237493 -260.404805)
			(xy 125.238002 -260.430772) (xy 125.237493 -260.456739) (xy 125.229368 -260.508034) (xy 125.21332 -260.557427)
			(xy 125.189742 -260.603701) (xy 125.159216 -260.645717) (xy 125.122493 -260.68244) (xy 125.080477 -260.712966)
			(xy 125.034203 -260.736544) (xy 124.98481 -260.752592) (xy 124.933515 -260.760717) (xy 124.881581 -260.760717)
			(xy 124.830286 -260.752592) (xy 124.780893 -260.736544) (xy 124.734619 -260.712966) (xy 124.692603 -260.68244)
			(xy 124.65588 -260.645717) (xy 124.625354 -260.603701) (xy 124.601776 -260.557427) (xy 124.585728 -260.508034)
			(xy 124.577603 -260.456739) (xy 124.297693 -260.456739) (xy 124.289568 -260.508034) (xy 124.27352 -260.557427)
			(xy 124.249942 -260.603701) (xy 124.219416 -260.645717) (xy 124.182693 -260.68244) (xy 124.140677 -260.712966)
			(xy 124.094403 -260.736544) (xy 124.04501 -260.752592) (xy 123.993715 -260.760717) (xy 123.941781 -260.760717)
			(xy 123.890486 -260.752592) (xy 123.841093 -260.736544) (xy 123.794819 -260.712966) (xy 123.752803 -260.68244)
			(xy 123.71608 -260.645717) (xy 123.685554 -260.603701) (xy 123.661976 -260.557427) (xy 123.645928 -260.508034)
			(xy 123.637803 -260.456739) (xy 123.357893 -260.456739) (xy 123.349768 -260.508034) (xy 123.33372 -260.557427)
			(xy 123.310142 -260.603701) (xy 123.279616 -260.645717) (xy 123.242893 -260.68244) (xy 123.200877 -260.712966)
			(xy 123.154603 -260.736544) (xy 123.10521 -260.752592) (xy 123.053915 -260.760717) (xy 123.001981 -260.760717)
			(xy 122.950686 -260.752592) (xy 122.901293 -260.736544) (xy 122.855019 -260.712966) (xy 122.813003 -260.68244)
			(xy 122.77628 -260.645717) (xy 122.745754 -260.603701) (xy 122.722176 -260.557427) (xy 122.706128 -260.508034)
			(xy 122.698003 -260.456739) (xy 122.418093 -260.456739) (xy 122.409968 -260.508034) (xy 122.39392 -260.557427)
			(xy 122.370342 -260.603701) (xy 122.339816 -260.645717) (xy 122.303093 -260.68244) (xy 122.261077 -260.712966)
			(xy 122.214803 -260.736544) (xy 122.16541 -260.752592) (xy 122.114115 -260.760717) (xy 122.062181 -260.760717)
			(xy 122.010886 -260.752592) (xy 121.961493 -260.736544) (xy 121.915219 -260.712966) (xy 121.873203 -260.68244)
			(xy 121.83648 -260.645717) (xy 121.805954 -260.603701) (xy 121.782376 -260.557427) (xy 121.766328 -260.508034)
			(xy 121.758203 -260.456739) (xy 120.108667 -260.456739) (xy 119.294597 -261.270809) (xy 121.288049 -261.270809)
			(xy 121.288049 -261.218875) (xy 121.296174 -261.16758) (xy 121.312222 -261.118187) (xy 121.3358 -261.071913)
			(xy 121.366326 -261.029897) (xy 121.403049 -260.993174) (xy 121.445065 -260.962648) (xy 121.491339 -260.93907)
			(xy 121.540732 -260.923022) (xy 121.592027 -260.914897) (xy 121.643961 -260.914897) (xy 121.695256 -260.923022)
			(xy 121.744649 -260.93907) (xy 121.790923 -260.962648) (xy 121.832939 -260.993174) (xy 121.869662 -261.029897)
			(xy 121.900188 -261.071913) (xy 121.923766 -261.118187) (xy 121.939814 -261.16758) (xy 121.947939 -261.218875)
			(xy 121.948448 -261.244842) (xy 121.947939 -261.270809) (xy 122.227849 -261.270809) (xy 122.227849 -261.218875)
			(xy 122.235974 -261.16758) (xy 122.252022 -261.118187) (xy 122.2756 -261.071913) (xy 122.306126 -261.029897)
			(xy 122.342849 -260.993174) (xy 122.384865 -260.962648) (xy 122.431139 -260.93907) (xy 122.480532 -260.923022)
			(xy 122.531827 -260.914897) (xy 122.583761 -260.914897) (xy 122.635056 -260.923022) (xy 122.684449 -260.93907)
			(xy 122.730723 -260.962648) (xy 122.772739 -260.993174) (xy 122.809462 -261.029897) (xy 122.839988 -261.071913)
			(xy 122.863566 -261.118187) (xy 122.879614 -261.16758) (xy 122.887739 -261.218875) (xy 122.888248 -261.244842)
			(xy 122.887739 -261.270809) (xy 123.167649 -261.270809) (xy 123.167649 -261.218875) (xy 123.175774 -261.16758)
			(xy 123.191822 -261.118187) (xy 123.2154 -261.071913) (xy 123.245926 -261.029897) (xy 123.282649 -260.993174)
			(xy 123.324665 -260.962648) (xy 123.370939 -260.93907) (xy 123.420332 -260.923022) (xy 123.471627 -260.914897)
			(xy 123.523561 -260.914897) (xy 123.574856 -260.923022) (xy 123.624249 -260.93907) (xy 123.670523 -260.962648)
			(xy 123.712539 -260.993174) (xy 123.749262 -261.029897) (xy 123.779788 -261.071913) (xy 123.803366 -261.118187)
			(xy 123.819414 -261.16758) (xy 123.827539 -261.218875) (xy 123.828048 -261.244842) (xy 123.827539 -261.270809)
			(xy 124.107449 -261.270809) (xy 124.107449 -261.218875) (xy 124.115574 -261.16758) (xy 124.131622 -261.118187)
			(xy 124.1552 -261.071913) (xy 124.185726 -261.029897) (xy 124.222449 -260.993174) (xy 124.264465 -260.962648)
			(xy 124.310739 -260.93907) (xy 124.360132 -260.923022) (xy 124.411427 -260.914897) (xy 124.463361 -260.914897)
			(xy 124.514656 -260.923022) (xy 124.564049 -260.93907) (xy 124.610323 -260.962648) (xy 124.652339 -260.993174)
			(xy 124.689062 -261.029897) (xy 124.719588 -261.071913) (xy 124.743166 -261.118187) (xy 124.759214 -261.16758)
			(xy 124.767339 -261.218875) (xy 124.767848 -261.244842) (xy 124.767339 -261.270809) (xy 125.047249 -261.270809)
			(xy 125.047249 -261.218875) (xy 125.055374 -261.16758) (xy 125.071422 -261.118187) (xy 125.095 -261.071913)
			(xy 125.125526 -261.029897) (xy 125.162249 -260.993174) (xy 125.204265 -260.962648) (xy 125.250539 -260.93907)
			(xy 125.299932 -260.923022) (xy 125.351227 -260.914897) (xy 125.403161 -260.914897) (xy 125.454456 -260.923022)
			(xy 125.503849 -260.93907) (xy 125.550123 -260.962648) (xy 125.592139 -260.993174) (xy 125.628862 -261.029897)
			(xy 125.659388 -261.071913) (xy 125.682966 -261.118187) (xy 125.699014 -261.16758) (xy 125.707139 -261.218875)
			(xy 125.707648 -261.244842) (xy 125.707139 -261.270809) (xy 125.699014 -261.322104) (xy 125.682966 -261.371497)
			(xy 125.659388 -261.417771) (xy 125.628862 -261.459787) (xy 125.592139 -261.49651) (xy 125.550123 -261.527036)
			(xy 125.503849 -261.550614) (xy 125.454456 -261.566662) (xy 125.403161 -261.574787) (xy 125.351227 -261.574787)
			(xy 125.299932 -261.566662) (xy 125.250539 -261.550614) (xy 125.204265 -261.527036) (xy 125.162249 -261.49651)
			(xy 125.125526 -261.459787) (xy 125.095 -261.417771) (xy 125.071422 -261.371497) (xy 125.055374 -261.322104)
			(xy 125.047249 -261.270809) (xy 124.767339 -261.270809) (xy 124.759214 -261.322104) (xy 124.743166 -261.371497)
			(xy 124.719588 -261.417771) (xy 124.689062 -261.459787) (xy 124.652339 -261.49651) (xy 124.610323 -261.527036)
			(xy 124.564049 -261.550614) (xy 124.514656 -261.566662) (xy 124.463361 -261.574787) (xy 124.411427 -261.574787)
			(xy 124.360132 -261.566662) (xy 124.310739 -261.550614) (xy 124.264465 -261.527036) (xy 124.222449 -261.49651)
			(xy 124.185726 -261.459787) (xy 124.1552 -261.417771) (xy 124.131622 -261.371497) (xy 124.115574 -261.322104)
			(xy 124.107449 -261.270809) (xy 123.827539 -261.270809) (xy 123.819414 -261.322104) (xy 123.803366 -261.371497)
			(xy 123.779788 -261.417771) (xy 123.749262 -261.459787) (xy 123.712539 -261.49651) (xy 123.670523 -261.527036)
			(xy 123.624249 -261.550614) (xy 123.574856 -261.566662) (xy 123.523561 -261.574787) (xy 123.471627 -261.574787)
			(xy 123.420332 -261.566662) (xy 123.370939 -261.550614) (xy 123.324665 -261.527036) (xy 123.282649 -261.49651)
			(xy 123.245926 -261.459787) (xy 123.2154 -261.417771) (xy 123.191822 -261.371497) (xy 123.175774 -261.322104)
			(xy 123.167649 -261.270809) (xy 122.887739 -261.270809) (xy 122.879614 -261.322104) (xy 122.863566 -261.371497)
			(xy 122.839988 -261.417771) (xy 122.809462 -261.459787) (xy 122.772739 -261.49651) (xy 122.730723 -261.527036)
			(xy 122.684449 -261.550614) (xy 122.635056 -261.566662) (xy 122.583761 -261.574787) (xy 122.531827 -261.574787)
			(xy 122.480532 -261.566662) (xy 122.431139 -261.550614) (xy 122.384865 -261.527036) (xy 122.342849 -261.49651)
			(xy 122.306126 -261.459787) (xy 122.2756 -261.417771) (xy 122.252022 -261.371497) (xy 122.235974 -261.322104)
			(xy 122.227849 -261.270809) (xy 121.947939 -261.270809) (xy 121.939814 -261.322104) (xy 121.923766 -261.371497)
			(xy 121.900188 -261.417771) (xy 121.869662 -261.459787) (xy 121.832939 -261.49651) (xy 121.790923 -261.527036)
			(xy 121.744649 -261.550614) (xy 121.695256 -261.566662) (xy 121.643961 -261.574787) (xy 121.592027 -261.574787)
			(xy 121.540732 -261.566662) (xy 121.491339 -261.550614) (xy 121.445065 -261.527036) (xy 121.403049 -261.49651)
			(xy 121.366326 -261.459787) (xy 121.3358 -261.417771) (xy 121.312222 -261.371497) (xy 121.296174 -261.322104)
			(xy 121.288049 -261.270809) (xy 119.294597 -261.270809) (xy 118.480781 -262.084625) (xy 121.758203 -262.084625)
			(xy 121.758203 -262.032691) (xy 121.766328 -261.981396) (xy 121.782376 -261.932003) (xy 121.805954 -261.885729)
			(xy 121.83648 -261.843713) (xy 121.873203 -261.80699) (xy 121.915219 -261.776464) (xy 121.961493 -261.752886)
			(xy 122.010886 -261.736838) (xy 122.062181 -261.728713) (xy 122.114115 -261.728713) (xy 122.16541 -261.736838)
			(xy 122.214803 -261.752886) (xy 122.261077 -261.776464) (xy 122.303093 -261.80699) (xy 122.339816 -261.843713)
			(xy 122.370342 -261.885729) (xy 122.39392 -261.932003) (xy 122.409968 -261.981396) (xy 122.418093 -262.032691)
			(xy 122.418602 -262.058658) (xy 122.418093 -262.084625) (xy 122.697749 -262.084625) (xy 122.697749 -262.032691)
			(xy 122.705874 -261.981396) (xy 122.721922 -261.932003) (xy 122.7455 -261.885729) (xy 122.776026 -261.843713)
			(xy 122.812749 -261.80699) (xy 122.854765 -261.776464) (xy 122.901039 -261.752886) (xy 122.950432 -261.736838)
			(xy 123.001727 -261.728713) (xy 123.053661 -261.728713) (xy 123.104956 -261.736838) (xy 123.154349 -261.752886)
			(xy 123.200623 -261.776464) (xy 123.242639 -261.80699) (xy 123.279362 -261.843713) (xy 123.309888 -261.885729)
			(xy 123.333466 -261.932003) (xy 123.349514 -261.981396) (xy 123.357639 -262.032691) (xy 123.358148 -262.058658)
			(xy 123.357639 -262.084625) (xy 123.637803 -262.084625) (xy 123.637803 -262.032691) (xy 123.645928 -261.981396)
			(xy 123.661976 -261.932003) (xy 123.685554 -261.885729) (xy 123.71608 -261.843713) (xy 123.752803 -261.80699)
			(xy 123.794819 -261.776464) (xy 123.841093 -261.752886) (xy 123.890486 -261.736838) (xy 123.941781 -261.728713)
			(xy 123.993715 -261.728713) (xy 124.04501 -261.736838) (xy 124.094403 -261.752886) (xy 124.140677 -261.776464)
			(xy 124.182693 -261.80699) (xy 124.219416 -261.843713) (xy 124.249942 -261.885729) (xy 124.27352 -261.932003)
			(xy 124.289568 -261.981396) (xy 124.297693 -262.032691) (xy 124.298202 -262.058658) (xy 124.297693 -262.084625)
			(xy 124.577603 -262.084625) (xy 124.577603 -262.032691) (xy 124.585728 -261.981396) (xy 124.601776 -261.932003)
			(xy 124.625354 -261.885729) (xy 124.65588 -261.843713) (xy 124.692603 -261.80699) (xy 124.734619 -261.776464)
			(xy 124.780893 -261.752886) (xy 124.830286 -261.736838) (xy 124.881581 -261.728713) (xy 124.933515 -261.728713)
			(xy 124.98481 -261.736838) (xy 125.034203 -261.752886) (xy 125.080477 -261.776464) (xy 125.122493 -261.80699)
			(xy 125.159216 -261.843713) (xy 125.189742 -261.885729) (xy 125.21332 -261.932003) (xy 125.229368 -261.981396)
			(xy 125.237493 -262.032691) (xy 125.238002 -262.058658) (xy 125.237493 -262.084625) (xy 125.517149 -262.084625)
			(xy 125.517149 -262.032691) (xy 125.525274 -261.981396) (xy 125.541322 -261.932003) (xy 125.5649 -261.885729)
			(xy 125.595426 -261.843713) (xy 125.632149 -261.80699) (xy 125.674165 -261.776464) (xy 125.720439 -261.752886)
			(xy 125.769832 -261.736838) (xy 125.821127 -261.728713) (xy 125.873061 -261.728713) (xy 125.924356 -261.736838)
			(xy 125.973749 -261.752886) (xy 126.020023 -261.776464) (xy 126.062039 -261.80699) (xy 126.098762 -261.843713)
			(xy 126.129288 -261.885729) (xy 126.152866 -261.932003) (xy 126.168914 -261.981396) (xy 126.177039 -262.032691)
			(xy 126.177548 -262.058658) (xy 126.177039 -262.084625) (xy 126.168914 -262.13592) (xy 126.152866 -262.185313)
			(xy 126.129288 -262.231587) (xy 126.098762 -262.273603) (xy 126.062039 -262.310326) (xy 126.020023 -262.340852)
			(xy 125.973749 -262.36443) (xy 125.924356 -262.380478) (xy 125.873061 -262.388603) (xy 125.821127 -262.388603)
			(xy 125.769832 -262.380478) (xy 125.720439 -262.36443) (xy 125.674165 -262.340852) (xy 125.632149 -262.310326)
			(xy 125.595426 -262.273603) (xy 125.5649 -262.231587) (xy 125.541322 -262.185313) (xy 125.525274 -262.13592)
			(xy 125.517149 -262.084625) (xy 125.237493 -262.084625) (xy 125.229368 -262.13592) (xy 125.21332 -262.185313)
			(xy 125.189742 -262.231587) (xy 125.159216 -262.273603) (xy 125.122493 -262.310326) (xy 125.080477 -262.340852)
			(xy 125.034203 -262.36443) (xy 124.98481 -262.380478) (xy 124.933515 -262.388603) (xy 124.881581 -262.388603)
			(xy 124.830286 -262.380478) (xy 124.780893 -262.36443) (xy 124.734619 -262.340852) (xy 124.692603 -262.310326)
			(xy 124.65588 -262.273603) (xy 124.625354 -262.231587) (xy 124.601776 -262.185313) (xy 124.585728 -262.13592)
			(xy 124.577603 -262.084625) (xy 124.297693 -262.084625) (xy 124.289568 -262.13592) (xy 124.27352 -262.185313)
			(xy 124.249942 -262.231587) (xy 124.219416 -262.273603) (xy 124.182693 -262.310326) (xy 124.140677 -262.340852)
			(xy 124.094403 -262.36443) (xy 124.04501 -262.380478) (xy 123.993715 -262.388603) (xy 123.941781 -262.388603)
			(xy 123.890486 -262.380478) (xy 123.841093 -262.36443) (xy 123.794819 -262.340852) (xy 123.752803 -262.310326)
			(xy 123.71608 -262.273603) (xy 123.685554 -262.231587) (xy 123.661976 -262.185313) (xy 123.645928 -262.13592)
			(xy 123.637803 -262.084625) (xy 123.357639 -262.084625) (xy 123.349514 -262.13592) (xy 123.333466 -262.185313)
			(xy 123.309888 -262.231587) (xy 123.279362 -262.273603) (xy 123.242639 -262.310326) (xy 123.200623 -262.340852)
			(xy 123.154349 -262.36443) (xy 123.104956 -262.380478) (xy 123.053661 -262.388603) (xy 123.001727 -262.388603)
			(xy 122.950432 -262.380478) (xy 122.901039 -262.36443) (xy 122.854765 -262.340852) (xy 122.812749 -262.310326)
			(xy 122.776026 -262.273603) (xy 122.7455 -262.231587) (xy 122.721922 -262.185313) (xy 122.705874 -262.13592)
			(xy 122.697749 -262.084625) (xy 122.418093 -262.084625) (xy 122.409968 -262.13592) (xy 122.39392 -262.185313)
			(xy 122.370342 -262.231587) (xy 122.339816 -262.273603) (xy 122.303093 -262.310326) (xy 122.261077 -262.340852)
			(xy 122.214803 -262.36443) (xy 122.16541 -262.380478) (xy 122.114115 -262.388603) (xy 122.062181 -262.388603)
			(xy 122.010886 -262.380478) (xy 121.961493 -262.36443) (xy 121.915219 -262.340852) (xy 121.873203 -262.310326)
			(xy 121.83648 -262.273603) (xy 121.805954 -262.231587) (xy 121.782376 -262.185313) (xy 121.766328 -262.13592)
			(xy 121.758203 -262.084625) (xy 118.480781 -262.084625) (xy 117.650768 -262.914638) (xy 117.641032 -262.925028)
			(xy 117.627224 -262.949915) (xy 117.620826 -262.977648) (xy 117.622335 -263.006069) (xy 117.631634 -263.032968)
			(xy 117.648 -263.056254) (xy 117.670159 -263.074115) (xy 117.696389 -263.085162) (xy 117.710458 -263.087358)
			(xy 117.736857 -263.091055) (xy 117.788066 -263.105854) (xy 117.836234 -263.128683) (xy 117.880112 -263.15895)
			(xy 117.91856 -263.19587) (xy 117.950581 -263.238485) (xy 117.975343 -263.285688) (xy 117.992205 -263.336255)
			(xy 118.000728 -263.388873) (xy 118.000793 -263.391963) (xy 118.382543 -263.391963) (xy 118.382543 -263.340029)
			(xy 118.390668 -263.288734) (xy 118.406716 -263.239341) (xy 118.430294 -263.193067) (xy 118.46082 -263.151051)
			(xy 118.497543 -263.114328) (xy 118.539559 -263.083802) (xy 118.585833 -263.060224) (xy 118.635226 -263.044176)
			(xy 118.686521 -263.036051) (xy 118.738455 -263.036051) (xy 118.78975 -263.044176) (xy 118.839143 -263.060224)
			(xy 118.885417 -263.083802) (xy 118.927433 -263.114328) (xy 118.964156 -263.151051) (xy 118.994682 -263.193067)
			(xy 119.01826 -263.239341) (xy 119.034308 -263.288734) (xy 119.036658 -263.30357) (xy 119.375633 -263.30357)
			(xy 119.375633 -263.25163) (xy 119.383759 -263.200328) (xy 119.39981 -263.15093) (xy 119.423392 -263.104651)
			(xy 119.453923 -263.062631) (xy 119.490653 -263.025905) (xy 119.532675 -262.995377) (xy 119.578956 -262.971799)
			(xy 119.628356 -262.955752) (xy 119.679658 -262.947631) (xy 119.705628 -262.94715) (xy 119.732142 -262.947677)
			(xy 119.784486 -262.956165) (xy 119.834799 -262.972918) (xy 119.858536 -262.984742) (xy 119.872252 -262.991257)
			(xy 119.902084 -262.996822) (xy 119.932234 -262.993381) (xy 119.960044 -262.981237) (xy 119.983062 -262.961461)
			(xy 119.991632 -262.948928) (xy 120.0069 -262.925775) (xy 120.043972 -262.884529) (xy 120.087412 -262.850053)
			(xy 120.135998 -262.823315) (xy 120.188368 -262.805066) (xy 120.243049 -262.795818) (xy 120.270778 -262.795258)
			(xy 120.296749 -262.795715) (xy 120.348053 -262.803838) (xy 120.397454 -262.819886) (xy 120.443737 -262.843466)
			(xy 120.48576 -262.873995) (xy 120.510208 -262.898441) (xy 121.288049 -262.898441) (xy 121.288049 -262.846507)
			(xy 121.296174 -262.795212) (xy 121.312222 -262.745819) (xy 121.3358 -262.699545) (xy 121.366326 -262.657529)
			(xy 121.403049 -262.620806) (xy 121.445065 -262.59028) (xy 121.491339 -262.566702) (xy 121.540732 -262.550654)
			(xy 121.592027 -262.542529) (xy 121.643961 -262.542529) (xy 121.695256 -262.550654) (xy 121.744649 -262.566702)
			(xy 121.790923 -262.59028) (xy 121.832939 -262.620806) (xy 121.869662 -262.657529) (xy 121.900188 -262.699545)
			(xy 121.923766 -262.745819) (xy 121.939814 -262.795212) (xy 121.947939 -262.846507) (xy 121.948448 -262.872474)
			(xy 121.947939 -262.898441) (xy 122.228103 -262.898441) (xy 122.228103 -262.846507) (xy 122.236228 -262.795212)
			(xy 122.252276 -262.745819) (xy 122.275854 -262.699545) (xy 122.30638 -262.657529) (xy 122.343103 -262.620806)
			(xy 122.385119 -262.59028) (xy 122.431393 -262.566702) (xy 122.480786 -262.550654) (xy 122.532081 -262.542529)
			(xy 122.584015 -262.542529) (xy 122.63531 -262.550654) (xy 122.684703 -262.566702) (xy 122.730977 -262.59028)
			(xy 122.772993 -262.620806) (xy 122.809716 -262.657529) (xy 122.840242 -262.699545) (xy 122.86382 -262.745819)
			(xy 122.879868 -262.795212) (xy 122.887993 -262.846507) (xy 122.888502 -262.872474) (xy 122.887993 -262.898441)
			(xy 123.167649 -262.898441) (xy 123.167649 -262.846507) (xy 123.175774 -262.795212) (xy 123.191822 -262.745819)
			(xy 123.2154 -262.699545) (xy 123.245926 -262.657529) (xy 123.282649 -262.620806) (xy 123.324665 -262.59028)
			(xy 123.370939 -262.566702) (xy 123.420332 -262.550654) (xy 123.471627 -262.542529) (xy 123.523561 -262.542529)
			(xy 123.574856 -262.550654) (xy 123.624249 -262.566702) (xy 123.670523 -262.59028) (xy 123.712539 -262.620806)
			(xy 123.749262 -262.657529) (xy 123.779788 -262.699545) (xy 123.803366 -262.745819) (xy 123.819414 -262.795212)
			(xy 123.827539 -262.846507) (xy 123.828048 -262.872474) (xy 123.827539 -262.898441) (xy 124.107449 -262.898441)
			(xy 124.107449 -262.846507) (xy 124.115574 -262.795212) (xy 124.131622 -262.745819) (xy 124.1552 -262.699545)
			(xy 124.185726 -262.657529) (xy 124.222449 -262.620806) (xy 124.264465 -262.59028) (xy 124.310739 -262.566702)
			(xy 124.360132 -262.550654) (xy 124.411427 -262.542529) (xy 124.463361 -262.542529) (xy 124.514656 -262.550654)
			(xy 124.564049 -262.566702) (xy 124.610323 -262.59028) (xy 124.652339 -262.620806) (xy 124.689062 -262.657529)
			(xy 124.719588 -262.699545) (xy 124.743166 -262.745819) (xy 124.759214 -262.795212) (xy 124.767339 -262.846507)
			(xy 124.767848 -262.872474) (xy 124.767339 -262.898441) (xy 125.047503 -262.898441) (xy 125.047503 -262.846507)
			(xy 125.055628 -262.795212) (xy 125.071676 -262.745819) (xy 125.095254 -262.699545) (xy 125.12578 -262.657529)
			(xy 125.162503 -262.620806) (xy 125.204519 -262.59028) (xy 125.250793 -262.566702) (xy 125.300186 -262.550654)
			(xy 125.351481 -262.542529) (xy 125.403415 -262.542529) (xy 125.45471 -262.550654) (xy 125.504103 -262.566702)
			(xy 125.550377 -262.59028) (xy 125.592393 -262.620806) (xy 125.629116 -262.657529) (xy 125.659642 -262.699545)
			(xy 125.68322 -262.745819) (xy 125.699268 -262.795212) (xy 125.707393 -262.846507) (xy 125.707902 -262.872474)
			(xy 125.707393 -262.898441) (xy 125.987049 -262.898441) (xy 125.987049 -262.846507) (xy 125.995174 -262.795212)
			(xy 126.011222 -262.745819) (xy 126.0348 -262.699545) (xy 126.065326 -262.657529) (xy 126.102049 -262.620806)
			(xy 126.144065 -262.59028) (xy 126.190339 -262.566702) (xy 126.239732 -262.550654) (xy 126.291027 -262.542529)
			(xy 126.342961 -262.542529) (xy 126.394256 -262.550654) (xy 126.443649 -262.566702) (xy 126.489923 -262.59028)
			(xy 126.531939 -262.620806) (xy 126.568662 -262.657529) (xy 126.599188 -262.699545) (xy 126.622766 -262.745819)
			(xy 126.638814 -262.795212) (xy 126.646939 -262.846507) (xy 126.647448 -262.872474) (xy 126.646939 -262.898441)
			(xy 126.638814 -262.949736) (xy 126.622766 -262.999129) (xy 126.599188 -263.045403) (xy 126.568662 -263.087419)
			(xy 126.531939 -263.124142) (xy 126.489923 -263.154668) (xy 126.443649 -263.178246) (xy 126.394256 -263.194294)
			(xy 126.342961 -263.202419) (xy 126.291027 -263.202419) (xy 126.239732 -263.194294) (xy 126.190339 -263.178246)
			(xy 126.144065 -263.154668) (xy 126.102049 -263.124142) (xy 126.065326 -263.087419) (xy 126.0348 -263.045403)
			(xy 126.011222 -262.999129) (xy 125.995174 -262.949736) (xy 125.987049 -262.898441) (xy 125.707393 -262.898441)
			(xy 125.699268 -262.949736) (xy 125.68322 -262.999129) (xy 125.659642 -263.045403) (xy 125.629116 -263.087419)
			(xy 125.592393 -263.124142) (xy 125.550377 -263.154668) (xy 125.504103 -263.178246) (xy 125.45471 -263.194294)
			(xy 125.403415 -263.202419) (xy 125.351481 -263.202419) (xy 125.300186 -263.194294) (xy 125.250793 -263.178246)
			(xy 125.204519 -263.154668) (xy 125.162503 -263.124142) (xy 125.12578 -263.087419) (xy 125.095254 -263.045403)
			(xy 125.071676 -262.999129) (xy 125.055628 -262.949736) (xy 125.047503 -262.898441) (xy 124.767339 -262.898441)
			(xy 124.759214 -262.949736) (xy 124.743166 -262.999129) (xy 124.719588 -263.045403) (xy 124.689062 -263.087419)
			(xy 124.652339 -263.124142) (xy 124.610323 -263.154668) (xy 124.564049 -263.178246) (xy 124.514656 -263.194294)
			(xy 124.463361 -263.202419) (xy 124.411427 -263.202419) (xy 124.360132 -263.194294) (xy 124.310739 -263.178246)
			(xy 124.264465 -263.154668) (xy 124.222449 -263.124142) (xy 124.185726 -263.087419) (xy 124.1552 -263.045403)
			(xy 124.131622 -262.999129) (xy 124.115574 -262.949736) (xy 124.107449 -262.898441) (xy 123.827539 -262.898441)
			(xy 123.819414 -262.949736) (xy 123.803366 -262.999129) (xy 123.779788 -263.045403) (xy 123.749262 -263.087419)
			(xy 123.712539 -263.124142) (xy 123.670523 -263.154668) (xy 123.624249 -263.178246) (xy 123.574856 -263.194294)
			(xy 123.523561 -263.202419) (xy 123.471627 -263.202419) (xy 123.420332 -263.194294) (xy 123.370939 -263.178246)
			(xy 123.324665 -263.154668) (xy 123.282649 -263.124142) (xy 123.245926 -263.087419) (xy 123.2154 -263.045403)
			(xy 123.191822 -262.999129) (xy 123.175774 -262.949736) (xy 123.167649 -262.898441) (xy 122.887993 -262.898441)
			(xy 122.879868 -262.949736) (xy 122.86382 -262.999129) (xy 122.840242 -263.045403) (xy 122.809716 -263.087419)
			(xy 122.772993 -263.124142) (xy 122.730977 -263.154668) (xy 122.684703 -263.178246) (xy 122.63531 -263.194294)
			(xy 122.584015 -263.202419) (xy 122.532081 -263.202419) (xy 122.480786 -263.194294) (xy 122.431393 -263.178246)
			(xy 122.385119 -263.154668) (xy 122.343103 -263.124142) (xy 122.30638 -263.087419) (xy 122.275854 -263.045403)
			(xy 122.252276 -262.999129) (xy 122.236228 -262.949736) (xy 122.228103 -262.898441) (xy 121.947939 -262.898441)
			(xy 121.939814 -262.949736) (xy 121.923766 -262.999129) (xy 121.900188 -263.045403) (xy 121.869662 -263.087419)
			(xy 121.832939 -263.124142) (xy 121.790923 -263.154668) (xy 121.744649 -263.178246) (xy 121.695256 -263.194294)
			(xy 121.643961 -263.202419) (xy 121.592027 -263.202419) (xy 121.540732 -263.194294) (xy 121.491339 -263.178246)
			(xy 121.445065 -263.154668) (xy 121.403049 -263.124142) (xy 121.366326 -263.087419) (xy 121.3358 -263.045403)
			(xy 121.312222 -262.999129) (xy 121.296174 -262.949736) (xy 121.288049 -262.898441) (xy 120.510208 -262.898441)
			(xy 120.522491 -262.910723) (xy 120.553023 -262.952745) (xy 120.576605 -262.999025) (xy 120.592657 -263.048426)
			(xy 120.600783 -263.099729) (xy 120.600783 -263.151671) (xy 120.592657 -263.202974) (xy 120.576605 -263.252375)
			(xy 120.553023 -263.298655) (xy 120.522491 -263.340677) (xy 120.48576 -263.377405) (xy 120.443737 -263.407934)
			(xy 120.397454 -263.431514) (xy 120.348053 -263.447562) (xy 120.296749 -263.455685) (xy 120.270778 -263.456166)
			(xy 120.244264 -263.455646) (xy 120.191919 -263.447157) (xy 120.141607 -263.430401) (xy 120.11787 -263.418574)
			(xy 120.104153 -263.41206) (xy 120.074322 -263.406492) (xy 120.044171 -263.409932) (xy 120.01636 -263.422076)
			(xy 119.993343 -263.441854) (xy 119.984774 -263.454388) (xy 119.969475 -263.47752) (xy 119.932412 -263.51877)
			(xy 119.88898 -263.553251) (xy 119.840399 -263.579994) (xy 119.788034 -263.598247) (xy 119.733356 -263.607497)
			(xy 119.705628 -263.608058) (xy 119.679658 -263.607569) (xy 119.628356 -263.599448) (xy 119.578956 -263.583401)
			(xy 119.532675 -263.559823) (xy 119.490653 -263.529295) (xy 119.453923 -263.492569) (xy 119.423392 -263.450549)
			(xy 119.39981 -263.40427) (xy 119.383759 -263.354872) (xy 119.375633 -263.30357) (xy 119.036658 -263.30357)
			(xy 119.042433 -263.340029) (xy 119.042942 -263.365996) (xy 119.042433 -263.391963) (xy 119.034308 -263.443258)
			(xy 119.01826 -263.492651) (xy 118.994682 -263.538925) (xy 118.964156 -263.580941) (xy 118.927433 -263.617664)
			(xy 118.885417 -263.64819) (xy 118.839143 -263.671768) (xy 118.78975 -263.687816) (xy 118.738455 -263.695941)
			(xy 118.686521 -263.695941) (xy 118.635226 -263.687816) (xy 118.585833 -263.671768) (xy 118.539559 -263.64819)
			(xy 118.497543 -263.617664) (xy 118.46082 -263.580941) (xy 118.430294 -263.538925) (xy 118.406716 -263.492651)
			(xy 118.390668 -263.443258) (xy 118.382543 -263.391963) (xy 118.000793 -263.391963) (xy 118.001288 -263.415526)
			(xy 118.000777 -263.441493) (xy 117.992649 -263.492787) (xy 117.976599 -263.542178) (xy 117.95302 -263.588451)
			(xy 117.922494 -263.630466) (xy 117.885772 -263.667189) (xy 117.843758 -263.697716) (xy 117.814725 -263.712511)
			(xy 121.758203 -263.712511) (xy 121.758203 -263.660577) (xy 121.766328 -263.609282) (xy 121.782376 -263.559889)
			(xy 121.805954 -263.513615) (xy 121.83648 -263.471599) (xy 121.873203 -263.434876) (xy 121.915219 -263.40435)
			(xy 121.961493 -263.380772) (xy 122.010886 -263.364724) (xy 122.062181 -263.356599) (xy 122.114115 -263.356599)
			(xy 122.16541 -263.364724) (xy 122.214803 -263.380772) (xy 122.261077 -263.40435) (xy 122.303093 -263.434876)
			(xy 122.339816 -263.471599) (xy 122.370342 -263.513615) (xy 122.39392 -263.559889) (xy 122.409968 -263.609282)
			(xy 122.418093 -263.660577) (xy 122.418602 -263.686544) (xy 122.418093 -263.712511) (xy 122.697749 -263.712511)
			(xy 122.697749 -263.660577) (xy 122.705874 -263.609282) (xy 122.721922 -263.559889) (xy 122.7455 -263.513615)
			(xy 122.776026 -263.471599) (xy 122.812749 -263.434876) (xy 122.854765 -263.40435) (xy 122.901039 -263.380772)
			(xy 122.950432 -263.364724) (xy 123.001727 -263.356599) (xy 123.053661 -263.356599) (xy 123.104956 -263.364724)
			(xy 123.154349 -263.380772) (xy 123.200623 -263.40435) (xy 123.242639 -263.434876) (xy 123.279362 -263.471599)
			(xy 123.309888 -263.513615) (xy 123.333466 -263.559889) (xy 123.349514 -263.609282) (xy 123.357639 -263.660577)
			(xy 123.358148 -263.686544) (xy 123.357639 -263.712511) (xy 123.637803 -263.712511) (xy 123.637803 -263.660577)
			(xy 123.645928 -263.609282) (xy 123.661976 -263.559889) (xy 123.685554 -263.513615) (xy 123.71608 -263.471599)
			(xy 123.752803 -263.434876) (xy 123.794819 -263.40435) (xy 123.841093 -263.380772) (xy 123.890486 -263.364724)
			(xy 123.941781 -263.356599) (xy 123.993715 -263.356599) (xy 124.04501 -263.364724) (xy 124.094403 -263.380772)
			(xy 124.140677 -263.40435) (xy 124.182693 -263.434876) (xy 124.219416 -263.471599) (xy 124.249942 -263.513615)
			(xy 124.27352 -263.559889) (xy 124.289568 -263.609282) (xy 124.297693 -263.660577) (xy 124.298202 -263.686544)
			(xy 124.297693 -263.712511) (xy 124.577603 -263.712511) (xy 124.577603 -263.660577) (xy 124.585728 -263.609282)
			(xy 124.601776 -263.559889) (xy 124.625354 -263.513615) (xy 124.65588 -263.471599) (xy 124.692603 -263.434876)
			(xy 124.734619 -263.40435) (xy 124.780893 -263.380772) (xy 124.830286 -263.364724) (xy 124.881581 -263.356599)
			(xy 124.933515 -263.356599) (xy 124.98481 -263.364724) (xy 125.034203 -263.380772) (xy 125.080477 -263.40435)
			(xy 125.122493 -263.434876) (xy 125.159216 -263.471599) (xy 125.189742 -263.513615) (xy 125.21332 -263.559889)
			(xy 125.229368 -263.609282) (xy 125.237493 -263.660577) (xy 125.238002 -263.686544) (xy 125.237493 -263.712511)
			(xy 125.517403 -263.712511) (xy 125.517403 -263.660577) (xy 125.525528 -263.609282) (xy 125.541576 -263.559889)
			(xy 125.565154 -263.513615) (xy 125.59568 -263.471599) (xy 125.632403 -263.434876) (xy 125.674419 -263.40435)
			(xy 125.720693 -263.380772) (xy 125.770086 -263.364724) (xy 125.821381 -263.356599) (xy 125.873315 -263.356599)
			(xy 125.92461 -263.364724) (xy 125.974003 -263.380772) (xy 126.020277 -263.40435) (xy 126.062293 -263.434876)
			(xy 126.099016 -263.471599) (xy 126.129542 -263.513615) (xy 126.15312 -263.559889) (xy 126.169168 -263.609282)
			(xy 126.177293 -263.660577) (xy 126.177802 -263.686544) (xy 126.177293 -263.712511) (xy 126.169168 -263.763806)
			(xy 126.15312 -263.813199) (xy 126.129542 -263.859473) (xy 126.099016 -263.901489) (xy 126.062293 -263.938212)
			(xy 126.020277 -263.968738) (xy 125.974003 -263.992316) (xy 125.92461 -264.008364) (xy 125.873315 -264.016489)
			(xy 125.821381 -264.016489) (xy 125.770086 -264.008364) (xy 125.720693 -263.992316) (xy 125.674419 -263.968738)
			(xy 125.632403 -263.938212) (xy 125.59568 -263.901489) (xy 125.565154 -263.859473) (xy 125.541576 -263.813199)
			(xy 125.525528 -263.763806) (xy 125.517403 -263.712511) (xy 125.237493 -263.712511) (xy 125.229368 -263.763806)
			(xy 125.21332 -263.813199) (xy 125.189742 -263.859473) (xy 125.159216 -263.901489) (xy 125.122493 -263.938212)
			(xy 125.080477 -263.968738) (xy 125.034203 -263.992316) (xy 124.98481 -264.008364) (xy 124.933515 -264.016489)
			(xy 124.881581 -264.016489) (xy 124.830286 -264.008364) (xy 124.780893 -263.992316) (xy 124.734619 -263.968738)
			(xy 124.692603 -263.938212) (xy 124.65588 -263.901489) (xy 124.625354 -263.859473) (xy 124.601776 -263.813199)
			(xy 124.585728 -263.763806) (xy 124.577603 -263.712511) (xy 124.297693 -263.712511) (xy 124.289568 -263.763806)
			(xy 124.27352 -263.813199) (xy 124.249942 -263.859473) (xy 124.219416 -263.901489) (xy 124.182693 -263.938212)
			(xy 124.140677 -263.968738) (xy 124.094403 -263.992316) (xy 124.04501 -264.008364) (xy 123.993715 -264.016489)
			(xy 123.941781 -264.016489) (xy 123.890486 -264.008364) (xy 123.841093 -263.992316) (xy 123.794819 -263.968738)
			(xy 123.752803 -263.938212) (xy 123.71608 -263.901489) (xy 123.685554 -263.859473) (xy 123.661976 -263.813199)
			(xy 123.645928 -263.763806) (xy 123.637803 -263.712511) (xy 123.357639 -263.712511) (xy 123.349514 -263.763806)
			(xy 123.333466 -263.813199) (xy 123.309888 -263.859473) (xy 123.279362 -263.901489) (xy 123.242639 -263.938212)
			(xy 123.200623 -263.968738) (xy 123.154349 -263.992316) (xy 123.104956 -264.008364) (xy 123.053661 -264.016489)
			(xy 123.001727 -264.016489) (xy 122.950432 -264.008364) (xy 122.901039 -263.992316) (xy 122.854765 -263.968738)
			(xy 122.812749 -263.938212) (xy 122.776026 -263.901489) (xy 122.7455 -263.859473) (xy 122.721922 -263.813199)
			(xy 122.705874 -263.763806) (xy 122.697749 -263.712511) (xy 122.418093 -263.712511) (xy 122.409968 -263.763806)
			(xy 122.39392 -263.813199) (xy 122.370342 -263.859473) (xy 122.339816 -263.901489) (xy 122.303093 -263.938212)
			(xy 122.261077 -263.968738) (xy 122.214803 -263.992316) (xy 122.16541 -264.008364) (xy 122.114115 -264.016489)
			(xy 122.062181 -264.016489) (xy 122.010886 -264.008364) (xy 121.961493 -263.992316) (xy 121.915219 -263.968738)
			(xy 121.873203 -263.938212) (xy 121.83648 -263.901489) (xy 121.805954 -263.859473) (xy 121.782376 -263.813199)
			(xy 121.766328 -263.763806) (xy 121.758203 -263.712511) (xy 117.814725 -263.712511) (xy 117.797485 -263.721296)
			(xy 117.748095 -263.737348) (xy 117.696801 -263.745476) (xy 117.670834 -263.74598) (xy 117.649149 -263.745656)
			(xy 117.606148 -263.740022) (xy 117.564251 -263.72882) (xy 117.544088 -263.720834) (xy 117.530724 -263.715816)
			(xy 117.502371 -263.712614) (xy 117.474239 -263.717381) (xy 117.448524 -263.729745) (xy 117.427233 -263.748741)
			(xy 117.412028 -263.772885) (xy 117.404096 -263.800294) (xy 117.403626 -263.81456) (xy 117.403626 -264.526327)
			(xy 117.528849 -264.526327) (xy 117.528849 -264.474393) (xy 117.536974 -264.423098) (xy 117.553022 -264.373705)
			(xy 117.5766 -264.327431) (xy 117.607126 -264.285415) (xy 117.643849 -264.248692) (xy 117.685865 -264.218166)
			(xy 117.732139 -264.194588) (xy 117.781532 -264.17854) (xy 117.832827 -264.170415) (xy 117.884761 -264.170415)
			(xy 117.936056 -264.17854) (xy 117.985449 -264.194588) (xy 118.031723 -264.218166) (xy 118.073739 -264.248692)
			(xy 118.110462 -264.285415) (xy 118.140988 -264.327431) (xy 118.164566 -264.373705) (xy 118.180614 -264.423098)
			(xy 118.188739 -264.474393) (xy 118.189248 -264.50036) (xy 118.188739 -264.526327) (xy 118.468649 -264.526327)
			(xy 118.468649 -264.474393) (xy 118.476774 -264.423098) (xy 118.492822 -264.373705) (xy 118.5164 -264.327431)
			(xy 118.546926 -264.285415) (xy 118.583649 -264.248692) (xy 118.625665 -264.218166) (xy 118.671939 -264.194588)
			(xy 118.721332 -264.17854) (xy 118.772627 -264.170415) (xy 118.824561 -264.170415) (xy 118.875856 -264.17854)
			(xy 118.925249 -264.194588) (xy 118.971523 -264.218166) (xy 119.013539 -264.248692) (xy 119.050262 -264.285415)
			(xy 119.080788 -264.327431) (xy 119.104366 -264.373705) (xy 119.120414 -264.423098) (xy 119.128539 -264.474393)
			(xy 119.129048 -264.50036) (xy 119.128539 -264.526327) (xy 119.408449 -264.526327) (xy 119.408449 -264.474393)
			(xy 119.416574 -264.423098) (xy 119.432622 -264.373705) (xy 119.4562 -264.327431) (xy 119.486726 -264.285415)
			(xy 119.523449 -264.248692) (xy 119.565465 -264.218166) (xy 119.611739 -264.194588) (xy 119.661132 -264.17854)
			(xy 119.712427 -264.170415) (xy 119.764361 -264.170415) (xy 119.815656 -264.17854) (xy 119.865049 -264.194588)
			(xy 119.911323 -264.218166) (xy 119.953339 -264.248692) (xy 119.990062 -264.285415) (xy 120.020588 -264.327431)
			(xy 120.044166 -264.373705) (xy 120.060214 -264.423098) (xy 120.068339 -264.474393) (xy 120.068848 -264.50036)
			(xy 120.068339 -264.526327) (xy 120.348249 -264.526327) (xy 120.348249 -264.474393) (xy 120.356374 -264.423098)
			(xy 120.372422 -264.373705) (xy 120.396 -264.327431) (xy 120.426526 -264.285415) (xy 120.463249 -264.248692)
			(xy 120.505265 -264.218166) (xy 120.551539 -264.194588) (xy 120.600932 -264.17854) (xy 120.652227 -264.170415)
			(xy 120.704161 -264.170415) (xy 120.755456 -264.17854) (xy 120.804849 -264.194588) (xy 120.851123 -264.218166)
			(xy 120.893139 -264.248692) (xy 120.929862 -264.285415) (xy 120.960388 -264.327431) (xy 120.983966 -264.373705)
			(xy 121.000014 -264.423098) (xy 121.008139 -264.474393) (xy 121.008648 -264.50036) (xy 121.008139 -264.526327)
			(xy 121.288049 -264.526327) (xy 121.288049 -264.474393) (xy 121.296174 -264.423098) (xy 121.312222 -264.373705)
			(xy 121.3358 -264.327431) (xy 121.366326 -264.285415) (xy 121.403049 -264.248692) (xy 121.445065 -264.218166)
			(xy 121.491339 -264.194588) (xy 121.540732 -264.17854) (xy 121.592027 -264.170415) (xy 121.643961 -264.170415)
			(xy 121.695256 -264.17854) (xy 121.744649 -264.194588) (xy 121.790923 -264.218166) (xy 121.832939 -264.248692)
			(xy 121.869662 -264.285415) (xy 121.900188 -264.327431) (xy 121.923766 -264.373705) (xy 121.939814 -264.423098)
			(xy 121.947939 -264.474393) (xy 121.948448 -264.50036) (xy 121.947939 -264.526327) (xy 122.227849 -264.526327)
			(xy 122.227849 -264.474393) (xy 122.235974 -264.423098) (xy 122.252022 -264.373705) (xy 122.2756 -264.327431)
			(xy 122.306126 -264.285415) (xy 122.342849 -264.248692) (xy 122.384865 -264.218166) (xy 122.431139 -264.194588)
			(xy 122.480532 -264.17854) (xy 122.531827 -264.170415) (xy 122.583761 -264.170415) (xy 122.635056 -264.17854)
			(xy 122.684449 -264.194588) (xy 122.730723 -264.218166) (xy 122.772739 -264.248692) (xy 122.809462 -264.285415)
			(xy 122.839988 -264.327431) (xy 122.863566 -264.373705) (xy 122.879614 -264.423098) (xy 122.887739 -264.474393)
			(xy 122.888248 -264.50036) (xy 122.887739 -264.526327) (xy 123.167649 -264.526327) (xy 123.167649 -264.474393)
			(xy 123.175774 -264.423098) (xy 123.191822 -264.373705) (xy 123.2154 -264.327431) (xy 123.245926 -264.285415)
			(xy 123.282649 -264.248692) (xy 123.324665 -264.218166) (xy 123.370939 -264.194588) (xy 123.420332 -264.17854)
			(xy 123.471627 -264.170415) (xy 123.523561 -264.170415) (xy 123.574856 -264.17854) (xy 123.624249 -264.194588)
			(xy 123.670523 -264.218166) (xy 123.712539 -264.248692) (xy 123.749262 -264.285415) (xy 123.779788 -264.327431)
			(xy 123.803366 -264.373705) (xy 123.819414 -264.423098) (xy 123.827539 -264.474393) (xy 123.828048 -264.50036)
			(xy 123.827539 -264.526327) (xy 124.107449 -264.526327) (xy 124.107449 -264.474393) (xy 124.115574 -264.423098)
			(xy 124.131622 -264.373705) (xy 124.1552 -264.327431) (xy 124.185726 -264.285415) (xy 124.222449 -264.248692)
			(xy 124.264465 -264.218166) (xy 124.310739 -264.194588) (xy 124.360132 -264.17854) (xy 124.411427 -264.170415)
			(xy 124.463361 -264.170415) (xy 124.514656 -264.17854) (xy 124.564049 -264.194588) (xy 124.610323 -264.218166)
			(xy 124.652339 -264.248692) (xy 124.689062 -264.285415) (xy 124.719588 -264.327431) (xy 124.743166 -264.373705)
			(xy 124.759214 -264.423098) (xy 124.767339 -264.474393) (xy 124.767848 -264.50036) (xy 124.767339 -264.526327)
			(xy 125.047249 -264.526327) (xy 125.047249 -264.474393) (xy 125.055374 -264.423098) (xy 125.071422 -264.373705)
			(xy 125.095 -264.327431) (xy 125.125526 -264.285415) (xy 125.162249 -264.248692) (xy 125.204265 -264.218166)
			(xy 125.250539 -264.194588) (xy 125.299932 -264.17854) (xy 125.351227 -264.170415) (xy 125.403161 -264.170415)
			(xy 125.454456 -264.17854) (xy 125.503849 -264.194588) (xy 125.550123 -264.218166) (xy 125.592139 -264.248692)
			(xy 125.628862 -264.285415) (xy 125.659388 -264.327431) (xy 125.682966 -264.373705) (xy 125.699014 -264.423098)
			(xy 125.707139 -264.474393) (xy 125.707648 -264.50036) (xy 125.707139 -264.526327) (xy 125.987303 -264.526327)
			(xy 125.987303 -264.474393) (xy 125.995428 -264.423098) (xy 126.011476 -264.373705) (xy 126.035054 -264.327431)
			(xy 126.06558 -264.285415) (xy 126.102303 -264.248692) (xy 126.144319 -264.218166) (xy 126.190593 -264.194588)
			(xy 126.239986 -264.17854) (xy 126.291281 -264.170415) (xy 126.343215 -264.170415) (xy 126.39451 -264.17854)
			(xy 126.443903 -264.194588) (xy 126.490177 -264.218166) (xy 126.532193 -264.248692) (xy 126.568916 -264.285415)
			(xy 126.599442 -264.327431) (xy 126.62302 -264.373705) (xy 126.639068 -264.423098) (xy 126.647193 -264.474393)
			(xy 126.647702 -264.50036) (xy 126.647193 -264.526327) (xy 126.639068 -264.577622) (xy 126.62302 -264.627015)
			(xy 126.599442 -264.673289) (xy 126.568916 -264.715305) (xy 126.532193 -264.752028) (xy 126.490177 -264.782554)
			(xy 126.443903 -264.806132) (xy 126.39451 -264.82218) (xy 126.343215 -264.830305) (xy 126.291281 -264.830305)
			(xy 126.239986 -264.82218) (xy 126.190593 -264.806132) (xy 126.144319 -264.782554) (xy 126.102303 -264.752028)
			(xy 126.06558 -264.715305) (xy 126.035054 -264.673289) (xy 126.011476 -264.627015) (xy 125.995428 -264.577622)
			(xy 125.987303 -264.526327) (xy 125.707139 -264.526327) (xy 125.699014 -264.577622) (xy 125.682966 -264.627015)
			(xy 125.659388 -264.673289) (xy 125.628862 -264.715305) (xy 125.592139 -264.752028) (xy 125.550123 -264.782554)
			(xy 125.503849 -264.806132) (xy 125.454456 -264.82218) (xy 125.403161 -264.830305) (xy 125.351227 -264.830305)
			(xy 125.299932 -264.82218) (xy 125.250539 -264.806132) (xy 125.204265 -264.782554) (xy 125.162249 -264.752028)
			(xy 125.125526 -264.715305) (xy 125.095 -264.673289) (xy 125.071422 -264.627015) (xy 125.055374 -264.577622)
			(xy 125.047249 -264.526327) (xy 124.767339 -264.526327) (xy 124.759214 -264.577622) (xy 124.743166 -264.627015)
			(xy 124.719588 -264.673289) (xy 124.689062 -264.715305) (xy 124.652339 -264.752028) (xy 124.610323 -264.782554)
			(xy 124.564049 -264.806132) (xy 124.514656 -264.82218) (xy 124.463361 -264.830305) (xy 124.411427 -264.830305)
			(xy 124.360132 -264.82218) (xy 124.310739 -264.806132) (xy 124.264465 -264.782554) (xy 124.222449 -264.752028)
			(xy 124.185726 -264.715305) (xy 124.1552 -264.673289) (xy 124.131622 -264.627015) (xy 124.115574 -264.577622)
			(xy 124.107449 -264.526327) (xy 123.827539 -264.526327) (xy 123.819414 -264.577622) (xy 123.803366 -264.627015)
			(xy 123.779788 -264.673289) (xy 123.749262 -264.715305) (xy 123.712539 -264.752028) (xy 123.670523 -264.782554)
			(xy 123.624249 -264.806132) (xy 123.574856 -264.82218) (xy 123.523561 -264.830305) (xy 123.471627 -264.830305)
			(xy 123.420332 -264.82218) (xy 123.370939 -264.806132) (xy 123.324665 -264.782554) (xy 123.282649 -264.752028)
			(xy 123.245926 -264.715305) (xy 123.2154 -264.673289) (xy 123.191822 -264.627015) (xy 123.175774 -264.577622)
			(xy 123.167649 -264.526327) (xy 122.887739 -264.526327) (xy 122.879614 -264.577622) (xy 122.863566 -264.627015)
			(xy 122.839988 -264.673289) (xy 122.809462 -264.715305) (xy 122.772739 -264.752028) (xy 122.730723 -264.782554)
			(xy 122.684449 -264.806132) (xy 122.635056 -264.82218) (xy 122.583761 -264.830305) (xy 122.531827 -264.830305)
			(xy 122.480532 -264.82218) (xy 122.431139 -264.806132) (xy 122.384865 -264.782554) (xy 122.342849 -264.752028)
			(xy 122.306126 -264.715305) (xy 122.2756 -264.673289) (xy 122.252022 -264.627015) (xy 122.235974 -264.577622)
			(xy 122.227849 -264.526327) (xy 121.947939 -264.526327) (xy 121.939814 -264.577622) (xy 121.923766 -264.627015)
			(xy 121.900188 -264.673289) (xy 121.869662 -264.715305) (xy 121.832939 -264.752028) (xy 121.790923 -264.782554)
			(xy 121.744649 -264.806132) (xy 121.695256 -264.82218) (xy 121.643961 -264.830305) (xy 121.592027 -264.830305)
			(xy 121.540732 -264.82218) (xy 121.491339 -264.806132) (xy 121.445065 -264.782554) (xy 121.403049 -264.752028)
			(xy 121.366326 -264.715305) (xy 121.3358 -264.673289) (xy 121.312222 -264.627015) (xy 121.296174 -264.577622)
			(xy 121.288049 -264.526327) (xy 121.008139 -264.526327) (xy 121.000014 -264.577622) (xy 120.983966 -264.627015)
			(xy 120.960388 -264.673289) (xy 120.929862 -264.715305) (xy 120.893139 -264.752028) (xy 120.851123 -264.782554)
			(xy 120.804849 -264.806132) (xy 120.755456 -264.82218) (xy 120.704161 -264.830305) (xy 120.652227 -264.830305)
			(xy 120.600932 -264.82218) (xy 120.551539 -264.806132) (xy 120.505265 -264.782554) (xy 120.463249 -264.752028)
			(xy 120.426526 -264.715305) (xy 120.396 -264.673289) (xy 120.372422 -264.627015) (xy 120.356374 -264.577622)
			(xy 120.348249 -264.526327) (xy 120.068339 -264.526327) (xy 120.060214 -264.577622) (xy 120.044166 -264.627015)
			(xy 120.020588 -264.673289) (xy 119.990062 -264.715305) (xy 119.953339 -264.752028) (xy 119.911323 -264.782554)
			(xy 119.865049 -264.806132) (xy 119.815656 -264.82218) (xy 119.764361 -264.830305) (xy 119.712427 -264.830305)
			(xy 119.661132 -264.82218) (xy 119.611739 -264.806132) (xy 119.565465 -264.782554) (xy 119.523449 -264.752028)
			(xy 119.486726 -264.715305) (xy 119.4562 -264.673289) (xy 119.432622 -264.627015) (xy 119.416574 -264.577622)
			(xy 119.408449 -264.526327) (xy 119.128539 -264.526327) (xy 119.120414 -264.577622) (xy 119.104366 -264.627015)
			(xy 119.080788 -264.673289) (xy 119.050262 -264.715305) (xy 119.013539 -264.752028) (xy 118.971523 -264.782554)
			(xy 118.925249 -264.806132) (xy 118.875856 -264.82218) (xy 118.824561 -264.830305) (xy 118.772627 -264.830305)
			(xy 118.721332 -264.82218) (xy 118.671939 -264.806132) (xy 118.625665 -264.782554) (xy 118.583649 -264.752028)
			(xy 118.546926 -264.715305) (xy 118.5164 -264.673289) (xy 118.492822 -264.627015) (xy 118.476774 -264.577622)
			(xy 118.468649 -264.526327) (xy 118.188739 -264.526327) (xy 118.180614 -264.577622) (xy 118.164566 -264.627015)
			(xy 118.140988 -264.673289) (xy 118.110462 -264.715305) (xy 118.073739 -264.752028) (xy 118.031723 -264.782554)
			(xy 117.985449 -264.806132) (xy 117.936056 -264.82218) (xy 117.884761 -264.830305) (xy 117.832827 -264.830305)
			(xy 117.781532 -264.82218) (xy 117.732139 -264.806132) (xy 117.685865 -264.782554) (xy 117.643849 -264.752028)
			(xy 117.607126 -264.715305) (xy 117.5766 -264.673289) (xy 117.553022 -264.627015) (xy 117.536974 -264.577622)
			(xy 117.528849 -264.526327) (xy 117.403626 -264.526327) (xy 117.403626 -264.981182) (xy 117.44579 -264.988548)
			(xy 117.47102 -264.993435) (xy 117.519674 -265.009977) (xy 117.565181 -265.033849) (xy 117.606446 -265.064476)
			(xy 117.642474 -265.101121) (xy 117.672397 -265.142899) (xy 117.695494 -265.188805) (xy 117.711208 -265.237732)
			(xy 117.719162 -265.288501) (xy 117.719162 -265.33989) (xy 117.719122 -265.340143) (xy 117.998749 -265.340143)
			(xy 117.998749 -265.288209) (xy 118.006874 -265.236914) (xy 118.022922 -265.187521) (xy 118.0465 -265.141247)
			(xy 118.077026 -265.099231) (xy 118.113749 -265.062508) (xy 118.155765 -265.031982) (xy 118.202039 -265.008404)
			(xy 118.251432 -264.992356) (xy 118.302727 -264.984231) (xy 118.354661 -264.984231) (xy 118.405956 -264.992356)
			(xy 118.455349 -265.008404) (xy 118.501623 -265.031982) (xy 118.543639 -265.062508) (xy 118.580362 -265.099231)
			(xy 118.610888 -265.141247) (xy 118.634466 -265.187521) (xy 118.650514 -265.236914) (xy 118.658639 -265.288209)
			(xy 118.659148 -265.314176) (xy 118.658639 -265.340143) (xy 118.938803 -265.340143) (xy 118.938803 -265.288209)
			(xy 118.946928 -265.236914) (xy 118.962976 -265.187521) (xy 118.986554 -265.141247) (xy 119.01708 -265.099231)
			(xy 119.053803 -265.062508) (xy 119.095819 -265.031982) (xy 119.142093 -265.008404) (xy 119.191486 -264.992356)
			(xy 119.242781 -264.984231) (xy 119.294715 -264.984231) (xy 119.34601 -264.992356) (xy 119.395403 -265.008404)
			(xy 119.441677 -265.031982) (xy 119.483693 -265.062508) (xy 119.520416 -265.099231) (xy 119.550942 -265.141247)
			(xy 119.57452 -265.187521) (xy 119.590568 -265.236914) (xy 119.598693 -265.288209) (xy 119.599202 -265.314176)
			(xy 119.598693 -265.340143) (xy 119.878603 -265.340143) (xy 119.878603 -265.288209) (xy 119.886728 -265.236914)
			(xy 119.902776 -265.187521) (xy 119.926354 -265.141247) (xy 119.95688 -265.099231) (xy 119.993603 -265.062508)
			(xy 120.035619 -265.031982) (xy 120.081893 -265.008404) (xy 120.131286 -264.992356) (xy 120.182581 -264.984231)
			(xy 120.234515 -264.984231) (xy 120.28581 -264.992356) (xy 120.335203 -265.008404) (xy 120.381477 -265.031982)
			(xy 120.423493 -265.062508) (xy 120.460216 -265.099231) (xy 120.490742 -265.141247) (xy 120.51432 -265.187521)
			(xy 120.530368 -265.236914) (xy 120.538493 -265.288209) (xy 120.539002 -265.314176) (xy 120.538493 -265.340143)
			(xy 121.758203 -265.340143) (xy 121.758203 -265.288209) (xy 121.766328 -265.236914) (xy 121.782376 -265.187521)
			(xy 121.805954 -265.141247) (xy 121.83648 -265.099231) (xy 121.873203 -265.062508) (xy 121.915219 -265.031982)
			(xy 121.961493 -265.008404) (xy 122.010886 -264.992356) (xy 122.062181 -264.984231) (xy 122.114115 -264.984231)
			(xy 122.16541 -264.992356) (xy 122.214803 -265.008404) (xy 122.261077 -265.031982) (xy 122.303093 -265.062508)
			(xy 122.339816 -265.099231) (xy 122.370342 -265.141247) (xy 122.39392 -265.187521) (xy 122.409968 -265.236914)
			(xy 122.418093 -265.288209) (xy 122.418602 -265.314176) (xy 122.418093 -265.340143) (xy 122.698003 -265.340143)
			(xy 122.698003 -265.288209) (xy 122.706128 -265.236914) (xy 122.722176 -265.187521) (xy 122.745754 -265.141247)
			(xy 122.77628 -265.099231) (xy 122.813003 -265.062508) (xy 122.855019 -265.031982) (xy 122.901293 -265.008404)
			(xy 122.950686 -264.992356) (xy 123.001981 -264.984231) (xy 123.053915 -264.984231) (xy 123.10521 -264.992356)
			(xy 123.154603 -265.008404) (xy 123.200877 -265.031982) (xy 123.242893 -265.062508) (xy 123.279616 -265.099231)
			(xy 123.310142 -265.141247) (xy 123.33372 -265.187521) (xy 123.349768 -265.236914) (xy 123.357893 -265.288209)
			(xy 123.358402 -265.314176) (xy 123.357893 -265.340143) (xy 123.637803 -265.340143) (xy 123.637803 -265.288209)
			(xy 123.645928 -265.236914) (xy 123.661976 -265.187521) (xy 123.685554 -265.141247) (xy 123.71608 -265.099231)
			(xy 123.752803 -265.062508) (xy 123.794819 -265.031982) (xy 123.841093 -265.008404) (xy 123.890486 -264.992356)
			(xy 123.941781 -264.984231) (xy 123.993715 -264.984231) (xy 124.04501 -264.992356) (xy 124.094403 -265.008404)
			(xy 124.140677 -265.031982) (xy 124.182693 -265.062508) (xy 124.219416 -265.099231) (xy 124.249942 -265.141247)
			(xy 124.27352 -265.187521) (xy 124.289568 -265.236914) (xy 124.297693 -265.288209) (xy 124.298202 -265.314176)
			(xy 124.297693 -265.340143) (xy 124.577603 -265.340143) (xy 124.577603 -265.288209) (xy 124.585728 -265.236914)
			(xy 124.601776 -265.187521) (xy 124.625354 -265.141247) (xy 124.65588 -265.099231) (xy 124.692603 -265.062508)
			(xy 124.734619 -265.031982) (xy 124.780893 -265.008404) (xy 124.830286 -264.992356) (xy 124.881581 -264.984231)
			(xy 124.933515 -264.984231) (xy 124.98481 -264.992356) (xy 125.034203 -265.008404) (xy 125.080477 -265.031982)
			(xy 125.122493 -265.062508) (xy 125.159216 -265.099231) (xy 125.189742 -265.141247) (xy 125.21332 -265.187521)
			(xy 125.229368 -265.236914) (xy 125.237493 -265.288209) (xy 125.238002 -265.314176) (xy 125.237493 -265.340143)
			(xy 125.517403 -265.340143) (xy 125.517403 -265.288209) (xy 125.525528 -265.236914) (xy 125.541576 -265.187521)
			(xy 125.565154 -265.141247) (xy 125.59568 -265.099231) (xy 125.632403 -265.062508) (xy 125.674419 -265.031982)
			(xy 125.720693 -265.008404) (xy 125.770086 -264.992356) (xy 125.821381 -264.984231) (xy 125.873315 -264.984231)
			(xy 125.92461 -264.992356) (xy 125.974003 -265.008404) (xy 126.020277 -265.031982) (xy 126.062293 -265.062508)
			(xy 126.099016 -265.099231) (xy 126.129542 -265.141247) (xy 126.15312 -265.187521) (xy 126.169168 -265.236914)
			(xy 126.177293 -265.288209) (xy 126.177802 -265.314176) (xy 126.177293 -265.340143) (xy 126.169168 -265.391438)
			(xy 126.15312 -265.440831) (xy 126.129542 -265.487105) (xy 126.099016 -265.529121) (xy 126.062293 -265.565844)
			(xy 126.020277 -265.59637) (xy 125.974003 -265.619948) (xy 125.92461 -265.635996) (xy 125.873315 -265.644121)
			(xy 125.821381 -265.644121) (xy 125.770086 -265.635996) (xy 125.720693 -265.619948) (xy 125.674419 -265.59637)
			(xy 125.632403 -265.565844) (xy 125.59568 -265.529121) (xy 125.565154 -265.487105) (xy 125.541576 -265.440831)
			(xy 125.525528 -265.391438) (xy 125.517403 -265.340143) (xy 125.237493 -265.340143) (xy 125.229368 -265.391438)
			(xy 125.21332 -265.440831) (xy 125.189742 -265.487105) (xy 125.159216 -265.529121) (xy 125.122493 -265.565844)
			(xy 125.080477 -265.59637) (xy 125.034203 -265.619948) (xy 124.98481 -265.635996) (xy 124.933515 -265.644121)
			(xy 124.881581 -265.644121) (xy 124.830286 -265.635996) (xy 124.780893 -265.619948) (xy 124.734619 -265.59637)
			(xy 124.692603 -265.565844) (xy 124.65588 -265.529121) (xy 124.625354 -265.487105) (xy 124.601776 -265.440831)
			(xy 124.585728 -265.391438) (xy 124.577603 -265.340143) (xy 124.297693 -265.340143) (xy 124.289568 -265.391438)
			(xy 124.27352 -265.440831) (xy 124.249942 -265.487105) (xy 124.219416 -265.529121) (xy 124.182693 -265.565844)
			(xy 124.140677 -265.59637) (xy 124.094403 -265.619948) (xy 124.04501 -265.635996) (xy 123.993715 -265.644121)
			(xy 123.941781 -265.644121) (xy 123.890486 -265.635996) (xy 123.841093 -265.619948) (xy 123.794819 -265.59637)
			(xy 123.752803 -265.565844) (xy 123.71608 -265.529121) (xy 123.685554 -265.487105) (xy 123.661976 -265.440831)
			(xy 123.645928 -265.391438) (xy 123.637803 -265.340143) (xy 123.357893 -265.340143) (xy 123.349768 -265.391438)
			(xy 123.33372 -265.440831) (xy 123.310142 -265.487105) (xy 123.279616 -265.529121) (xy 123.242893 -265.565844)
			(xy 123.200877 -265.59637) (xy 123.154603 -265.619948) (xy 123.10521 -265.635996) (xy 123.053915 -265.644121)
			(xy 123.001981 -265.644121) (xy 122.950686 -265.635996) (xy 122.901293 -265.619948) (xy 122.855019 -265.59637)
			(xy 122.813003 -265.565844) (xy 122.77628 -265.529121) (xy 122.745754 -265.487105) (xy 122.722176 -265.440831)
			(xy 122.706128 -265.391438) (xy 122.698003 -265.340143) (xy 122.418093 -265.340143) (xy 122.409968 -265.391438)
			(xy 122.39392 -265.440831) (xy 122.370342 -265.487105) (xy 122.339816 -265.529121) (xy 122.303093 -265.565844)
			(xy 122.261077 -265.59637) (xy 122.214803 -265.619948) (xy 122.16541 -265.635996) (xy 122.114115 -265.644121)
			(xy 122.062181 -265.644121) (xy 122.010886 -265.635996) (xy 121.961493 -265.619948) (xy 121.915219 -265.59637)
			(xy 121.873203 -265.565844) (xy 121.83648 -265.529121) (xy 121.805954 -265.487105) (xy 121.782376 -265.440831)
			(xy 121.766328 -265.391438) (xy 121.758203 -265.340143) (xy 120.538493 -265.340143) (xy 120.530368 -265.391438)
			(xy 120.51432 -265.440831) (xy 120.490742 -265.487105) (xy 120.460216 -265.529121) (xy 120.423493 -265.565844)
			(xy 120.381477 -265.59637) (xy 120.335203 -265.619948) (xy 120.28581 -265.635996) (xy 120.234515 -265.644121)
			(xy 120.182581 -265.644121) (xy 120.131286 -265.635996) (xy 120.081893 -265.619948) (xy 120.035619 -265.59637)
			(xy 119.993603 -265.565844) (xy 119.95688 -265.529121) (xy 119.926354 -265.487105) (xy 119.902776 -265.440831)
			(xy 119.886728 -265.391438) (xy 119.878603 -265.340143) (xy 119.598693 -265.340143) (xy 119.590568 -265.391438)
			(xy 119.57452 -265.440831) (xy 119.550942 -265.487105) (xy 119.520416 -265.529121) (xy 119.483693 -265.565844)
			(xy 119.441677 -265.59637) (xy 119.395403 -265.619948) (xy 119.34601 -265.635996) (xy 119.294715 -265.644121)
			(xy 119.242781 -265.644121) (xy 119.191486 -265.635996) (xy 119.142093 -265.619948) (xy 119.095819 -265.59637)
			(xy 119.053803 -265.565844) (xy 119.01708 -265.529121) (xy 118.986554 -265.487105) (xy 118.962976 -265.440831)
			(xy 118.946928 -265.391438) (xy 118.938803 -265.340143) (xy 118.658639 -265.340143) (xy 118.650514 -265.391438)
			(xy 118.634466 -265.440831) (xy 118.610888 -265.487105) (xy 118.580362 -265.529121) (xy 118.543639 -265.565844)
			(xy 118.501623 -265.59637) (xy 118.455349 -265.619948) (xy 118.405956 -265.635996) (xy 118.354661 -265.644121)
			(xy 118.302727 -265.644121) (xy 118.251432 -265.635996) (xy 118.202039 -265.619948) (xy 118.155765 -265.59637)
			(xy 118.113749 -265.565844) (xy 118.077026 -265.529121) (xy 118.0465 -265.487105) (xy 118.022922 -265.440831)
			(xy 118.006874 -265.391438) (xy 117.998749 -265.340143) (xy 117.719122 -265.340143) (xy 117.71121 -265.39066)
			(xy 117.695497 -265.439588) (xy 117.672401 -265.485494) (xy 117.642479 -265.527273) (xy 117.606452 -265.563918)
			(xy 117.565188 -265.594546) (xy 117.519681 -265.61842) (xy 117.471028 -265.634963) (xy 117.44579 -265.639804)
			(xy 117.403626 -265.64717) (xy 117.403626 -266.154213) (xy 117.528849 -266.154213) (xy 117.528849 -266.102279)
			(xy 117.536974 -266.050984) (xy 117.553022 -266.001591) (xy 117.5766 -265.955317) (xy 117.607126 -265.913301)
			(xy 117.643849 -265.876578) (xy 117.685865 -265.846052) (xy 117.732139 -265.822474) (xy 117.781532 -265.806426)
			(xy 117.832827 -265.798301) (xy 117.884761 -265.798301) (xy 117.936056 -265.806426) (xy 117.985449 -265.822474)
			(xy 118.031723 -265.846052) (xy 118.073739 -265.876578) (xy 118.110462 -265.913301) (xy 118.140988 -265.955317)
			(xy 118.164566 -266.001591) (xy 118.180614 -266.050984) (xy 118.188739 -266.102279) (xy 118.189248 -266.128246)
			(xy 118.188739 -266.154213) (xy 118.188699 -266.154467) (xy 118.468649 -266.154467) (xy 118.468649 -266.102533)
			(xy 118.476774 -266.051238) (xy 118.492822 -266.001845) (xy 118.5164 -265.955571) (xy 118.546926 -265.913555)
			(xy 118.583649 -265.876832) (xy 118.625665 -265.846306) (xy 118.671939 -265.822728) (xy 118.721332 -265.80668)
			(xy 118.772627 -265.798555) (xy 118.824561 -265.798555) (xy 118.875856 -265.80668) (xy 118.925249 -265.822728)
			(xy 118.971523 -265.846306) (xy 119.013539 -265.876832) (xy 119.050262 -265.913555) (xy 119.080788 -265.955571)
			(xy 119.104366 -266.001845) (xy 119.120414 -266.051238) (xy 119.128539 -266.102533) (xy 119.129048 -266.1285)
			(xy 119.128544 -266.154213) (xy 119.408449 -266.154213) (xy 119.408449 -266.102279) (xy 119.416574 -266.050984)
			(xy 119.432622 -266.001591) (xy 119.4562 -265.955317) (xy 119.486726 -265.913301) (xy 119.523449 -265.876578)
			(xy 119.565465 -265.846052) (xy 119.611739 -265.822474) (xy 119.661132 -265.806426) (xy 119.712427 -265.798301)
			(xy 119.764361 -265.798301) (xy 119.815656 -265.806426) (xy 119.865049 -265.822474) (xy 119.911323 -265.846052)
			(xy 119.953339 -265.876578) (xy 119.990062 -265.913301) (xy 120.020588 -265.955317) (xy 120.044166 -266.001591)
			(xy 120.060214 -266.050984) (xy 120.068339 -266.102279) (xy 120.068848 -266.128246) (xy 120.068339 -266.154213)
			(xy 120.348249 -266.154213) (xy 120.348249 -266.102279) (xy 120.356374 -266.050984) (xy 120.372422 -266.001591)
			(xy 120.396 -265.955317) (xy 120.426526 -265.913301) (xy 120.463249 -265.876578) (xy 120.505265 -265.846052)
			(xy 120.551539 -265.822474) (xy 120.600932 -265.806426) (xy 120.652227 -265.798301) (xy 120.704161 -265.798301)
			(xy 120.755456 -265.806426) (xy 120.804849 -265.822474) (xy 120.851123 -265.846052) (xy 120.893139 -265.876578)
			(xy 120.929862 -265.913301) (xy 120.960388 -265.955317) (xy 120.983966 -266.001591) (xy 121.000014 -266.050984)
			(xy 121.008139 -266.102279) (xy 121.008648 -266.128246) (xy 121.008139 -266.154213) (xy 122.227849 -266.154213)
			(xy 122.227849 -266.102279) (xy 122.235974 -266.050984) (xy 122.252022 -266.001591) (xy 122.2756 -265.955317)
			(xy 122.306126 -265.913301) (xy 122.342849 -265.876578) (xy 122.384865 -265.846052) (xy 122.431139 -265.822474)
			(xy 122.480532 -265.806426) (xy 122.531827 -265.798301) (xy 122.583761 -265.798301) (xy 122.635056 -265.806426)
			(xy 122.684449 -265.822474) (xy 122.730723 -265.846052) (xy 122.772739 -265.876578) (xy 122.809462 -265.913301)
			(xy 122.839988 -265.955317) (xy 122.863566 -266.001591) (xy 122.879614 -266.050984) (xy 122.887739 -266.102279)
			(xy 122.888248 -266.128246) (xy 122.887739 -266.154213) (xy 123.167649 -266.154213) (xy 123.167649 -266.102279)
			(xy 123.175774 -266.050984) (xy 123.191822 -266.001591) (xy 123.2154 -265.955317) (xy 123.245926 -265.913301)
			(xy 123.282649 -265.876578) (xy 123.324665 -265.846052) (xy 123.370939 -265.822474) (xy 123.420332 -265.806426)
			(xy 123.471627 -265.798301) (xy 123.523561 -265.798301) (xy 123.574856 -265.806426) (xy 123.624249 -265.822474)
			(xy 123.670523 -265.846052) (xy 123.712539 -265.876578) (xy 123.749262 -265.913301) (xy 123.779788 -265.955317)
			(xy 123.803366 -266.001591) (xy 123.819414 -266.050984) (xy 123.827539 -266.102279) (xy 123.828048 -266.128246)
			(xy 123.827539 -266.154213) (xy 124.107449 -266.154213) (xy 124.107449 -266.102279) (xy 124.115574 -266.050984)
			(xy 124.131622 -266.001591) (xy 124.1552 -265.955317) (xy 124.185726 -265.913301) (xy 124.222449 -265.876578)
			(xy 124.264465 -265.846052) (xy 124.310739 -265.822474) (xy 124.360132 -265.806426) (xy 124.411427 -265.798301)
			(xy 124.463361 -265.798301) (xy 124.514656 -265.806426) (xy 124.564049 -265.822474) (xy 124.610323 -265.846052)
			(xy 124.652339 -265.876578) (xy 124.689062 -265.913301) (xy 124.719588 -265.955317) (xy 124.743166 -266.001591)
			(xy 124.759214 -266.050984) (xy 124.767339 -266.102279) (xy 124.767848 -266.128246) (xy 124.767339 -266.154213)
			(xy 125.047249 -266.154213) (xy 125.047249 -266.102279) (xy 125.055374 -266.050984) (xy 125.071422 -266.001591)
			(xy 125.095 -265.955317) (xy 125.125526 -265.913301) (xy 125.162249 -265.876578) (xy 125.204265 -265.846052)
			(xy 125.250539 -265.822474) (xy 125.299932 -265.806426) (xy 125.351227 -265.798301) (xy 125.403161 -265.798301)
			(xy 125.454456 -265.806426) (xy 125.503849 -265.822474) (xy 125.550123 -265.846052) (xy 125.592139 -265.876578)
			(xy 125.628862 -265.913301) (xy 125.659388 -265.955317) (xy 125.682966 -266.001591) (xy 125.699014 -266.050984)
			(xy 125.707139 -266.102279) (xy 125.707648 -266.128246) (xy 125.707139 -266.154213) (xy 125.987049 -266.154213)
			(xy 125.987049 -266.102279) (xy 125.995174 -266.050984) (xy 126.011222 -266.001591) (xy 126.0348 -265.955317)
			(xy 126.065326 -265.913301) (xy 126.102049 -265.876578) (xy 126.144065 -265.846052) (xy 126.190339 -265.822474)
			(xy 126.239732 -265.806426) (xy 126.291027 -265.798301) (xy 126.342961 -265.798301) (xy 126.394256 -265.806426)
			(xy 126.443649 -265.822474) (xy 126.489923 -265.846052) (xy 126.531939 -265.876578) (xy 126.568662 -265.913301)
			(xy 126.599188 -265.955317) (xy 126.622766 -266.001591) (xy 126.638814 -266.050984) (xy 126.646939 -266.102279)
			(xy 126.647448 -266.128246) (xy 126.646939 -266.154213) (xy 126.638814 -266.205508) (xy 126.622766 -266.254901)
			(xy 126.599188 -266.301175) (xy 126.568662 -266.343191) (xy 126.531939 -266.379914) (xy 126.489923 -266.41044)
			(xy 126.443649 -266.434018) (xy 126.394256 -266.450066) (xy 126.342961 -266.458191) (xy 126.291027 -266.458191)
			(xy 126.239732 -266.450066) (xy 126.190339 -266.434018) (xy 126.144065 -266.41044) (xy 126.102049 -266.379914)
			(xy 126.065326 -266.343191) (xy 126.0348 -266.301175) (xy 126.011222 -266.254901) (xy 125.995174 -266.205508)
			(xy 125.987049 -266.154213) (xy 125.707139 -266.154213) (xy 125.699014 -266.205508) (xy 125.682966 -266.254901)
			(xy 125.659388 -266.301175) (xy 125.628862 -266.343191) (xy 125.592139 -266.379914) (xy 125.550123 -266.41044)
			(xy 125.503849 -266.434018) (xy 125.454456 -266.450066) (xy 125.403161 -266.458191) (xy 125.351227 -266.458191)
			(xy 125.299932 -266.450066) (xy 125.250539 -266.434018) (xy 125.204265 -266.41044) (xy 125.162249 -266.379914)
			(xy 125.125526 -266.343191) (xy 125.095 -266.301175) (xy 125.071422 -266.254901) (xy 125.055374 -266.205508)
			(xy 125.047249 -266.154213) (xy 124.767339 -266.154213) (xy 124.759214 -266.205508) (xy 124.743166 -266.254901)
			(xy 124.719588 -266.301175) (xy 124.689062 -266.343191) (xy 124.652339 -266.379914) (xy 124.610323 -266.41044)
			(xy 124.564049 -266.434018) (xy 124.514656 -266.450066) (xy 124.463361 -266.458191) (xy 124.411427 -266.458191)
			(xy 124.360132 -266.450066) (xy 124.310739 -266.434018) (xy 124.264465 -266.41044) (xy 124.222449 -266.379914)
			(xy 124.185726 -266.343191) (xy 124.1552 -266.301175) (xy 124.131622 -266.254901) (xy 124.115574 -266.205508)
			(xy 124.107449 -266.154213) (xy 123.827539 -266.154213) (xy 123.819414 -266.205508) (xy 123.803366 -266.254901)
			(xy 123.779788 -266.301175) (xy 123.749262 -266.343191) (xy 123.712539 -266.379914) (xy 123.670523 -266.41044)
			(xy 123.624249 -266.434018) (xy 123.574856 -266.450066) (xy 123.523561 -266.458191) (xy 123.471627 -266.458191)
			(xy 123.420332 -266.450066) (xy 123.370939 -266.434018) (xy 123.324665 -266.41044) (xy 123.282649 -266.379914)
			(xy 123.245926 -266.343191) (xy 123.2154 -266.301175) (xy 123.191822 -266.254901) (xy 123.175774 -266.205508)
			(xy 123.167649 -266.154213) (xy 122.887739 -266.154213) (xy 122.879614 -266.205508) (xy 122.863566 -266.254901)
			(xy 122.839988 -266.301175) (xy 122.809462 -266.343191) (xy 122.772739 -266.379914) (xy 122.730723 -266.41044)
			(xy 122.684449 -266.434018) (xy 122.635056 -266.450066) (xy 122.583761 -266.458191) (xy 122.531827 -266.458191)
			(xy 122.480532 -266.450066) (xy 122.431139 -266.434018) (xy 122.384865 -266.41044) (xy 122.342849 -266.379914)
			(xy 122.306126 -266.343191) (xy 122.2756 -266.301175) (xy 122.252022 -266.254901) (xy 122.235974 -266.205508)
			(xy 122.227849 -266.154213) (xy 121.008139 -266.154213) (xy 121.000014 -266.205508) (xy 120.983966 -266.254901)
			(xy 120.960388 -266.301175) (xy 120.929862 -266.343191) (xy 120.893139 -266.379914) (xy 120.851123 -266.41044)
			(xy 120.804849 -266.434018) (xy 120.755456 -266.450066) (xy 120.704161 -266.458191) (xy 120.652227 -266.458191)
			(xy 120.600932 -266.450066) (xy 120.551539 -266.434018) (xy 120.505265 -266.41044) (xy 120.463249 -266.379914)
			(xy 120.426526 -266.343191) (xy 120.396 -266.301175) (xy 120.372422 -266.254901) (xy 120.356374 -266.205508)
			(xy 120.348249 -266.154213) (xy 120.068339 -266.154213) (xy 120.060214 -266.205508) (xy 120.044166 -266.254901)
			(xy 120.020588 -266.301175) (xy 119.990062 -266.343191) (xy 119.953339 -266.379914) (xy 119.911323 -266.41044)
			(xy 119.865049 -266.434018) (xy 119.815656 -266.450066) (xy 119.764361 -266.458191) (xy 119.712427 -266.458191)
			(xy 119.661132 -266.450066) (xy 119.611739 -266.434018) (xy 119.565465 -266.41044) (xy 119.523449 -266.379914)
			(xy 119.486726 -266.343191) (xy 119.4562 -266.301175) (xy 119.432622 -266.254901) (xy 119.416574 -266.205508)
			(xy 119.408449 -266.154213) (xy 119.128544 -266.154213) (xy 119.128539 -266.154467) (xy 119.120414 -266.205762)
			(xy 119.104366 -266.255155) (xy 119.080788 -266.301429) (xy 119.050262 -266.343445) (xy 119.013539 -266.380168)
			(xy 118.971523 -266.410694) (xy 118.925249 -266.434272) (xy 118.875856 -266.45032) (xy 118.824561 -266.458445)
			(xy 118.772627 -266.458445) (xy 118.721332 -266.45032) (xy 118.671939 -266.434272) (xy 118.625665 -266.410694)
			(xy 118.583649 -266.380168) (xy 118.546926 -266.343445) (xy 118.5164 -266.301429) (xy 118.492822 -266.255155)
			(xy 118.476774 -266.205762) (xy 118.468649 -266.154467) (xy 118.188699 -266.154467) (xy 118.180614 -266.205508)
			(xy 118.164566 -266.254901) (xy 118.140988 -266.301175) (xy 118.110462 -266.343191) (xy 118.073739 -266.379914)
			(xy 118.031723 -266.41044) (xy 117.985449 -266.434018) (xy 117.936056 -266.450066) (xy 117.884761 -266.458191)
			(xy 117.832827 -266.458191) (xy 117.781532 -266.450066) (xy 117.732139 -266.434018) (xy 117.685865 -266.41044)
			(xy 117.643849 -266.379914) (xy 117.607126 -266.343191) (xy 117.5766 -266.301175) (xy 117.553022 -266.254901)
			(xy 117.536974 -266.205508) (xy 117.528849 -266.154213) (xy 117.403626 -266.154213) (xy 117.403626 -266.608814)
			(xy 117.44579 -266.61618) (xy 117.471018 -266.621067) (xy 117.519666 -266.637608) (xy 117.565169 -266.661479)
			(xy 117.606429 -266.692104) (xy 117.642453 -266.728745) (xy 117.672373 -266.77052) (xy 117.695467 -266.816422)
			(xy 117.711179 -266.865345) (xy 117.719131 -266.916109) (xy 117.71913 -266.967493) (xy 117.719086 -266.967775)
			(xy 117.998495 -266.967775) (xy 117.998495 -266.915841) (xy 118.00662 -266.864546) (xy 118.022668 -266.815153)
			(xy 118.046246 -266.768879) (xy 118.076772 -266.726863) (xy 118.113495 -266.69014) (xy 118.155511 -266.659614)
			(xy 118.201785 -266.636036) (xy 118.251178 -266.619988) (xy 118.302473 -266.611863) (xy 118.354407 -266.611863)
			(xy 118.405702 -266.619988) (xy 118.455095 -266.636036) (xy 118.501369 -266.659614) (xy 118.543385 -266.69014)
			(xy 118.580108 -266.726863) (xy 118.610634 -266.768879) (xy 118.634212 -266.815153) (xy 118.65026 -266.864546)
			(xy 118.658385 -266.915841) (xy 118.658894 -266.941808) (xy 118.658385 -266.967775) (xy 121.758203 -266.967775)
			(xy 121.758203 -266.915841) (xy 121.766328 -266.864546) (xy 121.782376 -266.815153) (xy 121.805954 -266.768879)
			(xy 121.83648 -266.726863) (xy 121.873203 -266.69014) (xy 121.915219 -266.659614) (xy 121.961493 -266.636036)
			(xy 122.010886 -266.619988) (xy 122.062181 -266.611863) (xy 122.114115 -266.611863) (xy 122.16541 -266.619988)
			(xy 122.214803 -266.636036) (xy 122.261077 -266.659614) (xy 122.303093 -266.69014) (xy 122.339816 -266.726863)
			(xy 122.370342 -266.768879) (xy 122.39392 -266.815153) (xy 122.409968 -266.864546) (xy 122.418093 -266.915841)
			(xy 122.418602 -266.941808) (xy 122.418093 -266.967775) (xy 122.698003 -266.967775) (xy 122.698003 -266.915841)
			(xy 122.706128 -266.864546) (xy 122.722176 -266.815153) (xy 122.745754 -266.768879) (xy 122.77628 -266.726863)
			(xy 122.813003 -266.69014) (xy 122.855019 -266.659614) (xy 122.901293 -266.636036) (xy 122.950686 -266.619988)
			(xy 123.001981 -266.611863) (xy 123.053915 -266.611863) (xy 123.10521 -266.619988) (xy 123.154603 -266.636036)
			(xy 123.200877 -266.659614) (xy 123.242893 -266.69014) (xy 123.279616 -266.726863) (xy 123.310142 -266.768879)
			(xy 123.33372 -266.815153) (xy 123.349768 -266.864546) (xy 123.357893 -266.915841) (xy 123.358402 -266.941808)
			(xy 123.357893 -266.967775) (xy 123.637803 -266.967775) (xy 123.637803 -266.915841) (xy 123.645928 -266.864546)
			(xy 123.661976 -266.815153) (xy 123.685554 -266.768879) (xy 123.71608 -266.726863) (xy 123.752803 -266.69014)
			(xy 123.794819 -266.659614) (xy 123.841093 -266.636036) (xy 123.890486 -266.619988) (xy 123.941781 -266.611863)
			(xy 123.993715 -266.611863) (xy 124.04501 -266.619988) (xy 124.094403 -266.636036) (xy 124.140677 -266.659614)
			(xy 124.182693 -266.69014) (xy 124.219416 -266.726863) (xy 124.249942 -266.768879) (xy 124.27352 -266.815153)
			(xy 124.289568 -266.864546) (xy 124.297693 -266.915841) (xy 124.298202 -266.941808) (xy 124.297693 -266.967775)
			(xy 124.577603 -266.967775) (xy 124.577603 -266.915841) (xy 124.585728 -266.864546) (xy 124.601776 -266.815153)
			(xy 124.625354 -266.768879) (xy 124.65588 -266.726863) (xy 124.692603 -266.69014) (xy 124.734619 -266.659614)
			(xy 124.780893 -266.636036) (xy 124.830286 -266.619988) (xy 124.881581 -266.611863) (xy 124.933515 -266.611863)
			(xy 124.98481 -266.619988) (xy 125.034203 -266.636036) (xy 125.080477 -266.659614) (xy 125.122493 -266.69014)
			(xy 125.159216 -266.726863) (xy 125.189742 -266.768879) (xy 125.21332 -266.815153) (xy 125.229368 -266.864546)
			(xy 125.237493 -266.915841) (xy 125.238002 -266.941808) (xy 125.237493 -266.967775) (xy 125.517149 -266.967775)
			(xy 125.517149 -266.915841) (xy 125.525274 -266.864546) (xy 125.541322 -266.815153) (xy 125.5649 -266.768879)
			(xy 125.595426 -266.726863) (xy 125.632149 -266.69014) (xy 125.674165 -266.659614) (xy 125.720439 -266.636036)
			(xy 125.769832 -266.619988) (xy 125.821127 -266.611863) (xy 125.873061 -266.611863) (xy 125.924356 -266.619988)
			(xy 125.973749 -266.636036) (xy 126.020023 -266.659614) (xy 126.062039 -266.69014) (xy 126.098762 -266.726863)
			(xy 126.129288 -266.768879) (xy 126.152866 -266.815153) (xy 126.168914 -266.864546) (xy 126.177039 -266.915841)
			(xy 126.177548 -266.941808) (xy 126.177039 -266.967775) (xy 126.168914 -267.01907) (xy 126.152866 -267.068463)
			(xy 126.129288 -267.114737) (xy 126.098762 -267.156753) (xy 126.062039 -267.193476) (xy 126.020023 -267.224002)
			(xy 125.973749 -267.24758) (xy 125.924356 -267.263628) (xy 125.873061 -267.271753) (xy 125.821127 -267.271753)
			(xy 125.769832 -267.263628) (xy 125.720439 -267.24758) (xy 125.674165 -267.224002) (xy 125.632149 -267.193476)
			(xy 125.595426 -267.156753) (xy 125.5649 -267.114737) (xy 125.541322 -267.068463) (xy 125.525274 -267.01907)
			(xy 125.517149 -266.967775) (xy 125.237493 -266.967775) (xy 125.229368 -267.01907) (xy 125.21332 -267.068463)
			(xy 125.189742 -267.114737) (xy 125.159216 -267.156753) (xy 125.122493 -267.193476) (xy 125.080477 -267.224002)
			(xy 125.034203 -267.24758) (xy 124.98481 -267.263628) (xy 124.933515 -267.271753) (xy 124.881581 -267.271753)
			(xy 124.830286 -267.263628) (xy 124.780893 -267.24758) (xy 124.734619 -267.224002) (xy 124.692603 -267.193476)
			(xy 124.65588 -267.156753) (xy 124.625354 -267.114737) (xy 124.601776 -267.068463) (xy 124.585728 -267.01907)
			(xy 124.577603 -266.967775) (xy 124.297693 -266.967775) (xy 124.289568 -267.01907) (xy 124.27352 -267.068463)
			(xy 124.249942 -267.114737) (xy 124.219416 -267.156753) (xy 124.182693 -267.193476) (xy 124.140677 -267.224002)
			(xy 124.094403 -267.24758) (xy 124.04501 -267.263628) (xy 123.993715 -267.271753) (xy 123.941781 -267.271753)
			(xy 123.890486 -267.263628) (xy 123.841093 -267.24758) (xy 123.794819 -267.224002) (xy 123.752803 -267.193476)
			(xy 123.71608 -267.156753) (xy 123.685554 -267.114737) (xy 123.661976 -267.068463) (xy 123.645928 -267.01907)
			(xy 123.637803 -266.967775) (xy 123.357893 -266.967775) (xy 123.349768 -267.01907) (xy 123.33372 -267.068463)
			(xy 123.310142 -267.114737) (xy 123.279616 -267.156753) (xy 123.242893 -267.193476) (xy 123.200877 -267.224002)
			(xy 123.154603 -267.24758) (xy 123.10521 -267.263628) (xy 123.053915 -267.271753) (xy 123.001981 -267.271753)
			(xy 122.950686 -267.263628) (xy 122.901293 -267.24758) (xy 122.855019 -267.224002) (xy 122.813003 -267.193476)
			(xy 122.77628 -267.156753) (xy 122.745754 -267.114737) (xy 122.722176 -267.068463) (xy 122.706128 -267.01907)
			(xy 122.698003 -266.967775) (xy 122.418093 -266.967775) (xy 122.409968 -267.01907) (xy 122.39392 -267.068463)
			(xy 122.370342 -267.114737) (xy 122.339816 -267.156753) (xy 122.303093 -267.193476) (xy 122.261077 -267.224002)
			(xy 122.214803 -267.24758) (xy 122.16541 -267.263628) (xy 122.114115 -267.271753) (xy 122.062181 -267.271753)
			(xy 122.010886 -267.263628) (xy 121.961493 -267.24758) (xy 121.915219 -267.224002) (xy 121.873203 -267.193476)
			(xy 121.83648 -267.156753) (xy 121.805954 -267.114737) (xy 121.782376 -267.068463) (xy 121.766328 -267.01907)
			(xy 121.758203 -266.967775) (xy 118.658385 -266.967775) (xy 118.65026 -267.01907) (xy 118.634212 -267.068463)
			(xy 118.610634 -267.114737) (xy 118.580108 -267.156753) (xy 118.543385 -267.193476) (xy 118.501369 -267.224002)
			(xy 118.455095 -267.24758) (xy 118.405702 -267.263628) (xy 118.354407 -267.271753) (xy 118.302473 -267.271753)
			(xy 118.251178 -267.263628) (xy 118.201785 -267.24758) (xy 118.155511 -267.224002) (xy 118.113495 -267.193476)
			(xy 118.076772 -267.156753) (xy 118.046246 -267.114737) (xy 118.022668 -267.068463) (xy 118.00662 -267.01907)
			(xy 117.998495 -266.967775) (xy 117.719086 -266.967775) (xy 117.711178 -267.018258) (xy 117.695466 -267.067181)
			(xy 117.672371 -267.113082) (xy 117.642451 -267.154857) (xy 117.606427 -267.191498) (xy 117.565167 -267.222123)
			(xy 117.519664 -267.245993) (xy 117.471015 -267.262534) (xy 117.44579 -267.267436) (xy 117.403626 -267.274802)
			(xy 117.403626 -267.781845) (xy 117.528849 -267.781845) (xy 117.528849 -267.729911) (xy 117.536974 -267.678616)
			(xy 117.553022 -267.629223) (xy 117.5766 -267.582949) (xy 117.607126 -267.540933) (xy 117.643849 -267.50421)
			(xy 117.685865 -267.473684) (xy 117.732139 -267.450106) (xy 117.781532 -267.434058) (xy 117.832827 -267.425933)
			(xy 117.884761 -267.425933) (xy 117.936056 -267.434058) (xy 117.985449 -267.450106) (xy 118.031723 -267.473684)
			(xy 118.073739 -267.50421) (xy 118.110462 -267.540933) (xy 118.140988 -267.582949) (xy 118.164566 -267.629223)
			(xy 118.180614 -267.678616) (xy 118.188739 -267.729911) (xy 118.189248 -267.755878) (xy 118.188739 -267.781845)
			(xy 119.408449 -267.781845) (xy 119.408449 -267.729911) (xy 119.416574 -267.678616) (xy 119.432622 -267.629223)
			(xy 119.4562 -267.582949) (xy 119.486726 -267.540933) (xy 119.523449 -267.50421) (xy 119.565465 -267.473684)
			(xy 119.611739 -267.450106) (xy 119.661132 -267.434058) (xy 119.712427 -267.425933) (xy 119.764361 -267.425933)
			(xy 119.815656 -267.434058) (xy 119.865049 -267.450106) (xy 119.911323 -267.473684) (xy 119.953339 -267.50421)
			(xy 119.990062 -267.540933) (xy 120.020588 -267.582949) (xy 120.044166 -267.629223) (xy 120.060214 -267.678616)
			(xy 120.068339 -267.729911) (xy 120.068848 -267.755878) (xy 120.068339 -267.781845) (xy 123.167649 -267.781845)
			(xy 123.167649 -267.729911) (xy 123.175774 -267.678616) (xy 123.191822 -267.629223) (xy 123.2154 -267.582949)
			(xy 123.245926 -267.540933) (xy 123.282649 -267.50421) (xy 123.324665 -267.473684) (xy 123.370939 -267.450106)
			(xy 123.420332 -267.434058) (xy 123.471627 -267.425933) (xy 123.523561 -267.425933) (xy 123.574856 -267.434058)
			(xy 123.624249 -267.450106) (xy 123.670523 -267.473684) (xy 123.712539 -267.50421) (xy 123.749262 -267.540933)
			(xy 123.779788 -267.582949) (xy 123.803366 -267.629223) (xy 123.819414 -267.678616) (xy 123.827539 -267.729911)
			(xy 123.828048 -267.755878) (xy 123.827539 -267.781845) (xy 124.107449 -267.781845) (xy 124.107449 -267.729911)
			(xy 124.115574 -267.678616) (xy 124.131622 -267.629223) (xy 124.1552 -267.582949) (xy 124.185726 -267.540933)
			(xy 124.222449 -267.50421) (xy 124.264465 -267.473684) (xy 124.310739 -267.450106) (xy 124.360132 -267.434058)
			(xy 124.411427 -267.425933) (xy 124.463361 -267.425933) (xy 124.514656 -267.434058) (xy 124.564049 -267.450106)
			(xy 124.610323 -267.473684) (xy 124.652339 -267.50421) (xy 124.689062 -267.540933) (xy 124.719588 -267.582949)
			(xy 124.743166 -267.629223) (xy 124.759214 -267.678616) (xy 124.767339 -267.729911) (xy 124.767848 -267.755878)
			(xy 124.767339 -267.781845) (xy 125.047249 -267.781845) (xy 125.047249 -267.729911) (xy 125.055374 -267.678616)
			(xy 125.071422 -267.629223) (xy 125.095 -267.582949) (xy 125.125526 -267.540933) (xy 125.162249 -267.50421)
			(xy 125.204265 -267.473684) (xy 125.250539 -267.450106) (xy 125.299932 -267.434058) (xy 125.351227 -267.425933)
			(xy 125.403161 -267.425933) (xy 125.454456 -267.434058) (xy 125.503849 -267.450106) (xy 125.550123 -267.473684)
			(xy 125.592139 -267.50421) (xy 125.628862 -267.540933) (xy 125.659388 -267.582949) (xy 125.682966 -267.629223)
			(xy 125.699014 -267.678616) (xy 125.707139 -267.729911) (xy 125.707648 -267.755878) (xy 125.707139 -267.781845)
			(xy 125.987049 -267.781845) (xy 125.987049 -267.729911) (xy 125.995174 -267.678616) (xy 126.011222 -267.629223)
			(xy 126.0348 -267.582949) (xy 126.065326 -267.540933) (xy 126.102049 -267.50421) (xy 126.144065 -267.473684)
			(xy 126.190339 -267.450106) (xy 126.239732 -267.434058) (xy 126.291027 -267.425933) (xy 126.342961 -267.425933)
			(xy 126.394256 -267.434058) (xy 126.443649 -267.450106) (xy 126.489923 -267.473684) (xy 126.531939 -267.50421)
			(xy 126.568662 -267.540933) (xy 126.599188 -267.582949) (xy 126.622766 -267.629223) (xy 126.638814 -267.678616)
			(xy 126.646939 -267.729911) (xy 126.647448 -267.755878) (xy 126.646939 -267.781845) (xy 126.638814 -267.83314)
			(xy 126.622766 -267.882533) (xy 126.599188 -267.928807) (xy 126.568662 -267.970823) (xy 126.531939 -268.007546)
			(xy 126.489923 -268.038072) (xy 126.443649 -268.06165) (xy 126.394256 -268.077698) (xy 126.342961 -268.085823)
			(xy 126.291027 -268.085823) (xy 126.239732 -268.077698) (xy 126.190339 -268.06165) (xy 126.144065 -268.038072)
			(xy 126.102049 -268.007546) (xy 126.065326 -267.970823) (xy 126.0348 -267.928807) (xy 126.011222 -267.882533)
			(xy 125.995174 -267.83314) (xy 125.987049 -267.781845) (xy 125.707139 -267.781845) (xy 125.699014 -267.83314)
			(xy 125.682966 -267.882533) (xy 125.659388 -267.928807) (xy 125.628862 -267.970823) (xy 125.592139 -268.007546)
			(xy 125.550123 -268.038072) (xy 125.503849 -268.06165) (xy 125.454456 -268.077698) (xy 125.403161 -268.085823)
			(xy 125.351227 -268.085823) (xy 125.299932 -268.077698) (xy 125.250539 -268.06165) (xy 125.204265 -268.038072)
			(xy 125.162249 -268.007546) (xy 125.125526 -267.970823) (xy 125.095 -267.928807) (xy 125.071422 -267.882533)
			(xy 125.055374 -267.83314) (xy 125.047249 -267.781845) (xy 124.767339 -267.781845) (xy 124.759214 -267.83314)
			(xy 124.743166 -267.882533) (xy 124.719588 -267.928807) (xy 124.689062 -267.970823) (xy 124.652339 -268.007546)
			(xy 124.610323 -268.038072) (xy 124.564049 -268.06165) (xy 124.514656 -268.077698) (xy 124.463361 -268.085823)
			(xy 124.411427 -268.085823) (xy 124.360132 -268.077698) (xy 124.310739 -268.06165) (xy 124.264465 -268.038072)
			(xy 124.222449 -268.007546) (xy 124.185726 -267.970823) (xy 124.1552 -267.928807) (xy 124.131622 -267.882533)
			(xy 124.115574 -267.83314) (xy 124.107449 -267.781845) (xy 123.827539 -267.781845) (xy 123.819414 -267.83314)
			(xy 123.803366 -267.882533) (xy 123.779788 -267.928807) (xy 123.749262 -267.970823) (xy 123.712539 -268.007546)
			(xy 123.670523 -268.038072) (xy 123.624249 -268.06165) (xy 123.574856 -268.077698) (xy 123.523561 -268.085823)
			(xy 123.471627 -268.085823) (xy 123.420332 -268.077698) (xy 123.370939 -268.06165) (xy 123.324665 -268.038072)
			(xy 123.282649 -268.007546) (xy 123.245926 -267.970823) (xy 123.2154 -267.928807) (xy 123.191822 -267.882533)
			(xy 123.175774 -267.83314) (xy 123.167649 -267.781845) (xy 120.068339 -267.781845) (xy 120.060214 -267.83314)
			(xy 120.044166 -267.882533) (xy 120.020588 -267.928807) (xy 119.990062 -267.970823) (xy 119.953339 -268.007546)
			(xy 119.911323 -268.038072) (xy 119.865049 -268.06165) (xy 119.815656 -268.077698) (xy 119.764361 -268.085823)
			(xy 119.712427 -268.085823) (xy 119.661132 -268.077698) (xy 119.611739 -268.06165) (xy 119.565465 -268.038072)
			(xy 119.523449 -268.007546) (xy 119.486726 -267.970823) (xy 119.4562 -267.928807) (xy 119.432622 -267.882533)
			(xy 119.416574 -267.83314) (xy 119.408449 -267.781845) (xy 118.188739 -267.781845) (xy 118.180614 -267.83314)
			(xy 118.164566 -267.882533) (xy 118.140988 -267.928807) (xy 118.110462 -267.970823) (xy 118.073739 -268.007546)
			(xy 118.031723 -268.038072) (xy 117.985449 -268.06165) (xy 117.936056 -268.077698) (xy 117.884761 -268.085823)
			(xy 117.832827 -268.085823) (xy 117.781532 -268.077698) (xy 117.732139 -268.06165) (xy 117.685865 -268.038072)
			(xy 117.643849 -268.007546) (xy 117.607126 -267.970823) (xy 117.5766 -267.928807) (xy 117.553022 -267.882533)
			(xy 117.536974 -267.83314) (xy 117.528849 -267.781845) (xy 117.403626 -267.781845) (xy 117.403626 -268.2367)
			(xy 117.44579 -268.244066) (xy 117.470991 -268.248985) (xy 117.519581 -268.265578) (xy 117.565022 -268.289483)
			(xy 117.60622 -268.320125) (xy 117.642187 -268.356768) (xy 117.672056 -268.39853) (xy 117.69511 -268.444409)
			(xy 117.710794 -268.493299) (xy 117.718732 -268.544027) (xy 117.718732 -268.595371) (xy 117.718687 -268.595661)
			(xy 117.999003 -268.595661) (xy 117.999003 -268.543727) (xy 118.007128 -268.492432) (xy 118.023176 -268.443039)
			(xy 118.046754 -268.396765) (xy 118.07728 -268.354749) (xy 118.114003 -268.318026) (xy 118.156019 -268.2875)
			(xy 118.202293 -268.263922) (xy 118.251686 -268.247874) (xy 118.302981 -268.239749) (xy 118.354915 -268.239749)
			(xy 118.40621 -268.247874) (xy 118.455603 -268.263922) (xy 118.501877 -268.2875) (xy 118.543893 -268.318026)
			(xy 118.580616 -268.354749) (xy 118.611142 -268.396765) (xy 118.63472 -268.443039) (xy 118.650768 -268.492432)
			(xy 118.658893 -268.543727) (xy 118.659402 -268.569694) (xy 118.658893 -268.595661) (xy 122.697749 -268.595661)
			(xy 122.697749 -268.543727) (xy 122.705874 -268.492432) (xy 122.721922 -268.443039) (xy 122.7455 -268.396765)
			(xy 122.776026 -268.354749) (xy 122.812749 -268.318026) (xy 122.854765 -268.2875) (xy 122.901039 -268.263922)
			(xy 122.950432 -268.247874) (xy 123.001727 -268.239749) (xy 123.053661 -268.239749) (xy 123.104956 -268.247874)
			(xy 123.154349 -268.263922) (xy 123.200623 -268.2875) (xy 123.242639 -268.318026) (xy 123.279362 -268.354749)
			(xy 123.309888 -268.396765) (xy 123.333466 -268.443039) (xy 123.349514 -268.492432) (xy 123.357639 -268.543727)
			(xy 123.358148 -268.569694) (xy 123.357639 -268.595661) (xy 123.637803 -268.595661) (xy 123.637803 -268.543727)
			(xy 123.645928 -268.492432) (xy 123.661976 -268.443039) (xy 123.685554 -268.396765) (xy 123.71608 -268.354749)
			(xy 123.752803 -268.318026) (xy 123.794819 -268.2875) (xy 123.841093 -268.263922) (xy 123.890486 -268.247874)
			(xy 123.941781 -268.239749) (xy 123.993715 -268.239749) (xy 124.04501 -268.247874) (xy 124.094403 -268.263922)
			(xy 124.140677 -268.2875) (xy 124.182693 -268.318026) (xy 124.219416 -268.354749) (xy 124.249942 -268.396765)
			(xy 124.27352 -268.443039) (xy 124.289568 -268.492432) (xy 124.297693 -268.543727) (xy 124.298202 -268.569694)
			(xy 124.297693 -268.595661) (xy 124.577603 -268.595661) (xy 124.577603 -268.543727) (xy 124.585728 -268.492432)
			(xy 124.601776 -268.443039) (xy 124.625354 -268.396765) (xy 124.65588 -268.354749) (xy 124.692603 -268.318026)
			(xy 124.734619 -268.2875) (xy 124.780893 -268.263922) (xy 124.830286 -268.247874) (xy 124.881581 -268.239749)
			(xy 124.933515 -268.239749) (xy 124.98481 -268.247874) (xy 125.034203 -268.263922) (xy 125.080477 -268.2875)
			(xy 125.122493 -268.318026) (xy 125.159216 -268.354749) (xy 125.189742 -268.396765) (xy 125.21332 -268.443039)
			(xy 125.229368 -268.492432) (xy 125.237493 -268.543727) (xy 125.238002 -268.569694) (xy 125.237493 -268.595661)
			(xy 125.517403 -268.595661) (xy 125.517403 -268.543727) (xy 125.525528 -268.492432) (xy 125.541576 -268.443039)
			(xy 125.565154 -268.396765) (xy 125.59568 -268.354749) (xy 125.632403 -268.318026) (xy 125.674419 -268.2875)
			(xy 125.720693 -268.263922) (xy 125.770086 -268.247874) (xy 125.821381 -268.239749) (xy 125.873315 -268.239749)
			(xy 125.92461 -268.247874) (xy 125.974003 -268.263922) (xy 126.020277 -268.2875) (xy 126.062293 -268.318026)
			(xy 126.099016 -268.354749) (xy 126.129542 -268.396765) (xy 126.15312 -268.443039) (xy 126.169168 -268.492432)
			(xy 126.177293 -268.543727) (xy 126.177802 -268.569694) (xy 126.177293 -268.595661) (xy 126.169168 -268.646956)
			(xy 126.15312 -268.696349) (xy 126.129542 -268.742623) (xy 126.099016 -268.784639) (xy 126.062293 -268.821362)
			(xy 126.020277 -268.851888) (xy 125.974003 -268.875466) (xy 125.92461 -268.891514) (xy 125.873315 -268.899639)
			(xy 125.821381 -268.899639) (xy 125.770086 -268.891514) (xy 125.720693 -268.875466) (xy 125.674419 -268.851888)
			(xy 125.632403 -268.821362) (xy 125.59568 -268.784639) (xy 125.565154 -268.742623) (xy 125.541576 -268.696349)
			(xy 125.525528 -268.646956) (xy 125.517403 -268.595661) (xy 125.237493 -268.595661) (xy 125.229368 -268.646956)
			(xy 125.21332 -268.696349) (xy 125.189742 -268.742623) (xy 125.159216 -268.784639) (xy 125.122493 -268.821362)
			(xy 125.080477 -268.851888) (xy 125.034203 -268.875466) (xy 124.98481 -268.891514) (xy 124.933515 -268.899639)
			(xy 124.881581 -268.899639) (xy 124.830286 -268.891514) (xy 124.780893 -268.875466) (xy 124.734619 -268.851888)
			(xy 124.692603 -268.821362) (xy 124.65588 -268.784639) (xy 124.625354 -268.742623) (xy 124.601776 -268.696349)
			(xy 124.585728 -268.646956) (xy 124.577603 -268.595661) (xy 124.297693 -268.595661) (xy 124.289568 -268.646956)
			(xy 124.27352 -268.696349) (xy 124.249942 -268.742623) (xy 124.219416 -268.784639) (xy 124.182693 -268.821362)
			(xy 124.140677 -268.851888) (xy 124.094403 -268.875466) (xy 124.04501 -268.891514) (xy 123.993715 -268.899639)
			(xy 123.941781 -268.899639) (xy 123.890486 -268.891514) (xy 123.841093 -268.875466) (xy 123.794819 -268.851888)
			(xy 123.752803 -268.821362) (xy 123.71608 -268.784639) (xy 123.685554 -268.742623) (xy 123.661976 -268.696349)
			(xy 123.645928 -268.646956) (xy 123.637803 -268.595661) (xy 123.357639 -268.595661) (xy 123.349514 -268.646956)
			(xy 123.333466 -268.696349) (xy 123.309888 -268.742623) (xy 123.279362 -268.784639) (xy 123.242639 -268.821362)
			(xy 123.200623 -268.851888) (xy 123.154349 -268.875466) (xy 123.104956 -268.891514) (xy 123.053661 -268.899639)
			(xy 123.001727 -268.899639) (xy 122.950432 -268.891514) (xy 122.901039 -268.875466) (xy 122.854765 -268.851888)
			(xy 122.812749 -268.821362) (xy 122.776026 -268.784639) (xy 122.7455 -268.742623) (xy 122.721922 -268.696349)
			(xy 122.705874 -268.646956) (xy 122.697749 -268.595661) (xy 118.658893 -268.595661) (xy 118.650768 -268.646956)
			(xy 118.63472 -268.696349) (xy 118.611142 -268.742623) (xy 118.580616 -268.784639) (xy 118.543893 -268.821362)
			(xy 118.501877 -268.851888) (xy 118.455603 -268.875466) (xy 118.40621 -268.891514) (xy 118.354915 -268.899639)
			(xy 118.302981 -268.899639) (xy 118.251686 -268.891514) (xy 118.202293 -268.875466) (xy 118.156019 -268.851888)
			(xy 118.114003 -268.821362) (xy 118.07728 -268.784639) (xy 118.046754 -268.742623) (xy 118.023176 -268.696349)
			(xy 118.007128 -268.646956) (xy 117.999003 -268.595661) (xy 117.718687 -268.595661) (xy 117.710795 -268.646099)
			(xy 117.695111 -268.69499) (xy 117.672057 -268.740868) (xy 117.642188 -268.782631) (xy 117.606222 -268.819274)
			(xy 117.565023 -268.849916) (xy 117.519583 -268.873821) (xy 117.470993 -268.890414) (xy 117.44579 -268.895322)
			(xy 117.403626 -268.902688) (xy 117.403626 -269.409477) (xy 117.529103 -269.409477) (xy 117.529103 -269.357543)
			(xy 117.537228 -269.306248) (xy 117.553276 -269.256855) (xy 117.576854 -269.210581) (xy 117.60738 -269.168565)
			(xy 117.644103 -269.131842) (xy 117.686119 -269.101316) (xy 117.732393 -269.077738) (xy 117.781786 -269.06169)
			(xy 117.833081 -269.053565) (xy 117.885015 -269.053565) (xy 117.93631 -269.06169) (xy 117.985703 -269.077738)
			(xy 118.031977 -269.101316) (xy 118.073993 -269.131842) (xy 118.110716 -269.168565) (xy 118.141242 -269.210581)
			(xy 118.16482 -269.256855) (xy 118.180868 -269.306248) (xy 118.188993 -269.357543) (xy 118.189502 -269.38351)
			(xy 118.188993 -269.409477) (xy 120.348249 -269.409477) (xy 120.348249 -269.357543) (xy 120.356374 -269.306248)
			(xy 120.372422 -269.256855) (xy 120.396 -269.210581) (xy 120.426526 -269.168565) (xy 120.463249 -269.131842)
			(xy 120.505265 -269.101316) (xy 120.551539 -269.077738) (xy 120.600932 -269.06169) (xy 120.652227 -269.053565)
			(xy 120.704161 -269.053565) (xy 120.755456 -269.06169) (xy 120.804849 -269.077738) (xy 120.851123 -269.101316)
			(xy 120.893139 -269.131842) (xy 120.929862 -269.168565) (xy 120.960388 -269.210581) (xy 120.983966 -269.256855)
			(xy 121.000014 -269.306248) (xy 121.008139 -269.357543) (xy 121.008648 -269.38351) (xy 121.008139 -269.409477)
			(xy 122.227849 -269.409477) (xy 122.227849 -269.357543) (xy 122.235974 -269.306248) (xy 122.252022 -269.256855)
			(xy 122.2756 -269.210581) (xy 122.306126 -269.168565) (xy 122.342849 -269.131842) (xy 122.384865 -269.101316)
			(xy 122.431139 -269.077738) (xy 122.480532 -269.06169) (xy 122.531827 -269.053565) (xy 122.583761 -269.053565)
			(xy 122.635056 -269.06169) (xy 122.684449 -269.077738) (xy 122.730723 -269.101316) (xy 122.772739 -269.131842)
			(xy 122.809462 -269.168565) (xy 122.839988 -269.210581) (xy 122.863566 -269.256855) (xy 122.879614 -269.306248)
			(xy 122.887739 -269.357543) (xy 122.888248 -269.38351) (xy 122.887739 -269.409477) (xy 123.167649 -269.409477)
			(xy 123.167649 -269.357543) (xy 123.175774 -269.306248) (xy 123.191822 -269.256855) (xy 123.2154 -269.210581)
			(xy 123.245926 -269.168565) (xy 123.282649 -269.131842) (xy 123.324665 -269.101316) (xy 123.370939 -269.077738)
			(xy 123.420332 -269.06169) (xy 123.471627 -269.053565) (xy 123.523561 -269.053565) (xy 123.574856 -269.06169)
			(xy 123.624249 -269.077738) (xy 123.670523 -269.101316) (xy 123.712539 -269.131842) (xy 123.749262 -269.168565)
			(xy 123.779788 -269.210581) (xy 123.803366 -269.256855) (xy 123.819414 -269.306248) (xy 123.827539 -269.357543)
			(xy 123.828048 -269.38351) (xy 123.827539 -269.409477) (xy 124.107449 -269.409477) (xy 124.107449 -269.357543)
			(xy 124.115574 -269.306248) (xy 124.131622 -269.256855) (xy 124.1552 -269.210581) (xy 124.185726 -269.168565)
			(xy 124.222449 -269.131842) (xy 124.264465 -269.101316) (xy 124.310739 -269.077738) (xy 124.360132 -269.06169)
			(xy 124.411427 -269.053565) (xy 124.463361 -269.053565) (xy 124.514656 -269.06169) (xy 124.564049 -269.077738)
			(xy 124.610323 -269.101316) (xy 124.652339 -269.131842) (xy 124.689062 -269.168565) (xy 124.719588 -269.210581)
			(xy 124.743166 -269.256855) (xy 124.759214 -269.306248) (xy 124.767339 -269.357543) (xy 124.767848 -269.38351)
			(xy 124.767339 -269.409477) (xy 125.047249 -269.409477) (xy 125.047249 -269.357543) (xy 125.055374 -269.306248)
			(xy 125.071422 -269.256855) (xy 125.095 -269.210581) (xy 125.125526 -269.168565) (xy 125.162249 -269.131842)
			(xy 125.204265 -269.101316) (xy 125.250539 -269.077738) (xy 125.299932 -269.06169) (xy 125.351227 -269.053565)
			(xy 125.403161 -269.053565) (xy 125.454456 -269.06169) (xy 125.503849 -269.077738) (xy 125.550123 -269.101316)
			(xy 125.592139 -269.131842) (xy 125.628862 -269.168565) (xy 125.659388 -269.210581) (xy 125.682966 -269.256855)
			(xy 125.699014 -269.306248) (xy 125.707139 -269.357543) (xy 125.707648 -269.38351) (xy 125.707139 -269.409477)
			(xy 125.987049 -269.409477) (xy 125.987049 -269.357543) (xy 125.995174 -269.306248) (xy 126.011222 -269.256855)
			(xy 126.0348 -269.210581) (xy 126.065326 -269.168565) (xy 126.102049 -269.131842) (xy 126.144065 -269.101316)
			(xy 126.190339 -269.077738) (xy 126.239732 -269.06169) (xy 126.291027 -269.053565) (xy 126.342961 -269.053565)
			(xy 126.394256 -269.06169) (xy 126.443649 -269.077738) (xy 126.489923 -269.101316) (xy 126.531939 -269.131842)
			(xy 126.568662 -269.168565) (xy 126.599188 -269.210581) (xy 126.622766 -269.256855) (xy 126.638814 -269.306248)
			(xy 126.646939 -269.357543) (xy 126.647448 -269.38351) (xy 126.646939 -269.409477) (xy 126.638814 -269.460772)
			(xy 126.622766 -269.510165) (xy 126.599188 -269.556439) (xy 126.568662 -269.598455) (xy 126.531939 -269.635178)
			(xy 126.489923 -269.665704) (xy 126.443649 -269.689282) (xy 126.394256 -269.70533) (xy 126.342961 -269.713455)
			(xy 126.291027 -269.713455) (xy 126.239732 -269.70533) (xy 126.190339 -269.689282) (xy 126.144065 -269.665704)
			(xy 126.102049 -269.635178) (xy 126.065326 -269.598455) (xy 126.0348 -269.556439) (xy 126.011222 -269.510165)
			(xy 125.995174 -269.460772) (xy 125.987049 -269.409477) (xy 125.707139 -269.409477) (xy 125.699014 -269.460772)
			(xy 125.682966 -269.510165) (xy 125.659388 -269.556439) (xy 125.628862 -269.598455) (xy 125.592139 -269.635178)
			(xy 125.550123 -269.665704) (xy 125.503849 -269.689282) (xy 125.454456 -269.70533) (xy 125.403161 -269.713455)
			(xy 125.351227 -269.713455) (xy 125.299932 -269.70533) (xy 125.250539 -269.689282) (xy 125.204265 -269.665704)
			(xy 125.162249 -269.635178) (xy 125.125526 -269.598455) (xy 125.095 -269.556439) (xy 125.071422 -269.510165)
			(xy 125.055374 -269.460772) (xy 125.047249 -269.409477) (xy 124.767339 -269.409477) (xy 124.759214 -269.460772)
			(xy 124.743166 -269.510165) (xy 124.719588 -269.556439) (xy 124.689062 -269.598455) (xy 124.652339 -269.635178)
			(xy 124.610323 -269.665704) (xy 124.564049 -269.689282) (xy 124.514656 -269.70533) (xy 124.463361 -269.713455)
			(xy 124.411427 -269.713455) (xy 124.360132 -269.70533) (xy 124.310739 -269.689282) (xy 124.264465 -269.665704)
			(xy 124.222449 -269.635178) (xy 124.185726 -269.598455) (xy 124.1552 -269.556439) (xy 124.131622 -269.510165)
			(xy 124.115574 -269.460772) (xy 124.107449 -269.409477) (xy 123.827539 -269.409477) (xy 123.819414 -269.460772)
			(xy 123.803366 -269.510165) (xy 123.779788 -269.556439) (xy 123.749262 -269.598455) (xy 123.712539 -269.635178)
			(xy 123.670523 -269.665704) (xy 123.624249 -269.689282) (xy 123.574856 -269.70533) (xy 123.523561 -269.713455)
			(xy 123.471627 -269.713455) (xy 123.420332 -269.70533) (xy 123.370939 -269.689282) (xy 123.324665 -269.665704)
			(xy 123.282649 -269.635178) (xy 123.245926 -269.598455) (xy 123.2154 -269.556439) (xy 123.191822 -269.510165)
			(xy 123.175774 -269.460772) (xy 123.167649 -269.409477) (xy 122.887739 -269.409477) (xy 122.879614 -269.460772)
			(xy 122.863566 -269.510165) (xy 122.839988 -269.556439) (xy 122.809462 -269.598455) (xy 122.772739 -269.635178)
			(xy 122.730723 -269.665704) (xy 122.684449 -269.689282) (xy 122.635056 -269.70533) (xy 122.583761 -269.713455)
			(xy 122.531827 -269.713455) (xy 122.480532 -269.70533) (xy 122.431139 -269.689282) (xy 122.384865 -269.665704)
			(xy 122.342849 -269.635178) (xy 122.306126 -269.598455) (xy 122.2756 -269.556439) (xy 122.252022 -269.510165)
			(xy 122.235974 -269.460772) (xy 122.227849 -269.409477) (xy 121.008139 -269.409477) (xy 121.000014 -269.460772)
			(xy 120.983966 -269.510165) (xy 120.960388 -269.556439) (xy 120.929862 -269.598455) (xy 120.893139 -269.635178)
			(xy 120.851123 -269.665704) (xy 120.804849 -269.689282) (xy 120.755456 -269.70533) (xy 120.704161 -269.713455)
			(xy 120.652227 -269.713455) (xy 120.600932 -269.70533) (xy 120.551539 -269.689282) (xy 120.505265 -269.665704)
			(xy 120.463249 -269.635178) (xy 120.426526 -269.598455) (xy 120.396 -269.556439) (xy 120.372422 -269.510165)
			(xy 120.356374 -269.460772) (xy 120.348249 -269.409477) (xy 118.188993 -269.409477) (xy 118.180868 -269.460772)
			(xy 118.16482 -269.510165) (xy 118.141242 -269.556439) (xy 118.110716 -269.598455) (xy 118.073993 -269.635178)
			(xy 118.031977 -269.665704) (xy 117.985703 -269.689282) (xy 117.93631 -269.70533) (xy 117.885015 -269.713455)
			(xy 117.833081 -269.713455) (xy 117.781786 -269.70533) (xy 117.732393 -269.689282) (xy 117.686119 -269.665704)
			(xy 117.644103 -269.635178) (xy 117.60738 -269.598455) (xy 117.576854 -269.556439) (xy 117.553276 -269.510165)
			(xy 117.537228 -269.460772) (xy 117.529103 -269.409477) (xy 117.403626 -269.409477) (xy 117.403626 -269.864586)
			(xy 117.44579 -269.871952) (xy 117.470992 -269.876871) (xy 117.519584 -269.893464) (xy 117.565027 -269.91737)
			(xy 117.606228 -269.948013) (xy 117.642196 -269.984657) (xy 117.672067 -270.026421) (xy 117.695122 -270.072301)
			(xy 117.710807 -270.121194) (xy 117.718746 -270.171923) (xy 117.718746 -270.22327) (xy 117.718703 -270.223547)
			(xy 117.999003 -270.223547) (xy 117.999003 -270.171613) (xy 118.007128 -270.120318) (xy 118.023176 -270.070925)
			(xy 118.046754 -270.024651) (xy 118.07728 -269.982635) (xy 118.114003 -269.945912) (xy 118.156019 -269.915386)
			(xy 118.202293 -269.891808) (xy 118.251686 -269.87576) (xy 118.302981 -269.867635) (xy 118.354915 -269.867635)
			(xy 118.40621 -269.87576) (xy 118.455603 -269.891808) (xy 118.501877 -269.915386) (xy 118.543893 -269.945912)
			(xy 118.580616 -269.982635) (xy 118.611142 -270.024651) (xy 118.63472 -270.070925) (xy 118.650768 -270.120318)
			(xy 118.658893 -270.171613) (xy 118.659402 -270.19758) (xy 118.658893 -270.223547) (xy 122.698003 -270.223547)
			(xy 122.698003 -270.171613) (xy 122.706128 -270.120318) (xy 122.722176 -270.070925) (xy 122.745754 -270.024651)
			(xy 122.77628 -269.982635) (xy 122.813003 -269.945912) (xy 122.855019 -269.915386) (xy 122.901293 -269.891808)
			(xy 122.950686 -269.87576) (xy 123.001981 -269.867635) (xy 123.053915 -269.867635) (xy 123.10521 -269.87576)
			(xy 123.154603 -269.891808) (xy 123.200877 -269.915386) (xy 123.242893 -269.945912) (xy 123.279616 -269.982635)
			(xy 123.310142 -270.024651) (xy 123.33372 -270.070925) (xy 123.349768 -270.120318) (xy 123.357893 -270.171613)
			(xy 123.358402 -270.19758) (xy 123.357893 -270.223547) (xy 123.637803 -270.223547) (xy 123.637803 -270.171613)
			(xy 123.645928 -270.120318) (xy 123.661976 -270.070925) (xy 123.685554 -270.024651) (xy 123.71608 -269.982635)
			(xy 123.752803 -269.945912) (xy 123.794819 -269.915386) (xy 123.841093 -269.891808) (xy 123.890486 -269.87576)
			(xy 123.941781 -269.867635) (xy 123.993715 -269.867635) (xy 124.04501 -269.87576) (xy 124.094403 -269.891808)
			(xy 124.140677 -269.915386) (xy 124.182693 -269.945912) (xy 124.219416 -269.982635) (xy 124.249942 -270.024651)
			(xy 124.27352 -270.070925) (xy 124.289568 -270.120318) (xy 124.297693 -270.171613) (xy 124.298202 -270.19758)
			(xy 124.297693 -270.223547) (xy 124.577603 -270.223547) (xy 124.577603 -270.171613) (xy 124.585728 -270.120318)
			(xy 124.601776 -270.070925) (xy 124.625354 -270.024651) (xy 124.65588 -269.982635) (xy 124.692603 -269.945912)
			(xy 124.734619 -269.915386) (xy 124.780893 -269.891808) (xy 124.830286 -269.87576) (xy 124.881581 -269.867635)
			(xy 124.933515 -269.867635) (xy 124.98481 -269.87576) (xy 125.034203 -269.891808) (xy 125.080477 -269.915386)
			(xy 125.122493 -269.945912) (xy 125.159216 -269.982635) (xy 125.189742 -270.024651) (xy 125.21332 -270.070925)
			(xy 125.229368 -270.120318) (xy 125.237493 -270.171613) (xy 125.238002 -270.19758) (xy 125.237493 -270.223547)
			(xy 125.517403 -270.223547) (xy 125.517403 -270.171613) (xy 125.525528 -270.120318) (xy 125.541576 -270.070925)
			(xy 125.565154 -270.024651) (xy 125.59568 -269.982635) (xy 125.632403 -269.945912) (xy 125.674419 -269.915386)
			(xy 125.720693 -269.891808) (xy 125.770086 -269.87576) (xy 125.821381 -269.867635) (xy 125.873315 -269.867635)
			(xy 125.92461 -269.87576) (xy 125.974003 -269.891808) (xy 126.020277 -269.915386) (xy 126.062293 -269.945912)
			(xy 126.099016 -269.982635) (xy 126.129542 -270.024651) (xy 126.15312 -270.070925) (xy 126.169168 -270.120318)
			(xy 126.177293 -270.171613) (xy 126.177802 -270.19758) (xy 126.177293 -270.223547) (xy 126.169168 -270.274842)
			(xy 126.15312 -270.324235) (xy 126.129542 -270.370509) (xy 126.099016 -270.412525) (xy 126.062293 -270.449248)
			(xy 126.020277 -270.479774) (xy 125.974003 -270.503352) (xy 125.92461 -270.5194) (xy 125.873315 -270.527525)
			(xy 125.821381 -270.527525) (xy 125.770086 -270.5194) (xy 125.720693 -270.503352) (xy 125.674419 -270.479774)
			(xy 125.632403 -270.449248) (xy 125.59568 -270.412525) (xy 125.565154 -270.370509) (xy 125.541576 -270.324235)
			(xy 125.525528 -270.274842) (xy 125.517403 -270.223547) (xy 125.237493 -270.223547) (xy 125.229368 -270.274842)
			(xy 125.21332 -270.324235) (xy 125.189742 -270.370509) (xy 125.159216 -270.412525) (xy 125.122493 -270.449248)
			(xy 125.080477 -270.479774) (xy 125.034203 -270.503352) (xy 124.98481 -270.5194) (xy 124.933515 -270.527525)
			(xy 124.881581 -270.527525) (xy 124.830286 -270.5194) (xy 124.780893 -270.503352) (xy 124.734619 -270.479774)
			(xy 124.692603 -270.449248) (xy 124.65588 -270.412525) (xy 124.625354 -270.370509) (xy 124.601776 -270.324235)
			(xy 124.585728 -270.274842) (xy 124.577603 -270.223547) (xy 124.297693 -270.223547) (xy 124.289568 -270.274842)
			(xy 124.27352 -270.324235) (xy 124.249942 -270.370509) (xy 124.219416 -270.412525) (xy 124.182693 -270.449248)
			(xy 124.140677 -270.479774) (xy 124.094403 -270.503352) (xy 124.04501 -270.5194) (xy 123.993715 -270.527525)
			(xy 123.941781 -270.527525) (xy 123.890486 -270.5194) (xy 123.841093 -270.503352) (xy 123.794819 -270.479774)
			(xy 123.752803 -270.449248) (xy 123.71608 -270.412525) (xy 123.685554 -270.370509) (xy 123.661976 -270.324235)
			(xy 123.645928 -270.274842) (xy 123.637803 -270.223547) (xy 123.357893 -270.223547) (xy 123.349768 -270.274842)
			(xy 123.33372 -270.324235) (xy 123.310142 -270.370509) (xy 123.279616 -270.412525) (xy 123.242893 -270.449248)
			(xy 123.200877 -270.479774) (xy 123.154603 -270.503352) (xy 123.10521 -270.5194) (xy 123.053915 -270.527525)
			(xy 123.001981 -270.527525) (xy 122.950686 -270.5194) (xy 122.901293 -270.503352) (xy 122.855019 -270.479774)
			(xy 122.813003 -270.449248) (xy 122.77628 -270.412525) (xy 122.745754 -270.370509) (xy 122.722176 -270.324235)
			(xy 122.706128 -270.274842) (xy 122.698003 -270.223547) (xy 118.658893 -270.223547) (xy 118.650768 -270.274842)
			(xy 118.63472 -270.324235) (xy 118.611142 -270.370509) (xy 118.580616 -270.412525) (xy 118.543893 -270.449248)
			(xy 118.501877 -270.479774) (xy 118.455603 -270.503352) (xy 118.40621 -270.5194) (xy 118.354915 -270.527525)
			(xy 118.302981 -270.527525) (xy 118.251686 -270.5194) (xy 118.202293 -270.503352) (xy 118.156019 -270.479774)
			(xy 118.114003 -270.449248) (xy 118.07728 -270.412525) (xy 118.046754 -270.370509) (xy 118.023176 -270.324235)
			(xy 118.007128 -270.274842) (xy 117.999003 -270.223547) (xy 117.718703 -270.223547) (xy 117.710809 -270.274)
			(xy 117.695125 -270.322892) (xy 117.67207 -270.368773) (xy 117.6422 -270.410538) (xy 117.606233 -270.447182)
			(xy 117.565033 -270.477827) (xy 117.519591 -270.501733) (xy 117.470999 -270.518327) (xy 117.44579 -270.523208)
			(xy 117.403626 -270.530574) (xy 117.403626 -271.037363) (xy 117.528849 -271.037363) (xy 117.528849 -270.985429)
			(xy 117.536974 -270.934134) (xy 117.553022 -270.884741) (xy 117.5766 -270.838467) (xy 117.607126 -270.796451)
			(xy 117.643849 -270.759728) (xy 117.685865 -270.729202) (xy 117.732139 -270.705624) (xy 117.781532 -270.689576)
			(xy 117.832827 -270.681451) (xy 117.884761 -270.681451) (xy 117.936056 -270.689576) (xy 117.985449 -270.705624)
			(xy 118.031723 -270.729202) (xy 118.073739 -270.759728) (xy 118.110462 -270.796451) (xy 118.140988 -270.838467)
			(xy 118.164566 -270.884741) (xy 118.180614 -270.934134) (xy 118.188739 -270.985429) (xy 118.189248 -271.011396)
			(xy 118.188739 -271.037363) (xy 118.468649 -271.037363) (xy 118.468649 -270.985429) (xy 118.476774 -270.934134)
			(xy 118.492822 -270.884741) (xy 118.5164 -270.838467) (xy 118.546926 -270.796451) (xy 118.583649 -270.759728)
			(xy 118.625665 -270.729202) (xy 118.671939 -270.705624) (xy 118.721332 -270.689576) (xy 118.772627 -270.681451)
			(xy 118.824561 -270.681451) (xy 118.875856 -270.689576) (xy 118.925249 -270.705624) (xy 118.971523 -270.729202)
			(xy 119.013539 -270.759728) (xy 119.050262 -270.796451) (xy 119.080788 -270.838467) (xy 119.104366 -270.884741)
			(xy 119.120414 -270.934134) (xy 119.128539 -270.985429) (xy 119.129048 -271.011396) (xy 119.128539 -271.037363)
			(xy 119.408449 -271.037363) (xy 119.408449 -270.985429) (xy 119.416574 -270.934134) (xy 119.432622 -270.884741)
			(xy 119.4562 -270.838467) (xy 119.486726 -270.796451) (xy 119.523449 -270.759728) (xy 119.565465 -270.729202)
			(xy 119.611739 -270.705624) (xy 119.661132 -270.689576) (xy 119.712427 -270.681451) (xy 119.764361 -270.681451)
			(xy 119.815656 -270.689576) (xy 119.865049 -270.705624) (xy 119.911323 -270.729202) (xy 119.953339 -270.759728)
			(xy 119.990062 -270.796451) (xy 120.020588 -270.838467) (xy 120.044166 -270.884741) (xy 120.060214 -270.934134)
			(xy 120.068339 -270.985429) (xy 120.068848 -271.011396) (xy 120.068339 -271.037363) (xy 120.348249 -271.037363)
			(xy 120.348249 -270.985429) (xy 120.356374 -270.934134) (xy 120.372422 -270.884741) (xy 120.396 -270.838467)
			(xy 120.426526 -270.796451) (xy 120.463249 -270.759728) (xy 120.505265 -270.729202) (xy 120.551539 -270.705624)
			(xy 120.600932 -270.689576) (xy 120.652227 -270.681451) (xy 120.704161 -270.681451) (xy 120.755456 -270.689576)
			(xy 120.804849 -270.705624) (xy 120.851123 -270.729202) (xy 120.893139 -270.759728) (xy 120.929862 -270.796451)
			(xy 120.960388 -270.838467) (xy 120.983966 -270.884741) (xy 121.000014 -270.934134) (xy 121.008139 -270.985429)
			(xy 121.008648 -271.011396) (xy 121.008139 -271.037363) (xy 121.288049 -271.037363) (xy 121.288049 -270.985429)
			(xy 121.296174 -270.934134) (xy 121.312222 -270.884741) (xy 121.3358 -270.838467) (xy 121.366326 -270.796451)
			(xy 121.403049 -270.759728) (xy 121.445065 -270.729202) (xy 121.491339 -270.705624) (xy 121.540732 -270.689576)
			(xy 121.592027 -270.681451) (xy 121.643961 -270.681451) (xy 121.695256 -270.689576) (xy 121.744649 -270.705624)
			(xy 121.790923 -270.729202) (xy 121.832939 -270.759728) (xy 121.869662 -270.796451) (xy 121.900188 -270.838467)
			(xy 121.923766 -270.884741) (xy 121.939814 -270.934134) (xy 121.947939 -270.985429) (xy 121.948448 -271.011396)
			(xy 121.947939 -271.037363) (xy 122.228103 -271.037363) (xy 122.228103 -270.985429) (xy 122.236228 -270.934134)
			(xy 122.252276 -270.884741) (xy 122.275854 -270.838467) (xy 122.30638 -270.796451) (xy 122.343103 -270.759728)
			(xy 122.385119 -270.729202) (xy 122.431393 -270.705624) (xy 122.480786 -270.689576) (xy 122.532081 -270.681451)
			(xy 122.584015 -270.681451) (xy 122.63531 -270.689576) (xy 122.684703 -270.705624) (xy 122.730977 -270.729202)
			(xy 122.772993 -270.759728) (xy 122.809716 -270.796451) (xy 122.840242 -270.838467) (xy 122.86382 -270.884741)
			(xy 122.879868 -270.934134) (xy 122.887993 -270.985429) (xy 122.888502 -271.011396) (xy 122.887993 -271.037363)
			(xy 123.167649 -271.037363) (xy 123.167649 -270.985429) (xy 123.175774 -270.934134) (xy 123.191822 -270.884741)
			(xy 123.2154 -270.838467) (xy 123.245926 -270.796451) (xy 123.282649 -270.759728) (xy 123.324665 -270.729202)
			(xy 123.370939 -270.705624) (xy 123.420332 -270.689576) (xy 123.471627 -270.681451) (xy 123.523561 -270.681451)
			(xy 123.574856 -270.689576) (xy 123.624249 -270.705624) (xy 123.670523 -270.729202) (xy 123.712539 -270.759728)
			(xy 123.749262 -270.796451) (xy 123.779788 -270.838467) (xy 123.803366 -270.884741) (xy 123.819414 -270.934134)
			(xy 123.827539 -270.985429) (xy 123.828048 -271.011396) (xy 123.827539 -271.037363) (xy 124.107449 -271.037363)
			(xy 124.107449 -270.985429) (xy 124.115574 -270.934134) (xy 124.131622 -270.884741) (xy 124.1552 -270.838467)
			(xy 124.185726 -270.796451) (xy 124.222449 -270.759728) (xy 124.264465 -270.729202) (xy 124.310739 -270.705624)
			(xy 124.360132 -270.689576) (xy 124.411427 -270.681451) (xy 124.463361 -270.681451) (xy 124.514656 -270.689576)
			(xy 124.564049 -270.705624) (xy 124.610323 -270.729202) (xy 124.652339 -270.759728) (xy 124.689062 -270.796451)
			(xy 124.719588 -270.838467) (xy 124.743166 -270.884741) (xy 124.759214 -270.934134) (xy 124.767339 -270.985429)
			(xy 124.767848 -271.011396) (xy 124.767339 -271.037363) (xy 125.047249 -271.037363) (xy 125.047249 -270.985429)
			(xy 125.055374 -270.934134) (xy 125.071422 -270.884741) (xy 125.095 -270.838467) (xy 125.125526 -270.796451)
			(xy 125.162249 -270.759728) (xy 125.204265 -270.729202) (xy 125.250539 -270.705624) (xy 125.299932 -270.689576)
			(xy 125.351227 -270.681451) (xy 125.403161 -270.681451) (xy 125.454456 -270.689576) (xy 125.503849 -270.705624)
			(xy 125.550123 -270.729202) (xy 125.592139 -270.759728) (xy 125.628862 -270.796451) (xy 125.659388 -270.838467)
			(xy 125.682966 -270.884741) (xy 125.699014 -270.934134) (xy 125.707139 -270.985429) (xy 125.707648 -271.011396)
			(xy 125.707139 -271.037363) (xy 125.987049 -271.037363) (xy 125.987049 -270.985429) (xy 125.995174 -270.934134)
			(xy 126.011222 -270.884741) (xy 126.0348 -270.838467) (xy 126.065326 -270.796451) (xy 126.102049 -270.759728)
			(xy 126.144065 -270.729202) (xy 126.190339 -270.705624) (xy 126.239732 -270.689576) (xy 126.291027 -270.681451)
			(xy 126.342961 -270.681451) (xy 126.394256 -270.689576) (xy 126.443649 -270.705624) (xy 126.489923 -270.729202)
			(xy 126.531939 -270.759728) (xy 126.568662 -270.796451) (xy 126.599188 -270.838467) (xy 126.622766 -270.884741)
			(xy 126.638814 -270.934134) (xy 126.646939 -270.985429) (xy 126.647448 -271.011396) (xy 126.646939 -271.037363)
			(xy 126.638814 -271.088658) (xy 126.622766 -271.138051) (xy 126.599188 -271.184325) (xy 126.568662 -271.226341)
			(xy 126.531939 -271.263064) (xy 126.489923 -271.29359) (xy 126.443649 -271.317168) (xy 126.394256 -271.333216)
			(xy 126.342961 -271.341341) (xy 126.291027 -271.341341) (xy 126.239732 -271.333216) (xy 126.190339 -271.317168)
			(xy 126.144065 -271.29359) (xy 126.102049 -271.263064) (xy 126.065326 -271.226341) (xy 126.0348 -271.184325)
			(xy 126.011222 -271.138051) (xy 125.995174 -271.088658) (xy 125.987049 -271.037363) (xy 125.707139 -271.037363)
			(xy 125.699014 -271.088658) (xy 125.682966 -271.138051) (xy 125.659388 -271.184325) (xy 125.628862 -271.226341)
			(xy 125.592139 -271.263064) (xy 125.550123 -271.29359) (xy 125.503849 -271.317168) (xy 125.454456 -271.333216)
			(xy 125.403161 -271.341341) (xy 125.351227 -271.341341) (xy 125.299932 -271.333216) (xy 125.250539 -271.317168)
			(xy 125.204265 -271.29359) (xy 125.162249 -271.263064) (xy 125.125526 -271.226341) (xy 125.095 -271.184325)
			(xy 125.071422 -271.138051) (xy 125.055374 -271.088658) (xy 125.047249 -271.037363) (xy 124.767339 -271.037363)
			(xy 124.759214 -271.088658) (xy 124.743166 -271.138051) (xy 124.719588 -271.184325) (xy 124.689062 -271.226341)
			(xy 124.652339 -271.263064) (xy 124.610323 -271.29359) (xy 124.564049 -271.317168) (xy 124.514656 -271.333216)
			(xy 124.463361 -271.341341) (xy 124.411427 -271.341341) (xy 124.360132 -271.333216) (xy 124.310739 -271.317168)
			(xy 124.264465 -271.29359) (xy 124.222449 -271.263064) (xy 124.185726 -271.226341) (xy 124.1552 -271.184325)
			(xy 124.131622 -271.138051) (xy 124.115574 -271.088658) (xy 124.107449 -271.037363) (xy 123.827539 -271.037363)
			(xy 123.819414 -271.088658) (xy 123.803366 -271.138051) (xy 123.779788 -271.184325) (xy 123.749262 -271.226341)
			(xy 123.712539 -271.263064) (xy 123.670523 -271.29359) (xy 123.624249 -271.317168) (xy 123.574856 -271.333216)
			(xy 123.523561 -271.341341) (xy 123.471627 -271.341341) (xy 123.420332 -271.333216) (xy 123.370939 -271.317168)
			(xy 123.324665 -271.29359) (xy 123.282649 -271.263064) (xy 123.245926 -271.226341) (xy 123.2154 -271.184325)
			(xy 123.191822 -271.138051) (xy 123.175774 -271.088658) (xy 123.167649 -271.037363) (xy 122.887993 -271.037363)
			(xy 122.879868 -271.088658) (xy 122.86382 -271.138051) (xy 122.840242 -271.184325) (xy 122.809716 -271.226341)
			(xy 122.772993 -271.263064) (xy 122.730977 -271.29359) (xy 122.684703 -271.317168) (xy 122.63531 -271.333216)
			(xy 122.584015 -271.341341) (xy 122.532081 -271.341341) (xy 122.480786 -271.333216) (xy 122.431393 -271.317168)
			(xy 122.385119 -271.29359) (xy 122.343103 -271.263064) (xy 122.30638 -271.226341) (xy 122.275854 -271.184325)
			(xy 122.252276 -271.138051) (xy 122.236228 -271.088658) (xy 122.228103 -271.037363) (xy 121.947939 -271.037363)
			(xy 121.939814 -271.088658) (xy 121.923766 -271.138051) (xy 121.900188 -271.184325) (xy 121.869662 -271.226341)
			(xy 121.832939 -271.263064) (xy 121.790923 -271.29359) (xy 121.744649 -271.317168) (xy 121.695256 -271.333216)
			(xy 121.643961 -271.341341) (xy 121.592027 -271.341341) (xy 121.540732 -271.333216) (xy 121.491339 -271.317168)
			(xy 121.445065 -271.29359) (xy 121.403049 -271.263064) (xy 121.366326 -271.226341) (xy 121.3358 -271.184325)
			(xy 121.312222 -271.138051) (xy 121.296174 -271.088658) (xy 121.288049 -271.037363) (xy 121.008139 -271.037363)
			(xy 121.000014 -271.088658) (xy 120.983966 -271.138051) (xy 120.960388 -271.184325) (xy 120.929862 -271.226341)
			(xy 120.893139 -271.263064) (xy 120.851123 -271.29359) (xy 120.804849 -271.317168) (xy 120.755456 -271.333216)
			(xy 120.704161 -271.341341) (xy 120.652227 -271.341341) (xy 120.600932 -271.333216) (xy 120.551539 -271.317168)
			(xy 120.505265 -271.29359) (xy 120.463249 -271.263064) (xy 120.426526 -271.226341) (xy 120.396 -271.184325)
			(xy 120.372422 -271.138051) (xy 120.356374 -271.088658) (xy 120.348249 -271.037363) (xy 120.068339 -271.037363)
			(xy 120.060214 -271.088658) (xy 120.044166 -271.138051) (xy 120.020588 -271.184325) (xy 119.990062 -271.226341)
			(xy 119.953339 -271.263064) (xy 119.911323 -271.29359) (xy 119.865049 -271.317168) (xy 119.815656 -271.333216)
			(xy 119.764361 -271.341341) (xy 119.712427 -271.341341) (xy 119.661132 -271.333216) (xy 119.611739 -271.317168)
			(xy 119.565465 -271.29359) (xy 119.523449 -271.263064) (xy 119.486726 -271.226341) (xy 119.4562 -271.184325)
			(xy 119.432622 -271.138051) (xy 119.416574 -271.088658) (xy 119.408449 -271.037363) (xy 119.128539 -271.037363)
			(xy 119.120414 -271.088658) (xy 119.104366 -271.138051) (xy 119.080788 -271.184325) (xy 119.050262 -271.226341)
			(xy 119.013539 -271.263064) (xy 118.971523 -271.29359) (xy 118.925249 -271.317168) (xy 118.875856 -271.333216)
			(xy 118.824561 -271.341341) (xy 118.772627 -271.341341) (xy 118.721332 -271.333216) (xy 118.671939 -271.317168)
			(xy 118.625665 -271.29359) (xy 118.583649 -271.263064) (xy 118.546926 -271.226341) (xy 118.5164 -271.184325)
			(xy 118.492822 -271.138051) (xy 118.476774 -271.088658) (xy 118.468649 -271.037363) (xy 118.188739 -271.037363)
			(xy 118.180614 -271.088658) (xy 118.164566 -271.138051) (xy 118.140988 -271.184325) (xy 118.110462 -271.226341)
			(xy 118.073739 -271.263064) (xy 118.031723 -271.29359) (xy 117.985449 -271.317168) (xy 117.936056 -271.333216)
			(xy 117.884761 -271.341341) (xy 117.832827 -271.341341) (xy 117.781532 -271.333216) (xy 117.732139 -271.317168)
			(xy 117.685865 -271.29359) (xy 117.643849 -271.263064) (xy 117.607126 -271.226341) (xy 117.5766 -271.184325)
			(xy 117.553022 -271.138051) (xy 117.536974 -271.088658) (xy 117.528849 -271.037363) (xy 117.403626 -271.037363)
			(xy 117.403626 -271.492218) (xy 117.44579 -271.499584) (xy 117.471017 -271.504471) (xy 117.519665 -271.521012)
			(xy 117.565167 -271.544883) (xy 117.606427 -271.575507) (xy 117.642451 -271.612148) (xy 117.67237 -271.653923)
			(xy 117.695463 -271.699824) (xy 117.711175 -271.748746) (xy 117.719127 -271.79951) (xy 117.719126 -271.850894)
			(xy 117.719081 -271.851179) (xy 117.998495 -271.851179) (xy 117.998495 -271.799245) (xy 118.00662 -271.74795)
			(xy 118.022668 -271.698557) (xy 118.046246 -271.652283) (xy 118.076772 -271.610267) (xy 118.113495 -271.573544)
			(xy 118.155511 -271.543018) (xy 118.201785 -271.51944) (xy 118.251178 -271.503392) (xy 118.302473 -271.495267)
			(xy 118.354407 -271.495267) (xy 118.405702 -271.503392) (xy 118.455095 -271.51944) (xy 118.501369 -271.543018)
			(xy 118.543385 -271.573544) (xy 118.580108 -271.610267) (xy 118.610634 -271.652283) (xy 118.634212 -271.698557)
			(xy 118.65026 -271.74795) (xy 118.658385 -271.799245) (xy 118.658894 -271.825212) (xy 118.658385 -271.851179)
			(xy 118.938295 -271.851179) (xy 118.938295 -271.799245) (xy 118.94642 -271.74795) (xy 118.962468 -271.698557)
			(xy 118.986046 -271.652283) (xy 119.016572 -271.610267) (xy 119.053295 -271.573544) (xy 119.095311 -271.543018)
			(xy 119.141585 -271.51944) (xy 119.190978 -271.503392) (xy 119.242273 -271.495267) (xy 119.294207 -271.495267)
			(xy 119.345502 -271.503392) (xy 119.394895 -271.51944) (xy 119.441169 -271.543018) (xy 119.483185 -271.573544)
			(xy 119.519908 -271.610267) (xy 119.550434 -271.652283) (xy 119.574012 -271.698557) (xy 119.59006 -271.74795)
			(xy 119.598185 -271.799245) (xy 119.598694 -271.825212) (xy 119.598185 -271.851179) (xy 119.878603 -271.851179)
			(xy 119.878603 -271.799245) (xy 119.886728 -271.74795) (xy 119.902776 -271.698557) (xy 119.926354 -271.652283)
			(xy 119.95688 -271.610267) (xy 119.993603 -271.573544) (xy 120.035619 -271.543018) (xy 120.081893 -271.51944)
			(xy 120.131286 -271.503392) (xy 120.182581 -271.495267) (xy 120.234515 -271.495267) (xy 120.28581 -271.503392)
			(xy 120.335203 -271.51944) (xy 120.381477 -271.543018) (xy 120.423493 -271.573544) (xy 120.460216 -271.610267)
			(xy 120.490742 -271.652283) (xy 120.51432 -271.698557) (xy 120.530368 -271.74795) (xy 120.538493 -271.799245)
			(xy 120.539002 -271.825212) (xy 120.538493 -271.851179) (xy 120.818403 -271.851179) (xy 120.818403 -271.799245)
			(xy 120.826528 -271.74795) (xy 120.842576 -271.698557) (xy 120.866154 -271.652283) (xy 120.89668 -271.610267)
			(xy 120.933403 -271.573544) (xy 120.975419 -271.543018) (xy 121.021693 -271.51944) (xy 121.071086 -271.503392)
			(xy 121.122381 -271.495267) (xy 121.174315 -271.495267) (xy 121.22561 -271.503392) (xy 121.275003 -271.51944)
			(xy 121.321277 -271.543018) (xy 121.363293 -271.573544) (xy 121.400016 -271.610267) (xy 121.430542 -271.652283)
			(xy 121.45412 -271.698557) (xy 121.470168 -271.74795) (xy 121.478293 -271.799245) (xy 121.478802 -271.825212)
			(xy 121.478293 -271.851179) (xy 121.758203 -271.851179) (xy 121.758203 -271.799245) (xy 121.766328 -271.74795)
			(xy 121.782376 -271.698557) (xy 121.805954 -271.652283) (xy 121.83648 -271.610267) (xy 121.873203 -271.573544)
			(xy 121.915219 -271.543018) (xy 121.961493 -271.51944) (xy 122.010886 -271.503392) (xy 122.062181 -271.495267)
			(xy 122.114115 -271.495267) (xy 122.16541 -271.503392) (xy 122.214803 -271.51944) (xy 122.261077 -271.543018)
			(xy 122.303093 -271.573544) (xy 122.339816 -271.610267) (xy 122.370342 -271.652283) (xy 122.39392 -271.698557)
			(xy 122.409968 -271.74795) (xy 122.418093 -271.799245) (xy 122.418602 -271.825212) (xy 122.418093 -271.851179)
			(xy 122.698003 -271.851179) (xy 122.698003 -271.799245) (xy 122.706128 -271.74795) (xy 122.722176 -271.698557)
			(xy 122.745754 -271.652283) (xy 122.77628 -271.610267) (xy 122.813003 -271.573544) (xy 122.855019 -271.543018)
			(xy 122.901293 -271.51944) (xy 122.950686 -271.503392) (xy 123.001981 -271.495267) (xy 123.053915 -271.495267)
			(xy 123.10521 -271.503392) (xy 123.154603 -271.51944) (xy 123.200877 -271.543018) (xy 123.242893 -271.573544)
			(xy 123.279616 -271.610267) (xy 123.310142 -271.652283) (xy 123.33372 -271.698557) (xy 123.349768 -271.74795)
			(xy 123.357893 -271.799245) (xy 123.358402 -271.825212) (xy 123.357893 -271.851179) (xy 123.637803 -271.851179)
			(xy 123.637803 -271.799245) (xy 123.645928 -271.74795) (xy 123.661976 -271.698557) (xy 123.685554 -271.652283)
			(xy 123.71608 -271.610267) (xy 123.752803 -271.573544) (xy 123.794819 -271.543018) (xy 123.841093 -271.51944)
			(xy 123.890486 -271.503392) (xy 123.941781 -271.495267) (xy 123.993715 -271.495267) (xy 124.04501 -271.503392)
			(xy 124.094403 -271.51944) (xy 124.140677 -271.543018) (xy 124.182693 -271.573544) (xy 124.219416 -271.610267)
			(xy 124.249942 -271.652283) (xy 124.27352 -271.698557) (xy 124.289568 -271.74795) (xy 124.297693 -271.799245)
			(xy 124.298202 -271.825212) (xy 124.297693 -271.851179) (xy 124.577603 -271.851179) (xy 124.577603 -271.799245)
			(xy 124.585728 -271.74795) (xy 124.601776 -271.698557) (xy 124.625354 -271.652283) (xy 124.65588 -271.610267)
			(xy 124.692603 -271.573544) (xy 124.734619 -271.543018) (xy 124.780893 -271.51944) (xy 124.830286 -271.503392)
			(xy 124.881581 -271.495267) (xy 124.933515 -271.495267) (xy 124.98481 -271.503392) (xy 125.034203 -271.51944)
			(xy 125.080477 -271.543018) (xy 125.122493 -271.573544) (xy 125.159216 -271.610267) (xy 125.189742 -271.652283)
			(xy 125.21332 -271.698557) (xy 125.229368 -271.74795) (xy 125.237493 -271.799245) (xy 125.238002 -271.825212)
			(xy 125.237493 -271.851179) (xy 125.517149 -271.851179) (xy 125.517149 -271.799245) (xy 125.525274 -271.74795)
			(xy 125.541322 -271.698557) (xy 125.5649 -271.652283) (xy 125.595426 -271.610267) (xy 125.632149 -271.573544)
			(xy 125.674165 -271.543018) (xy 125.720439 -271.51944) (xy 125.769832 -271.503392) (xy 125.821127 -271.495267)
			(xy 125.873061 -271.495267) (xy 125.924356 -271.503392) (xy 125.973749 -271.51944) (xy 126.020023 -271.543018)
			(xy 126.062039 -271.573544) (xy 126.098762 -271.610267) (xy 126.129288 -271.652283) (xy 126.152866 -271.698557)
			(xy 126.168914 -271.74795) (xy 126.177039 -271.799245) (xy 126.177548 -271.825212) (xy 126.177039 -271.851179)
			(xy 126.168914 -271.902474) (xy 126.152866 -271.951867) (xy 126.129288 -271.998141) (xy 126.098762 -272.040157)
			(xy 126.062039 -272.07688) (xy 126.020023 -272.107406) (xy 125.973749 -272.130984) (xy 125.924356 -272.147032)
			(xy 125.873061 -272.155157) (xy 125.821127 -272.155157) (xy 125.769832 -272.147032) (xy 125.720439 -272.130984)
			(xy 125.674165 -272.107406) (xy 125.632149 -272.07688) (xy 125.595426 -272.040157) (xy 125.5649 -271.998141)
			(xy 125.541322 -271.951867) (xy 125.525274 -271.902474) (xy 125.517149 -271.851179) (xy 125.237493 -271.851179)
			(xy 125.229368 -271.902474) (xy 125.21332 -271.951867) (xy 125.189742 -271.998141) (xy 125.159216 -272.040157)
			(xy 125.122493 -272.07688) (xy 125.080477 -272.107406) (xy 125.034203 -272.130984) (xy 124.98481 -272.147032)
			(xy 124.933515 -272.155157) (xy 124.881581 -272.155157) (xy 124.830286 -272.147032) (xy 124.780893 -272.130984)
			(xy 124.734619 -272.107406) (xy 124.692603 -272.07688) (xy 124.65588 -272.040157) (xy 124.625354 -271.998141)
			(xy 124.601776 -271.951867) (xy 124.585728 -271.902474) (xy 124.577603 -271.851179) (xy 124.297693 -271.851179)
			(xy 124.289568 -271.902474) (xy 124.27352 -271.951867) (xy 124.249942 -271.998141) (xy 124.219416 -272.040157)
			(xy 124.182693 -272.07688) (xy 124.140677 -272.107406) (xy 124.094403 -272.130984) (xy 124.04501 -272.147032)
			(xy 123.993715 -272.155157) (xy 123.941781 -272.155157) (xy 123.890486 -272.147032) (xy 123.841093 -272.130984)
			(xy 123.794819 -272.107406) (xy 123.752803 -272.07688) (xy 123.71608 -272.040157) (xy 123.685554 -271.998141)
			(xy 123.661976 -271.951867) (xy 123.645928 -271.902474) (xy 123.637803 -271.851179) (xy 123.357893 -271.851179)
			(xy 123.349768 -271.902474) (xy 123.33372 -271.951867) (xy 123.310142 -271.998141) (xy 123.279616 -272.040157)
			(xy 123.242893 -272.07688) (xy 123.200877 -272.107406) (xy 123.154603 -272.130984) (xy 123.10521 -272.147032)
			(xy 123.053915 -272.155157) (xy 123.001981 -272.155157) (xy 122.950686 -272.147032) (xy 122.901293 -272.130984)
			(xy 122.855019 -272.107406) (xy 122.813003 -272.07688) (xy 122.77628 -272.040157) (xy 122.745754 -271.998141)
			(xy 122.722176 -271.951867) (xy 122.706128 -271.902474) (xy 122.698003 -271.851179) (xy 122.418093 -271.851179)
			(xy 122.409968 -271.902474) (xy 122.39392 -271.951867) (xy 122.370342 -271.998141) (xy 122.339816 -272.040157)
			(xy 122.303093 -272.07688) (xy 122.261077 -272.107406) (xy 122.214803 -272.130984) (xy 122.16541 -272.147032)
			(xy 122.114115 -272.155157) (xy 122.062181 -272.155157) (xy 122.010886 -272.147032) (xy 121.961493 -272.130984)
			(xy 121.915219 -272.107406) (xy 121.873203 -272.07688) (xy 121.83648 -272.040157) (xy 121.805954 -271.998141)
			(xy 121.782376 -271.951867) (xy 121.766328 -271.902474) (xy 121.758203 -271.851179) (xy 121.478293 -271.851179)
			(xy 121.470168 -271.902474) (xy 121.45412 -271.951867) (xy 121.430542 -271.998141) (xy 121.400016 -272.040157)
			(xy 121.363293 -272.07688) (xy 121.321277 -272.107406) (xy 121.275003 -272.130984) (xy 121.22561 -272.147032)
			(xy 121.174315 -272.155157) (xy 121.122381 -272.155157) (xy 121.071086 -272.147032) (xy 121.021693 -272.130984)
			(xy 120.975419 -272.107406) (xy 120.933403 -272.07688) (xy 120.89668 -272.040157) (xy 120.866154 -271.998141)
			(xy 120.842576 -271.951867) (xy 120.826528 -271.902474) (xy 120.818403 -271.851179) (xy 120.538493 -271.851179)
			(xy 120.530368 -271.902474) (xy 120.51432 -271.951867) (xy 120.490742 -271.998141) (xy 120.460216 -272.040157)
			(xy 120.423493 -272.07688) (xy 120.381477 -272.107406) (xy 120.335203 -272.130984) (xy 120.28581 -272.147032)
			(xy 120.234515 -272.155157) (xy 120.182581 -272.155157) (xy 120.131286 -272.147032) (xy 120.081893 -272.130984)
			(xy 120.035619 -272.107406) (xy 119.993603 -272.07688) (xy 119.95688 -272.040157) (xy 119.926354 -271.998141)
			(xy 119.902776 -271.951867) (xy 119.886728 -271.902474) (xy 119.878603 -271.851179) (xy 119.598185 -271.851179)
			(xy 119.59006 -271.902474) (xy 119.574012 -271.951867) (xy 119.550434 -271.998141) (xy 119.519908 -272.040157)
			(xy 119.483185 -272.07688) (xy 119.441169 -272.107406) (xy 119.394895 -272.130984) (xy 119.345502 -272.147032)
			(xy 119.294207 -272.155157) (xy 119.242273 -272.155157) (xy 119.190978 -272.147032) (xy 119.141585 -272.130984)
			(xy 119.095311 -272.107406) (xy 119.053295 -272.07688) (xy 119.016572 -272.040157) (xy 118.986046 -271.998141)
			(xy 118.962468 -271.951867) (xy 118.94642 -271.902474) (xy 118.938295 -271.851179) (xy 118.658385 -271.851179)
			(xy 118.65026 -271.902474) (xy 118.634212 -271.951867) (xy 118.610634 -271.998141) (xy 118.580108 -272.040157)
			(xy 118.543385 -272.07688) (xy 118.501369 -272.107406) (xy 118.455095 -272.130984) (xy 118.405702 -272.147032)
			(xy 118.354407 -272.155157) (xy 118.302473 -272.155157) (xy 118.251178 -272.147032) (xy 118.201785 -272.130984)
			(xy 118.155511 -272.107406) (xy 118.113495 -272.07688) (xy 118.076772 -272.040157) (xy 118.046246 -271.998141)
			(xy 118.022668 -271.951867) (xy 118.00662 -271.902474) (xy 117.998495 -271.851179) (xy 117.719081 -271.851179)
			(xy 117.711174 -271.901658) (xy 117.695462 -271.95058) (xy 117.672367 -271.996481) (xy 117.642448 -272.038255)
			(xy 117.606424 -272.074895) (xy 117.565164 -272.10552) (xy 117.519662 -272.12939) (xy 117.471013 -272.14593)
			(xy 117.44579 -272.15084) (xy 117.403626 -272.158206) (xy 117.403626 -272.665249) (xy 117.528849 -272.665249)
			(xy 117.528849 -272.613315) (xy 117.536974 -272.56202) (xy 117.553022 -272.512627) (xy 117.5766 -272.466353)
			(xy 117.607126 -272.424337) (xy 117.643849 -272.387614) (xy 117.685865 -272.357088) (xy 117.732139 -272.33351)
			(xy 117.781532 -272.317462) (xy 117.832827 -272.309337) (xy 117.884761 -272.309337) (xy 117.936056 -272.317462)
			(xy 117.985449 -272.33351) (xy 118.031723 -272.357088) (xy 118.073739 -272.387614) (xy 118.110462 -272.424337)
			(xy 118.140988 -272.466353) (xy 118.164566 -272.512627) (xy 118.180614 -272.56202) (xy 118.188739 -272.613315)
			(xy 118.189248 -272.639282) (xy 118.188739 -272.665249) (xy 118.468649 -272.665249) (xy 118.468649 -272.613315)
			(xy 118.476774 -272.56202) (xy 118.492822 -272.512627) (xy 118.5164 -272.466353) (xy 118.546926 -272.424337)
			(xy 118.583649 -272.387614) (xy 118.625665 -272.357088) (xy 118.671939 -272.33351) (xy 118.721332 -272.317462)
			(xy 118.772627 -272.309337) (xy 118.824561 -272.309337) (xy 118.875856 -272.317462) (xy 118.925249 -272.33351)
			(xy 118.971523 -272.357088) (xy 119.013539 -272.387614) (xy 119.050262 -272.424337) (xy 119.080788 -272.466353)
			(xy 119.104366 -272.512627) (xy 119.120414 -272.56202) (xy 119.128539 -272.613315) (xy 119.129048 -272.639282)
			(xy 119.128539 -272.665249) (xy 119.408449 -272.665249) (xy 119.408449 -272.613315) (xy 119.416574 -272.56202)
			(xy 119.432622 -272.512627) (xy 119.4562 -272.466353) (xy 119.486726 -272.424337) (xy 119.523449 -272.387614)
			(xy 119.565465 -272.357088) (xy 119.611739 -272.33351) (xy 119.661132 -272.317462) (xy 119.712427 -272.309337)
			(xy 119.764361 -272.309337) (xy 119.815656 -272.317462) (xy 119.865049 -272.33351) (xy 119.911323 -272.357088)
			(xy 119.953339 -272.387614) (xy 119.990062 -272.424337) (xy 120.020588 -272.466353) (xy 120.044166 -272.512627)
			(xy 120.060214 -272.56202) (xy 120.068339 -272.613315) (xy 120.068848 -272.639282) (xy 120.068339 -272.665249)
			(xy 120.348249 -272.665249) (xy 120.348249 -272.613315) (xy 120.356374 -272.56202) (xy 120.372422 -272.512627)
			(xy 120.396 -272.466353) (xy 120.426526 -272.424337) (xy 120.463249 -272.387614) (xy 120.505265 -272.357088)
			(xy 120.551539 -272.33351) (xy 120.600932 -272.317462) (xy 120.652227 -272.309337) (xy 120.704161 -272.309337)
			(xy 120.755456 -272.317462) (xy 120.804849 -272.33351) (xy 120.851123 -272.357088) (xy 120.893139 -272.387614)
			(xy 120.929862 -272.424337) (xy 120.960388 -272.466353) (xy 120.983966 -272.512627) (xy 121.000014 -272.56202)
			(xy 121.008139 -272.613315) (xy 121.008648 -272.639282) (xy 121.008139 -272.665249) (xy 121.288049 -272.665249)
			(xy 121.288049 -272.613315) (xy 121.296174 -272.56202) (xy 121.312222 -272.512627) (xy 121.3358 -272.466353)
			(xy 121.366326 -272.424337) (xy 121.403049 -272.387614) (xy 121.445065 -272.357088) (xy 121.491339 -272.33351)
			(xy 121.540732 -272.317462) (xy 121.592027 -272.309337) (xy 121.643961 -272.309337) (xy 121.695256 -272.317462)
			(xy 121.744649 -272.33351) (xy 121.790923 -272.357088) (xy 121.832939 -272.387614) (xy 121.869662 -272.424337)
			(xy 121.900188 -272.466353) (xy 121.923766 -272.512627) (xy 121.939814 -272.56202) (xy 121.947939 -272.613315)
			(xy 121.948448 -272.639282) (xy 121.947939 -272.665249) (xy 122.227849 -272.665249) (xy 122.227849 -272.613315)
			(xy 122.235974 -272.56202) (xy 122.252022 -272.512627) (xy 122.2756 -272.466353) (xy 122.306126 -272.424337)
			(xy 122.342849 -272.387614) (xy 122.384865 -272.357088) (xy 122.431139 -272.33351) (xy 122.480532 -272.317462)
			(xy 122.531827 -272.309337) (xy 122.583761 -272.309337) (xy 122.635056 -272.317462) (xy 122.684449 -272.33351)
			(xy 122.730723 -272.357088) (xy 122.772739 -272.387614) (xy 122.809462 -272.424337) (xy 122.839988 -272.466353)
			(xy 122.863566 -272.512627) (xy 122.879614 -272.56202) (xy 122.887739 -272.613315) (xy 122.888248 -272.639282)
			(xy 122.887739 -272.665249) (xy 123.167649 -272.665249) (xy 123.167649 -272.613315) (xy 123.175774 -272.56202)
			(xy 123.191822 -272.512627) (xy 123.2154 -272.466353) (xy 123.245926 -272.424337) (xy 123.282649 -272.387614)
			(xy 123.324665 -272.357088) (xy 123.370939 -272.33351) (xy 123.420332 -272.317462) (xy 123.471627 -272.309337)
			(xy 123.523561 -272.309337) (xy 123.574856 -272.317462) (xy 123.624249 -272.33351) (xy 123.670523 -272.357088)
			(xy 123.712539 -272.387614) (xy 123.749262 -272.424337) (xy 123.779788 -272.466353) (xy 123.803366 -272.512627)
			(xy 123.819414 -272.56202) (xy 123.827539 -272.613315) (xy 123.828048 -272.639282) (xy 123.827539 -272.665249)
			(xy 124.107449 -272.665249) (xy 124.107449 -272.613315) (xy 124.115574 -272.56202) (xy 124.131622 -272.512627)
			(xy 124.1552 -272.466353) (xy 124.185726 -272.424337) (xy 124.222449 -272.387614) (xy 124.264465 -272.357088)
			(xy 124.310739 -272.33351) (xy 124.360132 -272.317462) (xy 124.411427 -272.309337) (xy 124.463361 -272.309337)
			(xy 124.514656 -272.317462) (xy 124.564049 -272.33351) (xy 124.610323 -272.357088) (xy 124.652339 -272.387614)
			(xy 124.689062 -272.424337) (xy 124.719588 -272.466353) (xy 124.743166 -272.512627) (xy 124.759214 -272.56202)
			(xy 124.767339 -272.613315) (xy 124.767848 -272.639282) (xy 124.767339 -272.665249) (xy 125.047503 -272.665249)
			(xy 125.047503 -272.613315) (xy 125.055628 -272.56202) (xy 125.071676 -272.512627) (xy 125.095254 -272.466353)
			(xy 125.12578 -272.424337) (xy 125.162503 -272.387614) (xy 125.204519 -272.357088) (xy 125.250793 -272.33351)
			(xy 125.300186 -272.317462) (xy 125.351481 -272.309337) (xy 125.403415 -272.309337) (xy 125.45471 -272.317462)
			(xy 125.504103 -272.33351) (xy 125.550377 -272.357088) (xy 125.592393 -272.387614) (xy 125.629116 -272.424337)
			(xy 125.659642 -272.466353) (xy 125.68322 -272.512627) (xy 125.699268 -272.56202) (xy 125.707393 -272.613315)
			(xy 125.707902 -272.639282) (xy 125.707393 -272.665249) (xy 125.987049 -272.665249) (xy 125.987049 -272.613315)
			(xy 125.995174 -272.56202) (xy 126.011222 -272.512627) (xy 126.0348 -272.466353) (xy 126.065326 -272.424337)
			(xy 126.102049 -272.387614) (xy 126.144065 -272.357088) (xy 126.190339 -272.33351) (xy 126.239732 -272.317462)
			(xy 126.291027 -272.309337) (xy 126.342961 -272.309337) (xy 126.394256 -272.317462) (xy 126.443649 -272.33351)
			(xy 126.489923 -272.357088) (xy 126.531939 -272.387614) (xy 126.568662 -272.424337) (xy 126.599188 -272.466353)
			(xy 126.622766 -272.512627) (xy 126.638814 -272.56202) (xy 126.646939 -272.613315) (xy 126.647448 -272.639282)
			(xy 126.646939 -272.665249) (xy 126.638814 -272.716544) (xy 126.622766 -272.765937) (xy 126.599188 -272.812211)
			(xy 126.568662 -272.854227) (xy 126.531939 -272.89095) (xy 126.489923 -272.921476) (xy 126.443649 -272.945054)
			(xy 126.394256 -272.961102) (xy 126.342961 -272.969227) (xy 126.291027 -272.969227) (xy 126.239732 -272.961102)
			(xy 126.190339 -272.945054) (xy 126.144065 -272.921476) (xy 126.102049 -272.89095) (xy 126.065326 -272.854227)
			(xy 126.0348 -272.812211) (xy 126.011222 -272.765937) (xy 125.995174 -272.716544) (xy 125.987049 -272.665249)
			(xy 125.707393 -272.665249) (xy 125.699268 -272.716544) (xy 125.68322 -272.765937) (xy 125.659642 -272.812211)
			(xy 125.629116 -272.854227) (xy 125.592393 -272.89095) (xy 125.550377 -272.921476) (xy 125.504103 -272.945054)
			(xy 125.45471 -272.961102) (xy 125.403415 -272.969227) (xy 125.351481 -272.969227) (xy 125.300186 -272.961102)
			(xy 125.250793 -272.945054) (xy 125.204519 -272.921476) (xy 125.162503 -272.89095) (xy 125.12578 -272.854227)
			(xy 125.095254 -272.812211) (xy 125.071676 -272.765937) (xy 125.055628 -272.716544) (xy 125.047503 -272.665249)
			(xy 124.767339 -272.665249) (xy 124.759214 -272.716544) (xy 124.743166 -272.765937) (xy 124.719588 -272.812211)
			(xy 124.689062 -272.854227) (xy 124.652339 -272.89095) (xy 124.610323 -272.921476) (xy 124.564049 -272.945054)
			(xy 124.514656 -272.961102) (xy 124.463361 -272.969227) (xy 124.411427 -272.969227) (xy 124.360132 -272.961102)
			(xy 124.310739 -272.945054) (xy 124.264465 -272.921476) (xy 124.222449 -272.89095) (xy 124.185726 -272.854227)
			(xy 124.1552 -272.812211) (xy 124.131622 -272.765937) (xy 124.115574 -272.716544) (xy 124.107449 -272.665249)
			(xy 123.827539 -272.665249) (xy 123.819414 -272.716544) (xy 123.803366 -272.765937) (xy 123.779788 -272.812211)
			(xy 123.749262 -272.854227) (xy 123.712539 -272.89095) (xy 123.670523 -272.921476) (xy 123.624249 -272.945054)
			(xy 123.574856 -272.961102) (xy 123.523561 -272.969227) (xy 123.471627 -272.969227) (xy 123.420332 -272.961102)
			(xy 123.370939 -272.945054) (xy 123.324665 -272.921476) (xy 123.282649 -272.89095) (xy 123.245926 -272.854227)
			(xy 123.2154 -272.812211) (xy 123.191822 -272.765937) (xy 123.175774 -272.716544) (xy 123.167649 -272.665249)
			(xy 122.887739 -272.665249) (xy 122.879614 -272.716544) (xy 122.863566 -272.765937) (xy 122.839988 -272.812211)
			(xy 122.809462 -272.854227) (xy 122.772739 -272.89095) (xy 122.730723 -272.921476) (xy 122.684449 -272.945054)
			(xy 122.635056 -272.961102) (xy 122.583761 -272.969227) (xy 122.531827 -272.969227) (xy 122.480532 -272.961102)
			(xy 122.431139 -272.945054) (xy 122.384865 -272.921476) (xy 122.342849 -272.89095) (xy 122.306126 -272.854227)
			(xy 122.2756 -272.812211) (xy 122.252022 -272.765937) (xy 122.235974 -272.716544) (xy 122.227849 -272.665249)
			(xy 121.947939 -272.665249) (xy 121.939814 -272.716544) (xy 121.923766 -272.765937) (xy 121.900188 -272.812211)
			(xy 121.869662 -272.854227) (xy 121.832939 -272.89095) (xy 121.790923 -272.921476) (xy 121.744649 -272.945054)
			(xy 121.695256 -272.961102) (xy 121.643961 -272.969227) (xy 121.592027 -272.969227) (xy 121.540732 -272.961102)
			(xy 121.491339 -272.945054) (xy 121.445065 -272.921476) (xy 121.403049 -272.89095) (xy 121.366326 -272.854227)
			(xy 121.3358 -272.812211) (xy 121.312222 -272.765937) (xy 121.296174 -272.716544) (xy 121.288049 -272.665249)
			(xy 121.008139 -272.665249) (xy 121.000014 -272.716544) (xy 120.983966 -272.765937) (xy 120.960388 -272.812211)
			(xy 120.929862 -272.854227) (xy 120.893139 -272.89095) (xy 120.851123 -272.921476) (xy 120.804849 -272.945054)
			(xy 120.755456 -272.961102) (xy 120.704161 -272.969227) (xy 120.652227 -272.969227) (xy 120.600932 -272.961102)
			(xy 120.551539 -272.945054) (xy 120.505265 -272.921476) (xy 120.463249 -272.89095) (xy 120.426526 -272.854227)
			(xy 120.396 -272.812211) (xy 120.372422 -272.765937) (xy 120.356374 -272.716544) (xy 120.348249 -272.665249)
			(xy 120.068339 -272.665249) (xy 120.060214 -272.716544) (xy 120.044166 -272.765937) (xy 120.020588 -272.812211)
			(xy 119.990062 -272.854227) (xy 119.953339 -272.89095) (xy 119.911323 -272.921476) (xy 119.865049 -272.945054)
			(xy 119.815656 -272.961102) (xy 119.764361 -272.969227) (xy 119.712427 -272.969227) (xy 119.661132 -272.961102)
			(xy 119.611739 -272.945054) (xy 119.565465 -272.921476) (xy 119.523449 -272.89095) (xy 119.486726 -272.854227)
			(xy 119.4562 -272.812211) (xy 119.432622 -272.765937) (xy 119.416574 -272.716544) (xy 119.408449 -272.665249)
			(xy 119.128539 -272.665249) (xy 119.120414 -272.716544) (xy 119.104366 -272.765937) (xy 119.080788 -272.812211)
			(xy 119.050262 -272.854227) (xy 119.013539 -272.89095) (xy 118.971523 -272.921476) (xy 118.925249 -272.945054)
			(xy 118.875856 -272.961102) (xy 118.824561 -272.969227) (xy 118.772627 -272.969227) (xy 118.721332 -272.961102)
			(xy 118.671939 -272.945054) (xy 118.625665 -272.921476) (xy 118.583649 -272.89095) (xy 118.546926 -272.854227)
			(xy 118.5164 -272.812211) (xy 118.492822 -272.765937) (xy 118.476774 -272.716544) (xy 118.468649 -272.665249)
			(xy 118.188739 -272.665249) (xy 118.180614 -272.716544) (xy 118.164566 -272.765937) (xy 118.140988 -272.812211)
			(xy 118.110462 -272.854227) (xy 118.073739 -272.89095) (xy 118.031723 -272.921476) (xy 117.985449 -272.945054)
			(xy 117.936056 -272.961102) (xy 117.884761 -272.969227) (xy 117.832827 -272.969227) (xy 117.781532 -272.961102)
			(xy 117.732139 -272.945054) (xy 117.685865 -272.921476) (xy 117.643849 -272.89095) (xy 117.607126 -272.854227)
			(xy 117.5766 -272.812211) (xy 117.553022 -272.765937) (xy 117.536974 -272.716544) (xy 117.528849 -272.665249)
			(xy 117.403626 -272.665249) (xy 117.403626 -272.81251) (xy 117.720618 -273.129502) (xy 118.261892 -273.129502)
		)
		(stroke
			(width 0)
			(type solid)
		)
		(fill yes)
		(layer "In4.Cu")
		(net "PVCCINFAON_CPU1")
	)
	(gr_line
		(start 3.905504 -350.169734)
		(end 3.905758 -350.169734)
		(stroke
			(width 0.07366)
			(type default)
		)
		(layer "In4.Cu")
	)
	(gr_line
		(start 3.966718 -351.033842)
		(end 3.652266 -350.274636)
		(stroke
			(width 0.07366)
			(type default)
		)
		(layer "In4.Cu")
	)
	(gr_line
		(start 4.219956 -350.928686)
		(end 3.905504 -350.169734)
		(stroke
			(width 0.07366)
			(type default)
		)
		(layer "In4.Cu")
	)
	(gr_line
		(start 12.558014 -224.264474)
		(end 12.558014 -224.26422)
		(stroke
			(width 0.07366)
			(type default)
		)
		(layer "In4.Cu")
	)
	(gr_line
		(start 12.702286 -192.730628)
		(end 12.630912 -193.384932)
		(stroke
			(width 0.07366)
			(type default)
		)
		(layer "In4.Cu")
	)
	(gr_line
		(start 12.876022 -191.136778)
		(end 12.872974 -191.164718)
		(stroke
			(width 0.07366)
			(type default)
		)
		(layer "In4.Cu")
	)
	(gr_line
		(start 12.884404 -191.110108)
		(end 12.876022 -191.136778)
		(stroke
			(width 0.07366)
			(type default)
		)
		(layer "In4.Cu")
	)
	(gr_line
		(start 12.884404 -191.110108)
		(end 12.884658 -191.110108)
		(stroke
			(width 0.07366)
			(type default)
		)
		(layer "In4.Cu")
	)
	(gr_line
		(start 12.976098 -192.761362)
		(end 13.103352 -192.919858)
		(stroke
			(width 0.07366)
			(type default)
		)
		(layer "In4.Cu")
	)
	(gr_line
		(start 13.063474 -193.28638)
		(end 12.904978 -193.413634)
		(stroke
			(width 0.07366)
			(type default)
		)
		(layer "In4.Cu")
	)
	(gr_line
		(start 13.103352 -192.919858)
		(end 13.063474 -193.28638)
		(stroke
			(width 0.07366)
			(type default)
		)
		(layer "In4.Cu")
	)
	(gr_line
		(start 13.772388 -188.363098)
		(end 13.772388 -188.363352)
		(stroke
			(width 0.07366)
			(type default)
		)
		(layer "In4.Cu")
	)
	(gr_line
		(start 16.728948 -371.695726)
		(end 16.602456 -371.38991)
		(stroke
			(width 0.07366)
			(type default)
		)
		(layer "In4.Cu")
	)
	(gr_line
		(start 16.98244 -371.590824)
		(end 16.855694 -371.285008)
		(stroke
			(width 0.07366)
			(type default)
		)
		(layer "In4.Cu")
	)
	(gr_line
		(start 16.987774 -372.320312)
		(end 16.728948 -371.695726)
		(stroke
			(width 0.07366)
			(type default)
		)
		(layer "In4.Cu")
	)
	(gr_line
		(start 17.141952 -371.656864)
		(end 16.984218 -371.591586)
		(stroke
			(width 0.07366)
			(type default)
		)
		(layer "In4.Cu")
	)
	(gr_line
		(start 17.152874 -372.719092)
		(end 17.100804 -372.593362)
		(stroke
			(width 0.07366)
			(type default)
		)
		(layer "In4.Cu")
	)
	(gr_line
		(start 17.242028 -372.213886)
		(end 17.307306 -372.055898)
		(stroke
			(width 0.07366)
			(type default)
		)
		(layer "In4.Cu")
	)
	(gr_line
		(start 17.307306 -372.055898)
		(end 17.141952 -371.656864)
		(stroke
			(width 0.07366)
			(type default)
		)
		(layer "In4.Cu")
	)
	(gr_line
		(start 17.406366 -372.61419)
		(end 17.354296 -372.48846)
		(stroke
			(width 0.07366)
			(type default)
		)
		(layer "In4.Cu")
	)
	(gr_line
		(start 17.4117 -373.343678)
		(end 17.152874 -372.719092)
		(stroke
			(width 0.07366)
			(type default)
		)
		(layer "In4.Cu")
	)
	(gr_line
		(start 17.565878 -372.68023)
		(end 17.408144 -372.614952)
		(stroke
			(width 0.07366)
			(type default)
		)
		(layer "In4.Cu")
	)
	(gr_line
		(start 17.665954 -373.237252)
		(end 17.731232 -373.079264)
		(stroke
			(width 0.07366)
			(type default)
		)
		(layer "In4.Cu")
	)
	(gr_line
		(start 17.731232 -373.079264)
		(end 17.565878 -372.68023)
		(stroke
			(width 0.07366)
			(type default)
		)
		(layer "In4.Cu")
	)
	(gr_line
		(start 17.835626 -374.367044)
		(end 17.5768 -373.742458)
		(stroke
			(width 0.07366)
			(type default)
		)
		(layer "In4.Cu")
	)
	(gr_line
		(start 17.989804 -373.703596)
		(end 17.831816 -373.638318)
		(stroke
			(width 0.07366)
			(type default)
		)
		(layer "In4.Cu")
	)
	(gr_line
		(start 18.089626 -374.260618)
		(end 18.155158 -374.10263)
		(stroke
			(width 0.07366)
			(type default)
		)
		(layer "In4.Cu")
	)
	(gr_line
		(start 18.155158 -374.10263)
		(end 17.989804 -373.703596)
		(stroke
			(width 0.07366)
			(type default)
		)
		(layer "In4.Cu")
	)
	(gr_line
		(start 19.84248 -385.7498)
		(end 19.84248 -385.784344)
		(stroke
			(width 0.07366)
			(type default)
		)
		(layer "In4.Cu")
	)
	(gr_line
		(start 20.092416 -385.17068)
		(end 19.84248 -384.920744)
		(stroke
			(width 0.07366)
			(type default)
		)
		(layer "In4.Cu")
	)
	(gr_line
		(start 20.14601 -385.44627)
		(end 19.84248 -385.7498)
		(stroke
			(width 0.07366)
			(type default)
		)
		(layer "In4.Cu")
	)
	(gr_line
		(start 20.14728 -385.17068)
		(end 20.092416 -385.17068)
		(stroke
			(width 0.07366)
			(type default)
		)
		(layer "In4.Cu")
	)
	(gr_line
		(start 21.073364 -382.18364)
		(end 20.814538 -381.559054)
		(stroke
			(width 0.07366)
			(type default)
		)
		(layer "In4.Cu")
	)
	(gr_line
		(start 21.227542 -381.520192)
		(end 21.069554 -381.454914)
		(stroke
			(width 0.07366)
			(type default)
		)
		(layer "In4.Cu")
	)
	(gr_line
		(start 21.327364 -382.077214)
		(end 21.392642 -381.919226)
		(stroke
			(width 0.07366)
			(type default)
		)
		(layer "In4.Cu")
	)
	(gr_line
		(start 21.392642 -381.919226)
		(end 21.227542 -381.520192)
		(stroke
			(width 0.07366)
			(type default)
		)
		(layer "In4.Cu")
	)
	(gr_line
		(start 21.788882 -386.356098)
		(end 21.618194 -386.356098)
		(stroke
			(width 0.07366)
			(type default)
		)
		(layer "In4.Cu")
	)
	(gr_line
		(start 21.900388 -387.027928)
		(end 21.422614 -386.550154)
		(stroke
			(width 0.07366)
			(type default)
		)
		(layer "In4.Cu")
	)
	(gr_line
		(start 22.094444 -386.832348)
		(end 22.094444 -386.66166)
		(stroke
			(width 0.07366)
			(type default)
		)
		(layer "In4.Cu")
	)
	(gr_line
		(start 22.094444 -386.66166)
		(end 21.788882 -386.356098)
		(stroke
			(width 0.07366)
			(type default)
		)
		(layer "In4.Cu")
	)
	(gr_line
		(start 22.832314 -385.52882)
		(end 22.80539 -385.52882)
		(stroke
			(width 0.07366)
			(type default)
		)
		(layer "In4.Cu")
	)
	(gr_line
		(start 23.113492 -385.809998)
		(end 22.832314 -385.52882)
		(stroke
			(width 0.07366)
			(type default)
		)
		(layer "In4.Cu")
	)
	(gr_line
		(start 23.113492 -384.946398)
		(end 22.80666 -385.25323)
		(stroke
			(width 0.07366)
			(type default)
		)
		(layer "In4.Cu")
	)
	(gr_line
		(start 23.33752 -387.01726)
		(end 23.21687 -387.13791)
		(stroke
			(width 0.07366)
			(type default)
		)
		(layer "In4.Cu")
	)
	(gr_line
		(start 23.76932 -387.01726)
		(end 23.33752 -387.01726)
		(stroke
			(width 0.07366)
			(type default)
		)
		(layer "In4.Cu")
	)
	(gr_line
		(start 23.88997 -387.13791)
		(end 23.76932 -387.01726)
		(stroke
			(width 0.07366)
			(type default)
		)
		(layer "In4.Cu")
	)
	(gr_line
		(start 23.89124 -387.4135)
		(end 23.2156 -387.4135)
		(stroke
			(width 0.07366)
			(type default)
		)
		(layer "In4.Cu")
	)
	(gr_line
		(start 23.896066 -373.440452)
		(end 24.201628 -373.746014)
		(stroke
			(width 0.07366)
			(type default)
		)
		(layer "In4.Cu")
	)
	(gr_line
		(start 23.896066 -373.26951)
		(end 23.896066 -373.440452)
		(stroke
			(width 0.07366)
			(type default)
		)
		(layer "In4.Cu")
	)
	(gr_line
		(start 24.090122 -373.07393)
		(end 24.56815 -373.551958)
		(stroke
			(width 0.07366)
			(type default)
		)
		(layer "In4.Cu")
	)
	(gr_line
		(start 24.201628 -373.746014)
		(end 24.37257 -373.746014)
		(stroke
			(width 0.07366)
			(type default)
		)
		(layer "In4.Cu")
	)
	(gr_line
		(start 24.97074 -385.81584)
		(end 25.09139 -385.93649)
		(stroke
			(width 0.07366)
			(type default)
		)
		(layer "In4.Cu")
	)
	(gr_line
		(start 24.97074 -385.38404)
		(end 24.97074 -385.81584)
		(stroke
			(width 0.07366)
			(type default)
		)
		(layer "In4.Cu")
	)
	(gr_line
		(start 24.97074 -384.7084)
		(end 25.09139 -384.82905)
		(stroke
			(width 0.07366)
			(type default)
		)
		(layer "In4.Cu")
	)
	(gr_line
		(start 24.97074 -384.2766)
		(end 24.97074 -384.7084)
		(stroke
			(width 0.07366)
			(type default)
		)
		(layer "In4.Cu")
	)
	(gr_line
		(start 24.97074 -383.60096)
		(end 25.09139 -383.72161)
		(stroke
			(width 0.07366)
			(type default)
		)
		(layer "In4.Cu")
	)
	(gr_line
		(start 24.97074 -383.16916)
		(end 24.97074 -383.60096)
		(stroke
			(width 0.07366)
			(type default)
		)
		(layer "In4.Cu")
	)
	(gr_line
		(start 24.97074 -382.49352)
		(end 25.09139 -382.61417)
		(stroke
			(width 0.07366)
			(type default)
		)
		(layer "In4.Cu")
	)
	(gr_line
		(start 24.97074 -382.06172)
		(end 24.97074 -382.49352)
		(stroke
			(width 0.07366)
			(type default)
		)
		(layer "In4.Cu")
	)
	(gr_line
		(start 24.97074 -381.38608)
		(end 25.09139 -381.50673)
		(stroke
			(width 0.07366)
			(type default)
		)
		(layer "In4.Cu")
	)
	(gr_line
		(start 24.97074 -380.95428)
		(end 24.97074 -381.38608)
		(stroke
			(width 0.07366)
			(type default)
		)
		(layer "In4.Cu")
	)
	(gr_line
		(start 24.97074 -380.27864)
		(end 25.09139 -380.39929)
		(stroke
			(width 0.07366)
			(type default)
		)
		(layer "In4.Cu")
	)
	(gr_line
		(start 24.97074 -379.84684)
		(end 24.97074 -380.27864)
		(stroke
			(width 0.07366)
			(type default)
		)
		(layer "In4.Cu")
	)
	(gr_line
		(start 24.97074 -379.1712)
		(end 25.09139 -379.29185)
		(stroke
			(width 0.07366)
			(type default)
		)
		(layer "In4.Cu")
	)
	(gr_line
		(start 24.97074 -378.7394)
		(end 24.97074 -379.1712)
		(stroke
			(width 0.07366)
			(type default)
		)
		(layer "In4.Cu")
	)
	(gr_line
		(start 24.97074 -378.06376)
		(end 25.09139 -378.18441)
		(stroke
			(width 0.07366)
			(type default)
		)
		(layer "In4.Cu")
	)
	(gr_line
		(start 24.97074 -377.63196)
		(end 24.97074 -378.06376)
		(stroke
			(width 0.07366)
			(type default)
		)
		(layer "In4.Cu")
	)
	(gr_line
		(start 25.09139 -385.26339)
		(end 24.97074 -385.38404)
		(stroke
			(width 0.07366)
			(type default)
		)
		(layer "In4.Cu")
	)
	(gr_line
		(start 25.09139 -384.15595)
		(end 24.97074 -384.2766)
		(stroke
			(width 0.07366)
			(type default)
		)
		(layer "In4.Cu")
	)
	(gr_line
		(start 25.09139 -383.04851)
		(end 24.97074 -383.16916)
		(stroke
			(width 0.07366)
			(type default)
		)
		(layer "In4.Cu")
	)
	(gr_line
		(start 25.09139 -381.94107)
		(end 24.97074 -382.06172)
		(stroke
			(width 0.07366)
			(type default)
		)
		(layer "In4.Cu")
	)
	(gr_line
		(start 25.09139 -380.83363)
		(end 24.97074 -380.95428)
		(stroke
			(width 0.07366)
			(type default)
		)
		(layer "In4.Cu")
	)
	(gr_line
		(start 25.09139 -379.72619)
		(end 24.97074 -379.84684)
		(stroke
			(width 0.07366)
			(type default)
		)
		(layer "In4.Cu")
	)
	(gr_line
		(start 25.09139 -378.61875)
		(end 24.97074 -378.7394)
		(stroke
			(width 0.07366)
			(type default)
		)
		(layer "In4.Cu")
	)
	(gr_line
		(start 25.09139 -377.51131)
		(end 24.97074 -377.63196)
		(stroke
			(width 0.07366)
			(type default)
		)
		(layer "In4.Cu")
	)
	(gr_line
		(start 25.36698 -385.26212)
		(end 25.36698 -385.93776)
		(stroke
			(width 0.07366)
			(type default)
		)
		(layer "In4.Cu")
	)
	(gr_line
		(start 25.36698 -384.15468)
		(end 25.36698 -384.83032)
		(stroke
			(width 0.07366)
			(type default)
		)
		(layer "In4.Cu")
	)
	(gr_line
		(start 25.36698 -383.04724)
		(end 25.36698 -383.72288)
		(stroke
			(width 0.07366)
			(type default)
		)
		(layer "In4.Cu")
	)
	(gr_line
		(start 25.36698 -381.9398)
		(end 25.36698 -382.61544)
		(stroke
			(width 0.07366)
			(type default)
		)
		(layer "In4.Cu")
	)
	(gr_line
		(start 25.36698 -380.83236)
		(end 25.36698 -381.508)
		(stroke
			(width 0.07366)
			(type default)
		)
		(layer "In4.Cu")
	)
	(gr_line
		(start 25.36698 -379.72492)
		(end 25.36698 -380.40056)
		(stroke
			(width 0.07366)
			(type default)
		)
		(layer "In4.Cu")
	)
	(gr_line
		(start 25.36698 -378.61748)
		(end 25.36698 -379.29312)
		(stroke
			(width 0.07366)
			(type default)
		)
		(layer "In4.Cu")
	)
	(gr_line
		(start 25.36698 -377.51004)
		(end 25.36698 -378.18568)
		(stroke
			(width 0.07366)
			(type default)
		)
		(layer "In4.Cu")
	)
	(gr_line
		(start 33.265872 -91.182698)
		(end 33.062672 -91.182698)
		(stroke
			(width 0.07366)
			(type default)
		)
		(layer "In4.Cu")
	)
	(gr_line
		(start 33.332674 -90.52306)
		(end 32.867092 -90.988642)
		(stroke
			(width 0.07366)
			(type default)
		)
		(layer "In4.Cu")
	)
	(gr_line
		(start 33.52673 -90.92184)
		(end 33.265872 -91.182698)
		(stroke
			(width 0.07366)
			(type default)
		)
		(layer "In4.Cu")
	)
	(gr_line
		(start 33.52673 -90.71864)
		(end 33.52673 -90.92184)
		(stroke
			(width 0.07366)
			(type default)
		)
		(layer "In4.Cu")
	)
	(gr_line
		(start 34.269172 -90.179398)
		(end 34.065972 -90.179398)
		(stroke
			(width 0.07366)
			(type default)
		)
		(layer "In4.Cu")
	)
	(gr_line
		(start 34.335974 -89.51976)
		(end 33.870392 -89.985342)
		(stroke
			(width 0.07366)
			(type default)
		)
		(layer "In4.Cu")
	)
	(gr_line
		(start 34.53003 -89.91854)
		(end 34.269172 -90.179398)
		(stroke
			(width 0.07366)
			(type default)
		)
		(layer "In4.Cu")
	)
	(gr_line
		(start 34.53003 -89.71534)
		(end 34.53003 -89.91854)
		(stroke
			(width 0.07366)
			(type default)
		)
		(layer "In4.Cu")
	)
	(gr_line
		(start 35.260788 -89.15527)
		(end 35.0901 -89.15527)
		(stroke
			(width 0.07366)
			(type default)
		)
		(layer "In4.Cu")
	)
	(gr_line
		(start 35.372294 -88.48344)
		(end 34.89452 -88.961214)
		(stroke
			(width 0.07366)
			(type default)
		)
		(layer "In4.Cu")
	)
	(gr_line
		(start 35.56635 -88.849708)
		(end 35.260788 -89.15527)
		(stroke
			(width 0.07366)
			(type default)
		)
		(layer "In4.Cu")
	)
	(gr_line
		(start 35.56635 -88.67902)
		(end 35.56635 -88.849708)
		(stroke
			(width 0.07366)
			(type default)
		)
		(layer "In4.Cu")
	)
	(gr_line
		(start 36.754816 -87.961724)
		(end 36.596574 -87.896446)
		(stroke
			(width 0.07366)
			(type default)
		)
		(layer "In4.Cu")
	)
	(gr_line
		(start 37.114734 -87.38362)
		(end 36.490402 -87.642192)
		(stroke
			(width 0.07366)
			(type default)
		)
		(layer "In4.Cu")
	)
	(gr_line
		(start 37.15385 -87.796624)
		(end 36.754816 -87.961724)
		(stroke
			(width 0.07366)
			(type default)
		)
		(layer "In4.Cu")
	)
	(gr_line
		(start 37.219382 -87.638636)
		(end 37.15385 -87.796624)
		(stroke
			(width 0.07366)
			(type default)
		)
		(layer "In4.Cu")
	)
	(gr_line
		(start 59.321446 -56.800496)
		(end 59.133486 -56.722772)
		(stroke
			(width 0.07366)
			(type default)
		)
		(layer "In4.Cu")
	)
	(gr_line
		(start 59.63539 -56.21655)
		(end 59.02706 -56.468518)
		(stroke
			(width 0.07366)
			(type default)
		)
		(layer "In4.Cu")
	)
	(gr_line
		(start 59.661806 -56.659526)
		(end 59.321446 -56.800496)
		(stroke
			(width 0.07366)
			(type default)
		)
		(layer "In4.Cu")
	)
	(gr_line
		(start 59.73953 -56.471566)
		(end 59.661806 -56.659526)
		(stroke
			(width 0.07366)
			(type default)
		)
		(layer "In4.Cu")
	)
	(gr_line
		(start 129.18186 -18.85442)
		(end 129.06121 -18.97507)
		(stroke
			(width 0.07366)
			(type default)
		)
		(layer "In4.Cu")
	)
	(gr_line
		(start 129.61366 -18.85442)
		(end 129.18186 -18.85442)
		(stroke
			(width 0.07366)
			(type default)
		)
		(layer "In4.Cu")
	)
	(gr_line
		(start 129.73431 -18.97507)
		(end 129.61366 -18.85442)
		(stroke
			(width 0.07366)
			(type default)
		)
		(layer "In4.Cu")
	)
	(gr_line
		(start 129.73558 -19.25066)
		(end 129.05994 -19.25066)
		(stroke
			(width 0.07366)
			(type default)
		)
		(layer "In4.Cu")
	)
	(gr_line
		(start 132.014468 -18.144744)
		(end 132.309108 -18.439384)
		(stroke
			(width 0.07366)
			(type default)
		)
		(layer "In4.Cu")
	)
	(gr_line
		(start 132.314696 -10.537952)
		(end 132.020056 -10.243312)
		(stroke
			(width 0.07366)
			(type default)
		)
		(layer "In4.Cu")
	)
	(gr_line
		(start 132.589016 -10.537952)
		(end 132.883656 -10.243312)
		(stroke
			(width 0.07366)
			(type default)
		)
		(layer "In4.Cu")
	)
	(gr_line
		(start 132.878068 -18.144744)
		(end 132.583428 -18.439384)
		(stroke
			(width 0.07366)
			(type default)
		)
		(layer "In4.Cu")
	)
	(gr_poly
		(pts
			(xy 230.38054 -434.93182)
			(arc
				(start 230.38054 -423.43578)
				(mid 230.404693 -423.314264)
				(end 230.473504 -423.211244)
			)
			(arc
				(start 232.965244 -420.719504)
				(mid 233.068276 -420.650723)
				(end 233.18978 -420.62654)
			)
			(xy 270.36522 -420.62654)
			(arc
				(start 275.456396 -415.535364)
				(mid 275.559428 -415.466583)
				(end 275.680932 -415.4424)
			)
			(xy 279.79624 -415.4424) (xy 280.19756 -415.04108) (xy 280.19756 -408.29992) (xy 279.96896 -408.07132)
			(xy 239.84458 -408.07132)
			(arc
				(start 233.163364 -414.752536)
				(mid 233.060332 -414.821317)
				(end 232.938828 -414.8455)
			)
			(xy 207.34528 -414.8455) (xy 206.49184 -415.69894) (xy 206.49184 -435.39156) (xy 207.63484 -436.53456)
			(xy 228.7778 -436.53456)
		)
		(stroke
			(width 0)
			(type solid)
		)
		(fill yes)
		(layer "In5.Cu")
		(net "P12V_PSU")
	)
	(gr_poly
		(pts
			(xy 531.7998 -462.520284) (xy 531.855607 -462.519775) (xy 531.96691 -462.511434) (xy 532.077278 -462.494798)
			(xy 532.186094 -462.469962) (xy 532.29275 -462.437062) (xy 532.396649 -462.396285) (xy 532.49721 -462.347857)
			(xy 532.593871 -462.292049) (xy 532.686092 -462.229174) (xy 532.773355 -462.159583) (xy 532.855174 -462.083666)
			(xy 532.931091 -462.001846) (xy 533.000681 -461.914582) (xy 533.063556 -461.822361) (xy 533.119362 -461.7257)
			(xy 533.16779 -461.625138) (xy 533.208566 -461.521239) (xy 533.241465 -461.414583) (xy 533.266301 -461.305766)
			(xy 533.282935 -461.195398) (xy 533.291275 -461.084095) (xy 533.291796 -461.028288) (xy 533.291796 -455.0283)
			(xy 533.291274 -454.972493) (xy 533.282933 -454.861191) (xy 533.266298 -454.750824) (xy 533.241462 -454.642008)
			(xy 533.208563 -454.535353) (xy 533.167786 -454.431454) (xy 533.119358 -454.330893) (xy 533.063551 -454.234233)
			(xy 533.000677 -454.142013) (xy 532.931086 -454.054749) (xy 532.85517 -453.97293) (xy 532.773351 -453.897014)
			(xy 532.686087 -453.827423) (xy 532.593867 -453.764549) (xy 532.497207 -453.708742) (xy 532.396646 -453.660314)
			(xy 532.292747 -453.619537) (xy 532.186092 -453.586638) (xy 532.077276 -453.561802) (xy 531.966909 -453.545167)
			(xy 531.855607 -453.536826) (xy 531.7998 -453.536304) (xy 516.019796 -453.536304) (xy 515.949442 -453.535811)
			(xy 515.808956 -453.527921) (xy 515.669133 -453.512166) (xy 515.530414 -453.488597) (xy 515.393234 -453.457286)
			(xy 515.258026 -453.418334) (xy 515.125215 -453.371861) (xy 514.995218 -453.318014) (xy 514.868445 -453.256963)
			(xy 514.745294 -453.188901) (xy 514.626154 -453.11404) (xy 514.511398 -453.032616) (xy 514.401389 -452.944887)
			(xy 514.296471 -452.851127) (xy 514.196976 -452.751632) (xy 514.103216 -452.646714) (xy 514.015486 -452.536705)
			(xy 513.934063 -452.421949) (xy 513.859201 -452.302809) (xy 513.791138 -452.179659) (xy 513.730087 -452.052886)
			(xy 513.676241 -451.922889) (xy 513.629768 -451.790078) (xy 513.590815 -451.65487) (xy 513.559504 -451.51769)
			(xy 513.535934 -451.378971) (xy 513.520179 -451.239148) (xy 513.512289 -451.098662) (xy 513.5118 -451.028308)
			(xy 513.5118 -312.408316) (xy 513.512284 -312.337962) (xy 513.520173 -312.197474) (xy 513.535926 -312.05765)
			(xy 513.559495 -311.91893) (xy 513.590805 -311.781749) (xy 513.629757 -311.646539) (xy 513.676229 -311.513726)
			(xy 513.730076 -311.383728) (xy 513.791126 -311.256954) (xy 513.859189 -311.133802) (xy 513.93405 -311.01466)
			(xy 514.015474 -310.899903) (xy 514.103203 -310.789893) (xy 514.196964 -310.684974) (xy 514.296459 -310.585477)
			(xy 514.401377 -310.491716) (xy 514.511387 -310.403986) (xy 514.626144 -310.322561) (xy 514.745285 -310.247699)
			(xy 514.868436 -310.179635) (xy 514.99521 -310.118584) (xy 515.125208 -310.064737) (xy 515.25802 -310.018263)
			(xy 515.393229 -309.97931) (xy 515.53041 -309.947999) (xy 515.669131 -309.924429) (xy 515.808954 -309.908674)
			(xy 515.949442 -309.900784) (xy 516.019796 -309.90032) (xy 531.7998 -309.90032) (xy 531.855607 -309.899798)
			(xy 531.96691 -309.891457) (xy 532.077278 -309.874822) (xy 532.186094 -309.849986) (xy 532.292751 -309.817087)
			(xy 532.39665 -309.77631) (xy 532.497211 -309.727883) (xy 532.593873 -309.672076) (xy 532.686094 -309.609202)
			(xy 532.773358 -309.539612) (xy 532.855178 -309.463695) (xy 532.931096 -309.381876) (xy 533.000687 -309.294613)
			(xy 533.063563 -309.202393) (xy 533.119372 -309.105733) (xy 533.167801 -309.005172) (xy 533.208579 -308.901273)
			(xy 533.24148 -308.794618) (xy 533.266318 -308.685802) (xy 533.282955 -308.575434) (xy 533.291297 -308.464131)
			(xy 533.291796 -308.408324) (xy 533.291796 10.40003) (xy 533.291273 10.455836) (xy 533.28293 10.567137)
			(xy 533.266293 10.677502) (xy 533.241455 10.786316) (xy 533.208555 10.89297) (xy 533.167777 10.996866)
			(xy 533.119348 11.097425) (xy 533.063541 11.194084) (xy 533.000666 11.286302) (xy 532.931076 11.373563)
			(xy 532.855159 11.45538) (xy 532.77334 11.531295) (xy 532.686078 11.600884) (xy 532.593858 11.663757)
			(xy 532.497199 11.719562) (xy 532.396639 11.767989) (xy 532.292741 11.808765) (xy 532.186087 11.841663)
			(xy 532.077273 11.866499) (xy 531.966907 11.883134) (xy 531.855606 11.891474) (xy 531.7998 11.892026)
			(xy 475.799912 11.892026) (xy 475.744104 11.891505) (xy 475.632801 11.883165) (xy 475.522432 11.86653)
			(xy 475.413615 11.841695) (xy 475.306958 11.808796) (xy 475.203057 11.76802) (xy 475.102495 11.719593)
			(xy 475.005832 11.663786) (xy 474.91361 11.600912) (xy 474.826345 11.531322) (xy 474.744524 11.455406)
			(xy 474.668605 11.373587) (xy 474.599013 11.286323) (xy 474.536136 11.194103) (xy 474.480327 11.097442)
			(xy 474.431897 10.996881) (xy 474.391117 10.892982) (xy 474.358216 10.786326) (xy 474.333378 10.677509)
			(xy 474.31674 10.567141) (xy 474.308397 10.455838) (xy 474.307916 10.40003) (xy 474.307916 7.335466)
			(xy 526.704041 7.335466) (xy 526.704041 7.464606) (xy 526.711991 7.593501) (xy 526.727861 7.721661)
			(xy 526.75159 7.848602) (xy 526.783089 7.973841) (xy 526.822238 8.096904) (xy 526.868889 8.217323)
			(xy 526.922864 8.334642) (xy 526.983959 8.448416) (xy 527.051942 8.558213) (xy 527.126556 8.663616)
			(xy 527.207517 8.764226) (xy 527.294517 8.859661) (xy 527.387228 8.94956) (xy 527.485298 9.033581)
			(xy 527.588353 9.111405) (xy 527.696004 9.182737) (xy 527.807843 9.247307) (xy 527.923444 9.304869)
			(xy 528.042369 9.355206) (xy 528.164168 9.398126) (xy 528.288378 9.433467) (xy 528.414527 9.461094)
			(xy 528.542139 9.480903) (xy 528.670728 9.492819) (xy 528.799806 9.496796) (xy 528.928884 9.492819)
			(xy 529.057473 9.480903) (xy 529.185085 9.461094) (xy 529.311234 9.433467) (xy 529.435444 9.398126)
			(xy 529.557243 9.355206) (xy 529.676168 9.304869) (xy 529.791769 9.247307) (xy 529.903608 9.182737)
			(xy 530.011259 9.111405) (xy 530.114314 9.033581) (xy 530.212384 8.94956) (xy 530.305095 8.859661)
			(xy 530.392095 8.764226) (xy 530.473056 8.663616) (xy 530.54767 8.558213) (xy 530.615653 8.448416)
			(xy 530.676748 8.334642) (xy 530.730723 8.217323) (xy 530.777374 8.096904) (xy 530.816523 7.973841)
			(xy 530.848022 7.848602) (xy 530.871751 7.721661) (xy 530.887621 7.593501) (xy 530.895571 7.464606)
			(xy 530.896068 7.400036) (xy 530.895571 7.335466) (xy 530.887621 7.206571) (xy 530.871751 7.078411)
			(xy 530.848022 6.95147) (xy 530.816523 6.826231) (xy 530.777374 6.703168) (xy 530.730723 6.582749)
			(xy 530.676748 6.46543) (xy 530.615653 6.351656) (xy 530.54767 6.241859) (xy 530.473056 6.136456)
			(xy 530.392095 6.035846) (xy 530.305095 5.940411) (xy 530.212384 5.850512) (xy 530.114314 5.766491)
			(xy 530.011259 5.688667) (xy 529.903608 5.617335) (xy 529.791769 5.552765) (xy 529.676168 5.495203)
			(xy 529.557243 5.444866) (xy 529.435444 5.401946) (xy 529.311234 5.366605) (xy 529.185085 5.338978)
			(xy 529.057473 5.319169) (xy 528.928884 5.307253) (xy 528.799806 5.303277) (xy 528.670728 5.307253)
			(xy 528.542139 5.319169) (xy 528.414527 5.338978) (xy 528.288378 5.366605) (xy 528.164168 5.401946)
			(xy 528.042369 5.444866) (xy 527.923444 5.495203) (xy 527.807843 5.552765) (xy 527.696004 5.617335)
			(xy 527.588353 5.688667) (xy 527.485298 5.766491) (xy 527.387228 5.850512) (xy 527.294517 5.940411)
			(xy 527.207517 6.035846) (xy 527.126556 6.136456) (xy 527.051942 6.241859) (xy 526.983959 6.351656)
			(xy 526.922864 6.46543) (xy 526.868889 6.582749) (xy 526.822238 6.703168) (xy 526.783089 6.826231)
			(xy 526.75159 6.95147) (xy 526.727861 7.078411) (xy 526.711991 7.206571) (xy 526.704041 7.335466)
			(xy 474.307916 7.335466) (xy 474.307916 -77.67193) (xy 474.307428 -77.765094) (xy 474.299715 -77.951262)
			(xy 474.284317 -78.136953) (xy 474.261258 -78.321849) (xy 474.23058 -78.505634) (xy 474.192333 -78.687994)
			(xy 474.146584 -78.868619) (xy 474.093411 -79.047199) (xy 474.032904 -79.223429) (xy 473.965167 -79.397008)
			(xy 473.890315 -79.56764) (xy 473.808477 -79.735034) (xy 473.719792 -79.898903) (xy 473.624411 -80.058968)
			(xy 473.522498 -80.214955) (xy 473.414227 -80.366597) (xy 473.299782 -80.513637) (xy 473.17936 -80.655821)
			(xy 473.053165 -80.792909) (xy 472.987624 -80.859122) (xy 471.245184 -82.601562) (xy 471.207836 -82.63956)
			(xy 471.138049 -82.720082) (xy 471.074185 -82.805378) (xy 471.01657 -82.895014) (xy 470.965496 -82.988531)
			(xy 470.921226 -83.085455) (xy 470.883983 -83.18529) (xy 470.853958 -83.287527) (xy 470.831304 -83.391646)
			(xy 470.816136 -83.497117) (xy 470.808532 -83.6034) (xy 470.80805 -83.656678) (xy 470.80805 -404.871936)
			(xy 470.807562 -404.9651) (xy 470.799849 -405.151268) (xy 470.78445 -405.336959) (xy 470.761392 -405.521855)
			(xy 470.730713 -405.70564) (xy 470.692467 -405.888001) (xy 470.646718 -406.068625) (xy 470.593544 -406.247205)
			(xy 470.533038 -406.423435) (xy 470.465301 -406.597015) (xy 470.39045 -406.767647) (xy 470.308612 -406.935041)
			(xy 470.219927 -407.098911) (xy 470.124547 -407.258976) (xy 470.022634 -407.414963) (xy 469.914363 -407.566606)
			(xy 469.799919 -407.713645) (xy 469.679497 -407.855831) (xy 469.553302 -407.992919) (xy 469.487758 -408.059128)
			(xy 468.244936 -409.30195) (xy 468.207612 -409.339964) (xy 468.137859 -409.4205) (xy 468.074028 -409.505805)
			(xy 468.016443 -409.595446) (xy 467.965398 -409.688966) (xy 467.921153 -409.785888) (xy 467.883933 -409.885719)
			(xy 467.853928 -409.98795) (xy 467.831291 -410.092061) (xy 467.816137 -410.197522) (xy 467.808543 -410.303794)
			(xy 467.808056 -410.357066) (xy 467.808056 -439.989976) (xy 467.808577 -440.045784) (xy 467.816916 -440.157089)
			(xy 467.83355 -440.267459) (xy 467.858385 -440.376277) (xy 467.891282 -440.482936) (xy 467.932058 -440.586837)
			(xy 467.980485 -440.687401) (xy 468.036291 -440.784065) (xy 468.099165 -440.876289) (xy 468.168754 -440.963556)
			(xy 468.244671 -441.045378) (xy 468.32649 -441.121299) (xy 468.413753 -441.190893) (xy 468.505974 -441.253771)
			(xy 468.602635 -441.309582) (xy 468.703197 -441.358013) (xy 468.807096 -441.398794) (xy 468.913753 -441.431697)
			(xy 469.02257 -441.456537) (xy 469.13294 -441.473176) (xy 469.244244 -441.48152) (xy 469.300052 -441.481972)
			(xy 471.79992 -441.481972) (xy 471.870274 -441.482466) (xy 472.01076 -441.490356) (xy 472.150582 -441.506112)
			(xy 472.289302 -441.529682) (xy 472.426481 -441.560993) (xy 472.561689 -441.599946) (xy 472.6945 -441.646419)
			(xy 472.824497 -441.700266) (xy 472.95127 -441.761317) (xy 473.07442 -441.82938) (xy 473.19356 -441.904241)
			(xy 473.308316 -441.985664) (xy 473.418325 -442.073394) (xy 473.523243 -442.167153) (xy 473.622738 -442.266648)
			(xy 473.716499 -442.371565) (xy 473.804229 -442.481575) (xy 473.885652 -442.59633) (xy 473.960514 -442.71547)
			(xy 474.028578 -442.83862) (xy 474.089629 -442.965392) (xy 474.143476 -443.095389) (xy 474.18995 -443.2282)
			(xy 474.228904 -443.363407) (xy 474.260216 -443.500587) (xy 474.283787 -443.639306) (xy 474.299543 -443.779128)
			(xy 474.307434 -443.919614) (xy 474.307916 -443.989968) (xy 474.307916 -458.092864) (xy 526.704041 -458.092864)
			(xy 526.704041 -457.963724) (xy 526.711991 -457.834829) (xy 526.727861 -457.706669) (xy 526.75159 -457.579728)
			(xy 526.783089 -457.454489) (xy 526.822238 -457.331426) (xy 526.868889 -457.211007) (xy 526.922864 -457.093688)
			(xy 526.983959 -456.979914) (xy 527.051942 -456.870117) (xy 527.126556 -456.764714) (xy 527.207517 -456.664104)
			(xy 527.294517 -456.568669) (xy 527.387228 -456.47877) (xy 527.485298 -456.394749) (xy 527.588353 -456.316925)
			(xy 527.696004 -456.245593) (xy 527.807843 -456.181023) (xy 527.923444 -456.123461) (xy 528.042369 -456.073124)
			(xy 528.164168 -456.030204) (xy 528.288378 -455.994863) (xy 528.414527 -455.967236) (xy 528.542139 -455.947427)
			(xy 528.670728 -455.935511) (xy 528.799806 -455.931535) (xy 528.928884 -455.935511) (xy 529.057473 -455.947427)
			(xy 529.185085 -455.967236) (xy 529.311234 -455.994863) (xy 529.435444 -456.030204) (xy 529.557243 -456.073124)
			(xy 529.676168 -456.123461) (xy 529.791769 -456.181023) (xy 529.903608 -456.245593) (xy 530.011259 -456.316925)
			(xy 530.114314 -456.394749) (xy 530.212384 -456.47877) (xy 530.305095 -456.568669) (xy 530.392095 -456.664104)
			(xy 530.473056 -456.764714) (xy 530.54767 -456.870117) (xy 530.615653 -456.979914) (xy 530.676748 -457.093688)
			(xy 530.730723 -457.211007) (xy 530.777374 -457.331426) (xy 530.816523 -457.454489) (xy 530.848022 -457.579728)
			(xy 530.871751 -457.706669) (xy 530.887621 -457.834829) (xy 530.895571 -457.963724) (xy 530.896068 -458.028294)
			(xy 530.895571 -458.092864) (xy 530.887621 -458.221759) (xy 530.871751 -458.349919) (xy 530.848022 -458.47686)
			(xy 530.816523 -458.602099) (xy 530.777374 -458.725162) (xy 530.730723 -458.845581) (xy 530.676748 -458.9629)
			(xy 530.615653 -459.076674) (xy 530.54767 -459.186471) (xy 530.473056 -459.291874) (xy 530.392095 -459.392484)
			(xy 530.305095 -459.487919) (xy 530.212384 -459.577818) (xy 530.114314 -459.661839) (xy 530.011259 -459.739663)
			(xy 529.903608 -459.810995) (xy 529.791769 -459.875565) (xy 529.676168 -459.933127) (xy 529.557243 -459.983464)
			(xy 529.435444 -460.026384) (xy 529.311234 -460.061725) (xy 529.185085 -460.089352) (xy 529.057473 -460.109161)
			(xy 528.928884 -460.121077) (xy 528.799806 -460.125054) (xy 528.670728 -460.121077) (xy 528.542139 -460.109161)
			(xy 528.414527 -460.089352) (xy 528.288378 -460.061725) (xy 528.164168 -460.026384) (xy 528.042369 -459.983464)
			(xy 527.923444 -459.933127) (xy 527.807843 -459.875565) (xy 527.696004 -459.810995) (xy 527.588353 -459.739663)
			(xy 527.485298 -459.661839) (xy 527.387228 -459.577818) (xy 527.294517 -459.487919) (xy 527.207517 -459.392484)
			(xy 527.126556 -459.291874) (xy 527.051942 -459.186471) (xy 526.983959 -459.076674) (xy 526.922864 -458.9629)
			(xy 526.868889 -458.845581) (xy 526.822238 -458.725162) (xy 526.783089 -458.602099) (xy 526.75159 -458.47686)
			(xy 526.727861 -458.349919) (xy 526.711991 -458.221759) (xy 526.704041 -458.092864) (xy 474.307916 -458.092864)
			(xy 474.307916 -461.028288) (xy 474.308425 -461.084096) (xy 474.316765 -461.195399) (xy 474.3334 -461.305768)
			(xy 474.358236 -461.414584) (xy 474.391134 -461.521241) (xy 474.431912 -461.625141) (xy 474.480339 -461.725703)
			(xy 474.536147 -461.822365) (xy 474.599022 -461.914586) (xy 474.668612 -462.00185) (xy 474.74453 -462.08367)
			(xy 474.82635 -462.159588) (xy 474.913614 -462.229178) (xy 475.005835 -462.292053) (xy 475.102497 -462.347861)
			(xy 475.203059 -462.396288) (xy 475.306959 -462.437066) (xy 475.413616 -462.469964) (xy 475.522432 -462.4948)
			(xy 475.632801 -462.511435) (xy 475.744104 -462.519775) (xy 475.799912 -462.520284)
		)
		(stroke
			(width 0)
			(type solid)
		)
		(fill yes)
		(layer "In5.Cu")
		(net "T1_GND")
	)
	(gr_poly
		(pts
			(xy 256.292096 -31.120588) (xy 256.292096 -11.780012) (xy 256.29258 -11.709658) (xy 256.300469 -11.56917)
			(xy 256.316223 -11.429347) (xy 256.339792 -11.290626) (xy 256.371101 -11.153445) (xy 256.410054 -11.018236)
			(xy 256.456527 -10.885423) (xy 256.510373 -10.755425) (xy 256.571423 -10.628651) (xy 256.639486 -10.505499)
			(xy 256.714347 -10.386357) (xy 256.795771 -10.2716) (xy 256.883501 -10.16159) (xy 256.977261 -10.056671)
			(xy 257.076757 -9.957175) (xy 257.181674 -9.863414) (xy 257.291684 -9.775683) (xy 257.406441 -9.694258)
			(xy 257.525582 -9.619396) (xy 257.648733 -9.551333) (xy 257.775507 -9.490281) (xy 257.905504 -9.436434)
			(xy 258.038317 -9.38996) (xy 258.173526 -9.351006) (xy 258.310706 -9.319695) (xy 258.449427 -9.296125)
			(xy 258.589251 -9.280371) (xy 258.729738 -9.272481) (xy 258.800092 -9.272016) (xy 383.601976 -9.272016)
			(xy 383.657784 -9.271508) (xy 383.769089 -9.263168) (xy 383.879459 -9.246534) (xy 383.988278 -9.221699)
			(xy 384.094936 -9.188801) (xy 384.198838 -9.148025) (xy 384.299402 -9.099598) (xy 384.396066 -9.043791)
			(xy 384.488289 -8.980916) (xy 384.575555 -8.911326) (xy 384.657377 -8.835408) (xy 384.733297 -8.753588)
			(xy 384.80289 -8.666324) (xy 384.865767 -8.574103) (xy 384.921577 -8.477441) (xy 384.970007 -8.376878)
			(xy 385.010787 -8.272978) (xy 385.043688 -8.16632) (xy 385.068526 -8.057503) (xy 385.085163 -7.947133)
			(xy 385.093506 -7.835828) (xy 385.093972 -7.78002) (xy 385.093972 0.999998) (xy 385.094465 1.070352)
			(xy 385.102355 1.210839) (xy 385.118109 1.350662) (xy 385.141678 1.489383) (xy 385.172988 1.626563)
			(xy 385.211941 1.761772) (xy 385.258413 1.894584) (xy 385.312259 2.024582) (xy 385.37331 2.151356)
			(xy 385.441373 2.274507) (xy 385.516233 2.393649) (xy 385.597656 2.508405) (xy 385.685386 2.618416)
			(xy 385.779146 2.723335) (xy 385.878641 2.822831) (xy 385.983558 2.916592) (xy 386.093567 3.004323)
			(xy 386.208323 3.085748) (xy 386.327463 3.16061) (xy 386.450614 3.228674) (xy 386.577387 3.289727)
			(xy 386.707384 3.343575) (xy 386.840195 3.390049) (xy 386.975404 3.429003) (xy 387.112584 3.460315)
			(xy 387.251304 3.483887) (xy 387.391127 3.499643) (xy 387.531614 3.507534) (xy 387.601968 3.507994)
			(xy 456.202034 3.507994) (xy 456.272387 3.5075) (xy 456.412872 3.499608) (xy 456.552693 3.483853)
			(xy 456.691411 3.460282) (xy 456.828589 3.42897) (xy 456.963796 3.390016) (xy 457.096605 3.343542)
			(xy 457.226601 3.289695) (xy 457.353372 3.228644) (xy 457.476521 3.16058) (xy 457.595659 3.085719)
			(xy 457.710413 3.004295) (xy 457.820421 2.916565) (xy 457.925337 2.822806) (xy 458.02483 2.723311)
			(xy 458.118589 2.618393) (xy 458.206317 2.508384) (xy 458.287739 2.393629) (xy 458.362598 2.27449)
			(xy 458.43066 2.15134) (xy 458.49171 2.024568) (xy 458.545555 1.894572) (xy 458.592027 1.761761)
			(xy 458.630979 1.626554) (xy 458.662289 1.489376) (xy 458.685858 1.350658) (xy 458.701612 1.210836)
			(xy 458.709501 1.070351) (xy 458.71003 0.999998) (xy 458.71003 -7.78002) (xy 458.71054 -7.835827)
			(xy 458.718882 -7.947128) (xy 458.735519 -8.057494) (xy 458.760357 -8.166309) (xy 458.793257 -8.272963)
			(xy 458.834035 -8.37686) (xy 458.882464 -8.47742) (xy 458.938272 -8.574079) (xy 459.001148 -8.666297)
			(xy 459.070739 -8.753559) (xy 459.146656 -8.835376) (xy 459.228476 -8.911291) (xy 459.31574 -8.98088)
			(xy 459.40796 -9.043752) (xy 459.504621 -9.099557) (xy 459.605182 -9.147983) (xy 459.70908 -9.188758)
			(xy 459.815736 -9.221655) (xy 459.924551 -9.24649) (xy 460.034918 -9.263123) (xy 460.146219 -9.271462)
			(xy 460.202026 -9.272016) (xy 464.327748 -9.272016) (xy 464.332574 -9.271) (xy 464.357024 -9.266474)
			(xy 464.406516 -9.261643) (xy 464.43138 -9.261348) (xy 464.456244 -9.26164) (xy 464.505735 -9.266479)
			(xy 464.530186 -9.271) (xy 464.535012 -9.272016) (xy 469.799924 -9.272016) (xy 469.855731 -9.271493)
			(xy 469.967032 -9.263151) (xy 470.077399 -9.246514) (xy 470.186213 -9.221677) (xy 470.292868 -9.188777)
			(xy 470.396765 -9.147999) (xy 470.497325 -9.099571) (xy 470.593985 -9.043764) (xy 470.686204 -8.980889)
			(xy 470.773467 -8.911299) (xy 470.855285 -8.835382) (xy 470.931202 -8.753564) (xy 471.000791 -8.666301)
			(xy 471.063666 -8.574082) (xy 471.119473 -8.477422) (xy 471.167901 -8.376862) (xy 471.208678 -8.272964)
			(xy 471.241578 -8.166309) (xy 471.266415 -8.057495) (xy 471.283051 -7.947128) (xy 471.291394 -7.835827)
			(xy 471.29192 -7.78002) (xy 471.29192 10.40003) (xy 471.291397 10.455837) (xy 471.283054 10.567138)
			(xy 471.266417 10.677504) (xy 471.241579 10.786319) (xy 471.208679 10.892973) (xy 471.167901 10.99687)
			(xy 471.119473 11.09743) (xy 471.063666 11.194089) (xy 471.000791 11.286308) (xy 470.931201 11.373571)
			(xy 470.855284 11.455389) (xy 470.773466 11.531305) (xy 470.686203 11.600895) (xy 470.593984 11.663769)
			(xy 470.497324 11.719576) (xy 470.396765 11.768004) (xy 470.292867 11.808781) (xy 470.186213 11.841681)
			(xy 470.077398 11.866518) (xy 469.967032 11.883155) (xy 469.855731 11.891497) (xy 469.799924 11.892026)
			(xy 1.999996 11.892026) (xy 1.944189 11.891504) (xy 1.832887 11.883163) (xy 1.72252 11.866527) (xy 1.613705 11.841691)
			(xy 1.50705 11.808792) (xy 1.403151 11.768014) (xy 1.302591 11.719587) (xy 1.20593 11.66378) (xy 1.113711 11.600905)
			(xy 1.026448 11.531315) (xy 0.944629 11.455398) (xy 0.868712 11.373579) (xy 0.799122 11.286316) (xy 0.736248 11.194096)
			(xy 0.680441 11.097436) (xy 0.632014 10.996875) (xy 0.591237 10.892977) (xy 0.558338 10.786321) (xy 0.533502 10.677506)
			(xy 0.516867 10.567139) (xy 0.508526 10.455837) (xy 0.508 10.40003) (xy 0.508 7.335466) (xy 2.904225 7.335466)
			(xy 2.904225 7.464606) (xy 2.912175 7.593501) (xy 2.928045 7.721661) (xy 2.951774 7.848602) (xy 2.983273 7.973841)
			(xy 3.022422 8.096904) (xy 3.069073 8.217323) (xy 3.123048 8.334642) (xy 3.184143 8.448416) (xy 3.252126 8.558213)
			(xy 3.32674 8.663616) (xy 3.407701 8.764226) (xy 3.494701 8.859661) (xy 3.587412 8.94956) (xy 3.685482 9.033581)
			(xy 3.788537 9.111405) (xy 3.896188 9.182737) (xy 4.008027 9.247307) (xy 4.123628 9.304869) (xy 4.242553 9.355206)
			(xy 4.364352 9.398126) (xy 4.488562 9.433467) (xy 4.614711 9.461094) (xy 4.742323 9.480903) (xy 4.870912 9.492819)
			(xy 4.99999 9.496796) (xy 5.129068 9.492819) (xy 5.257657 9.480903) (xy 5.385269 9.461094) (xy 5.511418 9.433467)
			(xy 5.635628 9.398126) (xy 5.757427 9.355206) (xy 5.876352 9.304869) (xy 5.991953 9.247307) (xy 6.020338 9.230919)
			(xy 256.921241 9.230919) (xy 256.921241 9.316669) (xy 256.929153 9.402052) (xy 256.944909 9.486342)
			(xy 256.968376 9.568818) (xy 256.999352 9.648777) (xy 257.037574 9.725537) (xy 257.082715 9.798443)
			(xy 257.134391 9.866872) (xy 257.19216 9.930242) (xy 257.25553 9.988011) (xy 257.323959 10.039687)
			(xy 257.396865 10.084828) (xy 257.473625 10.12305) (xy 257.553584 10.154026) (xy 257.63606 10.177493)
			(xy 257.72035 10.193249) (xy 257.805733 10.201161) (xy 257.891483 10.201161) (xy 257.976866 10.193249)
			(xy 258.061156 10.177493) (xy 258.143632 10.154026) (xy 258.223591 10.12305) (xy 258.300351 10.084828)
			(xy 258.373257 10.039687) (xy 258.441686 9.988011) (xy 258.505056 9.930242) (xy 258.562825 9.866872)
			(xy 258.614501 9.798443) (xy 258.659642 9.725537) (xy 258.697864 9.648777) (xy 258.72884 9.568818)
			(xy 258.752307 9.486342) (xy 258.768063 9.402052) (xy 258.775975 9.316669) (xy 258.77647 9.273794)
			(xy 258.775975 9.230919) (xy 263.271241 9.230919) (xy 263.271241 9.316669) (xy 263.279153 9.402052)
			(xy 263.294909 9.486342) (xy 263.318376 9.568818) (xy 263.349352 9.648777) (xy 263.387574 9.725537)
			(xy 263.432715 9.798443) (xy 263.484391 9.866872) (xy 263.54216 9.930242) (xy 263.60553 9.988011)
			(xy 263.673959 10.039687) (xy 263.746865 10.084828) (xy 263.823625 10.12305) (xy 263.903584 10.154026)
			(xy 263.98606 10.177493) (xy 264.07035 10.193249) (xy 264.155733 10.201161) (xy 264.241483 10.201161)
			(xy 264.326866 10.193249) (xy 264.411156 10.177493) (xy 264.493632 10.154026) (xy 264.573591 10.12305)
			(xy 264.650351 10.084828) (xy 264.723257 10.039687) (xy 264.791686 9.988011) (xy 264.855056 9.930242)
			(xy 264.912825 9.866872) (xy 264.964501 9.798443) (xy 265.009642 9.725537) (xy 265.047864 9.648777)
			(xy 265.07884 9.568818) (xy 265.102307 9.486342) (xy 265.118063 9.402052) (xy 265.125975 9.316669)
			(xy 265.12647 9.273794) (xy 265.125975 9.230919) (xy 324.845921 9.230919) (xy 324.845921 9.316669)
			(xy 324.853833 9.402052) (xy 324.869589 9.486342) (xy 324.893056 9.568818) (xy 324.924032 9.648777)
			(xy 324.962254 9.725537) (xy 325.007395 9.798443) (xy 325.059071 9.866872) (xy 325.11684 9.930242)
			(xy 325.18021 9.988011) (xy 325.248639 10.039687) (xy 325.321545 10.084828) (xy 325.398305 10.12305)
			(xy 325.478264 10.154026) (xy 325.56074 10.177493) (xy 325.64503 10.193249) (xy 325.730413 10.201161)
			(xy 325.816163 10.201161) (xy 325.901546 10.193249) (xy 325.985836 10.177493) (xy 326.068312 10.154026)
			(xy 326.148271 10.12305) (xy 326.225031 10.084828) (xy 326.297937 10.039687) (xy 326.366366 9.988011)
			(xy 326.429736 9.930242) (xy 326.487505 9.866872) (xy 326.539181 9.798443) (xy 326.584322 9.725537)
			(xy 326.622544 9.648777) (xy 326.65352 9.568818) (xy 326.676987 9.486342) (xy 326.692743 9.402052)
			(xy 326.700655 9.316669) (xy 326.70115 9.273794) (xy 326.700655 9.230919) (xy 331.195921 9.230919)
			(xy 331.195921 9.316669) (xy 331.203833 9.402052) (xy 331.219589 9.486342) (xy 331.243056 9.568818)
			(xy 331.274032 9.648777) (xy 331.312254 9.725537) (xy 331.357395 9.798443) (xy 331.409071 9.866872)
			(xy 331.46684 9.930242) (xy 331.53021 9.988011) (xy 331.598639 10.039687) (xy 331.671545 10.084828)
			(xy 331.748305 10.12305) (xy 331.828264 10.154026) (xy 331.91074 10.177493) (xy 331.99503 10.193249)
			(xy 332.080413 10.201161) (xy 332.166163 10.201161) (xy 332.251546 10.193249) (xy 332.335836 10.177493)
			(xy 332.418312 10.154026) (xy 332.498271 10.12305) (xy 332.575031 10.084828) (xy 332.647937 10.039687)
			(xy 332.716366 9.988011) (xy 332.779736 9.930242) (xy 332.837505 9.866872) (xy 332.889181 9.798443)
			(xy 332.934322 9.725537) (xy 332.972544 9.648777) (xy 333.00352 9.568818) (xy 333.026987 9.486342)
			(xy 333.042743 9.402052) (xy 333.050655 9.316669) (xy 333.05115 9.273794) (xy 333.050655 9.230919)
			(xy 335.488267 9.230919) (xy 335.488267 9.316669) (xy 335.496179 9.402052) (xy 335.511935 9.486342)
			(xy 335.535402 9.568818) (xy 335.566378 9.648777) (xy 335.6046 9.725537) (xy 335.649741 9.798443)
			(xy 335.701417 9.866872) (xy 335.759186 9.930242) (xy 335.822556 9.988011) (xy 335.890985 10.039687)
			(xy 335.963891 10.084828) (xy 336.040651 10.12305) (xy 336.12061 10.154026) (xy 336.203086 10.177493)
			(xy 336.287376 10.193249) (xy 336.372759 10.201161) (xy 336.458509 10.201161) (xy 336.543892 10.193249)
			(xy 336.628182 10.177493) (xy 336.710658 10.154026) (xy 336.790617 10.12305) (xy 336.867377 10.084828)
			(xy 336.940283 10.039687) (xy 337.008712 9.988011) (xy 337.072082 9.930242) (xy 337.129851 9.866872)
			(xy 337.181527 9.798443) (xy 337.226668 9.725537) (xy 337.26489 9.648777) (xy 337.295866 9.568818)
			(xy 337.319333 9.486342) (xy 337.335089 9.402052) (xy 337.343001 9.316669) (xy 337.343496 9.273794)
			(xy 337.343001 9.230919) (xy 341.838267 9.230919) (xy 341.838267 9.316669) (xy 341.846179 9.402052)
			(xy 341.861935 9.486342) (xy 341.885402 9.568818) (xy 341.916378 9.648777) (xy 341.9546 9.725537)
			(xy 341.999741 9.798443) (xy 342.051417 9.866872) (xy 342.109186 9.930242) (xy 342.172556 9.988011)
			(xy 342.240985 10.039687) (xy 342.313891 10.084828) (xy 342.390651 10.12305) (xy 342.47061 10.154026)
			(xy 342.553086 10.177493) (xy 342.637376 10.193249) (xy 342.722759 10.201161) (xy 342.808509 10.201161)
			(xy 342.893892 10.193249) (xy 342.978182 10.177493) (xy 343.060658 10.154026) (xy 343.140617 10.12305)
			(xy 343.217377 10.084828) (xy 343.290283 10.039687) (xy 343.358712 9.988011) (xy 343.422082 9.930242)
			(xy 343.479851 9.866872) (xy 343.531527 9.798443) (xy 343.576668 9.725537) (xy 343.61489 9.648777)
			(xy 343.645866 9.568818) (xy 343.669333 9.486342) (xy 343.685089 9.402052) (xy 343.693001 9.316669)
			(xy 343.693496 9.273794) (xy 343.693001 9.230919) (xy 373.705107 9.230919) (xy 373.705107 9.316669)
			(xy 373.713019 9.402052) (xy 373.728775 9.486342) (xy 373.752242 9.568818) (xy 373.783218 9.648777)
			(xy 373.82144 9.725537) (xy 373.866581 9.798443) (xy 373.918257 9.866872) (xy 373.976026 9.930242)
			(xy 374.039396 9.988011) (xy 374.107825 10.039687) (xy 374.180731 10.084828) (xy 374.257491 10.12305)
			(xy 374.33745 10.154026) (xy 374.419926 10.177493) (xy 374.504216 10.193249) (xy 374.589599 10.201161)
			(xy 374.675349 10.201161) (xy 374.760732 10.193249) (xy 374.845022 10.177493) (xy 374.927498 10.154026)
			(xy 375.007457 10.12305) (xy 375.084217 10.084828) (xy 375.157123 10.039687) (xy 375.225552 9.988011)
			(xy 375.288922 9.930242) (xy 375.346691 9.866872) (xy 375.398367 9.798443) (xy 375.443508 9.725537)
			(xy 375.48173 9.648777) (xy 375.512706 9.568818) (xy 375.536173 9.486342) (xy 375.551929 9.402052)
			(xy 375.559841 9.316669) (xy 375.560336 9.273794) (xy 375.559841 9.230919) (xy 380.055107 9.230919)
			(xy 380.055107 9.316669) (xy 380.063019 9.402052) (xy 380.078775 9.486342) (xy 380.102242 9.568818)
			(xy 380.133218 9.648777) (xy 380.17144 9.725537) (xy 380.216581 9.798443) (xy 380.268257 9.866872)
			(xy 380.326026 9.930242) (xy 380.389396 9.988011) (xy 380.457825 10.039687) (xy 380.530731 10.084828)
			(xy 380.607491 10.12305) (xy 380.68745 10.154026) (xy 380.769926 10.177493) (xy 380.854216 10.193249)
			(xy 380.939599 10.201161) (xy 381.025349 10.201161) (xy 381.110732 10.193249) (xy 381.195022 10.177493)
			(xy 381.277498 10.154026) (xy 381.357457 10.12305) (xy 381.434217 10.084828) (xy 381.507123 10.039687)
			(xy 381.575552 9.988011) (xy 381.638922 9.930242) (xy 381.696691 9.866872) (xy 381.748367 9.798443)
			(xy 381.793508 9.725537) (xy 381.83173 9.648777) (xy 381.862706 9.568818) (xy 381.886173 9.486342)
			(xy 381.901929 9.402052) (xy 381.909841 9.316669) (xy 381.910336 9.273794) (xy 381.909841 9.230919)
			(xy 381.901929 9.145536) (xy 381.886173 9.061246) (xy 381.862706 8.97877) (xy 381.83173 8.898811)
			(xy 381.793508 8.822051) (xy 381.748367 8.749145) (xy 381.696691 8.680716) (xy 381.638922 8.617346)
			(xy 381.575552 8.559577) (xy 381.507123 8.507901) (xy 381.434217 8.46276) (xy 381.357457 8.424538)
			(xy 381.277498 8.393562) (xy 381.195022 8.370095) (xy 381.110732 8.354339) (xy 381.025349 8.346427)
			(xy 380.939599 8.346427) (xy 380.854216 8.354339) (xy 380.769926 8.370095) (xy 380.68745 8.393562)
			(xy 380.607491 8.424538) (xy 380.530731 8.46276) (xy 380.457825 8.507901) (xy 380.389396 8.559577)
			(xy 380.326026 8.617346) (xy 380.268257 8.680716) (xy 380.216581 8.749145) (xy 380.17144 8.822051)
			(xy 380.133218 8.898811) (xy 380.102242 8.97877) (xy 380.078775 9.061246) (xy 380.063019 9.145536)
			(xy 380.055107 9.230919) (xy 375.559841 9.230919) (xy 375.551929 9.145536) (xy 375.536173 9.061246)
			(xy 375.512706 8.97877) (xy 375.48173 8.898811) (xy 375.443508 8.822051) (xy 375.398367 8.749145)
			(xy 375.346691 8.680716) (xy 375.288922 8.617346) (xy 375.225552 8.559577) (xy 375.157123 8.507901)
			(xy 375.084217 8.46276) (xy 375.007457 8.424538) (xy 374.927498 8.393562) (xy 374.845022 8.370095)
			(xy 374.760732 8.354339) (xy 374.675349 8.346427) (xy 374.589599 8.346427) (xy 374.504216 8.354339)
			(xy 374.419926 8.370095) (xy 374.33745 8.393562) (xy 374.257491 8.424538) (xy 374.180731 8.46276)
			(xy 374.107825 8.507901) (xy 374.039396 8.559577) (xy 373.976026 8.617346) (xy 373.918257 8.680716)
			(xy 373.866581 8.749145) (xy 373.82144 8.822051) (xy 373.783218 8.898811) (xy 373.752242 8.97877)
			(xy 373.728775 9.061246) (xy 373.713019 9.145536) (xy 373.705107 9.230919) (xy 343.693001 9.230919)
			(xy 343.685089 9.145536) (xy 343.669333 9.061246) (xy 343.645866 8.97877) (xy 343.61489 8.898811)
			(xy 343.576668 8.822051) (xy 343.531527 8.749145) (xy 343.479851 8.680716) (xy 343.422082 8.617346)
			(xy 343.358712 8.559577) (xy 343.290283 8.507901) (xy 343.217377 8.46276) (xy 343.140617 8.424538)
			(xy 343.060658 8.393562) (xy 342.978182 8.370095) (xy 342.893892 8.354339) (xy 342.808509 8.346427)
			(xy 342.722759 8.346427) (xy 342.637376 8.354339) (xy 342.553086 8.370095) (xy 342.47061 8.393562)
			(xy 342.390651 8.424538) (xy 342.313891 8.46276) (xy 342.240985 8.507901) (xy 342.172556 8.559577)
			(xy 342.109186 8.617346) (xy 342.051417 8.680716) (xy 341.999741 8.749145) (xy 341.9546 8.822051)
			(xy 341.916378 8.898811) (xy 341.885402 8.97877) (xy 341.861935 9.061246) (xy 341.846179 9.145536)
			(xy 341.838267 9.230919) (xy 337.343001 9.230919) (xy 337.335089 9.145536) (xy 337.319333 9.061246)
			(xy 337.295866 8.97877) (xy 337.26489 8.898811) (xy 337.226668 8.822051) (xy 337.181527 8.749145)
			(xy 337.129851 8.680716) (xy 337.072082 8.617346) (xy 337.008712 8.559577) (xy 336.940283 8.507901)
			(xy 336.867377 8.46276) (xy 336.790617 8.424538) (xy 336.710658 8.393562) (xy 336.628182 8.370095)
			(xy 336.543892 8.354339) (xy 336.458509 8.346427) (xy 336.372759 8.346427) (xy 336.287376 8.354339)
			(xy 336.203086 8.370095) (xy 336.12061 8.393562) (xy 336.040651 8.424538) (xy 335.963891 8.46276)
			(xy 335.890985 8.507901) (xy 335.822556 8.559577) (xy 335.759186 8.617346) (xy 335.701417 8.680716)
			(xy 335.649741 8.749145) (xy 335.6046 8.822051) (xy 335.566378 8.898811) (xy 335.535402 8.97877)
			(xy 335.511935 9.061246) (xy 335.496179 9.145536) (xy 335.488267 9.230919) (xy 333.050655 9.230919)
			(xy 333.042743 9.145536) (xy 333.026987 9.061246) (xy 333.00352 8.97877) (xy 332.972544 8.898811)
			(xy 332.934322 8.822051) (xy 332.889181 8.749145) (xy 332.837505 8.680716) (xy 332.779736 8.617346)
			(xy 332.716366 8.559577) (xy 332.647937 8.507901) (xy 332.575031 8.46276) (xy 332.498271 8.424538)
			(xy 332.418312 8.393562) (xy 332.335836 8.370095) (xy 332.251546 8.354339) (xy 332.166163 8.346427)
			(xy 332.080413 8.346427) (xy 331.99503 8.354339) (xy 331.91074 8.370095) (xy 331.828264 8.393562)
			(xy 331.748305 8.424538) (xy 331.671545 8.46276) (xy 331.598639 8.507901) (xy 331.53021 8.559577)
			(xy 331.46684 8.617346) (xy 331.409071 8.680716) (xy 331.357395 8.749145) (xy 331.312254 8.822051)
			(xy 331.274032 8.898811) (xy 331.243056 8.97877) (xy 331.219589 9.061246) (xy 331.203833 9.145536)
			(xy 331.195921 9.230919) (xy 326.700655 9.230919) (xy 326.692743 9.145536) (xy 326.676987 9.061246)
			(xy 326.65352 8.97877) (xy 326.622544 8.898811) (xy 326.584322 8.822051) (xy 326.539181 8.749145)
			(xy 326.487505 8.680716) (xy 326.429736 8.617346) (xy 326.366366 8.559577) (xy 326.297937 8.507901)
			(xy 326.225031 8.46276) (xy 326.148271 8.424538) (xy 326.068312 8.393562) (xy 325.985836 8.370095)
			(xy 325.901546 8.354339) (xy 325.816163 8.346427) (xy 325.730413 8.346427) (xy 325.64503 8.354339)
			(xy 325.56074 8.370095) (xy 325.478264 8.393562) (xy 325.398305 8.424538) (xy 325.321545 8.46276)
			(xy 325.248639 8.507901) (xy 325.18021 8.559577) (xy 325.11684 8.617346) (xy 325.059071 8.680716)
			(xy 325.007395 8.749145) (xy 324.962254 8.822051) (xy 324.924032 8.898811) (xy 324.893056 8.97877)
			(xy 324.869589 9.061246) (xy 324.853833 9.145536) (xy 324.845921 9.230919) (xy 265.125975 9.230919)
			(xy 265.118063 9.145536) (xy 265.102307 9.061246) (xy 265.07884 8.97877) (xy 265.047864 8.898811)
			(xy 265.009642 8.822051) (xy 264.964501 8.749145) (xy 264.912825 8.680716) (xy 264.855056 8.617346)
			(xy 264.791686 8.559577) (xy 264.723257 8.507901) (xy 264.650351 8.46276) (xy 264.573591 8.424538)
			(xy 264.493632 8.393562) (xy 264.411156 8.370095) (xy 264.326866 8.354339) (xy 264.241483 8.346427)
			(xy 264.155733 8.346427) (xy 264.07035 8.354339) (xy 263.98606 8.370095) (xy 263.903584 8.393562)
			(xy 263.823625 8.424538) (xy 263.746865 8.46276) (xy 263.673959 8.507901) (xy 263.60553 8.559577)
			(xy 263.54216 8.617346) (xy 263.484391 8.680716) (xy 263.432715 8.749145) (xy 263.387574 8.822051)
			(xy 263.349352 8.898811) (xy 263.318376 8.97877) (xy 263.294909 9.061246) (xy 263.279153 9.145536)
			(xy 263.271241 9.230919) (xy 258.775975 9.230919) (xy 258.768063 9.145536) (xy 258.752307 9.061246)
			(xy 258.72884 8.97877) (xy 258.697864 8.898811) (xy 258.659642 8.822051) (xy 258.614501 8.749145)
			(xy 258.562825 8.680716) (xy 258.505056 8.617346) (xy 258.441686 8.559577) (xy 258.373257 8.507901)
			(xy 258.300351 8.46276) (xy 258.223591 8.424538) (xy 258.143632 8.393562) (xy 258.061156 8.370095)
			(xy 257.976866 8.354339) (xy 257.891483 8.346427) (xy 257.805733 8.346427) (xy 257.72035 8.354339)
			(xy 257.63606 8.370095) (xy 257.553584 8.393562) (xy 257.473625 8.424538) (xy 257.396865 8.46276)
			(xy 257.323959 8.507901) (xy 257.25553 8.559577) (xy 257.19216 8.617346) (xy 257.134391 8.680716)
			(xy 257.082715 8.749145) (xy 257.037574 8.822051) (xy 256.999352 8.898811) (xy 256.968376 8.97877)
			(xy 256.944909 9.061246) (xy 256.929153 9.145536) (xy 256.921241 9.230919) (xy 6.020338 9.230919)
			(xy 6.103792 9.182737) (xy 6.211443 9.111405) (xy 6.314498 9.033581) (xy 6.412568 8.94956) (xy 6.505279 8.859661)
			(xy 6.592279 8.764226) (xy 6.67324 8.663616) (xy 6.747854 8.558213) (xy 6.815837 8.448416) (xy 6.876932 8.334642)
			(xy 6.930907 8.217323) (xy 6.977558 8.096904) (xy 7.016707 7.973841) (xy 7.048206 7.848602) (xy 7.071935 7.721661)
			(xy 7.087805 7.593501) (xy 7.095755 7.464606) (xy 7.096252 7.400036) (xy 7.095755 7.335466) (xy 7.087805 7.206571)
			(xy 7.071935 7.078411) (xy 7.048206 6.95147) (xy 7.016707 6.826231) (xy 6.977558 6.703168) (xy 6.97173 6.688125)
			(xy 178.335673 6.688125) (xy 178.335673 6.773875) (xy 178.343585 6.859258) (xy 178.359341 6.943548)
			(xy 178.382808 7.026024) (xy 178.413784 7.105983) (xy 178.452006 7.182743) (xy 178.497147 7.255649)
			(xy 178.548823 7.324078) (xy 178.606592 7.387448) (xy 178.669962 7.445217) (xy 178.738391 7.496893)
			(xy 178.811297 7.542034) (xy 178.888057 7.580256) (xy 178.968016 7.611232) (xy 179.050492 7.634699)
			(xy 179.134782 7.650455) (xy 179.220165 7.658367) (xy 179.305915 7.658367) (xy 179.391298 7.650455)
			(xy 179.475588 7.634699) (xy 179.558064 7.611232) (xy 179.638023 7.580256) (xy 179.714783 7.542034)
			(xy 179.787689 7.496893) (xy 179.856118 7.445217) (xy 179.919488 7.387448) (xy 179.977257 7.324078)
			(xy 180.028933 7.255649) (xy 180.074074 7.182743) (xy 180.112296 7.105983) (xy 180.143272 7.026024)
			(xy 180.166739 6.943548) (xy 180.182495 6.859258) (xy 180.190407 6.773875) (xy 180.190902 6.731)
			(xy 180.190407 6.688125) (xy 184.685673 6.688125) (xy 184.685673 6.773875) (xy 184.693585 6.859258)
			(xy 184.709341 6.943548) (xy 184.732808 7.026024) (xy 184.763784 7.105983) (xy 184.802006 7.182743)
			(xy 184.847147 7.255649) (xy 184.898823 7.324078) (xy 184.956592 7.387448) (xy 185.019962 7.445217)
			(xy 185.088391 7.496893) (xy 185.161297 7.542034) (xy 185.238057 7.580256) (xy 185.318016 7.611232)
			(xy 185.400492 7.634699) (xy 185.484782 7.650455) (xy 185.570165 7.658367) (xy 185.655915 7.658367)
			(xy 185.741298 7.650455) (xy 185.825588 7.634699) (xy 185.908064 7.611232) (xy 185.988023 7.580256)
			(xy 186.064783 7.542034) (xy 186.137689 7.496893) (xy 186.206118 7.445217) (xy 186.269488 7.387448)
			(xy 186.327257 7.324078) (xy 186.378933 7.255649) (xy 186.424074 7.182743) (xy 186.462296 7.105983)
			(xy 186.493272 7.026024) (xy 186.516739 6.943548) (xy 186.532495 6.859258) (xy 186.540407 6.773875)
			(xy 186.540902 6.731) (xy 186.540407 6.688125) (xy 246.260353 6.688125) (xy 246.260353 6.773875)
			(xy 246.268265 6.859258) (xy 246.284021 6.943548) (xy 246.307488 7.026024) (xy 246.338464 7.105983)
			(xy 246.376686 7.182743) (xy 246.421827 7.255649) (xy 246.473503 7.324078) (xy 246.531272 7.387448)
			(xy 246.594642 7.445217) (xy 246.663071 7.496893) (xy 246.735977 7.542034) (xy 246.812737 7.580256)
			(xy 246.892696 7.611232) (xy 246.975172 7.634699) (xy 247.059462 7.650455) (xy 247.144845 7.658367)
			(xy 247.230595 7.658367) (xy 247.315978 7.650455) (xy 247.400268 7.634699) (xy 247.482744 7.611232)
			(xy 247.562703 7.580256) (xy 247.639463 7.542034) (xy 247.712369 7.496893) (xy 247.780798 7.445217)
			(xy 247.844168 7.387448) (xy 247.901937 7.324078) (xy 247.953613 7.255649) (xy 247.998754 7.182743)
			(xy 248.036976 7.105983) (xy 248.067952 7.026024) (xy 248.091419 6.943548) (xy 248.107175 6.859258)
			(xy 248.115087 6.773875) (xy 248.115582 6.731) (xy 248.115087 6.688125) (xy 252.610353 6.688125)
			(xy 252.610353 6.773875) (xy 252.618265 6.859258) (xy 252.634021 6.943548) (xy 252.657488 7.026024)
			(xy 252.688464 7.105983) (xy 252.726686 7.182743) (xy 252.771827 7.255649) (xy 252.823503 7.324078)
			(xy 252.881272 7.387448) (xy 252.944642 7.445217) (xy 253.013071 7.496893) (xy 253.085977 7.542034)
			(xy 253.162737 7.580256) (xy 253.242696 7.611232) (xy 253.325172 7.634699) (xy 253.409462 7.650455)
			(xy 253.494845 7.658367) (xy 253.580595 7.658367) (xy 253.665978 7.650455) (xy 253.750268 7.634699)
			(xy 253.832744 7.611232) (xy 253.912703 7.580256) (xy 253.989463 7.542034) (xy 254.062369 7.496893)
			(xy 254.130798 7.445217) (xy 254.194168 7.387448) (xy 254.251937 7.324078) (xy 254.303613 7.255649)
			(xy 254.348754 7.182743) (xy 254.386976 7.105983) (xy 254.417952 7.026024) (xy 254.441419 6.943548)
			(xy 254.457175 6.859258) (xy 254.465087 6.773875) (xy 254.465582 6.731) (xy 254.465119 6.690919)
			(xy 256.921241 6.690919) (xy 256.921241 6.776669) (xy 256.929153 6.862052) (xy 256.944909 6.946342)
			(xy 256.968376 7.028818) (xy 256.999352 7.108777) (xy 257.037574 7.185537) (xy 257.082715 7.258443)
			(xy 257.134391 7.326872) (xy 257.19216 7.390242) (xy 257.25553 7.448011) (xy 257.323959 7.499687)
			(xy 257.396865 7.544828) (xy 257.473625 7.58305) (xy 257.553584 7.614026) (xy 257.63606 7.637493)
			(xy 257.72035 7.653249) (xy 257.805733 7.661161) (xy 257.891483 7.661161) (xy 257.976866 7.653249)
			(xy 258.061156 7.637493) (xy 258.143632 7.614026) (xy 258.223591 7.58305) (xy 258.245794 7.571994)
			(xy 261.85622 7.571994) (xy 261.85622 8.435594) (xy 261.856706 8.462863) (xy 261.864468 8.516847)
			(xy 261.879833 8.569177) (xy 261.90249 8.618787) (xy 261.931976 8.664668) (xy 261.967691 8.705885)
			(xy 262.008908 8.7416) (xy 262.054789 8.771086) (xy 262.104399 8.793743) (xy 262.156729 8.809108)
			(xy 262.210713 8.81687) (xy 262.265251 8.81687) (xy 262.319235 8.809108) (xy 262.371565 8.793743)
			(xy 262.421175 8.771086) (xy 262.467056 8.7416) (xy 262.508273 8.705885) (xy 262.543988 8.664668)
			(xy 262.573474 8.618787) (xy 262.596131 8.569177) (xy 262.611496 8.516847) (xy 262.619258 8.462863)
			(xy 262.619744 8.435594) (xy 262.619744 7.571994) (xy 262.619258 7.544725) (xy 262.611496 7.490741)
			(xy 262.596131 7.438411) (xy 262.573474 7.388801) (xy 262.543988 7.34292) (xy 262.508273 7.301703)
			(xy 262.467056 7.265988) (xy 262.421175 7.236502) (xy 262.371565 7.213845) (xy 262.319235 7.19848)
			(xy 262.265251 7.190718) (xy 262.210713 7.190718) (xy 262.156729 7.19848) (xy 262.104399 7.213845)
			(xy 262.054789 7.236502) (xy 262.008908 7.265988) (xy 261.967691 7.301703) (xy 261.931976 7.34292)
			(xy 261.90249 7.388801) (xy 261.879833 7.438411) (xy 261.864468 7.490741) (xy 261.856706 7.544725)
			(xy 261.85622 7.571994) (xy 258.245794 7.571994) (xy 258.300351 7.544828) (xy 258.373257 7.499687)
			(xy 258.441686 7.448011) (xy 258.505056 7.390242) (xy 258.562825 7.326872) (xy 258.614501 7.258443)
			(xy 258.659642 7.185537) (xy 258.697864 7.108777) (xy 258.72884 7.028818) (xy 258.752307 6.946342)
			(xy 258.768063 6.862052) (xy 258.775975 6.776669) (xy 258.77647 6.733794) (xy 258.775975 6.690919)
			(xy 263.271241 6.690919) (xy 263.271241 6.776669) (xy 263.279153 6.862052) (xy 263.294909 6.946342)
			(xy 263.318376 7.028818) (xy 263.349352 7.108777) (xy 263.387574 7.185537) (xy 263.432715 7.258443)
			(xy 263.484391 7.326872) (xy 263.54216 7.390242) (xy 263.60553 7.448011) (xy 263.673959 7.499687)
			(xy 263.746865 7.544828) (xy 263.823625 7.58305) (xy 263.903584 7.614026) (xy 263.98606 7.637493)
			(xy 264.07035 7.653249) (xy 264.155733 7.661161) (xy 264.241483 7.661161) (xy 264.326866 7.653249)
			(xy 264.411156 7.637493) (xy 264.493632 7.614026) (xy 264.573591 7.58305) (xy 264.650351 7.544828)
			(xy 264.723257 7.499687) (xy 264.791686 7.448011) (xy 264.855056 7.390242) (xy 264.912825 7.326872)
			(xy 264.964501 7.258443) (xy 265.009642 7.185537) (xy 265.047864 7.108777) (xy 265.07884 7.028818)
			(xy 265.102307 6.946342) (xy 265.118063 6.862052) (xy 265.125975 6.776669) (xy 265.12647 6.733794)
			(xy 265.125975 6.690919) (xy 324.845921 6.690919) (xy 324.845921 6.776669) (xy 324.853833 6.862052)
			(xy 324.869589 6.946342) (xy 324.893056 7.028818) (xy 324.924032 7.108777) (xy 324.962254 7.185537)
			(xy 325.007395 7.258443) (xy 325.059071 7.326872) (xy 325.11684 7.390242) (xy 325.18021 7.448011)
			(xy 325.248639 7.499687) (xy 325.321545 7.544828) (xy 325.398305 7.58305) (xy 325.478264 7.614026)
			(xy 325.56074 7.637493) (xy 325.64503 7.653249) (xy 325.730413 7.661161) (xy 325.816163 7.661161)
			(xy 325.901546 7.653249) (xy 325.985836 7.637493) (xy 326.068312 7.614026) (xy 326.148271 7.58305)
			(xy 326.170474 7.571994) (xy 327.352152 7.571994) (xy 327.352152 8.435594) (xy 327.352638 8.462863)
			(xy 327.3604 8.516847) (xy 327.375765 8.569177) (xy 327.398422 8.618787) (xy 327.427908 8.664668)
			(xy 327.463623 8.705885) (xy 327.50484 8.7416) (xy 327.550721 8.771086) (xy 327.600331 8.793743)
			(xy 327.652661 8.809108) (xy 327.706645 8.81687) (xy 327.761183 8.81687) (xy 327.815167 8.809108)
			(xy 327.867497 8.793743) (xy 327.917107 8.771086) (xy 327.962988 8.7416) (xy 328.004205 8.705885)
			(xy 328.03992 8.664668) (xy 328.069406 8.618787) (xy 328.092063 8.569177) (xy 328.107428 8.516847)
			(xy 328.11519 8.462863) (xy 328.115676 8.435594) (xy 328.115676 7.571994) (xy 328.11519 7.544725)
			(xy 328.107428 7.490741) (xy 328.092063 7.438411) (xy 328.069406 7.388801) (xy 328.03992 7.34292)
			(xy 328.004205 7.301703) (xy 327.962988 7.265988) (xy 327.917107 7.236502) (xy 327.867497 7.213845)
			(xy 327.815167 7.19848) (xy 327.761183 7.190718) (xy 327.706645 7.190718) (xy 327.652661 7.19848)
			(xy 327.600331 7.213845) (xy 327.550721 7.236502) (xy 327.50484 7.265988) (xy 327.463623 7.301703)
			(xy 327.427908 7.34292) (xy 327.398422 7.388801) (xy 327.375765 7.438411) (xy 327.3604 7.490741)
			(xy 327.352638 7.544725) (xy 327.352152 7.571994) (xy 326.170474 7.571994) (xy 326.225031 7.544828)
			(xy 326.297937 7.499687) (xy 326.366366 7.448011) (xy 326.429736 7.390242) (xy 326.487505 7.326872)
			(xy 326.539181 7.258443) (xy 326.584322 7.185537) (xy 326.622544 7.108777) (xy 326.65352 7.028818)
			(xy 326.676987 6.946342) (xy 326.692743 6.862052) (xy 326.700655 6.776669) (xy 326.70115 6.733794)
			(xy 326.700655 6.690919) (xy 331.195921 6.690919) (xy 331.195921 6.776669) (xy 331.203833 6.862052)
			(xy 331.219589 6.946342) (xy 331.243056 7.028818) (xy 331.274032 7.108777) (xy 331.312254 7.185537)
			(xy 331.357395 7.258443) (xy 331.409071 7.326872) (xy 331.46684 7.390242) (xy 331.53021 7.448011)
			(xy 331.598639 7.499687) (xy 331.671545 7.544828) (xy 331.748305 7.58305) (xy 331.828264 7.614026)
			(xy 331.91074 7.637493) (xy 331.99503 7.653249) (xy 332.080413 7.661161) (xy 332.166163 7.661161)
			(xy 332.251546 7.653249) (xy 332.335836 7.637493) (xy 332.418312 7.614026) (xy 332.498271 7.58305)
			(xy 332.575031 7.544828) (xy 332.647937 7.499687) (xy 332.716366 7.448011) (xy 332.779736 7.390242)
			(xy 332.837505 7.326872) (xy 332.889181 7.258443) (xy 332.934322 7.185537) (xy 332.972544 7.108777)
			(xy 333.00352 7.028818) (xy 333.026987 6.946342) (xy 333.042743 6.862052) (xy 333.050655 6.776669)
			(xy 333.05115 6.733794) (xy 333.050655 6.690919) (xy 335.488267 6.690919) (xy 335.488267 6.776669)
			(xy 335.496179 6.862052) (xy 335.511935 6.946342) (xy 335.535402 7.028818) (xy 335.566378 7.108777)
			(xy 335.6046 7.185537) (xy 335.649741 7.258443) (xy 335.701417 7.326872) (xy 335.759186 7.390242)
			(xy 335.822556 7.448011) (xy 335.890985 7.499687) (xy 335.963891 7.544828) (xy 336.040651 7.58305)
			(xy 336.12061 7.614026) (xy 336.203086 7.637493) (xy 336.287376 7.653249) (xy 336.372759 7.661161)
			(xy 336.458509 7.661161) (xy 336.543892 7.653249) (xy 336.628182 7.637493) (xy 336.710658 7.614026)
			(xy 336.790617 7.58305) (xy 336.81282 7.571994) (xy 340.4235 7.571994) (xy 340.4235 8.435594) (xy 340.423986 8.462845)
			(xy 340.431742 8.516793) (xy 340.447097 8.569088) (xy 340.469739 8.618665) (xy 340.499205 8.664515)
			(xy 340.534896 8.705706) (xy 340.576087 8.741397) (xy 340.621937 8.770863) (xy 340.671514 8.793505)
			(xy 340.723809 8.80886) (xy 340.777757 8.816616) (xy 340.832259 8.816616) (xy 340.886207 8.80886)
			(xy 340.938502 8.793505) (xy 340.988079 8.770863) (xy 341.033929 8.741397) (xy 341.07512 8.705706)
			(xy 341.110811 8.664515) (xy 341.140277 8.618665) (xy 341.162919 8.569088) (xy 341.178274 8.516793)
			(xy 341.18603 8.462845) (xy 341.186516 8.435594) (xy 341.186516 7.571994) (xy 341.18603 7.544743)
			(xy 341.178274 7.490795) (xy 341.162919 7.4385) (xy 341.140277 7.388923) (xy 341.110811 7.343073)
			(xy 341.07512 7.301882) (xy 341.033929 7.266191) (xy 340.988079 7.236725) (xy 340.938502 7.214083)
			(xy 340.886207 7.198728) (xy 340.832259 7.190972) (xy 340.777757 7.190972) (xy 340.723809 7.198728)
			(xy 340.671514 7.214083) (xy 340.621937 7.236725) (xy 340.576087 7.266191) (xy 340.534896 7.301882)
			(xy 340.499205 7.343073) (xy 340.469739 7.388923) (xy 340.447097 7.4385) (xy 340.431742 7.490795)
			(xy 340.423986 7.544743) (xy 340.4235 7.571994) (xy 336.81282 7.571994) (xy 336.867377 7.544828)
			(xy 336.940283 7.499687) (xy 337.008712 7.448011) (xy 337.072082 7.390242) (xy 337.129851 7.326872)
			(xy 337.181527 7.258443) (xy 337.226668 7.185537) (xy 337.26489 7.108777) (xy 337.295866 7.028818)
			(xy 337.319333 6.946342) (xy 337.335089 6.862052) (xy 337.343001 6.776669) (xy 337.343496 6.733794)
			(xy 337.343001 6.690919) (xy 341.838267 6.690919) (xy 341.838267 6.776669) (xy 341.846179 6.862052)
			(xy 341.861935 6.946342) (xy 341.885402 7.028818) (xy 341.916378 7.108777) (xy 341.9546 7.185537)
			(xy 341.999741 7.258443) (xy 342.051417 7.326872) (xy 342.109186 7.390242) (xy 342.172556 7.448011)
			(xy 342.240985 7.499687) (xy 342.313891 7.544828) (xy 342.390651 7.58305) (xy 342.47061 7.614026)
			(xy 342.553086 7.637493) (xy 342.637376 7.653249) (xy 342.722759 7.661161) (xy 342.808509 7.661161)
			(xy 342.893892 7.653249) (xy 342.978182 7.637493) (xy 343.060658 7.614026) (xy 343.140617 7.58305)
			(xy 343.217377 7.544828) (xy 343.290283 7.499687) (xy 343.358712 7.448011) (xy 343.422082 7.390242)
			(xy 343.479851 7.326872) (xy 343.531527 7.258443) (xy 343.576668 7.185537) (xy 343.61489 7.108777)
			(xy 343.645866 7.028818) (xy 343.669333 6.946342) (xy 343.685089 6.862052) (xy 343.693001 6.776669)
			(xy 343.693496 6.733794) (xy 343.693001 6.690919) (xy 373.705107 6.690919) (xy 373.705107 6.776669)
			(xy 373.713019 6.862052) (xy 373.728775 6.946342) (xy 373.752242 7.028818) (xy 373.783218 7.108777)
			(xy 373.82144 7.185537) (xy 373.866581 7.258443) (xy 373.918257 7.326872) (xy 373.976026 7.390242)
			(xy 374.039396 7.448011) (xy 374.107825 7.499687) (xy 374.180731 7.544828) (xy 374.257491 7.58305)
			(xy 374.33745 7.614026) (xy 374.419926 7.637493) (xy 374.504216 7.653249) (xy 374.589599 7.661161)
			(xy 374.675349 7.661161) (xy 374.760732 7.653249) (xy 374.845022 7.637493) (xy 374.927498 7.614026)
			(xy 375.007457 7.58305) (xy 375.02966 7.571994) (xy 376.211592 7.571994) (xy 376.211592 8.435594)
			(xy 376.212078 8.462845) (xy 376.219834 8.516793) (xy 376.235189 8.569088) (xy 376.257831 8.618665)
			(xy 376.287297 8.664515) (xy 376.322988 8.705706) (xy 376.364179 8.741397) (xy 376.410029 8.770863)
			(xy 376.459606 8.793505) (xy 376.511901 8.80886) (xy 376.565849 8.816616) (xy 376.620351 8.816616)
			(xy 376.674299 8.80886) (xy 376.726594 8.793505) (xy 376.776171 8.770863) (xy 376.822021 8.741397)
			(xy 376.863212 8.705706) (xy 376.898903 8.664515) (xy 376.928369 8.618665) (xy 376.951011 8.569088)
			(xy 376.966366 8.516793) (xy 376.974122 8.462845) (xy 376.974608 8.435594) (xy 376.974608 7.571994)
			(xy 376.974122 7.544743) (xy 376.966366 7.490795) (xy 376.951011 7.4385) (xy 376.928369 7.388923)
			(xy 376.898903 7.343073) (xy 376.863212 7.301882) (xy 376.822021 7.266191) (xy 376.776171 7.236725)
			(xy 376.726594 7.214083) (xy 376.674299 7.198728) (xy 376.620351 7.190972) (xy 376.565849 7.190972)
			(xy 376.511901 7.198728) (xy 376.459606 7.214083) (xy 376.410029 7.236725) (xy 376.364179 7.266191)
			(xy 376.322988 7.301882) (xy 376.287297 7.343073) (xy 376.257831 7.388923) (xy 376.235189 7.4385)
			(xy 376.219834 7.490795) (xy 376.212078 7.544743) (xy 376.211592 7.571994) (xy 375.02966 7.571994)
			(xy 375.084217 7.544828) (xy 375.157123 7.499687) (xy 375.225552 7.448011) (xy 375.288922 7.390242)
			(xy 375.346691 7.326872) (xy 375.398367 7.258443) (xy 375.443508 7.185537) (xy 375.48173 7.108777)
			(xy 375.512706 7.028818) (xy 375.536173 6.946342) (xy 375.551929 6.862052) (xy 375.559841 6.776669)
			(xy 375.560336 6.733794) (xy 375.559841 6.690919) (xy 380.055107 6.690919) (xy 380.055107 6.776669)
			(xy 380.063019 6.862052) (xy 380.078775 6.946342) (xy 380.102242 7.028818) (xy 380.133218 7.108777)
			(xy 380.17144 7.185537) (xy 380.216581 7.258443) (xy 380.268257 7.326872) (xy 380.326026 7.390242)
			(xy 380.389396 7.448011) (xy 380.457825 7.499687) (xy 380.530731 7.544828) (xy 380.607491 7.58305)
			(xy 380.68745 7.614026) (xy 380.769926 7.637493) (xy 380.854216 7.653249) (xy 380.939599 7.661161)
			(xy 381.025349 7.661161) (xy 381.110732 7.653249) (xy 381.195022 7.637493) (xy 381.277498 7.614026)
			(xy 381.357457 7.58305) (xy 381.434217 7.544828) (xy 381.507123 7.499687) (xy 381.575552 7.448011)
			(xy 381.638922 7.390242) (xy 381.688857 7.335466) (xy 464.704165 7.335466) (xy 464.704165 7.464606)
			(xy 464.712115 7.593501) (xy 464.727985 7.721661) (xy 464.751714 7.848602) (xy 464.783213 7.973841)
			(xy 464.822362 8.096904) (xy 464.869013 8.217323) (xy 464.922988 8.334642) (xy 464.984083 8.448416)
			(xy 465.052066 8.558213) (xy 465.12668 8.663616) (xy 465.207641 8.764226) (xy 465.294641 8.859661)
			(xy 465.387352 8.94956) (xy 465.485422 9.033581) (xy 465.588477 9.111405) (xy 465.696128 9.182737)
			(xy 465.807967 9.247307) (xy 465.923568 9.304869) (xy 466.042493 9.355206) (xy 466.164292 9.398126)
			(xy 466.288502 9.433467) (xy 466.414651 9.461094) (xy 466.542263 9.480903) (xy 466.670852 9.492819)
			(xy 466.79993 9.496796) (xy 466.929008 9.492819) (xy 467.057597 9.480903) (xy 467.185209 9.461094)
			(xy 467.311358 9.433467) (xy 467.435568 9.398126) (xy 467.557367 9.355206) (xy 467.676292 9.304869)
			(xy 467.791893 9.247307) (xy 467.903732 9.182737) (xy 468.011383 9.111405) (xy 468.114438 9.033581)
			(xy 468.212508 8.94956) (xy 468.305219 8.859661) (xy 468.392219 8.764226) (xy 468.47318 8.663616)
			(xy 468.547794 8.558213) (xy 468.615777 8.448416) (xy 468.676872 8.334642) (xy 468.730847 8.217323)
			(xy 468.777498 8.096904) (xy 468.816647 7.973841) (xy 468.848146 7.848602) (xy 468.871875 7.721661)
			(xy 468.887745 7.593501) (xy 468.895695 7.464606) (xy 468.896192 7.400036) (xy 468.895695 7.335466)
			(xy 468.887745 7.206571) (xy 468.871875 7.078411) (xy 468.848146 6.95147) (xy 468.816647 6.826231)
			(xy 468.777498 6.703168) (xy 468.730847 6.582749) (xy 468.676872 6.46543) (xy 468.615777 6.351656)
			(xy 468.547794 6.241859) (xy 468.47318 6.136456) (xy 468.392219 6.035846) (xy 468.305219 5.940411)
			(xy 468.212508 5.850512) (xy 468.114438 5.766491) (xy 468.011383 5.688667) (xy 467.903732 5.617335)
			(xy 467.791893 5.552765) (xy 467.676292 5.495203) (xy 467.557367 5.444866) (xy 467.435568 5.401946)
			(xy 467.311358 5.366605) (xy 467.185209 5.338978) (xy 467.057597 5.319169) (xy 466.929008 5.307253)
			(xy 466.79993 5.303277) (xy 466.670852 5.307253) (xy 466.542263 5.319169) (xy 466.414651 5.338978)
			(xy 466.288502 5.366605) (xy 466.164292 5.401946) (xy 466.042493 5.444866) (xy 465.923568 5.495203)
			(xy 465.807967 5.552765) (xy 465.696128 5.617335) (xy 465.588477 5.688667) (xy 465.485422 5.766491)
			(xy 465.387352 5.850512) (xy 465.294641 5.940411) (xy 465.207641 6.035846) (xy 465.12668 6.136456)
			(xy 465.052066 6.241859) (xy 464.984083 6.351656) (xy 464.922988 6.46543) (xy 464.869013 6.582749)
			(xy 464.822362 6.703168) (xy 464.783213 6.826231) (xy 464.751714 6.95147) (xy 464.727985 7.078411)
			(xy 464.712115 7.206571) (xy 464.704165 7.335466) (xy 381.688857 7.335466) (xy 381.696691 7.326872)
			(xy 381.748367 7.258443) (xy 381.793508 7.185537) (xy 381.83173 7.108777) (xy 381.862706 7.028818)
			(xy 381.886173 6.946342) (xy 381.901929 6.862052) (xy 381.909841 6.776669) (xy 381.910336 6.733794)
			(xy 381.909841 6.690919) (xy 381.901929 6.605536) (xy 381.886173 6.521246) (xy 381.862706 6.43877)
			(xy 381.83173 6.358811) (xy 381.793508 6.282051) (xy 381.748367 6.209145) (xy 381.696691 6.140716)
			(xy 381.638922 6.077346) (xy 381.575552 6.019577) (xy 381.507123 5.967901) (xy 381.434217 5.92276)
			(xy 381.357457 5.884538) (xy 381.277498 5.853562) (xy 381.195022 5.830095) (xy 381.110732 5.814339)
			(xy 381.025349 5.806427) (xy 380.939599 5.806427) (xy 380.854216 5.814339) (xy 380.769926 5.830095)
			(xy 380.68745 5.853562) (xy 380.607491 5.884538) (xy 380.530731 5.92276) (xy 380.457825 5.967901)
			(xy 380.389396 6.019577) (xy 380.326026 6.077346) (xy 380.268257 6.140716) (xy 380.216581 6.209145)
			(xy 380.17144 6.282051) (xy 380.133218 6.358811) (xy 380.102242 6.43877) (xy 380.078775 6.521246)
			(xy 380.063019 6.605536) (xy 380.055107 6.690919) (xy 375.559841 6.690919) (xy 375.551929 6.605536)
			(xy 375.536173 6.521246) (xy 375.512706 6.43877) (xy 375.48173 6.358811) (xy 375.443508 6.282051)
			(xy 375.398367 6.209145) (xy 375.346691 6.140716) (xy 375.288922 6.077346) (xy 375.225552 6.019577)
			(xy 375.157123 5.967901) (xy 375.084217 5.92276) (xy 375.007457 5.884538) (xy 374.927498 5.853562)
			(xy 374.845022 5.830095) (xy 374.760732 5.814339) (xy 374.675349 5.806427) (xy 374.589599 5.806427)
			(xy 374.504216 5.814339) (xy 374.419926 5.830095) (xy 374.33745 5.853562) (xy 374.257491 5.884538)
			(xy 374.180731 5.92276) (xy 374.107825 5.967901) (xy 374.039396 6.019577) (xy 373.976026 6.077346)
			(xy 373.918257 6.140716) (xy 373.866581 6.209145) (xy 373.82144 6.282051) (xy 373.783218 6.358811)
			(xy 373.752242 6.43877) (xy 373.728775 6.521246) (xy 373.713019 6.605536) (xy 373.705107 6.690919)
			(xy 343.693001 6.690919) (xy 343.685089 6.605536) (xy 343.669333 6.521246) (xy 343.645866 6.43877)
			(xy 343.61489 6.358811) (xy 343.576668 6.282051) (xy 343.531527 6.209145) (xy 343.479851 6.140716)
			(xy 343.422082 6.077346) (xy 343.358712 6.019577) (xy 343.290283 5.967901) (xy 343.217377 5.92276)
			(xy 343.140617 5.884538) (xy 343.060658 5.853562) (xy 342.978182 5.830095) (xy 342.893892 5.814339)
			(xy 342.808509 5.806427) (xy 342.722759 5.806427) (xy 342.637376 5.814339) (xy 342.553086 5.830095)
			(xy 342.47061 5.853562) (xy 342.390651 5.884538) (xy 342.313891 5.92276) (xy 342.240985 5.967901)
			(xy 342.172556 6.019577) (xy 342.109186 6.077346) (xy 342.051417 6.140716) (xy 341.999741 6.209145)
			(xy 341.9546 6.282051) (xy 341.916378 6.358811) (xy 341.885402 6.43877) (xy 341.861935 6.521246)
			(xy 341.846179 6.605536) (xy 341.838267 6.690919) (xy 337.343001 6.690919) (xy 337.335089 6.605536)
			(xy 337.319333 6.521246) (xy 337.295866 6.43877) (xy 337.26489 6.358811) (xy 337.226668 6.282051)
			(xy 337.181527 6.209145) (xy 337.129851 6.140716) (xy 337.072082 6.077346) (xy 337.008712 6.019577)
			(xy 336.940283 5.967901) (xy 336.867377 5.92276) (xy 336.790617 5.884538) (xy 336.710658 5.853562)
			(xy 336.628182 5.830095) (xy 336.543892 5.814339) (xy 336.458509 5.806427) (xy 336.372759 5.806427)
			(xy 336.287376 5.814339) (xy 336.203086 5.830095) (xy 336.12061 5.853562) (xy 336.040651 5.884538)
			(xy 335.963891 5.92276) (xy 335.890985 5.967901) (xy 335.822556 6.019577) (xy 335.759186 6.077346)
			(xy 335.701417 6.140716) (xy 335.649741 6.209145) (xy 335.6046 6.282051) (xy 335.566378 6.358811)
			(xy 335.535402 6.43877) (xy 335.511935 6.521246) (xy 335.496179 6.605536) (xy 335.488267 6.690919)
			(xy 333.050655 6.690919) (xy 333.042743 6.605536) (xy 333.026987 6.521246) (xy 333.00352 6.43877)
			(xy 332.972544 6.358811) (xy 332.934322 6.282051) (xy 332.889181 6.209145) (xy 332.837505 6.140716)
			(xy 332.779736 6.077346) (xy 332.716366 6.019577) (xy 332.647937 5.967901) (xy 332.575031 5.92276)
			(xy 332.498271 5.884538) (xy 332.418312 5.853562) (xy 332.335836 5.830095) (xy 332.251546 5.814339)
			(xy 332.166163 5.806427) (xy 332.080413 5.806427) (xy 331.99503 5.814339) (xy 331.91074 5.830095)
			(xy 331.828264 5.853562) (xy 331.748305 5.884538) (xy 331.671545 5.92276) (xy 331.598639 5.967901)
			(xy 331.53021 6.019577) (xy 331.46684 6.077346) (xy 331.409071 6.140716) (xy 331.357395 6.209145)
			(xy 331.312254 6.282051) (xy 331.274032 6.358811) (xy 331.243056 6.43877) (xy 331.219589 6.521246)
			(xy 331.203833 6.605536) (xy 331.195921 6.690919) (xy 326.700655 6.690919) (xy 326.692743 6.605536)
			(xy 326.676987 6.521246) (xy 326.65352 6.43877) (xy 326.622544 6.358811) (xy 326.584322 6.282051)
			(xy 326.539181 6.209145) (xy 326.487505 6.140716) (xy 326.429736 6.077346) (xy 326.366366 6.019577)
			(xy 326.297937 5.967901) (xy 326.225031 5.92276) (xy 326.148271 5.884538) (xy 326.068312 5.853562)
			(xy 325.985836 5.830095) (xy 325.901546 5.814339) (xy 325.816163 5.806427) (xy 325.730413 5.806427)
			(xy 325.64503 5.814339) (xy 325.56074 5.830095) (xy 325.478264 5.853562) (xy 325.398305 5.884538)
			(xy 325.321545 5.92276) (xy 325.248639 5.967901) (xy 325.18021 6.019577) (xy 325.11684 6.077346)
			(xy 325.059071 6.140716) (xy 325.007395 6.209145) (xy 324.962254 6.282051) (xy 324.924032 6.358811)
			(xy 324.893056 6.43877) (xy 324.869589 6.521246) (xy 324.853833 6.605536) (xy 324.845921 6.690919)
			(xy 265.125975 6.690919) (xy 265.118063 6.605536) (xy 265.102307 6.521246) (xy 265.07884 6.43877)
			(xy 265.047864 6.358811) (xy 265.009642 6.282051) (xy 264.964501 6.209145) (xy 264.912825 6.140716)
			(xy 264.855056 6.077346) (xy 264.791686 6.019577) (xy 264.723257 5.967901) (xy 264.650351 5.92276)
			(xy 264.573591 5.884538) (xy 264.493632 5.853562) (xy 264.411156 5.830095) (xy 264.326866 5.814339)
			(xy 264.241483 5.806427) (xy 264.155733 5.806427) (xy 264.07035 5.814339) (xy 263.98606 5.830095)
			(xy 263.903584 5.853562) (xy 263.823625 5.884538) (xy 263.746865 5.92276) (xy 263.673959 5.967901)
			(xy 263.60553 6.019577) (xy 263.54216 6.077346) (xy 263.484391 6.140716) (xy 263.432715 6.209145)
			(xy 263.387574 6.282051) (xy 263.349352 6.358811) (xy 263.318376 6.43877) (xy 263.294909 6.521246)
			(xy 263.279153 6.605536) (xy 263.271241 6.690919) (xy 258.775975 6.690919) (xy 258.768063 6.605536)
			(xy 258.752307 6.521246) (xy 258.72884 6.43877) (xy 258.697864 6.358811) (xy 258.659642 6.282051)
			(xy 258.614501 6.209145) (xy 258.562825 6.140716) (xy 258.505056 6.077346) (xy 258.441686 6.019577)
			(xy 258.373257 5.967901) (xy 258.300351 5.92276) (xy 258.223591 5.884538) (xy 258.143632 5.853562)
			(xy 258.061156 5.830095) (xy 257.976866 5.814339) (xy 257.891483 5.806427) (xy 257.805733 5.806427)
			(xy 257.72035 5.814339) (xy 257.63606 5.830095) (xy 257.553584 5.853562) (xy 257.473625 5.884538)
			(xy 257.396865 5.92276) (xy 257.323959 5.967901) (xy 257.25553 6.019577) (xy 257.19216 6.077346)
			(xy 257.134391 6.140716) (xy 257.082715 6.209145) (xy 257.037574 6.282051) (xy 256.999352 6.358811)
			(xy 256.968376 6.43877) (xy 256.944909 6.521246) (xy 256.929153 6.605536) (xy 256.921241 6.690919)
			(xy 254.465119 6.690919) (xy 254.465087 6.688125) (xy 254.457175 6.602742) (xy 254.441419 6.518452)
			(xy 254.417952 6.435976) (xy 254.386976 6.356017) (xy 254.348754 6.279257) (xy 254.303613 6.206351)
			(xy 254.251937 6.137922) (xy 254.194168 6.074552) (xy 254.130798 6.016783) (xy 254.062369 5.965107)
			(xy 253.989463 5.919966) (xy 253.912703 5.881744) (xy 253.832744 5.850768) (xy 253.750268 5.827301)
			(xy 253.665978 5.811545) (xy 253.580595 5.803633) (xy 253.494845 5.803633) (xy 253.409462 5.811545)
			(xy 253.325172 5.827301) (xy 253.242696 5.850768) (xy 253.162737 5.881744) (xy 253.085977 5.919966)
			(xy 253.013071 5.965107) (xy 252.944642 6.016783) (xy 252.881272 6.074552) (xy 252.823503 6.137922)
			(xy 252.771827 6.206351) (xy 252.726686 6.279257) (xy 252.688464 6.356017) (xy 252.657488 6.435976)
			(xy 252.634021 6.518452) (xy 252.618265 6.602742) (xy 252.610353 6.688125) (xy 248.115087 6.688125)
			(xy 248.107175 6.602742) (xy 248.091419 6.518452) (xy 248.067952 6.435976) (xy 248.036976 6.356017)
			(xy 247.998754 6.279257) (xy 247.953613 6.206351) (xy 247.901937 6.137922) (xy 247.844168 6.074552)
			(xy 247.780798 6.016783) (xy 247.712369 5.965107) (xy 247.639463 5.919966) (xy 247.562703 5.881744)
			(xy 247.482744 5.850768) (xy 247.400268 5.827301) (xy 247.315978 5.811545) (xy 247.230595 5.803633)
			(xy 247.144845 5.803633) (xy 247.059462 5.811545) (xy 246.975172 5.827301) (xy 246.892696 5.850768)
			(xy 246.812737 5.881744) (xy 246.735977 5.919966) (xy 246.663071 5.965107) (xy 246.594642 6.016783)
			(xy 246.531272 6.074552) (xy 246.473503 6.137922) (xy 246.421827 6.206351) (xy 246.376686 6.279257)
			(xy 246.338464 6.356017) (xy 246.307488 6.435976) (xy 246.284021 6.518452) (xy 246.268265 6.602742)
			(xy 246.260353 6.688125) (xy 186.540407 6.688125) (xy 186.532495 6.602742) (xy 186.516739 6.518452)
			(xy 186.493272 6.435976) (xy 186.462296 6.356017) (xy 186.424074 6.279257) (xy 186.378933 6.206351)
			(xy 186.327257 6.137922) (xy 186.269488 6.074552) (xy 186.206118 6.016783) (xy 186.137689 5.965107)
			(xy 186.064783 5.919966) (xy 185.988023 5.881744) (xy 185.908064 5.850768) (xy 185.825588 5.827301)
			(xy 185.741298 5.811545) (xy 185.655915 5.803633) (xy 185.570165 5.803633) (xy 185.484782 5.811545)
			(xy 185.400492 5.827301) (xy 185.318016 5.850768) (xy 185.238057 5.881744) (xy 185.161297 5.919966)
			(xy 185.088391 5.965107) (xy 185.019962 6.016783) (xy 184.956592 6.074552) (xy 184.898823 6.137922)
			(xy 184.847147 6.206351) (xy 184.802006 6.279257) (xy 184.763784 6.356017) (xy 184.732808 6.435976)
			(xy 184.709341 6.518452) (xy 184.693585 6.602742) (xy 184.685673 6.688125) (xy 180.190407 6.688125)
			(xy 180.182495 6.602742) (xy 180.166739 6.518452) (xy 180.143272 6.435976) (xy 180.112296 6.356017)
			(xy 180.074074 6.279257) (xy 180.028933 6.206351) (xy 179.977257 6.137922) (xy 179.919488 6.074552)
			(xy 179.856118 6.016783) (xy 179.787689 5.965107) (xy 179.714783 5.919966) (xy 179.638023 5.881744)
			(xy 179.558064 5.850768) (xy 179.475588 5.827301) (xy 179.391298 5.811545) (xy 179.305915 5.803633)
			(xy 179.220165 5.803633) (xy 179.134782 5.811545) (xy 179.050492 5.827301) (xy 178.968016 5.850768)
			(xy 178.888057 5.881744) (xy 178.811297 5.919966) (xy 178.738391 5.965107) (xy 178.669962 6.016783)
			(xy 178.606592 6.074552) (xy 178.548823 6.137922) (xy 178.497147 6.206351) (xy 178.452006 6.279257)
			(xy 178.413784 6.356017) (xy 178.382808 6.435976) (xy 178.359341 6.518452) (xy 178.343585 6.602742)
			(xy 178.335673 6.688125) (xy 6.97173 6.688125) (xy 6.930907 6.582749) (xy 6.876932 6.46543) (xy 6.815837 6.351656)
			(xy 6.747854 6.241859) (xy 6.67324 6.136456) (xy 6.592279 6.035846) (xy 6.505279 5.940411) (xy 6.412568 5.850512)
			(xy 6.314498 5.766491) (xy 6.211443 5.688667) (xy 6.103792 5.617335) (xy 5.991953 5.552765) (xy 5.876352 5.495203)
			(xy 5.757427 5.444866) (xy 5.635628 5.401946) (xy 5.511418 5.366605) (xy 5.385269 5.338978) (xy 5.257657 5.319169)
			(xy 5.129068 5.307253) (xy 4.99999 5.303277) (xy 4.870912 5.307253) (xy 4.742323 5.319169) (xy 4.614711 5.338978)
			(xy 4.488562 5.366605) (xy 4.364352 5.401946) (xy 4.242553 5.444866) (xy 4.123628 5.495203) (xy 4.008027 5.552765)
			(xy 3.896188 5.617335) (xy 3.788537 5.688667) (xy 3.685482 5.766491) (xy 3.587412 5.850512) (xy 3.494701 5.940411)
			(xy 3.407701 6.035846) (xy 3.32674 6.136456) (xy 3.252126 6.241859) (xy 3.184143 6.351656) (xy 3.123048 6.46543)
			(xy 3.069073 6.582749) (xy 3.022422 6.703168) (xy 2.983273 6.826231) (xy 2.951774 6.95147) (xy 2.928045 7.078411)
			(xy 2.912175 7.206571) (xy 2.904225 7.335466) (xy 0.508 7.335466) (xy 0.508 4.148125) (xy 178.335673 4.148125)
			(xy 178.335673 4.233875) (xy 178.343585 4.319258) (xy 178.359341 4.403548) (xy 178.382808 4.486024)
			(xy 178.413784 4.565983) (xy 178.452006 4.642743) (xy 178.497147 4.715649) (xy 178.548823 4.784078)
			(xy 178.606592 4.847448) (xy 178.669962 4.905217) (xy 178.738391 4.956893) (xy 178.811297 5.002034)
			(xy 178.888057 5.040256) (xy 178.968016 5.071232) (xy 179.050492 5.094699) (xy 179.134782 5.110455)
			(xy 179.220165 5.118367) (xy 179.305915 5.118367) (xy 179.391298 5.110455) (xy 179.475588 5.094699)
			(xy 179.558064 5.071232) (xy 179.638023 5.040256) (xy 179.660226 5.0292) (xy 183.270652 5.0292) (xy 183.270652 5.8928)
			(xy 183.271138 5.920069) (xy 183.2789 5.974053) (xy 183.294265 6.026383) (xy 183.316922 6.075993)
			(xy 183.346408 6.121874) (xy 183.382123 6.163091) (xy 183.42334 6.198806) (xy 183.469221 6.228292)
			(xy 183.518831 6.250949) (xy 183.571161 6.266314) (xy 183.625145 6.274076) (xy 183.679683 6.274076)
			(xy 183.733667 6.266314) (xy 183.785997 6.250949) (xy 183.835607 6.228292) (xy 183.881488 6.198806)
			(xy 183.922705 6.163091) (xy 183.95842 6.121874) (xy 183.987906 6.075993) (xy 184.010563 6.026383)
			(xy 184.025928 5.974053) (xy 184.03369 5.920069) (xy 184.034176 5.8928) (xy 184.034176 5.0292) (xy 184.03369 5.001931)
			(xy 184.025928 4.947947) (xy 184.010563 4.895617) (xy 183.987906 4.846007) (xy 183.95842 4.800126)
			(xy 183.922705 4.758909) (xy 183.881488 4.723194) (xy 183.835607 4.693708) (xy 183.785997 4.671051)
			(xy 183.733667 4.655686) (xy 183.679683 4.647924) (xy 183.625145 4.647924) (xy 183.571161 4.655686)
			(xy 183.518831 4.671051) (xy 183.469221 4.693708) (xy 183.42334 4.723194) (xy 183.382123 4.758909)
			(xy 183.346408 4.800126) (xy 183.316922 4.846007) (xy 183.294265 4.895617) (xy 183.2789 4.947947)
			(xy 183.271138 5.001931) (xy 183.270652 5.0292) (xy 179.660226 5.0292) (xy 179.714783 5.002034) (xy 179.787689 4.956893)
			(xy 179.856118 4.905217) (xy 179.919488 4.847448) (xy 179.977257 4.784078) (xy 180.028933 4.715649)
			(xy 180.074074 4.642743) (xy 180.112296 4.565983) (xy 180.143272 4.486024) (xy 180.166739 4.403548)
			(xy 180.182495 4.319258) (xy 180.190407 4.233875) (xy 180.190902 4.191) (xy 180.190407 4.148125)
			(xy 184.685673 4.148125) (xy 184.685673 4.233875) (xy 184.693585 4.319258) (xy 184.709341 4.403548)
			(xy 184.732808 4.486024) (xy 184.763784 4.565983) (xy 184.802006 4.642743) (xy 184.847147 4.715649)
			(xy 184.898823 4.784078) (xy 184.956592 4.847448) (xy 185.019962 4.905217) (xy 185.088391 4.956893)
			(xy 185.161297 5.002034) (xy 185.238057 5.040256) (xy 185.318016 5.071232) (xy 185.400492 5.094699)
			(xy 185.484782 5.110455) (xy 185.570165 5.118367) (xy 185.655915 5.118367) (xy 185.741298 5.110455)
			(xy 185.825588 5.094699) (xy 185.908064 5.071232) (xy 185.988023 5.040256) (xy 186.064783 5.002034)
			(xy 186.137689 4.956893) (xy 186.206118 4.905217) (xy 186.269488 4.847448) (xy 186.327257 4.784078)
			(xy 186.378933 4.715649) (xy 186.424074 4.642743) (xy 186.462296 4.565983) (xy 186.493272 4.486024)
			(xy 186.516739 4.403548) (xy 186.532495 4.319258) (xy 186.540407 4.233875) (xy 186.540902 4.191)
			(xy 186.540407 4.148125) (xy 246.260353 4.148125) (xy 246.260353 4.233875) (xy 246.268265 4.319258)
			(xy 246.284021 4.403548) (xy 246.307488 4.486024) (xy 246.338464 4.565983) (xy 246.376686 4.642743)
			(xy 246.421827 4.715649) (xy 246.473503 4.784078) (xy 246.531272 4.847448) (xy 246.594642 4.905217)
			(xy 246.663071 4.956893) (xy 246.735977 5.002034) (xy 246.812737 5.040256) (xy 246.892696 5.071232)
			(xy 246.975172 5.094699) (xy 247.059462 5.110455) (xy 247.144845 5.118367) (xy 247.230595 5.118367)
			(xy 247.315978 5.110455) (xy 247.400268 5.094699) (xy 247.482744 5.071232) (xy 247.562703 5.040256)
			(xy 247.584906 5.0292) (xy 248.766584 5.0292) (xy 248.766584 5.8928) (xy 248.76707 5.920069) (xy 248.774832 5.974053)
			(xy 248.790197 6.026383) (xy 248.812854 6.075993) (xy 248.84234 6.121874) (xy 248.878055 6.163091)
			(xy 248.919272 6.198806) (xy 248.965153 6.228292) (xy 249.014763 6.250949) (xy 249.067093 6.266314)
			(xy 249.121077 6.274076) (xy 249.175615 6.274076) (xy 249.229599 6.266314) (xy 249.281929 6.250949)
			(xy 249.331539 6.228292) (xy 249.37742 6.198806) (xy 249.418637 6.163091) (xy 249.454352 6.121874)
			(xy 249.483838 6.075993) (xy 249.506495 6.026383) (xy 249.52186 5.974053) (xy 249.529622 5.920069)
			(xy 249.530108 5.8928) (xy 249.530108 5.0292) (xy 249.529622 5.001931) (xy 249.52186 4.947947) (xy 249.506495 4.895617)
			(xy 249.483838 4.846007) (xy 249.454352 4.800126) (xy 249.418637 4.758909) (xy 249.37742 4.723194)
			(xy 249.331539 4.693708) (xy 249.281929 4.671051) (xy 249.229599 4.655686) (xy 249.175615 4.647924)
			(xy 249.121077 4.647924) (xy 249.067093 4.655686) (xy 249.014763 4.671051) (xy 248.965153 4.693708)
			(xy 248.919272 4.723194) (xy 248.878055 4.758909) (xy 248.84234 4.800126) (xy 248.812854 4.846007)
			(xy 248.790197 4.895617) (xy 248.774832 4.947947) (xy 248.76707 5.001931) (xy 248.766584 5.0292)
			(xy 247.584906 5.0292) (xy 247.639463 5.002034) (xy 247.712369 4.956893) (xy 247.780798 4.905217)
			(xy 247.844168 4.847448) (xy 247.901937 4.784078) (xy 247.953613 4.715649) (xy 247.998754 4.642743)
			(xy 248.036976 4.565983) (xy 248.067952 4.486024) (xy 248.091419 4.403548) (xy 248.107175 4.319258)
			(xy 248.115087 4.233875) (xy 248.115582 4.191) (xy 248.115087 4.148125) (xy 252.610353 4.148125)
			(xy 252.610353 4.233875) (xy 252.618265 4.319258) (xy 252.634021 4.403548) (xy 252.657488 4.486024)
			(xy 252.688464 4.565983) (xy 252.726686 4.642743) (xy 252.771827 4.715649) (xy 252.823503 4.784078)
			(xy 252.881272 4.847448) (xy 252.944642 4.905217) (xy 253.013071 4.956893) (xy 253.085977 5.002034)
			(xy 253.162737 5.040256) (xy 253.242696 5.071232) (xy 253.325172 5.094699) (xy 253.409462 5.110455)
			(xy 253.494845 5.118367) (xy 253.580595 5.118367) (xy 253.665978 5.110455) (xy 253.750268 5.094699)
			(xy 253.832744 5.071232) (xy 253.912703 5.040256) (xy 253.989463 5.002034) (xy 254.062369 4.956893)
			(xy 254.130798 4.905217) (xy 254.194168 4.847448) (xy 254.251937 4.784078) (xy 254.303613 4.715649)
			(xy 254.348754 4.642743) (xy 254.386976 4.565983) (xy 254.417952 4.486024) (xy 254.441419 4.403548)
			(xy 254.457175 4.319258) (xy 254.465087 4.233875) (xy 254.465582 4.191) (xy 254.465119 4.150919)
			(xy 256.921241 4.150919) (xy 256.921241 4.236669) (xy 256.929153 4.322052) (xy 256.944909 4.406342)
			(xy 256.968376 4.488818) (xy 256.999352 4.568777) (xy 257.037574 4.645537) (xy 257.082715 4.718443)
			(xy 257.134391 4.786872) (xy 257.19216 4.850242) (xy 257.25553 4.908011) (xy 257.323959 4.959687)
			(xy 257.396865 5.004828) (xy 257.473625 5.04305) (xy 257.553584 5.074026) (xy 257.63606 5.097493)
			(xy 257.72035 5.113249) (xy 257.805733 5.121161) (xy 257.891483 5.121161) (xy 257.976866 5.113249)
			(xy 258.061156 5.097493) (xy 258.143632 5.074026) (xy 258.223591 5.04305) (xy 258.245794 5.031994)
			(xy 261.85622 5.031994) (xy 261.85622 5.895594) (xy 261.856706 5.922863) (xy 261.864468 5.976847)
			(xy 261.879833 6.029177) (xy 261.90249 6.078787) (xy 261.931976 6.124668) (xy 261.967691 6.165885)
			(xy 262.008908 6.2016) (xy 262.054789 6.231086) (xy 262.104399 6.253743) (xy 262.156729 6.269108)
			(xy 262.210713 6.27687) (xy 262.265251 6.27687) (xy 262.319235 6.269108) (xy 262.371565 6.253743)
			(xy 262.421175 6.231086) (xy 262.467056 6.2016) (xy 262.508273 6.165885) (xy 262.543988 6.124668)
			(xy 262.573474 6.078787) (xy 262.596131 6.029177) (xy 262.611496 5.976847) (xy 262.619258 5.922863)
			(xy 262.619744 5.895594) (xy 262.619744 5.031994) (xy 262.619258 5.004725) (xy 262.611496 4.950741)
			(xy 262.596131 4.898411) (xy 262.573474 4.848801) (xy 262.543988 4.80292) (xy 262.508273 4.761703)
			(xy 262.467056 4.725988) (xy 262.421175 4.696502) (xy 262.371565 4.673845) (xy 262.319235 4.65848)
			(xy 262.265251 4.650718) (xy 262.210713 4.650718) (xy 262.156729 4.65848) (xy 262.104399 4.673845)
			(xy 262.054789 4.696502) (xy 262.008908 4.725988) (xy 261.967691 4.761703) (xy 261.931976 4.80292)
			(xy 261.90249 4.848801) (xy 261.879833 4.898411) (xy 261.864468 4.950741) (xy 261.856706 5.004725)
			(xy 261.85622 5.031994) (xy 258.245794 5.031994) (xy 258.300351 5.004828) (xy 258.373257 4.959687)
			(xy 258.441686 4.908011) (xy 258.505056 4.850242) (xy 258.562825 4.786872) (xy 258.614501 4.718443)
			(xy 258.659642 4.645537) (xy 258.697864 4.568777) (xy 258.72884 4.488818) (xy 258.752307 4.406342)
			(xy 258.768063 4.322052) (xy 258.775975 4.236669) (xy 258.77647 4.193794) (xy 258.775975 4.150919)
			(xy 263.271241 4.150919) (xy 263.271241 4.236669) (xy 263.279153 4.322052) (xy 263.294909 4.406342)
			(xy 263.318376 4.488818) (xy 263.349352 4.568777) (xy 263.387574 4.645537) (xy 263.432715 4.718443)
			(xy 263.484391 4.786872) (xy 263.54216 4.850242) (xy 263.60553 4.908011) (xy 263.673959 4.959687)
			(xy 263.746865 5.004828) (xy 263.823625 5.04305) (xy 263.903584 5.074026) (xy 263.98606 5.097493)
			(xy 264.07035 5.113249) (xy 264.155733 5.121161) (xy 264.241483 5.121161) (xy 264.326866 5.113249)
			(xy 264.411156 5.097493) (xy 264.493632 5.074026) (xy 264.573591 5.04305) (xy 264.650351 5.004828)
			(xy 264.723257 4.959687) (xy 264.791686 4.908011) (xy 264.855056 4.850242) (xy 264.912825 4.786872)
			(xy 264.964501 4.718443) (xy 265.009642 4.645537) (xy 265.047864 4.568777) (xy 265.07884 4.488818)
			(xy 265.102307 4.406342) (xy 265.118063 4.322052) (xy 265.125975 4.236669) (xy 265.12647 4.193794)
			(xy 265.125975 4.150919) (xy 324.845921 4.150919) (xy 324.845921 4.236669) (xy 324.853833 4.322052)
			(xy 324.869589 4.406342) (xy 324.893056 4.488818) (xy 324.924032 4.568777) (xy 324.962254 4.645537)
			(xy 325.007395 4.718443) (xy 325.059071 4.786872) (xy 325.11684 4.850242) (xy 325.18021 4.908011)
			(xy 325.248639 4.959687) (xy 325.321545 5.004828) (xy 325.398305 5.04305) (xy 325.478264 5.074026)
			(xy 325.56074 5.097493) (xy 325.64503 5.113249) (xy 325.730413 5.121161) (xy 325.816163 5.121161)
			(xy 325.901546 5.113249) (xy 325.985836 5.097493) (xy 326.068312 5.074026) (xy 326.148271 5.04305)
			(xy 326.170474 5.031994) (xy 327.352152 5.031994) (xy 327.352152 5.895594) (xy 327.352638 5.922863)
			(xy 327.3604 5.976847) (xy 327.375765 6.029177) (xy 327.398422 6.078787) (xy 327.427908 6.124668)
			(xy 327.463623 6.165885) (xy 327.50484 6.2016) (xy 327.550721 6.231086) (xy 327.600331 6.253743)
			(xy 327.652661 6.269108) (xy 327.706645 6.27687) (xy 327.761183 6.27687) (xy 327.815167 6.269108)
			(xy 327.867497 6.253743) (xy 327.917107 6.231086) (xy 327.962988 6.2016) (xy 328.004205 6.165885)
			(xy 328.03992 6.124668) (xy 328.069406 6.078787) (xy 328.092063 6.029177) (xy 328.107428 5.976847)
			(xy 328.11519 5.922863) (xy 328.115676 5.895594) (xy 328.115676 5.031994) (xy 328.11519 5.004725)
			(xy 328.107428 4.950741) (xy 328.092063 4.898411) (xy 328.069406 4.848801) (xy 328.03992 4.80292)
			(xy 328.004205 4.761703) (xy 327.962988 4.725988) (xy 327.917107 4.696502) (xy 327.867497 4.673845)
			(xy 327.815167 4.65848) (xy 327.761183 4.650718) (xy 327.706645 4.650718) (xy 327.652661 4.65848)
			(xy 327.600331 4.673845) (xy 327.550721 4.696502) (xy 327.50484 4.725988) (xy 327.463623 4.761703)
			(xy 327.427908 4.80292) (xy 327.398422 4.848801) (xy 327.375765 4.898411) (xy 327.3604 4.950741)
			(xy 327.352638 5.004725) (xy 327.352152 5.031994) (xy 326.170474 5.031994) (xy 326.225031 5.004828)
			(xy 326.297937 4.959687) (xy 326.366366 4.908011) (xy 326.429736 4.850242) (xy 326.487505 4.786872)
			(xy 326.539181 4.718443) (xy 326.584322 4.645537) (xy 326.622544 4.568777) (xy 326.65352 4.488818)
			(xy 326.676987 4.406342) (xy 326.692743 4.322052) (xy 326.700655 4.236669) (xy 326.70115 4.193794)
			(xy 326.700655 4.150919) (xy 331.195921 4.150919) (xy 331.195921 4.236669) (xy 331.203833 4.322052)
			(xy 331.219589 4.406342) (xy 331.243056 4.488818) (xy 331.274032 4.568777) (xy 331.312254 4.645537)
			(xy 331.357395 4.718443) (xy 331.409071 4.786872) (xy 331.46684 4.850242) (xy 331.53021 4.908011)
			(xy 331.598639 4.959687) (xy 331.671545 5.004828) (xy 331.748305 5.04305) (xy 331.828264 5.074026)
			(xy 331.91074 5.097493) (xy 331.99503 5.113249) (xy 332.080413 5.121161) (xy 332.166163 5.121161)
			(xy 332.251546 5.113249) (xy 332.335836 5.097493) (xy 332.418312 5.074026) (xy 332.498271 5.04305)
			(xy 332.575031 5.004828) (xy 332.647937 4.959687) (xy 332.716366 4.908011) (xy 332.779736 4.850242)
			(xy 332.837505 4.786872) (xy 332.889181 4.718443) (xy 332.934322 4.645537) (xy 332.972544 4.568777)
			(xy 333.00352 4.488818) (xy 333.026987 4.406342) (xy 333.042743 4.322052) (xy 333.050655 4.236669)
			(xy 333.05115 4.193794) (xy 333.050655 4.150919) (xy 335.488267 4.150919) (xy 335.488267 4.236669)
			(xy 335.496179 4.322052) (xy 335.511935 4.406342) (xy 335.535402 4.488818) (xy 335.566378 4.568777)
			(xy 335.6046 4.645537) (xy 335.649741 4.718443) (xy 335.701417 4.786872) (xy 335.759186 4.850242)
			(xy 335.822556 4.908011) (xy 335.890985 4.959687) (xy 335.963891 5.004828) (xy 336.040651 5.04305)
			(xy 336.12061 5.074026) (xy 336.203086 5.097493) (xy 336.287376 5.113249) (xy 336.372759 5.121161)
			(xy 336.458509 5.121161) (xy 336.543892 5.113249) (xy 336.628182 5.097493) (xy 336.710658 5.074026)
			(xy 336.790617 5.04305) (xy 336.81282 5.031994) (xy 340.4235 5.031994) (xy 340.4235 5.895594) (xy 340.423986 5.922845)
			(xy 340.431742 5.976793) (xy 340.447097 6.029088) (xy 340.469739 6.078665) (xy 340.499205 6.124515)
			(xy 340.534896 6.165706) (xy 340.576087 6.201397) (xy 340.621937 6.230863) (xy 340.671514 6.253505)
			(xy 340.723809 6.26886) (xy 340.777757 6.276616) (xy 340.832259 6.276616) (xy 340.886207 6.26886)
			(xy 340.938502 6.253505) (xy 340.988079 6.230863) (xy 341.033929 6.201397) (xy 341.07512 6.165706)
			(xy 341.110811 6.124515) (xy 341.140277 6.078665) (xy 341.162919 6.029088) (xy 341.178274 5.976793)
			(xy 341.18603 5.922845) (xy 341.186516 5.895594) (xy 341.186516 5.031994) (xy 341.18603 5.004743)
			(xy 341.178274 4.950795) (xy 341.162919 4.8985) (xy 341.140277 4.848923) (xy 341.110811 4.803073)
			(xy 341.07512 4.761882) (xy 341.033929 4.726191) (xy 340.988079 4.696725) (xy 340.938502 4.674083)
			(xy 340.886207 4.658728) (xy 340.832259 4.650972) (xy 340.777757 4.650972) (xy 340.723809 4.658728)
			(xy 340.671514 4.674083) (xy 340.621937 4.696725) (xy 340.576087 4.726191) (xy 340.534896 4.761882)
			(xy 340.499205 4.803073) (xy 340.469739 4.848923) (xy 340.447097 4.8985) (xy 340.431742 4.950795)
			(xy 340.423986 5.004743) (xy 340.4235 5.031994) (xy 336.81282 5.031994) (xy 336.867377 5.004828)
			(xy 336.940283 4.959687) (xy 337.008712 4.908011) (xy 337.072082 4.850242) (xy 337.129851 4.786872)
			(xy 337.181527 4.718443) (xy 337.226668 4.645537) (xy 337.26489 4.568777) (xy 337.295866 4.488818)
			(xy 337.319333 4.406342) (xy 337.335089 4.322052) (xy 337.343001 4.236669) (xy 337.343496 4.193794)
			(xy 337.343001 4.150919) (xy 341.838267 4.150919) (xy 341.838267 4.236669) (xy 341.846179 4.322052)
			(xy 341.861935 4.406342) (xy 341.885402 4.488818) (xy 341.916378 4.568777) (xy 341.9546 4.645537)
			(xy 341.999741 4.718443) (xy 342.051417 4.786872) (xy 342.109186 4.850242) (xy 342.172556 4.908011)
			(xy 342.240985 4.959687) (xy 342.313891 5.004828) (xy 342.390651 5.04305) (xy 342.47061 5.074026)
			(xy 342.553086 5.097493) (xy 342.637376 5.113249) (xy 342.722759 5.121161) (xy 342.808509 5.121161)
			(xy 342.893892 5.113249) (xy 342.978182 5.097493) (xy 343.060658 5.074026) (xy 343.140617 5.04305)
			(xy 343.217377 5.004828) (xy 343.290283 4.959687) (xy 343.358712 4.908011) (xy 343.422082 4.850242)
			(xy 343.479851 4.786872) (xy 343.531527 4.718443) (xy 343.576668 4.645537) (xy 343.61489 4.568777)
			(xy 343.645866 4.488818) (xy 343.669333 4.406342) (xy 343.685089 4.322052) (xy 343.693001 4.236669)
			(xy 343.693496 4.193794) (xy 343.693001 4.150919) (xy 373.705107 4.150919) (xy 373.705107 4.236669)
			(xy 373.713019 4.322052) (xy 373.728775 4.406342) (xy 373.752242 4.488818) (xy 373.783218 4.568777)
			(xy 373.82144 4.645537) (xy 373.866581 4.718443) (xy 373.918257 4.786872) (xy 373.976026 4.850242)
			(xy 374.039396 4.908011) (xy 374.107825 4.959687) (xy 374.180731 5.004828) (xy 374.257491 5.04305)
			(xy 374.33745 5.074026) (xy 374.419926 5.097493) (xy 374.504216 5.113249) (xy 374.589599 5.121161)
			(xy 374.675349 5.121161) (xy 374.760732 5.113249) (xy 374.845022 5.097493) (xy 374.927498 5.074026)
			(xy 375.007457 5.04305) (xy 375.02966 5.031994) (xy 376.211592 5.031994) (xy 376.211592 5.895594)
			(xy 376.212078 5.922845) (xy 376.219834 5.976793) (xy 376.235189 6.029088) (xy 376.257831 6.078665)
			(xy 376.287297 6.124515) (xy 376.322988 6.165706) (xy 376.364179 6.201397) (xy 376.410029 6.230863)
			(xy 376.459606 6.253505) (xy 376.511901 6.26886) (xy 376.565849 6.276616) (xy 376.620351 6.276616)
			(xy 376.674299 6.26886) (xy 376.726594 6.253505) (xy 376.776171 6.230863) (xy 376.822021 6.201397)
			(xy 376.863212 6.165706) (xy 376.898903 6.124515) (xy 376.928369 6.078665) (xy 376.951011 6.029088)
			(xy 376.966366 5.976793) (xy 376.974122 5.922845) (xy 376.974608 5.895594) (xy 376.974608 5.031994)
			(xy 376.974122 5.004743) (xy 376.966366 4.950795) (xy 376.951011 4.8985) (xy 376.928369 4.848923)
			(xy 376.898903 4.803073) (xy 376.863212 4.761882) (xy 376.822021 4.726191) (xy 376.776171 4.696725)
			(xy 376.726594 4.674083) (xy 376.674299 4.658728) (xy 376.620351 4.650972) (xy 376.565849 4.650972)
			(xy 376.511901 4.658728) (xy 376.459606 4.674083) (xy 376.410029 4.696725) (xy 376.364179 4.726191)
			(xy 376.322988 4.761882) (xy 376.287297 4.803073) (xy 376.257831 4.848923) (xy 376.235189 4.8985)
			(xy 376.219834 4.950795) (xy 376.212078 5.004743) (xy 376.211592 5.031994) (xy 375.02966 5.031994)
			(xy 375.084217 5.004828) (xy 375.157123 4.959687) (xy 375.225552 4.908011) (xy 375.288922 4.850242)
			(xy 375.346691 4.786872) (xy 375.398367 4.718443) (xy 375.443508 4.645537) (xy 375.48173 4.568777)
			(xy 375.512706 4.488818) (xy 375.536173 4.406342) (xy 375.551929 4.322052) (xy 375.559841 4.236669)
			(xy 375.560336 4.193794) (xy 375.559841 4.150919) (xy 380.055107 4.150919) (xy 380.055107 4.236669)
			(xy 380.063019 4.322052) (xy 380.078775 4.406342) (xy 380.102242 4.488818) (xy 380.133218 4.568777)
			(xy 380.17144 4.645537) (xy 380.216581 4.718443) (xy 380.268257 4.786872) (xy 380.326026 4.850242)
			(xy 380.389396 4.908011) (xy 380.457825 4.959687) (xy 380.530731 5.004828) (xy 380.607491 5.04305)
			(xy 380.68745 5.074026) (xy 380.769926 5.097493) (xy 380.854216 5.113249) (xy 380.939599 5.121161)
			(xy 381.025349 5.121161) (xy 381.110732 5.113249) (xy 381.195022 5.097493) (xy 381.277498 5.074026)
			(xy 381.357457 5.04305) (xy 381.434217 5.004828) (xy 381.507123 4.959687) (xy 381.575552 4.908011)
			(xy 381.638922 4.850242) (xy 381.696691 4.786872) (xy 381.748367 4.718443) (xy 381.793508 4.645537)
			(xy 381.83173 4.568777) (xy 381.862706 4.488818) (xy 381.886173 4.406342) (xy 381.901929 4.322052)
			(xy 381.909841 4.236669) (xy 381.910336 4.193794) (xy 381.909841 4.150919) (xy 381.901929 4.065536)
			(xy 381.886173 3.981246) (xy 381.862706 3.89877) (xy 381.83173 3.818811) (xy 381.793508 3.742051)
			(xy 381.748367 3.669145) (xy 381.696691 3.600716) (xy 381.638922 3.537346) (xy 381.575552 3.479577)
			(xy 381.507123 3.427901) (xy 381.434217 3.38276) (xy 381.357457 3.344538) (xy 381.277498 3.313562)
			(xy 381.195022 3.290095) (xy 381.110732 3.274339) (xy 381.025349 3.266427) (xy 380.939599 3.266427)
			(xy 380.854216 3.274339) (xy 380.769926 3.290095) (xy 380.68745 3.313562) (xy 380.607491 3.344538)
			(xy 380.530731 3.38276) (xy 380.457825 3.427901) (xy 380.389396 3.479577) (xy 380.326026 3.537346)
			(xy 380.268257 3.600716) (xy 380.216581 3.669145) (xy 380.17144 3.742051) (xy 380.133218 3.818811)
			(xy 380.102242 3.89877) (xy 380.078775 3.981246) (xy 380.063019 4.065536) (xy 380.055107 4.150919)
			(xy 375.559841 4.150919) (xy 375.551929 4.065536) (xy 375.536173 3.981246) (xy 375.512706 3.89877)
			(xy 375.48173 3.818811) (xy 375.443508 3.742051) (xy 375.398367 3.669145) (xy 375.346691 3.600716)
			(xy 375.288922 3.537346) (xy 375.225552 3.479577) (xy 375.157123 3.427901) (xy 375.084217 3.38276)
			(xy 375.007457 3.344538) (xy 374.927498 3.313562) (xy 374.845022 3.290095) (xy 374.760732 3.274339)
			(xy 374.675349 3.266427) (xy 374.589599 3.266427) (xy 374.504216 3.274339) (xy 374.419926 3.290095)
			(xy 374.33745 3.313562) (xy 374.257491 3.344538) (xy 374.180731 3.38276) (xy 374.107825 3.427901)
			(xy 374.039396 3.479577) (xy 373.976026 3.537346) (xy 373.918257 3.600716) (xy 373.866581 3.669145)
			(xy 373.82144 3.742051) (xy 373.783218 3.818811) (xy 373.752242 3.89877) (xy 373.728775 3.981246)
			(xy 373.713019 4.065536) (xy 373.705107 4.150919) (xy 343.693001 4.150919) (xy 343.685089 4.065536)
			(xy 343.669333 3.981246) (xy 343.645866 3.89877) (xy 343.61489 3.818811) (xy 343.576668 3.742051)
			(xy 343.531527 3.669145) (xy 343.479851 3.600716) (xy 343.422082 3.537346) (xy 343.358712 3.479577)
			(xy 343.290283 3.427901) (xy 343.217377 3.38276) (xy 343.140617 3.344538) (xy 343.060658 3.313562)
			(xy 342.978182 3.290095) (xy 342.893892 3.274339) (xy 342.808509 3.266427) (xy 342.722759 3.266427)
			(xy 342.637376 3.274339) (xy 342.553086 3.290095) (xy 342.47061 3.313562) (xy 342.390651 3.344538)
			(xy 342.313891 3.38276) (xy 342.240985 3.427901) (xy 342.172556 3.479577) (xy 342.109186 3.537346)
			(xy 342.051417 3.600716) (xy 341.999741 3.669145) (xy 341.9546 3.742051) (xy 341.916378 3.818811)
			(xy 341.885402 3.89877) (xy 341.861935 3.981246) (xy 341.846179 4.065536) (xy 341.838267 4.150919)
			(xy 337.343001 4.150919) (xy 337.335089 4.065536) (xy 337.319333 3.981246) (xy 337.295866 3.89877)
			(xy 337.26489 3.818811) (xy 337.226668 3.742051) (xy 337.181527 3.669145) (xy 337.129851 3.600716)
			(xy 337.072082 3.537346) (xy 337.008712 3.479577) (xy 336.940283 3.427901) (xy 336.867377 3.38276)
			(xy 336.790617 3.344538) (xy 336.710658 3.313562) (xy 336.628182 3.290095) (xy 336.543892 3.274339)
			(xy 336.458509 3.266427) (xy 336.372759 3.266427) (xy 336.287376 3.274339) (xy 336.203086 3.290095)
			(xy 336.12061 3.313562) (xy 336.040651 3.344538) (xy 335.963891 3.38276) (xy 335.890985 3.427901)
			(xy 335.822556 3.479577) (xy 335.759186 3.537346) (xy 335.701417 3.600716) (xy 335.649741 3.669145)
			(xy 335.6046 3.742051) (xy 335.566378 3.818811) (xy 335.535402 3.89877) (xy 335.511935 3.981246)
			(xy 335.496179 4.065536) (xy 335.488267 4.150919) (xy 333.050655 4.150919) (xy 333.042743 4.065536)
			(xy 333.026987 3.981246) (xy 333.00352 3.89877) (xy 332.972544 3.818811) (xy 332.934322 3.742051)
			(xy 332.889181 3.669145) (xy 332.837505 3.600716) (xy 332.779736 3.537346) (xy 332.716366 3.479577)
			(xy 332.647937 3.427901) (xy 332.575031 3.38276) (xy 332.498271 3.344538) (xy 332.418312 3.313562)
			(xy 332.335836 3.290095) (xy 332.251546 3.274339) (xy 332.166163 3.266427) (xy 332.080413 3.266427)
			(xy 331.99503 3.274339) (xy 331.91074 3.290095) (xy 331.828264 3.313562) (xy 331.748305 3.344538)
			(xy 331.671545 3.38276) (xy 331.598639 3.427901) (xy 331.53021 3.479577) (xy 331.46684 3.537346)
			(xy 331.409071 3.600716) (xy 331.357395 3.669145) (xy 331.312254 3.742051) (xy 331.274032 3.818811)
			(xy 331.243056 3.89877) (xy 331.219589 3.981246) (xy 331.203833 4.065536) (xy 331.195921 4.150919)
			(xy 326.700655 4.150919) (xy 326.692743 4.065536) (xy 326.676987 3.981246) (xy 326.65352 3.89877)
			(xy 326.622544 3.818811) (xy 326.584322 3.742051) (xy 326.539181 3.669145) (xy 326.487505 3.600716)
			(xy 326.429736 3.537346) (xy 326.366366 3.479577) (xy 326.297937 3.427901) (xy 326.225031 3.38276)
			(xy 326.148271 3.344538) (xy 326.068312 3.313562) (xy 325.985836 3.290095) (xy 325.901546 3.274339)
			(xy 325.816163 3.266427) (xy 325.730413 3.266427) (xy 325.64503 3.274339) (xy 325.56074 3.290095)
			(xy 325.478264 3.313562) (xy 325.398305 3.344538) (xy 325.321545 3.38276) (xy 325.248639 3.427901)
			(xy 325.18021 3.479577) (xy 325.11684 3.537346) (xy 325.059071 3.600716) (xy 325.007395 3.669145)
			(xy 324.962254 3.742051) (xy 324.924032 3.818811) (xy 324.893056 3.89877) (xy 324.869589 3.981246)
			(xy 324.853833 4.065536) (xy 324.845921 4.150919) (xy 265.125975 4.150919) (xy 265.118063 4.065536)
			(xy 265.102307 3.981246) (xy 265.07884 3.89877) (xy 265.047864 3.818811) (xy 265.009642 3.742051)
			(xy 264.964501 3.669145) (xy 264.912825 3.600716) (xy 264.855056 3.537346) (xy 264.791686 3.479577)
			(xy 264.723257 3.427901) (xy 264.650351 3.38276) (xy 264.573591 3.344538) (xy 264.493632 3.313562)
			(xy 264.411156 3.290095) (xy 264.326866 3.274339) (xy 264.241483 3.266427) (xy 264.155733 3.266427)
			(xy 264.07035 3.274339) (xy 263.98606 3.290095) (xy 263.903584 3.313562) (xy 263.823625 3.344538)
			(xy 263.746865 3.38276) (xy 263.673959 3.427901) (xy 263.60553 3.479577) (xy 263.54216 3.537346)
			(xy 263.484391 3.600716) (xy 263.432715 3.669145) (xy 263.387574 3.742051) (xy 263.349352 3.818811)
			(xy 263.318376 3.89877) (xy 263.294909 3.981246) (xy 263.279153 4.065536) (xy 263.271241 4.150919)
			(xy 258.775975 4.150919) (xy 258.768063 4.065536) (xy 258.752307 3.981246) (xy 258.72884 3.89877)
			(xy 258.697864 3.818811) (xy 258.659642 3.742051) (xy 258.614501 3.669145) (xy 258.562825 3.600716)
			(xy 258.505056 3.537346) (xy 258.441686 3.479577) (xy 258.373257 3.427901) (xy 258.300351 3.38276)
			(xy 258.223591 3.344538) (xy 258.143632 3.313562) (xy 258.061156 3.290095) (xy 257.976866 3.274339)
			(xy 257.891483 3.266427) (xy 257.805733 3.266427) (xy 257.72035 3.274339) (xy 257.63606 3.290095)
			(xy 257.553584 3.313562) (xy 257.473625 3.344538) (xy 257.396865 3.38276) (xy 257.323959 3.427901)
			(xy 257.25553 3.479577) (xy 257.19216 3.537346) (xy 257.134391 3.600716) (xy 257.082715 3.669145)
			(xy 257.037574 3.742051) (xy 256.999352 3.818811) (xy 256.968376 3.89877) (xy 256.944909 3.981246)
			(xy 256.929153 4.065536) (xy 256.921241 4.150919) (xy 254.465119 4.150919) (xy 254.465087 4.148125)
			(xy 254.457175 4.062742) (xy 254.441419 3.978452) (xy 254.417952 3.895976) (xy 254.386976 3.816017)
			(xy 254.348754 3.739257) (xy 254.303613 3.666351) (xy 254.251937 3.597922) (xy 254.194168 3.534552)
			(xy 254.130798 3.476783) (xy 254.062369 3.425107) (xy 253.989463 3.379966) (xy 253.912703 3.341744)
			(xy 253.832744 3.310768) (xy 253.750268 3.287301) (xy 253.665978 3.271545) (xy 253.580595 3.263633)
			(xy 253.494845 3.263633) (xy 253.409462 3.271545) (xy 253.325172 3.287301) (xy 253.242696 3.310768)
			(xy 253.162737 3.341744) (xy 253.085977 3.379966) (xy 253.013071 3.425107) (xy 252.944642 3.476783)
			(xy 252.881272 3.534552) (xy 252.823503 3.597922) (xy 252.771827 3.666351) (xy 252.726686 3.739257)
			(xy 252.688464 3.816017) (xy 252.657488 3.895976) (xy 252.634021 3.978452) (xy 252.618265 4.062742)
			(xy 252.610353 4.148125) (xy 248.115087 4.148125) (xy 248.107175 4.062742) (xy 248.091419 3.978452)
			(xy 248.067952 3.895976) (xy 248.036976 3.816017) (xy 247.998754 3.739257) (xy 247.953613 3.666351)
			(xy 247.901937 3.597922) (xy 247.844168 3.534552) (xy 247.780798 3.476783) (xy 247.712369 3.425107)
			(xy 247.639463 3.379966) (xy 247.562703 3.341744) (xy 247.482744 3.310768) (xy 247.400268 3.287301)
			(xy 247.315978 3.271545) (xy 247.230595 3.263633) (xy 247.144845 3.263633) (xy 247.059462 3.271545)
			(xy 246.975172 3.287301) (xy 246.892696 3.310768) (xy 246.812737 3.341744) (xy 246.735977 3.379966)
			(xy 246.663071 3.425107) (xy 246.594642 3.476783) (xy 246.531272 3.534552) (xy 246.473503 3.597922)
			(xy 246.421827 3.666351) (xy 246.376686 3.739257) (xy 246.338464 3.816017) (xy 246.307488 3.895976)
			(xy 246.284021 3.978452) (xy 246.268265 4.062742) (xy 246.260353 4.148125) (xy 186.540407 4.148125)
			(xy 186.532495 4.062742) (xy 186.516739 3.978452) (xy 186.493272 3.895976) (xy 186.462296 3.816017)
			(xy 186.424074 3.739257) (xy 186.378933 3.666351) (xy 186.327257 3.597922) (xy 186.269488 3.534552)
			(xy 186.206118 3.476783) (xy 186.137689 3.425107) (xy 186.064783 3.379966) (xy 185.988023 3.341744)
			(xy 185.908064 3.310768) (xy 185.825588 3.287301) (xy 185.741298 3.271545) (xy 185.655915 3.263633)
			(xy 185.570165 3.263633) (xy 185.484782 3.271545) (xy 185.400492 3.287301) (xy 185.318016 3.310768)
			(xy 185.238057 3.341744) (xy 185.161297 3.379966) (xy 185.088391 3.425107) (xy 185.019962 3.476783)
			(xy 184.956592 3.534552) (xy 184.898823 3.597922) (xy 184.847147 3.666351) (xy 184.802006 3.739257)
			(xy 184.763784 3.816017) (xy 184.732808 3.895976) (xy 184.709341 3.978452) (xy 184.693585 4.062742)
			(xy 184.685673 4.148125) (xy 180.190407 4.148125) (xy 180.182495 4.062742) (xy 180.166739 3.978452)
			(xy 180.143272 3.895976) (xy 180.112296 3.816017) (xy 180.074074 3.739257) (xy 180.028933 3.666351)
			(xy 179.977257 3.597922) (xy 179.919488 3.534552) (xy 179.856118 3.476783) (xy 179.787689 3.425107)
			(xy 179.714783 3.379966) (xy 179.638023 3.341744) (xy 179.558064 3.310768) (xy 179.475588 3.287301)
			(xy 179.391298 3.271545) (xy 179.305915 3.263633) (xy 179.220165 3.263633) (xy 179.134782 3.271545)
			(xy 179.050492 3.287301) (xy 178.968016 3.310768) (xy 178.888057 3.341744) (xy 178.811297 3.379966)
			(xy 178.738391 3.425107) (xy 178.669962 3.476783) (xy 178.606592 3.534552) (xy 178.548823 3.597922)
			(xy 178.497147 3.666351) (xy 178.452006 3.739257) (xy 178.413784 3.816017) (xy 178.382808 3.895976)
			(xy 178.359341 3.978452) (xy 178.343585 4.062742) (xy 178.335673 4.148125) (xy 0.508 4.148125) (xy 0.508 -7.78002)
			(xy 0.508522 -7.835827) (xy 0.516863 -7.947129) (xy 0.533498 -8.057497) (xy 0.558334 -8.166312) (xy 0.591233 -8.272968)
			(xy 0.63201 -8.376867) (xy 0.680438 -8.477428) (xy 0.736245 -8.574088) (xy 0.799119 -8.666308) (xy 0.868709 -8.753572)
			(xy 0.944626 -8.835391) (xy 1.026445 -8.911308) (xy 1.113708 -8.980898) (xy 1.205928 -9.043773) (xy 1.302589 -9.09958)
			(xy 1.40315 -9.148008) (xy 1.507048 -9.188786) (xy 1.613704 -9.221685) (xy 1.722519 -9.246521) (xy 1.832887 -9.263157)
			(xy 1.944189 -9.271498) (xy 1.999996 -9.272016) (xy 9.10209 -9.272016) (xy 9.157898 -9.271495) (xy 9.269201 -9.263154)
			(xy 9.379569 -9.24652) (xy 9.488386 -9.221684) (xy 9.595043 -9.188786) (xy 9.698942 -9.148009) (xy 9.799505 -9.099582)
			(xy 9.896167 -9.043775) (xy 9.988388 -8.980901) (xy 10.075653 -8.911311) (xy 10.157473 -8.835394)
			(xy 10.233392 -8.753575) (xy 10.302983 -8.666312) (xy 10.365859 -8.574092) (xy 10.421668 -8.477431)
			(xy 10.470097 -8.37687) (xy 10.510876 -8.272971) (xy 10.543776 -8.166315) (xy 10.568614 -8.057499)
			(xy 10.585251 -7.94713) (xy 10.593594 -7.835828) (xy 10.594086 -7.78002) (xy 10.594086 0.999998)
			(xy 10.59457 1.070352) (xy 10.60246 1.210839) (xy 10.618214 1.350662) (xy 10.641783 1.489382) (xy 10.673094 1.626562)
			(xy 10.712047 1.761771) (xy 10.758519 1.894583) (xy 10.812366 2.02458) (xy 10.873417 2.151354) (xy 10.94148 2.274505)
			(xy 11.016341 2.393646) (xy 11.097765 2.508402) (xy 11.185495 2.618411) (xy 11.279255 2.723329) (xy 11.378751 2.822825)
			(xy 11.483669 2.916585) (xy 11.593678 3.004315) (xy 11.708434 3.085739) (xy 11.827575 3.1606) (xy 11.950726 3.228663)
			(xy 12.0775 3.289714) (xy 12.207497 3.343561) (xy 12.340309 3.390033) (xy 12.475518 3.428986) (xy 12.612698 3.460297)
			(xy 12.751418 3.483866) (xy 12.891241 3.49962) (xy 13.031728 3.50751) (xy 13.102082 3.507994) (xy 81.701894 3.507994)
			(xy 81.772248 3.50751) (xy 81.912735 3.499621) (xy 82.052558 3.483867) (xy 82.191278 3.460297) (xy 82.328459 3.428987)
			(xy 82.463668 3.390034) (xy 82.59648 3.343562) (xy 82.726477 3.289715) (xy 82.853251 3.228664) (xy 82.976402 3.160601)
			(xy 83.095543 3.08574) (xy 83.2103 3.004317) (xy 83.32031 2.916587) (xy 83.425228 2.822826) (xy 83.524724 2.723331)
			(xy 83.618484 2.618413) (xy 83.706214 2.508403) (xy 83.787638 2.393647) (xy 83.862499 2.274506) (xy 83.930563 2.151355)
			(xy 83.991614 2.024581) (xy 84.04546 1.894584) (xy 84.091933 1.761772) (xy 84.130886 1.626563) (xy 84.135094 1.608125)
			(xy 178.335673 1.608125) (xy 178.335673 1.693875) (xy 178.343585 1.779258) (xy 178.359341 1.863548)
			(xy 178.382808 1.946024) (xy 178.413784 2.025983) (xy 178.452006 2.102743) (xy 178.497147 2.175649)
			(xy 178.548823 2.244078) (xy 178.606592 2.307448) (xy 178.669962 2.365217) (xy 178.738391 2.416893)
			(xy 178.811297 2.462034) (xy 178.888057 2.500256) (xy 178.968016 2.531232) (xy 179.050492 2.554699)
			(xy 179.134782 2.570455) (xy 179.220165 2.578367) (xy 179.305915 2.578367) (xy 179.391298 2.570455)
			(xy 179.475588 2.554699) (xy 179.558064 2.531232) (xy 179.638023 2.500256) (xy 179.660226 2.4892)
			(xy 183.270652 2.4892) (xy 183.270652 3.3528) (xy 183.271138 3.380069) (xy 183.2789 3.434053) (xy 183.294265 3.486383)
			(xy 183.316922 3.535993) (xy 183.346408 3.581874) (xy 183.382123 3.623091) (xy 183.42334 3.658806)
			(xy 183.469221 3.688292) (xy 183.518831 3.710949) (xy 183.571161 3.726314) (xy 183.625145 3.734076)
			(xy 183.679683 3.734076) (xy 183.733667 3.726314) (xy 183.785997 3.710949) (xy 183.835607 3.688292)
			(xy 183.881488 3.658806) (xy 183.922705 3.623091) (xy 183.95842 3.581874) (xy 183.987906 3.535993)
			(xy 184.010563 3.486383) (xy 184.025928 3.434053) (xy 184.03369 3.380069) (xy 184.034176 3.3528)
			(xy 184.034176 2.4892) (xy 184.03369 2.461931) (xy 184.025928 2.407947) (xy 184.010563 2.355617)
			(xy 183.987906 2.306007) (xy 183.95842 2.260126) (xy 183.922705 2.218909) (xy 183.881488 2.183194)
			(xy 183.835607 2.153708) (xy 183.785997 2.131051) (xy 183.733667 2.115686) (xy 183.679683 2.107924)
			(xy 183.625145 2.107924) (xy 183.571161 2.115686) (xy 183.518831 2.131051) (xy 183.469221 2.153708)
			(xy 183.42334 2.183194) (xy 183.382123 2.218909) (xy 183.346408 2.260126) (xy 183.316922 2.306007)
			(xy 183.294265 2.355617) (xy 183.2789 2.407947) (xy 183.271138 2.461931) (xy 183.270652 2.4892) (xy 179.660226 2.4892)
			(xy 179.714783 2.462034) (xy 179.787689 2.416893) (xy 179.856118 2.365217) (xy 179.919488 2.307448)
			(xy 179.977257 2.244078) (xy 180.028933 2.175649) (xy 180.074074 2.102743) (xy 180.112296 2.025983)
			(xy 180.143272 1.946024) (xy 180.166739 1.863548) (xy 180.182495 1.779258) (xy 180.190407 1.693875)
			(xy 180.190902 1.651) (xy 180.190407 1.608125) (xy 184.685673 1.608125) (xy 184.685673 1.693875)
			(xy 184.693585 1.779258) (xy 184.709341 1.863548) (xy 184.732808 1.946024) (xy 184.763784 2.025983)
			(xy 184.802006 2.102743) (xy 184.847147 2.175649) (xy 184.898823 2.244078) (xy 184.956592 2.307448)
			(xy 185.019962 2.365217) (xy 185.088391 2.416893) (xy 185.161297 2.462034) (xy 185.238057 2.500256)
			(xy 185.318016 2.531232) (xy 185.400492 2.554699) (xy 185.484782 2.570455) (xy 185.570165 2.578367)
			(xy 185.655915 2.578367) (xy 185.741298 2.570455) (xy 185.825588 2.554699) (xy 185.908064 2.531232)
			(xy 185.988023 2.500256) (xy 186.064783 2.462034) (xy 186.137689 2.416893) (xy 186.206118 2.365217)
			(xy 186.269488 2.307448) (xy 186.327257 2.244078) (xy 186.378933 2.175649) (xy 186.424074 2.102743)
			(xy 186.462296 2.025983) (xy 186.493272 1.946024) (xy 186.516739 1.863548) (xy 186.532495 1.779258)
			(xy 186.540407 1.693875) (xy 186.540902 1.651) (xy 186.540407 1.608125) (xy 246.260353 1.608125)
			(xy 246.260353 1.693875) (xy 246.268265 1.779258) (xy 246.284021 1.863548) (xy 246.307488 1.946024)
			(xy 246.338464 2.025983) (xy 246.376686 2.102743) (xy 246.421827 2.175649) (xy 246.473503 2.244078)
			(xy 246.531272 2.307448) (xy 246.594642 2.365217) (xy 246.663071 2.416893) (xy 246.735977 2.462034)
			(xy 246.812737 2.500256) (xy 246.892696 2.531232) (xy 246.975172 2.554699) (xy 247.059462 2.570455)
			(xy 247.144845 2.578367) (xy 247.230595 2.578367) (xy 247.315978 2.570455) (xy 247.400268 2.554699)
			(xy 247.482744 2.531232) (xy 247.562703 2.500256) (xy 247.584906 2.4892) (xy 248.766584 2.4892) (xy 248.766584 3.3528)
			(xy 248.76707 3.380069) (xy 248.774832 3.434053) (xy 248.790197 3.486383) (xy 248.812854 3.535993)
			(xy 248.84234 3.581874) (xy 248.878055 3.623091) (xy 248.919272 3.658806) (xy 248.965153 3.688292)
			(xy 249.014763 3.710949) (xy 249.067093 3.726314) (xy 249.121077 3.734076) (xy 249.175615 3.734076)
			(xy 249.229599 3.726314) (xy 249.281929 3.710949) (xy 249.331539 3.688292) (xy 249.37742 3.658806)
			(xy 249.418637 3.623091) (xy 249.454352 3.581874) (xy 249.483838 3.535993) (xy 249.506495 3.486383)
			(xy 249.52186 3.434053) (xy 249.529622 3.380069) (xy 249.530108 3.3528) (xy 249.530108 2.4892) (xy 249.529622 2.461931)
			(xy 249.52186 2.407947) (xy 249.506495 2.355617) (xy 249.483838 2.306007) (xy 249.454352 2.260126)
			(xy 249.418637 2.218909) (xy 249.37742 2.183194) (xy 249.331539 2.153708) (xy 249.281929 2.131051)
			(xy 249.229599 2.115686) (xy 249.175615 2.107924) (xy 249.121077 2.107924) (xy 249.067093 2.115686)
			(xy 249.014763 2.131051) (xy 248.965153 2.153708) (xy 248.919272 2.183194) (xy 248.878055 2.218909)
			(xy 248.84234 2.260126) (xy 248.812854 2.306007) (xy 248.790197 2.355617) (xy 248.774832 2.407947)
			(xy 248.76707 2.461931) (xy 248.766584 2.4892) (xy 247.584906 2.4892) (xy 247.639463 2.462034) (xy 247.712369 2.416893)
			(xy 247.780798 2.365217) (xy 247.844168 2.307448) (xy 247.901937 2.244078) (xy 247.953613 2.175649)
			(xy 247.998754 2.102743) (xy 248.036976 2.025983) (xy 248.067952 1.946024) (xy 248.091419 1.863548)
			(xy 248.107175 1.779258) (xy 248.115087 1.693875) (xy 248.115582 1.651) (xy 248.115087 1.608125)
			(xy 252.610353 1.608125) (xy 252.610353 1.693875) (xy 252.618265 1.779258) (xy 252.634021 1.863548)
			(xy 252.657488 1.946024) (xy 252.688464 2.025983) (xy 252.726686 2.102743) (xy 252.771827 2.175649)
			(xy 252.823503 2.244078) (xy 252.881272 2.307448) (xy 252.944642 2.365217) (xy 253.013071 2.416893)
			(xy 253.085977 2.462034) (xy 253.162737 2.500256) (xy 253.242696 2.531232) (xy 253.325172 2.554699)
			(xy 253.409462 2.570455) (xy 253.494845 2.578367) (xy 253.580595 2.578367) (xy 253.665978 2.570455)
			(xy 253.750268 2.554699) (xy 253.832744 2.531232) (xy 253.912703 2.500256) (xy 253.989463 2.462034)
			(xy 254.062369 2.416893) (xy 254.130798 2.365217) (xy 254.194168 2.307448) (xy 254.251937 2.244078)
			(xy 254.303613 2.175649) (xy 254.348754 2.102743) (xy 254.386976 2.025983) (xy 254.417952 1.946024)
			(xy 254.441419 1.863548) (xy 254.457175 1.779258) (xy 254.465087 1.693875) (xy 254.465582 1.651)
			(xy 254.465119 1.610919) (xy 256.921241 1.610919) (xy 256.921241 1.696669) (xy 256.929153 1.782052)
			(xy 256.944909 1.866342) (xy 256.968376 1.948818) (xy 256.999352 2.028777) (xy 257.037574 2.105537)
			(xy 257.082715 2.178443) (xy 257.134391 2.246872) (xy 257.19216 2.310242) (xy 257.25553 2.368011)
			(xy 257.323959 2.419687) (xy 257.396865 2.464828) (xy 257.473625 2.50305) (xy 257.553584 2.534026)
			(xy 257.63606 2.557493) (xy 257.72035 2.573249) (xy 257.805733 2.581161) (xy 257.891483 2.581161)
			(xy 257.976866 2.573249) (xy 258.061156 2.557493) (xy 258.143632 2.534026) (xy 258.223591 2.50305)
			(xy 258.245794 2.491994) (xy 261.85622 2.491994) (xy 261.85622 3.355594) (xy 261.856706 3.382863)
			(xy 261.864468 3.436847) (xy 261.879833 3.489177) (xy 261.90249 3.538787) (xy 261.931976 3.584668)
			(xy 261.967691 3.625885) (xy 262.008908 3.6616) (xy 262.054789 3.691086) (xy 262.104399 3.713743)
			(xy 262.156729 3.729108) (xy 262.210713 3.73687) (xy 262.265251 3.73687) (xy 262.319235 3.729108)
			(xy 262.371565 3.713743) (xy 262.421175 3.691086) (xy 262.467056 3.6616) (xy 262.508273 3.625885)
			(xy 262.543988 3.584668) (xy 262.573474 3.538787) (xy 262.596131 3.489177) (xy 262.611496 3.436847)
			(xy 262.619258 3.382863) (xy 262.619744 3.355594) (xy 262.619744 2.491994) (xy 262.619258 2.464725)
			(xy 262.611496 2.410741) (xy 262.596131 2.358411) (xy 262.573474 2.308801) (xy 262.543988 2.26292)
			(xy 262.508273 2.221703) (xy 262.467056 2.185988) (xy 262.421175 2.156502) (xy 262.371565 2.133845)
			(xy 262.319235 2.11848) (xy 262.265251 2.110718) (xy 262.210713 2.110718) (xy 262.156729 2.11848)
			(xy 262.104399 2.133845) (xy 262.054789 2.156502) (xy 262.008908 2.185988) (xy 261.967691 2.221703)
			(xy 261.931976 2.26292) (xy 261.90249 2.308801) (xy 261.879833 2.358411) (xy 261.864468 2.410741)
			(xy 261.856706 2.464725) (xy 261.85622 2.491994) (xy 258.245794 2.491994) (xy 258.300351 2.464828)
			(xy 258.373257 2.419687) (xy 258.441686 2.368011) (xy 258.505056 2.310242) (xy 258.562825 2.246872)
			(xy 258.614501 2.178443) (xy 258.659642 2.105537) (xy 258.697864 2.028777) (xy 258.72884 1.948818)
			(xy 258.752307 1.866342) (xy 258.768063 1.782052) (xy 258.775975 1.696669) (xy 258.77647 1.653794)
			(xy 258.775975 1.610919) (xy 263.271241 1.610919) (xy 263.271241 1.696669) (xy 263.279153 1.782052)
			(xy 263.294909 1.866342) (xy 263.318376 1.948818) (xy 263.349352 2.028777) (xy 263.387574 2.105537)
			(xy 263.432715 2.178443) (xy 263.484391 2.246872) (xy 263.54216 2.310242) (xy 263.60553 2.368011)
			(xy 263.673959 2.419687) (xy 263.746865 2.464828) (xy 263.823625 2.50305) (xy 263.903584 2.534026)
			(xy 263.98606 2.557493) (xy 264.07035 2.573249) (xy 264.155733 2.581161) (xy 264.241483 2.581161)
			(xy 264.326866 2.573249) (xy 264.411156 2.557493) (xy 264.493632 2.534026) (xy 264.573591 2.50305)
			(xy 264.650351 2.464828) (xy 264.723257 2.419687) (xy 264.791686 2.368011) (xy 264.855056 2.310242)
			(xy 264.912825 2.246872) (xy 264.964501 2.178443) (xy 265.009642 2.105537) (xy 265.047864 2.028777)
			(xy 265.07884 1.948818) (xy 265.102307 1.866342) (xy 265.118063 1.782052) (xy 265.125975 1.696669)
			(xy 265.12647 1.653794) (xy 265.125975 1.610919) (xy 324.845921 1.610919) (xy 324.845921 1.696669)
			(xy 324.853833 1.782052) (xy 324.869589 1.866342) (xy 324.893056 1.948818) (xy 324.924032 2.028777)
			(xy 324.962254 2.105537) (xy 325.007395 2.178443) (xy 325.059071 2.246872) (xy 325.11684 2.310242)
			(xy 325.18021 2.368011) (xy 325.248639 2.419687) (xy 325.321545 2.464828) (xy 325.398305 2.50305)
			(xy 325.478264 2.534026) (xy 325.56074 2.557493) (xy 325.64503 2.573249) (xy 325.730413 2.581161)
			(xy 325.816163 2.581161) (xy 325.901546 2.573249) (xy 325.985836 2.557493) (xy 326.068312 2.534026)
			(xy 326.148271 2.50305) (xy 326.170474 2.491994) (xy 327.352152 2.491994) (xy 327.352152 3.355594)
			(xy 327.352638 3.382863) (xy 327.3604 3.436847) (xy 327.375765 3.489177) (xy 327.398422 3.538787)
			(xy 327.427908 3.584668) (xy 327.463623 3.625885) (xy 327.50484 3.6616) (xy 327.550721 3.691086)
			(xy 327.600331 3.713743) (xy 327.652661 3.729108) (xy 327.706645 3.73687) (xy 327.761183 3.73687)
			(xy 327.815167 3.729108) (xy 327.867497 3.713743) (xy 327.917107 3.691086) (xy 327.962988 3.6616)
			(xy 328.004205 3.625885) (xy 328.03992 3.584668) (xy 328.069406 3.538787) (xy 328.092063 3.489177)
			(xy 328.107428 3.436847) (xy 328.11519 3.382863) (xy 328.115676 3.355594) (xy 328.115676 2.491994)
			(xy 328.11519 2.464725) (xy 328.107428 2.410741) (xy 328.092063 2.358411) (xy 328.069406 2.308801)
			(xy 328.03992 2.26292) (xy 328.004205 2.221703) (xy 327.962988 2.185988) (xy 327.917107 2.156502)
			(xy 327.867497 2.133845) (xy 327.815167 2.11848) (xy 327.761183 2.110718) (xy 327.706645 2.110718)
			(xy 327.652661 2.11848) (xy 327.600331 2.133845) (xy 327.550721 2.156502) (xy 327.50484 2.185988)
			(xy 327.463623 2.221703) (xy 327.427908 2.26292) (xy 327.398422 2.308801) (xy 327.375765 2.358411)
			(xy 327.3604 2.410741) (xy 327.352638 2.464725) (xy 327.352152 2.491994) (xy 326.170474 2.491994)
			(xy 326.225031 2.464828) (xy 326.297937 2.419687) (xy 326.366366 2.368011) (xy 326.429736 2.310242)
			(xy 326.487505 2.246872) (xy 326.539181 2.178443) (xy 326.584322 2.105537) (xy 326.622544 2.028777)
			(xy 326.65352 1.948818) (xy 326.676987 1.866342) (xy 326.692743 1.782052) (xy 326.700655 1.696669)
			(xy 326.70115 1.653794) (xy 326.700655 1.610919) (xy 331.195921 1.610919) (xy 331.195921 1.696669)
			(xy 331.203833 1.782052) (xy 331.219589 1.866342) (xy 331.243056 1.948818) (xy 331.274032 2.028777)
			(xy 331.312254 2.105537) (xy 331.357395 2.178443) (xy 331.409071 2.246872) (xy 331.46684 2.310242)
			(xy 331.53021 2.368011) (xy 331.598639 2.419687) (xy 331.671545 2.464828) (xy 331.748305 2.50305)
			(xy 331.828264 2.534026) (xy 331.91074 2.557493) (xy 331.99503 2.573249) (xy 332.080413 2.581161)
			(xy 332.166163 2.581161) (xy 332.251546 2.573249) (xy 332.335836 2.557493) (xy 332.418312 2.534026)
			(xy 332.498271 2.50305) (xy 332.575031 2.464828) (xy 332.647937 2.419687) (xy 332.716366 2.368011)
			(xy 332.779736 2.310242) (xy 332.837505 2.246872) (xy 332.889181 2.178443) (xy 332.934322 2.105537)
			(xy 332.972544 2.028777) (xy 333.00352 1.948818) (xy 333.026987 1.866342) (xy 333.042743 1.782052)
			(xy 333.050655 1.696669) (xy 333.05115 1.653794) (xy 333.050655 1.610919) (xy 335.488267 1.610919)
			(xy 335.488267 1.696669) (xy 335.496179 1.782052) (xy 335.511935 1.866342) (xy 335.535402 1.948818)
			(xy 335.566378 2.028777) (xy 335.6046 2.105537) (xy 335.649741 2.178443) (xy 335.701417 2.246872)
			(xy 335.759186 2.310242) (xy 335.822556 2.368011) (xy 335.890985 2.419687) (xy 335.963891 2.464828)
			(xy 336.040651 2.50305) (xy 336.12061 2.534026) (xy 336.203086 2.557493) (xy 336.287376 2.573249)
			(xy 336.372759 2.581161) (xy 336.458509 2.581161) (xy 336.543892 2.573249) (xy 336.628182 2.557493)
			(xy 336.710658 2.534026) (xy 336.790617 2.50305) (xy 336.81282 2.491994) (xy 340.4235 2.491994) (xy 340.4235 3.355594)
			(xy 340.423986 3.382845) (xy 340.431742 3.436793) (xy 340.447097 3.489088) (xy 340.469739 3.538665)
			(xy 340.499205 3.584515) (xy 340.534896 3.625706) (xy 340.576087 3.661397) (xy 340.621937 3.690863)
			(xy 340.671514 3.713505) (xy 340.723809 3.72886) (xy 340.777757 3.736616) (xy 340.832259 3.736616)
			(xy 340.886207 3.72886) (xy 340.938502 3.713505) (xy 340.988079 3.690863) (xy 341.033929 3.661397)
			(xy 341.07512 3.625706) (xy 341.110811 3.584515) (xy 341.140277 3.538665) (xy 341.162919 3.489088)
			(xy 341.178274 3.436793) (xy 341.18603 3.382845) (xy 341.186516 3.355594) (xy 341.186516 2.491994)
			(xy 341.18603 2.464743) (xy 341.178274 2.410795) (xy 341.162919 2.3585) (xy 341.140277 2.308923)
			(xy 341.110811 2.263073) (xy 341.07512 2.221882) (xy 341.033929 2.186191) (xy 340.988079 2.156725)
			(xy 340.938502 2.134083) (xy 340.886207 2.118728) (xy 340.832259 2.110972) (xy 340.777757 2.110972)
			(xy 340.723809 2.118728) (xy 340.671514 2.134083) (xy 340.621937 2.156725) (xy 340.576087 2.186191)
			(xy 340.534896 2.221882) (xy 340.499205 2.263073) (xy 340.469739 2.308923) (xy 340.447097 2.3585)
			(xy 340.431742 2.410795) (xy 340.423986 2.464743) (xy 340.4235 2.491994) (xy 336.81282 2.491994)
			(xy 336.867377 2.464828) (xy 336.940283 2.419687) (xy 337.008712 2.368011) (xy 337.072082 2.310242)
			(xy 337.129851 2.246872) (xy 337.181527 2.178443) (xy 337.226668 2.105537) (xy 337.26489 2.028777)
			(xy 337.295866 1.948818) (xy 337.319333 1.866342) (xy 337.335089 1.782052) (xy 337.343001 1.696669)
			(xy 337.343496 1.653794) (xy 337.343001 1.610919) (xy 341.838267 1.610919) (xy 341.838267 1.696669)
			(xy 341.846179 1.782052) (xy 341.861935 1.866342) (xy 341.885402 1.948818) (xy 341.916378 2.028777)
			(xy 341.9546 2.105537) (xy 341.999741 2.178443) (xy 342.051417 2.246872) (xy 342.109186 2.310242)
			(xy 342.172556 2.368011) (xy 342.240985 2.419687) (xy 342.313891 2.464828) (xy 342.390651 2.50305)
			(xy 342.47061 2.534026) (xy 342.553086 2.557493) (xy 342.637376 2.573249) (xy 342.722759 2.581161)
			(xy 342.808509 2.581161) (xy 342.893892 2.573249) (xy 342.978182 2.557493) (xy 343.060658 2.534026)
			(xy 343.140617 2.50305) (xy 343.217377 2.464828) (xy 343.290283 2.419687) (xy 343.358712 2.368011)
			(xy 343.422082 2.310242) (xy 343.479851 2.246872) (xy 343.531527 2.178443) (xy 343.576668 2.105537)
			(xy 343.61489 2.028777) (xy 343.645866 1.948818) (xy 343.669333 1.866342) (xy 343.685089 1.782052)
			(xy 343.693001 1.696669) (xy 343.693496 1.653794) (xy 343.693001 1.610919) (xy 373.705107 1.610919)
			(xy 373.705107 1.696669) (xy 373.713019 1.782052) (xy 373.728775 1.866342) (xy 373.752242 1.948818)
			(xy 373.783218 2.028777) (xy 373.82144 2.105537) (xy 373.866581 2.178443) (xy 373.918257 2.246872)
			(xy 373.976026 2.310242) (xy 374.039396 2.368011) (xy 374.107825 2.419687) (xy 374.180731 2.464828)
			(xy 374.257491 2.50305) (xy 374.33745 2.534026) (xy 374.419926 2.557493) (xy 374.504216 2.573249)
			(xy 374.589599 2.581161) (xy 374.675349 2.581161) (xy 374.760732 2.573249) (xy 374.845022 2.557493)
			(xy 374.927498 2.534026) (xy 375.007457 2.50305) (xy 375.02966 2.491994) (xy 376.211592 2.491994)
			(xy 376.211592 3.355594) (xy 376.212078 3.382845) (xy 376.219834 3.436793) (xy 376.235189 3.489088)
			(xy 376.257831 3.538665) (xy 376.287297 3.584515) (xy 376.322988 3.625706) (xy 376.364179 3.661397)
			(xy 376.410029 3.690863) (xy 376.459606 3.713505) (xy 376.511901 3.72886) (xy 376.565849 3.736616)
			(xy 376.620351 3.736616) (xy 376.674299 3.72886) (xy 376.726594 3.713505) (xy 376.776171 3.690863)
			(xy 376.822021 3.661397) (xy 376.863212 3.625706) (xy 376.898903 3.584515) (xy 376.928369 3.538665)
			(xy 376.951011 3.489088) (xy 376.966366 3.436793) (xy 376.974122 3.382845) (xy 376.974608 3.355594)
			(xy 376.974608 2.491994) (xy 376.974122 2.464743) (xy 376.966366 2.410795) (xy 376.951011 2.3585)
			(xy 376.928369 2.308923) (xy 376.898903 2.263073) (xy 376.863212 2.221882) (xy 376.822021 2.186191)
			(xy 376.776171 2.156725) (xy 376.726594 2.134083) (xy 376.674299 2.118728) (xy 376.620351 2.110972)
			(xy 376.565849 2.110972) (xy 376.511901 2.118728) (xy 376.459606 2.134083) (xy 376.410029 2.156725)
			(xy 376.364179 2.186191) (xy 376.322988 2.221882) (xy 376.287297 2.263073) (xy 376.257831 2.308923)
			(xy 376.235189 2.3585) (xy 376.219834 2.410795) (xy 376.212078 2.464743) (xy 376.211592 2.491994)
			(xy 375.02966 2.491994) (xy 375.084217 2.464828) (xy 375.157123 2.419687) (xy 375.225552 2.368011)
			(xy 375.288922 2.310242) (xy 375.346691 2.246872) (xy 375.398367 2.178443) (xy 375.443508 2.105537)
			(xy 375.48173 2.028777) (xy 375.512706 1.948818) (xy 375.536173 1.866342) (xy 375.551929 1.782052)
			(xy 375.559841 1.696669) (xy 375.560336 1.653794) (xy 375.559841 1.610919) (xy 380.055107 1.610919)
			(xy 380.055107 1.696669) (xy 380.063019 1.782052) (xy 380.078775 1.866342) (xy 380.102242 1.948818)
			(xy 380.133218 2.028777) (xy 380.17144 2.105537) (xy 380.216581 2.178443) (xy 380.268257 2.246872)
			(xy 380.326026 2.310242) (xy 380.389396 2.368011) (xy 380.457825 2.419687) (xy 380.530731 2.464828)
			(xy 380.607491 2.50305) (xy 380.68745 2.534026) (xy 380.769926 2.557493) (xy 380.854216 2.573249)
			(xy 380.939599 2.581161) (xy 381.025349 2.581161) (xy 381.110732 2.573249) (xy 381.195022 2.557493)
			(xy 381.277498 2.534026) (xy 381.357457 2.50305) (xy 381.434217 2.464828) (xy 381.507123 2.419687)
			(xy 381.575552 2.368011) (xy 381.638922 2.310242) (xy 381.696691 2.246872) (xy 381.748367 2.178443)
			(xy 381.793508 2.105537) (xy 381.83173 2.028777) (xy 381.862706 1.948818) (xy 381.886173 1.866342)
			(xy 381.901929 1.782052) (xy 381.909841 1.696669) (xy 381.910336 1.653794) (xy 381.909841 1.610919)
			(xy 381.901929 1.525536) (xy 381.886173 1.441246) (xy 381.862706 1.35877) (xy 381.83173 1.278811)
			(xy 381.793508 1.202051) (xy 381.748367 1.129145) (xy 381.696691 1.060716) (xy 381.638922 0.997346)
			(xy 381.575552 0.939577) (xy 381.507123 0.887901) (xy 381.434217 0.84276) (xy 381.357457 0.804538)
			(xy 381.277498 0.773562) (xy 381.195022 0.750095) (xy 381.110732 0.734339) (xy 381.025349 0.726427)
			(xy 380.939599 0.726427) (xy 380.854216 0.734339) (xy 380.769926 0.750095) (xy 380.68745 0.773562)
			(xy 380.607491 0.804538) (xy 380.530731 0.84276) (xy 380.457825 0.887901) (xy 380.389396 0.939577)
			(xy 380.326026 0.997346) (xy 380.268257 1.060716) (xy 380.216581 1.129145) (xy 380.17144 1.202051)
			(xy 380.133218 1.278811) (xy 380.102242 1.35877) (xy 380.078775 1.441246) (xy 380.063019 1.525536)
			(xy 380.055107 1.610919) (xy 375.559841 1.610919) (xy 375.551929 1.525536) (xy 375.536173 1.441246)
			(xy 375.512706 1.35877) (xy 375.48173 1.278811) (xy 375.443508 1.202051) (xy 375.398367 1.129145)
			(xy 375.346691 1.060716) (xy 375.288922 0.997346) (xy 375.225552 0.939577) (xy 375.157123 0.887901)
			(xy 375.084217 0.84276) (xy 375.007457 0.804538) (xy 374.927498 0.773562) (xy 374.845022 0.750095)
			(xy 374.760732 0.734339) (xy 374.675349 0.726427) (xy 374.589599 0.726427) (xy 374.504216 0.734339)
			(xy 374.419926 0.750095) (xy 374.33745 0.773562) (xy 374.257491 0.804538) (xy 374.180731 0.84276)
			(xy 374.107825 0.887901) (xy 374.039396 0.939577) (xy 373.976026 0.997346) (xy 373.918257 1.060716)
			(xy 373.866581 1.129145) (xy 373.82144 1.202051) (xy 373.783218 1.278811) (xy 373.752242 1.35877)
			(xy 373.728775 1.441246) (xy 373.713019 1.525536) (xy 373.705107 1.610919) (xy 343.693001 1.610919)
			(xy 343.685089 1.525536) (xy 343.669333 1.441246) (xy 343.645866 1.35877) (xy 343.61489 1.278811)
			(xy 343.576668 1.202051) (xy 343.531527 1.129145) (xy 343.479851 1.060716) (xy 343.422082 0.997346)
			(xy 343.358712 0.939577) (xy 343.290283 0.887901) (xy 343.217377 0.84276) (xy 343.140617 0.804538)
			(xy 343.060658 0.773562) (xy 342.978182 0.750095) (xy 342.893892 0.734339) (xy 342.808509 0.726427)
			(xy 342.722759 0.726427) (xy 342.637376 0.734339) (xy 342.553086 0.750095) (xy 342.47061 0.773562)
			(xy 342.390651 0.804538) (xy 342.313891 0.84276) (xy 342.240985 0.887901) (xy 342.172556 0.939577)
			(xy 342.109186 0.997346) (xy 342.051417 1.060716) (xy 341.999741 1.129145) (xy 341.9546 1.202051)
			(xy 341.916378 1.278811) (xy 341.885402 1.35877) (xy 341.861935 1.441246) (xy 341.846179 1.525536)
			(xy 341.838267 1.610919) (xy 337.343001 1.610919) (xy 337.335089 1.525536) (xy 337.319333 1.441246)
			(xy 337.295866 1.35877) (xy 337.26489 1.278811) (xy 337.226668 1.202051) (xy 337.181527 1.129145)
			(xy 337.129851 1.060716) (xy 337.072082 0.997346) (xy 337.008712 0.939577) (xy 336.940283 0.887901)
			(xy 336.867377 0.84276) (xy 336.790617 0.804538) (xy 336.710658 0.773562) (xy 336.628182 0.750095)
			(xy 336.543892 0.734339) (xy 336.458509 0.726427) (xy 336.372759 0.726427) (xy 336.287376 0.734339)
			(xy 336.203086 0.750095) (xy 336.12061 0.773562) (xy 336.040651 0.804538) (xy 335.963891 0.84276)
			(xy 335.890985 0.887901) (xy 335.822556 0.939577) (xy 335.759186 0.997346) (xy 335.701417 1.060716)
			(xy 335.649741 1.129145) (xy 335.6046 1.202051) (xy 335.566378 1.278811) (xy 335.535402 1.35877)
			(xy 335.511935 1.441246) (xy 335.496179 1.525536) (xy 335.488267 1.610919) (xy 333.050655 1.610919)
			(xy 333.042743 1.525536) (xy 333.026987 1.441246) (xy 333.00352 1.35877) (xy 332.972544 1.278811)
			(xy 332.934322 1.202051) (xy 332.889181 1.129145) (xy 332.837505 1.060716) (xy 332.779736 0.997346)
			(xy 332.716366 0.939577) (xy 332.647937 0.887901) (xy 332.575031 0.84276) (xy 332.498271 0.804538)
			(xy 332.418312 0.773562) (xy 332.335836 0.750095) (xy 332.251546 0.734339) (xy 332.166163 0.726427)
			(xy 332.080413 0.726427) (xy 331.99503 0.734339) (xy 331.91074 0.750095) (xy 331.828264 0.773562)
			(xy 331.748305 0.804538) (xy 331.671545 0.84276) (xy 331.598639 0.887901) (xy 331.53021 0.939577)
			(xy 331.46684 0.997346) (xy 331.409071 1.060716) (xy 331.357395 1.129145) (xy 331.312254 1.202051)
			(xy 331.274032 1.278811) (xy 331.243056 1.35877) (xy 331.219589 1.441246) (xy 331.203833 1.525536)
			(xy 331.195921 1.610919) (xy 326.700655 1.610919) (xy 326.692743 1.525536) (xy 326.676987 1.441246)
			(xy 326.65352 1.35877) (xy 326.622544 1.278811) (xy 326.584322 1.202051) (xy 326.539181 1.129145)
			(xy 326.487505 1.060716) (xy 326.429736 0.997346) (xy 326.366366 0.939577) (xy 326.297937 0.887901)
			(xy 326.225031 0.84276) (xy 326.148271 0.804538) (xy 326.068312 0.773562) (xy 325.985836 0.750095)
			(xy 325.901546 0.734339) (xy 325.816163 0.726427) (xy 325.730413 0.726427) (xy 325.64503 0.734339)
			(xy 325.56074 0.750095) (xy 325.478264 0.773562) (xy 325.398305 0.804538) (xy 325.321545 0.84276)
			(xy 325.248639 0.887901) (xy 325.18021 0.939577) (xy 325.11684 0.997346) (xy 325.059071 1.060716)
			(xy 325.007395 1.129145) (xy 324.962254 1.202051) (xy 324.924032 1.278811) (xy 324.893056 1.35877)
			(xy 324.869589 1.441246) (xy 324.853833 1.525536) (xy 324.845921 1.610919) (xy 265.125975 1.610919)
			(xy 265.118063 1.525536) (xy 265.102307 1.441246) (xy 265.07884 1.35877) (xy 265.047864 1.278811)
			(xy 265.009642 1.202051) (xy 264.964501 1.129145) (xy 264.912825 1.060716) (xy 264.855056 0.997346)
			(xy 264.791686 0.939577) (xy 264.723257 0.887901) (xy 264.650351 0.84276) (xy 264.573591 0.804538)
			(xy 264.493632 0.773562) (xy 264.411156 0.750095) (xy 264.326866 0.734339) (xy 264.241483 0.726427)
			(xy 264.155733 0.726427) (xy 264.07035 0.734339) (xy 263.98606 0.750095) (xy 263.903584 0.773562)
			(xy 263.823625 0.804538) (xy 263.746865 0.84276) (xy 263.673959 0.887901) (xy 263.60553 0.939577)
			(xy 263.54216 0.997346) (xy 263.484391 1.060716) (xy 263.432715 1.129145) (xy 263.387574 1.202051)
			(xy 263.349352 1.278811) (xy 263.318376 1.35877) (xy 263.294909 1.441246) (xy 263.279153 1.525536)
			(xy 263.271241 1.610919) (xy 258.775975 1.610919) (xy 258.768063 1.525536) (xy 258.752307 1.441246)
			(xy 258.72884 1.35877) (xy 258.697864 1.278811) (xy 258.659642 1.202051) (xy 258.614501 1.129145)
			(xy 258.562825 1.060716) (xy 258.505056 0.997346) (xy 258.441686 0.939577) (xy 258.373257 0.887901)
			(xy 258.300351 0.84276) (xy 258.223591 0.804538) (xy 258.143632 0.773562) (xy 258.061156 0.750095)
			(xy 257.976866 0.734339) (xy 257.891483 0.726427) (xy 257.805733 0.726427) (xy 257.72035 0.734339)
			(xy 257.63606 0.750095) (xy 257.553584 0.773562) (xy 257.473625 0.804538) (xy 257.396865 0.84276)
			(xy 257.323959 0.887901) (xy 257.25553 0.939577) (xy 257.19216 0.997346) (xy 257.134391 1.060716)
			(xy 257.082715 1.129145) (xy 257.037574 1.202051) (xy 256.999352 1.278811) (xy 256.968376 1.35877)
			(xy 256.944909 1.441246) (xy 256.929153 1.525536) (xy 256.921241 1.610919) (xy 254.465119 1.610919)
			(xy 254.465087 1.608125) (xy 254.457175 1.522742) (xy 254.441419 1.438452) (xy 254.417952 1.355976)
			(xy 254.386976 1.276017) (xy 254.348754 1.199257) (xy 254.303613 1.126351) (xy 254.251937 1.057922)
			(xy 254.194168 0.994552) (xy 254.130798 0.936783) (xy 254.062369 0.885107) (xy 253.989463 0.839966)
			(xy 253.912703 0.801744) (xy 253.832744 0.770768) (xy 253.750268 0.747301) (xy 253.665978 0.731545)
			(xy 253.580595 0.723633) (xy 253.494845 0.723633) (xy 253.409462 0.731545) (xy 253.325172 0.747301)
			(xy 253.242696 0.770768) (xy 253.162737 0.801744) (xy 253.085977 0.839966) (xy 253.013071 0.885107)
			(xy 252.944642 0.936783) (xy 252.881272 0.994552) (xy 252.823503 1.057922) (xy 252.771827 1.126351)
			(xy 252.726686 1.199257) (xy 252.688464 1.276017) (xy 252.657488 1.355976) (xy 252.634021 1.438452)
			(xy 252.618265 1.522742) (xy 252.610353 1.608125) (xy 248.115087 1.608125) (xy 248.107175 1.522742)
			(xy 248.091419 1.438452) (xy 248.067952 1.355976) (xy 248.036976 1.276017) (xy 247.998754 1.199257)
			(xy 247.953613 1.126351) (xy 247.901937 1.057922) (xy 247.844168 0.994552) (xy 247.780798 0.936783)
			(xy 247.712369 0.885107) (xy 247.639463 0.839966) (xy 247.562703 0.801744) (xy 247.482744 0.770768)
			(xy 247.400268 0.747301) (xy 247.315978 0.731545) (xy 247.230595 0.723633) (xy 247.144845 0.723633)
			(xy 247.059462 0.731545) (xy 246.975172 0.747301) (xy 246.892696 0.770768) (xy 246.812737 0.801744)
			(xy 246.735977 0.839966) (xy 246.663071 0.885107) (xy 246.594642 0.936783) (xy 246.531272 0.994552)
			(xy 246.473503 1.057922) (xy 246.421827 1.126351) (xy 246.376686 1.199257) (xy 246.338464 1.276017)
			(xy 246.307488 1.355976) (xy 246.284021 1.438452) (xy 246.268265 1.522742) (xy 246.260353 1.608125)
			(xy 186.540407 1.608125) (xy 186.532495 1.522742) (xy 186.516739 1.438452) (xy 186.493272 1.355976)
			(xy 186.462296 1.276017) (xy 186.424074 1.199257) (xy 186.378933 1.126351) (xy 186.327257 1.057922)
			(xy 186.269488 0.994552) (xy 186.206118 0.936783) (xy 186.137689 0.885107) (xy 186.064783 0.839966)
			(xy 185.988023 0.801744) (xy 185.908064 0.770768) (xy 185.825588 0.747301) (xy 185.741298 0.731545)
			(xy 185.655915 0.723633) (xy 185.570165 0.723633) (xy 185.484782 0.731545) (xy 185.400492 0.747301)
			(xy 185.318016 0.770768) (xy 185.238057 0.801744) (xy 185.161297 0.839966) (xy 185.088391 0.885107)
			(xy 185.019962 0.936783) (xy 184.956592 0.994552) (xy 184.898823 1.057922) (xy 184.847147 1.126351)
			(xy 184.802006 1.199257) (xy 184.763784 1.276017) (xy 184.732808 1.355976) (xy 184.709341 1.438452)
			(xy 184.693585 1.522742) (xy 184.685673 1.608125) (xy 180.190407 1.608125) (xy 180.182495 1.522742)
			(xy 180.166739 1.438452) (xy 180.143272 1.355976) (xy 180.112296 1.276017) (xy 180.074074 1.199257)
			(xy 180.028933 1.126351) (xy 179.977257 1.057922) (xy 179.919488 0.994552) (xy 179.856118 0.936783)
			(xy 179.787689 0.885107) (xy 179.714783 0.839966) (xy 179.638023 0.801744) (xy 179.558064 0.770768)
			(xy 179.475588 0.747301) (xy 179.391298 0.731545) (xy 179.305915 0.723633) (xy 179.220165 0.723633)
			(xy 179.134782 0.731545) (xy 179.050492 0.747301) (xy 178.968016 0.770768) (xy 178.888057 0.801744)
			(xy 178.811297 0.839966) (xy 178.738391 0.885107) (xy 178.669962 0.936783) (xy 178.606592 0.994552)
			(xy 178.548823 1.057922) (xy 178.497147 1.126351) (xy 178.452006 1.199257) (xy 178.413784 1.276017)
			(xy 178.382808 1.355976) (xy 178.359341 1.438452) (xy 178.343585 1.522742) (xy 178.335673 1.608125)
			(xy 84.135094 1.608125) (xy 84.162197 1.489382) (xy 84.185766 1.350662) (xy 84.20152 1.210839) (xy 84.20941 1.070352)
			(xy 84.20989 0.999998) (xy 84.20989 -0.931875) (xy 208.043513 -0.931875) (xy 208.043513 -0.846125)
			(xy 208.051425 -0.760742) (xy 208.067181 -0.676452) (xy 208.090648 -0.593976) (xy 208.121624 -0.514017)
			(xy 208.159846 -0.437257) (xy 208.204987 -0.364351) (xy 208.256663 -0.295922) (xy 208.314432 -0.232552)
			(xy 208.377802 -0.174783) (xy 208.446231 -0.123107) (xy 208.519137 -0.077966) (xy 208.595897 -0.039744)
			(xy 208.675856 -0.008768) (xy 208.758332 0.014699) (xy 208.842622 0.030455) (xy 208.928005 0.038367)
			(xy 209.013755 0.038367) (xy 209.099138 0.030455) (xy 209.183428 0.014699) (xy 209.265904 -0.008768)
			(xy 209.345863 -0.039744) (xy 209.422623 -0.077966) (xy 209.495529 -0.123107) (xy 209.563958 -0.174783)
			(xy 209.627328 -0.232552) (xy 209.685097 -0.295922) (xy 209.736773 -0.364351) (xy 209.781914 -0.437257)
			(xy 209.820136 -0.514017) (xy 209.851112 -0.593976) (xy 209.874579 -0.676452) (xy 209.890335 -0.760742)
			(xy 209.898247 -0.846125) (xy 209.898742 -0.889) (xy 209.898247 -0.931875) (xy 214.393513 -0.931875)
			(xy 214.393513 -0.846125) (xy 214.401425 -0.760742) (xy 214.417181 -0.676452) (xy 214.440648 -0.593976)
			(xy 214.471624 -0.514017) (xy 214.509846 -0.437257) (xy 214.554987 -0.364351) (xy 214.606663 -0.295922)
			(xy 214.664432 -0.232552) (xy 214.727802 -0.174783) (xy 214.796231 -0.123107) (xy 214.869137 -0.077966)
			(xy 214.945897 -0.039744) (xy 215.025856 -0.008768) (xy 215.108332 0.014699) (xy 215.192622 0.030455)
			(xy 215.278005 0.038367) (xy 215.363755 0.038367) (xy 215.449138 0.030455) (xy 215.533428 0.014699)
			(xy 215.615904 -0.008768) (xy 215.695863 -0.039744) (xy 215.772623 -0.077966) (xy 215.845529 -0.123107)
			(xy 215.913958 -0.174783) (xy 215.977328 -0.232552) (xy 216.035097 -0.295922) (xy 216.086773 -0.364351)
			(xy 216.131914 -0.437257) (xy 216.170136 -0.514017) (xy 216.201112 -0.593976) (xy 216.224579 -0.676452)
			(xy 216.240335 -0.760742) (xy 216.248247 -0.846125) (xy 216.248742 -0.889) (xy 216.248247 -0.931875)
			(xy 246.260353 -0.931875) (xy 246.260353 -0.846125) (xy 246.268265 -0.760742) (xy 246.284021 -0.676452)
			(xy 246.307488 -0.593976) (xy 246.338464 -0.514017) (xy 246.376686 -0.437257) (xy 246.421827 -0.364351)
			(xy 246.473503 -0.295922) (xy 246.531272 -0.232552) (xy 246.594642 -0.174783) (xy 246.663071 -0.123107)
			(xy 246.735977 -0.077966) (xy 246.812737 -0.039744) (xy 246.892696 -0.008768) (xy 246.975172 0.014699)
			(xy 247.059462 0.030455) (xy 247.144845 0.038367) (xy 247.230595 0.038367) (xy 247.315978 0.030455)
			(xy 247.400268 0.014699) (xy 247.482744 -0.008768) (xy 247.562703 -0.039744) (xy 247.639463 -0.077966)
			(xy 247.712369 -0.123107) (xy 247.780798 -0.174783) (xy 247.844168 -0.232552) (xy 247.901937 -0.295922)
			(xy 247.953613 -0.364351) (xy 247.998754 -0.437257) (xy 248.036976 -0.514017) (xy 248.067952 -0.593976)
			(xy 248.091419 -0.676452) (xy 248.107175 -0.760742) (xy 248.115087 -0.846125) (xy 248.115582 -0.889)
			(xy 248.115087 -0.931875) (xy 252.610353 -0.931875) (xy 252.610353 -0.846125) (xy 252.618265 -0.760742)
			(xy 252.634021 -0.676452) (xy 252.657488 -0.593976) (xy 252.688464 -0.514017) (xy 252.726686 -0.437257)
			(xy 252.771827 -0.364351) (xy 252.823503 -0.295922) (xy 252.881272 -0.232552) (xy 252.944642 -0.174783)
			(xy 253.013071 -0.123107) (xy 253.085977 -0.077966) (xy 253.162737 -0.039744) (xy 253.242696 -0.008768)
			(xy 253.325172 0.014699) (xy 253.409462 0.030455) (xy 253.494845 0.038367) (xy 253.580595 0.038367)
			(xy 253.665978 0.030455) (xy 253.750268 0.014699) (xy 253.832744 -0.008768) (xy 253.912703 -0.039744)
			(xy 253.989463 -0.077966) (xy 254.062369 -0.123107) (xy 254.130798 -0.174783) (xy 254.194168 -0.232552)
			(xy 254.251937 -0.295922) (xy 254.303613 -0.364351) (xy 254.348754 -0.437257) (xy 254.386976 -0.514017)
			(xy 254.417952 -0.593976) (xy 254.441419 -0.676452) (xy 254.457175 -0.760742) (xy 254.465087 -0.846125)
			(xy 254.465582 -0.889) (xy 254.465119 -0.929081) (xy 256.921241 -0.929081) (xy 256.921241 -0.843331)
			(xy 256.929153 -0.757948) (xy 256.944909 -0.673658) (xy 256.968376 -0.591182) (xy 256.999352 -0.511223)
			(xy 257.037574 -0.434463) (xy 257.082715 -0.361557) (xy 257.134391 -0.293128) (xy 257.19216 -0.229758)
			(xy 257.25553 -0.171989) (xy 257.323959 -0.120313) (xy 257.396865 -0.075172) (xy 257.473625 -0.03695)
			(xy 257.553584 -0.005974) (xy 257.63606 0.017493) (xy 257.72035 0.033249) (xy 257.805733 0.041161)
			(xy 257.891483 0.041161) (xy 257.976866 0.033249) (xy 258.061156 0.017493) (xy 258.143632 -0.005974)
			(xy 258.223591 -0.03695) (xy 258.245794 -0.048006) (xy 261.85622 -0.048006) (xy 261.85622 0.815594)
			(xy 261.856706 0.842863) (xy 261.864468 0.896847) (xy 261.879833 0.949177) (xy 261.90249 0.998787)
			(xy 261.931976 1.044668) (xy 261.967691 1.085885) (xy 262.008908 1.1216) (xy 262.054789 1.151086)
			(xy 262.104399 1.173743) (xy 262.156729 1.189108) (xy 262.210713 1.19687) (xy 262.265251 1.19687)
			(xy 262.319235 1.189108) (xy 262.371565 1.173743) (xy 262.421175 1.151086) (xy 262.467056 1.1216)
			(xy 262.508273 1.085885) (xy 262.543988 1.044668) (xy 262.573474 0.998787) (xy 262.596131 0.949177)
			(xy 262.611496 0.896847) (xy 262.619258 0.842863) (xy 262.619744 0.815594) (xy 262.619744 -0.048006)
			(xy 262.619258 -0.075275) (xy 262.611496 -0.129259) (xy 262.596131 -0.181589) (xy 262.573474 -0.231199)
			(xy 262.543988 -0.27708) (xy 262.508273 -0.318297) (xy 262.467056 -0.354012) (xy 262.421175 -0.383498)
			(xy 262.371565 -0.406155) (xy 262.319235 -0.42152) (xy 262.265251 -0.429282) (xy 262.210713 -0.429282)
			(xy 262.156729 -0.42152) (xy 262.104399 -0.406155) (xy 262.054789 -0.383498) (xy 262.008908 -0.354012)
			(xy 261.967691 -0.318297) (xy 261.931976 -0.27708) (xy 261.90249 -0.231199) (xy 261.879833 -0.181589)
			(xy 261.864468 -0.129259) (xy 261.856706 -0.075275) (xy 261.85622 -0.048006) (xy 258.245794 -0.048006)
			(xy 258.300351 -0.075172) (xy 258.373257 -0.120313) (xy 258.441686 -0.171989) (xy 258.505056 -0.229758)
			(xy 258.562825 -0.293128) (xy 258.614501 -0.361557) (xy 258.659642 -0.434463) (xy 258.697864 -0.511223)
			(xy 258.72884 -0.591182) (xy 258.752307 -0.673658) (xy 258.768063 -0.757948) (xy 258.775975 -0.843331)
			(xy 258.77647 -0.886206) (xy 258.775975 -0.929081) (xy 263.271241 -0.929081) (xy 263.271241 -0.843331)
			(xy 263.279153 -0.757948) (xy 263.294909 -0.673658) (xy 263.318376 -0.591182) (xy 263.349352 -0.511223)
			(xy 263.387574 -0.434463) (xy 263.432715 -0.361557) (xy 263.484391 -0.293128) (xy 263.54216 -0.229758)
			(xy 263.60553 -0.171989) (xy 263.673959 -0.120313) (xy 263.746865 -0.075172) (xy 263.823625 -0.03695)
			(xy 263.903584 -0.005974) (xy 263.98606 0.017493) (xy 264.07035 0.033249) (xy 264.155733 0.041161)
			(xy 264.241483 0.041161) (xy 264.326866 0.033249) (xy 264.411156 0.017493) (xy 264.493632 -0.005974)
			(xy 264.573591 -0.03695) (xy 264.650351 -0.075172) (xy 264.723257 -0.120313) (xy 264.791686 -0.171989)
			(xy 264.855056 -0.229758) (xy 264.912825 -0.293128) (xy 264.964501 -0.361557) (xy 265.009642 -0.434463)
			(xy 265.047864 -0.511223) (xy 265.07884 -0.591182) (xy 265.102307 -0.673658) (xy 265.118063 -0.757948)
			(xy 265.125975 -0.843331) (xy 265.12647 -0.886206) (xy 265.125975 -0.929081) (xy 324.845921 -0.929081)
			(xy 324.845921 -0.843331) (xy 324.853833 -0.757948) (xy 324.869589 -0.673658) (xy 324.893056 -0.591182)
			(xy 324.924032 -0.511223) (xy 324.962254 -0.434463) (xy 325.007395 -0.361557) (xy 325.059071 -0.293128)
			(xy 325.11684 -0.229758) (xy 325.18021 -0.171989) (xy 325.248639 -0.120313) (xy 325.321545 -0.075172)
			(xy 325.398305 -0.03695) (xy 325.478264 -0.005974) (xy 325.56074 0.017493) (xy 325.64503 0.033249)
			(xy 325.730413 0.041161) (xy 325.816163 0.041161) (xy 325.901546 0.033249) (xy 325.985836 0.017493)
			(xy 326.068312 -0.005974) (xy 326.148271 -0.03695) (xy 326.170474 -0.048006) (xy 327.352152 -0.048006)
			(xy 327.352152 0.815594) (xy 327.352638 0.842863) (xy 327.3604 0.896847) (xy 327.375765 0.949177)
			(xy 327.398422 0.998787) (xy 327.427908 1.044668) (xy 327.463623 1.085885) (xy 327.50484 1.1216)
			(xy 327.550721 1.151086) (xy 327.600331 1.173743) (xy 327.652661 1.189108) (xy 327.706645 1.19687)
			(xy 327.761183 1.19687) (xy 327.815167 1.189108) (xy 327.867497 1.173743) (xy 327.917107 1.151086)
			(xy 327.962988 1.1216) (xy 328.004205 1.085885) (xy 328.03992 1.044668) (xy 328.069406 0.998787)
			(xy 328.092063 0.949177) (xy 328.107428 0.896847) (xy 328.11519 0.842863) (xy 328.115676 0.815594)
			(xy 328.115676 -0.048006) (xy 328.11519 -0.075275) (xy 328.107428 -0.129259) (xy 328.092063 -0.181589)
			(xy 328.069406 -0.231199) (xy 328.03992 -0.27708) (xy 328.004205 -0.318297) (xy 327.962988 -0.354012)
			(xy 327.917107 -0.383498) (xy 327.867497 -0.406155) (xy 327.815167 -0.42152) (xy 327.761183 -0.429282)
			(xy 327.706645 -0.429282) (xy 327.652661 -0.42152) (xy 327.600331 -0.406155) (xy 327.550721 -0.383498)
			(xy 327.50484 -0.354012) (xy 327.463623 -0.318297) (xy 327.427908 -0.27708) (xy 327.398422 -0.231199)
			(xy 327.375765 -0.181589) (xy 327.3604 -0.129259) (xy 327.352638 -0.075275) (xy 327.352152 -0.048006)
			(xy 326.170474 -0.048006) (xy 326.225031 -0.075172) (xy 326.297937 -0.120313) (xy 326.366366 -0.171989)
			(xy 326.429736 -0.229758) (xy 326.487505 -0.293128) (xy 326.539181 -0.361557) (xy 326.584322 -0.434463)
			(xy 326.622544 -0.511223) (xy 326.65352 -0.591182) (xy 326.676987 -0.673658) (xy 326.692743 -0.757948)
			(xy 326.700655 -0.843331) (xy 326.70115 -0.886206) (xy 326.700655 -0.929081) (xy 331.195921 -0.929081)
			(xy 331.195921 -0.843331) (xy 331.203833 -0.757948) (xy 331.219589 -0.673658) (xy 331.243056 -0.591182)
			(xy 331.274032 -0.511223) (xy 331.312254 -0.434463) (xy 331.357395 -0.361557) (xy 331.409071 -0.293128)
			(xy 331.46684 -0.229758) (xy 331.53021 -0.171989) (xy 331.598639 -0.120313) (xy 331.671545 -0.075172)
			(xy 331.748305 -0.03695) (xy 331.828264 -0.005974) (xy 331.91074 0.017493) (xy 331.99503 0.033249)
			(xy 332.080413 0.041161) (xy 332.166163 0.041161) (xy 332.251546 0.033249) (xy 332.335836 0.017493)
			(xy 332.418312 -0.005974) (xy 332.498271 -0.03695) (xy 332.575031 -0.075172) (xy 332.647937 -0.120313)
			(xy 332.716366 -0.171989) (xy 332.779736 -0.229758) (xy 332.837505 -0.293128) (xy 332.889181 -0.361557)
			(xy 332.934322 -0.434463) (xy 332.972544 -0.511223) (xy 333.00352 -0.591182) (xy 333.026987 -0.673658)
			(xy 333.042743 -0.757948) (xy 333.050655 -0.843331) (xy 333.05115 -0.886206) (xy 333.050655 -0.929081)
			(xy 335.488267 -0.929081) (xy 335.488267 -0.843331) (xy 335.496179 -0.757948) (xy 335.511935 -0.673658)
			(xy 335.535402 -0.591182) (xy 335.566378 -0.511223) (xy 335.6046 -0.434463) (xy 335.649741 -0.361557)
			(xy 335.701417 -0.293128) (xy 335.759186 -0.229758) (xy 335.822556 -0.171989) (xy 335.890985 -0.120313)
			(xy 335.963891 -0.075172) (xy 336.040651 -0.03695) (xy 336.12061 -0.005974) (xy 336.203086 0.017493)
			(xy 336.287376 0.033249) (xy 336.372759 0.041161) (xy 336.458509 0.041161) (xy 336.543892 0.033249)
			(xy 336.628182 0.017493) (xy 336.710658 -0.005974) (xy 336.790617 -0.03695) (xy 336.81282 -0.048006)
			(xy 340.4235 -0.048006) (xy 340.4235 0.815594) (xy 340.423986 0.842845) (xy 340.431742 0.896793)
			(xy 340.447097 0.949088) (xy 340.469739 0.998665) (xy 340.499205 1.044515) (xy 340.534896 1.085706)
			(xy 340.576087 1.121397) (xy 340.621937 1.150863) (xy 340.671514 1.173505) (xy 340.723809 1.18886)
			(xy 340.777757 1.196616) (xy 340.832259 1.196616) (xy 340.886207 1.18886) (xy 340.938502 1.173505)
			(xy 340.988079 1.150863) (xy 341.033929 1.121397) (xy 341.07512 1.085706) (xy 341.110811 1.044515)
			(xy 341.140277 0.998665) (xy 341.162919 0.949088) (xy 341.178274 0.896793) (xy 341.18603 0.842845)
			(xy 341.186516 0.815594) (xy 341.186516 -0.048006) (xy 341.18603 -0.075257) (xy 341.178274 -0.129205)
			(xy 341.162919 -0.1815) (xy 341.140277 -0.231077) (xy 341.110811 -0.276927) (xy 341.07512 -0.318118)
			(xy 341.033929 -0.353809) (xy 340.988079 -0.383275) (xy 340.938502 -0.405917) (xy 340.886207 -0.421272)
			(xy 340.832259 -0.429028) (xy 340.777757 -0.429028) (xy 340.723809 -0.421272) (xy 340.671514 -0.405917)
			(xy 340.621937 -0.383275) (xy 340.576087 -0.353809) (xy 340.534896 -0.318118) (xy 340.499205 -0.276927)
			(xy 340.469739 -0.231077) (xy 340.447097 -0.1815) (xy 340.431742 -0.129205) (xy 340.423986 -0.075257)
			(xy 340.4235 -0.048006) (xy 336.81282 -0.048006) (xy 336.867377 -0.075172) (xy 336.940283 -0.120313)
			(xy 337.008712 -0.171989) (xy 337.072082 -0.229758) (xy 337.129851 -0.293128) (xy 337.181527 -0.361557)
			(xy 337.226668 -0.434463) (xy 337.26489 -0.511223) (xy 337.295866 -0.591182) (xy 337.319333 -0.673658)
			(xy 337.335089 -0.757948) (xy 337.343001 -0.843331) (xy 337.343496 -0.886206) (xy 337.343001 -0.929081)
			(xy 341.838267 -0.929081) (xy 341.838267 -0.843331) (xy 341.846179 -0.757948) (xy 341.861935 -0.673658)
			(xy 341.885402 -0.591182) (xy 341.916378 -0.511223) (xy 341.9546 -0.434463) (xy 341.999741 -0.361557)
			(xy 342.051417 -0.293128) (xy 342.109186 -0.229758) (xy 342.172556 -0.171989) (xy 342.240985 -0.120313)
			(xy 342.313891 -0.075172) (xy 342.390651 -0.03695) (xy 342.47061 -0.005974) (xy 342.553086 0.017493)
			(xy 342.637376 0.033249) (xy 342.722759 0.041161) (xy 342.808509 0.041161) (xy 342.893892 0.033249)
			(xy 342.978182 0.017493) (xy 343.060658 -0.005974) (xy 343.140617 -0.03695) (xy 343.217377 -0.075172)
			(xy 343.290283 -0.120313) (xy 343.358712 -0.171989) (xy 343.422082 -0.229758) (xy 343.479851 -0.293128)
			(xy 343.531527 -0.361557) (xy 343.576668 -0.434463) (xy 343.61489 -0.511223) (xy 343.645866 -0.591182)
			(xy 343.669333 -0.673658) (xy 343.685089 -0.757948) (xy 343.693001 -0.843331) (xy 343.693496 -0.886206)
			(xy 343.693001 -0.929081) (xy 373.705107 -0.929081) (xy 373.705107 -0.843331) (xy 373.713019 -0.757948)
			(xy 373.728775 -0.673658) (xy 373.752242 -0.591182) (xy 373.783218 -0.511223) (xy 373.82144 -0.434463)
			(xy 373.866581 -0.361557) (xy 373.918257 -0.293128) (xy 373.976026 -0.229758) (xy 374.039396 -0.171989)
			(xy 374.107825 -0.120313) (xy 374.180731 -0.075172) (xy 374.257491 -0.03695) (xy 374.33745 -0.005974)
			(xy 374.419926 0.017493) (xy 374.504216 0.033249) (xy 374.589599 0.041161) (xy 374.675349 0.041161)
			(xy 374.760732 0.033249) (xy 374.845022 0.017493) (xy 374.927498 -0.005974) (xy 375.007457 -0.03695)
			(xy 375.02966 -0.048006) (xy 376.211592 -0.048006) (xy 376.211592 0.815594) (xy 376.212078 0.842845)
			(xy 376.219834 0.896793) (xy 376.235189 0.949088) (xy 376.257831 0.998665) (xy 376.287297 1.044515)
			(xy 376.322988 1.085706) (xy 376.364179 1.121397) (xy 376.410029 1.150863) (xy 376.459606 1.173505)
			(xy 376.511901 1.18886) (xy 376.565849 1.196616) (xy 376.620351 1.196616) (xy 376.674299 1.18886)
			(xy 376.726594 1.173505) (xy 376.776171 1.150863) (xy 376.822021 1.121397) (xy 376.863212 1.085706)
			(xy 376.898903 1.044515) (xy 376.928369 0.998665) (xy 376.951011 0.949088) (xy 376.966366 0.896793)
			(xy 376.974122 0.842845) (xy 376.974608 0.815594) (xy 376.974608 -0.048006) (xy 376.974122 -0.075257)
			(xy 376.966366 -0.129205) (xy 376.951011 -0.1815) (xy 376.928369 -0.231077) (xy 376.898903 -0.276927)
			(xy 376.863212 -0.318118) (xy 376.822021 -0.353809) (xy 376.776171 -0.383275) (xy 376.726594 -0.405917)
			(xy 376.674299 -0.421272) (xy 376.620351 -0.429028) (xy 376.565849 -0.429028) (xy 376.511901 -0.421272)
			(xy 376.459606 -0.405917) (xy 376.410029 -0.383275) (xy 376.364179 -0.353809) (xy 376.322988 -0.318118)
			(xy 376.287297 -0.276927) (xy 376.257831 -0.231077) (xy 376.235189 -0.1815) (xy 376.219834 -0.129205)
			(xy 376.212078 -0.075257) (xy 376.211592 -0.048006) (xy 375.02966 -0.048006) (xy 375.084217 -0.075172)
			(xy 375.157123 -0.120313) (xy 375.225552 -0.171989) (xy 375.288922 -0.229758) (xy 375.346691 -0.293128)
			(xy 375.398367 -0.361557) (xy 375.443508 -0.434463) (xy 375.48173 -0.511223) (xy 375.512706 -0.591182)
			(xy 375.536173 -0.673658) (xy 375.551929 -0.757948) (xy 375.559841 -0.843331) (xy 375.560336 -0.886206)
			(xy 375.559841 -0.929081) (xy 380.055107 -0.929081) (xy 380.055107 -0.843331) (xy 380.063019 -0.757948)
			(xy 380.078775 -0.673658) (xy 380.102242 -0.591182) (xy 380.133218 -0.511223) (xy 380.17144 -0.434463)
			(xy 380.216581 -0.361557) (xy 380.268257 -0.293128) (xy 380.326026 -0.229758) (xy 380.389396 -0.171989)
			(xy 380.457825 -0.120313) (xy 380.530731 -0.075172) (xy 380.607491 -0.03695) (xy 380.68745 -0.005974)
			(xy 380.769926 0.017493) (xy 380.854216 0.033249) (xy 380.939599 0.041161) (xy 381.025349 0.041161)
			(xy 381.110732 0.033249) (xy 381.195022 0.017493) (xy 381.277498 -0.005974) (xy 381.357457 -0.03695)
			(xy 381.434217 -0.075172) (xy 381.507123 -0.120313) (xy 381.575552 -0.171989) (xy 381.638922 -0.229758)
			(xy 381.696691 -0.293128) (xy 381.748367 -0.361557) (xy 381.793508 -0.434463) (xy 381.83173 -0.511223)
			(xy 381.862706 -0.591182) (xy 381.886173 -0.673658) (xy 381.901929 -0.757948) (xy 381.909841 -0.843331)
			(xy 381.910336 -0.886206) (xy 381.909841 -0.929081) (xy 381.901929 -1.014464) (xy 381.886173 -1.098754)
			(xy 381.862706 -1.18123) (xy 381.83173 -1.261189) (xy 381.793508 -1.337949) (xy 381.748367 -1.410855)
			(xy 381.696691 -1.479284) (xy 381.638922 -1.542654) (xy 381.575552 -1.600423) (xy 381.507123 -1.652099)
			(xy 381.434217 -1.69724) (xy 381.357457 -1.735462) (xy 381.277498 -1.766438) (xy 381.195022 -1.789905)
			(xy 381.110732 -1.805661) (xy 381.025349 -1.813573) (xy 380.939599 -1.813573) (xy 380.854216 -1.805661)
			(xy 380.769926 -1.789905) (xy 380.68745 -1.766438) (xy 380.607491 -1.735462) (xy 380.530731 -1.69724)
			(xy 380.457825 -1.652099) (xy 380.389396 -1.600423) (xy 380.326026 -1.542654) (xy 380.268257 -1.479284)
			(xy 380.216581 -1.410855) (xy 380.17144 -1.337949) (xy 380.133218 -1.261189) (xy 380.102242 -1.18123)
			(xy 380.078775 -1.098754) (xy 380.063019 -1.014464) (xy 380.055107 -0.929081) (xy 375.559841 -0.929081)
			(xy 375.551929 -1.014464) (xy 375.536173 -1.098754) (xy 375.512706 -1.18123) (xy 375.48173 -1.261189)
			(xy 375.443508 -1.337949) (xy 375.398367 -1.410855) (xy 375.346691 -1.479284) (xy 375.288922 -1.542654)
			(xy 375.225552 -1.600423) (xy 375.157123 -1.652099) (xy 375.084217 -1.69724) (xy 375.007457 -1.735462)
			(xy 374.927498 -1.766438) (xy 374.845022 -1.789905) (xy 374.760732 -1.805661) (xy 374.675349 -1.813573)
			(xy 374.589599 -1.813573) (xy 374.504216 -1.805661) (xy 374.419926 -1.789905) (xy 374.33745 -1.766438)
			(xy 374.257491 -1.735462) (xy 374.180731 -1.69724) (xy 374.107825 -1.652099) (xy 374.039396 -1.600423)
			(xy 373.976026 -1.542654) (xy 373.918257 -1.479284) (xy 373.866581 -1.410855) (xy 373.82144 -1.337949)
			(xy 373.783218 -1.261189) (xy 373.752242 -1.18123) (xy 373.728775 -1.098754) (xy 373.713019 -1.014464)
			(xy 373.705107 -0.929081) (xy 343.693001 -0.929081) (xy 343.685089 -1.014464) (xy 343.669333 -1.098754)
			(xy 343.645866 -1.18123) (xy 343.61489 -1.261189) (xy 343.576668 -1.337949) (xy 343.531527 -1.410855)
			(xy 343.479851 -1.479284) (xy 343.422082 -1.542654) (xy 343.358712 -1.600423) (xy 343.290283 -1.652099)
			(xy 343.217377 -1.69724) (xy 343.140617 -1.735462) (xy 343.060658 -1.766438) (xy 342.978182 -1.789905)
			(xy 342.893892 -1.805661) (xy 342.808509 -1.813573) (xy 342.722759 -1.813573) (xy 342.637376 -1.805661)
			(xy 342.553086 -1.789905) (xy 342.47061 -1.766438) (xy 342.390651 -1.735462) (xy 342.313891 -1.69724)
			(xy 342.240985 -1.652099) (xy 342.172556 -1.600423) (xy 342.109186 -1.542654) (xy 342.051417 -1.479284)
			(xy 341.999741 -1.410855) (xy 341.9546 -1.337949) (xy 341.916378 -1.261189) (xy 341.885402 -1.18123)
			(xy 341.861935 -1.098754) (xy 341.846179 -1.014464) (xy 341.838267 -0.929081) (xy 337.343001 -0.929081)
			(xy 337.335089 -1.014464) (xy 337.319333 -1.098754) (xy 337.295866 -1.18123) (xy 337.26489 -1.261189)
			(xy 337.226668 -1.337949) (xy 337.181527 -1.410855) (xy 337.129851 -1.479284) (xy 337.072082 -1.542654)
			(xy 337.008712 -1.600423) (xy 336.940283 -1.652099) (xy 336.867377 -1.69724) (xy 336.790617 -1.735462)
			(xy 336.710658 -1.766438) (xy 336.628182 -1.789905) (xy 336.543892 -1.805661) (xy 336.458509 -1.813573)
			(xy 336.372759 -1.813573) (xy 336.287376 -1.805661) (xy 336.203086 -1.789905) (xy 336.12061 -1.766438)
			(xy 336.040651 -1.735462) (xy 335.963891 -1.69724) (xy 335.890985 -1.652099) (xy 335.822556 -1.600423)
			(xy 335.759186 -1.542654) (xy 335.701417 -1.479284) (xy 335.649741 -1.410855) (xy 335.6046 -1.337949)
			(xy 335.566378 -1.261189) (xy 335.535402 -1.18123) (xy 335.511935 -1.098754) (xy 335.496179 -1.014464)
			(xy 335.488267 -0.929081) (xy 333.050655 -0.929081) (xy 333.042743 -1.014464) (xy 333.026987 -1.098754)
			(xy 333.00352 -1.18123) (xy 332.972544 -1.261189) (xy 332.934322 -1.337949) (xy 332.889181 -1.410855)
			(xy 332.837505 -1.479284) (xy 332.779736 -1.542654) (xy 332.716366 -1.600423) (xy 332.647937 -1.652099)
			(xy 332.575031 -1.69724) (xy 332.498271 -1.735462) (xy 332.418312 -1.766438) (xy 332.335836 -1.789905)
			(xy 332.251546 -1.805661) (xy 332.166163 -1.813573) (xy 332.080413 -1.813573) (xy 331.99503 -1.805661)
			(xy 331.91074 -1.789905) (xy 331.828264 -1.766438) (xy 331.748305 -1.735462) (xy 331.671545 -1.69724)
			(xy 331.598639 -1.652099) (xy 331.53021 -1.600423) (xy 331.46684 -1.542654) (xy 331.409071 -1.479284)
			(xy 331.357395 -1.410855) (xy 331.312254 -1.337949) (xy 331.274032 -1.261189) (xy 331.243056 -1.18123)
			(xy 331.219589 -1.098754) (xy 331.203833 -1.014464) (xy 331.195921 -0.929081) (xy 326.700655 -0.929081)
			(xy 326.692743 -1.014464) (xy 326.676987 -1.098754) (xy 326.65352 -1.18123) (xy 326.622544 -1.261189)
			(xy 326.584322 -1.337949) (xy 326.539181 -1.410855) (xy 326.487505 -1.479284) (xy 326.429736 -1.542654)
			(xy 326.366366 -1.600423) (xy 326.297937 -1.652099) (xy 326.225031 -1.69724) (xy 326.148271 -1.735462)
			(xy 326.068312 -1.766438) (xy 325.985836 -1.789905) (xy 325.901546 -1.805661) (xy 325.816163 -1.813573)
			(xy 325.730413 -1.813573) (xy 325.64503 -1.805661) (xy 325.56074 -1.789905) (xy 325.478264 -1.766438)
			(xy 325.398305 -1.735462) (xy 325.321545 -1.69724) (xy 325.248639 -1.652099) (xy 325.18021 -1.600423)
			(xy 325.11684 -1.542654) (xy 325.059071 -1.479284) (xy 325.007395 -1.410855) (xy 324.962254 -1.337949)
			(xy 324.924032 -1.261189) (xy 324.893056 -1.18123) (xy 324.869589 -1.098754) (xy 324.853833 -1.014464)
			(xy 324.845921 -0.929081) (xy 265.125975 -0.929081) (xy 265.118063 -1.014464) (xy 265.102307 -1.098754)
			(xy 265.07884 -1.18123) (xy 265.047864 -1.261189) (xy 265.009642 -1.337949) (xy 264.964501 -1.410855)
			(xy 264.912825 -1.479284) (xy 264.855056 -1.542654) (xy 264.791686 -1.600423) (xy 264.723257 -1.652099)
			(xy 264.650351 -1.69724) (xy 264.573591 -1.735462) (xy 264.493632 -1.766438) (xy 264.411156 -1.789905)
			(xy 264.326866 -1.805661) (xy 264.241483 -1.813573) (xy 264.155733 -1.813573) (xy 264.07035 -1.805661)
			(xy 263.98606 -1.789905) (xy 263.903584 -1.766438) (xy 263.823625 -1.735462) (xy 263.746865 -1.69724)
			(xy 263.673959 -1.652099) (xy 263.60553 -1.600423) (xy 263.54216 -1.542654) (xy 263.484391 -1.479284)
			(xy 263.432715 -1.410855) (xy 263.387574 -1.337949) (xy 263.349352 -1.261189) (xy 263.318376 -1.18123)
			(xy 263.294909 -1.098754) (xy 263.279153 -1.014464) (xy 263.271241 -0.929081) (xy 258.775975 -0.929081)
			(xy 258.768063 -1.014464) (xy 258.752307 -1.098754) (xy 258.72884 -1.18123) (xy 258.697864 -1.261189)
			(xy 258.659642 -1.337949) (xy 258.614501 -1.410855) (xy 258.562825 -1.479284) (xy 258.505056 -1.542654)
			(xy 258.441686 -1.600423) (xy 258.373257 -1.652099) (xy 258.300351 -1.69724) (xy 258.223591 -1.735462)
			(xy 258.143632 -1.766438) (xy 258.061156 -1.789905) (xy 257.976866 -1.805661) (xy 257.891483 -1.813573)
			(xy 257.805733 -1.813573) (xy 257.72035 -1.805661) (xy 257.63606 -1.789905) (xy 257.553584 -1.766438)
			(xy 257.473625 -1.735462) (xy 257.396865 -1.69724) (xy 257.323959 -1.652099) (xy 257.25553 -1.600423)
			(xy 257.19216 -1.542654) (xy 257.134391 -1.479284) (xy 257.082715 -1.410855) (xy 257.037574 -1.337949)
			(xy 256.999352 -1.261189) (xy 256.968376 -1.18123) (xy 256.944909 -1.098754) (xy 256.929153 -1.014464)
			(xy 256.921241 -0.929081) (xy 254.465119 -0.929081) (xy 254.465087 -0.931875) (xy 254.457175 -1.017258)
			(xy 254.441419 -1.101548) (xy 254.417952 -1.184024) (xy 254.386976 -1.263983) (xy 254.348754 -1.340743)
			(xy 254.303613 -1.413649) (xy 254.251937 -1.482078) (xy 254.194168 -1.545448) (xy 254.130798 -1.603217)
			(xy 254.062369 -1.654893) (xy 253.989463 -1.700034) (xy 253.912703 -1.738256) (xy 253.832744 -1.769232)
			(xy 253.750268 -1.792699) (xy 253.665978 -1.808455) (xy 253.580595 -1.816367) (xy 253.494845 -1.816367)
			(xy 253.409462 -1.808455) (xy 253.325172 -1.792699) (xy 253.242696 -1.769232) (xy 253.162737 -1.738256)
			(xy 253.085977 -1.700034) (xy 253.013071 -1.654893) (xy 252.944642 -1.603217) (xy 252.881272 -1.545448)
			(xy 252.823503 -1.482078) (xy 252.771827 -1.413649) (xy 252.726686 -1.340743) (xy 252.688464 -1.263983)
			(xy 252.657488 -1.184024) (xy 252.634021 -1.101548) (xy 252.618265 -1.017258) (xy 252.610353 -0.931875)
			(xy 248.115087 -0.931875) (xy 248.107175 -1.017258) (xy 248.091419 -1.101548) (xy 248.067952 -1.184024)
			(xy 248.036976 -1.263983) (xy 247.998754 -1.340743) (xy 247.953613 -1.413649) (xy 247.901937 -1.482078)
			(xy 247.844168 -1.545448) (xy 247.780798 -1.603217) (xy 247.712369 -1.654893) (xy 247.639463 -1.700034)
			(xy 247.562703 -1.738256) (xy 247.482744 -1.769232) (xy 247.400268 -1.792699) (xy 247.315978 -1.808455)
			(xy 247.230595 -1.816367) (xy 247.144845 -1.816367) (xy 247.059462 -1.808455) (xy 246.975172 -1.792699)
			(xy 246.892696 -1.769232) (xy 246.812737 -1.738256) (xy 246.735977 -1.700034) (xy 246.663071 -1.654893)
			(xy 246.594642 -1.603217) (xy 246.531272 -1.545448) (xy 246.473503 -1.482078) (xy 246.421827 -1.413649)
			(xy 246.376686 -1.340743) (xy 246.338464 -1.263983) (xy 246.307488 -1.184024) (xy 246.284021 -1.101548)
			(xy 246.268265 -1.017258) (xy 246.260353 -0.931875) (xy 216.248247 -0.931875) (xy 216.240335 -1.017258)
			(xy 216.224579 -1.101548) (xy 216.201112 -1.184024) (xy 216.170136 -1.263983) (xy 216.131914 -1.340743)
			(xy 216.086773 -1.413649) (xy 216.035097 -1.482078) (xy 215.977328 -1.545448) (xy 215.913958 -1.603217)
			(xy 215.845529 -1.654893) (xy 215.772623 -1.700034) (xy 215.695863 -1.738256) (xy 215.615904 -1.769232)
			(xy 215.533428 -1.792699) (xy 215.449138 -1.808455) (xy 215.363755 -1.816367) (xy 215.278005 -1.816367)
			(xy 215.192622 -1.808455) (xy 215.108332 -1.792699) (xy 215.025856 -1.769232) (xy 214.945897 -1.738256)
			(xy 214.869137 -1.700034) (xy 214.796231 -1.654893) (xy 214.727802 -1.603217) (xy 214.664432 -1.545448)
			(xy 214.606663 -1.482078) (xy 214.554987 -1.413649) (xy 214.509846 -1.340743) (xy 214.471624 -1.263983)
			(xy 214.440648 -1.184024) (xy 214.417181 -1.101548) (xy 214.401425 -1.017258) (xy 214.393513 -0.931875)
			(xy 209.898247 -0.931875) (xy 209.890335 -1.017258) (xy 209.874579 -1.101548) (xy 209.851112 -1.184024)
			(xy 209.820136 -1.263983) (xy 209.781914 -1.340743) (xy 209.736773 -1.413649) (xy 209.685097 -1.482078)
			(xy 209.627328 -1.545448) (xy 209.563958 -1.603217) (xy 209.495529 -1.654893) (xy 209.422623 -1.700034)
			(xy 209.345863 -1.738256) (xy 209.265904 -1.769232) (xy 209.183428 -1.792699) (xy 209.099138 -1.808455)
			(xy 209.013755 -1.816367) (xy 208.928005 -1.816367) (xy 208.842622 -1.808455) (xy 208.758332 -1.792699)
			(xy 208.675856 -1.769232) (xy 208.595897 -1.738256) (xy 208.519137 -1.700034) (xy 208.446231 -1.654893)
			(xy 208.377802 -1.603217) (xy 208.314432 -1.545448) (xy 208.256663 -1.482078) (xy 208.204987 -1.413649)
			(xy 208.159846 -1.340743) (xy 208.121624 -1.263983) (xy 208.090648 -1.184024) (xy 208.067181 -1.101548)
			(xy 208.051425 -1.017258) (xy 208.043513 -0.931875) (xy 84.20989 -0.931875) (xy 84.20989 -7.78002)
			(xy 84.210412 -7.835827) (xy 84.218755 -7.947128) (xy 84.235391 -8.057495) (xy 84.260229 -8.16631)
			(xy 84.293128 -8.272964) (xy 84.333906 -8.376862) (xy 84.382334 -8.477422) (xy 84.438141 -8.574082)
			(xy 84.501016 -8.666301) (xy 84.570606 -8.753563) (xy 84.646523 -8.835382) (xy 84.728341 -8.911298)
			(xy 84.815604 -8.980888) (xy 84.907824 -9.043762) (xy 85.004484 -9.099569) (xy 85.105044 -9.147996)
			(xy 85.208942 -9.188774) (xy 85.315596 -9.221673) (xy 85.424411 -9.24651) (xy 85.534778 -9.263146)
			(xy 85.646079 -9.271488) (xy 85.701886 -9.272016) (xy 122.102118 -9.272016) (xy 122.157925 -9.271494)
			(xy 122.269226 -9.263152) (xy 122.379593 -9.246515) (xy 122.488409 -9.221678) (xy 122.595063 -9.188778)
			(xy 122.698961 -9.148001) (xy 122.799522 -9.099573) (xy 122.896182 -9.043766) (xy 122.988401 -8.980891)
			(xy 123.075664 -8.911301) (xy 123.157483 -8.835384) (xy 123.2334 -8.753566) (xy 123.30299 -8.666303)
			(xy 123.365865 -8.574084) (xy 123.421672 -8.477423) (xy 123.4701 -8.376863) (xy 123.510878 -8.272965)
			(xy 123.543777 -8.16631) (xy 123.568615 -8.057495) (xy 123.585251 -7.947128) (xy 123.593594 -7.835827)
			(xy 123.594114 -7.78002) (xy 123.594114 -4.2799) (xy 123.594598 -4.209546) (xy 123.602488 -4.06906)
			(xy 123.618242 -3.929237) (xy 123.641812 -3.790517) (xy 123.673122 -3.653337) (xy 123.712075 -3.518129)
			(xy 123.758548 -3.385317) (xy 123.812395 -3.25532) (xy 123.873446 -3.128547) (xy 123.941509 -3.005396)
			(xy 124.01637 -2.886255) (xy 124.097794 -2.7715) (xy 124.185524 -2.66149) (xy 124.279284 -2.556573)
			(xy 124.37878 -2.457077) (xy 124.483698 -2.363317) (xy 124.593708 -2.275588) (xy 124.708464 -2.194165)
			(xy 124.827605 -2.119304) (xy 124.950755 -2.051241) (xy 125.077529 -1.990191) (xy 125.207526 -1.936345)
			(xy 125.340338 -1.889872) (xy 125.475547 -1.85092) (xy 125.612727 -1.81961) (xy 125.751447 -1.796041)
			(xy 125.89127 -1.780287) (xy 126.031756 -1.772398) (xy 126.10211 -1.771904) (xy 194.701922 -1.771904)
			(xy 194.772275 -1.772398) (xy 194.912761 -1.780289) (xy 195.052582 -1.796044) (xy 195.191301 -1.819614)
			(xy 195.32848 -1.850925) (xy 195.463687 -1.889879) (xy 195.596497 -1.936352) (xy 195.726493 -1.990199)
			(xy 195.853265 -2.05125) (xy 195.976414 -2.119314) (xy 196.095554 -2.194175) (xy 196.210308 -2.275598)
			(xy 196.320316 -2.363328) (xy 196.425233 -2.457088) (xy 196.524727 -2.556583) (xy 196.618486 -2.6615)
			(xy 196.706215 -2.77151) (xy 196.787637 -2.886265) (xy 196.862497 -3.005405) (xy 196.93056 -3.128555)
			(xy 196.99161 -3.255327) (xy 197.045455 -3.385323) (xy 197.075741 -3.471875) (xy 208.043513 -3.471875)
			(xy 208.043513 -3.386125) (xy 208.051425 -3.300742) (xy 208.067181 -3.216452) (xy 208.090648 -3.133976)
			(xy 208.121624 -3.054017) (xy 208.159846 -2.977257) (xy 208.204987 -2.904351) (xy 208.256663 -2.835922)
			(xy 208.314432 -2.772552) (xy 208.377802 -2.714783) (xy 208.446231 -2.663107) (xy 208.519137 -2.617966)
			(xy 208.595897 -2.579744) (xy 208.675856 -2.548768) (xy 208.758332 -2.525301) (xy 208.842622 -2.509545)
			(xy 208.928005 -2.501633) (xy 209.013755 -2.501633) (xy 209.099138 -2.509545) (xy 209.183428 -2.525301)
			(xy 209.265904 -2.548768) (xy 209.345863 -2.579744) (xy 209.368066 -2.5908) (xy 212.978492 -2.5908)
			(xy 212.978492 -1.7272) (xy 212.978978 -1.699931) (xy 212.98674 -1.645947) (xy 213.002105 -1.593617)
			(xy 213.024762 -1.544007) (xy 213.054248 -1.498126) (xy 213.089963 -1.456909) (xy 213.13118 -1.421194)
			(xy 213.177061 -1.391708) (xy 213.226671 -1.369051) (xy 213.279001 -1.353686) (xy 213.332985 -1.345924)
			(xy 213.387523 -1.345924) (xy 213.441507 -1.353686) (xy 213.493837 -1.369051) (xy 213.543447 -1.391708)
			(xy 213.589328 -1.421194) (xy 213.630545 -1.456909) (xy 213.66626 -1.498126) (xy 213.695746 -1.544007)
			(xy 213.718403 -1.593617) (xy 213.733768 -1.645947) (xy 213.74153 -1.699931) (xy 213.742016 -1.7272)
			(xy 213.742016 -2.5908) (xy 213.74153 -2.618069) (xy 213.733768 -2.672053) (xy 213.718403 -2.724383)
			(xy 213.695746 -2.773993) (xy 213.66626 -2.819874) (xy 213.630545 -2.861091) (xy 213.589328 -2.896806)
			(xy 213.543447 -2.926292) (xy 213.493837 -2.948949) (xy 213.441507 -2.964314) (xy 213.387523 -2.972076)
			(xy 213.332985 -2.972076) (xy 213.279001 -2.964314) (xy 213.226671 -2.948949) (xy 213.177061 -2.926292)
			(xy 213.13118 -2.896806) (xy 213.089963 -2.861091) (xy 213.054248 -2.819874) (xy 213.024762 -2.773993)
			(xy 213.002105 -2.724383) (xy 212.98674 -2.672053) (xy 212.978978 -2.618069) (xy 212.978492 -2.5908)
			(xy 209.368066 -2.5908) (xy 209.422623 -2.617966) (xy 209.495529 -2.663107) (xy 209.563958 -2.714783)
			(xy 209.627328 -2.772552) (xy 209.685097 -2.835922) (xy 209.736773 -2.904351) (xy 209.781914 -2.977257)
			(xy 209.820136 -3.054017) (xy 209.851112 -3.133976) (xy 209.874579 -3.216452) (xy 209.890335 -3.300742)
			(xy 209.898247 -3.386125) (xy 209.898742 -3.429) (xy 209.898247 -3.471875) (xy 214.393513 -3.471875)
			(xy 214.393513 -3.386125) (xy 214.401425 -3.300742) (xy 214.417181 -3.216452) (xy 214.440648 -3.133976)
			(xy 214.471624 -3.054017) (xy 214.509846 -2.977257) (xy 214.554987 -2.904351) (xy 214.606663 -2.835922)
			(xy 214.664432 -2.772552) (xy 214.727802 -2.714783) (xy 214.796231 -2.663107) (xy 214.869137 -2.617966)
			(xy 214.945897 -2.579744) (xy 215.025856 -2.548768) (xy 215.108332 -2.525301) (xy 215.192622 -2.509545)
			(xy 215.278005 -2.501633) (xy 215.363755 -2.501633) (xy 215.449138 -2.509545) (xy 215.533428 -2.525301)
			(xy 215.615904 -2.548768) (xy 215.695863 -2.579744) (xy 215.772623 -2.617966) (xy 215.845529 -2.663107)
			(xy 215.913958 -2.714783) (xy 215.977328 -2.772552) (xy 216.035097 -2.835922) (xy 216.086773 -2.904351)
			(xy 216.131914 -2.977257) (xy 216.170136 -3.054017) (xy 216.201112 -3.133976) (xy 216.224579 -3.216452)
			(xy 216.240335 -3.300742) (xy 216.248247 -3.386125) (xy 216.248742 -3.429) (xy 216.248247 -3.471875)
			(xy 246.260353 -3.471875) (xy 246.260353 -3.386125) (xy 246.268265 -3.300742) (xy 246.284021 -3.216452)
			(xy 246.307488 -3.133976) (xy 246.338464 -3.054017) (xy 246.376686 -2.977257) (xy 246.421827 -2.904351)
			(xy 246.473503 -2.835922) (xy 246.531272 -2.772552) (xy 246.594642 -2.714783) (xy 246.663071 -2.663107)
			(xy 246.735977 -2.617966) (xy 246.812737 -2.579744) (xy 246.892696 -2.548768) (xy 246.975172 -2.525301)
			(xy 247.059462 -2.509545) (xy 247.144845 -2.501633) (xy 247.230595 -2.501633) (xy 247.315978 -2.509545)
			(xy 247.400268 -2.525301) (xy 247.482744 -2.548768) (xy 247.562703 -2.579744) (xy 247.584906 -2.5908)
			(xy 248.766584 -2.5908) (xy 248.766584 -1.7272) (xy 248.76707 -1.699931) (xy 248.774832 -1.645947)
			(xy 248.790197 -1.593617) (xy 248.812854 -1.544007) (xy 248.84234 -1.498126) (xy 248.878055 -1.456909)
			(xy 248.919272 -1.421194) (xy 248.965153 -1.391708) (xy 249.014763 -1.369051) (xy 249.067093 -1.353686)
			(xy 249.121077 -1.345924) (xy 249.175615 -1.345924) (xy 249.229599 -1.353686) (xy 249.281929 -1.369051)
			(xy 249.331539 -1.391708) (xy 249.37742 -1.421194) (xy 249.418637 -1.456909) (xy 249.454352 -1.498126)
			(xy 249.483838 -1.544007) (xy 249.506495 -1.593617) (xy 249.52186 -1.645947) (xy 249.529622 -1.699931)
			(xy 249.530108 -1.7272) (xy 249.530108 -2.5908) (xy 249.529622 -2.618069) (xy 249.52186 -2.672053)
			(xy 249.506495 -2.724383) (xy 249.483838 -2.773993) (xy 249.454352 -2.819874) (xy 249.418637 -2.861091)
			(xy 249.37742 -2.896806) (xy 249.331539 -2.926292) (xy 249.281929 -2.948949) (xy 249.229599 -2.964314)
			(xy 249.175615 -2.972076) (xy 249.121077 -2.972076) (xy 249.067093 -2.964314) (xy 249.014763 -2.948949)
			(xy 248.965153 -2.926292) (xy 248.919272 -2.896806) (xy 248.878055 -2.861091) (xy 248.84234 -2.819874)
			(xy 248.812854 -2.773993) (xy 248.790197 -2.724383) (xy 248.774832 -2.672053) (xy 248.76707 -2.618069)
			(xy 248.766584 -2.5908) (xy 247.584906 -2.5908) (xy 247.639463 -2.617966) (xy 247.712369 -2.663107)
			(xy 247.780798 -2.714783) (xy 247.844168 -2.772552) (xy 247.901937 -2.835922) (xy 247.953613 -2.904351)
			(xy 247.998754 -2.977257) (xy 248.036976 -3.054017) (xy 248.067952 -3.133976) (xy 248.091419 -3.216452)
			(xy 248.107175 -3.300742) (xy 248.115087 -3.386125) (xy 248.115582 -3.429) (xy 248.115087 -3.471875)
			(xy 252.610353 -3.471875) (xy 252.610353 -3.386125) (xy 252.618265 -3.300742) (xy 252.634021 -3.216452)
			(xy 252.657488 -3.133976) (xy 252.688464 -3.054017) (xy 252.726686 -2.977257) (xy 252.771827 -2.904351)
			(xy 252.823503 -2.835922) (xy 252.881272 -2.772552) (xy 252.944642 -2.714783) (xy 253.013071 -2.663107)
			(xy 253.085977 -2.617966) (xy 253.162737 -2.579744) (xy 253.242696 -2.548768) (xy 253.325172 -2.525301)
			(xy 253.409462 -2.509545) (xy 253.494845 -2.501633) (xy 253.580595 -2.501633) (xy 253.665978 -2.509545)
			(xy 253.750268 -2.525301) (xy 253.832744 -2.548768) (xy 253.912703 -2.579744) (xy 253.989463 -2.617966)
			(xy 254.062369 -2.663107) (xy 254.130798 -2.714783) (xy 254.194168 -2.772552) (xy 254.251937 -2.835922)
			(xy 254.303613 -2.904351) (xy 254.348754 -2.977257) (xy 254.386976 -3.054017) (xy 254.417952 -3.133976)
			(xy 254.441419 -3.216452) (xy 254.457175 -3.300742) (xy 254.465087 -3.386125) (xy 254.465582 -3.429)
			(xy 254.465119 -3.469081) (xy 256.921241 -3.469081) (xy 256.921241 -3.383331) (xy 256.929153 -3.297948)
			(xy 256.944909 -3.213658) (xy 256.968376 -3.131182) (xy 256.999352 -3.051223) (xy 257.037574 -2.974463)
			(xy 257.082715 -2.901557) (xy 257.134391 -2.833128) (xy 257.19216 -2.769758) (xy 257.25553 -2.711989)
			(xy 257.323959 -2.660313) (xy 257.396865 -2.615172) (xy 257.473625 -2.57695) (xy 257.553584 -2.545974)
			(xy 257.63606 -2.522507) (xy 257.72035 -2.506751) (xy 257.805733 -2.498839) (xy 257.891483 -2.498839)
			(xy 257.976866 -2.506751) (xy 258.061156 -2.522507) (xy 258.143632 -2.545974) (xy 258.223591 -2.57695)
			(xy 258.300351 -2.615172) (xy 258.373257 -2.660313) (xy 258.441686 -2.711989) (xy 258.505056 -2.769758)
			(xy 258.562825 -2.833128) (xy 258.614501 -2.901557) (xy 258.659642 -2.974463) (xy 258.697864 -3.051223)
			(xy 258.72884 -3.131182) (xy 258.752307 -3.213658) (xy 258.768063 -3.297948) (xy 258.775975 -3.383331)
			(xy 258.77647 -3.426206) (xy 258.775975 -3.469081) (xy 263.271241 -3.469081) (xy 263.271241 -3.383331)
			(xy 263.279153 -3.297948) (xy 263.294909 -3.213658) (xy 263.318376 -3.131182) (xy 263.349352 -3.051223)
			(xy 263.387574 -2.974463) (xy 263.432715 -2.901557) (xy 263.484391 -2.833128) (xy 263.54216 -2.769758)
			(xy 263.60553 -2.711989) (xy 263.673959 -2.660313) (xy 263.746865 -2.615172) (xy 263.823625 -2.57695)
			(xy 263.903584 -2.545974) (xy 263.98606 -2.522507) (xy 264.07035 -2.506751) (xy 264.155733 -2.498839)
			(xy 264.241483 -2.498839) (xy 264.326866 -2.506751) (xy 264.411156 -2.522507) (xy 264.493632 -2.545974)
			(xy 264.573591 -2.57695) (xy 264.650351 -2.615172) (xy 264.723257 -2.660313) (xy 264.791686 -2.711989)
			(xy 264.855056 -2.769758) (xy 264.912825 -2.833128) (xy 264.964501 -2.901557) (xy 265.009642 -2.974463)
			(xy 265.047864 -3.051223) (xy 265.07884 -3.131182) (xy 265.102307 -3.213658) (xy 265.118063 -3.297948)
			(xy 265.125975 -3.383331) (xy 265.12647 -3.426206) (xy 265.125975 -3.469081) (xy 324.845921 -3.469081)
			(xy 324.845921 -3.383331) (xy 324.853833 -3.297948) (xy 324.869589 -3.213658) (xy 324.893056 -3.131182)
			(xy 324.924032 -3.051223) (xy 324.962254 -2.974463) (xy 325.007395 -2.901557) (xy 325.059071 -2.833128)
			(xy 325.11684 -2.769758) (xy 325.18021 -2.711989) (xy 325.248639 -2.660313) (xy 325.321545 -2.615172)
			(xy 325.398305 -2.57695) (xy 325.478264 -2.545974) (xy 325.56074 -2.522507) (xy 325.64503 -2.506751)
			(xy 325.730413 -2.498839) (xy 325.816163 -2.498839) (xy 325.901546 -2.506751) (xy 325.985836 -2.522507)
			(xy 326.068312 -2.545974) (xy 326.148271 -2.57695) (xy 326.225031 -2.615172) (xy 326.297937 -2.660313)
			(xy 326.366366 -2.711989) (xy 326.429736 -2.769758) (xy 326.487505 -2.833128) (xy 326.539181 -2.901557)
			(xy 326.584322 -2.974463) (xy 326.622544 -3.051223) (xy 326.65352 -3.131182) (xy 326.676987 -3.213658)
			(xy 326.692743 -3.297948) (xy 326.700655 -3.383331) (xy 326.70115 -3.426206) (xy 326.700655 -3.469081)
			(xy 331.195921 -3.469081) (xy 331.195921 -3.383331) (xy 331.203833 -3.297948) (xy 331.219589 -3.213658)
			(xy 331.243056 -3.131182) (xy 331.274032 -3.051223) (xy 331.312254 -2.974463) (xy 331.357395 -2.901557)
			(xy 331.409071 -2.833128) (xy 331.46684 -2.769758) (xy 331.53021 -2.711989) (xy 331.598639 -2.660313)
			(xy 331.671545 -2.615172) (xy 331.748305 -2.57695) (xy 331.828264 -2.545974) (xy 331.91074 -2.522507)
			(xy 331.99503 -2.506751) (xy 332.080413 -2.498839) (xy 332.166163 -2.498839) (xy 332.251546 -2.506751)
			(xy 332.335836 -2.522507) (xy 332.418312 -2.545974) (xy 332.498271 -2.57695) (xy 332.575031 -2.615172)
			(xy 332.647937 -2.660313) (xy 332.716366 -2.711989) (xy 332.779736 -2.769758) (xy 332.837505 -2.833128)
			(xy 332.889181 -2.901557) (xy 332.934322 -2.974463) (xy 332.972544 -3.051223) (xy 333.00352 -3.131182)
			(xy 333.026987 -3.213658) (xy 333.042743 -3.297948) (xy 333.050655 -3.383331) (xy 333.05115 -3.426206)
			(xy 333.050655 -3.469081) (xy 335.488267 -3.469081) (xy 335.488267 -3.383331) (xy 335.496179 -3.297948)
			(xy 335.511935 -3.213658) (xy 335.535402 -3.131182) (xy 335.566378 -3.051223) (xy 335.6046 -2.974463)
			(xy 335.649741 -2.901557) (xy 335.701417 -2.833128) (xy 335.759186 -2.769758) (xy 335.822556 -2.711989)
			(xy 335.890985 -2.660313) (xy 335.963891 -2.615172) (xy 336.040651 -2.57695) (xy 336.12061 -2.545974)
			(xy 336.203086 -2.522507) (xy 336.287376 -2.506751) (xy 336.372759 -2.498839) (xy 336.458509 -2.498839)
			(xy 336.543892 -2.506751) (xy 336.628182 -2.522507) (xy 336.710658 -2.545974) (xy 336.790617 -2.57695)
			(xy 336.867377 -2.615172) (xy 336.940283 -2.660313) (xy 337.008712 -2.711989) (xy 337.072082 -2.769758)
			(xy 337.129851 -2.833128) (xy 337.181527 -2.901557) (xy 337.226668 -2.974463) (xy 337.26489 -3.051223)
			(xy 337.295866 -3.131182) (xy 337.319333 -3.213658) (xy 337.335089 -3.297948) (xy 337.343001 -3.383331)
			(xy 337.343496 -3.426206) (xy 337.343001 -3.469081) (xy 341.838267 -3.469081) (xy 341.838267 -3.383331)
			(xy 341.846179 -3.297948) (xy 341.861935 -3.213658) (xy 341.885402 -3.131182) (xy 341.916378 -3.051223)
			(xy 341.9546 -2.974463) (xy 341.999741 -2.901557) (xy 342.051417 -2.833128) (xy 342.109186 -2.769758)
			(xy 342.172556 -2.711989) (xy 342.240985 -2.660313) (xy 342.313891 -2.615172) (xy 342.390651 -2.57695)
			(xy 342.47061 -2.545974) (xy 342.553086 -2.522507) (xy 342.637376 -2.506751) (xy 342.722759 -2.498839)
			(xy 342.808509 -2.498839) (xy 342.893892 -2.506751) (xy 342.978182 -2.522507) (xy 343.060658 -2.545974)
			(xy 343.140617 -2.57695) (xy 343.217377 -2.615172) (xy 343.290283 -2.660313) (xy 343.358712 -2.711989)
			(xy 343.422082 -2.769758) (xy 343.479851 -2.833128) (xy 343.531527 -2.901557) (xy 343.576668 -2.974463)
			(xy 343.61489 -3.051223) (xy 343.645866 -3.131182) (xy 343.669333 -3.213658) (xy 343.685089 -3.297948)
			(xy 343.693001 -3.383331) (xy 343.693496 -3.426206) (xy 343.693001 -3.469081) (xy 373.705107 -3.469081)
			(xy 373.705107 -3.383331) (xy 373.713019 -3.297948) (xy 373.728775 -3.213658) (xy 373.752242 -3.131182)
			(xy 373.783218 -3.051223) (xy 373.82144 -2.974463) (xy 373.866581 -2.901557) (xy 373.918257 -2.833128)
			(xy 373.976026 -2.769758) (xy 374.039396 -2.711989) (xy 374.107825 -2.660313) (xy 374.180731 -2.615172)
			(xy 374.257491 -2.57695) (xy 374.33745 -2.545974) (xy 374.419926 -2.522507) (xy 374.504216 -2.506751)
			(xy 374.589599 -2.498839) (xy 374.675349 -2.498839) (xy 374.760732 -2.506751) (xy 374.845022 -2.522507)
			(xy 374.927498 -2.545974) (xy 375.007457 -2.57695) (xy 375.084217 -2.615172) (xy 375.157123 -2.660313)
			(xy 375.225552 -2.711989) (xy 375.288922 -2.769758) (xy 375.346691 -2.833128) (xy 375.398367 -2.901557)
			(xy 375.443508 -2.974463) (xy 375.48173 -3.051223) (xy 375.512706 -3.131182) (xy 375.536173 -3.213658)
			(xy 375.551929 -3.297948) (xy 375.559841 -3.383331) (xy 375.560336 -3.426206) (xy 375.559841 -3.469081)
			(xy 380.055107 -3.469081) (xy 380.055107 -3.383331) (xy 380.063019 -3.297948) (xy 380.078775 -3.213658)
			(xy 380.102242 -3.131182) (xy 380.133218 -3.051223) (xy 380.17144 -2.974463) (xy 380.216581 -2.901557)
			(xy 380.268257 -2.833128) (xy 380.326026 -2.769758) (xy 380.389396 -2.711989) (xy 380.457825 -2.660313)
			(xy 380.530731 -2.615172) (xy 380.607491 -2.57695) (xy 380.68745 -2.545974) (xy 380.769926 -2.522507)
			(xy 380.854216 -2.506751) (xy 380.939599 -2.498839) (xy 381.025349 -2.498839) (xy 381.110732 -2.506751)
			(xy 381.195022 -2.522507) (xy 381.277498 -2.545974) (xy 381.357457 -2.57695) (xy 381.434217 -2.615172)
			(xy 381.507123 -2.660313) (xy 381.575552 -2.711989) (xy 381.638922 -2.769758) (xy 381.696691 -2.833128)
			(xy 381.748367 -2.901557) (xy 381.793508 -2.974463) (xy 381.83173 -3.051223) (xy 381.862706 -3.131182)
			(xy 381.886173 -3.213658) (xy 381.901929 -3.297948) (xy 381.909841 -3.383331) (xy 381.910336 -3.426206)
			(xy 381.909841 -3.469081) (xy 381.901929 -3.554464) (xy 381.886173 -3.638754) (xy 381.862706 -3.72123)
			(xy 381.83173 -3.801189) (xy 381.793508 -3.877949) (xy 381.748367 -3.950855) (xy 381.696691 -4.019284)
			(xy 381.638922 -4.082654) (xy 381.575552 -4.140423) (xy 381.507123 -4.192099) (xy 381.434217 -4.23724)
			(xy 381.357457 -4.275462) (xy 381.277498 -4.306438) (xy 381.195022 -4.329905) (xy 381.110732 -4.345661)
			(xy 381.025349 -4.353573) (xy 380.939599 -4.353573) (xy 380.854216 -4.345661) (xy 380.769926 -4.329905)
			(xy 380.68745 -4.306438) (xy 380.607491 -4.275462) (xy 380.530731 -4.23724) (xy 380.457825 -4.192099)
			(xy 380.389396 -4.140423) (xy 380.326026 -4.082654) (xy 380.268257 -4.019284) (xy 380.216581 -3.950855)
			(xy 380.17144 -3.877949) (xy 380.133218 -3.801189) (xy 380.102242 -3.72123) (xy 380.078775 -3.638754)
			(xy 380.063019 -3.554464) (xy 380.055107 -3.469081) (xy 375.559841 -3.469081) (xy 375.551929 -3.554464)
			(xy 375.536173 -3.638754) (xy 375.512706 -3.72123) (xy 375.48173 -3.801189) (xy 375.443508 -3.877949)
			(xy 375.398367 -3.950855) (xy 375.346691 -4.019284) (xy 375.288922 -4.082654) (xy 375.225552 -4.140423)
			(xy 375.157123 -4.192099) (xy 375.084217 -4.23724) (xy 375.007457 -4.275462) (xy 374.927498 -4.306438)
			(xy 374.845022 -4.329905) (xy 374.760732 -4.345661) (xy 374.675349 -4.353573) (xy 374.589599 -4.353573)
			(xy 374.504216 -4.345661) (xy 374.419926 -4.329905) (xy 374.33745 -4.306438) (xy 374.257491 -4.275462)
			(xy 374.180731 -4.23724) (xy 374.107825 -4.192099) (xy 374.039396 -4.140423) (xy 373.976026 -4.082654)
			(xy 373.918257 -4.019284) (xy 373.866581 -3.950855) (xy 373.82144 -3.877949) (xy 373.783218 -3.801189)
			(xy 373.752242 -3.72123) (xy 373.728775 -3.638754) (xy 373.713019 -3.554464) (xy 373.705107 -3.469081)
			(xy 343.693001 -3.469081) (xy 343.685089 -3.554464) (xy 343.669333 -3.638754) (xy 343.645866 -3.72123)
			(xy 343.61489 -3.801189) (xy 343.576668 -3.877949) (xy 343.531527 -3.950855) (xy 343.479851 -4.019284)
			(xy 343.422082 -4.082654) (xy 343.358712 -4.140423) (xy 343.290283 -4.192099) (xy 343.217377 -4.23724)
			(xy 343.140617 -4.275462) (xy 343.060658 -4.306438) (xy 342.978182 -4.329905) (xy 342.893892 -4.345661)
			(xy 342.808509 -4.353573) (xy 342.722759 -4.353573) (xy 342.637376 -4.345661) (xy 342.553086 -4.329905)
			(xy 342.47061 -4.306438) (xy 342.390651 -4.275462) (xy 342.313891 -4.23724) (xy 342.240985 -4.192099)
			(xy 342.172556 -4.140423) (xy 342.109186 -4.082654) (xy 342.051417 -4.019284) (xy 341.999741 -3.950855)
			(xy 341.9546 -3.877949) (xy 341.916378 -3.801189) (xy 341.885402 -3.72123) (xy 341.861935 -3.638754)
			(xy 341.846179 -3.554464) (xy 341.838267 -3.469081) (xy 337.343001 -3.469081) (xy 337.335089 -3.554464)
			(xy 337.319333 -3.638754) (xy 337.295866 -3.72123) (xy 337.26489 -3.801189) (xy 337.226668 -3.877949)
			(xy 337.181527 -3.950855) (xy 337.129851 -4.019284) (xy 337.072082 -4.082654) (xy 337.008712 -4.140423)
			(xy 336.940283 -4.192099) (xy 336.867377 -4.23724) (xy 336.790617 -4.275462) (xy 336.710658 -4.306438)
			(xy 336.628182 -4.329905) (xy 336.543892 -4.345661) (xy 336.458509 -4.353573) (xy 336.372759 -4.353573)
			(xy 336.287376 -4.345661) (xy 336.203086 -4.329905) (xy 336.12061 -4.306438) (xy 336.040651 -4.275462)
			(xy 335.963891 -4.23724) (xy 335.890985 -4.192099) (xy 335.822556 -4.140423) (xy 335.759186 -4.082654)
			(xy 335.701417 -4.019284) (xy 335.649741 -3.950855) (xy 335.6046 -3.877949) (xy 335.566378 -3.801189)
			(xy 335.535402 -3.72123) (xy 335.511935 -3.638754) (xy 335.496179 -3.554464) (xy 335.488267 -3.469081)
			(xy 333.050655 -3.469081) (xy 333.042743 -3.554464) (xy 333.026987 -3.638754) (xy 333.00352 -3.72123)
			(xy 332.972544 -3.801189) (xy 332.934322 -3.877949) (xy 332.889181 -3.950855) (xy 332.837505 -4.019284)
			(xy 332.779736 -4.082654) (xy 332.716366 -4.140423) (xy 332.647937 -4.192099) (xy 332.575031 -4.23724)
			(xy 332.498271 -4.275462) (xy 332.418312 -4.306438) (xy 332.335836 -4.329905) (xy 332.251546 -4.345661)
			(xy 332.166163 -4.353573) (xy 332.080413 -4.353573) (xy 331.99503 -4.345661) (xy 331.91074 -4.329905)
			(xy 331.828264 -4.306438) (xy 331.748305 -4.275462) (xy 331.671545 -4.23724) (xy 331.598639 -4.192099)
			(xy 331.53021 -4.140423) (xy 331.46684 -4.082654) (xy 331.409071 -4.019284) (xy 331.357395 -3.950855)
			(xy 331.312254 -3.877949) (xy 331.274032 -3.801189) (xy 331.243056 -3.72123) (xy 331.219589 -3.638754)
			(xy 331.203833 -3.554464) (xy 331.195921 -3.469081) (xy 326.700655 -3.469081) (xy 326.692743 -3.554464)
			(xy 326.676987 -3.638754) (xy 326.65352 -3.72123) (xy 326.622544 -3.801189) (xy 326.584322 -3.877949)
			(xy 326.539181 -3.950855) (xy 326.487505 -4.019284) (xy 326.429736 -4.082654) (xy 326.366366 -4.140423)
			(xy 326.297937 -4.192099) (xy 326.225031 -4.23724) (xy 326.148271 -4.275462) (xy 326.068312 -4.306438)
			(xy 325.985836 -4.329905) (xy 325.901546 -4.345661) (xy 325.816163 -4.353573) (xy 325.730413 -4.353573)
			(xy 325.64503 -4.345661) (xy 325.56074 -4.329905) (xy 325.478264 -4.306438) (xy 325.398305 -4.275462)
			(xy 325.321545 -4.23724) (xy 325.248639 -4.192099) (xy 325.18021 -4.140423) (xy 325.11684 -4.082654)
			(xy 325.059071 -4.019284) (xy 325.007395 -3.950855) (xy 324.962254 -3.877949) (xy 324.924032 -3.801189)
			(xy 324.893056 -3.72123) (xy 324.869589 -3.638754) (xy 324.853833 -3.554464) (xy 324.845921 -3.469081)
			(xy 265.125975 -3.469081) (xy 265.118063 -3.554464) (xy 265.102307 -3.638754) (xy 265.07884 -3.72123)
			(xy 265.047864 -3.801189) (xy 265.009642 -3.877949) (xy 264.964501 -3.950855) (xy 264.912825 -4.019284)
			(xy 264.855056 -4.082654) (xy 264.791686 -4.140423) (xy 264.723257 -4.192099) (xy 264.650351 -4.23724)
			(xy 264.573591 -4.275462) (xy 264.493632 -4.306438) (xy 264.411156 -4.329905) (xy 264.326866 -4.345661)
			(xy 264.241483 -4.353573) (xy 264.155733 -4.353573) (xy 264.07035 -4.345661) (xy 263.98606 -4.329905)
			(xy 263.903584 -4.306438) (xy 263.823625 -4.275462) (xy 263.746865 -4.23724) (xy 263.673959 -4.192099)
			(xy 263.60553 -4.140423) (xy 263.54216 -4.082654) (xy 263.484391 -4.019284) (xy 263.432715 -3.950855)
			(xy 263.387574 -3.877949) (xy 263.349352 -3.801189) (xy 263.318376 -3.72123) (xy 263.294909 -3.638754)
			(xy 263.279153 -3.554464) (xy 263.271241 -3.469081) (xy 258.775975 -3.469081) (xy 258.768063 -3.554464)
			(xy 258.752307 -3.638754) (xy 258.72884 -3.72123) (xy 258.697864 -3.801189) (xy 258.659642 -3.877949)
			(xy 258.614501 -3.950855) (xy 258.562825 -4.019284) (xy 258.505056 -4.082654) (xy 258.441686 -4.140423)
			(xy 258.373257 -4.192099) (xy 258.300351 -4.23724) (xy 258.223591 -4.275462) (xy 258.143632 -4.306438)
			(xy 258.061156 -4.329905) (xy 257.976866 -4.345661) (xy 257.891483 -4.353573) (xy 257.805733 -4.353573)
			(xy 257.72035 -4.345661) (xy 257.63606 -4.329905) (xy 257.553584 -4.306438) (xy 257.473625 -4.275462)
			(xy 257.396865 -4.23724) (xy 257.323959 -4.192099) (xy 257.25553 -4.140423) (xy 257.19216 -4.082654)
			(xy 257.134391 -4.019284) (xy 257.082715 -3.950855) (xy 257.037574 -3.877949) (xy 256.999352 -3.801189)
			(xy 256.968376 -3.72123) (xy 256.944909 -3.638754) (xy 256.929153 -3.554464) (xy 256.921241 -3.469081)
			(xy 254.465119 -3.469081) (xy 254.465087 -3.471875) (xy 254.457175 -3.557258) (xy 254.441419 -3.641548)
			(xy 254.417952 -3.724024) (xy 254.386976 -3.803983) (xy 254.348754 -3.880743) (xy 254.303613 -3.953649)
			(xy 254.251937 -4.022078) (xy 254.194168 -4.085448) (xy 254.130798 -4.143217) (xy 254.062369 -4.194893)
			(xy 253.989463 -4.240034) (xy 253.912703 -4.278256) (xy 253.832744 -4.309232) (xy 253.750268 -4.332699)
			(xy 253.665978 -4.348455) (xy 253.580595 -4.356367) (xy 253.494845 -4.356367) (xy 253.409462 -4.348455)
			(xy 253.325172 -4.332699) (xy 253.242696 -4.309232) (xy 253.162737 -4.278256) (xy 253.085977 -4.240034)
			(xy 253.013071 -4.194893) (xy 252.944642 -4.143217) (xy 252.881272 -4.085448) (xy 252.823503 -4.022078)
			(xy 252.771827 -3.953649) (xy 252.726686 -3.880743) (xy 252.688464 -3.803983) (xy 252.657488 -3.724024)
			(xy 252.634021 -3.641548) (xy 252.618265 -3.557258) (xy 252.610353 -3.471875) (xy 248.115087 -3.471875)
			(xy 248.107175 -3.557258) (xy 248.091419 -3.641548) (xy 248.067952 -3.724024) (xy 248.036976 -3.803983)
			(xy 247.998754 -3.880743) (xy 247.953613 -3.953649) (xy 247.901937 -4.022078) (xy 247.844168 -4.085448)
			(xy 247.780798 -4.143217) (xy 247.712369 -4.194893) (xy 247.639463 -4.240034) (xy 247.562703 -4.278256)
			(xy 247.482744 -4.309232) (xy 247.400268 -4.332699) (xy 247.315978 -4.348455) (xy 247.230595 -4.356367)
			(xy 247.144845 -4.356367) (xy 247.059462 -4.348455) (xy 246.975172 -4.332699) (xy 246.892696 -4.309232)
			(xy 246.812737 -4.278256) (xy 246.735977 -4.240034) (xy 246.663071 -4.194893) (xy 246.594642 -4.143217)
			(xy 246.531272 -4.085448) (xy 246.473503 -4.022078) (xy 246.421827 -3.953649) (xy 246.376686 -3.880743)
			(xy 246.338464 -3.803983) (xy 246.307488 -3.724024) (xy 246.284021 -3.641548) (xy 246.268265 -3.557258)
			(xy 246.260353 -3.471875) (xy 216.248247 -3.471875) (xy 216.240335 -3.557258) (xy 216.224579 -3.641548)
			(xy 216.201112 -3.724024) (xy 216.170136 -3.803983) (xy 216.131914 -3.880743) (xy 216.086773 -3.953649)
			(xy 216.035097 -4.022078) (xy 215.977328 -4.085448) (xy 215.913958 -4.143217) (xy 215.845529 -4.194893)
			(xy 215.772623 -4.240034) (xy 215.695863 -4.278256) (xy 215.615904 -4.309232) (xy 215.533428 -4.332699)
			(xy 215.449138 -4.348455) (xy 215.363755 -4.356367) (xy 215.278005 -4.356367) (xy 215.192622 -4.348455)
			(xy 215.108332 -4.332699) (xy 215.025856 -4.309232) (xy 214.945897 -4.278256) (xy 214.869137 -4.240034)
			(xy 214.796231 -4.194893) (xy 214.727802 -4.143217) (xy 214.664432 -4.085448) (xy 214.606663 -4.022078)
			(xy 214.554987 -3.953649) (xy 214.509846 -3.880743) (xy 214.471624 -3.803983) (xy 214.440648 -3.724024)
			(xy 214.417181 -3.641548) (xy 214.401425 -3.557258) (xy 214.393513 -3.471875) (xy 209.898247 -3.471875)
			(xy 209.890335 -3.557258) (xy 209.874579 -3.641548) (xy 209.851112 -3.724024) (xy 209.820136 -3.803983)
			(xy 209.781914 -3.880743) (xy 209.736773 -3.953649) (xy 209.685097 -4.022078) (xy 209.627328 -4.085448)
			(xy 209.563958 -4.143217) (xy 209.495529 -4.194893) (xy 209.422623 -4.240034) (xy 209.345863 -4.278256)
			(xy 209.265904 -4.309232) (xy 209.183428 -4.332699) (xy 209.099138 -4.348455) (xy 209.013755 -4.356367)
			(xy 208.928005 -4.356367) (xy 208.842622 -4.348455) (xy 208.758332 -4.332699) (xy 208.675856 -4.309232)
			(xy 208.595897 -4.278256) (xy 208.519137 -4.240034) (xy 208.446231 -4.194893) (xy 208.377802 -4.143217)
			(xy 208.314432 -4.085448) (xy 208.256663 -4.022078) (xy 208.204987 -3.953649) (xy 208.159846 -3.880743)
			(xy 208.121624 -3.803983) (xy 208.090648 -3.724024) (xy 208.067181 -3.641548) (xy 208.051425 -3.557258)
			(xy 208.043513 -3.471875) (xy 197.075741 -3.471875) (xy 197.091928 -3.518134) (xy 197.13088 -3.653342)
			(xy 197.16219 -3.790521) (xy 197.185759 -3.929239) (xy 197.201513 -4.069061) (xy 197.209403 -4.209547)
			(xy 197.209918 -4.2799) (xy 197.209918 -6.011875) (xy 208.043513 -6.011875) (xy 208.043513 -5.926125)
			(xy 208.051425 -5.840742) (xy 208.067181 -5.756452) (xy 208.090648 -5.673976) (xy 208.121624 -5.594017)
			(xy 208.159846 -5.517257) (xy 208.204987 -5.444351) (xy 208.256663 -5.375922) (xy 208.314432 -5.312552)
			(xy 208.377802 -5.254783) (xy 208.446231 -5.203107) (xy 208.519137 -5.157966) (xy 208.595897 -5.119744)
			(xy 208.675856 -5.088768) (xy 208.758332 -5.065301) (xy 208.842622 -5.049545) (xy 208.928005 -5.041633)
			(xy 209.013755 -5.041633) (xy 209.099138 -5.049545) (xy 209.183428 -5.065301) (xy 209.265904 -5.088768)
			(xy 209.345863 -5.119744) (xy 209.368066 -5.1308) (xy 212.978492 -5.1308) (xy 212.978492 -4.2672)
			(xy 212.978978 -4.239931) (xy 212.98674 -4.185947) (xy 213.002105 -4.133617) (xy 213.024762 -4.084007)
			(xy 213.054248 -4.038126) (xy 213.089963 -3.996909) (xy 213.13118 -3.961194) (xy 213.177061 -3.931708)
			(xy 213.226671 -3.909051) (xy 213.279001 -3.893686) (xy 213.332985 -3.885924) (xy 213.387523 -3.885924)
			(xy 213.441507 -3.893686) (xy 213.493837 -3.909051) (xy 213.543447 -3.931708) (xy 213.589328 -3.961194)
			(xy 213.630545 -3.996909) (xy 213.66626 -4.038126) (xy 213.695746 -4.084007) (xy 213.718403 -4.133617)
			(xy 213.733768 -4.185947) (xy 213.74153 -4.239931) (xy 213.742016 -4.2672) (xy 213.742016 -5.1308)
			(xy 213.74153 -5.158069) (xy 213.733768 -5.212053) (xy 213.718403 -5.264383) (xy 213.695746 -5.313993)
			(xy 213.66626 -5.359874) (xy 213.630545 -5.401091) (xy 213.589328 -5.436806) (xy 213.543447 -5.466292)
			(xy 213.493837 -5.488949) (xy 213.441507 -5.504314) (xy 213.387523 -5.512076) (xy 213.332985 -5.512076)
			(xy 213.279001 -5.504314) (xy 213.226671 -5.488949) (xy 213.177061 -5.466292) (xy 213.13118 -5.436806)
			(xy 213.089963 -5.401091) (xy 213.054248 -5.359874) (xy 213.024762 -5.313993) (xy 213.002105 -5.264383)
			(xy 212.98674 -5.212053) (xy 212.978978 -5.158069) (xy 212.978492 -5.1308) (xy 209.368066 -5.1308)
			(xy 209.422623 -5.157966) (xy 209.495529 -5.203107) (xy 209.563958 -5.254783) (xy 209.627328 -5.312552)
			(xy 209.685097 -5.375922) (xy 209.736773 -5.444351) (xy 209.781914 -5.517257) (xy 209.820136 -5.594017)
			(xy 209.851112 -5.673976) (xy 209.874579 -5.756452) (xy 209.890335 -5.840742) (xy 209.898247 -5.926125)
			(xy 209.898742 -5.969) (xy 209.898247 -6.011875) (xy 214.393513 -6.011875) (xy 214.393513 -5.926125)
			(xy 214.401425 -5.840742) (xy 214.417181 -5.756452) (xy 214.440648 -5.673976) (xy 214.471624 -5.594017)
			(xy 214.509846 -5.517257) (xy 214.554987 -5.444351) (xy 214.606663 -5.375922) (xy 214.664432 -5.312552)
			(xy 214.727802 -5.254783) (xy 214.796231 -5.203107) (xy 214.869137 -5.157966) (xy 214.945897 -5.119744)
			(xy 215.025856 -5.088768) (xy 215.108332 -5.065301) (xy 215.192622 -5.049545) (xy 215.278005 -5.041633)
			(xy 215.363755 -5.041633) (xy 215.449138 -5.049545) (xy 215.533428 -5.065301) (xy 215.615904 -5.088768)
			(xy 215.695863 -5.119744) (xy 215.772623 -5.157966) (xy 215.845529 -5.203107) (xy 215.913958 -5.254783)
			(xy 215.977328 -5.312552) (xy 216.035097 -5.375922) (xy 216.086773 -5.444351) (xy 216.131914 -5.517257)
			(xy 216.170136 -5.594017) (xy 216.201112 -5.673976) (xy 216.224579 -5.756452) (xy 216.240335 -5.840742)
			(xy 216.248247 -5.926125) (xy 216.248742 -5.969) (xy 216.248247 -6.011875) (xy 246.260353 -6.011875)
			(xy 246.260353 -5.926125) (xy 246.268265 -5.840742) (xy 246.284021 -5.756452) (xy 246.307488 -5.673976)
			(xy 246.338464 -5.594017) (xy 246.376686 -5.517257) (xy 246.421827 -5.444351) (xy 246.473503 -5.375922)
			(xy 246.531272 -5.312552) (xy 246.594642 -5.254783) (xy 246.663071 -5.203107) (xy 246.735977 -5.157966)
			(xy 246.812737 -5.119744) (xy 246.892696 -5.088768) (xy 246.975172 -5.065301) (xy 247.059462 -5.049545)
			(xy 247.144845 -5.041633) (xy 247.230595 -5.041633) (xy 247.315978 -5.049545) (xy 247.400268 -5.065301)
			(xy 247.482744 -5.088768) (xy 247.562703 -5.119744) (xy 247.584906 -5.1308) (xy 248.766584 -5.1308)
			(xy 248.766584 -4.2672) (xy 248.76707 -4.239931) (xy 248.774832 -4.185947) (xy 248.790197 -4.133617)
			(xy 248.812854 -4.084007) (xy 248.84234 -4.038126) (xy 248.878055 -3.996909) (xy 248.919272 -3.961194)
			(xy 248.965153 -3.931708) (xy 249.014763 -3.909051) (xy 249.067093 -3.893686) (xy 249.121077 -3.885924)
			(xy 249.175615 -3.885924) (xy 249.229599 -3.893686) (xy 249.281929 -3.909051) (xy 249.331539 -3.931708)
			(xy 249.37742 -3.961194) (xy 249.418637 -3.996909) (xy 249.454352 -4.038126) (xy 249.483838 -4.084007)
			(xy 249.506495 -4.133617) (xy 249.52186 -4.185947) (xy 249.529622 -4.239931) (xy 249.530108 -4.2672)
			(xy 249.530108 -5.1308) (xy 249.529622 -5.158069) (xy 249.52186 -5.212053) (xy 249.506495 -5.264383)
			(xy 249.483838 -5.313993) (xy 249.454352 -5.359874) (xy 249.418637 -5.401091) (xy 249.37742 -5.436806)
			(xy 249.331539 -5.466292) (xy 249.281929 -5.488949) (xy 249.229599 -5.504314) (xy 249.175615 -5.512076)
			(xy 249.121077 -5.512076) (xy 249.067093 -5.504314) (xy 249.014763 -5.488949) (xy 248.965153 -5.466292)
			(xy 248.919272 -5.436806) (xy 248.878055 -5.401091) (xy 248.84234 -5.359874) (xy 248.812854 -5.313993)
			(xy 248.790197 -5.264383) (xy 248.774832 -5.212053) (xy 248.76707 -5.158069) (xy 248.766584 -5.1308)
			(xy 247.584906 -5.1308) (xy 247.639463 -5.157966) (xy 247.712369 -5.203107) (xy 247.780798 -5.254783)
			(xy 247.844168 -5.312552) (xy 247.901937 -5.375922) (xy 247.953613 -5.444351) (xy 247.998754 -5.517257)
			(xy 248.036976 -5.594017) (xy 248.067952 -5.673976) (xy 248.091419 -5.756452) (xy 248.107175 -5.840742)
			(xy 248.115087 -5.926125) (xy 248.115582 -5.969) (xy 248.115087 -6.011875) (xy 252.610353 -6.011875)
			(xy 252.610353 -5.926125) (xy 252.618265 -5.840742) (xy 252.634021 -5.756452) (xy 252.657488 -5.673976)
			(xy 252.688464 -5.594017) (xy 252.726686 -5.517257) (xy 252.771827 -5.444351) (xy 252.823503 -5.375922)
			(xy 252.881272 -5.312552) (xy 252.944642 -5.254783) (xy 253.013071 -5.203107) (xy 253.085977 -5.157966)
			(xy 253.162737 -5.119744) (xy 253.242696 -5.088768) (xy 253.325172 -5.065301) (xy 253.409462 -5.049545)
			(xy 253.494845 -5.041633) (xy 253.580595 -5.041633) (xy 253.665978 -5.049545) (xy 253.750268 -5.065301)
			(xy 253.832744 -5.088768) (xy 253.912703 -5.119744) (xy 253.989463 -5.157966) (xy 254.062369 -5.203107)
			(xy 254.130798 -5.254783) (xy 254.194168 -5.312552) (xy 254.251937 -5.375922) (xy 254.303613 -5.444351)
			(xy 254.348754 -5.517257) (xy 254.386976 -5.594017) (xy 254.417952 -5.673976) (xy 254.441419 -5.756452)
			(xy 254.457175 -5.840742) (xy 254.465087 -5.926125) (xy 254.465582 -5.969) (xy 254.465119 -6.009081)
			(xy 256.921241 -6.009081) (xy 256.921241 -5.923331) (xy 256.929153 -5.837948) (xy 256.944909 -5.753658)
			(xy 256.968376 -5.671182) (xy 256.999352 -5.591223) (xy 257.037574 -5.514463) (xy 257.082715 -5.441557)
			(xy 257.134391 -5.373128) (xy 257.19216 -5.309758) (xy 257.25553 -5.251989) (xy 257.323959 -5.200313)
			(xy 257.396865 -5.155172) (xy 257.473625 -5.11695) (xy 257.553584 -5.085974) (xy 257.63606 -5.062507)
			(xy 257.72035 -5.046751) (xy 257.805733 -5.038839) (xy 257.891483 -5.038839) (xy 257.976866 -5.046751)
			(xy 258.061156 -5.062507) (xy 258.143632 -5.085974) (xy 258.223591 -5.11695) (xy 258.300351 -5.155172)
			(xy 258.373257 -5.200313) (xy 258.441686 -5.251989) (xy 258.505056 -5.309758) (xy 258.562825 -5.373128)
			(xy 258.614501 -5.441557) (xy 258.659642 -5.514463) (xy 258.697864 -5.591223) (xy 258.72884 -5.671182)
			(xy 258.752307 -5.753658) (xy 258.768063 -5.837948) (xy 258.775975 -5.923331) (xy 258.77647 -5.966206)
			(xy 258.775975 -6.009081) (xy 263.271241 -6.009081) (xy 263.271241 -5.923331) (xy 263.279153 -5.837948)
			(xy 263.294909 -5.753658) (xy 263.318376 -5.671182) (xy 263.349352 -5.591223) (xy 263.387574 -5.514463)
			(xy 263.432715 -5.441557) (xy 263.484391 -5.373128) (xy 263.54216 -5.309758) (xy 263.60553 -5.251989)
			(xy 263.673959 -5.200313) (xy 263.746865 -5.155172) (xy 263.823625 -5.11695) (xy 263.903584 -5.085974)
			(xy 263.98606 -5.062507) (xy 264.07035 -5.046751) (xy 264.155733 -5.038839) (xy 264.241483 -5.038839)
			(xy 264.326866 -5.046751) (xy 264.411156 -5.062507) (xy 264.493632 -5.085974) (xy 264.573591 -5.11695)
			(xy 264.650351 -5.155172) (xy 264.723257 -5.200313) (xy 264.791686 -5.251989) (xy 264.855056 -5.309758)
			(xy 264.912825 -5.373128) (xy 264.964501 -5.441557) (xy 265.009642 -5.514463) (xy 265.047864 -5.591223)
			(xy 265.07884 -5.671182) (xy 265.102307 -5.753658) (xy 265.118063 -5.837948) (xy 265.125975 -5.923331)
			(xy 265.12647 -5.966206) (xy 265.125975 -6.009081) (xy 324.845921 -6.009081) (xy 324.845921 -5.923331)
			(xy 324.853833 -5.837948) (xy 324.869589 -5.753658) (xy 324.893056 -5.671182) (xy 324.924032 -5.591223)
			(xy 324.962254 -5.514463) (xy 325.007395 -5.441557) (xy 325.059071 -5.373128) (xy 325.11684 -5.309758)
			(xy 325.18021 -5.251989) (xy 325.248639 -5.200313) (xy 325.321545 -5.155172) (xy 325.398305 -5.11695)
			(xy 325.478264 -5.085974) (xy 325.56074 -5.062507) (xy 325.64503 -5.046751) (xy 325.730413 -5.038839)
			(xy 325.816163 -5.038839) (xy 325.901546 -5.046751) (xy 325.985836 -5.062507) (xy 326.068312 -5.085974)
			(xy 326.148271 -5.11695) (xy 326.225031 -5.155172) (xy 326.297937 -5.200313) (xy 326.366366 -5.251989)
			(xy 326.429736 -5.309758) (xy 326.487505 -5.373128) (xy 326.539181 -5.441557) (xy 326.584322 -5.514463)
			(xy 326.622544 -5.591223) (xy 326.65352 -5.671182) (xy 326.676987 -5.753658) (xy 326.692743 -5.837948)
			(xy 326.700655 -5.923331) (xy 326.70115 -5.966206) (xy 326.700655 -6.009081) (xy 331.195921 -6.009081)
			(xy 331.195921 -5.923331) (xy 331.203833 -5.837948) (xy 331.219589 -5.753658) (xy 331.243056 -5.671182)
			(xy 331.274032 -5.591223) (xy 331.312254 -5.514463) (xy 331.357395 -5.441557) (xy 331.409071 -5.373128)
			(xy 331.46684 -5.309758) (xy 331.53021 -5.251989) (xy 331.598639 -5.200313) (xy 331.671545 -5.155172)
			(xy 331.748305 -5.11695) (xy 331.828264 -5.085974) (xy 331.91074 -5.062507) (xy 331.99503 -5.046751)
			(xy 332.080413 -5.038839) (xy 332.166163 -5.038839) (xy 332.251546 -5.046751) (xy 332.335836 -5.062507)
			(xy 332.418312 -5.085974) (xy 332.498271 -5.11695) (xy 332.575031 -5.155172) (xy 332.647937 -5.200313)
			(xy 332.716366 -5.251989) (xy 332.779736 -5.309758) (xy 332.837505 -5.373128) (xy 332.889181 -5.441557)
			(xy 332.934322 -5.514463) (xy 332.972544 -5.591223) (xy 333.00352 -5.671182) (xy 333.026987 -5.753658)
			(xy 333.042743 -5.837948) (xy 333.050655 -5.923331) (xy 333.05115 -5.966206) (xy 333.050655 -6.009081)
			(xy 335.488267 -6.009081) (xy 335.488267 -5.923331) (xy 335.496179 -5.837948) (xy 335.511935 -5.753658)
			(xy 335.535402 -5.671182) (xy 335.566378 -5.591223) (xy 335.6046 -5.514463) (xy 335.649741 -5.441557)
			(xy 335.701417 -5.373128) (xy 335.759186 -5.309758) (xy 335.822556 -5.251989) (xy 335.890985 -5.200313)
			(xy 335.963891 -5.155172) (xy 336.040651 -5.11695) (xy 336.12061 -5.085974) (xy 336.203086 -5.062507)
			(xy 336.287376 -5.046751) (xy 336.372759 -5.038839) (xy 336.458509 -5.038839) (xy 336.543892 -5.046751)
			(xy 336.628182 -5.062507) (xy 336.710658 -5.085974) (xy 336.790617 -5.11695) (xy 336.867377 -5.155172)
			(xy 336.940283 -5.200313) (xy 337.008712 -5.251989) (xy 337.072082 -5.309758) (xy 337.129851 -5.373128)
			(xy 337.181527 -5.441557) (xy 337.226668 -5.514463) (xy 337.26489 -5.591223) (xy 337.295866 -5.671182)
			(xy 337.319333 -5.753658) (xy 337.335089 -5.837948) (xy 337.343001 -5.923331) (xy 337.343496 -5.966206)
			(xy 337.343001 -6.009081) (xy 341.838267 -6.009081) (xy 341.838267 -5.923331) (xy 341.846179 -5.837948)
			(xy 341.861935 -5.753658) (xy 341.885402 -5.671182) (xy 341.916378 -5.591223) (xy 341.9546 -5.514463)
			(xy 341.999741 -5.441557) (xy 342.051417 -5.373128) (xy 342.109186 -5.309758) (xy 342.172556 -5.251989)
			(xy 342.240985 -5.200313) (xy 342.313891 -5.155172) (xy 342.390651 -5.11695) (xy 342.47061 -5.085974)
			(xy 342.553086 -5.062507) (xy 342.637376 -5.046751) (xy 342.722759 -5.038839) (xy 342.808509 -5.038839)
			(xy 342.893892 -5.046751) (xy 342.978182 -5.062507) (xy 343.060658 -5.085974) (xy 343.140617 -5.11695)
			(xy 343.217377 -5.155172) (xy 343.290283 -5.200313) (xy 343.358712 -5.251989) (xy 343.422082 -5.309758)
			(xy 343.479851 -5.373128) (xy 343.531527 -5.441557) (xy 343.576668 -5.514463) (xy 343.61489 -5.591223)
			(xy 343.645866 -5.671182) (xy 343.669333 -5.753658) (xy 343.685089 -5.837948) (xy 343.693001 -5.923331)
			(xy 343.693496 -5.966206) (xy 343.693001 -6.009081) (xy 373.705107 -6.009081) (xy 373.705107 -5.923331)
			(xy 373.713019 -5.837948) (xy 373.728775 -5.753658) (xy 373.752242 -5.671182) (xy 373.783218 -5.591223)
			(xy 373.82144 -5.514463) (xy 373.866581 -5.441557) (xy 373.918257 -5.373128) (xy 373.976026 -5.309758)
			(xy 374.039396 -5.251989) (xy 374.107825 -5.200313) (xy 374.180731 -5.155172) (xy 374.257491 -5.11695)
			(xy 374.33745 -5.085974) (xy 374.419926 -5.062507) (xy 374.504216 -5.046751) (xy 374.589599 -5.038839)
			(xy 374.675349 -5.038839) (xy 374.760732 -5.046751) (xy 374.845022 -5.062507) (xy 374.927498 -5.085974)
			(xy 375.007457 -5.11695) (xy 375.084217 -5.155172) (xy 375.157123 -5.200313) (xy 375.225552 -5.251989)
			(xy 375.288922 -5.309758) (xy 375.346691 -5.373128) (xy 375.398367 -5.441557) (xy 375.443508 -5.514463)
			(xy 375.48173 -5.591223) (xy 375.512706 -5.671182) (xy 375.536173 -5.753658) (xy 375.551929 -5.837948)
			(xy 375.559841 -5.923331) (xy 375.560336 -5.966206) (xy 375.559841 -6.009081) (xy 380.055107 -6.009081)
			(xy 380.055107 -5.923331) (xy 380.063019 -5.837948) (xy 380.078775 -5.753658) (xy 380.102242 -5.671182)
			(xy 380.133218 -5.591223) (xy 380.17144 -5.514463) (xy 380.216581 -5.441557) (xy 380.268257 -5.373128)
			(xy 380.326026 -5.309758) (xy 380.389396 -5.251989) (xy 380.457825 -5.200313) (xy 380.530731 -5.155172)
			(xy 380.607491 -5.11695) (xy 380.68745 -5.085974) (xy 380.769926 -5.062507) (xy 380.854216 -5.046751)
			(xy 380.939599 -5.038839) (xy 381.025349 -5.038839) (xy 381.110732 -5.046751) (xy 381.195022 -5.062507)
			(xy 381.277498 -5.085974) (xy 381.357457 -5.11695) (xy 381.434217 -5.155172) (xy 381.507123 -5.200313)
			(xy 381.575552 -5.251989) (xy 381.638922 -5.309758) (xy 381.696691 -5.373128) (xy 381.748367 -5.441557)
			(xy 381.793508 -5.514463) (xy 381.83173 -5.591223) (xy 381.862706 -5.671182) (xy 381.886173 -5.753658)
			(xy 381.901929 -5.837948) (xy 381.909841 -5.923331) (xy 381.910336 -5.966206) (xy 381.909841 -6.009081)
			(xy 381.901929 -6.094464) (xy 381.886173 -6.178754) (xy 381.862706 -6.26123) (xy 381.83173 -6.341189)
			(xy 381.793508 -6.417949) (xy 381.748367 -6.490855) (xy 381.696691 -6.559284) (xy 381.638922 -6.622654)
			(xy 381.575552 -6.680423) (xy 381.507123 -6.732099) (xy 381.434217 -6.77724) (xy 381.357457 -6.815462)
			(xy 381.277498 -6.846438) (xy 381.195022 -6.869905) (xy 381.110732 -6.885661) (xy 381.025349 -6.893573)
			(xy 380.939599 -6.893573) (xy 380.854216 -6.885661) (xy 380.769926 -6.869905) (xy 380.68745 -6.846438)
			(xy 380.607491 -6.815462) (xy 380.530731 -6.77724) (xy 380.457825 -6.732099) (xy 380.389396 -6.680423)
			(xy 380.326026 -6.622654) (xy 380.268257 -6.559284) (xy 380.216581 -6.490855) (xy 380.17144 -6.417949)
			(xy 380.133218 -6.341189) (xy 380.102242 -6.26123) (xy 380.078775 -6.178754) (xy 380.063019 -6.094464)
			(xy 380.055107 -6.009081) (xy 375.559841 -6.009081) (xy 375.551929 -6.094464) (xy 375.536173 -6.178754)
			(xy 375.512706 -6.26123) (xy 375.48173 -6.341189) (xy 375.443508 -6.417949) (xy 375.398367 -6.490855)
			(xy 375.346691 -6.559284) (xy 375.288922 -6.622654) (xy 375.225552 -6.680423) (xy 375.157123 -6.732099)
			(xy 375.084217 -6.77724) (xy 375.007457 -6.815462) (xy 374.927498 -6.846438) (xy 374.845022 -6.869905)
			(xy 374.760732 -6.885661) (xy 374.675349 -6.893573) (xy 374.589599 -6.893573) (xy 374.504216 -6.885661)
			(xy 374.419926 -6.869905) (xy 374.33745 -6.846438) (xy 374.257491 -6.815462) (xy 374.180731 -6.77724)
			(xy 374.107825 -6.732099) (xy 374.039396 -6.680423) (xy 373.976026 -6.622654) (xy 373.918257 -6.559284)
			(xy 373.866581 -6.490855) (xy 373.82144 -6.417949) (xy 373.783218 -6.341189) (xy 373.752242 -6.26123)
			(xy 373.728775 -6.178754) (xy 373.713019 -6.094464) (xy 373.705107 -6.009081) (xy 343.693001 -6.009081)
			(xy 343.685089 -6.094464) (xy 343.669333 -6.178754) (xy 343.645866 -6.26123) (xy 343.61489 -6.341189)
			(xy 343.576668 -6.417949) (xy 343.531527 -6.490855) (xy 343.479851 -6.559284) (xy 343.422082 -6.622654)
			(xy 343.358712 -6.680423) (xy 343.290283 -6.732099) (xy 343.217377 -6.77724) (xy 343.140617 -6.815462)
			(xy 343.060658 -6.846438) (xy 342.978182 -6.869905) (xy 342.893892 -6.885661) (xy 342.808509 -6.893573)
			(xy 342.722759 -6.893573) (xy 342.637376 -6.885661) (xy 342.553086 -6.869905) (xy 342.47061 -6.846438)
			(xy 342.390651 -6.815462) (xy 342.313891 -6.77724) (xy 342.240985 -6.732099) (xy 342.172556 -6.680423)
			(xy 342.109186 -6.622654) (xy 342.051417 -6.559284) (xy 341.999741 -6.490855) (xy 341.9546 -6.417949)
			(xy 341.916378 -6.341189) (xy 341.885402 -6.26123) (xy 341.861935 -6.178754) (xy 341.846179 -6.094464)
			(xy 341.838267 -6.009081) (xy 337.343001 -6.009081) (xy 337.335089 -6.094464) (xy 337.319333 -6.178754)
			(xy 337.295866 -6.26123) (xy 337.26489 -6.341189) (xy 337.226668 -6.417949) (xy 337.181527 -6.490855)
			(xy 337.129851 -6.559284) (xy 337.072082 -6.622654) (xy 337.008712 -6.680423) (xy 336.940283 -6.732099)
			(xy 336.867377 -6.77724) (xy 336.790617 -6.815462) (xy 336.710658 -6.846438) (xy 336.628182 -6.869905)
			(xy 336.543892 -6.885661) (xy 336.458509 -6.893573) (xy 336.372759 -6.893573) (xy 336.287376 -6.885661)
			(xy 336.203086 -6.869905) (xy 336.12061 -6.846438) (xy 336.040651 -6.815462) (xy 335.963891 -6.77724)
			(xy 335.890985 -6.732099) (xy 335.822556 -6.680423) (xy 335.759186 -6.622654) (xy 335.701417 -6.559284)
			(xy 335.649741 -6.490855) (xy 335.6046 -6.417949) (xy 335.566378 -6.341189) (xy 335.535402 -6.26123)
			(xy 335.511935 -6.178754) (xy 335.496179 -6.094464) (xy 335.488267 -6.009081) (xy 333.050655 -6.009081)
			(xy 333.042743 -6.094464) (xy 333.026987 -6.178754) (xy 333.00352 -6.26123) (xy 332.972544 -6.341189)
			(xy 332.934322 -6.417949) (xy 332.889181 -6.490855) (xy 332.837505 -6.559284) (xy 332.779736 -6.622654)
			(xy 332.716366 -6.680423) (xy 332.647937 -6.732099) (xy 332.575031 -6.77724) (xy 332.498271 -6.815462)
			(xy 332.418312 -6.846438) (xy 332.335836 -6.869905) (xy 332.251546 -6.885661) (xy 332.166163 -6.893573)
			(xy 332.080413 -6.893573) (xy 331.99503 -6.885661) (xy 331.91074 -6.869905) (xy 331.828264 -6.846438)
			(xy 331.748305 -6.815462) (xy 331.671545 -6.77724) (xy 331.598639 -6.732099) (xy 331.53021 -6.680423)
			(xy 331.46684 -6.622654) (xy 331.409071 -6.559284) (xy 331.357395 -6.490855) (xy 331.312254 -6.417949)
			(xy 331.274032 -6.341189) (xy 331.243056 -6.26123) (xy 331.219589 -6.178754) (xy 331.203833 -6.094464)
			(xy 331.195921 -6.009081) (xy 326.700655 -6.009081) (xy 326.692743 -6.094464) (xy 326.676987 -6.178754)
			(xy 326.65352 -6.26123) (xy 326.622544 -6.341189) (xy 326.584322 -6.417949) (xy 326.539181 -6.490855)
			(xy 326.487505 -6.559284) (xy 326.429736 -6.622654) (xy 326.366366 -6.680423) (xy 326.297937 -6.732099)
			(xy 326.225031 -6.77724) (xy 326.148271 -6.815462) (xy 326.068312 -6.846438) (xy 325.985836 -6.869905)
			(xy 325.901546 -6.885661) (xy 325.816163 -6.893573) (xy 325.730413 -6.893573) (xy 325.64503 -6.885661)
			(xy 325.56074 -6.869905) (xy 325.478264 -6.846438) (xy 325.398305 -6.815462) (xy 325.321545 -6.77724)
			(xy 325.248639 -6.732099) (xy 325.18021 -6.680423) (xy 325.11684 -6.622654) (xy 325.059071 -6.559284)
			(xy 325.007395 -6.490855) (xy 324.962254 -6.417949) (xy 324.924032 -6.341189) (xy 324.893056 -6.26123)
			(xy 324.869589 -6.178754) (xy 324.853833 -6.094464) (xy 324.845921 -6.009081) (xy 265.125975 -6.009081)
			(xy 265.118063 -6.094464) (xy 265.102307 -6.178754) (xy 265.07884 -6.26123) (xy 265.047864 -6.341189)
			(xy 265.009642 -6.417949) (xy 264.964501 -6.490855) (xy 264.912825 -6.559284) (xy 264.855056 -6.622654)
			(xy 264.791686 -6.680423) (xy 264.723257 -6.732099) (xy 264.650351 -6.77724) (xy 264.573591 -6.815462)
			(xy 264.493632 -6.846438) (xy 264.411156 -6.869905) (xy 264.326866 -6.885661) (xy 264.241483 -6.893573)
			(xy 264.155733 -6.893573) (xy 264.07035 -6.885661) (xy 263.98606 -6.869905) (xy 263.903584 -6.846438)
			(xy 263.823625 -6.815462) (xy 263.746865 -6.77724) (xy 263.673959 -6.732099) (xy 263.60553 -6.680423)
			(xy 263.54216 -6.622654) (xy 263.484391 -6.559284) (xy 263.432715 -6.490855) (xy 263.387574 -6.417949)
			(xy 263.349352 -6.341189) (xy 263.318376 -6.26123) (xy 263.294909 -6.178754) (xy 263.279153 -6.094464)
			(xy 263.271241 -6.009081) (xy 258.775975 -6.009081) (xy 258.768063 -6.094464) (xy 258.752307 -6.178754)
			(xy 258.72884 -6.26123) (xy 258.697864 -6.341189) (xy 258.659642 -6.417949) (xy 258.614501 -6.490855)
			(xy 258.562825 -6.559284) (xy 258.505056 -6.622654) (xy 258.441686 -6.680423) (xy 258.373257 -6.732099)
			(xy 258.300351 -6.77724) (xy 258.223591 -6.815462) (xy 258.143632 -6.846438) (xy 258.061156 -6.869905)
			(xy 257.976866 -6.885661) (xy 257.891483 -6.893573) (xy 257.805733 -6.893573) (xy 257.72035 -6.885661)
			(xy 257.63606 -6.869905) (xy 257.553584 -6.846438) (xy 257.473625 -6.815462) (xy 257.396865 -6.77724)
			(xy 257.323959 -6.732099) (xy 257.25553 -6.680423) (xy 257.19216 -6.622654) (xy 257.134391 -6.559284)
			(xy 257.082715 -6.490855) (xy 257.037574 -6.417949) (xy 256.999352 -6.341189) (xy 256.968376 -6.26123)
			(xy 256.944909 -6.178754) (xy 256.929153 -6.094464) (xy 256.921241 -6.009081) (xy 254.465119 -6.009081)
			(xy 254.465087 -6.011875) (xy 254.457175 -6.097258) (xy 254.441419 -6.181548) (xy 254.417952 -6.264024)
			(xy 254.386976 -6.343983) (xy 254.348754 -6.420743) (xy 254.303613 -6.493649) (xy 254.251937 -6.562078)
			(xy 254.194168 -6.625448) (xy 254.130798 -6.683217) (xy 254.062369 -6.734893) (xy 253.989463 -6.780034)
			(xy 253.912703 -6.818256) (xy 253.832744 -6.849232) (xy 253.750268 -6.872699) (xy 253.665978 -6.888455)
			(xy 253.580595 -6.896367) (xy 253.494845 -6.896367) (xy 253.409462 -6.888455) (xy 253.325172 -6.872699)
			(xy 253.242696 -6.849232) (xy 253.162737 -6.818256) (xy 253.085977 -6.780034) (xy 253.013071 -6.734893)
			(xy 252.944642 -6.683217) (xy 252.881272 -6.625448) (xy 252.823503 -6.562078) (xy 252.771827 -6.493649)
			(xy 252.726686 -6.420743) (xy 252.688464 -6.343983) (xy 252.657488 -6.264024) (xy 252.634021 -6.181548)
			(xy 252.618265 -6.097258) (xy 252.610353 -6.011875) (xy 248.115087 -6.011875) (xy 248.107175 -6.097258)
			(xy 248.091419 -6.181548) (xy 248.067952 -6.264024) (xy 248.036976 -6.343983) (xy 247.998754 -6.420743)
			(xy 247.953613 -6.493649) (xy 247.901937 -6.562078) (xy 247.844168 -6.625448) (xy 247.780798 -6.683217)
			(xy 247.712369 -6.734893) (xy 247.639463 -6.780034) (xy 247.562703 -6.818256) (xy 247.482744 -6.849232)
			(xy 247.400268 -6.872699) (xy 247.315978 -6.888455) (xy 247.230595 -6.896367) (xy 247.144845 -6.896367)
			(xy 247.059462 -6.888455) (xy 246.975172 -6.872699) (xy 246.892696 -6.849232) (xy 246.812737 -6.818256)
			(xy 246.735977 -6.780034) (xy 246.663071 -6.734893) (xy 246.594642 -6.683217) (xy 246.531272 -6.625448)
			(xy 246.473503 -6.562078) (xy 246.421827 -6.493649) (xy 246.376686 -6.420743) (xy 246.338464 -6.343983)
			(xy 246.307488 -6.264024) (xy 246.284021 -6.181548) (xy 246.268265 -6.097258) (xy 246.260353 -6.011875)
			(xy 216.248247 -6.011875) (xy 216.240335 -6.097258) (xy 216.224579 -6.181548) (xy 216.201112 -6.264024)
			(xy 216.170136 -6.343983) (xy 216.131914 -6.420743) (xy 216.086773 -6.493649) (xy 216.035097 -6.562078)
			(xy 215.977328 -6.625448) (xy 215.913958 -6.683217) (xy 215.845529 -6.734893) (xy 215.772623 -6.780034)
			(xy 215.695863 -6.818256) (xy 215.615904 -6.849232) (xy 215.533428 -6.872699) (xy 215.449138 -6.888455)
			(xy 215.363755 -6.896367) (xy 215.278005 -6.896367) (xy 215.192622 -6.888455) (xy 215.108332 -6.872699)
			(xy 215.025856 -6.849232) (xy 214.945897 -6.818256) (xy 214.869137 -6.780034) (xy 214.796231 -6.734893)
			(xy 214.727802 -6.683217) (xy 214.664432 -6.625448) (xy 214.606663 -6.562078) (xy 214.554987 -6.493649)
			(xy 214.509846 -6.420743) (xy 214.471624 -6.343983) (xy 214.440648 -6.264024) (xy 214.417181 -6.181548)
			(xy 214.401425 -6.097258) (xy 214.393513 -6.011875) (xy 209.898247 -6.011875) (xy 209.890335 -6.097258)
			(xy 209.874579 -6.181548) (xy 209.851112 -6.264024) (xy 209.820136 -6.343983) (xy 209.781914 -6.420743)
			(xy 209.736773 -6.493649) (xy 209.685097 -6.562078) (xy 209.627328 -6.625448) (xy 209.563958 -6.683217)
			(xy 209.495529 -6.734893) (xy 209.422623 -6.780034) (xy 209.345863 -6.818256) (xy 209.265904 -6.849232)
			(xy 209.183428 -6.872699) (xy 209.099138 -6.888455) (xy 209.013755 -6.896367) (xy 208.928005 -6.896367)
			(xy 208.842622 -6.888455) (xy 208.758332 -6.872699) (xy 208.675856 -6.849232) (xy 208.595897 -6.818256)
			(xy 208.519137 -6.780034) (xy 208.446231 -6.734893) (xy 208.377802 -6.683217) (xy 208.314432 -6.625448)
			(xy 208.256663 -6.562078) (xy 208.204987 -6.493649) (xy 208.159846 -6.420743) (xy 208.121624 -6.343983)
			(xy 208.090648 -6.264024) (xy 208.067181 -6.181548) (xy 208.051425 -6.097258) (xy 208.043513 -6.011875)
			(xy 197.209918 -6.011875) (xy 197.209918 -7.78002) (xy 197.21044 -7.835826) (xy 197.218783 -7.947127)
			(xy 197.235419 -8.057493) (xy 197.260257 -8.166307) (xy 197.293157 -8.27296) (xy 197.333935 -8.376857)
			(xy 197.382363 -8.477416) (xy 197.43817 -8.574075) (xy 197.501045 -8.666293) (xy 197.570635 -8.753555)
			(xy 197.646552 -8.835372) (xy 197.728371 -8.911287) (xy 197.815634 -8.980875) (xy 197.907854 -9.043748)
			(xy 198.004514 -9.099553) (xy 198.105074 -9.147979) (xy 198.208972 -9.188755) (xy 198.315626 -9.221652)
			(xy 198.424441 -9.246487) (xy 198.534807 -9.263121) (xy 198.646108 -9.271461) (xy 198.701914 -9.272016)
			(xy 223.300036 -9.272016) (xy 223.370389 -9.27251) (xy 223.510873 -9.280402) (xy 223.650694 -9.296158)
			(xy 223.789412 -9.319729) (xy 223.92659 -9.35104) (xy 224.061796 -9.389995) (xy 224.194606 -9.436468)
			(xy 224.3246 -9.490316) (xy 224.451371 -9.551367) (xy 224.57452 -9.619431) (xy 224.693658 -9.694292)
			(xy 224.808411 -9.775716) (xy 224.918419 -9.863446) (xy 225.023334 -9.957206) (xy 225.122827 -10.056701)
			(xy 225.216585 -10.161618) (xy 225.304313 -10.271627) (xy 225.385734 -10.386382) (xy 225.460594 -10.505522)
			(xy 225.528655 -10.628671) (xy 225.589704 -10.755444) (xy 225.643549 -10.885439) (xy 225.69002 -11.01825)
			(xy 225.728972 -11.153457) (xy 225.760281 -11.290635) (xy 225.783849 -11.429353) (xy 225.799602 -11.569174)
			(xy 225.807491 -11.709659) (xy 225.808032 -11.780012) (xy 225.808032 -31.197296) (xy 227.377752 -32.767016)
			(xy 254.645668 -32.767016)
		)
		(stroke
			(width 0)
			(type solid)
		)
		(fill yes)
		(layer "In5.Cu")
		(net "DELTA_L_GND_1")
	)
	(gr_poly
		(pts
			(xy 194.495928 -441.17006) (xy 194.49641 -441.126022) (xy 194.50409 -441.03828) (xy 194.519387 -440.951542)
			(xy 194.542185 -440.866466) (xy 194.572311 -440.783702) (xy 194.609536 -440.703878) (xy 194.653576 -440.627602)
			(xy 194.704095 -440.555454) (xy 194.760711 -440.487984) (xy 194.822991 -440.425704) (xy 194.890462 -440.369089)
			(xy 194.96261 -440.31857) (xy 195.038887 -440.274531) (xy 195.118711 -440.237308) (xy 195.201476 -440.207182)
			(xy 195.286551 -440.184385) (xy 195.37329 -440.169088) (xy 195.461032 -440.16141) (xy 195.50507 -440.160918)
			(xy 276.314916 -440.160918) (xy 276.358955 -440.161399) (xy 276.446699 -440.169077) (xy 276.533439 -440.184372)
			(xy 276.618516 -440.207169) (xy 276.701283 -440.237294) (xy 276.781109 -440.274518) (xy 276.857388 -440.318557)
			(xy 276.929538 -440.369076) (xy 276.99701 -440.425692) (xy 277.059292 -440.487972) (xy 277.115909 -440.555443)
			(xy 277.16643 -440.627592) (xy 277.210471 -440.703869) (xy 277.247697 -440.783695) (xy 277.277823 -440.866461)
			(xy 277.300622 -440.951538) (xy 277.31592 -441.038278) (xy 277.3236 -441.126021) (xy 277.324058 -441.17006)
			(xy 277.324058 -441.480956) (xy 463.300064 -441.480956) (xy 463.355834 -441.480449) (xy 463.467062 -441.472116)
			(xy 463.577357 -441.455494) (xy 463.686101 -441.430676) (xy 463.792686 -441.397801) (xy 463.896517 -441.357052)
			(xy 463.997011 -441.308658) (xy 464.093608 -441.252889) (xy 464.185768 -441.190057) (xy 464.272974 -441.120513)
			(xy 464.354739 -441.044647) (xy 464.430606 -440.962883) (xy 464.50015 -440.875677) (xy 464.562982 -440.783519)
			(xy 464.618752 -440.686922) (xy 464.667147 -440.586428) (xy 464.707897 -440.482598) (xy 464.740773 -440.376013)
			(xy 464.765592 -440.267269) (xy 464.782215 -440.156974) (xy 464.790548 -440.045746) (xy 464.791044 -439.989976)
			(xy 464.791044 -419.236652) (xy 464.79206 -419.236652) (xy 464.79206 -419.160198) (xy 464.791552 -419.157912)
			(xy 464.783498 -419.125745) (xy 464.774831 -419.060003) (xy 464.77428 -419.026848) (xy 464.774826 -418.994155)
			(xy 464.783231 -418.929312) (xy 464.791044 -418.897562) (xy 464.791044 -409.528264) (xy 464.791527 -409.457889)
			(xy 464.799416 -409.317359) (xy 464.815173 -409.177493) (xy 464.838748 -409.03873) (xy 464.870067 -408.901508)
			(xy 464.909031 -408.766258) (xy 464.955519 -408.633405) (xy 465.009383 -408.503369) (xy 465.070454 -408.376557)
			(xy 465.138539 -408.25337) (xy 465.213426 -408.134194) (xy 465.294877 -408.019405) (xy 465.382637 -407.909364)
			(xy 465.47643 -407.804418) (xy 465.525866 -407.754328) (xy 467.354412 -405.925782) (xy 467.391723 -405.887821)
			(xy 467.461438 -405.807375) (xy 467.525236 -405.722161) (xy 467.582791 -405.632611) (xy 467.633809 -405.539182)
			(xy 467.678031 -405.442352) (xy 467.715231 -405.342613) (xy 467.74522 -405.240474) (xy 467.767844 -405.136455)
			(xy 467.782988 -405.031087) (xy 467.790575 -404.924907) (xy 467.791038 -404.871682) (xy 467.791038 -82.82813)
			(xy 467.791541 -82.757757) (xy 467.799451 -82.617233) (xy 467.815226 -82.477373) (xy 467.838815 -82.338618)
			(xy 467.870145 -82.201402) (xy 467.909116 -82.066159) (xy 467.955608 -81.933313) (xy 468.009473 -81.803282)
			(xy 468.070541 -81.676474) (xy 468.138622 -81.553289) (xy 468.213501 -81.434114) (xy 468.294942 -81.319323)
			(xy 468.382689 -81.209278) (xy 468.476467 -81.104324) (xy 468.52586 -81.054194) (xy 470.854278 -78.725776)
			(xy 470.891589 -78.687815) (xy 470.961306 -78.60737) (xy 471.025105 -78.522156) (xy 471.082661 -78.432606)
			(xy 471.13368 -78.339178) (xy 471.177903 -78.242348) (xy 471.215103 -78.142608) (xy 471.245092 -78.040469)
			(xy 471.267716 -77.93645) (xy 471.28286 -77.831082) (xy 471.290447 -77.724901) (xy 471.290904 -77.671676)
			(xy 471.290904 -13.780008) (xy 471.290383 -13.724238) (xy 471.282048 -13.613011) (xy 471.265425 -13.502718)
			(xy 471.240606 -13.393975) (xy 471.20773 -13.287391) (xy 471.166981 -13.183562) (xy 471.118587 -13.083068)
			(xy 471.062818 -12.986472) (xy 470.999987 -12.894314) (xy 470.930444 -12.807108) (xy 470.854579 -12.725344)
			(xy 470.772816 -12.649477) (xy 470.685612 -12.579932) (xy 470.593455 -12.517099) (xy 470.49686 -12.461328)
			(xy 470.396367 -12.412932) (xy 470.292539 -12.372181) (xy 470.185956 -12.339303) (xy 470.077214 -12.314481)
			(xy 469.966921 -12.297855) (xy 469.855694 -12.289518) (xy 469.799924 -12.289028) (xy 464.613244 -12.289028)
			(xy 464.613244 -12.288012) (xy 464.272376 -12.288012) (xy 464.272376 -12.289028) (xy 458.20203 -12.289028)
			(xy 458.131647 -12.288544) (xy 457.991102 -12.280653) (xy 457.85122 -12.264894) (xy 457.712443 -12.241316)
			(xy 457.575205 -12.209994) (xy 457.43994 -12.171027) (xy 457.307072 -12.124536) (xy 457.177021 -12.070668)
			(xy 457.050194 -12.009593) (xy 456.926991 -11.941503) (xy 456.8078 -11.866612) (xy 456.692996 -11.785156)
			(xy 456.582939 -11.69739) (xy 456.477977 -11.603592) (xy 456.378439 -11.504056) (xy 456.284639 -11.399096)
			(xy 456.196872 -11.289041) (xy 456.115413 -11.174238) (xy 456.04052 -11.055048) (xy 455.972428 -10.931847)
			(xy 455.911351 -10.805021) (xy 455.857481 -10.674971) (xy 455.810987 -10.542104) (xy 455.772017 -10.406839)
			(xy 455.740693 -10.269603) (xy 455.717113 -10.130825) (xy 455.701351 -9.990944) (xy 455.693457 -9.850399)
			(xy 455.693018 -9.780016) (xy 455.693018 -0.999998) (xy 455.692493 -0.967851) (xy 455.684101 -0.904107)
			(xy 455.667461 -0.842004) (xy 455.642857 -0.782603) (xy 455.610712 -0.726922) (xy 455.571573 -0.675913)
			(xy 455.526112 -0.630449) (xy 455.475106 -0.591307) (xy 455.419427 -0.559158) (xy 455.360029 -0.53455)
			(xy 455.297926 -0.517906) (xy 455.234183 -0.50951) (xy 455.202036 -0.509016) (xy 388.601966 -0.509016)
			(xy 388.569821 -0.509544) (xy 388.506082 -0.517939) (xy 388.443984 -0.534582) (xy 388.384589 -0.559188)
			(xy 388.328914 -0.591335) (xy 388.277911 -0.630474) (xy 388.232453 -0.675936) (xy 388.193318 -0.726941)
			(xy 388.161174 -0.782618) (xy 388.136572 -0.842014) (xy 388.119933 -0.904114) (xy 388.111542 -0.967853)
			(xy 388.110984 -0.999998) (xy 388.110984 -5.169916) (xy 388.850131 -5.169916) (xy 388.854136 -5.082008)
			(xy 388.866119 -4.994828) (xy 388.885979 -4.909099) (xy 388.913554 -4.825531) (xy 388.948613 -4.744817)
			(xy 388.990866 -4.667625) (xy 389.039964 -4.594596) (xy 389.0955 -4.526334) (xy 389.157012 -4.463404)
			(xy 389.223993 -4.40633) (xy 389.295886 -4.355582) (xy 389.372095 -4.311582) (xy 389.45199 -4.274695)
			(xy 389.534909 -4.245226) (xy 389.620164 -4.223419) (xy 389.707048 -4.209455) (xy 389.794842 -4.203449)
			(xy 389.882819 -4.205453) (xy 389.970249 -4.215448) (xy 390.056408 -4.233352) (xy 390.140582 -4.259016)
			(xy 390.222073 -4.292229) (xy 390.300207 -4.332715) (xy 390.374335 -4.380137) (xy 390.443843 -4.434104)
			(xy 390.508157 -4.494169) (xy 390.566741 -4.559833) (xy 390.619112 -4.630552) (xy 390.664835 -4.70574)
			(xy 390.703532 -4.784775) (xy 390.734881 -4.867001) (xy 390.758623 -4.951737) (xy 390.763638 -4.978969)
			(xy 394.947631 -4.978969) (xy 394.947631 -4.924431) (xy 394.955393 -4.870448) (xy 394.970758 -4.81812)
			(xy 394.993414 -4.76851) (xy 395.0229 -4.72263) (xy 395.058614 -4.681413) (xy 395.099832 -4.645698)
			(xy 395.145712 -4.616213) (xy 395.195321 -4.593557) (xy 395.24765 -4.578193) (xy 395.301633 -4.570431)
			(xy 395.328902 -4.569968) (xy 396.192502 -4.569968) (xy 396.219773 -4.570395) (xy 396.273761 -4.578157)
			(xy 396.326094 -4.593524) (xy 396.375708 -4.616182) (xy 396.421593 -4.64567) (xy 396.462813 -4.681388)
			(xy 396.498531 -4.722609) (xy 396.528019 -4.768493) (xy 396.550677 -4.818107) (xy 396.566043 -4.870441)
			(xy 396.573806 -4.924429) (xy 396.573806 -4.978971) (xy 398.547532 -4.978971) (xy 398.547532 -4.924429)
			(xy 398.555294 -4.870443) (xy 398.570661 -4.818111) (xy 398.593321 -4.768498) (xy 398.62281 -4.722616)
			(xy 398.658529 -4.681398) (xy 398.699751 -4.645684) (xy 398.745637 -4.616199) (xy 398.795252 -4.593546)
			(xy 398.847586 -4.578185) (xy 398.901573 -4.570428) (xy 398.928844 -4.569968) (xy 399.792444 -4.569968)
			(xy 399.819713 -4.570398) (xy 399.873697 -4.578165) (xy 399.926025 -4.593535) (xy 399.975633 -4.616196)
			(xy 400.021512 -4.645685) (xy 400.062728 -4.681403) (xy 400.098441 -4.722623) (xy 400.127925 -4.768505)
			(xy 400.15058 -4.818116) (xy 400.165944 -4.870447) (xy 400.173706 -4.92443) (xy 400.173706 -4.978967)
			(xy 402.147554 -4.978967) (xy 402.147554 -4.924433) (xy 402.155315 -4.870455) (xy 402.170678 -4.818131)
			(xy 402.193332 -4.768526) (xy 402.222814 -4.722649) (xy 402.258525 -4.681435) (xy 402.299738 -4.645722)
			(xy 402.345613 -4.616239) (xy 402.395218 -4.593583) (xy 402.447542 -4.578218) (xy 402.501519 -4.570455)
			(xy 402.528786 -4.569968) (xy 403.392386 -4.569968) (xy 403.41966 -4.570371) (xy 403.473652 -4.578132)
			(xy 403.525991 -4.593498) (xy 403.57561 -4.616157) (xy 403.621499 -4.645646) (xy 403.662724 -4.681366)
			(xy 403.698445 -4.72259) (xy 403.727937 -4.768478) (xy 403.750597 -4.818096) (xy 403.765965 -4.870434)
			(xy 403.773728 -4.924426) (xy 403.773728 -4.978966) (xy 405.747754 -4.978966) (xy 405.747754 -4.924434)
			(xy 405.755515 -4.870456) (xy 405.770878 -4.818132) (xy 405.793531 -4.768527) (xy 405.823013 -4.72265)
			(xy 405.858724 -4.681436) (xy 405.899936 -4.645724) (xy 405.945811 -4.61624) (xy 405.995415 -4.593584)
			(xy 406.047738 -4.578219) (xy 406.101716 -4.570456) (xy 406.128982 -4.569968) (xy 406.992582 -4.569968)
			(xy 407.019856 -4.57037) (xy 407.073849 -4.578131) (xy 407.126188 -4.593497) (xy 407.175807 -4.616155)
			(xy 407.221697 -4.645645) (xy 407.262922 -4.681365) (xy 407.298644 -4.722589) (xy 407.328136 -4.768477)
			(xy 407.350797 -4.818095) (xy 407.366165 -4.870433) (xy 407.373928 -4.924426) (xy 407.373928 -4.978971)
			(xy 414.857632 -4.978971) (xy 414.857632 -4.924429) (xy 414.865394 -4.870442) (xy 414.880762 -4.81811)
			(xy 414.903421 -4.768498) (xy 414.93291 -4.722616) (xy 414.96863 -4.681397) (xy 415.009852 -4.645683)
			(xy 415.055738 -4.616199) (xy 415.105353 -4.593546) (xy 415.157687 -4.578184) (xy 415.211675 -4.570428)
			(xy 415.238946 -4.569968) (xy 416.102546 -4.569968) (xy 416.129815 -4.570398) (xy 416.183798 -4.578165)
			(xy 416.236126 -4.593536) (xy 416.285735 -4.616196) (xy 416.331613 -4.645686) (xy 416.372829 -4.681404)
			(xy 416.408542 -4.722624) (xy 416.438026 -4.768506) (xy 416.46068 -4.818117) (xy 416.476045 -4.870447)
			(xy 416.483806 -4.924431) (xy 416.483806 -4.978967) (xy 418.457654 -4.978967) (xy 418.457654 -4.924433)
			(xy 418.465415 -4.870455) (xy 418.480779 -4.818131) (xy 418.503432 -4.768525) (xy 418.532915 -4.722648)
			(xy 418.568626 -4.681434) (xy 418.609839 -4.645722) (xy 418.655715 -4.616238) (xy 418.705319 -4.593583)
			(xy 418.757643 -4.578218) (xy 418.811621 -4.570455) (xy 418.838888 -4.569968) (xy 419.702488 -4.569968)
			(xy 419.729762 -4.570371) (xy 419.783754 -4.578132) (xy 419.836092 -4.593499) (xy 419.885711 -4.616157)
			(xy 419.9316 -4.645647) (xy 419.972824 -4.681367) (xy 420.008546 -4.722591) (xy 420.038037 -4.768479)
			(xy 420.060697 -4.818096) (xy 420.076065 -4.870434) (xy 420.083828 -4.924426) (xy 420.083828 -4.978966)
			(xy 426.067754 -4.978966) (xy 426.067754 -4.924434) (xy 426.075515 -4.870456) (xy 426.090878 -4.818132)
			(xy 426.113531 -4.768527) (xy 426.143013 -4.72265) (xy 426.178724 -4.681436) (xy 426.219936 -4.645724)
			(xy 426.265811 -4.61624) (xy 426.315415 -4.593584) (xy 426.367738 -4.578219) (xy 426.421716 -4.570456)
			(xy 426.448982 -4.569968) (xy 427.312582 -4.569968) (xy 427.339856 -4.57037) (xy 427.393849 -4.578131)
			(xy 427.446188 -4.593497) (xy 427.495807 -4.616155) (xy 427.541697 -4.645645) (xy 427.582922 -4.681365)
			(xy 427.618644 -4.722589) (xy 427.648136 -4.768477) (xy 427.670797 -4.818095) (xy 427.686165 -4.870433)
			(xy 427.693928 -4.924426) (xy 427.693928 -4.97897) (xy 429.667631 -4.97897) (xy 429.667631 -4.92443)
			(xy 429.675394 -4.870445) (xy 429.69076 -4.818115) (xy 429.713417 -4.768504) (xy 429.742905 -4.722623)
			(xy 429.778622 -4.681405) (xy 429.819842 -4.645691) (xy 429.865725 -4.616206) (xy 429.915337 -4.593552)
			(xy 429.967669 -4.578189) (xy 430.021654 -4.57043) (xy 430.048924 -4.569968) (xy 430.912524 -4.569968)
			(xy 430.939794 -4.570396) (xy 430.99378 -4.578161) (xy 431.04611 -4.59353) (xy 431.095721 -4.616189)
			(xy 431.141603 -4.645678) (xy 431.182821 -4.681396) (xy 431.218536 -4.722616) (xy 431.248022 -4.7685)
			(xy 431.270679 -4.818112) (xy 431.286044 -4.870444) (xy 431.293806 -4.92443) (xy 431.293806 -4.97897)
			(xy 431.286044 -5.032956) (xy 431.270679 -5.085288) (xy 431.248022 -5.1349) (xy 431.218536 -5.180784)
			(xy 431.182821 -5.222004) (xy 431.141603 -5.257722) (xy 431.095721 -5.287211) (xy 431.04611 -5.30987)
			(xy 430.99378 -5.325239) (xy 430.939794 -5.333004) (xy 430.912524 -5.333492) (xy 430.048924 -5.333492)
			(xy 430.021654 -5.33297) (xy 429.967669 -5.325211) (xy 429.915337 -5.309848) (xy 429.865725 -5.287194)
			(xy 429.819842 -5.257709) (xy 429.778622 -5.221995) (xy 429.742905 -5.180777) (xy 429.713417 -5.134896)
			(xy 429.69076 -5.085285) (xy 429.675394 -5.032955) (xy 429.667631 -4.97897) (xy 427.693928 -4.97897)
			(xy 427.693928 -4.978974) (xy 427.686165 -5.032967) (xy 427.670797 -5.085305) (xy 427.648136 -5.134923)
			(xy 427.618644 -5.180811) (xy 427.582922 -5.222035) (xy 427.541697 -5.257755) (xy 427.495807 -5.287245)
			(xy 427.446188 -5.309903) (xy 427.393849 -5.325269) (xy 427.339856 -5.33303) (xy 427.312582 -5.333492)
			(xy 426.448982 -5.333492) (xy 426.421716 -5.332944) (xy 426.367738 -5.325181) (xy 426.315415 -5.309816)
			(xy 426.265811 -5.28716) (xy 426.219936 -5.257676) (xy 426.178724 -5.221964) (xy 426.143013 -5.18075)
			(xy 426.113531 -5.134873) (xy 426.090878 -5.085268) (xy 426.075515 -5.032944) (xy 426.067754 -4.978966)
			(xy 420.083828 -4.978966) (xy 420.083828 -4.978974) (xy 420.076065 -5.032966) (xy 420.060697 -5.085304)
			(xy 420.038037 -5.134921) (xy 420.008546 -5.180809) (xy 419.972824 -5.222033) (xy 419.9316 -5.257753)
			(xy 419.885711 -5.287243) (xy 419.836092 -5.309901) (xy 419.783754 -5.325268) (xy 419.729762 -5.333029)
			(xy 419.702488 -5.333492) (xy 418.838888 -5.333492) (xy 418.811621 -5.332945) (xy 418.757643 -5.325182)
			(xy 418.705319 -5.309817) (xy 418.655715 -5.287162) (xy 418.609839 -5.257678) (xy 418.568626 -5.221966)
			(xy 418.532915 -5.180752) (xy 418.503432 -5.134875) (xy 418.480779 -5.085269) (xy 418.465415 -5.032945)
			(xy 418.457654 -4.978967) (xy 416.483806 -4.978967) (xy 416.483806 -4.978969) (xy 416.476045 -5.032953)
			(xy 416.46068 -5.085283) (xy 416.438026 -5.134894) (xy 416.408542 -5.180776) (xy 416.372829 -5.221996)
			(xy 416.331613 -5.257714) (xy 416.285735 -5.287204) (xy 416.236126 -5.309864) (xy 416.183798 -5.325235)
			(xy 416.129815 -5.333002) (xy 416.102546 -5.333492) (xy 415.238946 -5.333492) (xy 415.211675 -5.332972)
			(xy 415.157687 -5.325216) (xy 415.105353 -5.309854) (xy 415.055738 -5.287201) (xy 415.009852 -5.257717)
			(xy 414.96863 -5.222003) (xy 414.93291 -5.180784) (xy 414.903421 -5.134902) (xy 414.880762 -5.08529)
			(xy 414.865394 -5.032958) (xy 414.857632 -4.978971) (xy 407.373928 -4.978971) (xy 407.373928 -4.978974)
			(xy 407.366165 -5.032967) (xy 407.350797 -5.085305) (xy 407.328136 -5.134923) (xy 407.298644 -5.180811)
			(xy 407.262922 -5.222035) (xy 407.221697 -5.257755) (xy 407.175807 -5.287245) (xy 407.126188 -5.309903)
			(xy 407.073849 -5.325269) (xy 407.019856 -5.33303) (xy 406.992582 -5.333492) (xy 406.128982 -5.333492)
			(xy 406.101716 -5.332944) (xy 406.047738 -5.325181) (xy 405.995415 -5.309816) (xy 405.945811 -5.28716)
			(xy 405.899936 -5.257676) (xy 405.858724 -5.221964) (xy 405.823013 -5.18075) (xy 405.793531 -5.134873)
			(xy 405.770878 -5.085268) (xy 405.755515 -5.032944) (xy 405.747754 -4.978966) (xy 403.773728 -4.978966)
			(xy 403.773728 -4.978974) (xy 403.765965 -5.032966) (xy 403.750597 -5.085304) (xy 403.727937 -5.134922)
			(xy 403.698445 -5.18081) (xy 403.662724 -5.222034) (xy 403.621499 -5.257754) (xy 403.57561 -5.287243)
			(xy 403.525991 -5.309902) (xy 403.473652 -5.325268) (xy 403.41966 -5.333029) (xy 403.392386 -5.333492)
			(xy 402.528786 -5.333492) (xy 402.501519 -5.332945) (xy 402.447542 -5.325182) (xy 402.395218 -5.309817)
			(xy 402.345613 -5.287161) (xy 402.299738 -5.257678) (xy 402.258525 -5.221965) (xy 402.222814 -5.180751)
			(xy 402.193332 -5.134874) (xy 402.170678 -5.085269) (xy 402.155315 -5.032945) (xy 402.147554 -4.978967)
			(xy 400.173706 -4.978967) (xy 400.173706 -4.97897) (xy 400.165944 -5.032953) (xy 400.15058 -5.085284)
			(xy 400.127925 -5.134895) (xy 400.098441 -5.180777) (xy 400.062728 -5.221997) (xy 400.021512 -5.257715)
			(xy 399.975633 -5.287204) (xy 399.926025 -5.309865) (xy 399.873697 -5.325235) (xy 399.819713 -5.333002)
			(xy 399.792444 -5.333492) (xy 398.928844 -5.333492) (xy 398.901573 -5.332972) (xy 398.847586 -5.325215)
			(xy 398.795252 -5.309854) (xy 398.745637 -5.287201) (xy 398.699751 -5.257716) (xy 398.658529 -5.222002)
			(xy 398.62281 -5.180784) (xy 398.593321 -5.134902) (xy 398.570661 -5.085289) (xy 398.555294 -5.032957)
			(xy 398.547532 -4.978971) (xy 396.573806 -4.978971) (xy 396.566043 -5.032959) (xy 396.550677 -5.085293)
			(xy 396.528019 -5.134907) (xy 396.498531 -5.180791) (xy 396.462813 -5.222012) (xy 396.421593 -5.25773)
			(xy 396.375708 -5.287218) (xy 396.326094 -5.309876) (xy 396.273761 -5.325243) (xy 396.219773 -5.333005)
			(xy 396.192502 -5.333492) (xy 395.328902 -5.333492) (xy 395.301633 -5.332969) (xy 395.24765 -5.325207)
			(xy 395.195321 -5.309843) (xy 395.145712 -5.287187) (xy 395.099832 -5.257702) (xy 395.058614 -5.221987)
			(xy 395.0229 -5.18077) (xy 394.993414 -5.13489) (xy 394.970758 -5.08528) (xy 394.955393 -5.032952)
			(xy 394.947631 -4.978969) (xy 390.763638 -4.978969) (xy 390.774561 -5.038281) (xy 390.782563 -5.125916)
			(xy 390.783064 -5.169916) (xy 390.782563 -5.213916) (xy 390.774561 -5.301551) (xy 390.758623 -5.388095)
			(xy 390.734881 -5.472831) (xy 390.703532 -5.555057) (xy 390.664835 -5.634092) (xy 390.619112 -5.70928)
			(xy 390.566741 -5.779999) (xy 390.508157 -5.845663) (xy 390.443843 -5.905728) (xy 390.374335 -5.959695)
			(xy 390.300207 -6.007117) (xy 390.222073 -6.047603) (xy 390.140582 -6.080816) (xy 390.056408 -6.10648)
			(xy 389.970249 -6.124384) (xy 389.882819 -6.134379) (xy 389.794842 -6.136383) (xy 389.707048 -6.130377)
			(xy 389.620164 -6.116413) (xy 389.534909 -6.094606) (xy 389.45199 -6.065137) (xy 389.372095 -6.02825)
			(xy 389.295886 -5.98425) (xy 389.223993 -5.933502) (xy 389.157012 -5.876428) (xy 389.0955 -5.813498)
			(xy 389.039964 -5.745236) (xy 388.990866 -5.672207) (xy 388.948613 -5.595015) (xy 388.913554 -5.514301)
			(xy 388.885979 -5.430733) (xy 388.866119 -5.345004) (xy 388.854136 -5.257824) (xy 388.850131 -5.169916)
			(xy 388.110984 -5.169916) (xy 388.110984 -6.169914) (xy 453.015103 -6.169914) (xy 453.019108 -6.082006)
			(xy 453.031091 -5.994826) (xy 453.050951 -5.909097) (xy 453.078526 -5.825529) (xy 453.113585 -5.744815)
			(xy 453.155838 -5.667623) (xy 453.204936 -5.594594) (xy 453.260472 -5.526332) (xy 453.321984 -5.463402)
			(xy 453.388965 -5.406328) (xy 453.460858 -5.35558) (xy 453.537067 -5.31158) (xy 453.616962 -5.274693)
			(xy 453.699881 -5.245224) (xy 453.785136 -5.223417) (xy 453.87202 -5.209453) (xy 453.959814 -5.203447)
			(xy 454.047791 -5.205451) (xy 454.135221 -5.215446) (xy 454.22138 -5.23335) (xy 454.305554 -5.259014)
			(xy 454.387045 -5.292227) (xy 454.465179 -5.332713) (xy 454.539307 -5.380135) (xy 454.608815 -5.434102)
			(xy 454.673129 -5.494167) (xy 454.731713 -5.559831) (xy 454.784084 -5.63055) (xy 454.829807 -5.705738)
			(xy 454.868504 -5.784773) (xy 454.899853 -5.866999) (xy 454.923595 -5.951735) (xy 454.939533 -6.038279)
			(xy 454.947535 -6.125914) (xy 454.948036 -6.169914) (xy 454.947535 -6.213914) (xy 454.939533 -6.301549)
			(xy 454.923595 -6.388093) (xy 454.899853 -6.472829) (xy 454.868504 -6.555055) (xy 454.829807 -6.63409)
			(xy 454.784084 -6.709278) (xy 454.731713 -6.779997) (xy 454.673129 -6.845661) (xy 454.608815 -6.905726)
			(xy 454.539307 -6.959693) (xy 454.465179 -7.007115) (xy 454.387045 -7.047601) (xy 454.305554 -7.080814)
			(xy 454.22138 -7.106478) (xy 454.135221 -7.124382) (xy 454.047791 -7.134377) (xy 453.959814 -7.136381)
			(xy 453.87202 -7.130375) (xy 453.785136 -7.116411) (xy 453.699881 -7.094604) (xy 453.616962 -7.065135)
			(xy 453.537067 -7.028248) (xy 453.460858 -6.984248) (xy 453.388965 -6.9335) (xy 453.321984 -6.876426)
			(xy 453.260472 -6.813496) (xy 453.204936 -6.745234) (xy 453.155838 -6.672205) (xy 453.113585 -6.595013)
			(xy 453.078526 -6.514299) (xy 453.050951 -6.430731) (xy 453.031091 -6.345002) (xy 453.019108 -6.257822)
			(xy 453.015103 -6.169914) (xy 388.110984 -6.169914) (xy 388.110984 -6.740774) (xy 393.142876 -6.740774)
			(xy 393.142876 -6.686226) (xy 393.150639 -6.632232) (xy 393.166008 -6.579894) (xy 393.18867 -6.530275)
			(xy 393.218162 -6.484387) (xy 393.253885 -6.443163) (xy 393.295112 -6.407443) (xy 393.341003 -6.377954)
			(xy 393.390624 -6.355297) (xy 393.442964 -6.339932) (xy 393.496958 -6.332173) (xy 393.524232 -6.331712)
			(xy 394.387832 -6.331712) (xy 394.415098 -6.332253) (xy 394.469074 -6.340017) (xy 394.521397 -6.355384)
			(xy 394.570999 -6.378041) (xy 394.616873 -6.407526) (xy 394.658084 -6.443238) (xy 394.693794 -6.484452)
			(xy 394.723274 -6.530329) (xy 394.745927 -6.579933) (xy 394.761289 -6.632257) (xy 394.76905 -6.686234)
			(xy 394.76905 -6.740766) (xy 394.769049 -6.74077) (xy 396.742898 -6.74077) (xy 396.742898 -6.68623)
			(xy 396.75066 -6.632245) (xy 396.766025 -6.579914) (xy 396.788681 -6.530302) (xy 396.818166 -6.484419)
			(xy 396.853881 -6.4432) (xy 396.895099 -6.407482) (xy 396.940979 -6.377993) (xy 396.99059 -6.355334)
			(xy 397.04292 -6.339965) (xy 397.096904 -6.3322) (xy 397.124174 -6.331712) (xy 397.987774 -6.331712)
			(xy 398.015044 -6.332226) (xy 398.06903 -6.339984) (xy 398.121363 -6.355347) (xy 398.170976 -6.378002)
			(xy 398.216859 -6.407487) (xy 398.25808 -6.443202) (xy 398.293798 -6.48442) (xy 398.323286 -6.530301)
			(xy 398.345944 -6.579913) (xy 398.36131 -6.632244) (xy 398.369072 -6.68623) (xy 398.369072 -6.74077)
			(xy 398.369071 -6.740774) (xy 400.342776 -6.740774) (xy 400.342776 -6.686226) (xy 400.350539 -6.632234)
			(xy 400.365907 -6.579897) (xy 400.388567 -6.530279) (xy 400.418058 -6.484392) (xy 400.45378 -6.443168)
			(xy 400.495005 -6.407449) (xy 400.540893 -6.377959) (xy 400.590512 -6.355301) (xy 400.64285 -6.339935)
			(xy 400.696842 -6.332174) (xy 400.724116 -6.331712) (xy 401.587716 -6.331712) (xy 401.614983 -6.332251)
			(xy 401.668961 -6.340014) (xy 401.721285 -6.35538) (xy 401.77089 -6.378036) (xy 401.816766 -6.40752)
			(xy 401.857978 -6.443233) (xy 401.89369 -6.484447) (xy 401.923172 -6.530324) (xy 401.945825 -6.57993)
			(xy 401.961189 -6.632255) (xy 401.96895 -6.686233) (xy 401.96895 -6.740767) (xy 401.968949 -6.740773)
			(xy 403.942976 -6.740773) (xy 403.942976 -6.686227) (xy 403.950739 -6.632235) (xy 403.966106 -6.579898)
			(xy 403.988766 -6.53028) (xy 404.018257 -6.484393) (xy 404.053978 -6.44317) (xy 404.095203 -6.40745)
			(xy 404.141091 -6.377961) (xy 404.190709 -6.355302) (xy 404.243047 -6.339936) (xy 404.297039 -6.332175)
			(xy 404.324312 -6.331712) (xy 405.187912 -6.331712) (xy 405.215179 -6.332251) (xy 405.269158 -6.340014)
			(xy 405.321482 -6.355379) (xy 405.371087 -6.378034) (xy 405.416964 -6.407519) (xy 405.458177 -6.443231)
			(xy 405.493889 -6.484446) (xy 405.523371 -6.530323) (xy 405.546025 -6.579929) (xy 405.561389 -6.632254)
			(xy 405.56915 -6.686233) (xy 405.56915 -6.740767) (xy 405.56915 -6.74077) (xy 413.052998 -6.74077)
			(xy 413.052998 -6.68623) (xy 413.06076 -6.632245) (xy 413.076125 -6.579914) (xy 413.098781 -6.530302)
			(xy 413.128267 -6.484419) (xy 413.163982 -6.443199) (xy 413.205199 -6.407481) (xy 413.25108 -6.377993)
			(xy 413.300691 -6.355334) (xy 413.353021 -6.339965) (xy 413.407006 -6.3322) (xy 413.434276 -6.331712)
			(xy 414.297876 -6.331712) (xy 414.325146 -6.332226) (xy 414.379132 -6.339985) (xy 414.431464 -6.355348)
			(xy 414.481077 -6.378002) (xy 414.52696 -6.407487) (xy 414.568181 -6.443202) (xy 414.603898 -6.48442)
			(xy 414.633386 -6.530302) (xy 414.656044 -6.579913) (xy 414.67141 -6.632244) (xy 414.679173 -6.68623)
			(xy 414.679173 -6.74077) (xy 414.679172 -6.740774) (xy 416.652876 -6.740774) (xy 416.652876 -6.686226)
			(xy 416.660639 -6.632234) (xy 416.676007 -6.579897) (xy 416.698667 -6.530279) (xy 416.728159 -6.484391)
			(xy 416.763881 -6.443168) (xy 416.805106 -6.407448) (xy 416.850995 -6.377959) (xy 416.900613 -6.355301)
			(xy 416.952952 -6.339935) (xy 417.006944 -6.332174) (xy 417.034218 -6.331712) (xy 417.897818 -6.331712)
			(xy 417.925085 -6.332252) (xy 417.979063 -6.340015) (xy 418.031386 -6.355381) (xy 418.080991 -6.378036)
			(xy 418.126867 -6.407521) (xy 418.168079 -6.443234) (xy 418.20379 -6.484448) (xy 418.233272 -6.530325)
			(xy 418.255926 -6.57993) (xy 418.271289 -6.632255) (xy 418.27905 -6.686233) (xy 418.27905 -6.740767)
			(xy 418.279049 -6.740773) (xy 424.262976 -6.740773) (xy 424.262976 -6.686227) (xy 424.270739 -6.632235)
			(xy 424.286106 -6.579898) (xy 424.308766 -6.53028) (xy 424.338257 -6.484393) (xy 424.373978 -6.44317)
			(xy 424.415203 -6.40745) (xy 424.461091 -6.377961) (xy 424.510709 -6.355302) (xy 424.563047 -6.339936)
			(xy 424.617039 -6.332175) (xy 424.644312 -6.331712) (xy 425.507912 -6.331712) (xy 425.535179 -6.332251)
			(xy 425.589158 -6.340014) (xy 425.641482 -6.355379) (xy 425.691087 -6.378034) (xy 425.736964 -6.407519)
			(xy 425.778177 -6.443231) (xy 425.813889 -6.484446) (xy 425.843371 -6.530323) (xy 425.866025 -6.579929)
			(xy 425.881389 -6.632254) (xy 425.88915 -6.686233) (xy 425.88915 -6.740767) (xy 425.88915 -6.740769)
			(xy 427.862998 -6.740769) (xy 427.862998 -6.686231) (xy 427.870759 -6.632248) (xy 427.886123 -6.579918)
			(xy 427.908778 -6.530308) (xy 427.938261 -6.484426) (xy 427.973974 -6.443207) (xy 428.015189 -6.407489)
			(xy 428.061067 -6.378) (xy 428.110675 -6.35534) (xy 428.163003 -6.339969) (xy 428.216985 -6.332202)
			(xy 428.244254 -6.331712) (xy 429.107854 -6.331712) (xy 429.135125 -6.332224) (xy 429.189113 -6.339981)
			(xy 429.241448 -6.355342) (xy 429.291064 -6.377995) (xy 429.33695 -6.40748) (xy 429.378173 -6.443195)
			(xy 429.413893 -6.484413) (xy 429.443383 -6.530296) (xy 429.466042 -6.579909) (xy 429.48141 -6.632242)
			(xy 429.489172 -6.686229) (xy 429.489172 -6.740771) (xy 429.488151 -6.747873) (xy 431.473788 -6.747873)
			(xy 431.473788 -6.693327) (xy 431.48155 -6.639337) (xy 431.496918 -6.587001) (xy 431.519578 -6.537385)
			(xy 431.549068 -6.491498) (xy 431.584789 -6.450276) (xy 431.626013 -6.414558) (xy 431.6719 -6.385069)
			(xy 431.721518 -6.362412) (xy 431.773854 -6.347047) (xy 431.827845 -6.339286) (xy 431.855118 -6.338824)
			(xy 432.718718 -6.338824) (xy 432.745986 -6.33934) (xy 432.799965 -6.347103) (xy 432.852291 -6.362469)
			(xy 432.901897 -6.385126) (xy 432.947774 -6.414611) (xy 432.988988 -6.450325) (xy 433.0247 -6.491541)
			(xy 433.054183 -6.537419) (xy 433.076837 -6.587026) (xy 433.092201 -6.639352) (xy 433.099962 -6.693332)
			(xy 433.099962 -6.740771) (xy 445.457798 -6.740771) (xy 445.457798 -6.686229) (xy 445.46556 -6.632243)
			(xy 445.480926 -6.579911) (xy 445.503583 -6.530298) (xy 445.53307 -6.484415) (xy 445.568786 -6.443195)
			(xy 445.610005 -6.407477) (xy 445.655888 -6.377989) (xy 445.7055 -6.35533) (xy 445.757831 -6.339963)
			(xy 445.811817 -6.332199) (xy 445.839088 -6.331712) (xy 446.702688 -6.331712) (xy 446.729958 -6.332227)
			(xy 446.783942 -6.339987) (xy 446.836273 -6.355351) (xy 446.885884 -6.378006) (xy 446.931766 -6.407492)
			(xy 446.972985 -6.443207) (xy 447.008701 -6.484424) (xy 447.038188 -6.530305) (xy 447.060845 -6.579916)
			(xy 447.076211 -6.632246) (xy 447.083973 -6.68623) (xy 447.083973 -6.74077) (xy 447.076211 -6.794754)
			(xy 447.060845 -6.847084) (xy 447.038188 -6.896695) (xy 447.008701 -6.942576) (xy 446.972985 -6.983793)
			(xy 446.931766 -7.019508) (xy 446.885884 -7.048994) (xy 446.836273 -7.071649) (xy 446.783942 -7.087013)
			(xy 446.729958 -7.094773) (xy 446.702688 -7.095236) (xy 445.839088 -7.095236) (xy 445.811817 -7.094801)
			(xy 445.757831 -7.087037) (xy 445.7055 -7.07167) (xy 445.655888 -7.049011) (xy 445.610005 -7.019523)
			(xy 445.568786 -6.983805) (xy 445.53307 -6.942585) (xy 445.503583 -6.896702) (xy 445.480926 -6.847089)
			(xy 445.46556 -6.794757) (xy 445.457798 -6.740771) (xy 433.099962 -6.740771) (xy 433.099962 -6.747868)
			(xy 433.092201 -6.801848) (xy 433.076837 -6.854174) (xy 433.054183 -6.903781) (xy 433.0247 -6.949659)
			(xy 432.988988 -6.990875) (xy 432.947774 -7.026589) (xy 432.901897 -7.056074) (xy 432.852291 -7.078731)
			(xy 432.799965 -7.094097) (xy 432.745986 -7.10186) (xy 432.718718 -7.102348) (xy 431.855118 -7.102348)
			(xy 431.827845 -7.101914) (xy 431.773854 -7.094153) (xy 431.721518 -7.078788) (xy 431.6719 -7.056131)
			(xy 431.626013 -7.026642) (xy 431.584789 -6.990924) (xy 431.549068 -6.949702) (xy 431.519578 -6.903815)
			(xy 431.496918 -6.854199) (xy 431.48155 -6.801863) (xy 431.473788 -6.747873) (xy 429.488151 -6.747873)
			(xy 429.48141 -6.794758) (xy 429.466042 -6.847091) (xy 429.443383 -6.896704) (xy 429.413893 -6.942587)
			(xy 429.378173 -6.983805) (xy 429.33695 -7.01952) (xy 429.291064 -7.049005) (xy 429.241448 -7.071658)
			(xy 429.189113 -7.087019) (xy 429.135125 -7.094776) (xy 429.107854 -7.095236) (xy 428.244254 -7.095236)
			(xy 428.216985 -7.094798) (xy 428.163003 -7.087031) (xy 428.110675 -7.07166) (xy 428.061067 -7.049)
			(xy 428.015189 -7.019511) (xy 427.973974 -6.983793) (xy 427.938261 -6.942574) (xy 427.908778 -6.896692)
			(xy 427.886123 -6.847082) (xy 427.870759 -6.794752) (xy 427.862998 -6.740769) (xy 425.88915 -6.740769)
			(xy 425.881389 -6.794746) (xy 425.866025 -6.847071) (xy 425.843371 -6.896677) (xy 425.813889 -6.942554)
			(xy 425.778177 -6.983769) (xy 425.736964 -7.019481) (xy 425.691087 -7.048966) (xy 425.641482 -7.071621)
			(xy 425.589158 -7.086986) (xy 425.535179 -7.094749) (xy 425.507912 -7.095236) (xy 424.644312 -7.095236)
			(xy 424.617039 -7.094825) (xy 424.563047 -7.087064) (xy 424.510709 -7.071698) (xy 424.461091 -7.049039)
			(xy 424.415203 -7.01955) (xy 424.373978 -6.98383) (xy 424.338257 -6.942607) (xy 424.308766 -6.89672)
			(xy 424.286106 -6.847102) (xy 424.270739 -6.794765) (xy 424.262976 -6.740773) (xy 418.279049 -6.740773)
			(xy 418.271289 -6.794745) (xy 418.255926 -6.84707) (xy 418.233272 -6.896675) (xy 418.20379 -6.942552)
			(xy 418.168079 -6.983766) (xy 418.126867 -7.019479) (xy 418.080991 -7.048964) (xy 418.031386 -7.071619)
			(xy 417.979063 -7.086985) (xy 417.925085 -7.094748) (xy 417.897818 -7.095236) (xy 417.034218 -7.095236)
			(xy 417.006944 -7.094826) (xy 416.952952 -7.087065) (xy 416.900613 -7.071699) (xy 416.850995 -7.049041)
			(xy 416.805106 -7.019552) (xy 416.763881 -6.983832) (xy 416.728159 -6.942609) (xy 416.698667 -6.896721)
			(xy 416.676007 -6.847103) (xy 416.660639 -6.794766) (xy 416.652876 -6.740774) (xy 414.679172 -6.740774)
			(xy 414.67141 -6.794756) (xy 414.656044 -6.847087) (xy 414.633386 -6.896698) (xy 414.603898 -6.94258)
			(xy 414.568181 -6.983798) (xy 414.52696 -7.019513) (xy 414.481077 -7.048998) (xy 414.431464 -7.071652)
			(xy 414.379132 -7.087015) (xy 414.325146 -7.094774) (xy 414.297876 -7.095236) (xy 413.434276 -7.095236)
			(xy 413.407006 -7.0948) (xy 413.353021 -7.087035) (xy 413.300691 -7.071666) (xy 413.25108 -7.049007)
			(xy 413.205199 -7.019519) (xy 413.163982 -6.983801) (xy 413.128267 -6.942581) (xy 413.098781 -6.896698)
			(xy 413.076125 -6.847086) (xy 413.06076 -6.794755) (xy 413.052998 -6.74077) (xy 405.56915 -6.74077)
			(xy 405.561389 -6.794746) (xy 405.546025 -6.847071) (xy 405.523371 -6.896677) (xy 405.493889 -6.942554)
			(xy 405.458177 -6.983769) (xy 405.416964 -7.019481) (xy 405.371087 -7.048966) (xy 405.321482 -7.071621)
			(xy 405.269158 -7.086986) (xy 405.215179 -7.094749) (xy 405.187912 -7.095236) (xy 404.324312 -7.095236)
			(xy 404.297039 -7.094825) (xy 404.243047 -7.087064) (xy 404.190709 -7.071698) (xy 404.141091 -7.049039)
			(xy 404.095203 -7.01955) (xy 404.053978 -6.98383) (xy 404.018257 -6.942607) (xy 403.988766 -6.89672)
			(xy 403.966106 -6.847102) (xy 403.950739 -6.794765) (xy 403.942976 -6.740773) (xy 401.968949 -6.740773)
			(xy 401.961189 -6.794745) (xy 401.945825 -6.84707) (xy 401.923172 -6.896676) (xy 401.89369 -6.942553)
			(xy 401.857978 -6.983767) (xy 401.816766 -7.01948) (xy 401.77089 -7.048964) (xy 401.721285 -7.07162)
			(xy 401.668961 -7.086986) (xy 401.614983 -7.094749) (xy 401.587716 -7.095236) (xy 400.724116 -7.095236)
			(xy 400.696842 -7.094826) (xy 400.64285 -7.087065) (xy 400.590512 -7.071699) (xy 400.540893 -7.049041)
			(xy 400.495005 -7.019551) (xy 400.45378 -6.983832) (xy 400.418058 -6.942608) (xy 400.388567 -6.896721)
			(xy 400.365907 -6.847103) (xy 400.350539 -6.794766) (xy 400.342776 -6.740774) (xy 398.369071 -6.740774)
			(xy 398.36131 -6.794756) (xy 398.345944 -6.847087) (xy 398.323286 -6.896699) (xy 398.293798 -6.94258)
			(xy 398.25808 -6.983798) (xy 398.216859 -7.019513) (xy 398.170976 -7.048998) (xy 398.121363 -7.071653)
			(xy 398.06903 -7.087016) (xy 398.015044 -7.094774) (xy 397.987774 -7.095236) (xy 397.124174 -7.095236)
			(xy 397.096904 -7.0948) (xy 397.04292 -7.087035) (xy 396.99059 -7.071666) (xy 396.940979 -7.049007)
			(xy 396.895099 -7.019518) (xy 396.853881 -6.9838) (xy 396.818166 -6.942581) (xy 396.788681 -6.896698)
			(xy 396.766025 -6.847086) (xy 396.75066 -6.794755) (xy 396.742898 -6.74077) (xy 394.769049 -6.74077)
			(xy 394.761289 -6.794743) (xy 394.745927 -6.847067) (xy 394.723274 -6.896671) (xy 394.693794 -6.942548)
			(xy 394.658084 -6.983762) (xy 394.616873 -7.019474) (xy 394.570999 -7.048959) (xy 394.521397 -7.071616)
			(xy 394.469074 -7.086983) (xy 394.415098 -7.094747) (xy 394.387832 -7.095236) (xy 393.524232 -7.095236)
			(xy 393.496958 -7.094827) (xy 393.442964 -7.087068) (xy 393.390624 -7.071703) (xy 393.341003 -7.049046)
			(xy 393.295112 -7.019557) (xy 393.253885 -6.983837) (xy 393.218162 -6.942613) (xy 393.18867 -6.896725)
			(xy 393.166008 -6.847106) (xy 393.150639 -6.794768) (xy 393.142876 -6.740774) (xy 388.110984 -6.740774)
			(xy 388.110984 -9.780016) (xy 388.110499 -9.850398) (xy 388.102605 -9.99094) (xy 388.086844 -10.130819)
			(xy 388.063264 -10.269594) (xy 388.03194 -10.406828) (xy 387.992971 -10.54209) (xy 387.946478 -10.674954)
			(xy 387.892609 -10.805003) (xy 387.831533 -10.931826) (xy 387.763442 -11.055026) (xy 387.68855 -11.174213)
			(xy 387.607093 -11.289014) (xy 387.519328 -11.399067) (xy 387.425529 -11.504025) (xy 387.325993 -11.60356)
			(xy 387.221033 -11.697356) (xy 387.110979 -11.78512) (xy 386.996176 -11.866575) (xy 386.876988 -11.941465)
			(xy 386.753787 -12.009554) (xy 386.626963 -12.070627) (xy 386.496913 -12.124494) (xy 386.364048 -12.170984)
			(xy 386.228785 -12.209951) (xy 386.091551 -12.241273) (xy 385.952775 -12.26485) (xy 385.812896 -12.280609)
			(xy 385.672354 -12.2885) (xy 385.601972 -12.289028) (xy 260.800088 -12.289028) (xy 260.744319 -12.28955)
			(xy 260.633094 -12.297886) (xy 260.522803 -12.314511) (xy 260.414062 -12.339331) (xy 260.30748 -12.372208)
			(xy 260.203654 -12.412958) (xy 260.103162 -12.461353) (xy 260.006569 -12.517122) (xy 259.914413 -12.579954)
			(xy 259.82721 -12.649497) (xy 259.745448 -12.725362) (xy 259.669584 -12.807125) (xy 259.601847 -12.892065)
			(xy 431.46197 -12.892065) (xy 431.46197 -12.837535) (xy 431.46973 -12.783559) (xy 431.485093 -12.731238)
			(xy 431.507745 -12.681635) (xy 431.537225 -12.635761) (xy 431.572934 -12.594548) (xy 431.614145 -12.558837)
			(xy 431.660017 -12.529355) (xy 431.709619 -12.5067) (xy 431.76194 -12.491335) (xy 431.815915 -12.483572)
			(xy 431.84318 -12.483084) (xy 432.70678 -12.483084) (xy 432.734055 -12.483454) (xy 432.788051 -12.491215)
			(xy 432.840392 -12.506581) (xy 432.890014 -12.529241) (xy 432.935905 -12.558731) (xy 432.977133 -12.594453)
			(xy 433.012857 -12.635678) (xy 433.04235 -12.681569) (xy 433.065012 -12.731189) (xy 433.080381 -12.78353)
			(xy 433.088144 -12.837525) (xy 433.088144 -12.864846) (xy 445.45631 -12.864846) (xy 445.45631 -12.864592)
			(xy 445.456564 -12.850622) (xy 445.45717 -12.823469) (xy 445.46523 -12.769758) (xy 445.48082 -12.717731)
			(xy 445.503625 -12.668439) (xy 445.533186 -12.622876) (xy 445.568905 -12.581962) (xy 445.610062 -12.546522)
			(xy 445.655826 -12.517273) (xy 445.705273 -12.494804) (xy 445.757405 -12.47957) (xy 445.81117 -12.471876)
			(xy 445.838326 -12.4714) (xy 446.701926 -12.4714) (xy 446.72908 -12.471883) (xy 446.782838 -12.479582)
			(xy 446.834964 -12.494821) (xy 446.884404 -12.517293) (xy 446.93016 -12.546543) (xy 446.971311 -12.581982)
			(xy 447.007024 -12.622895) (xy 447.03658 -12.668455) (xy 447.059381 -12.717744) (xy 447.074968 -12.769766)
			(xy 447.083027 -12.823472) (xy 447.083688 -12.850622) (xy 447.083942 -12.864592) (xy 447.083942 -12.864846)
			(xy 447.083472 -12.892133) (xy 447.0757 -12.946152) (xy 447.06032 -12.998515) (xy 447.037645 -13.048157)
			(xy 447.008137 -13.094067) (xy 446.972397 -13.135311) (xy 446.931151 -13.171049) (xy 446.885239 -13.200555)
			(xy 446.835597 -13.223227) (xy 446.783233 -13.238604) (xy 446.729214 -13.246374) (xy 446.701926 -13.246862)
			(xy 446.679426 -13.246581) (xy 446.634732 -13.241355) (xy 446.612772 -13.236448) (xy 446.60693 -13.234924)
			(xy 445.933322 -13.234924) (xy 445.92748 -13.236448) (xy 445.905519 -13.241348) (xy 445.860825 -13.246566)
			(xy 445.838326 -13.246862) (xy 445.811041 -13.246305) (xy 445.757027 -13.238543) (xy 445.704666 -13.223173)
			(xy 445.655026 -13.200508) (xy 445.609117 -13.17101) (xy 445.567873 -13.135278) (xy 445.532133 -13.094041)
			(xy 445.502626 -13.048137) (xy 445.479952 -12.998501) (xy 445.464572 -12.946144) (xy 445.4568 -12.892131)
			(xy 445.45631 -12.864846) (xy 433.088144 -12.864846) (xy 433.088144 -12.892075) (xy 433.080381 -12.94607)
			(xy 433.065012 -12.998411) (xy 433.04235 -13.048031) (xy 433.012857 -13.093921) (xy 432.977133 -13.135147)
			(xy 432.935905 -13.170869) (xy 432.890014 -13.200359) (xy 432.840392 -13.223019) (xy 432.788051 -13.238385)
			(xy 432.734055 -13.246146) (xy 432.70678 -13.246608) (xy 431.84318 -13.246608) (xy 431.815915 -13.246028)
			(xy 431.76194 -13.238265) (xy 431.709619 -13.2229) (xy 431.660017 -13.200245) (xy 431.614145 -13.170763)
			(xy 431.572934 -13.135052) (xy 431.537225 -13.093839) (xy 431.507745 -13.047965) (xy 431.485093 -12.998362)
			(xy 431.46973 -12.946041) (xy 431.46197 -12.892065) (xy 259.601847 -12.892065) (xy 259.600042 -12.894329)
			(xy 259.537211 -12.986486) (xy 259.481443 -13.08308) (xy 259.43305 -13.183572) (xy 259.392301 -13.287399)
			(xy 259.359426 -13.393981) (xy 259.334607 -13.502722) (xy 259.317984 -13.613014) (xy 259.309649 -13.724239)
			(xy 259.309108 -13.780008) (xy 259.309108 -17.628666) (xy 389.660162 -17.628666) (xy 389.660162 -17.574134)
			(xy 389.667923 -17.520157) (xy 389.683286 -17.467834) (xy 389.705939 -17.41823) (xy 389.73542 -17.372354)
			(xy 389.77113 -17.331141) (xy 389.812342 -17.29543) (xy 389.858216 -17.265946) (xy 389.907819 -17.243291)
			(xy 389.960142 -17.227926) (xy 390.014118 -17.220163) (xy 390.041384 -17.219676) (xy 390.904984 -17.219676)
			(xy 390.932258 -17.220062) (xy 390.986252 -17.227824) (xy 391.038592 -17.24319) (xy 391.088212 -17.265849)
			(xy 391.134103 -17.295339) (xy 391.175329 -17.33106) (xy 391.211051 -17.372285) (xy 391.240543 -17.418174)
			(xy 391.263204 -17.467793) (xy 391.278573 -17.520132) (xy 391.286336 -17.574126) (xy 391.286336 -17.628666)
			(xy 395.248162 -17.628666) (xy 395.248162 -17.574134) (xy 395.255923 -17.520157) (xy 395.271286 -17.467834)
			(xy 395.293939 -17.41823) (xy 395.32342 -17.372354) (xy 395.35913 -17.331141) (xy 395.400342 -17.29543)
			(xy 395.446216 -17.265946) (xy 395.495819 -17.243291) (xy 395.548142 -17.227926) (xy 395.602118 -17.220163)
			(xy 395.629384 -17.219676) (xy 396.492984 -17.219676) (xy 396.520258 -17.220062) (xy 396.574252 -17.227824)
			(xy 396.626592 -17.24319) (xy 396.676212 -17.265849) (xy 396.722103 -17.295339) (xy 396.763329 -17.33106)
			(xy 396.799051 -17.372285) (xy 396.828543 -17.418174) (xy 396.851204 -17.467793) (xy 396.866573 -17.520132)
			(xy 396.874336 -17.574126) (xy 396.874336 -17.628666) (xy 400.836162 -17.628666) (xy 400.836162 -17.574134)
			(xy 400.843923 -17.520157) (xy 400.859286 -17.467834) (xy 400.881939 -17.41823) (xy 400.91142 -17.372354)
			(xy 400.94713 -17.331141) (xy 400.988342 -17.29543) (xy 401.034216 -17.265946) (xy 401.083819 -17.243291)
			(xy 401.136142 -17.227926) (xy 401.190118 -17.220163) (xy 401.217384 -17.219676) (xy 402.080984 -17.219676)
			(xy 402.108258 -17.220062) (xy 402.162252 -17.227824) (xy 402.214592 -17.24319) (xy 402.264212 -17.265849)
			(xy 402.310103 -17.295339) (xy 402.351329 -17.33106) (xy 402.387051 -17.372285) (xy 402.416543 -17.418174)
			(xy 402.439204 -17.467793) (xy 402.454573 -17.520132) (xy 402.462336 -17.574126) (xy 402.462336 -17.628666)
			(xy 406.424162 -17.628666) (xy 406.424162 -17.574134) (xy 406.431923 -17.520157) (xy 406.447286 -17.467834)
			(xy 406.469939 -17.41823) (xy 406.49942 -17.372354) (xy 406.53513 -17.331141) (xy 406.576342 -17.29543)
			(xy 406.622216 -17.265946) (xy 406.671819 -17.243291) (xy 406.724142 -17.227926) (xy 406.778118 -17.220163)
			(xy 406.805384 -17.219676) (xy 407.668984 -17.219676) (xy 407.696258 -17.220062) (xy 407.750252 -17.227824)
			(xy 407.802592 -17.24319) (xy 407.852212 -17.265849) (xy 407.898103 -17.295339) (xy 407.939329 -17.33106)
			(xy 407.975051 -17.372285) (xy 408.004543 -17.418174) (xy 408.027204 -17.467793) (xy 408.042573 -17.520132)
			(xy 408.050336 -17.574126) (xy 408.050336 -17.628666) (xy 412.012162 -17.628666) (xy 412.012162 -17.574134)
			(xy 412.019923 -17.520157) (xy 412.035286 -17.467834) (xy 412.057939 -17.41823) (xy 412.08742 -17.372354)
			(xy 412.12313 -17.331141) (xy 412.164342 -17.29543) (xy 412.210216 -17.265946) (xy 412.259819 -17.243291)
			(xy 412.312142 -17.227926) (xy 412.366118 -17.220163) (xy 412.393384 -17.219676) (xy 413.256984 -17.219676)
			(xy 413.284258 -17.220062) (xy 413.338252 -17.227824) (xy 413.390592 -17.24319) (xy 413.440212 -17.265849)
			(xy 413.486103 -17.295339) (xy 413.527329 -17.33106) (xy 413.563051 -17.372285) (xy 413.592543 -17.418174)
			(xy 413.615204 -17.467793) (xy 413.630573 -17.520132) (xy 413.638336 -17.574126) (xy 413.638336 -17.628667)
			(xy 417.905962 -17.628667) (xy 417.905962 -17.574133) (xy 417.913723 -17.520155) (xy 417.929087 -17.467831)
			(xy 417.951741 -17.418226) (xy 417.981224 -17.372349) (xy 418.016936 -17.331136) (xy 418.058149 -17.295424)
			(xy 418.104026 -17.265941) (xy 418.153631 -17.243287) (xy 418.205955 -17.227923) (xy 418.259933 -17.220162)
			(xy 418.2872 -17.219676) (xy 419.1508 -17.219676) (xy 419.178072 -17.220087) (xy 419.232061 -17.227849)
			(xy 419.284396 -17.243216) (xy 419.334011 -17.265874) (xy 419.379896 -17.295363) (xy 419.421118 -17.331082)
			(xy 419.456837 -17.372304) (xy 419.486326 -17.418189) (xy 419.508984 -17.467804) (xy 419.524351 -17.520139)
			(xy 419.532113 -17.574128) (xy 419.532113 -17.628667) (xy 423.493962 -17.628667) (xy 423.493962 -17.574133)
			(xy 423.501723 -17.520155) (xy 423.517087 -17.467831) (xy 423.539741 -17.418226) (xy 423.569224 -17.372349)
			(xy 423.604936 -17.331136) (xy 423.646149 -17.295424) (xy 423.692026 -17.265941) (xy 423.741631 -17.243287)
			(xy 423.793955 -17.227923) (xy 423.847933 -17.220162) (xy 423.8752 -17.219676) (xy 424.7388 -17.219676)
			(xy 424.766072 -17.220087) (xy 424.820061 -17.227849) (xy 424.872396 -17.243216) (xy 424.922011 -17.265874)
			(xy 424.967896 -17.295363) (xy 425.009118 -17.331082) (xy 425.044837 -17.372304) (xy 425.074326 -17.418189)
			(xy 425.096984 -17.467804) (xy 425.112351 -17.520139) (xy 425.120113 -17.574128) (xy 425.120113 -17.62867)
			(xy 429.11594 -17.62867) (xy 429.11594 -17.57413) (xy 429.123702 -17.520145) (xy 429.139068 -17.467815)
			(xy 429.161726 -17.418204) (xy 429.191214 -17.372324) (xy 429.226932 -17.331107) (xy 429.268152 -17.295393)
			(xy 429.314036 -17.265909) (xy 429.363649 -17.243256) (xy 429.415981 -17.227894) (xy 429.469966 -17.220137)
			(xy 429.497236 -17.219676) (xy 430.360836 -17.219676) (xy 430.388106 -17.220089) (xy 430.442091 -17.227856)
			(xy 430.494422 -17.243226) (xy 430.544032 -17.265886) (xy 430.589913 -17.295376) (xy 430.631131 -17.331095)
			(xy 430.666846 -17.372315) (xy 430.696331 -17.418199) (xy 430.718987 -17.467812) (xy 430.734352 -17.520144)
			(xy 430.742114 -17.57413) (xy 430.742114 -17.62867) (xy 430.734352 -17.682656) (xy 430.718987 -17.734988)
			(xy 430.696331 -17.784601) (xy 430.666846 -17.830485) (xy 430.631131 -17.871705) (xy 430.589913 -17.907424)
			(xy 430.544032 -17.936914) (xy 430.494422 -17.959574) (xy 430.442091 -17.974944) (xy 430.388106 -17.982711)
			(xy 430.360836 -17.9832) (xy 429.497236 -17.9832) (xy 429.469966 -17.982663) (xy 429.415981 -17.974906)
			(xy 429.363649 -17.959544) (xy 429.314036 -17.936891) (xy 429.268152 -17.907407) (xy 429.226932 -17.871693)
			(xy 429.191214 -17.830476) (xy 429.161726 -17.784596) (xy 429.139068 -17.734985) (xy 429.123702 -17.682655)
			(xy 429.11594 -17.62867) (xy 425.120113 -17.62867) (xy 425.120113 -17.628672) (xy 425.112351 -17.682661)
			(xy 425.096984 -17.734996) (xy 425.074326 -17.784611) (xy 425.044837 -17.830496) (xy 425.009118 -17.871718)
			(xy 424.967896 -17.907437) (xy 424.922011 -17.936926) (xy 424.872396 -17.959584) (xy 424.820061 -17.974951)
			(xy 424.766072 -17.982713) (xy 424.7388 -17.9832) (xy 423.8752 -17.9832) (xy 423.847933 -17.982638)
			(xy 423.793955 -17.974877) (xy 423.741631 -17.959513) (xy 423.692026 -17.936859) (xy 423.646149 -17.907376)
			(xy 423.604936 -17.871664) (xy 423.569224 -17.830451) (xy 423.539741 -17.784574) (xy 423.517087 -17.734969)
			(xy 423.501723 -17.682645) (xy 423.493962 -17.628667) (xy 419.532113 -17.628667) (xy 419.532113 -17.628672)
			(xy 419.524351 -17.682661) (xy 419.508984 -17.734996) (xy 419.486326 -17.784611) (xy 419.456837 -17.830496)
			(xy 419.421118 -17.871718) (xy 419.379896 -17.907437) (xy 419.334011 -17.936926) (xy 419.284396 -17.959584)
			(xy 419.232061 -17.974951) (xy 419.178072 -17.982713) (xy 419.1508 -17.9832) (xy 418.2872 -17.9832)
			(xy 418.259933 -17.982638) (xy 418.205955 -17.974877) (xy 418.153631 -17.959513) (xy 418.104026 -17.936859)
			(xy 418.058149 -17.907376) (xy 418.016936 -17.871664) (xy 417.981224 -17.830451) (xy 417.951741 -17.784574)
			(xy 417.929087 -17.734969) (xy 417.913723 -17.682645) (xy 417.905962 -17.628667) (xy 413.638336 -17.628667)
			(xy 413.638336 -17.628674) (xy 413.630573 -17.682668) (xy 413.615204 -17.735007) (xy 413.592543 -17.784626)
			(xy 413.563051 -17.830515) (xy 413.527329 -17.87174) (xy 413.486103 -17.907461) (xy 413.440212 -17.936951)
			(xy 413.390592 -17.95961) (xy 413.338252 -17.974976) (xy 413.284258 -17.982738) (xy 413.256984 -17.9832)
			(xy 412.393384 -17.9832) (xy 412.366118 -17.982637) (xy 412.312142 -17.974874) (xy 412.259819 -17.959509)
			(xy 412.210216 -17.936854) (xy 412.164342 -17.90737) (xy 412.12313 -17.871659) (xy 412.08742 -17.830446)
			(xy 412.057939 -17.78457) (xy 412.035286 -17.734966) (xy 412.019923 -17.682643) (xy 412.012162 -17.628666)
			(xy 408.050336 -17.628666) (xy 408.050336 -17.628674) (xy 408.042573 -17.682668) (xy 408.027204 -17.735007)
			(xy 408.004543 -17.784626) (xy 407.975051 -17.830515) (xy 407.939329 -17.87174) (xy 407.898103 -17.907461)
			(xy 407.852212 -17.936951) (xy 407.802592 -17.95961) (xy 407.750252 -17.974976) (xy 407.696258 -17.982738)
			(xy 407.668984 -17.9832) (xy 406.805384 -17.9832) (xy 406.778118 -17.982637) (xy 406.724142 -17.974874)
			(xy 406.671819 -17.959509) (xy 406.622216 -17.936854) (xy 406.576342 -17.90737) (xy 406.53513 -17.871659)
			(xy 406.49942 -17.830446) (xy 406.469939 -17.78457) (xy 406.447286 -17.734966) (xy 406.431923 -17.682643)
			(xy 406.424162 -17.628666) (xy 402.462336 -17.628666) (xy 402.462336 -17.628674) (xy 402.454573 -17.682668)
			(xy 402.439204 -17.735007) (xy 402.416543 -17.784626) (xy 402.387051 -17.830515) (xy 402.351329 -17.87174)
			(xy 402.310103 -17.907461) (xy 402.264212 -17.936951) (xy 402.214592 -17.95961) (xy 402.162252 -17.974976)
			(xy 402.108258 -17.982738) (xy 402.080984 -17.9832) (xy 401.217384 -17.9832) (xy 401.190118 -17.982637)
			(xy 401.136142 -17.974874) (xy 401.083819 -17.959509) (xy 401.034216 -17.936854) (xy 400.988342 -17.90737)
			(xy 400.94713 -17.871659) (xy 400.91142 -17.830446) (xy 400.881939 -17.78457) (xy 400.859286 -17.734966)
			(xy 400.843923 -17.682643) (xy 400.836162 -17.628666) (xy 396.874336 -17.628666) (xy 396.874336 -17.628674)
			(xy 396.866573 -17.682668) (xy 396.851204 -17.735007) (xy 396.828543 -17.784626) (xy 396.799051 -17.830515)
			(xy 396.763329 -17.87174) (xy 396.722103 -17.907461) (xy 396.676212 -17.936951) (xy 396.626592 -17.95961)
			(xy 396.574252 -17.974976) (xy 396.520258 -17.982738) (xy 396.492984 -17.9832) (xy 395.629384 -17.9832)
			(xy 395.602118 -17.982637) (xy 395.548142 -17.974874) (xy 395.495819 -17.959509) (xy 395.446216 -17.936854)
			(xy 395.400342 -17.90737) (xy 395.35913 -17.871659) (xy 395.32342 -17.830446) (xy 395.293939 -17.78457)
			(xy 395.271286 -17.734966) (xy 395.255923 -17.682643) (xy 395.248162 -17.628666) (xy 391.286336 -17.628666)
			(xy 391.286336 -17.628674) (xy 391.278573 -17.682668) (xy 391.263204 -17.735007) (xy 391.240543 -17.784626)
			(xy 391.211051 -17.830515) (xy 391.175329 -17.87174) (xy 391.134103 -17.907461) (xy 391.088212 -17.936951)
			(xy 391.038592 -17.95961) (xy 390.986252 -17.974976) (xy 390.932258 -17.982738) (xy 390.904984 -17.9832)
			(xy 390.041384 -17.9832) (xy 390.014118 -17.982637) (xy 389.960142 -17.974874) (xy 389.907819 -17.959509)
			(xy 389.858216 -17.936854) (xy 389.812342 -17.90737) (xy 389.77113 -17.871659) (xy 389.73542 -17.830446)
			(xy 389.705939 -17.78457) (xy 389.683286 -17.734966) (xy 389.667923 -17.682643) (xy 389.660162 -17.628666)
			(xy 259.309108 -17.628666) (xy 259.309108 -19.152666) (xy 392.454162 -19.152666) (xy 392.454162 -19.098134)
			(xy 392.461923 -19.044157) (xy 392.477286 -18.991834) (xy 392.499939 -18.94223) (xy 392.52942 -18.896354)
			(xy 392.56513 -18.855141) (xy 392.606342 -18.81943) (xy 392.652216 -18.789946) (xy 392.701819 -18.767291)
			(xy 392.754142 -18.751926) (xy 392.808118 -18.744163) (xy 392.835384 -18.743676) (xy 393.698984 -18.743676)
			(xy 393.726258 -18.744062) (xy 393.780252 -18.751824) (xy 393.832592 -18.76719) (xy 393.882212 -18.789849)
			(xy 393.928103 -18.819339) (xy 393.969329 -18.85506) (xy 394.005051 -18.896285) (xy 394.034543 -18.942174)
			(xy 394.057204 -18.991793) (xy 394.072573 -19.044132) (xy 394.080336 -19.098126) (xy 394.080336 -19.152666)
			(xy 398.042162 -19.152666) (xy 398.042162 -19.098134) (xy 398.049923 -19.044157) (xy 398.065286 -18.991834)
			(xy 398.087939 -18.94223) (xy 398.11742 -18.896354) (xy 398.15313 -18.855141) (xy 398.194342 -18.81943)
			(xy 398.240216 -18.789946) (xy 398.289819 -18.767291) (xy 398.342142 -18.751926) (xy 398.396118 -18.744163)
			(xy 398.423384 -18.743676) (xy 399.286984 -18.743676) (xy 399.314258 -18.744062) (xy 399.368252 -18.751824)
			(xy 399.420592 -18.76719) (xy 399.470212 -18.789849) (xy 399.516103 -18.819339) (xy 399.557329 -18.85506)
			(xy 399.593051 -18.896285) (xy 399.622543 -18.942174) (xy 399.645204 -18.991793) (xy 399.660573 -19.044132)
			(xy 399.668336 -19.098126) (xy 399.668336 -19.152666) (xy 403.630162 -19.152666) (xy 403.630162 -19.098134)
			(xy 403.637923 -19.044157) (xy 403.653286 -18.991834) (xy 403.675939 -18.94223) (xy 403.70542 -18.896354)
			(xy 403.74113 -18.855141) (xy 403.782342 -18.81943) (xy 403.828216 -18.789946) (xy 403.877819 -18.767291)
			(xy 403.930142 -18.751926) (xy 403.984118 -18.744163) (xy 404.011384 -18.743676) (xy 404.874984 -18.743676)
			(xy 404.902258 -18.744062) (xy 404.956252 -18.751824) (xy 405.008592 -18.76719) (xy 405.058212 -18.789849)
			(xy 405.104103 -18.819339) (xy 405.145329 -18.85506) (xy 405.181051 -18.896285) (xy 405.210543 -18.942174)
			(xy 405.233204 -18.991793) (xy 405.248573 -19.044132) (xy 405.256336 -19.098126) (xy 405.256336 -19.152666)
			(xy 409.218162 -19.152666) (xy 409.218162 -19.098134) (xy 409.225923 -19.044157) (xy 409.241286 -18.991834)
			(xy 409.263939 -18.94223) (xy 409.29342 -18.896354) (xy 409.32913 -18.855141) (xy 409.370342 -18.81943)
			(xy 409.416216 -18.789946) (xy 409.465819 -18.767291) (xy 409.518142 -18.751926) (xy 409.572118 -18.744163)
			(xy 409.599384 -18.743676) (xy 410.462984 -18.743676) (xy 410.490258 -18.744062) (xy 410.544252 -18.751824)
			(xy 410.596592 -18.76719) (xy 410.646212 -18.789849) (xy 410.692103 -18.819339) (xy 410.733329 -18.85506)
			(xy 410.769051 -18.896285) (xy 410.798543 -18.942174) (xy 410.821204 -18.991793) (xy 410.836573 -19.044132)
			(xy 410.844336 -19.098126) (xy 410.844336 -19.152667) (xy 415.111962 -19.152667) (xy 415.111962 -19.098133)
			(xy 415.119723 -19.044155) (xy 415.135087 -18.991831) (xy 415.157741 -18.942226) (xy 415.187224 -18.896349)
			(xy 415.222936 -18.855136) (xy 415.264149 -18.819424) (xy 415.310026 -18.789941) (xy 415.359631 -18.767287)
			(xy 415.411955 -18.751923) (xy 415.465933 -18.744162) (xy 415.4932 -18.743676) (xy 416.3568 -18.743676)
			(xy 416.384072 -18.744087) (xy 416.438061 -18.751849) (xy 416.490396 -18.767216) (xy 416.540011 -18.789874)
			(xy 416.585896 -18.819363) (xy 416.627118 -18.855082) (xy 416.662837 -18.896304) (xy 416.692326 -18.942189)
			(xy 416.714984 -18.991804) (xy 416.730351 -19.044139) (xy 416.738113 -19.098128) (xy 416.738113 -19.152667)
			(xy 420.699962 -19.152667) (xy 420.699962 -19.098133) (xy 420.707723 -19.044155) (xy 420.723087 -18.991831)
			(xy 420.745741 -18.942226) (xy 420.775224 -18.896349) (xy 420.810936 -18.855136) (xy 420.852149 -18.819424)
			(xy 420.898026 -18.789941) (xy 420.947631 -18.767287) (xy 420.999955 -18.751923) (xy 421.053933 -18.744162)
			(xy 421.0812 -18.743676) (xy 421.9448 -18.743676) (xy 421.972072 -18.744087) (xy 422.026061 -18.751849)
			(xy 422.078396 -18.767216) (xy 422.128011 -18.789874) (xy 422.173896 -18.819363) (xy 422.215118 -18.855082)
			(xy 422.250837 -18.896304) (xy 422.280326 -18.942189) (xy 422.302984 -18.991804) (xy 422.318351 -19.044139)
			(xy 422.326113 -19.098128) (xy 422.326113 -19.15267) (xy 426.32194 -19.15267) (xy 426.32194 -19.09813)
			(xy 426.329702 -19.044145) (xy 426.345068 -18.991815) (xy 426.367726 -18.942204) (xy 426.397214 -18.896324)
			(xy 426.432932 -18.855107) (xy 426.474152 -18.819393) (xy 426.520036 -18.789909) (xy 426.569649 -18.767256)
			(xy 426.621981 -18.751894) (xy 426.675966 -18.744137) (xy 426.703236 -18.743676) (xy 427.566836 -18.743676)
			(xy 427.594106 -18.744089) (xy 427.648091 -18.751856) (xy 427.700422 -18.767226) (xy 427.750032 -18.789886)
			(xy 427.795913 -18.819376) (xy 427.837131 -18.855095) (xy 427.872846 -18.896315) (xy 427.902331 -18.942199)
			(xy 427.924987 -18.991812) (xy 427.940352 -19.044144) (xy 427.948114 -19.09813) (xy 427.948114 -19.15267)
			(xy 431.90994 -19.15267) (xy 431.90994 -19.09813) (xy 431.917702 -19.044145) (xy 431.933068 -18.991815)
			(xy 431.955726 -18.942204) (xy 431.985214 -18.896324) (xy 432.020932 -18.855107) (xy 432.062152 -18.819393)
			(xy 432.108036 -18.789909) (xy 432.157649 -18.767256) (xy 432.209981 -18.751894) (xy 432.263966 -18.744137)
			(xy 432.291236 -18.743676) (xy 433.154836 -18.743676) (xy 433.182106 -18.744089) (xy 433.236091 -18.751856)
			(xy 433.288422 -18.767226) (xy 433.338032 -18.789886) (xy 433.383913 -18.819376) (xy 433.425131 -18.855095)
			(xy 433.460846 -18.896315) (xy 433.490331 -18.942199) (xy 433.512987 -18.991812) (xy 433.528352 -19.044144)
			(xy 433.536114 -19.09813) (xy 433.536114 -19.15267) (xy 433.528352 -19.206656) (xy 433.512987 -19.258988)
			(xy 433.490331 -19.308601) (xy 433.460846 -19.354485) (xy 433.425131 -19.395705) (xy 433.383913 -19.431424)
			(xy 433.338032 -19.460914) (xy 433.288422 -19.483574) (xy 433.236091 -19.498944) (xy 433.182106 -19.506711)
			(xy 433.154836 -19.5072) (xy 432.291236 -19.5072) (xy 432.263966 -19.506663) (xy 432.209981 -19.498906)
			(xy 432.157649 -19.483544) (xy 432.108036 -19.460891) (xy 432.062152 -19.431407) (xy 432.020932 -19.395693)
			(xy 431.985214 -19.354476) (xy 431.955726 -19.308596) (xy 431.933068 -19.258985) (xy 431.917702 -19.206655)
			(xy 431.90994 -19.15267) (xy 427.948114 -19.15267) (xy 427.940352 -19.206656) (xy 427.924987 -19.258988)
			(xy 427.902331 -19.308601) (xy 427.872846 -19.354485) (xy 427.837131 -19.395705) (xy 427.795913 -19.431424)
			(xy 427.750032 -19.460914) (xy 427.700422 -19.483574) (xy 427.648091 -19.498944) (xy 427.594106 -19.506711)
			(xy 427.566836 -19.5072) (xy 426.703236 -19.5072) (xy 426.675966 -19.506663) (xy 426.621981 -19.498906)
			(xy 426.569649 -19.483544) (xy 426.520036 -19.460891) (xy 426.474152 -19.431407) (xy 426.432932 -19.395693)
			(xy 426.397214 -19.354476) (xy 426.367726 -19.308596) (xy 426.345068 -19.258985) (xy 426.329702 -19.206655)
			(xy 426.32194 -19.15267) (xy 422.326113 -19.15267) (xy 422.326113 -19.152672) (xy 422.318351 -19.206661)
			(xy 422.302984 -19.258996) (xy 422.280326 -19.308611) (xy 422.250837 -19.354496) (xy 422.215118 -19.395718)
			(xy 422.173896 -19.431437) (xy 422.128011 -19.460926) (xy 422.078396 -19.483584) (xy 422.026061 -19.498951)
			(xy 421.972072 -19.506713) (xy 421.9448 -19.5072) (xy 421.0812 -19.5072) (xy 421.053933 -19.506638)
			(xy 420.999955 -19.498877) (xy 420.947631 -19.483513) (xy 420.898026 -19.460859) (xy 420.852149 -19.431376)
			(xy 420.810936 -19.395664) (xy 420.775224 -19.354451) (xy 420.745741 -19.308574) (xy 420.723087 -19.258969)
			(xy 420.707723 -19.206645) (xy 420.699962 -19.152667) (xy 416.738113 -19.152667) (xy 416.738113 -19.152672)
			(xy 416.730351 -19.206661) (xy 416.714984 -19.258996) (xy 416.692326 -19.308611) (xy 416.662837 -19.354496)
			(xy 416.627118 -19.395718) (xy 416.585896 -19.431437) (xy 416.540011 -19.460926) (xy 416.490396 -19.483584)
			(xy 416.438061 -19.498951) (xy 416.384072 -19.506713) (xy 416.3568 -19.5072) (xy 415.4932 -19.5072)
			(xy 415.465933 -19.506638) (xy 415.411955 -19.498877) (xy 415.359631 -19.483513) (xy 415.310026 -19.460859)
			(xy 415.264149 -19.431376) (xy 415.222936 -19.395664) (xy 415.187224 -19.354451) (xy 415.157741 -19.308574)
			(xy 415.135087 -19.258969) (xy 415.119723 -19.206645) (xy 415.111962 -19.152667) (xy 410.844336 -19.152667)
			(xy 410.844336 -19.152674) (xy 410.836573 -19.206668) (xy 410.821204 -19.259007) (xy 410.798543 -19.308626)
			(xy 410.769051 -19.354515) (xy 410.733329 -19.39574) (xy 410.692103 -19.431461) (xy 410.646212 -19.460951)
			(xy 410.596592 -19.48361) (xy 410.544252 -19.498976) (xy 410.490258 -19.506738) (xy 410.462984 -19.5072)
			(xy 409.599384 -19.5072) (xy 409.572118 -19.506637) (xy 409.518142 -19.498874) (xy 409.465819 -19.483509)
			(xy 409.416216 -19.460854) (xy 409.370342 -19.43137) (xy 409.32913 -19.395659) (xy 409.29342 -19.354446)
			(xy 409.263939 -19.30857) (xy 409.241286 -19.258966) (xy 409.225923 -19.206643) (xy 409.218162 -19.152666)
			(xy 405.256336 -19.152666) (xy 405.256336 -19.152674) (xy 405.248573 -19.206668) (xy 405.233204 -19.259007)
			(xy 405.210543 -19.308626) (xy 405.181051 -19.354515) (xy 405.145329 -19.39574) (xy 405.104103 -19.431461)
			(xy 405.058212 -19.460951) (xy 405.008592 -19.48361) (xy 404.956252 -19.498976) (xy 404.902258 -19.506738)
			(xy 404.874984 -19.5072) (xy 404.011384 -19.5072) (xy 403.984118 -19.506637) (xy 403.930142 -19.498874)
			(xy 403.877819 -19.483509) (xy 403.828216 -19.460854) (xy 403.782342 -19.43137) (xy 403.74113 -19.395659)
			(xy 403.70542 -19.354446) (xy 403.675939 -19.30857) (xy 403.653286 -19.258966) (xy 403.637923 -19.206643)
			(xy 403.630162 -19.152666) (xy 399.668336 -19.152666) (xy 399.668336 -19.152674) (xy 399.660573 -19.206668)
			(xy 399.645204 -19.259007) (xy 399.622543 -19.308626) (xy 399.593051 -19.354515) (xy 399.557329 -19.39574)
			(xy 399.516103 -19.431461) (xy 399.470212 -19.460951) (xy 399.420592 -19.48361) (xy 399.368252 -19.498976)
			(xy 399.314258 -19.506738) (xy 399.286984 -19.5072) (xy 398.423384 -19.5072) (xy 398.396118 -19.506637)
			(xy 398.342142 -19.498874) (xy 398.289819 -19.483509) (xy 398.240216 -19.460854) (xy 398.194342 -19.43137)
			(xy 398.15313 -19.395659) (xy 398.11742 -19.354446) (xy 398.087939 -19.30857) (xy 398.065286 -19.258966)
			(xy 398.049923 -19.206643) (xy 398.042162 -19.152666) (xy 394.080336 -19.152666) (xy 394.080336 -19.152674)
			(xy 394.072573 -19.206668) (xy 394.057204 -19.259007) (xy 394.034543 -19.308626) (xy 394.005051 -19.354515)
			(xy 393.969329 -19.39574) (xy 393.928103 -19.431461) (xy 393.882212 -19.460951) (xy 393.832592 -19.48361)
			(xy 393.780252 -19.498976) (xy 393.726258 -19.506738) (xy 393.698984 -19.5072) (xy 392.835384 -19.5072)
			(xy 392.808118 -19.506637) (xy 392.754142 -19.498874) (xy 392.701819 -19.483509) (xy 392.652216 -19.460854)
			(xy 392.606342 -19.43137) (xy 392.56513 -19.395659) (xy 392.52942 -19.354446) (xy 392.499939 -19.30857)
			(xy 392.477286 -19.258966) (xy 392.461923 -19.206643) (xy 392.454162 -19.152666) (xy 259.309108 -19.152666)
			(xy 259.309108 -25.468351) (xy 388.406603 -25.468351) (xy 388.406603 -25.413849) (xy 388.41436 -25.359901)
			(xy 388.429716 -25.307607) (xy 388.452359 -25.25803) (xy 388.481827 -25.212181) (xy 388.517521 -25.170992)
			(xy 388.558713 -25.135303) (xy 388.604565 -25.10584) (xy 388.654144 -25.083202) (xy 388.70644 -25.067852)
			(xy 388.760389 -25.0601) (xy 388.78764 -25.05964) (xy 389.65124 -25.05964) (xy 389.678493 -25.060033)
			(xy 389.732443 -25.067795) (xy 389.78474 -25.083155) (xy 389.834318 -25.105802) (xy 389.880169 -25.135273)
			(xy 389.92136 -25.170969) (xy 389.957051 -25.212163) (xy 389.986518 -25.258017) (xy 390.009159 -25.307598)
			(xy 390.024514 -25.359896) (xy 390.03227 -25.413847) (xy 390.03227 -25.468353) (xy 390.024514 -25.522304)
			(xy 390.009159 -25.574602) (xy 389.986518 -25.624183) (xy 389.957051 -25.670037) (xy 389.92136 -25.711231)
			(xy 389.880169 -25.746927) (xy 389.834318 -25.776398) (xy 389.78474 -25.799045) (xy 389.732443 -25.814405)
			(xy 389.678493 -25.822167) (xy 389.65124 -25.822656) (xy 388.78764 -25.822656) (xy 388.760389 -25.8221)
			(xy 388.70644 -25.814348) (xy 388.654144 -25.798998) (xy 388.604565 -25.77636) (xy 388.558713 -25.746897)
			(xy 388.517521 -25.711208) (xy 388.481827 -25.670019) (xy 388.452359 -25.62417) (xy 388.429716 -25.574593)
			(xy 388.41436 -25.522299) (xy 388.406603 -25.468351) (xy 259.309108 -25.468351) (xy 259.309108 -28.450032)
			(xy 354.840804 -28.450032) (xy 354.844787 -28.322014) (xy 354.856722 -28.194492) (xy 354.876561 -28.067958)
			(xy 354.904228 -27.942902) (xy 354.939617 -27.819809) (xy 354.98259 -27.699153) (xy 355.032981 -27.581403)
			(xy 355.090595 -27.467013) (xy 355.155209 -27.356426) (xy 355.226573 -27.25007) (xy 355.304411 -27.148357)
			(xy 355.388422 -27.051679) (xy 355.478281 -26.960412) (xy 355.57364 -26.874907) (xy 355.674131 -26.795497)
			(xy 355.779364 -26.722487) (xy 355.888933 -26.656161) (xy 356.002413 -26.596775) (xy 356.119365 -26.544559)
			(xy 356.239338 -26.499715) (xy 356.361866 -26.462417) (xy 356.486477 -26.432808) (xy 356.612686 -26.411003)
			(xy 356.740008 -26.397087) (xy 356.867948 -26.391113) (xy 356.996012 -26.393105) (xy 357.123705 -26.403055)
			(xy 357.250532 -26.420924) (xy 357.376003 -26.446643) (xy 357.499632 -26.480113) (xy 357.620941 -26.521204)
			(xy 357.739461 -26.569758) (xy 357.854733 -26.625586) (xy 357.966311 -26.688472) (xy 358.073764 -26.758174)
			(xy 358.176676 -26.834421) (xy 358.274648 -26.916918) (xy 358.367302 -27.005347) (xy 358.454279 -27.099365)
			(xy 358.535243 -27.198608) (xy 358.60988 -27.302693) (xy 358.677902 -27.411217) (xy 358.739046 -27.52376)
			(xy 358.793074 -27.639886) (xy 358.839779 -27.759147) (xy 358.878979 -27.88108) (xy 358.910522 -28.005215)
			(xy 358.934287 -28.131071) (xy 358.950181 -28.25816) (xy 358.958144 -28.385992) (xy 358.958642 -28.450032)
			(xy 358.958144 -28.514072) (xy 358.950181 -28.641904) (xy 358.934287 -28.768993) (xy 358.910522 -28.894849)
			(xy 358.878979 -29.018984) (xy 358.839779 -29.140917) (xy 358.793074 -29.260178) (xy 358.739046 -29.376304)
			(xy 358.677902 -29.488847) (xy 358.60988 -29.597371) (xy 358.535243 -29.701456) (xy 358.454279 -29.800699)
			(xy 358.367302 -29.894717) (xy 358.274648 -29.983146) (xy 358.176676 -30.065643) (xy 358.073764 -30.14189)
			(xy 357.966311 -30.211592) (xy 357.854733 -30.274478) (xy 357.739461 -30.330306) (xy 357.620941 -30.37886)
			(xy 357.499632 -30.419951) (xy 357.376003 -30.453421) (xy 357.250532 -30.47914) (xy 357.123705 -30.497009)
			(xy 356.996012 -30.506959) (xy 356.867948 -30.508951) (xy 356.740008 -30.502977) (xy 356.612686 -30.489061)
			(xy 356.486477 -30.467256) (xy 356.361866 -30.437647) (xy 356.239338 -30.400349) (xy 356.119365 -30.355505)
			(xy 356.002413 -30.303289) (xy 355.888933 -30.243903) (xy 355.779364 -30.177577) (xy 355.674131 -30.104567)
			(xy 355.57364 -30.025157) (xy 355.478281 -29.939652) (xy 355.388422 -29.848385) (xy 355.304411 -29.751707)
			(xy 355.226573 -29.649994) (xy 355.155209 -29.543638) (xy 355.090595 -29.433051) (xy 355.032981 -29.318661)
			(xy 354.98259 -29.200911) (xy 354.939617 -29.080255) (xy 354.904228 -28.957162) (xy 354.876561 -28.832106)
			(xy 354.856722 -28.705572) (xy 354.844787 -28.57805) (xy 354.840804 -28.450032) (xy 259.309108 -28.450032)
			(xy 259.309108 -33.275016) (xy 259.308614 -33.345398) (xy 259.30072 -33.48594) (xy 259.284959 -33.625819)
			(xy 259.261379 -33.764594) (xy 259.230448 -33.90011) (xy 462.69148 -33.90011) (xy 462.69148 -32.29991)
			(xy 462.691988 -32.23523) (xy 462.700111 -32.106124) (xy 462.716324 -31.977784) (xy 462.740564 -31.850714)
			(xy 462.772734 -31.725418) (xy 462.812709 -31.602388) (xy 462.86033 -31.482112) (xy 462.915409 -31.365063)
			(xy 462.977729 -31.251703) (xy 463.047044 -31.14248) (xy 463.12308 -31.037825) (xy 463.205538 -30.938151)
			(xy 463.294091 -30.843851) (xy 463.388391 -30.755298) (xy 463.488065 -30.67284) (xy 463.59272 -30.596804)
			(xy 463.701943 -30.527489) (xy 463.815303 -30.465169) (xy 463.932352 -30.41009) (xy 464.052628 -30.362469)
			(xy 464.175658 -30.322494) (xy 464.300954 -30.290324) (xy 464.428024 -30.266084) (xy 464.556364 -30.249871)
			(xy 464.68547 -30.241748) (xy 464.81483 -30.241748) (xy 464.943936 -30.249871) (xy 465.072276 -30.266084)
			(xy 465.199346 -30.290324) (xy 465.324642 -30.322494) (xy 465.447672 -30.362469) (xy 465.567948 -30.41009)
			(xy 465.684997 -30.465169) (xy 465.798357 -30.527489) (xy 465.90758 -30.596804) (xy 466.012235 -30.67284)
			(xy 466.111909 -30.755298) (xy 466.206209 -30.843851) (xy 466.294762 -30.938151) (xy 466.37722 -31.037825)
			(xy 466.453256 -31.14248) (xy 466.522571 -31.251703) (xy 466.584891 -31.365063) (xy 466.63997 -31.482112)
			(xy 466.687591 -31.602388) (xy 466.727566 -31.725418) (xy 466.759736 -31.850714) (xy 466.783976 -31.977784)
			(xy 466.800189 -32.106124) (xy 466.808312 -32.23523) (xy 466.80882 -32.29991) (xy 466.80882 -33.90011)
			(xy 466.808312 -33.96479) (xy 466.800189 -34.093896) (xy 466.783976 -34.222236) (xy 466.759736 -34.349306)
			(xy 466.727566 -34.474602) (xy 466.687591 -34.597632) (xy 466.63997 -34.717908) (xy 466.584891 -34.834957)
			(xy 466.522571 -34.948317) (xy 466.453256 -35.05754) (xy 466.37722 -35.162195) (xy 466.294762 -35.261869)
			(xy 466.206209 -35.356169) (xy 466.111909 -35.444722) (xy 466.012235 -35.52718) (xy 465.90758 -35.603216)
			(xy 465.798357 -35.672531) (xy 465.684997 -35.734851) (xy 465.567948 -35.78993) (xy 465.447672 -35.837551)
			(xy 465.324642 -35.877526) (xy 465.199346 -35.909696) (xy 465.072276 -35.933936) (xy 464.943936 -35.950149)
			(xy 464.81483 -35.958272) (xy 464.68547 -35.958272) (xy 464.556364 -35.950149) (xy 464.428024 -35.933936)
			(xy 464.300954 -35.909696) (xy 464.175658 -35.877526) (xy 464.052628 -35.837551) (xy 463.932352 -35.78993)
			(xy 463.815303 -35.734851) (xy 463.701943 -35.672531) (xy 463.59272 -35.603216) (xy 463.488065 -35.52718)
			(xy 463.388391 -35.444722) (xy 463.294091 -35.356169) (xy 463.205538 -35.261869) (xy 463.12308 -35.162195)
			(xy 463.047044 -35.05754) (xy 462.977729 -34.948317) (xy 462.915409 -34.834957) (xy 462.86033 -34.717908)
			(xy 462.812709 -34.597632) (xy 462.772734 -34.474602) (xy 462.740564 -34.349306) (xy 462.716324 -34.222236)
			(xy 462.700111 -34.093896) (xy 462.691988 -33.96479) (xy 462.69148 -33.90011) (xy 259.230448 -33.90011)
			(xy 259.230056 -33.901828) (xy 259.191086 -34.03709) (xy 259.144594 -34.169955) (xy 259.090726 -34.300003)
			(xy 259.02965 -34.426827) (xy 258.961559 -34.550026) (xy 258.886668 -34.669214) (xy 258.805211 -34.784015)
			(xy 258.717446 -34.894068) (xy 258.623648 -34.999027) (xy 258.524113 -35.098562) (xy 258.419153 -35.192359)
			(xy 258.324611 -35.267753) (xy 356.989346 -35.267753) (xy 356.989346 -35.213247) (xy 356.997102 -35.159297)
			(xy 357.012458 -35.106999) (xy 357.035099 -35.057419) (xy 357.064566 -35.011566) (xy 357.100259 -34.970373)
			(xy 357.14145 -34.934678) (xy 357.187302 -34.905209) (xy 357.236881 -34.882565) (xy 357.289177 -34.867207)
			(xy 357.343127 -34.859447) (xy 357.37038 -34.85896) (xy 358.23398 -34.85896) (xy 358.261232 -34.859486)
			(xy 358.31518 -34.86724) (xy 358.367476 -34.882593) (xy 358.417054 -34.905232) (xy 358.462906 -34.934697)
			(xy 358.504098 -34.970388) (xy 358.539791 -35.011578) (xy 358.569258 -35.057428) (xy 358.5919 -35.107005)
			(xy 358.607256 -35.1593) (xy 358.615013 -35.213249) (xy 358.615013 -35.267751) (xy 358.607256 -35.3217)
			(xy 358.5919 -35.373995) (xy 358.569258 -35.423572) (xy 358.539791 -35.469422) (xy 358.504098 -35.510612)
			(xy 358.462906 -35.546303) (xy 358.417054 -35.575768) (xy 358.367476 -35.598407) (xy 358.31518 -35.61376)
			(xy 358.261232 -35.621514) (xy 358.23398 -35.621976) (xy 357.37038 -35.621976) (xy 357.343127 -35.621553)
			(xy 357.289177 -35.613793) (xy 357.236881 -35.598435) (xy 357.187302 -35.575791) (xy 357.14145 -35.546322)
			(xy 357.100259 -35.510627) (xy 357.064566 -35.469434) (xy 357.035099 -35.423581) (xy 357.012458 -35.374001)
			(xy 356.997102 -35.321703) (xy 356.989346 -35.267753) (xy 258.324611 -35.267753) (xy 258.309099 -35.280123)
			(xy 258.194297 -35.361579) (xy 258.075109 -35.436469) (xy 257.951909 -35.504559) (xy 257.825085 -35.565634)
			(xy 257.695036 -35.619502) (xy 257.562171 -35.665993) (xy 257.426909 -35.704961) (xy 257.289674 -35.736283)
			(xy 257.150899 -35.759862) (xy 257.01102 -35.775622) (xy 256.870478 -35.783514) (xy 256.800096 -35.784028)
			(xy 225.300032 -35.784028) (xy 225.229649 -35.783544) (xy 225.089104 -35.775653) (xy 224.949222 -35.759894)
			(xy 224.810444 -35.736316) (xy 224.673207 -35.704995) (xy 224.537941 -35.666027) (xy 224.405074 -35.619536)
			(xy 224.275022 -35.565669) (xy 224.148195 -35.504594) (xy 224.024992 -35.436504) (xy 223.905801 -35.361613)
			(xy 223.790997 -35.280156) (xy 223.68094 -35.192391) (xy 223.575978 -35.098593) (xy 223.47644 -34.999057)
			(xy 223.38264 -34.894096) (xy 223.294872 -34.784042) (xy 223.213414 -34.669239) (xy 223.138521 -34.550049)
			(xy 223.070428 -34.426848) (xy 223.009351 -34.300022) (xy 222.955481 -34.169971) (xy 222.908988 -34.037104)
			(xy 222.870017 -33.90184) (xy 222.838693 -33.764603) (xy 222.815113 -33.625825) (xy 222.799351 -33.485944)
			(xy 222.791457 -33.345399) (xy 222.79102 -33.275016) (xy 222.79102 -13.780008) (xy 222.790499 -13.724238)
			(xy 222.782164 -13.613011) (xy 222.765541 -13.502717) (xy 222.740722 -13.393974) (xy 222.707846 -13.287389)
			(xy 222.667097 -13.183559) (xy 222.618703 -13.083065) (xy 222.562935 -12.986469) (xy 222.500103 -12.894309)
			(xy 222.430561 -12.807103) (xy 222.354696 -12.725338) (xy 222.272933 -12.64947) (xy 222.185729 -12.579925)
			(xy 222.093572 -12.517091) (xy 221.996977 -12.461319) (xy 221.896485 -12.412922) (xy 221.792656 -12.37217)
			(xy 221.686073 -12.339291) (xy 221.57733 -12.314468) (xy 221.467037 -12.297841) (xy 221.35581 -12.289503)
			(xy 221.30004 -12.289028) (xy 196.701918 -12.289028) (xy 196.631535 -12.288544) (xy 196.49099 -12.280652)
			(xy 196.35111 -12.264892) (xy 196.212332 -12.241314) (xy 196.075095 -12.209992) (xy 195.939831 -12.171024)
			(xy 195.806964 -12.124532) (xy 195.676913 -12.070665) (xy 195.550086 -12.009589) (xy 195.426884 -11.941499)
			(xy 195.307694 -11.866608) (xy 195.19289 -11.785152) (xy 195.082834 -11.697386) (xy 194.977873 -11.603588)
			(xy 194.878335 -11.504052) (xy 194.784536 -11.399092) (xy 194.696769 -11.289037) (xy 194.615311 -11.174234)
			(xy 194.540418 -11.055045) (xy 194.472326 -10.931844) (xy 194.411249 -10.805018) (xy 194.35738 -10.674968)
			(xy 194.310887 -10.542102) (xy 194.271917 -10.406837) (xy 194.240593 -10.269601) (xy 194.217013 -10.130824)
			(xy 194.201251 -9.990943) (xy 194.193357 -9.850399) (xy 194.192906 -9.780016) (xy 194.192906 -6.279896)
			(xy 194.19238 -6.247749) (xy 194.183988 -6.184006) (xy 194.167348 -6.121904) (xy 194.142744 -6.062504)
			(xy 194.110598 -6.006824) (xy 194.07146 -5.955816) (xy 194.025999 -5.910353) (xy 193.974992 -5.871213)
			(xy 193.919314 -5.839064) (xy 193.859915 -5.814458) (xy 193.797813 -5.797816) (xy 193.734071 -5.789421)
			(xy 193.701924 -5.788914) (xy 127.102108 -5.788914) (xy 127.06996 -5.789416) (xy 127.006214 -5.797808)
			(xy 126.944108 -5.814448) (xy 126.884706 -5.839052) (xy 126.829023 -5.8712) (xy 126.778013 -5.91034)
			(xy 126.732548 -5.955804) (xy 126.693406 -6.006813) (xy 126.661257 -6.062495) (xy 126.636652 -6.121897)
			(xy 126.62001 -6.184002) (xy 126.611617 -6.247748) (xy 126.611126 -6.279896) (xy 126.611126 -9.780016)
			(xy 126.610632 -9.850398) (xy 126.602738 -9.990941) (xy 126.586977 -10.13082) (xy 126.563397 -10.269595)
			(xy 126.532074 -10.40683) (xy 126.519617 -10.450068) (xy 127.350273 -10.450068) (xy 127.354278 -10.36216)
			(xy 127.366261 -10.27498) (xy 127.386121 -10.189251) (xy 127.413696 -10.105683) (xy 127.448755 -10.024969)
			(xy 127.491008 -9.947777) (xy 127.540106 -9.874748) (xy 127.595642 -9.806486) (xy 127.657154 -9.743556)
			(xy 127.724135 -9.686482) (xy 127.796028 -9.635734) (xy 127.872237 -9.591734) (xy 127.952132 -9.554847)
			(xy 128.035051 -9.525378) (xy 128.120306 -9.503571) (xy 128.20719 -9.489607) (xy 128.294984 -9.483601)
			(xy 128.382961 -9.485605) (xy 128.470391 -9.4956) (xy 128.55655 -9.513504) (xy 128.640724 -9.539168)
			(xy 128.722215 -9.572381) (xy 128.800349 -9.612867) (xy 128.874477 -9.660289) (xy 128.943985 -9.714256)
			(xy 129.008299 -9.774321) (xy 129.066883 -9.839985) (xy 129.119254 -9.910704) (xy 129.164977 -9.985892)
			(xy 129.203674 -10.064927) (xy 129.235023 -10.147153) (xy 129.258765 -10.231889) (xy 129.265884 -10.270548)
			(xy 131.63909 -10.270548) (xy 131.63909 -10.216052) (xy 131.646845 -10.16211) (xy 131.662198 -10.10982)
			(xy 131.684835 -10.060247) (xy 131.714296 -10.014401) (xy 131.749982 -9.973213) (xy 131.791165 -9.937522)
			(xy 131.837009 -9.908056) (xy 131.886579 -9.885413) (xy 131.938866 -9.870055) (xy 131.992808 -9.862293)
			(xy 132.020056 -9.861804) (xy 132.883656 -9.861804) (xy 132.910912 -9.86224) (xy 132.964869 -9.869992)
			(xy 133.017174 -9.885345) (xy 133.066761 -9.907985) (xy 133.112622 -9.937453) (xy 133.153821 -9.973148)
			(xy 133.18952 -10.014343) (xy 133.218993 -10.0602) (xy 133.24164 -10.109785) (xy 133.256999 -10.162088)
			(xy 133.264757 -10.216044) (xy 133.264757 -10.270556) (xy 133.256999 -10.324512) (xy 133.24164 -10.376815)
			(xy 133.218993 -10.4264) (xy 133.18952 -10.472257) (xy 133.153821 -10.513452) (xy 133.112622 -10.549147)
			(xy 133.066761 -10.578615) (xy 133.017174 -10.601255) (xy 132.964869 -10.616608) (xy 132.910912 -10.62436)
			(xy 132.883656 -10.62482) (xy 132.020056 -10.62482) (xy 131.992808 -10.624307) (xy 131.938866 -10.616545)
			(xy 131.886579 -10.601187) (xy 131.837009 -10.578544) (xy 131.791165 -10.549078) (xy 131.749982 -10.513387)
			(xy 131.714296 -10.472199) (xy 131.684835 -10.426353) (xy 131.662198 -10.37678) (xy 131.646845 -10.32449)
			(xy 131.63909 -10.270548) (xy 129.265884 -10.270548) (xy 129.274703 -10.318433) (xy 129.282705 -10.406068)
			(xy 129.283206 -10.450068) (xy 129.282705 -10.494068) (xy 129.274703 -10.581703) (xy 129.258765 -10.668247)
			(xy 129.235023 -10.752983) (xy 129.203674 -10.835209) (xy 129.164977 -10.914244) (xy 129.119254 -10.989432)
			(xy 129.087321 -11.032553) (xy 168.158867 -11.032553) (xy 168.158867 -10.978047) (xy 168.166625 -10.924096)
			(xy 168.181981 -10.871798) (xy 168.204625 -10.822218) (xy 168.234094 -10.776365) (xy 168.269789 -10.735173)
			(xy 168.310983 -10.699481) (xy 168.356837 -10.670014) (xy 168.406419 -10.647374) (xy 168.458717 -10.63202)
			(xy 168.512669 -10.624266) (xy 168.539922 -10.623804) (xy 169.403522 -10.623804) (xy 169.430773 -10.624267)
			(xy 169.48472 -10.632027) (xy 169.537014 -10.647384) (xy 169.58659 -10.670027) (xy 169.632439 -10.699495)
			(xy 169.673628 -10.735188) (xy 169.709318 -10.776379) (xy 169.738783 -10.822229) (xy 169.761424 -10.871807)
			(xy 169.776778 -10.924101) (xy 169.784534 -10.978049) (xy 169.784534 -11.032551) (xy 169.776778 -11.086499)
			(xy 169.761424 -11.138793) (xy 169.738783 -11.188371) (xy 169.709318 -11.234221) (xy 169.673628 -11.275412)
			(xy 169.632439 -11.311105) (xy 169.58659 -11.340573) (xy 169.537014 -11.363216) (xy 169.48472 -11.378573)
			(xy 169.430773 -11.386333) (xy 169.403522 -11.38682) (xy 168.539922 -11.38682) (xy 168.512669 -11.386334)
			(xy 168.458717 -11.37858) (xy 168.406419 -11.363226) (xy 168.356837 -11.340586) (xy 168.310983 -11.311119)
			(xy 168.269789 -11.275427) (xy 168.234094 -11.234235) (xy 168.204625 -11.188382) (xy 168.181981 -11.138802)
			(xy 168.166625 -11.086504) (xy 168.158867 -11.032553) (xy 129.087321 -11.032553) (xy 129.066883 -11.060151)
			(xy 129.008299 -11.125815) (xy 128.943985 -11.18588) (xy 128.874477 -11.239847) (xy 128.800349 -11.287269)
			(xy 128.722215 -11.327755) (xy 128.640724 -11.360968) (xy 128.55655 -11.386632) (xy 128.470391 -11.404536)
			(xy 128.382961 -11.414531) (xy 128.294984 -11.416535) (xy 128.20719 -11.410529) (xy 128.120306 -11.396565)
			(xy 128.035051 -11.374758) (xy 127.952132 -11.345289) (xy 127.872237 -11.308402) (xy 127.796028 -11.264402)
			(xy 127.724135 -11.213654) (xy 127.657154 -11.15658) (xy 127.595642 -11.09365) (xy 127.540106 -11.025388)
			(xy 127.491008 -10.952359) (xy 127.448755 -10.875167) (xy 127.413696 -10.794453) (xy 127.386121 -10.710885)
			(xy 127.366261 -10.625156) (xy 127.354278 -10.537976) (xy 127.350273 -10.450068) (xy 126.519617 -10.450068)
			(xy 126.493105 -10.542092) (xy 126.446613 -10.674957) (xy 126.392744 -10.805006) (xy 126.331668 -10.93183)
			(xy 126.263578 -11.05503) (xy 126.188687 -11.174218) (xy 126.10723 -11.28902) (xy 126.019465 -11.399074)
			(xy 125.973895 -11.450066) (xy 191.515245 -11.450066) (xy 191.51925 -11.362158) (xy 191.531233 -11.274978)
			(xy 191.551093 -11.189249) (xy 191.578668 -11.105681) (xy 191.613727 -11.024967) (xy 191.65598 -10.947775)
			(xy 191.705078 -10.874746) (xy 191.760614 -10.806484) (xy 191.822126 -10.743554) (xy 191.889107 -10.68648)
			(xy 191.961 -10.635732) (xy 192.037209 -10.591732) (xy 192.117104 -10.554845) (xy 192.200023 -10.525376)
			(xy 192.285278 -10.503569) (xy 192.372162 -10.489605) (xy 192.459956 -10.483599) (xy 192.547933 -10.485603)
			(xy 192.635363 -10.495598) (xy 192.721522 -10.513502) (xy 192.805696 -10.539166) (xy 192.887187 -10.572379)
			(xy 192.965321 -10.612865) (xy 193.039449 -10.660287) (xy 193.108957 -10.714254) (xy 193.173271 -10.774319)
			(xy 193.231855 -10.839983) (xy 193.284226 -10.910702) (xy 193.329949 -10.98589) (xy 193.368646 -11.064925)
			(xy 193.399995 -11.147151) (xy 193.423737 -11.231887) (xy 193.439675 -11.318431) (xy 193.447677 -11.406066)
			(xy 193.448178 -11.450066) (xy 193.447677 -11.494066) (xy 193.439675 -11.581701) (xy 193.423737 -11.668245)
			(xy 193.399995 -11.752981) (xy 193.368646 -11.835207) (xy 193.329949 -11.914242) (xy 193.284226 -11.98943)
			(xy 193.231855 -12.060149) (xy 193.173271 -12.125813) (xy 193.108957 -12.185878) (xy 193.039449 -12.239845)
			(xy 192.965321 -12.287267) (xy 192.887187 -12.327753) (xy 192.805696 -12.360966) (xy 192.721522 -12.38663)
			(xy 192.635363 -12.404534) (xy 192.547933 -12.414529) (xy 192.459956 -12.416533) (xy 192.372162 -12.410527)
			(xy 192.285278 -12.396563) (xy 192.200023 -12.374756) (xy 192.117104 -12.345287) (xy 192.037209 -12.3084)
			(xy 191.961 -12.2644) (xy 191.889107 -12.213652) (xy 191.822126 -12.156578) (xy 191.760614 -12.093648)
			(xy 191.705078 -12.025386) (xy 191.65598 -11.952357) (xy 191.613727 -11.875165) (xy 191.578668 -11.794451)
			(xy 191.551093 -11.710883) (xy 191.531233 -11.625154) (xy 191.51925 -11.537974) (xy 191.515245 -11.450066)
			(xy 125.973895 -11.450066) (xy 125.925667 -11.504033) (xy 125.826132 -11.603569) (xy 125.721172 -11.697366)
			(xy 125.611118 -11.785131) (xy 125.496317 -11.866588) (xy 125.377128 -11.941479) (xy 125.253928 -12.009569)
			(xy 125.206611 -12.032356) (xy 166.354411 -12.032356) (xy 166.354411 -11.977844) (xy 166.362169 -11.923886)
			(xy 166.377527 -11.871582) (xy 166.400173 -11.821995) (xy 166.429645 -11.776137) (xy 166.465343 -11.734939)
			(xy 166.506541 -11.699241) (xy 166.552401 -11.66977) (xy 166.601987 -11.647125) (xy 166.654292 -11.631768)
			(xy 166.70825 -11.624011) (xy 166.735506 -11.623548) (xy 167.599106 -11.623548) (xy 167.626354 -11.624123)
			(xy 167.680295 -11.631879) (xy 167.732583 -11.647233) (xy 167.782153 -11.669872) (xy 167.827998 -11.699335)
			(xy 167.869182 -11.735022) (xy 167.904869 -11.776207) (xy 167.934331 -11.822052) (xy 167.956969 -11.871623)
			(xy 167.972322 -11.923911) (xy 167.980078 -11.977852) (xy 167.980078 -12.032348) (xy 167.980077 -12.032358)
			(xy 169.954311 -12.032358) (xy 169.954311 -11.977842) (xy 169.96207 -11.92388) (xy 169.97743 -11.871573)
			(xy 170.000079 -11.821984) (xy 170.029555 -11.776123) (xy 170.065258 -11.734924) (xy 170.106461 -11.699226)
			(xy 170.152326 -11.669756) (xy 170.201918 -11.647114) (xy 170.254227 -11.63176) (xy 170.30819 -11.624008)
			(xy 170.335448 -11.623548) (xy 171.199048 -11.623548) (xy 171.226294 -11.624125) (xy 171.28023 -11.631887)
			(xy 171.332513 -11.647244) (xy 171.382078 -11.669885) (xy 171.427917 -11.699349) (xy 171.469097 -11.735037)
			(xy 171.504779 -11.776221) (xy 171.534238 -11.822064) (xy 171.556873 -11.871632) (xy 171.572224 -11.923917)
			(xy 171.579978 -11.977854) (xy 171.579978 -12.032346) (xy 171.572224 -12.086283) (xy 171.556873 -12.138568)
			(xy 171.534238 -12.188136) (xy 171.504779 -12.233979) (xy 171.469097 -12.275163) (xy 171.427917 -12.310851)
			(xy 171.382078 -12.340315) (xy 171.332513 -12.362956) (xy 171.28023 -12.378313) (xy 171.226294 -12.386075)
			(xy 171.199048 -12.386564) (xy 170.335448 -12.386564) (xy 170.30819 -12.386192) (xy 170.254227 -12.37844)
			(xy 170.201918 -12.363086) (xy 170.152326 -12.340444) (xy 170.106461 -12.310974) (xy 170.065258 -12.275276)
			(xy 170.029555 -12.234077) (xy 170.000079 -12.188216) (xy 169.97743 -12.138627) (xy 169.96207 -12.08632)
			(xy 169.954311 -12.032358) (xy 167.980077 -12.032358) (xy 167.972322 -12.086289) (xy 167.956969 -12.138577)
			(xy 167.934331 -12.188148) (xy 167.904869 -12.233993) (xy 167.869182 -12.275178) (xy 167.827998 -12.310865)
			(xy 167.782153 -12.340328) (xy 167.732583 -12.362967) (xy 167.680295 -12.378321) (xy 167.626354 -12.386077)
			(xy 167.599106 -12.386564) (xy 166.735506 -12.386564) (xy 166.70825 -12.386189) (xy 166.654292 -12.378432)
			(xy 166.601987 -12.363075) (xy 166.552401 -12.34043) (xy 166.506541 -12.310959) (xy 166.465343 -12.275261)
			(xy 166.429645 -12.234063) (xy 166.400173 -12.188205) (xy 166.377527 -12.138618) (xy 166.362169 -12.086314)
			(xy 166.354411 -12.032356) (xy 125.206611 -12.032356) (xy 125.127104 -12.070645) (xy 124.997055 -12.124513)
			(xy 124.86419 -12.171005) (xy 124.728928 -12.209974) (xy 124.591693 -12.241298) (xy 124.452918 -12.264877)
			(xy 124.313039 -12.280639) (xy 124.172496 -12.288532) (xy 124.102114 -12.289028) (xy 83.70189 -12.289028)
			(xy 83.631508 -12.288534) (xy 83.490965 -12.280641) (xy 83.351086 -12.26488) (xy 83.21231 -12.2413)
			(xy 83.075075 -12.209977) (xy 82.939812 -12.171008) (xy 82.806947 -12.124516) (xy 82.676898 -12.070648)
			(xy 82.550073 -12.009572) (xy 82.426873 -11.941482) (xy 82.307684 -11.866591) (xy 82.192882 -11.785134)
			(xy 82.082828 -11.697369) (xy 81.977868 -11.603571) (xy 81.878333 -11.504036) (xy 81.784535 -11.399076)
			(xy 81.696769 -11.289022) (xy 81.615313 -11.174221) (xy 81.540421 -11.055032) (xy 81.47233 -10.931832)
			(xy 81.411254 -10.805008) (xy 81.357386 -10.674959) (xy 81.310894 -10.542094) (xy 81.271924 -10.406831)
			(xy 81.240601 -10.269596) (xy 81.217021 -10.13082) (xy 81.20126 -9.990941) (xy 81.193366 -9.850398)
			(xy 81.192878 -9.780016) (xy 81.192878 -0.999998) (xy 81.192375 -0.96785) (xy 81.183982 -0.904106)
			(xy 81.167341 -0.842001) (xy 81.142736 -0.782601) (xy 81.110589 -0.72692) (xy 81.071448 -0.675911)
			(xy 81.025984 -0.630448) (xy 80.974975 -0.591308) (xy 80.919294 -0.559161) (xy 80.859893 -0.534557)
			(xy 80.797789 -0.517916) (xy 80.734044 -0.509525) (xy 80.701896 -0.509016) (xy 14.10208 -0.509016)
			(xy 14.069935 -0.509543) (xy 14.006194 -0.517937) (xy 13.944095 -0.534579) (xy 13.884698 -0.559184)
			(xy 13.829022 -0.59133) (xy 13.778017 -0.630469) (xy 13.732558 -0.675931) (xy 13.69342 -0.726937)
			(xy 13.661276 -0.782614) (xy 13.636673 -0.842012) (xy 13.620034 -0.904112) (xy 13.611642 -0.967853)
			(xy 13.611098 -0.999998) (xy 13.611098 -5.184498) (xy 14.350702 -5.184498) (xy 14.35331 -5.097781)
			(xy 14.363685 -5.011647) (xy 14.381743 -4.926791) (xy 14.40734 -4.843896) (xy 14.440268 -4.763631)
			(xy 14.480262 -4.686643) (xy 14.526999 -4.613552) (xy 14.580104 -4.544948) (xy 14.639148 -4.481383)
			(xy 14.703655 -4.42337) (xy 14.738096 -4.396994) (xy 14.773029 -4.371293) (xy 14.846784 -4.325653)
			(xy 14.924335 -4.28681) (xy 15.005056 -4.255076) (xy 15.088297 -4.230709) (xy 15.173387 -4.213903)
			(xy 15.259642 -4.204794) (xy 15.346366 -4.203455) (xy 15.432861 -4.209898) (xy 15.518429 -4.224071)
			(xy 15.602382 -4.245858) (xy 15.684044 -4.275086) (xy 15.762756 -4.311517) (xy 15.837884 -4.35486)
			(xy 15.908824 -4.404764) (xy 15.975003 -4.460828) (xy 16.035889 -4.5226) (xy 16.090991 -4.589582)
			(xy 16.139865 -4.661235) (xy 16.182118 -4.736981) (xy 16.217409 -4.816211) (xy 16.245454 -4.898286)
			(xy 16.266027 -4.982545) (xy 16.267136 -4.989901) (xy 20.44038 -4.989901) (xy 20.44038 -4.935399)
			(xy 20.448136 -4.881452) (xy 20.463491 -4.829158) (xy 20.486132 -4.779581) (xy 20.515597 -4.733731)
			(xy 20.551288 -4.692541) (xy 20.592478 -4.65685) (xy 20.638328 -4.627384) (xy 20.687904 -4.604742)
			(xy 20.740198 -4.589387) (xy 20.794145 -4.58163) (xy 20.821396 -4.581144) (xy 21.684996 -4.581144)
			(xy 21.712249 -4.581603) (xy 21.766201 -4.58936) (xy 21.818499 -4.604715) (xy 21.86808 -4.627358)
			(xy 21.913934 -4.656826) (xy 21.955128 -4.69252) (xy 21.990822 -4.733713) (xy 22.02029 -4.779566)
			(xy 22.042933 -4.829147) (xy 22.05829 -4.881445) (xy 22.066047 -4.935397) (xy 22.066047 -4.989901)
			(xy 24.04032 -4.989901) (xy 24.04032 -4.935399) (xy 24.048076 -4.881452) (xy 24.063431 -4.829157)
			(xy 24.086072 -4.779581) (xy 24.115538 -4.73373) (xy 24.151229 -4.692541) (xy 24.192419 -4.656849)
			(xy 24.238269 -4.627383) (xy 24.287846 -4.604742) (xy 24.34014 -4.589387) (xy 24.394087 -4.58163)
			(xy 24.421338 -4.581144) (xy 25.284938 -4.581144) (xy 25.312191 -4.581603) (xy 25.366143 -4.58936)
			(xy 25.418441 -4.604716) (xy 25.468021 -4.627358) (xy 25.513875 -4.656827) (xy 25.555068 -4.69252)
			(xy 25.590762 -4.733713) (xy 25.620231 -4.779567) (xy 25.642873 -4.829147) (xy 25.65823 -4.881446)
			(xy 25.665987 -4.935397) (xy 25.665987 -4.989903) (xy 25.66598 -4.989954) (xy 27.64023 -4.989954)
			(xy 27.64023 -4.935446) (xy 27.647987 -4.881493) (xy 27.663343 -4.829194) (xy 27.685985 -4.779612)
			(xy 27.715454 -4.733756) (xy 27.751147 -4.692562) (xy 27.79234 -4.656866) (xy 27.838194 -4.627395)
			(xy 27.887775 -4.60475) (xy 27.940074 -4.589391) (xy 27.994026 -4.581631) (xy 28.02128 -4.581144)
			(xy 28.88488 -4.581144) (xy 28.91213 -4.581702) (xy 28.966077 -4.589456) (xy 29.01837 -4.604808)
			(xy 29.067947 -4.627446) (xy 29.113797 -4.65691) (xy 29.154986 -4.692599) (xy 29.190678 -4.733787)
			(xy 29.220144 -4.779636) (xy 29.242785 -4.829211) (xy 29.25814 -4.881504) (xy 29.265897 -4.93545)
			(xy 29.265897 -4.98995) (xy 29.265896 -4.989954) (xy 31.24043 -4.989954) (xy 31.24043 -4.935446)
			(xy 31.248187 -4.881494) (xy 31.263543 -4.829195) (xy 31.286185 -4.779613) (xy 31.315653 -4.733758)
			(xy 31.351346 -4.692563) (xy 31.392538 -4.656867) (xy 31.438392 -4.627396) (xy 31.487972 -4.604751)
			(xy 31.540271 -4.589392) (xy 31.594222 -4.581632) (xy 31.621476 -4.581144) (xy 32.485076 -4.581144)
			(xy 32.512327 -4.581702) (xy 32.566273 -4.589455) (xy 32.618567 -4.604807) (xy 32.668144 -4.627445)
			(xy 32.713995 -4.656909) (xy 32.755185 -4.692598) (xy 32.790877 -4.733786) (xy 32.820343 -4.779635)
			(xy 32.842985 -4.82921) (xy 32.85834 -4.881503) (xy 32.866097 -4.935449) (xy 32.866097 -4.989951)
			(xy 32.866096 -4.989958) (xy 40.350307 -4.989958) (xy 40.350307 -4.935442) (xy 40.358066 -4.881481)
			(xy 40.373426 -4.829173) (xy 40.396074 -4.779584) (xy 40.42555 -4.733723) (xy 40.461252 -4.692524)
			(xy 40.502455 -4.656826) (xy 40.548319 -4.627355) (xy 40.59791 -4.604712) (xy 40.65022 -4.589358)
			(xy 40.704182 -4.581604) (xy 40.73144 -4.581144) (xy 41.59504 -4.581144) (xy 41.622286 -4.581729)
			(xy 41.676222 -4.589489) (xy 41.728506 -4.604846) (xy 41.778072 -4.627486) (xy 41.823911 -4.65695)
			(xy 41.865091 -4.692637) (xy 41.900774 -4.733821) (xy 41.930233 -4.779663) (xy 41.952868 -4.829232)
			(xy 41.968219 -4.881517) (xy 41.975974 -4.935454) (xy 41.975974 -4.989946) (xy 41.975973 -4.989954)
			(xy 43.95033 -4.989954) (xy 43.95033 -4.935446) (xy 43.958087 -4.881493) (xy 43.973443 -4.829193)
			(xy 43.996086 -4.779611) (xy 44.025554 -4.733756) (xy 44.061248 -4.692561) (xy 44.102441 -4.656865)
			(xy 44.148295 -4.627394) (xy 44.197876 -4.604749) (xy 44.250176 -4.589391) (xy 44.304128 -4.581631)
			(xy 44.331382 -4.581144) (xy 45.194982 -4.581144) (xy 45.222232 -4.581702) (xy 45.276178 -4.589456)
			(xy 45.328472 -4.604808) (xy 45.378048 -4.627447) (xy 45.423898 -4.656911) (xy 45.465087 -4.6926)
			(xy 45.500778 -4.733788) (xy 45.530244 -4.779636) (xy 45.552885 -4.829211) (xy 45.56824 -4.881504)
			(xy 45.575997 -4.93545) (xy 45.575997 -4.98995) (xy 45.575996 -4.989954) (xy 51.56043 -4.989954)
			(xy 51.56043 -4.935446) (xy 51.568187 -4.881494) (xy 51.583543 -4.829195) (xy 51.606185 -4.779613)
			(xy 51.635653 -4.733758) (xy 51.671346 -4.692563) (xy 51.712538 -4.656867) (xy 51.758392 -4.627396)
			(xy 51.807972 -4.604751) (xy 51.860271 -4.589392) (xy 51.914222 -4.581632) (xy 51.941476 -4.581144)
			(xy 52.805076 -4.581144) (xy 52.832327 -4.581702) (xy 52.886273 -4.589455) (xy 52.938567 -4.604807)
			(xy 52.988144 -4.627445) (xy 53.033995 -4.656909) (xy 53.075185 -4.692598) (xy 53.110877 -4.733786)
			(xy 53.140343 -4.779635) (xy 53.162985 -4.82921) (xy 53.17834 -4.881503) (xy 53.186097 -4.935449)
			(xy 53.186097 -4.989951) (xy 53.186096 -4.989957) (xy 55.160307 -4.989957) (xy 55.160307 -4.935443)
			(xy 55.168065 -4.881484) (xy 55.183424 -4.829178) (xy 55.206071 -4.77959) (xy 55.235544 -4.73373)
			(xy 55.271245 -4.692532) (xy 55.312445 -4.656834) (xy 55.358306 -4.627362) (xy 55.407894 -4.604718)
			(xy 55.460201 -4.589362) (xy 55.514161 -4.581606) (xy 55.541418 -4.581144) (xy 56.405018 -4.581144)
			(xy 56.432265 -4.581727) (xy 56.486204 -4.589485) (xy 56.53849 -4.60484) (xy 56.588058 -4.627479)
			(xy 56.633901 -4.656942) (xy 56.675084 -4.692629) (xy 56.710769 -4.733814) (xy 56.74023 -4.779657)
			(xy 56.762867 -4.829227) (xy 56.778219 -4.881514) (xy 56.785974 -4.935453) (xy 56.785974 -4.989947)
			(xy 56.778219 -5.043886) (xy 56.762867 -5.096173) (xy 56.74023 -5.145743) (xy 56.710769 -5.191586)
			(xy 56.675084 -5.232771) (xy 56.633901 -5.268458) (xy 56.588058 -5.297921) (xy 56.53849 -5.32056)
			(xy 56.486204 -5.335915) (xy 56.432265 -5.343673) (xy 56.405018 -5.34416) (xy 55.541418 -5.34416)
			(xy 55.514161 -5.343794) (xy 55.460201 -5.336038) (xy 55.407894 -5.320682) (xy 55.358306 -5.298038)
			(xy 55.312445 -5.268566) (xy 55.271245 -5.232868) (xy 55.235544 -5.19167) (xy 55.206071 -5.14581)
			(xy 55.183424 -5.096222) (xy 55.168065 -5.043916) (xy 55.160307 -4.989957) (xy 53.186096 -4.989957)
			(xy 53.17834 -5.043897) (xy 53.162985 -5.09619) (xy 53.140343 -5.145765) (xy 53.110877 -5.191614)
			(xy 53.075185 -5.232802) (xy 53.033995 -5.268491) (xy 52.988144 -5.297955) (xy 52.938567 -5.320593)
			(xy 52.886273 -5.335945) (xy 52.832327 -5.343698) (xy 52.805076 -5.34416) (xy 51.941476 -5.34416)
			(xy 51.914222 -5.343768) (xy 51.860271 -5.336008) (xy 51.807972 -5.320649) (xy 51.758392 -5.298004)
			(xy 51.712538 -5.268533) (xy 51.671346 -5.232837) (xy 51.635653 -5.191642) (xy 51.606185 -5.145787)
			(xy 51.583543 -5.096205) (xy 51.568187 -5.043906) (xy 51.56043 -4.989954) (xy 45.575996 -4.989954)
			(xy 45.56824 -5.043896) (xy 45.552885 -5.096189) (xy 45.530244 -5.145764) (xy 45.500778 -5.191612)
			(xy 45.465087 -5.2328) (xy 45.423898 -5.268489) (xy 45.378048 -5.297953) (xy 45.328472 -5.320592)
			(xy 45.276178 -5.335944) (xy 45.222232 -5.343698) (xy 45.194982 -5.34416) (xy 44.331382 -5.34416)
			(xy 44.304128 -5.343769) (xy 44.250176 -5.336009) (xy 44.197876 -5.320651) (xy 44.148295 -5.298006)
			(xy 44.102441 -5.268535) (xy 44.061248 -5.232839) (xy 44.025554 -5.191644) (xy 43.996086 -5.145789)
			(xy 43.973443 -5.096207) (xy 43.958087 -5.043907) (xy 43.95033 -4.989954) (xy 41.975973 -4.989954)
			(xy 41.968219 -5.043883) (xy 41.952868 -5.096168) (xy 41.930233 -5.145737) (xy 41.900774 -5.191579)
			(xy 41.865091 -5.232763) (xy 41.823911 -5.26845) (xy 41.778072 -5.297914) (xy 41.728506 -5.320554)
			(xy 41.676222 -5.335911) (xy 41.622286 -5.343671) (xy 41.59504 -5.34416) (xy 40.73144 -5.34416) (xy 40.704182 -5.343796)
			(xy 40.65022 -5.336042) (xy 40.59791 -5.320688) (xy 40.548319 -5.298045) (xy 40.502455 -5.268574)
			(xy 40.461252 -5.232876) (xy 40.42555 -5.191677) (xy 40.396074 -5.145816) (xy 40.373426 -5.096227)
			(xy 40.358066 -5.043919) (xy 40.350307 -4.989958) (xy 32.866096 -4.989958) (xy 32.85834 -5.043897)
			(xy 32.842985 -5.09619) (xy 32.820343 -5.145765) (xy 32.790877 -5.191614) (xy 32.755185 -5.232802)
			(xy 32.713995 -5.268491) (xy 32.668144 -5.297955) (xy 32.618567 -5.320593) (xy 32.566273 -5.335945)
			(xy 32.512327 -5.343698) (xy 32.485076 -5.34416) (xy 31.621476 -5.34416) (xy 31.594222 -5.343768)
			(xy 31.540271 -5.336008) (xy 31.487972 -5.320649) (xy 31.438392 -5.298004) (xy 31.392538 -5.268533)
			(xy 31.351346 -5.232837) (xy 31.315653 -5.191642) (xy 31.286185 -5.145787) (xy 31.263543 -5.096205)
			(xy 31.248187 -5.043906) (xy 31.24043 -4.989954) (xy 29.265896 -4.989954) (xy 29.25814 -5.043896)
			(xy 29.242785 -5.096189) (xy 29.220144 -5.145764) (xy 29.190678 -5.191613) (xy 29.154986 -5.232801)
			(xy 29.113797 -5.26849) (xy 29.067947 -5.297954) (xy 29.01837 -5.320592) (xy 28.966077 -5.335944)
			(xy 28.91213 -5.343698) (xy 28.88488 -5.34416) (xy 28.02128 -5.34416) (xy 27.994026 -5.343769) (xy 27.940074 -5.336009)
			(xy 27.887775 -5.32065) (xy 27.838194 -5.298005) (xy 27.79234 -5.268534) (xy 27.751147 -5.232838)
			(xy 27.715454 -5.191644) (xy 27.685985 -5.145788) (xy 27.663343 -5.096206) (xy 27.647987 -5.043907)
			(xy 27.64023 -4.989954) (xy 25.66598 -4.989954) (xy 25.65823 -5.043854) (xy 25.642873 -5.096153)
			(xy 25.620231 -5.145733) (xy 25.590762 -5.191587) (xy 25.555068 -5.23278) (xy 25.513875 -5.268473)
			(xy 25.468021 -5.297942) (xy 25.418441 -5.320584) (xy 25.366143 -5.33594) (xy 25.312191 -5.343697)
			(xy 25.284938 -5.34416) (xy 24.421338 -5.34416) (xy 24.394087 -5.34367) (xy 24.34014 -5.335913) (xy 24.287846 -5.320558)
			(xy 24.238269 -5.297917) (xy 24.192419 -5.268451) (xy 24.151229 -5.232759) (xy 24.115538 -5.19157)
			(xy 24.086072 -5.145719) (xy 24.063431 -5.096143) (xy 24.048076 -5.043848) (xy 24.04032 -4.989901)
			(xy 22.066047 -4.989901) (xy 22.066047 -4.989903) (xy 22.05829 -5.043855) (xy 22.042933 -5.096153)
			(xy 22.02029 -5.145734) (xy 21.990822 -5.191587) (xy 21.955128 -5.23278) (xy 21.913934 -5.268474)
			(xy 21.86808 -5.297942) (xy 21.818499 -5.320585) (xy 21.766201 -5.33594) (xy 21.712249 -5.343697)
			(xy 21.684996 -5.34416) (xy 20.821396 -5.34416) (xy 20.794145 -5.34367) (xy 20.740198 -5.335913)
			(xy 20.687904 -5.320558) (xy 20.638328 -5.297916) (xy 20.592478 -5.26845) (xy 20.551288 -5.232759)
			(xy 20.515597 -5.191569) (xy 20.486132 -5.145719) (xy 20.463491 -5.096142) (xy 20.448136 -5.043848)
			(xy 20.44038 -4.989901) (xy 16.267136 -4.989901) (xy 16.278962 -5.06831) (xy 16.284155 -5.154889)
			(xy 16.281564 -5.241584) (xy 16.27121 -5.327698) (xy 16.253177 -5.412537) (xy 16.22761 -5.495418)
			(xy 16.194714 -5.575672) (xy 16.154755 -5.652653) (xy 16.108054 -5.725741) (xy 16.054988 -5.794348)
			(xy 15.995985 -5.85792) (xy 15.931519 -5.915946) (xy 15.897098 -5.94233) (xy 15.862132 -5.968006)
			(xy 15.788377 -6.013689) (xy 15.710822 -6.052572) (xy 15.630093 -6.084344) (xy 15.546839 -6.108746)
			(xy 15.461732 -6.125584) (xy 15.375458 -6.13472) (xy 15.288712 -6.136082) (xy 15.202194 -6.129659)
			(xy 15.116601 -6.115502) (xy 15.032622 -6.093724) (xy 14.950935 -6.064503) (xy 14.872197 -6.028073)
			(xy 14.797045 -5.984729) (xy 14.726083 -5.934818) (xy 14.659883 -5.878744) (xy 14.598979 -5.816959)
			(xy 14.543862 -5.749961) (xy 14.494977 -5.678289) (xy 14.452716 -5.602521) (xy 14.417421 -5.523269)
			(xy 14.389376 -5.44117) (xy 14.368808 -5.356887) (xy 14.355882 -5.271099) (xy 14.350702 -5.184498)
			(xy 13.611098 -5.184498) (xy 13.611098 -6.169914) (xy 78.515217 -6.169914) (xy 78.519222 -6.082006)
			(xy 78.531205 -5.994826) (xy 78.551065 -5.909097) (xy 78.57864 -5.825529) (xy 78.613699 -5.744815)
			(xy 78.655952 -5.667623) (xy 78.70505 -5.594594) (xy 78.760586 -5.526332) (xy 78.822098 -5.463402)
			(xy 78.889079 -5.406328) (xy 78.960972 -5.35558) (xy 79.037181 -5.31158) (xy 79.117076 -5.274693)
			(xy 79.199995 -5.245224) (xy 79.28525 -5.223417) (xy 79.372134 -5.209453) (xy 79.459928 -5.203447)
			(xy 79.547905 -5.205451) (xy 79.635335 -5.215446) (xy 79.721494 -5.23335) (xy 79.805668 -5.259014)
			(xy 79.887159 -5.292227) (xy 79.965293 -5.332713) (xy 80.039421 -5.380135) (xy 80.108929 -5.434102)
			(xy 80.173243 -5.494167) (xy 80.231827 -5.559831) (xy 80.284198 -5.63055) (xy 80.329921 -5.705738)
			(xy 80.368618 -5.784773) (xy 80.399967 -5.866999) (xy 80.423709 -5.951735) (xy 80.439647 -6.038279)
			(xy 80.447649 -6.125914) (xy 80.44815 -6.169914) (xy 80.447649 -6.213914) (xy 80.439647 -6.301549)
			(xy 80.423709 -6.388093) (xy 80.399967 -6.472829) (xy 80.368618 -6.555055) (xy 80.329921 -6.63409)
			(xy 80.284198 -6.709278) (xy 80.231827 -6.779997) (xy 80.173243 -6.845661) (xy 80.108929 -6.905726)
			(xy 80.039421 -6.959693) (xy 79.965293 -7.007115) (xy 79.887159 -7.047601) (xy 79.805668 -7.080814)
			(xy 79.721494 -7.106478) (xy 79.635335 -7.124382) (xy 79.547905 -7.134377) (xy 79.459928 -7.136381)
			(xy 79.372134 -7.130375) (xy 79.28525 -7.116411) (xy 79.199995 -7.094604) (xy 79.117076 -7.065135)
			(xy 79.037181 -7.028248) (xy 78.960972 -6.984248) (xy 78.889079 -6.9335) (xy 78.822098 -6.876426)
			(xy 78.760586 -6.813496) (xy 78.70505 -6.745234) (xy 78.655952 -6.672205) (xy 78.613699 -6.595013)
			(xy 78.57864 -6.514299) (xy 78.551065 -6.430731) (xy 78.531205 -6.345002) (xy 78.519222 -6.257822)
			(xy 78.515217 -6.169914) (xy 13.611098 -6.169914) (xy 13.611098 -6.751654) (xy 18.635651 -6.751654)
			(xy 18.635651 -6.697146) (xy 18.643409 -6.643192) (xy 18.658767 -6.590891) (xy 18.681411 -6.541309)
			(xy 18.710882 -6.495454) (xy 18.746579 -6.45426) (xy 18.787775 -6.418566) (xy 18.833632 -6.389099)
			(xy 18.883216 -6.366458) (xy 18.935517 -6.351104) (xy 18.989472 -6.34335) (xy 19.016726 -6.342888)
			(xy 19.880326 -6.342888) (xy 19.907576 -6.343384) (xy 19.96152 -6.351143) (xy 20.013811 -6.3665)
			(xy 20.063385 -6.389143) (xy 20.109231 -6.418609) (xy 20.150418 -6.4543) (xy 20.186106 -6.49549)
			(xy 20.21557 -6.541338) (xy 20.238209 -6.590913) (xy 20.253563 -6.643205) (xy 20.261318 -6.69715)
			(xy 20.261318 -6.75165) (xy 22.235674 -6.75165) (xy 22.235674 -6.69715) (xy 22.243429 -6.643204)
			(xy 22.258783 -6.590912) (xy 22.281422 -6.541336) (xy 22.310886 -6.495487) (xy 22.346574 -6.454297)
			(xy 22.387761 -6.418605) (xy 22.433608 -6.389138) (xy 22.483182 -6.366494) (xy 22.535473 -6.351136)
			(xy 22.589418 -6.343376) (xy 22.616668 -6.342888) (xy 23.480268 -6.342888) (xy 23.507522 -6.343357)
			(xy 23.561476 -6.35111) (xy 23.613777 -6.366463) (xy 23.663361 -6.389104) (xy 23.709217 -6.418571)
			(xy 23.750413 -6.454264) (xy 23.78611 -6.495457) (xy 23.815581 -6.541311) (xy 23.838225 -6.590893)
			(xy 23.853583 -6.643193) (xy 23.861341 -6.697146) (xy 23.861341 -6.751654) (xy 25.835551 -6.751654)
			(xy 25.835551 -6.697146) (xy 25.843309 -6.643194) (xy 25.858665 -6.590895) (xy 25.881309 -6.541314)
			(xy 25.910778 -6.495459) (xy 25.946473 -6.454266) (xy 25.987667 -6.418572) (xy 26.033522 -6.389104)
			(xy 26.083104 -6.366462) (xy 26.135404 -6.351107) (xy 26.189356 -6.343351) (xy 26.21661 -6.342888)
			(xy 27.08021 -6.342888) (xy 27.10746 -6.343382) (xy 27.161407 -6.35114) (xy 27.2137 -6.366496) (xy 27.263275 -6.389137)
			(xy 27.309124 -6.418604) (xy 27.350312 -6.454295) (xy 27.386002 -6.495484) (xy 27.415467 -6.541334)
			(xy 27.438108 -6.59091) (xy 27.453462 -6.643203) (xy 27.461218 -6.697149) (xy 27.461218 -6.751651)
			(xy 27.461218 -6.751653) (xy 29.435751 -6.751653) (xy 29.435751 -6.697147) (xy 29.443509 -6.643195)
			(xy 29.458865 -6.590896) (xy 29.481508 -6.541315) (xy 29.510977 -6.495461) (xy 29.546672 -6.454268)
			(xy 29.587866 -6.418574) (xy 29.63372 -6.389105) (xy 29.683301 -6.366463) (xy 29.7356 -6.351107)
			(xy 29.789553 -6.343351) (xy 29.816806 -6.342888) (xy 30.680406 -6.342888) (xy 30.707657 -6.343382)
			(xy 30.761603 -6.351139) (xy 30.813897 -6.366495) (xy 30.863473 -6.389136) (xy 30.909322 -6.418602)
			(xy 30.950511 -6.454293) (xy 30.986201 -6.495483) (xy 31.015667 -6.541333) (xy 31.038307 -6.590909)
			(xy 31.053662 -6.643203) (xy 31.061418 -6.697149) (xy 31.061418 -6.75165) (xy 38.545774 -6.75165)
			(xy 38.545774 -6.69715) (xy 38.55353 -6.643204) (xy 38.568883 -6.590911) (xy 38.591522 -6.541336)
			(xy 38.620986 -6.495486) (xy 38.656675 -6.454296) (xy 38.697862 -6.418604) (xy 38.743709 -6.389137)
			(xy 38.793283 -6.366494) (xy 38.845575 -6.351136) (xy 38.89952 -6.343376) (xy 38.92677 -6.342888)
			(xy 39.79037 -6.342888) (xy 39.817624 -6.343357) (xy 39.871578 -6.351111) (xy 39.923878 -6.366464)
			(xy 39.973462 -6.389105) (xy 40.019318 -6.418571) (xy 40.060514 -6.454265) (xy 40.096211 -6.495458)
			(xy 40.125681 -6.541312) (xy 40.148326 -6.590893) (xy 40.163683 -6.643193) (xy 40.171441 -6.697146)
			(xy 40.171441 -6.751654) (xy 42.145651 -6.751654) (xy 42.145651 -6.697146) (xy 42.153409 -6.643194)
			(xy 42.168766 -6.590894) (xy 42.191409 -6.541313) (xy 42.220879 -6.495459) (xy 42.256574 -6.454265)
			(xy 42.297768 -6.418571) (xy 42.343624 -6.389103) (xy 42.393206 -6.366461) (xy 42.445506 -6.351106)
			(xy 42.499458 -6.343351) (xy 42.526712 -6.342888) (xy 43.390312 -6.342888) (xy 43.417562 -6.343383)
			(xy 43.471508 -6.35114) (xy 43.523801 -6.366496) (xy 43.573376 -6.389138) (xy 43.619225 -6.418604)
			(xy 43.660413 -6.454295) (xy 43.696103 -6.495485) (xy 43.725568 -6.541334) (xy 43.748208 -6.59091)
			(xy 43.763562 -6.643203) (xy 43.771318 -6.69715) (xy 43.771318 -6.75165) (xy 43.771318 -6.751653)
			(xy 49.755751 -6.751653) (xy 49.755751 -6.697147) (xy 49.763509 -6.643195) (xy 49.778865 -6.590896)
			(xy 49.801508 -6.541315) (xy 49.830977 -6.495461) (xy 49.866672 -6.454268) (xy 49.907866 -6.418574)
			(xy 49.95372 -6.389105) (xy 50.003301 -6.366463) (xy 50.0556 -6.351107) (xy 50.109553 -6.343351)
			(xy 50.136806 -6.342888) (xy 51.000406 -6.342888) (xy 51.027657 -6.343382) (xy 51.081603 -6.351139)
			(xy 51.133897 -6.366495) (xy 51.183473 -6.389136) (xy 51.229322 -6.418602) (xy 51.270511 -6.454293)
			(xy 51.306201 -6.495483) (xy 51.335667 -6.541333) (xy 51.358307 -6.590909) (xy 51.373662 -6.643203)
			(xy 51.381418 -6.697149) (xy 51.381418 -6.751651) (xy 51.381417 -6.751655) (xy 53.355652 -6.751655)
			(xy 53.355652 -6.697145) (xy 53.36341 -6.643189) (xy 53.378768 -6.590887) (xy 53.401415 -6.541303)
			(xy 53.430887 -6.495447) (xy 53.466587 -6.454253) (xy 53.507785 -6.418559) (xy 53.553645 -6.389092)
			(xy 53.603232 -6.366452) (xy 53.655536 -6.3511) (xy 53.709493 -6.343348) (xy 53.736748 -6.342888)
			(xy 54.600348 -6.342888) (xy 54.627597 -6.343385) (xy 54.681539 -6.351147) (xy 54.733827 -6.366506)
			(xy 54.783398 -6.38915) (xy 54.829242 -6.418617) (xy 54.870426 -6.454308) (xy 54.906112 -6.495497)
			(xy 54.935573 -6.541344) (xy 54.958211 -6.590918) (xy 54.973563 -6.643208) (xy 54.981318 -6.697151)
			(xy 54.981318 -6.751649) (xy 54.981318 -6.751651) (xy 56.955674 -6.751651) (xy 56.955674 -6.697149)
			(xy 56.96343 -6.643201) (xy 56.978785 -6.590907) (xy 57.001426 -6.54133) (xy 57.030891 -6.49548)
			(xy 57.066582 -6.454289) (xy 57.107771 -6.418597) (xy 57.153621 -6.38913) (xy 57.203198 -6.366488)
			(xy 57.255492 -6.351132) (xy 57.309439 -6.343374) (xy 57.33669 -6.342888) (xy 58.20029 -6.342888)
			(xy 58.227543 -6.343359) (xy 58.281494 -6.351114) (xy 58.333793 -6.366469) (xy 58.383374 -6.389111)
			(xy 58.429228 -6.418578) (xy 58.470421 -6.454272) (xy 58.506116 -6.495464) (xy 58.535584 -6.541317)
			(xy 58.558227 -6.590898) (xy 58.573583 -6.643196) (xy 58.581341 -6.697147) (xy 58.581341 -6.751651)
			(xy 70.950574 -6.751651) (xy 70.950574 -6.697149) (xy 70.95833 -6.643203) (xy 70.973684 -6.590909)
			(xy 70.996324 -6.541332) (xy 71.025789 -6.495482) (xy 71.061479 -6.454292) (xy 71.102668 -6.4186)
			(xy 71.148516 -6.389133) (xy 71.198092 -6.366491) (xy 71.250385 -6.351134) (xy 71.304331 -6.343375)
			(xy 71.331582 -6.342888) (xy 72.195182 -6.342888) (xy 72.222435 -6.343358) (xy 72.276388 -6.351113)
			(xy 72.328687 -6.366467) (xy 72.378269 -6.389108) (xy 72.424124 -6.418576) (xy 72.465318 -6.454269)
			(xy 72.501014 -6.495462) (xy 72.530483 -6.541315) (xy 72.553126 -6.590896) (xy 72.568483 -6.643195)
			(xy 72.576241 -6.697147) (xy 72.576241 -6.751653) (xy 72.568483 -6.805605) (xy 72.553126 -6.857904)
			(xy 72.530483 -6.907485) (xy 72.501014 -6.953338) (xy 72.465318 -6.994531) (xy 72.424124 -7.030224)
			(xy 72.378269 -7.059692) (xy 72.328687 -7.082333) (xy 72.276388 -7.097687) (xy 72.222435 -7.105442)
			(xy 72.195182 -7.105904) (xy 71.331582 -7.105904) (xy 71.304331 -7.105425) (xy 71.250385 -7.097666)
			(xy 71.198092 -7.082309) (xy 71.148516 -7.059667) (xy 71.102668 -7.0302) (xy 71.061479 -6.994508)
			(xy 71.025789 -6.953318) (xy 70.996324 -6.907468) (xy 70.973684 -6.857891) (xy 70.95833 -6.805597)
			(xy 70.950574 -6.751651) (xy 58.581341 -6.751651) (xy 58.581341 -6.751653) (xy 58.573583 -6.805604)
			(xy 58.558227 -6.857902) (xy 58.535584 -6.907483) (xy 58.506116 -6.953336) (xy 58.470421 -6.994528)
			(xy 58.429228 -7.030222) (xy 58.383374 -7.059689) (xy 58.333793 -7.082331) (xy 58.281494 -7.097686)
			(xy 58.227543 -7.105441) (xy 58.20029 -7.105904) (xy 57.33669 -7.105904) (xy 57.309439 -7.105426)
			(xy 57.255492 -7.097668) (xy 57.203198 -7.082312) (xy 57.153621 -7.05967) (xy 57.107771 -7.030203)
			(xy 57.066582 -6.994511) (xy 57.030891 -6.95332) (xy 57.001426 -6.90747) (xy 56.978785 -6.857893)
			(xy 56.96343 -6.805599) (xy 56.955674 -6.751651) (xy 54.981318 -6.751651) (xy 54.973563 -6.805592)
			(xy 54.958211 -6.857882) (xy 54.935573 -6.907456) (xy 54.906112 -6.953303) (xy 54.870426 -6.994492)
			(xy 54.829242 -7.030183) (xy 54.783398 -7.05965) (xy 54.733827 -7.082294) (xy 54.681539 -7.097653)
			(xy 54.627597 -7.105415) (xy 54.600348 -7.105904) (xy 53.736748 -7.105904) (xy 53.709493 -7.105452)
			(xy 53.655536 -7.0977) (xy 53.603232 -7.082348) (xy 53.553645 -7.059708) (xy 53.507785 -7.030241)
			(xy 53.466587 -6.994547) (xy 53.430887 -6.953353) (xy 53.401415 -6.907497) (xy 53.378768 -6.857913)
			(xy 53.36341 -6.805611) (xy 53.355652 -6.751655) (xy 51.381417 -6.751655) (xy 51.373662 -6.805597)
			(xy 51.358307 -6.857891) (xy 51.335667 -6.907467) (xy 51.306201 -6.953317) (xy 51.270511 -6.994507)
			(xy 51.229322 -7.030198) (xy 51.183473 -7.059664) (xy 51.133897 -7.082305) (xy 51.081603 -7.097661)
			(xy 51.027657 -7.105418) (xy 51.000406 -7.105904) (xy 50.136806 -7.105904) (xy 50.109553 -7.105449)
			(xy 50.0556 -7.097693) (xy 50.003301 -7.082337) (xy 49.95372 -7.059695) (xy 49.907866 -7.030226)
			(xy 49.866672 -6.994532) (xy 49.830977 -6.953339) (xy 49.801508 -6.907485) (xy 49.778865 -6.857904)
			(xy 49.763509 -6.805605) (xy 49.755751 -6.751653) (xy 43.771318 -6.751653) (xy 43.763562 -6.805597)
			(xy 43.748208 -6.85789) (xy 43.725568 -6.907466) (xy 43.696103 -6.953315) (xy 43.660413 -6.994505)
			(xy 43.619225 -7.030196) (xy 43.573376 -7.059662) (xy 43.523801 -7.082304) (xy 43.471508 -7.09766)
			(xy 43.417562 -7.105417) (xy 43.390312 -7.105904) (xy 42.526712 -7.105904) (xy 42.499458 -7.105449)
			(xy 42.445506 -7.097694) (xy 42.393206 -7.082339) (xy 42.343624 -7.059697) (xy 42.297768 -7.030229)
			(xy 42.256574 -6.994535) (xy 42.220879 -6.953341) (xy 42.191409 -6.907487) (xy 42.168766 -6.857906)
			(xy 42.153409 -6.805606) (xy 42.145651 -6.751654) (xy 40.171441 -6.751654) (xy 40.163683 -6.805607)
			(xy 40.148326 -6.857907) (xy 40.125681 -6.907488) (xy 40.096211 -6.953342) (xy 40.060514 -6.994535)
			(xy 40.019318 -7.030229) (xy 39.973462 -7.059695) (xy 39.923878 -7.082336) (xy 39.871578 -7.097689)
			(xy 39.817624 -7.105443) (xy 39.79037 -7.105904) (xy 38.92677 -7.105904) (xy 38.89952 -7.105424)
			(xy 38.845575 -7.097664) (xy 38.793283 -7.082306) (xy 38.743709 -7.059663) (xy 38.697862 -7.030196)
			(xy 38.656675 -6.994504) (xy 38.620986 -6.953314) (xy 38.591522 -6.907464) (xy 38.568883 -6.857889)
			(xy 38.55353 -6.805596) (xy 38.545774 -6.75165) (xy 31.061418 -6.75165) (xy 31.061418 -6.751651)
			(xy 31.053662 -6.805597) (xy 31.038307 -6.857891) (xy 31.015667 -6.907467) (xy 30.986201 -6.953317)
			(xy 30.950511 -6.994507) (xy 30.909322 -7.030198) (xy 30.863473 -7.059664) (xy 30.813897 -7.082305)
			(xy 30.761603 -7.097661) (xy 30.707657 -7.105418) (xy 30.680406 -7.105904) (xy 29.816806 -7.105904)
			(xy 29.789553 -7.105449) (xy 29.7356 -7.097693) (xy 29.683301 -7.082337) (xy 29.63372 -7.059695)
			(xy 29.587866 -7.030226) (xy 29.546672 -6.994532) (xy 29.510977 -6.953339) (xy 29.481508 -6.907485)
			(xy 29.458865 -6.857904) (xy 29.443509 -6.805605) (xy 29.435751 -6.751653) (xy 27.461218 -6.751653)
			(xy 27.453462 -6.805597) (xy 27.438108 -6.85789) (xy 27.415467 -6.907466) (xy 27.386002 -6.953316)
			(xy 27.350312 -6.994505) (xy 27.309124 -7.030196) (xy 27.263275 -7.059663) (xy 27.2137 -7.082304)
			(xy 27.161407 -7.09766) (xy 27.10746 -7.105418) (xy 27.08021 -7.105904) (xy 26.21661 -7.105904) (xy 26.189356 -7.105449)
			(xy 26.135404 -7.097693) (xy 26.083104 -7.082338) (xy 26.033522 -7.059696) (xy 25.987667 -7.030228)
			(xy 25.946473 -6.994534) (xy 25.910778 -6.953341) (xy 25.881309 -6.907486) (xy 25.858665 -6.857905)
			(xy 25.843309 -6.805606) (xy 25.835551 -6.751654) (xy 23.861341 -6.751654) (xy 23.853583 -6.805607)
			(xy 23.838225 -6.857907) (xy 23.815581 -6.907489) (xy 23.78611 -6.953343) (xy 23.750413 -6.994536)
			(xy 23.709217 -7.030229) (xy 23.663361 -7.059696) (xy 23.613777 -7.082337) (xy 23.561476 -7.09769)
			(xy 23.507522 -7.105443) (xy 23.480268 -7.105904) (xy 22.616668 -7.105904) (xy 22.589418 -7.105424)
			(xy 22.535473 -7.097664) (xy 22.483182 -7.082306) (xy 22.433608 -7.059662) (xy 22.387761 -7.030195)
			(xy 22.346574 -6.994503) (xy 22.310886 -6.953313) (xy 22.281422 -6.907464) (xy 22.258783 -6.857888)
			(xy 22.243429 -6.805596) (xy 22.235674 -6.75165) (xy 20.261318 -6.75165) (xy 20.253563 -6.805595)
			(xy 20.238209 -6.857887) (xy 20.21557 -6.907462) (xy 20.186106 -6.95331) (xy 20.150418 -6.9945) (xy 20.109231 -7.030191)
			(xy 20.063385 -7.059657) (xy 20.013811 -7.0823) (xy 19.96152 -7.097657) (xy 19.907576 -7.105416)
			(xy 19.880326 -7.105904) (xy 19.016726 -7.105904) (xy 18.989472 -7.10545) (xy 18.935517 -7.097696)
			(xy 18.883216 -7.082342) (xy 18.833632 -7.059701) (xy 18.787775 -7.030234) (xy 18.746579 -6.99454)
			(xy 18.710882 -6.953346) (xy 18.681411 -6.907491) (xy 18.658767 -6.857909) (xy 18.643409 -6.805608)
			(xy 18.635651 -6.751654) (xy 13.611098 -6.751654) (xy 13.611098 -9.780016) (xy 13.610604 -9.850398)
			(xy 13.602711 -9.990941) (xy 13.58695 -10.13082) (xy 13.563371 -10.269596) (xy 13.532048 -10.406831)
			(xy 13.493079 -10.542094) (xy 13.446587 -10.674959) (xy 13.392719 -10.805008) (xy 13.331643 -10.931832)
			(xy 13.263553 -11.055033) (xy 13.188662 -11.174221) (xy 13.107205 -11.289023) (xy 13.01944 -11.399077)
			(xy 12.925642 -11.504037) (xy 12.826107 -11.603572) (xy 12.721147 -11.69737) (xy 12.611093 -11.785135)
			(xy 12.496291 -11.866592) (xy 12.377103 -11.941483) (xy 12.253902 -12.009573) (xy 12.127078 -12.070649)
			(xy 11.997029 -12.124517) (xy 11.864164 -12.171009) (xy 11.728901 -12.209978) (xy 11.591666 -12.241301)
			(xy 11.45289 -12.26488) (xy 11.313011 -12.280641) (xy 11.172468 -12.288534) (xy 11.102086 -12.289028)
			(xy 1.999996 -12.289028) (xy 1.944227 -12.289537) (xy 1.833 -12.297872) (xy 1.722707 -12.314497)
			(xy 1.613965 -12.339317) (xy 1.507382 -12.372193) (xy 1.403554 -12.412943) (xy 1.303061 -12.461339)
			(xy 1.206466 -12.517108) (xy 1.114309 -12.579941) (xy 1.027105 -12.649484) (xy 0.945341 -12.72535)
			(xy 0.869476 -12.807114) (xy 0.802299 -12.891351) (xy 56.954662 -12.891351) (xy 56.954662 -12.836849)
			(xy 56.962418 -12.782901) (xy 56.977772 -12.730606) (xy 57.000413 -12.681029) (xy 57.029878 -12.635178)
			(xy 57.065568 -12.593986) (xy 57.106757 -12.558293) (xy 57.152606 -12.528825) (xy 57.202182 -12.506181)
			(xy 57.254476 -12.490823) (xy 57.308423 -12.483064) (xy 57.335674 -12.482576) (xy 58.199274 -12.482576)
			(xy 58.226527 -12.48307) (xy 58.280478 -12.490823) (xy 58.332777 -12.506176) (xy 58.382358 -12.528816)
			(xy 58.428213 -12.558282) (xy 58.469407 -12.593975) (xy 58.505102 -12.635166) (xy 58.534571 -12.681019)
			(xy 58.557215 -12.730598) (xy 58.572571 -12.782896) (xy 58.580329 -12.836847) (xy 58.580329 -12.891353)
			(xy 58.580329 -12.891355) (xy 70.949739 -12.891355) (xy 70.949739 -12.836845) (xy 70.957497 -12.78289)
			(xy 70.972854 -12.730588) (xy 70.995499 -12.681005) (xy 71.024971 -12.635149) (xy 71.060668 -12.593954)
			(xy 71.101865 -12.558259) (xy 71.147722 -12.52879) (xy 71.197307 -12.506147) (xy 71.24961 -12.490793)
			(xy 71.303565 -12.483038) (xy 71.33082 -12.482576) (xy 72.19442 -12.482576) (xy 72.221669 -12.483096)
			(xy 72.275612 -12.490854) (xy 72.327902 -12.50621) (xy 72.377475 -12.528852) (xy 72.423321 -12.558317)
			(xy 72.464507 -12.594007) (xy 72.500195 -12.635195) (xy 72.529658 -12.681043) (xy 72.552297 -12.730616)
			(xy 72.56765 -12.782907) (xy 72.575406 -12.836851) (xy 72.575406 -12.891349) (xy 72.56765 -12.945293)
			(xy 72.552297 -12.997584) (xy 72.529658 -13.047157) (xy 72.500195 -13.093005) (xy 72.464507 -13.134193)
			(xy 72.423321 -13.169883) (xy 72.377475 -13.199348) (xy 72.327902 -13.22199) (xy 72.275612 -13.237346)
			(xy 72.221669 -13.245104) (xy 72.19442 -13.245592) (xy 71.33082 -13.245592) (xy 71.303565 -13.245162)
			(xy 71.24961 -13.237407) (xy 71.197307 -13.222053) (xy 71.147722 -13.19941) (xy 71.101865 -13.169941)
			(xy 71.060668 -13.134246) (xy 71.024971 -13.093051) (xy 70.995499 -13.047195) (xy 70.972854 -12.997612)
			(xy 70.957497 -12.94531) (xy 70.949739 -12.891355) (xy 58.580329 -12.891355) (xy 58.572571 -12.945304)
			(xy 58.557215 -12.997602) (xy 58.534571 -13.047181) (xy 58.505102 -13.093034) (xy 58.469407 -13.134225)
			(xy 58.428213 -13.169918) (xy 58.382358 -13.199384) (xy 58.332777 -13.222024) (xy 58.280478 -13.237377)
			(xy 58.226527 -13.24513) (xy 58.199274 -13.245592) (xy 57.335674 -13.245592) (xy 57.308423 -13.245136)
			(xy 57.254476 -13.237377) (xy 57.202182 -13.222019) (xy 57.152606 -13.199375) (xy 57.106757 -13.169907)
			(xy 57.065568 -13.134214) (xy 57.029878 -13.093022) (xy 57.000413 -13.047171) (xy 56.977772 -12.997594)
			(xy 56.962418 -12.945299) (xy 56.954662 -12.891351) (xy 0.802299 -12.891351) (xy 0.799933 -12.894318)
			(xy 0.737102 -12.986476) (xy 0.681333 -13.083072) (xy 0.632939 -13.183565) (xy 0.59219 -13.287393)
			(xy 0.559313 -13.393977) (xy 0.534494 -13.502719) (xy 0.517871 -13.613012) (xy 0.509536 -13.724239)
			(xy 0.509016 -13.780008) (xy 0.509016 -15.222054) (xy 135.233343 -15.222054) (xy 135.233343 -15.167546)
			(xy 135.2411 -15.113592) (xy 135.256457 -15.061292) (xy 135.279101 -15.011709) (xy 135.308571 -14.965854)
			(xy 135.344267 -14.92466) (xy 135.385462 -14.888965) (xy 135.431318 -14.859497) (xy 135.480901 -14.836854)
			(xy 135.533202 -14.821498) (xy 135.587156 -14.813742) (xy 135.61441 -14.81328) (xy 136.47801 -14.81328)
			(xy 136.50526 -14.813791) (xy 136.559205 -14.821548) (xy 136.611497 -14.836904) (xy 136.661071 -14.859545)
			(xy 136.706919 -14.88901) (xy 136.748106 -14.924701) (xy 136.783796 -14.965889) (xy 136.81326 -15.011738)
			(xy 136.8359 -15.061313) (xy 136.851254 -15.113605) (xy 136.85901 -15.16755) (xy 136.85901 -15.22205)
			(xy 136.851254 -15.275995) (xy 136.8359 -15.328287) (xy 136.81326 -15.377862) (xy 136.783796 -15.423711)
			(xy 136.748106 -15.464899) (xy 136.706919 -15.50059) (xy 136.661071 -15.530055) (xy 136.611497 -15.552696)
			(xy 136.559205 -15.568052) (xy 136.50526 -15.575809) (xy 136.47801 -15.576296) (xy 135.61441 -15.576296)
			(xy 135.587156 -15.575858) (xy 135.533202 -15.568102) (xy 135.480901 -15.552746) (xy 135.431318 -15.530103)
			(xy 135.385462 -15.500635) (xy 135.344267 -15.46494) (xy 135.308571 -15.423746) (xy 135.279101 -15.377891)
			(xy 135.256457 -15.328308) (xy 135.2411 -15.276008) (xy 135.233343 -15.222054) (xy 0.509016 -15.222054)
			(xy 0.509016 -17.639611) (xy 15.152858 -17.639611) (xy 15.152858 -17.585109) (xy 15.160614 -17.531161)
			(xy 15.175969 -17.478867) (xy 15.19861 -17.42929) (xy 15.228076 -17.383439) (xy 15.263768 -17.342249)
			(xy 15.304958 -17.306558) (xy 15.350808 -17.277091) (xy 15.400385 -17.25445) (xy 15.452679 -17.239095)
			(xy 15.506627 -17.231338) (xy 15.533878 -17.230852) (xy 16.397478 -17.230852) (xy 16.424731 -17.231315)
			(xy 16.478682 -17.239072) (xy 16.53098 -17.254428) (xy 16.580561 -17.27707) (xy 16.626414 -17.306538)
			(xy 16.667607 -17.342232) (xy 16.703301 -17.383424) (xy 16.732769 -17.429278) (xy 16.755412 -17.478858)
			(xy 16.770768 -17.531156) (xy 16.778525 -17.585107) (xy 16.778525 -17.639611) (xy 20.740858 -17.639611)
			(xy 20.740858 -17.585109) (xy 20.748614 -17.531161) (xy 20.763969 -17.478867) (xy 20.78661 -17.42929)
			(xy 20.816076 -17.383439) (xy 20.851768 -17.342249) (xy 20.892958 -17.306558) (xy 20.938808 -17.277091)
			(xy 20.988385 -17.25445) (xy 21.040679 -17.239095) (xy 21.094627 -17.231338) (xy 21.121878 -17.230852)
			(xy 21.985478 -17.230852) (xy 22.012729 -17.231394) (xy 22.066677 -17.239147) (xy 22.118972 -17.2545)
			(xy 22.168549 -17.277139) (xy 22.2144 -17.306603) (xy 22.255591 -17.342293) (xy 22.291284 -17.383482)
			(xy 22.320751 -17.429331) (xy 22.343392 -17.478908) (xy 22.358748 -17.531202) (xy 22.366505 -17.585149)
			(xy 22.366505 -17.639651) (xy 22.366505 -17.639653) (xy 26.328838 -17.639653) (xy 26.328838 -17.585147)
			(xy 26.336595 -17.531195) (xy 26.35195 -17.478897) (xy 26.374592 -17.429316) (xy 26.404059 -17.383462)
			(xy 26.439752 -17.342268) (xy 26.480944 -17.306573) (xy 26.526797 -17.277103) (xy 26.576376 -17.254458)
			(xy 26.628674 -17.239099) (xy 26.682625 -17.231339) (xy 26.709878 -17.230852) (xy 27.573478 -17.230852)
			(xy 27.600729 -17.231394) (xy 27.654677 -17.239147) (xy 27.706972 -17.2545) (xy 27.756549 -17.277139)
			(xy 27.8024 -17.306603) (xy 27.843591 -17.342293) (xy 27.879284 -17.383482) (xy 27.908751 -17.429331)
			(xy 27.931392 -17.478908) (xy 27.946748 -17.531202) (xy 27.954505 -17.585149) (xy 27.954505 -17.639651)
			(xy 27.954505 -17.639653) (xy 31.916838 -17.639653) (xy 31.916838 -17.585147) (xy 31.924595 -17.531195)
			(xy 31.93995 -17.478897) (xy 31.962592 -17.429316) (xy 31.992059 -17.383462) (xy 32.027752 -17.342268)
			(xy 32.068944 -17.306573) (xy 32.114797 -17.277103) (xy 32.164376 -17.254458) (xy 32.216674 -17.239099)
			(xy 32.270625 -17.231339) (xy 32.297878 -17.230852) (xy 33.161478 -17.230852) (xy 33.188729 -17.231394)
			(xy 33.242677 -17.239147) (xy 33.294972 -17.2545) (xy 33.344549 -17.277139) (xy 33.3904 -17.306603)
			(xy 33.431591 -17.342293) (xy 33.467284 -17.383482) (xy 33.496751 -17.429331) (xy 33.519392 -17.478908)
			(xy 33.534748 -17.531202) (xy 33.542505 -17.585149) (xy 33.542505 -17.639651) (xy 33.542505 -17.639653)
			(xy 37.504838 -17.639653) (xy 37.504838 -17.585147) (xy 37.512595 -17.531195) (xy 37.52795 -17.478897)
			(xy 37.550592 -17.429316) (xy 37.580059 -17.383462) (xy 37.615752 -17.342268) (xy 37.656944 -17.306573)
			(xy 37.702797 -17.277103) (xy 37.752376 -17.254458) (xy 37.804674 -17.239099) (xy 37.858625 -17.231339)
			(xy 37.885878 -17.230852) (xy 38.749478 -17.230852) (xy 38.776729 -17.231394) (xy 38.830677 -17.239147)
			(xy 38.882972 -17.2545) (xy 38.932549 -17.277139) (xy 38.9784 -17.306603) (xy 39.019591 -17.342293)
			(xy 39.055284 -17.383482) (xy 39.084751 -17.429331) (xy 39.107392 -17.478908) (xy 39.122748 -17.531202)
			(xy 39.130505 -17.585149) (xy 39.130505 -17.639651) (xy 39.130505 -17.639654) (xy 43.398638 -17.639654)
			(xy 43.398638 -17.585146) (xy 43.406395 -17.531193) (xy 43.421751 -17.478894) (xy 43.444395 -17.429312)
			(xy 43.473863 -17.383457) (xy 43.509558 -17.342262) (xy 43.550752 -17.306567) (xy 43.596606 -17.277097)
			(xy 43.646188 -17.254454) (xy 43.698487 -17.239096) (xy 43.75244 -17.231338) (xy 43.779694 -17.230852)
			(xy 44.643294 -17.230852) (xy 44.670544 -17.231395) (xy 44.72449 -17.23915) (xy 44.776783 -17.254504)
			(xy 44.826359 -17.277144) (xy 44.872208 -17.306609) (xy 44.913397 -17.342299) (xy 44.949088 -17.383487)
			(xy 44.978553 -17.429336) (xy 45.001194 -17.478911) (xy 45.016548 -17.531204) (xy 45.024305 -17.58515)
			(xy 45.024305 -17.63965) (xy 45.024304 -17.639654) (xy 48.986638 -17.639654) (xy 48.986638 -17.585146)
			(xy 48.994395 -17.531193) (xy 49.009751 -17.478894) (xy 49.032395 -17.429312) (xy 49.061863 -17.383457)
			(xy 49.097558 -17.342262) (xy 49.138752 -17.306567) (xy 49.184606 -17.277097) (xy 49.234188 -17.254454)
			(xy 49.286487 -17.239096) (xy 49.34044 -17.231338) (xy 49.367694 -17.230852) (xy 50.231294 -17.230852)
			(xy 50.258544 -17.231395) (xy 50.31249 -17.23915) (xy 50.364783 -17.254504) (xy 50.414359 -17.277144)
			(xy 50.460208 -17.306609) (xy 50.501397 -17.342299) (xy 50.537088 -17.383487) (xy 50.566553 -17.429336)
			(xy 50.589194 -17.478911) (xy 50.604548 -17.531204) (xy 50.612305 -17.58515) (xy 50.612305 -17.63965)
			(xy 50.612304 -17.639657) (xy 54.608615 -17.639657) (xy 54.608615 -17.585143) (xy 54.616374 -17.531184)
			(xy 54.631733 -17.478878) (xy 54.65438 -17.42929) (xy 54.683854 -17.383431) (xy 54.719554 -17.342233)
			(xy 54.760755 -17.306536) (xy 54.806617 -17.277065) (xy 54.856206 -17.254422) (xy 54.908513 -17.239067)
			(xy 54.962473 -17.231313) (xy 54.98973 -17.230852) (xy 55.85333 -17.230852) (xy 55.880577 -17.23142)
			(xy 55.934516 -17.239179) (xy 55.986801 -17.254535) (xy 56.03637 -17.277176) (xy 56.082211 -17.30664)
			(xy 56.123394 -17.342328) (xy 56.159078 -17.383513) (xy 56.188538 -17.429357) (xy 56.211175 -17.478927)
			(xy 56.226527 -17.531214) (xy 56.234282 -17.585153) (xy 56.234282 -17.639647) (xy 56.226527 -17.693586)
			(xy 56.211175 -17.745873) (xy 56.188538 -17.795443) (xy 56.159078 -17.841287) (xy 56.123394 -17.882472)
			(xy 56.082211 -17.91816) (xy 56.03637 -17.947624) (xy 55.986801 -17.970265) (xy 55.934516 -17.985621)
			(xy 55.880577 -17.99338) (xy 55.85333 -17.993868) (xy 54.98973 -17.993868) (xy 54.962473 -17.993487)
			(xy 54.908513 -17.985733) (xy 54.856206 -17.970378) (xy 54.806617 -17.947735) (xy 54.760755 -17.918264)
			(xy 54.719554 -17.882567) (xy 54.683854 -17.841369) (xy 54.65438 -17.79551) (xy 54.631733 -17.745922)
			(xy 54.616374 -17.693616) (xy 54.608615 -17.639657) (xy 50.612304 -17.639657) (xy 50.604548 -17.693596)
			(xy 50.589194 -17.745889) (xy 50.566553 -17.795464) (xy 50.537088 -17.841313) (xy 50.501397 -17.882501)
			(xy 50.460208 -17.918191) (xy 50.414359 -17.947656) (xy 50.364783 -17.970296) (xy 50.31249 -17.98565)
			(xy 50.258544 -17.993405) (xy 50.231294 -17.993868) (xy 49.367694 -17.993868) (xy 49.34044 -17.993462)
			(xy 49.286487 -17.985704) (xy 49.234188 -17.970346) (xy 49.184606 -17.947703) (xy 49.138752 -17.918233)
			(xy 49.097558 -17.882538) (xy 49.061863 -17.841343) (xy 49.032395 -17.795488) (xy 49.009751 -17.745906)
			(xy 48.994395 -17.693607) (xy 48.986638 -17.639654) (xy 45.024304 -17.639654) (xy 45.016548 -17.693596)
			(xy 45.001194 -17.745889) (xy 44.978553 -17.795464) (xy 44.949088 -17.841313) (xy 44.913397 -17.882501)
			(xy 44.872208 -17.918191) (xy 44.826359 -17.947656) (xy 44.776783 -17.970296) (xy 44.72449 -17.98565)
			(xy 44.670544 -17.993405) (xy 44.643294 -17.993868) (xy 43.779694 -17.993868) (xy 43.75244 -17.993462)
			(xy 43.698487 -17.985704) (xy 43.646188 -17.970346) (xy 43.596606 -17.947703) (xy 43.550752 -17.918233)
			(xy 43.509558 -17.882538) (xy 43.473863 -17.841343) (xy 43.444395 -17.795488) (xy 43.421751 -17.745906)
			(xy 43.406395 -17.693607) (xy 43.398638 -17.639654) (xy 39.130505 -17.639654) (xy 39.122748 -17.693598)
			(xy 39.107392 -17.745892) (xy 39.084751 -17.795469) (xy 39.055284 -17.841318) (xy 39.019591 -17.882507)
			(xy 38.9784 -17.918197) (xy 38.932549 -17.947661) (xy 38.882972 -17.9703) (xy 38.830677 -17.985653)
			(xy 38.776729 -17.993406) (xy 38.749478 -17.993868) (xy 37.885878 -17.993868) (xy 37.858625 -17.993461)
			(xy 37.804674 -17.985701) (xy 37.752376 -17.970342) (xy 37.702797 -17.947697) (xy 37.656944 -17.918227)
			(xy 37.615752 -17.882532) (xy 37.580059 -17.841338) (xy 37.550592 -17.795484) (xy 37.52795 -17.745903)
			(xy 37.512595 -17.693605) (xy 37.504838 -17.639653) (xy 33.542505 -17.639653) (xy 33.534748 -17.693598)
			(xy 33.519392 -17.745892) (xy 33.496751 -17.795469) (xy 33.467284 -17.841318) (xy 33.431591 -17.882507)
			(xy 33.3904 -17.918197) (xy 33.344549 -17.947661) (xy 33.294972 -17.9703) (xy 33.242677 -17.985653)
			(xy 33.188729 -17.993406) (xy 33.161478 -17.993868) (xy 32.297878 -17.993868) (xy 32.270625 -17.993461)
			(xy 32.216674 -17.985701) (xy 32.164376 -17.970342) (xy 32.114797 -17.947697) (xy 32.068944 -17.918227)
			(xy 32.027752 -17.882532) (xy 31.992059 -17.841338) (xy 31.962592 -17.795484) (xy 31.93995 -17.745903)
			(xy 31.924595 -17.693605) (xy 31.916838 -17.639653) (xy 27.954505 -17.639653) (xy 27.946748 -17.693598)
			(xy 27.931392 -17.745892) (xy 27.908751 -17.795469) (xy 27.879284 -17.841318) (xy 27.843591 -17.882507)
			(xy 27.8024 -17.918197) (xy 27.756549 -17.947661) (xy 27.706972 -17.9703) (xy 27.654677 -17.985653)
			(xy 27.600729 -17.993406) (xy 27.573478 -17.993868) (xy 26.709878 -17.993868) (xy 26.682625 -17.993461)
			(xy 26.628674 -17.985701) (xy 26.576376 -17.970342) (xy 26.526797 -17.947697) (xy 26.480944 -17.918227)
			(xy 26.439752 -17.882532) (xy 26.404059 -17.841338) (xy 26.374592 -17.795484) (xy 26.35195 -17.745903)
			(xy 26.336595 -17.693605) (xy 26.328838 -17.639653) (xy 22.366505 -17.639653) (xy 22.358748 -17.693598)
			(xy 22.343392 -17.745892) (xy 22.320751 -17.795469) (xy 22.291284 -17.841318) (xy 22.255591 -17.882507)
			(xy 22.2144 -17.918197) (xy 22.168549 -17.947661) (xy 22.118972 -17.9703) (xy 22.066677 -17.985653)
			(xy 22.012729 -17.993406) (xy 21.985478 -17.993868) (xy 21.121878 -17.993868) (xy 21.094627 -17.993382)
			(xy 21.040679 -17.985625) (xy 20.988385 -17.97027) (xy 20.938808 -17.947629) (xy 20.892958 -17.918162)
			(xy 20.851768 -17.882471) (xy 20.816076 -17.841281) (xy 20.78661 -17.79543) (xy 20.763969 -17.745853)
			(xy 20.748614 -17.693559) (xy 20.740858 -17.639611) (xy 16.778525 -17.639611) (xy 16.778525 -17.639613)
			(xy 16.770768 -17.693564) (xy 16.755412 -17.745862) (xy 16.732769 -17.795442) (xy 16.703301 -17.841296)
			(xy 16.667607 -17.882488) (xy 16.626414 -17.918182) (xy 16.580561 -17.94765) (xy 16.53098 -17.970292)
			(xy 16.478682 -17.985648) (xy 16.424731 -17.993405) (xy 16.397478 -17.993868) (xy 15.533878 -17.993868)
			(xy 15.506627 -17.993382) (xy 15.452679 -17.985625) (xy 15.400385 -17.97027) (xy 15.350808 -17.947629)
			(xy 15.304958 -17.918162) (xy 15.263768 -17.882471) (xy 15.228076 -17.841281) (xy 15.19861 -17.79543)
			(xy 15.175969 -17.745853) (xy 15.160614 -17.693559) (xy 15.152858 -17.639611) (xy 0.509016 -17.639611)
			(xy 0.509016 -18.171947) (xy 131.633522 -18.171947) (xy 131.633522 -18.117453) (xy 131.641277 -18.063515)
			(xy 131.656629 -18.011229) (xy 131.679265 -17.961659) (xy 131.708725 -17.915816) (xy 131.744409 -17.874631)
			(xy 131.78559 -17.838944) (xy 131.831431 -17.80948) (xy 131.880999 -17.78684) (xy 131.933283 -17.771484)
			(xy 131.987221 -17.763724) (xy 132.014468 -17.763236) (xy 132.878068 -17.763236) (xy 132.905326 -17.763609)
			(xy 132.959286 -17.771363) (xy 133.011594 -17.786718) (xy 133.061184 -17.809361) (xy 133.107046 -17.838832)
			(xy 133.148248 -17.87453) (xy 133.183949 -17.915728) (xy 133.213423 -17.961588) (xy 133.236071 -18.011176)
			(xy 133.25143 -18.063483) (xy 133.259189 -18.117443) (xy 133.259189 -18.17195) (xy 137.033499 -18.17195)
			(xy 137.033499 -18.11745) (xy 137.041256 -18.063505) (xy 137.05661 -18.011212) (xy 137.079251 -17.961637)
			(xy 137.108716 -17.915789) (xy 137.144406 -17.874601) (xy 137.185595 -17.838911) (xy 137.231444 -17.809447)
			(xy 137.28102 -17.786807) (xy 137.333312 -17.771454) (xy 137.387258 -17.763699) (xy 137.414508 -17.763236)
			(xy 138.278108 -17.763236) (xy 138.305362 -17.763634) (xy 138.359315 -17.771393) (xy 138.411615 -17.78675)
			(xy 138.461197 -17.809395) (xy 138.507052 -17.838864) (xy 138.548246 -17.87456) (xy 138.58394 -17.915755)
			(xy 138.613409 -17.96161) (xy 138.636052 -18.011193) (xy 138.651409 -18.063493) (xy 138.659166 -18.117446)
			(xy 138.659166 -18.171946) (xy 140.633522 -18.171946) (xy 140.633522 -18.117454) (xy 140.641276 -18.063517)
			(xy 140.656627 -18.011232) (xy 140.679262 -17.961664) (xy 140.70872 -17.915822) (xy 140.744402 -17.874638)
			(xy 140.785582 -17.83895) (xy 140.83142 -17.809486) (xy 140.880986 -17.786845) (xy 140.933268 -17.771487)
			(xy 140.987204 -17.763726) (xy 141.01445 -17.763236) (xy 141.87805 -17.763236) (xy 141.905308 -17.763608)
			(xy 141.959271 -17.77136) (xy 142.011581 -17.786713) (xy 142.061173 -17.809355) (xy 142.107038 -17.838825)
			(xy 142.148241 -17.874523) (xy 142.183945 -17.915722) (xy 142.213421 -17.961583) (xy 142.236069 -18.011172)
			(xy 142.25143 -18.06348) (xy 142.259189 -18.117442) (xy 142.259189 -18.171951) (xy 185.748399 -18.171951)
			(xy 185.748399 -18.117449) (xy 185.756156 -18.063503) (xy 185.771511 -18.011209) (xy 185.794153 -17.961633)
			(xy 185.823619 -17.915784) (xy 185.859311 -17.874596) (xy 185.900502 -17.838906) (xy 185.946353 -17.809442)
			(xy 185.99593 -17.786804) (xy 186.048224 -17.771451) (xy 186.102171 -17.763698) (xy 186.129422 -17.763236)
			(xy 186.993022 -17.763236) (xy 187.020275 -17.763635) (xy 187.074227 -17.771395) (xy 187.126525 -17.786754)
			(xy 187.176105 -17.809399) (xy 187.201242 -17.825555) (xy 218.803143 -17.825555) (xy 218.803143 -17.771045)
			(xy 218.810901 -17.717091) (xy 218.826258 -17.66479) (xy 218.848903 -17.615207) (xy 218.878374 -17.569351)
			(xy 218.914071 -17.528157) (xy 218.955267 -17.492462) (xy 219.001124 -17.462993) (xy 219.050709 -17.440351)
			(xy 219.10301 -17.424996) (xy 219.156965 -17.417242) (xy 219.18422 -17.41678) (xy 220.04782 -17.41678)
			(xy 220.075069 -17.417292) (xy 220.129013 -17.42505) (xy 220.181304 -17.440407) (xy 220.230877 -17.463048)
			(xy 220.276723 -17.492514) (xy 220.31791 -17.528204) (xy 220.353598 -17.569393) (xy 220.383062 -17.615241)
			(xy 220.4057 -17.664815) (xy 220.421054 -17.717106) (xy 220.42881 -17.771051) (xy 220.42881 -17.825549)
			(xy 220.421054 -17.879494) (xy 220.4057 -17.931785) (xy 220.383062 -17.981359) (xy 220.353598 -18.027207)
			(xy 220.31791 -18.068396) (xy 220.276723 -18.104086) (xy 220.230877 -18.133552) (xy 220.181304 -18.156193)
			(xy 220.129013 -18.17155) (xy 220.075069 -18.179308) (xy 220.04782 -18.179796) (xy 219.18422 -18.179796)
			(xy 219.156965 -18.179358) (xy 219.10301 -18.171604) (xy 219.050709 -18.156249) (xy 219.001124 -18.133607)
			(xy 218.955267 -18.104138) (xy 218.914071 -18.068443) (xy 218.878374 -18.027249) (xy 218.848903 -17.981393)
			(xy 218.826258 -17.93181) (xy 218.810901 -17.879509) (xy 218.803143 -17.825555) (xy 187.201242 -17.825555)
			(xy 187.221958 -17.838869) (xy 187.263151 -17.874565) (xy 187.298844 -17.915759) (xy 187.328311 -17.961614)
			(xy 187.350954 -18.011196) (xy 187.366309 -18.063495) (xy 187.374066 -18.117447) (xy 187.374066 -18.171953)
			(xy 187.366309 -18.225905) (xy 187.350954 -18.278204) (xy 187.328311 -18.327786) (xy 187.298844 -18.373641)
			(xy 187.263151 -18.414835) (xy 187.221958 -18.450531) (xy 187.176105 -18.480001) (xy 187.126525 -18.502646)
			(xy 187.074227 -18.518005) (xy 187.020275 -18.525765) (xy 186.993022 -18.526252) (xy 186.129422 -18.526252)
			(xy 186.102171 -18.525702) (xy 186.048224 -18.517949) (xy 185.99593 -18.502596) (xy 185.946353 -18.479958)
			(xy 185.900502 -18.450494) (xy 185.859311 -18.414804) (xy 185.823619 -18.373616) (xy 185.794153 -18.327767)
			(xy 185.771511 -18.278191) (xy 185.756156 -18.225897) (xy 185.748399 -18.171951) (xy 142.259189 -18.171951)
			(xy 142.259189 -18.171958) (xy 142.25143 -18.22592) (xy 142.236069 -18.278228) (xy 142.213421 -18.327817)
			(xy 142.183945 -18.373678) (xy 142.148241 -18.414877) (xy 142.107038 -18.450575) (xy 142.061173 -18.480045)
			(xy 142.011581 -18.502687) (xy 141.959271 -18.51804) (xy 141.905308 -18.525792) (xy 141.87805 -18.526252)
			(xy 141.01445 -18.526252) (xy 140.987204 -18.525674) (xy 140.933268 -18.517913) (xy 140.880986 -18.502555)
			(xy 140.83142 -18.479914) (xy 140.785582 -18.45045) (xy 140.744402 -18.414762) (xy 140.70872 -18.373578)
			(xy 140.679262 -18.327736) (xy 140.656627 -18.278168) (xy 140.641276 -18.225883) (xy 140.633522 -18.171946)
			(xy 138.659166 -18.171946) (xy 138.659166 -18.171954) (xy 138.651409 -18.225907) (xy 138.636052 -18.278207)
			(xy 138.613409 -18.32779) (xy 138.58394 -18.373645) (xy 138.548246 -18.41484) (xy 138.507052 -18.450536)
			(xy 138.461197 -18.480005) (xy 138.411615 -18.50265) (xy 138.359315 -18.518007) (xy 138.305362 -18.525766)
			(xy 138.278108 -18.526252) (xy 137.414508 -18.526252) (xy 137.387258 -18.525701) (xy 137.333312 -18.517946)
			(xy 137.28102 -18.502593) (xy 137.231444 -18.479953) (xy 137.185595 -18.450489) (xy 137.144406 -18.414799)
			(xy 137.108716 -18.373611) (xy 137.079251 -18.327763) (xy 137.05661 -18.278188) (xy 137.041256 -18.225895)
			(xy 137.033499 -18.17195) (xy 133.259189 -18.17195) (xy 133.259189 -18.171957) (xy 133.25143 -18.225917)
			(xy 133.236071 -18.278224) (xy 133.213423 -18.327812) (xy 133.183949 -18.373672) (xy 133.148248 -18.41487)
			(xy 133.107046 -18.450568) (xy 133.061184 -18.480039) (xy 133.011594 -18.502682) (xy 132.959286 -18.518037)
			(xy 132.905326 -18.525791) (xy 132.878068 -18.526252) (xy 132.014468 -18.526252) (xy 131.987221 -18.525676)
			(xy 131.933283 -18.517916) (xy 131.880999 -18.50256) (xy 131.831431 -18.47992) (xy 131.78559 -18.450456)
			(xy 131.744409 -18.414769) (xy 131.708725 -18.373584) (xy 131.679265 -18.327741) (xy 131.656629 -18.278171)
			(xy 131.641277 -18.225885) (xy 131.633522 -18.171947) (xy 0.509016 -18.171947) (xy 0.509016 -19.163611)
			(xy 17.946858 -19.163611) (xy 17.946858 -19.109109) (xy 17.954614 -19.055161) (xy 17.969969 -19.002867)
			(xy 17.99261 -18.95329) (xy 18.022076 -18.907439) (xy 18.057768 -18.866249) (xy 18.098958 -18.830558)
			(xy 18.144808 -18.801091) (xy 18.194385 -18.77845) (xy 18.246679 -18.763095) (xy 18.300627 -18.755338)
			(xy 18.327878 -18.754852) (xy 19.191478 -18.754852) (xy 19.218731 -18.755315) (xy 19.272682 -18.763072)
			(xy 19.32498 -18.778428) (xy 19.374561 -18.80107) (xy 19.420414 -18.830538) (xy 19.461607 -18.866232)
			(xy 19.497301 -18.907424) (xy 19.526769 -18.953278) (xy 19.549412 -19.002858) (xy 19.564768 -19.055156)
			(xy 19.572525 -19.109107) (xy 19.572525 -19.163613) (xy 19.572519 -19.163653) (xy 23.534838 -19.163653)
			(xy 23.534838 -19.109147) (xy 23.542595 -19.055195) (xy 23.55795 -19.002897) (xy 23.580592 -18.953316)
			(xy 23.610059 -18.907462) (xy 23.645752 -18.866268) (xy 23.686944 -18.830573) (xy 23.732797 -18.801103)
			(xy 23.782376 -18.778458) (xy 23.834674 -18.763099) (xy 23.888625 -18.755339) (xy 23.915878 -18.754852)
			(xy 24.779478 -18.754852) (xy 24.806729 -18.755394) (xy 24.860677 -18.763147) (xy 24.912972 -18.7785)
			(xy 24.962549 -18.801139) (xy 25.0084 -18.830603) (xy 25.049591 -18.866293) (xy 25.085284 -18.907482)
			(xy 25.114751 -18.953331) (xy 25.137392 -19.002908) (xy 25.152748 -19.055202) (xy 25.160505 -19.109149)
			(xy 25.160505 -19.163651) (xy 25.160505 -19.163653) (xy 29.122838 -19.163653) (xy 29.122838 -19.109147)
			(xy 29.130595 -19.055195) (xy 29.14595 -19.002897) (xy 29.168592 -18.953316) (xy 29.198059 -18.907462)
			(xy 29.233752 -18.866268) (xy 29.274944 -18.830573) (xy 29.320797 -18.801103) (xy 29.370376 -18.778458)
			(xy 29.422674 -18.763099) (xy 29.476625 -18.755339) (xy 29.503878 -18.754852) (xy 30.367478 -18.754852)
			(xy 30.394729 -18.755394) (xy 30.448677 -18.763147) (xy 30.500972 -18.7785) (xy 30.550549 -18.801139)
			(xy 30.5964 -18.830603) (xy 30.637591 -18.866293) (xy 30.673284 -18.907482) (xy 30.702751 -18.953331)
			(xy 30.725392 -19.002908) (xy 30.740748 -19.055202) (xy 30.748505 -19.109149) (xy 30.748505 -19.163651)
			(xy 30.748505 -19.163653) (xy 34.710838 -19.163653) (xy 34.710838 -19.109147) (xy 34.718595 -19.055195)
			(xy 34.73395 -19.002897) (xy 34.756592 -18.953316) (xy 34.786059 -18.907462) (xy 34.821752 -18.866268)
			(xy 34.862944 -18.830573) (xy 34.908797 -18.801103) (xy 34.958376 -18.778458) (xy 35.010674 -18.763099)
			(xy 35.064625 -18.755339) (xy 35.091878 -18.754852) (xy 35.955478 -18.754852) (xy 35.982729 -18.755394)
			(xy 36.036677 -18.763147) (xy 36.088972 -18.7785) (xy 36.138549 -18.801139) (xy 36.1844 -18.830603)
			(xy 36.225591 -18.866293) (xy 36.261284 -18.907482) (xy 36.290751 -18.953331) (xy 36.313392 -19.002908)
			(xy 36.328748 -19.055202) (xy 36.336505 -19.109149) (xy 36.336505 -19.163651) (xy 36.336505 -19.163654)
			(xy 40.604638 -19.163654) (xy 40.604638 -19.109146) (xy 40.612395 -19.055193) (xy 40.627751 -19.002894)
			(xy 40.650395 -18.953312) (xy 40.679863 -18.907457) (xy 40.715558 -18.866262) (xy 40.756752 -18.830567)
			(xy 40.802606 -18.801097) (xy 40.852188 -18.778454) (xy 40.904487 -18.763096) (xy 40.95844 -18.755338)
			(xy 40.985694 -18.754852) (xy 41.849294 -18.754852) (xy 41.876544 -18.755395) (xy 41.93049 -18.76315)
			(xy 41.982783 -18.778504) (xy 42.032359 -18.801144) (xy 42.078208 -18.830609) (xy 42.119397 -18.866299)
			(xy 42.155088 -18.907487) (xy 42.184553 -18.953336) (xy 42.207194 -19.002911) (xy 42.222548 -19.055204)
			(xy 42.230305 -19.10915) (xy 42.230305 -19.16365) (xy 42.230304 -19.163654) (xy 46.192638 -19.163654)
			(xy 46.192638 -19.109146) (xy 46.200395 -19.055193) (xy 46.215751 -19.002894) (xy 46.238395 -18.953312)
			(xy 46.267863 -18.907457) (xy 46.303558 -18.866262) (xy 46.344752 -18.830567) (xy 46.390606 -18.801097)
			(xy 46.440188 -18.778454) (xy 46.492487 -18.763096) (xy 46.54644 -18.755338) (xy 46.573694 -18.754852)
			(xy 47.437294 -18.754852) (xy 47.464544 -18.755395) (xy 47.51849 -18.76315) (xy 47.570783 -18.778504)
			(xy 47.620359 -18.801144) (xy 47.666208 -18.830609) (xy 47.707397 -18.866299) (xy 47.743088 -18.907487)
			(xy 47.772553 -18.953336) (xy 47.795194 -19.002911) (xy 47.810548 -19.055204) (xy 47.818305 -19.10915)
			(xy 47.818305 -19.16365) (xy 47.818304 -19.163657) (xy 51.814615 -19.163657) (xy 51.814615 -19.109143)
			(xy 51.822374 -19.055184) (xy 51.837733 -19.002878) (xy 51.86038 -18.95329) (xy 51.889854 -18.907431)
			(xy 51.925554 -18.866233) (xy 51.966755 -18.830536) (xy 52.012617 -18.801065) (xy 52.062206 -18.778422)
			(xy 52.114513 -18.763067) (xy 52.168473 -18.755313) (xy 52.19573 -18.754852) (xy 53.05933 -18.754852)
			(xy 53.086577 -18.75542) (xy 53.140516 -18.763179) (xy 53.192801 -18.778535) (xy 53.24237 -18.801176)
			(xy 53.288211 -18.83064) (xy 53.329394 -18.866328) (xy 53.365078 -18.907513) (xy 53.394538 -18.953357)
			(xy 53.417175 -19.002927) (xy 53.432527 -19.055214) (xy 53.440282 -19.109153) (xy 53.440282 -19.163647)
			(xy 53.440281 -19.163657) (xy 57.402615 -19.163657) (xy 57.402615 -19.109143) (xy 57.410374 -19.055184)
			(xy 57.425733 -19.002878) (xy 57.44838 -18.95329) (xy 57.477854 -18.907431) (xy 57.513554 -18.866233)
			(xy 57.554755 -18.830536) (xy 57.600617 -18.801065) (xy 57.650206 -18.778422) (xy 57.702513 -18.763067)
			(xy 57.756473 -18.755313) (xy 57.78373 -18.754852) (xy 58.64733 -18.754852) (xy 58.674577 -18.75542)
			(xy 58.728516 -18.763179) (xy 58.780801 -18.778535) (xy 58.83037 -18.801176) (xy 58.876211 -18.83064)
			(xy 58.917394 -18.866328) (xy 58.953078 -18.907513) (xy 58.982538 -18.953357) (xy 59.005175 -19.002927)
			(xy 59.020527 -19.055214) (xy 59.028282 -19.109153) (xy 59.028282 -19.163647) (xy 59.020527 -19.217586)
			(xy 59.005175 -19.269873) (xy 58.982538 -19.319443) (xy 58.953078 -19.365287) (xy 58.917394 -19.406472)
			(xy 58.876211 -19.44216) (xy 58.83037 -19.471624) (xy 58.780801 -19.494265) (xy 58.728516 -19.509621)
			(xy 58.674577 -19.51738) (xy 58.64733 -19.517868) (xy 57.78373 -19.517868) (xy 57.756473 -19.517487)
			(xy 57.702513 -19.509733) (xy 57.650206 -19.494378) (xy 57.600617 -19.471735) (xy 57.554755 -19.442264)
			(xy 57.513554 -19.406567) (xy 57.477854 -19.365369) (xy 57.44838 -19.31951) (xy 57.425733 -19.269922)
			(xy 57.410374 -19.217616) (xy 57.402615 -19.163657) (xy 53.440281 -19.163657) (xy 53.432527 -19.217586)
			(xy 53.417175 -19.269873) (xy 53.394538 -19.319443) (xy 53.365078 -19.365287) (xy 53.329394 -19.406472)
			(xy 53.288211 -19.44216) (xy 53.24237 -19.471624) (xy 53.192801 -19.494265) (xy 53.140516 -19.509621)
			(xy 53.086577 -19.51738) (xy 53.05933 -19.517868) (xy 52.19573 -19.517868) (xy 52.168473 -19.517487)
			(xy 52.114513 -19.509733) (xy 52.062206 -19.494378) (xy 52.012617 -19.471735) (xy 51.966755 -19.442264)
			(xy 51.925554 -19.406567) (xy 51.889854 -19.365369) (xy 51.86038 -19.31951) (xy 51.837733 -19.269922)
			(xy 51.822374 -19.217616) (xy 51.814615 -19.163657) (xy 47.818304 -19.163657) (xy 47.810548 -19.217596)
			(xy 47.795194 -19.269889) (xy 47.772553 -19.319464) (xy 47.743088 -19.365313) (xy 47.707397 -19.406501)
			(xy 47.666208 -19.442191) (xy 47.620359 -19.471656) (xy 47.570783 -19.494296) (xy 47.51849 -19.50965)
			(xy 47.464544 -19.517405) (xy 47.437294 -19.517868) (xy 46.573694 -19.517868) (xy 46.54644 -19.517462)
			(xy 46.492487 -19.509704) (xy 46.440188 -19.494346) (xy 46.390606 -19.471703) (xy 46.344752 -19.442233)
			(xy 46.303558 -19.406538) (xy 46.267863 -19.365343) (xy 46.238395 -19.319488) (xy 46.215751 -19.269906)
			(xy 46.200395 -19.217607) (xy 46.192638 -19.163654) (xy 42.230304 -19.163654) (xy 42.222548 -19.217596)
			(xy 42.207194 -19.269889) (xy 42.184553 -19.319464) (xy 42.155088 -19.365313) (xy 42.119397 -19.406501)
			(xy 42.078208 -19.442191) (xy 42.032359 -19.471656) (xy 41.982783 -19.494296) (xy 41.93049 -19.50965)
			(xy 41.876544 -19.517405) (xy 41.849294 -19.517868) (xy 40.985694 -19.517868) (xy 40.95844 -19.517462)
			(xy 40.904487 -19.509704) (xy 40.852188 -19.494346) (xy 40.802606 -19.471703) (xy 40.756752 -19.442233)
			(xy 40.715558 -19.406538) (xy 40.679863 -19.365343) (xy 40.650395 -19.319488) (xy 40.627751 -19.269906)
			(xy 40.612395 -19.217607) (xy 40.604638 -19.163654) (xy 36.336505 -19.163654) (xy 36.328748 -19.217598)
			(xy 36.313392 -19.269892) (xy 36.290751 -19.319469) (xy 36.261284 -19.365318) (xy 36.225591 -19.406507)
			(xy 36.1844 -19.442197) (xy 36.138549 -19.471661) (xy 36.088972 -19.4943) (xy 36.036677 -19.509653)
			(xy 35.982729 -19.517406) (xy 35.955478 -19.517868) (xy 35.091878 -19.517868) (xy 35.064625 -19.517461)
			(xy 35.010674 -19.509701) (xy 34.958376 -19.494342) (xy 34.908797 -19.471697) (xy 34.862944 -19.442227)
			(xy 34.821752 -19.406532) (xy 34.786059 -19.365338) (xy 34.756592 -19.319484) (xy 34.73395 -19.269903)
			(xy 34.718595 -19.217605) (xy 34.710838 -19.163653) (xy 30.748505 -19.163653) (xy 30.740748 -19.217598)
			(xy 30.725392 -19.269892) (xy 30.702751 -19.319469) (xy 30.673284 -19.365318) (xy 30.637591 -19.406507)
			(xy 30.5964 -19.442197) (xy 30.550549 -19.471661) (xy 30.500972 -19.4943) (xy 30.448677 -19.509653)
			(xy 30.394729 -19.517406) (xy 30.367478 -19.517868) (xy 29.503878 -19.517868) (xy 29.476625 -19.517461)
			(xy 29.422674 -19.509701) (xy 29.370376 -19.494342) (xy 29.320797 -19.471697) (xy 29.274944 -19.442227)
			(xy 29.233752 -19.406532) (xy 29.198059 -19.365338) (xy 29.168592 -19.319484) (xy 29.14595 -19.269903)
			(xy 29.130595 -19.217605) (xy 29.122838 -19.163653) (xy 25.160505 -19.163653) (xy 25.152748 -19.217598)
			(xy 25.137392 -19.269892) (xy 25.114751 -19.319469) (xy 25.085284 -19.365318) (xy 25.049591 -19.406507)
			(xy 25.0084 -19.442197) (xy 24.962549 -19.471661) (xy 24.912972 -19.4943) (xy 24.860677 -19.509653)
			(xy 24.806729 -19.517406) (xy 24.779478 -19.517868) (xy 23.915878 -19.517868) (xy 23.888625 -19.517461)
			(xy 23.834674 -19.509701) (xy 23.782376 -19.494342) (xy 23.732797 -19.471697) (xy 23.686944 -19.442227)
			(xy 23.645752 -19.406532) (xy 23.610059 -19.365338) (xy 23.580592 -19.319484) (xy 23.55795 -19.269903)
			(xy 23.542595 -19.217605) (xy 23.534838 -19.163653) (xy 19.572519 -19.163653) (xy 19.564768 -19.217564)
			(xy 19.549412 -19.269862) (xy 19.526769 -19.319442) (xy 19.497301 -19.365296) (xy 19.461607 -19.406488)
			(xy 19.420414 -19.442182) (xy 19.374561 -19.47165) (xy 19.32498 -19.494292) (xy 19.272682 -19.509648)
			(xy 19.218731 -19.517405) (xy 19.191478 -19.517868) (xy 18.327878 -19.517868) (xy 18.300627 -19.517382)
			(xy 18.246679 -19.509625) (xy 18.194385 -19.49427) (xy 18.144808 -19.471629) (xy 18.098958 -19.442162)
			(xy 18.057768 -19.406471) (xy 18.022076 -19.365281) (xy 17.99261 -19.31943) (xy 17.969969 -19.269853)
			(xy 17.954614 -19.217559) (xy 17.946858 -19.163611) (xy 0.509016 -19.163611) (xy 0.509016 -20.187751)
			(xy 138.828766 -20.187751) (xy 138.828766 -20.133249) (xy 138.836522 -20.079301) (xy 138.851877 -20.027006)
			(xy 138.874517 -19.977429) (xy 138.903982 -19.931578) (xy 138.939673 -19.890387) (xy 138.980862 -19.854694)
			(xy 139.026711 -19.825227) (xy 139.076288 -19.802584) (xy 139.128582 -19.787226) (xy 139.182529 -19.779467)
			(xy 139.20978 -19.77898) (xy 140.07338 -19.77898) (xy 140.100633 -19.779466) (xy 140.154584 -19.78722)
			(xy 140.206883 -19.802574) (xy 140.256464 -19.825215) (xy 140.302318 -19.854681) (xy 140.343512 -19.890374)
			(xy 140.379207 -19.931566) (xy 140.408676 -19.977418) (xy 140.431319 -20.026998) (xy 140.446675 -20.079296)
			(xy 140.454433 -20.133247) (xy 140.454433 -20.187753) (xy 140.446675 -20.241704) (xy 140.431319 -20.294002)
			(xy 140.408676 -20.343582) (xy 140.379207 -20.389434) (xy 140.343512 -20.430626) (xy 140.302318 -20.466319)
			(xy 140.256464 -20.495785) (xy 140.206883 -20.518426) (xy 140.154584 -20.53378) (xy 140.100633 -20.541534)
			(xy 140.07338 -20.541996) (xy 139.20978 -20.541996) (xy 139.182529 -20.541533) (xy 139.128582 -20.533774)
			(xy 139.076288 -20.518416) (xy 139.026711 -20.495773) (xy 138.980862 -20.466306) (xy 138.939673 -20.430613)
			(xy 138.903982 -20.389422) (xy 138.874517 -20.343571) (xy 138.851877 -20.293994) (xy 138.836522 -20.241699)
			(xy 138.828766 -20.187751) (xy 0.509016 -20.187751) (xy 0.509016 -21.521251) (xy 15.232366 -21.521251)
			(xy 15.232366 -21.466749) (xy 15.240122 -21.412801) (xy 15.255477 -21.360506) (xy 15.278117 -21.310929)
			(xy 15.307582 -21.265078) (xy 15.343273 -21.223887) (xy 15.384462 -21.188194) (xy 15.430311 -21.158727)
			(xy 15.479888 -21.136084) (xy 15.532182 -21.120726) (xy 15.586129 -21.112967) (xy 15.61338 -21.11248)
			(xy 16.47698 -21.11248) (xy 16.504233 -21.112966) (xy 16.558184 -21.12072) (xy 16.610483 -21.136074)
			(xy 16.660064 -21.158715) (xy 16.705918 -21.188181) (xy 16.747112 -21.223874) (xy 16.782807 -21.265066)
			(xy 16.812276 -21.310918) (xy 16.834919 -21.360498) (xy 16.850275 -21.412796) (xy 16.858033 -21.466747)
			(xy 16.858033 -21.521253) (xy 16.850275 -21.575204) (xy 16.834919 -21.627502) (xy 16.812276 -21.677082)
			(xy 16.782807 -21.722934) (xy 16.747112 -21.764126) (xy 16.705918 -21.799819) (xy 16.660064 -21.829285)
			(xy 16.610483 -21.851926) (xy 16.558184 -21.86728) (xy 16.504233 -21.875034) (xy 16.47698 -21.875496)
			(xy 15.61338 -21.875496) (xy 15.586129 -21.875033) (xy 15.532182 -21.867274) (xy 15.479888 -21.851916)
			(xy 15.430311 -21.829273) (xy 15.384462 -21.799806) (xy 15.343273 -21.764113) (xy 15.307582 -21.722922)
			(xy 15.278117 -21.677071) (xy 15.255477 -21.627494) (xy 15.240122 -21.575199) (xy 15.232366 -21.521251)
			(xy 0.509016 -21.521251) (xy 0.509016 -24.929338) (xy 133.555232 -24.929338) (xy 133.555232 -24.065738)
			(xy 133.555718 -24.038487) (xy 133.563474 -23.984539) (xy 133.578829 -23.932244) (xy 133.601471 -23.882667)
			(xy 133.630937 -23.836817) (xy 133.666628 -23.795626) (xy 133.707819 -23.759935) (xy 133.753669 -23.730469)
			(xy 133.803246 -23.707827) (xy 133.855541 -23.692472) (xy 133.909489 -23.684716) (xy 133.963991 -23.684716)
			(xy 134.017939 -23.692472) (xy 134.070234 -23.707827) (xy 134.119811 -23.730469) (xy 134.165661 -23.759935)
			(xy 134.206852 -23.795626) (xy 134.242543 -23.836817) (xy 134.272009 -23.882667) (xy 134.294651 -23.932244)
			(xy 134.310006 -23.984539) (xy 134.317762 -24.038487) (xy 134.318248 -24.065738) (xy 134.318248 -24.929338)
			(xy 134.317762 -24.956589) (xy 134.310006 -25.010537) (xy 134.294651 -25.062832) (xy 134.272009 -25.112409)
			(xy 134.242543 -25.158259) (xy 134.206852 -25.19945) (xy 134.165661 -25.235141) (xy 134.119811 -25.264607)
			(xy 134.070234 -25.287249) (xy 134.017939 -25.302604) (xy 133.963991 -25.31036) (xy 133.909489 -25.31036)
			(xy 133.855541 -25.302604) (xy 133.803246 -25.287249) (xy 133.753669 -25.264607) (xy 133.707819 -25.235141)
			(xy 133.666628 -25.19945) (xy 133.630937 -25.158259) (xy 133.601471 -25.112409) (xy 133.578829 -25.062832)
			(xy 133.563474 -25.010537) (xy 133.555718 -24.956589) (xy 133.555232 -24.929338) (xy 0.509016 -24.929338)
			(xy 0.509016 -29.070615) (xy 12.244307 -29.070615) (xy 12.252198 -28.941486) (xy 12.268182 -28.813107)
			(xy 12.292195 -28.685984) (xy 12.324144 -28.560621) (xy 12.363901 -28.437511) (xy 12.41131 -28.31714)
			(xy 12.466183 -28.199984) (xy 12.528305 -28.086504) (xy 12.59743 -27.97715) (xy 12.673285 -27.872351)
			(xy 12.75557 -27.772522) (xy 12.843962 -27.678057) (xy 12.938111 -27.589329) (xy 13.037646 -27.506688)
			(xy 13.142173 -27.43046) (xy 13.25128 -27.360945) (xy 13.364537 -27.298419) (xy 13.481497 -27.243128)
			(xy 13.601698 -27.19529) (xy 13.724665 -27.155093) (xy 13.849914 -27.122698) (xy 13.97695 -27.098231)
			(xy 14.105271 -27.081789) (xy 14.234372 -27.073437) (xy 14.363742 -27.073208) (xy 14.492871 -27.081103)
			(xy 14.62125 -27.097091) (xy 14.748372 -27.121108) (xy 14.873734 -27.15306) (xy 14.996843 -27.19282)
			(xy 15.117212 -27.240232) (xy 15.234367 -27.295109) (xy 15.347845 -27.357234) (xy 15.457198 -27.426362)
			(xy 15.561994 -27.50222) (xy 15.661821 -27.584508) (xy 15.709392 -27.628342) (xy 16.877792 -28.721304)
			(xy 16.92464 -28.765906) (xy 17.013363 -28.860052) (xy 17.096 -28.959584) (xy 17.172224 -29.064107)
			(xy 17.241734 -29.17321) (xy 17.304257 -29.286463) (xy 17.359545 -29.403418) (xy 17.407381 -29.523614)
			(xy 17.447575 -29.646576) (xy 17.479969 -29.771819) (xy 17.504435 -29.898849) (xy 17.520877 -30.027165)
			(xy 17.529229 -30.15626) (xy 17.529459 -30.285624) (xy 17.521566 -30.414748) (xy 17.50558 -30.543122)
			(xy 17.481566 -30.670238) (xy 17.449617 -30.795596) (xy 17.40986 -30.9187) (xy 17.362452 -31.039065)
			(xy 17.30758 -31.156215) (xy 17.24546 -31.26969) (xy 17.176338 -31.379039) (xy 17.100486 -31.483833)
			(xy 17.018204 -31.583657) (xy 16.929816 -31.678118) (xy 16.835671 -31.766843) (xy 16.736141 -31.849481)
			(xy 16.631619 -31.925706) (xy 16.522517 -31.995218) (xy 16.409265 -32.057743) (xy 16.292311 -32.113033)
			(xy 16.172116 -32.16087) (xy 16.049154 -32.201066) (xy 15.923911 -32.233462) (xy 15.796882 -32.25793)
			(xy 15.668566 -32.274374) (xy 15.539471 -32.282728) (xy 15.410107 -32.28296) (xy 15.280983 -32.275069)
			(xy 15.152609 -32.259085) (xy 15.025493 -32.235073) (xy 14.900134 -32.203126) (xy 14.77703 -32.163371)
			(xy 14.656664 -32.115965) (xy 14.539512 -32.061094) (xy 14.426037 -31.998976) (xy 14.316687 -31.929855)
			(xy 14.211892 -31.854005) (xy 14.112066 -31.771724) (xy 14.064488 -31.727902) (xy 12.896088 -30.63494)
			(xy 12.849198 -30.590378) (xy 12.760467 -30.496232) (xy 12.677823 -30.3967) (xy 12.601592 -30.292174)
			(xy 12.532074 -30.183069) (xy 12.469545 -30.069814) (xy 12.41425 -29.952855) (xy 12.366409 -29.832656)
			(xy 12.32621 -29.70969) (xy 12.293811 -29.584442) (xy 12.26934 -29.457407) (xy 12.252895 -29.329086)
			(xy 12.244539 -29.199985) (xy 12.244307 -29.070615) (xy 0.509016 -29.070615) (xy 0.509016 -37.099629)
			(xy 170.600616 -37.099629) (xy 170.600616 -37.000299) (xy 170.608608 -36.901292) (xy 170.624542 -36.803249)
			(xy 170.648313 -36.706806) (xy 170.679768 -36.612588) (xy 170.718701 -36.521208) (xy 170.764862 -36.433256)
			(xy 170.81795 -36.349304) (xy 170.877621 -36.269895) (xy 170.943489 -36.195546) (xy 171.015126 -36.126738)
			(xy 171.092067 -36.063918) (xy 171.173813 -36.007493) (xy 171.259835 -35.957828) (xy 171.349574 -35.915246)
			(xy 171.442448 -35.880024) (xy 171.537856 -35.852388) (xy 171.635178 -35.83252) (xy 171.733783 -35.820547)
			(xy 171.833032 -35.816548) (xy 171.932281 -35.820547) (xy 172.030886 -35.83252) (xy 172.128208 -35.852388)
			(xy 172.223616 -35.880024) (xy 172.31649 -35.915246) (xy 172.406229 -35.957828) (xy 172.492251 -36.007493)
			(xy 172.573997 -36.063918) (xy 172.650938 -36.126738) (xy 172.722575 -36.195546) (xy 172.788443 -36.269895)
			(xy 172.848114 -36.349304) (xy 172.901202 -36.433256) (xy 172.947363 -36.521208) (xy 172.986296 -36.612588)
			(xy 173.017751 -36.706806) (xy 173.041522 -36.803249) (xy 173.057456 -36.901292) (xy 173.065448 -37.000299)
			(xy 173.065948 -37.049964) (xy 173.065448 -37.099629) (xy 173.057456 -37.198636) (xy 173.041522 -37.296679)
			(xy 173.017751 -37.393122) (xy 172.986296 -37.48734) (xy 172.947363 -37.57872) (xy 172.901202 -37.666672)
			(xy 172.848114 -37.750624) (xy 172.788443 -37.830033) (xy 172.722575 -37.904382) (xy 172.650938 -37.97319)
			(xy 172.573997 -38.03601) (xy 172.492251 -38.092435) (xy 172.406229 -38.1421) (xy 172.31649 -38.184682)
			(xy 172.223616 -38.219904) (xy 172.128208 -38.24754) (xy 172.030886 -38.267408) (xy 171.932281 -38.279381)
			(xy 171.833032 -38.283381) (xy 171.733783 -38.279381) (xy 171.635178 -38.267408) (xy 171.537856 -38.24754)
			(xy 171.442448 -38.219904) (xy 171.349574 -38.184682) (xy 171.259835 -38.1421) (xy 171.173813 -38.092435)
			(xy 171.092067 -38.03601) (xy 171.015126 -37.97319) (xy 170.943489 -37.904382) (xy 170.877621 -37.830033)
			(xy 170.81795 -37.750624) (xy 170.764862 -37.666672) (xy 170.718701 -37.57872) (xy 170.679768 -37.48734)
			(xy 170.648313 -37.393122) (xy 170.624542 -37.296679) (xy 170.608608 -37.198636) (xy 170.600616 -37.099629)
			(xy 0.509016 -37.099629) (xy 0.509016 -39.657528) (xy 357.003604 -39.657528) (xy 357.003604 -38.793928)
			(xy 357.00409 -38.766659) (xy 357.011852 -38.712675) (xy 357.027217 -38.660345) (xy 357.049874 -38.610735)
			(xy 357.07936 -38.564854) (xy 357.115075 -38.523637) (xy 357.156292 -38.487922) (xy 357.202173 -38.458436)
			(xy 357.251783 -38.435779) (xy 357.304113 -38.420414) (xy 357.358097 -38.412652) (xy 357.412635 -38.412652)
			(xy 357.466619 -38.420414) (xy 357.518949 -38.435779) (xy 357.568559 -38.458436) (xy 357.61444 -38.487922)
			(xy 357.655657 -38.523637) (xy 357.691372 -38.564854) (xy 357.720858 -38.610735) (xy 357.743515 -38.660345)
			(xy 357.75888 -38.712675) (xy 357.766642 -38.766659) (xy 357.767128 -38.793928) (xy 357.767128 -39.657528)
			(xy 357.766642 -39.684797) (xy 357.75888 -39.738781) (xy 357.743515 -39.791111) (xy 357.720858 -39.840721)
			(xy 357.691372 -39.886602) (xy 357.655657 -39.927819) (xy 357.61444 -39.963534) (xy 357.568559 -39.99302)
			(xy 357.518949 -40.015677) (xy 357.466619 -40.031042) (xy 357.412635 -40.038804) (xy 357.358097 -40.038804)
			(xy 357.304113 -40.031042) (xy 357.251783 -40.015677) (xy 357.202173 -39.99302) (xy 357.156292 -39.963534)
			(xy 357.115075 -39.927819) (xy 357.07936 -39.886602) (xy 357.049874 -39.840721) (xy 357.027217 -39.791111)
			(xy 357.011852 -39.738781) (xy 357.00409 -39.684797) (xy 357.003604 -39.657528) (xy 0.509016 -39.657528)
			(xy 0.509016 -40.744902) (xy 235.083357 -40.744902) (xy 235.087362 -40.656994) (xy 235.099345 -40.569814)
			(xy 235.119205 -40.484085) (xy 235.14678 -40.400517) (xy 235.181839 -40.319803) (xy 235.224092 -40.242611)
			(xy 235.27319 -40.169582) (xy 235.328726 -40.10132) (xy 235.390238 -40.03839) (xy 235.457219 -39.981316)
			(xy 235.529112 -39.930568) (xy 235.605321 -39.886568) (xy 235.685216 -39.849681) (xy 235.768135 -39.820212)
			(xy 235.85339 -39.798405) (xy 235.940274 -39.784441) (xy 236.028068 -39.778435) (xy 236.116045 -39.780439)
			(xy 236.203475 -39.790434) (xy 236.289634 -39.808338) (xy 236.373808 -39.834002) (xy 236.455299 -39.867215)
			(xy 236.533433 -39.907701) (xy 236.607561 -39.955123) (xy 236.677069 -40.00909) (xy 236.741383 -40.069155)
			(xy 236.799967 -40.134819) (xy 236.852338 -40.205538) (xy 236.898061 -40.280726) (xy 236.936758 -40.359761)
			(xy 236.968107 -40.441987) (xy 236.991849 -40.526723) (xy 237.007787 -40.613267) (xy 237.015789 -40.700902)
			(xy 237.01629 -40.744902) (xy 237.015789 -40.788902) (xy 237.007787 -40.876537) (xy 236.991849 -40.963081)
			(xy 236.968107 -41.047817) (xy 236.936758 -41.130043) (xy 236.898061 -41.209078) (xy 236.852338 -41.284266)
			(xy 236.799967 -41.354985) (xy 236.741383 -41.420649) (xy 236.677069 -41.480714) (xy 236.607561 -41.534681)
			(xy 236.533433 -41.582103) (xy 236.455299 -41.622589) (xy 236.373808 -41.655802) (xy 236.289634 -41.681466)
			(xy 236.203475 -41.69937) (xy 236.116045 -41.709365) (xy 236.028068 -41.711369) (xy 235.940274 -41.705363)
			(xy 235.85339 -41.691399) (xy 235.768135 -41.669592) (xy 235.685216 -41.640123) (xy 235.605321 -41.603236)
			(xy 235.529112 -41.559236) (xy 235.457219 -41.508488) (xy 235.390238 -41.451414) (xy 235.328726 -41.388484)
			(xy 235.27319 -41.320222) (xy 235.224092 -41.247193) (xy 235.181839 -41.170001) (xy 235.14678 -41.089287)
			(xy 235.119205 -41.005719) (xy 235.099345 -40.91999) (xy 235.087362 -40.83281) (xy 235.083357 -40.744902)
			(xy 0.509016 -40.744902) (xy 0.509016 -43.999912) (xy 16.983969 -43.999912) (xy 16.987993 -43.914144)
			(xy 17.000031 -43.82913) (xy 17.019978 -43.745616) (xy 17.047657 -43.664337) (xy 17.082825 -43.586008)
			(xy 17.125174 -43.511315) (xy 17.174331 -43.440917) (xy 17.229864 -43.375431) (xy 17.291286 -43.315433)
			(xy 17.358055 -43.26145) (xy 17.429587 -43.213957) (xy 17.505251 -43.173371) (xy 17.584384 -43.140048)
			(xy 17.666289 -43.114282) (xy 17.750247 -43.096299) (xy 17.835521 -43.086257) (xy 17.92136 -43.084244)
			(xy 18.00701 -43.090278) (xy 18.091718 -43.104306) (xy 18.174741 -43.126205) (xy 18.255349 -43.155782)
			(xy 18.332833 -43.192777) (xy 18.406512 -43.236865) (xy 18.475738 -43.287659) (xy 18.539905 -43.344712)
			(xy 18.598446 -43.407523) (xy 18.650849 -43.47554) (xy 18.696652 -43.548165) (xy 18.735453 -43.62476)
			(xy 18.766912 -43.704652) (xy 18.790751 -43.787139) (xy 18.806761 -43.871496) (xy 18.814801 -43.956981)
			(xy 18.815304 -43.999912) (xy 18.814801 -44.042843) (xy 18.806761 -44.128328) (xy 18.790751 -44.212685)
			(xy 18.766912 -44.295172) (xy 18.735453 -44.375064) (xy 18.696652 -44.451659) (xy 18.650849 -44.524284)
			(xy 18.598446 -44.592301) (xy 18.539905 -44.655112) (xy 18.475738 -44.712165) (xy 18.406512 -44.762959)
			(xy 18.332833 -44.807047) (xy 18.255349 -44.844042) (xy 18.174741 -44.873619) (xy 18.091718 -44.895518)
			(xy 18.00701 -44.909546) (xy 17.92136 -44.91558) (xy 17.835521 -44.913567) (xy 17.750247 -44.903525)
			(xy 17.666289 -44.885542) (xy 17.584384 -44.859776) (xy 17.505251 -44.826453) (xy 17.429587 -44.785867)
			(xy 17.358055 -44.738374) (xy 17.291286 -44.684391) (xy 17.229864 -44.624393) (xy 17.174331 -44.558907)
			(xy 17.125174 -44.488509) (xy 17.082825 -44.413816) (xy 17.047657 -44.335487) (xy 17.019978 -44.254208)
			(xy 17.000031 -44.170694) (xy 16.987993 -44.08568) (xy 16.983969 -43.999912) (xy 0.509016 -43.999912)
			(xy 0.509016 -47.049813) (xy 59.781451 -47.049813) (xy 59.785436 -46.895317) (xy 59.79737 -46.74123)
			(xy 59.817219 -46.587962) (xy 59.844933 -46.43592) (xy 59.880436 -46.285505) (xy 59.923635 -46.137118)
			(xy 59.974415 -45.991151) (xy 60.032642 -45.847991) (xy 60.098162 -45.708019) (xy 60.1708 -45.571605)
			(xy 60.250363 -45.439111) (xy 60.336642 -45.310889) (xy 60.429407 -45.187278) (xy 60.528412 -45.068606)
			(xy 60.633395 -44.955188) (xy 60.744077 -44.847324) (xy 60.860165 -44.745302) (xy 60.981351 -44.64939)
			(xy 61.107313 -44.559844) (xy 61.237718 -44.476901) (xy 61.37222 -44.400781) (xy 61.510462 -44.331685)
			(xy 61.652077 -44.269798) (xy 61.796691 -44.215282) (xy 61.943919 -44.168283) (xy 62.093371 -44.128926)
			(xy 62.244652 -44.097314) (xy 62.397358 -44.073531) (xy 62.551087 -44.057641) (xy 62.70543 -44.049685)
			(xy 62.782704 -44.049188) (xy 64.383158 -44.049188) (xy 64.460432 -44.049684) (xy 64.614774 -44.057653)
			(xy 64.768502 -44.073557) (xy 64.921207 -44.097353) (xy 65.072484 -44.128978) (xy 65.221933 -44.168349)
			(xy 65.369158 -44.21536) (xy 65.513767 -44.269888) (xy 65.655377 -44.331788) (xy 65.793613 -44.400896)
			(xy 65.928108 -44.477028) (xy 66.058506 -44.559982) (xy 66.184461 -44.649539) (xy 66.305639 -44.745461)
			(xy 66.421718 -44.847494) (xy 66.532391 -44.955367) (xy 66.637364 -45.068794) (xy 66.736359 -45.187475)
			(xy 66.829113 -45.311094) (xy 66.915381 -45.439324) (xy 66.994934 -45.571824) (xy 67.06756 -45.708245)
			(xy 67.133068 -45.848223) (xy 67.191283 -45.991387) (xy 67.242051 -46.137359) (xy 67.285237 -46.28575)
			(xy 67.320727 -46.436168) (xy 67.348428 -46.588213) (xy 67.368264 -46.741483) (xy 67.380185 -46.89557)
			(xy 67.384154 -47.04994) (xy 89.78165 -47.04994) (xy 89.78563 -46.895439) (xy 89.797557 -46.741349)
			(xy 89.817402 -46.588076) (xy 89.84511 -46.436028) (xy 89.880608 -46.285609) (xy 89.923803 -46.137216)
			(xy 89.97458 -45.991243) (xy 90.032804 -45.848078) (xy 90.098321 -45.708101) (xy 90.170957 -45.571681)
			(xy 90.250519 -45.439181) (xy 90.336796 -45.310953) (xy 90.42956 -45.187337) (xy 90.528565 -45.068659)
			(xy 90.633548 -44.955236) (xy 90.74423 -44.847368) (xy 90.860319 -44.74534) (xy 90.981506 -44.649424)
			(xy 91.10747 -44.559873) (xy 91.237877 -44.476926) (xy 91.372381 -44.400801) (xy 91.510626 -44.331702)
			(xy 91.652244 -44.269811) (xy 91.796861 -44.215293) (xy 91.944092 -44.168291) (xy 92.093548 -44.128931)
			(xy 92.244832 -44.097317) (xy 92.397543 -44.073533) (xy 92.551275 -44.057642) (xy 92.705622 -44.049686)
			(xy 92.782898 -44.049188) (xy 94.383098 -44.049188) (xy 94.460374 -44.049669) (xy 94.614722 -44.057625)
			(xy 94.768456 -44.073516) (xy 94.921168 -44.0973) (xy 95.072452 -44.128914) (xy 95.221909 -44.168274)
			(xy 95.369142 -44.215276) (xy 95.513759 -44.269795) (xy 95.655379 -44.331686) (xy 95.793624 -44.400785)
			(xy 95.928129 -44.47691) (xy 96.058537 -44.559858) (xy 96.184502 -44.649409) (xy 96.30569 -44.745326)
			(xy 96.421779 -44.847354) (xy 96.532463 -44.955223) (xy 96.637446 -45.068647) (xy 96.736452 -45.187325)
			(xy 96.829216 -45.310943) (xy 96.915495 -45.439171) (xy 96.995057 -45.571672) (xy 97.038059 -45.652436)
			(xy 155.97378 -45.652436) (xy 155.97378 -44.788836) (xy 155.974266 -44.761567) (xy 155.982028 -44.707583)
			(xy 155.997393 -44.655253) (xy 156.02005 -44.605643) (xy 156.049536 -44.559762) (xy 156.085251 -44.518545)
			(xy 156.126468 -44.48283) (xy 156.172349 -44.453344) (xy 156.221959 -44.430687) (xy 156.274289 -44.415322)
			(xy 156.328273 -44.40756) (xy 156.382811 -44.40756) (xy 156.436795 -44.415322) (xy 156.489125 -44.430687)
			(xy 156.538735 -44.453344) (xy 156.584616 -44.48283) (xy 156.625833 -44.518545) (xy 156.661548 -44.559762)
			(xy 156.691034 -44.605643) (xy 156.713691 -44.655253) (xy 156.72159 -44.682156) (xy 159.179768 -44.682156)
			(xy 159.179768 -43.818556) (xy 159.180254 -43.791287) (xy 159.188016 -43.737303) (xy 159.203381 -43.684973)
			(xy 159.226038 -43.635363) (xy 159.255524 -43.589482) (xy 159.291239 -43.548265) (xy 159.332456 -43.51255)
			(xy 159.378337 -43.483064) (xy 159.427947 -43.460407) (xy 159.480277 -43.445042) (xy 159.534261 -43.43728)
			(xy 159.588799 -43.43728) (xy 159.642783 -43.445042) (xy 159.695113 -43.460407) (xy 159.74185 -43.481752)
			(xy 178.891692 -43.481752) (xy 178.891692 -42.618152) (xy 178.892178 -42.590901) (xy 178.899934 -42.536953)
			(xy 178.915289 -42.484658) (xy 178.937931 -42.435081) (xy 178.967397 -42.389231) (xy 179.003088 -42.34804)
			(xy 179.044279 -42.312349) (xy 179.090129 -42.282883) (xy 179.139706 -42.260241) (xy 179.192001 -42.244886)
			(xy 179.245949 -42.23713) (xy 179.300451 -42.23713) (xy 179.354399 -42.244886) (xy 179.406694 -42.260241)
			(xy 179.456271 -42.282883) (xy 179.502121 -42.312349) (xy 179.543312 -42.34804) (xy 179.579003 -42.389231)
			(xy 179.608469 -42.435081) (xy 179.631111 -42.484658) (xy 179.646466 -42.536953) (xy 179.654222 -42.590901)
			(xy 179.654708 -42.618152) (xy 179.654708 -43.481752) (xy 179.654222 -43.509003) (xy 179.647839 -43.5534)
			(xy 353.767583 -43.5534) (xy 353.771544 -43.500544) (xy 353.783339 -43.44887) (xy 353.802705 -43.39953)
			(xy 353.829208 -43.353628) (xy 353.862256 -43.312189) (xy 353.901112 -43.276139) (xy 353.944908 -43.246283)
			(xy 353.992664 -43.223289) (xy 354.043314 -43.207669) (xy 354.095726 -43.199773) (xy 354.122228 -43.199304)
			(xy 354.122736 -43.199304) (xy 354.153713 -43.199978) (xy 354.214715 -43.210807) (xy 354.272905 -43.232077)
			(xy 354.300028 -43.247056) (xy 354.328004 -43.238767) (xy 354.385663 -43.229845) (xy 354.414836 -43.229276)
			(xy 354.99548 -43.229276) (xy 355.004624 -43.225466) (xy 355.025917 -43.217194) (xy 355.070087 -43.205543)
			(xy 355.115388 -43.199665) (xy 355.138228 -43.199304) (xy 355.162681 -43.199729) (xy 355.211118 -43.206478)
			(xy 355.25817 -43.219815) (xy 355.280722 -43.229276) (xy 355.307866 -43.229907) (xy 355.361565 -43.237931)
			(xy 355.413585 -43.253486) (xy 355.462874 -43.276259) (xy 355.508436 -43.305789) (xy 355.549352 -43.341481)
			(xy 355.584795 -43.382612) (xy 355.61405 -43.428352) (xy 355.636524 -43.477777) (xy 355.651765 -43.52989)
			(xy 355.659465 -43.583636) (xy 355.659944 -43.610784) (xy 355.659468 -43.634951) (xy 356.178591 -43.634951)
			(xy 356.178591 -43.580449) (xy 356.186348 -43.526502) (xy 356.201703 -43.474208) (xy 356.224344 -43.424632)
			(xy 356.253811 -43.378783) (xy 356.289502 -43.337594) (xy 356.330692 -43.301903) (xy 356.376543 -43.272438)
			(xy 356.42612 -43.249799) (xy 356.478414 -43.234445) (xy 356.532361 -43.22669) (xy 356.559612 -43.226228)
			(xy 357.423212 -43.226228) (xy 357.450465 -43.226643) (xy 357.504417 -43.234401) (xy 357.556715 -43.249759)
			(xy 357.606295 -43.272403) (xy 357.652149 -43.301872) (xy 357.693341 -43.337567) (xy 357.729035 -43.378761)
			(xy 357.758503 -43.424615) (xy 357.781145 -43.474196) (xy 357.796501 -43.526495) (xy 357.804258 -43.580447)
			(xy 357.804258 -43.634953) (xy 357.803812 -43.638056) (xy 358.339039 -43.638056) (xy 358.339039 -43.583544)
			(xy 358.346797 -43.529588) (xy 358.362156 -43.477285) (xy 358.384802 -43.4277) (xy 358.414274 -43.381843)
			(xy 358.449974 -43.340648) (xy 358.491172 -43.304953) (xy 358.537032 -43.275485) (xy 358.586619 -43.252843)
			(xy 358.638923 -43.23749) (xy 358.69288 -43.229736) (xy 358.720136 -43.229276) (xy 359.583736 -43.229276)
			(xy 359.610984 -43.229797) (xy 359.664926 -43.237557) (xy 359.717214 -43.252915) (xy 359.766785 -43.275557)
			(xy 359.812629 -43.305023) (xy 359.853813 -43.340713) (xy 359.889499 -43.3819) (xy 359.91896 -43.427747)
			(xy 359.941598 -43.47732) (xy 359.956951 -43.529609) (xy 359.964706 -43.583552) (xy 359.964706 -43.638048)
			(xy 359.956951 -43.691991) (xy 359.941598 -43.74428) (xy 359.91896 -43.793853) (xy 359.889499 -43.8397)
			(xy 359.853813 -43.880887) (xy 359.812629 -43.916577) (xy 359.766785 -43.946043) (xy 359.717214 -43.968685)
			(xy 359.664926 -43.984043) (xy 359.610984 -43.991803) (xy 359.583736 -43.992292) (xy 358.720136 -43.992292)
			(xy 358.69288 -43.991864) (xy 358.638923 -43.98411) (xy 358.586619 -43.968757) (xy 358.537032 -43.946115)
			(xy 358.491172 -43.916647) (xy 358.449974 -43.880952) (xy 358.414274 -43.839757) (xy 358.384802 -43.7939)
			(xy 358.362156 -43.744315) (xy 358.346797 -43.692012) (xy 358.339039 -43.638056) (xy 357.803812 -43.638056)
			(xy 357.796501 -43.688905) (xy 357.781145 -43.741204) (xy 357.758503 -43.790785) (xy 357.729035 -43.836639)
			(xy 357.693341 -43.877833) (xy 357.652149 -43.913528) (xy 357.606295 -43.942997) (xy 357.556715 -43.965641)
			(xy 357.504417 -43.980999) (xy 357.450465 -43.988757) (xy 357.423212 -43.989244) (xy 356.559612 -43.989244)
			(xy 356.532361 -43.98871) (xy 356.478414 -43.980955) (xy 356.42612 -43.965601) (xy 356.376543 -43.942962)
			(xy 356.330692 -43.913497) (xy 356.289502 -43.877806) (xy 356.253811 -43.836617) (xy 356.224344 -43.790768)
			(xy 356.201703 -43.741192) (xy 356.186348 -43.688898) (xy 356.178591 -43.634951) (xy 355.659468 -43.634951)
			(xy 355.659407 -43.638033) (xy 355.651654 -43.691977) (xy 355.636302 -43.744269) (xy 355.613666 -43.793843)
			(xy 355.584204 -43.839692) (xy 355.548518 -43.880882) (xy 355.507334 -43.916573) (xy 355.461489 -43.946041)
			(xy 355.411917 -43.968684) (xy 355.359628 -43.984043) (xy 355.305685 -43.991803) (xy 355.278436 -43.992292)
			(xy 354.414836 -43.992292) (xy 354.388369 -43.991825) (xy 354.335944 -43.984518) (xy 354.285033 -43.970025)
			(xy 354.236619 -43.948625) (xy 354.191633 -43.920731) (xy 354.170996 -43.904154) (xy 354.158864 -43.905712)
			(xy 354.134459 -43.907367) (xy 354.122228 -43.907456) (xy 354.095726 -43.907027) (xy 354.043314 -43.899131)
			(xy 353.992664 -43.883511) (xy 353.944908 -43.860517) (xy 353.901112 -43.830661) (xy 353.862256 -43.794611)
			(xy 353.829208 -43.753172) (xy 353.802705 -43.70727) (xy 353.783339 -43.65793) (xy 353.771544 -43.606256)
			(xy 353.767583 -43.5534) (xy 179.647839 -43.5534) (xy 179.646466 -43.562951) (xy 179.631111 -43.615246)
			(xy 179.608469 -43.664823) (xy 179.579003 -43.710673) (xy 179.543312 -43.751864) (xy 179.502121 -43.787555)
			(xy 179.456271 -43.817021) (xy 179.406694 -43.839663) (xy 179.354399 -43.855018) (xy 179.300451 -43.862774)
			(xy 179.245949 -43.862774) (xy 179.192001 -43.855018) (xy 179.139706 -43.839663) (xy 179.090129 -43.817021)
			(xy 179.044279 -43.787555) (xy 179.003088 -43.751864) (xy 178.967397 -43.710673) (xy 178.937931 -43.664823)
			(xy 178.915289 -43.615246) (xy 178.899934 -43.562951) (xy 178.892178 -43.509003) (xy 178.891692 -43.481752)
			(xy 159.74185 -43.481752) (xy 159.744723 -43.483064) (xy 159.790604 -43.51255) (xy 159.831821 -43.548265)
			(xy 159.867536 -43.589482) (xy 159.897022 -43.635363) (xy 159.919679 -43.684973) (xy 159.935044 -43.737303)
			(xy 159.942806 -43.791287) (xy 159.943292 -43.818556) (xy 159.943292 -44.682156) (xy 159.942806 -44.709425)
			(xy 159.935044 -44.763409) (xy 159.919679 -44.815739) (xy 159.897022 -44.865349) (xy 159.867536 -44.91123)
			(xy 159.831821 -44.952447) (xy 159.79991 -44.980098) (xy 181.659784 -44.980098) (xy 181.659784 -44.116498)
			(xy 181.66027 -44.089247) (xy 181.668026 -44.035299) (xy 181.683381 -43.983004) (xy 181.706023 -43.933427)
			(xy 181.735489 -43.887577) (xy 181.77118 -43.846386) (xy 181.812371 -43.810695) (xy 181.858221 -43.781229)
			(xy 181.907798 -43.758587) (xy 181.960093 -43.743232) (xy 182.014041 -43.735476) (xy 182.068543 -43.735476)
			(xy 182.122491 -43.743232) (xy 182.174786 -43.758587) (xy 182.224363 -43.781229) (xy 182.270213 -43.810695)
			(xy 182.311404 -43.846386) (xy 182.347095 -43.887577) (xy 182.376561 -43.933427) (xy 182.399203 -43.983004)
			(xy 182.414558 -44.035299) (xy 182.422314 -44.089247) (xy 182.4228 -44.116498) (xy 182.4228 -44.840452)
			(xy 348.511075 -44.840452) (xy 348.511075 -44.785948) (xy 348.518832 -44.731999) (xy 348.534188 -44.679702)
			(xy 348.556831 -44.630124) (xy 348.586298 -44.584273) (xy 348.621992 -44.543082) (xy 348.663184 -44.50739)
			(xy 348.709036 -44.477924) (xy 348.758616 -44.455283) (xy 348.810912 -44.439929) (xy 348.864862 -44.432174)
			(xy 348.892114 -44.431712) (xy 349.755714 -44.431712) (xy 349.782966 -44.432159) (xy 349.836915 -44.439917)
			(xy 349.889211 -44.455274) (xy 349.938789 -44.477918) (xy 349.98464 -44.507386) (xy 350.025831 -44.543079)
			(xy 350.061523 -44.584271) (xy 350.090989 -44.630123) (xy 350.11363 -44.679702) (xy 350.128986 -44.731999)
			(xy 350.136742 -44.785948) (xy 350.136742 -44.840452) (xy 350.128986 -44.894401) (xy 350.11363 -44.946698)
			(xy 350.090989 -44.996277) (xy 350.072098 -45.025673) (xy 355.559288 -45.025673) (xy 355.559288 -44.971127)
			(xy 355.56705 -44.917137) (xy 355.582418 -44.864802) (xy 355.605077 -44.815186) (xy 355.634567 -44.7693)
			(xy 355.670288 -44.728078) (xy 355.711511 -44.692359) (xy 355.757398 -44.662871) (xy 355.807015 -44.640213)
			(xy 355.859351 -44.624847) (xy 355.913341 -44.617087) (xy 355.940614 -44.616624) (xy 356.804214 -44.616624)
			(xy 356.831482 -44.617139) (xy 356.885462 -44.624902) (xy 356.937788 -44.640268) (xy 356.987394 -44.662925)
			(xy 357.033272 -44.69241) (xy 357.074486 -44.728124) (xy 357.110199 -44.769339) (xy 357.139682 -44.815218)
			(xy 357.162337 -44.864825) (xy 357.177701 -44.917152) (xy 357.185462 -44.971132) (xy 357.185462 -45.025668)
			(xy 357.177701 -45.079648) (xy 357.162337 -45.131975) (xy 357.139682 -45.181582) (xy 357.110199 -45.227461)
			(xy 357.074486 -45.268676) (xy 357.033272 -45.30439) (xy 356.987394 -45.333875) (xy 356.937788 -45.356532)
			(xy 356.885462 -45.371898) (xy 356.831482 -45.379661) (xy 356.804214 -45.380148) (xy 355.940614 -45.380148)
			(xy 355.913341 -45.379713) (xy 355.859351 -45.371953) (xy 355.807015 -45.356587) (xy 355.757398 -45.333929)
			(xy 355.711511 -45.304441) (xy 355.670288 -45.268722) (xy 355.634567 -45.2275) (xy 355.605077 -45.181614)
			(xy 355.582418 -45.131998) (xy 355.56705 -45.079663) (xy 355.559288 -45.025673) (xy 350.072098 -45.025673)
			(xy 350.061523 -45.042129) (xy 350.025831 -45.083321) (xy 349.98464 -45.119014) (xy 349.938789 -45.148482)
			(xy 349.889211 -45.171126) (xy 349.836915 -45.186483) (xy 349.782966 -45.194241) (xy 349.755714 -45.194728)
			(xy 348.892114 -45.194728) (xy 348.864862 -45.194226) (xy 348.810912 -45.186471) (xy 348.758616 -45.171117)
			(xy 348.709036 -45.148476) (xy 348.663184 -45.11901) (xy 348.621992 -45.083318) (xy 348.586298 -45.042127)
			(xy 348.556831 -44.996276) (xy 348.534188 -44.946698) (xy 348.518832 -44.894401) (xy 348.511075 -44.840452)
			(xy 182.4228 -44.840452) (xy 182.4228 -44.980098) (xy 182.422314 -45.007349) (xy 182.414558 -45.061297)
			(xy 182.399203 -45.113592) (xy 182.376561 -45.163169) (xy 182.347095 -45.209019) (xy 182.311404 -45.25021)
			(xy 182.270213 -45.285901) (xy 182.224363 -45.315367) (xy 182.174786 -45.338009) (xy 182.122491 -45.353364)
			(xy 182.068543 -45.36112) (xy 182.014041 -45.36112) (xy 181.960093 -45.353364) (xy 181.907798 -45.338009)
			(xy 181.858221 -45.315367) (xy 181.812371 -45.285901) (xy 181.77118 -45.25021) (xy 181.735489 -45.209019)
			(xy 181.706023 -45.163169) (xy 181.683381 -45.113592) (xy 181.668026 -45.061297) (xy 181.66027 -45.007349)
			(xy 181.659784 -44.980098) (xy 159.79991 -44.980098) (xy 159.790604 -44.988162) (xy 159.744723 -45.017648)
			(xy 159.695113 -45.040305) (xy 159.642783 -45.05567) (xy 159.588799 -45.063432) (xy 159.534261 -45.063432)
			(xy 159.480277 -45.05567) (xy 159.427947 -45.040305) (xy 159.378337 -45.017648) (xy 159.332456 -44.988162)
			(xy 159.291239 -44.952447) (xy 159.255524 -44.91123) (xy 159.226038 -44.865349) (xy 159.203381 -44.815739)
			(xy 159.188016 -44.763409) (xy 159.180254 -44.709425) (xy 159.179768 -44.682156) (xy 156.72159 -44.682156)
			(xy 156.729056 -44.707583) (xy 156.736818 -44.761567) (xy 156.737304 -44.788836) (xy 156.737304 -45.652436)
			(xy 156.736818 -45.679705) (xy 156.729056 -45.733689) (xy 156.713691 -45.786019) (xy 156.691034 -45.835629)
			(xy 156.661548 -45.88151) (xy 156.625833 -45.922727) (xy 156.584616 -45.958442) (xy 156.538735 -45.987928)
			(xy 156.489125 -46.010585) (xy 156.436795 -46.02595) (xy 156.382811 -46.033712) (xy 156.328273 -46.033712)
			(xy 156.274289 -46.02595) (xy 156.221959 -46.010585) (xy 156.172349 -45.987928) (xy 156.126468 -45.958442)
			(xy 156.085251 -45.922727) (xy 156.049536 -45.88151) (xy 156.02005 -45.835629) (xy 155.997393 -45.786019)
			(xy 155.982028 -45.733689) (xy 155.974266 -45.679705) (xy 155.97378 -45.652436) (xy 97.038059 -45.652436)
			(xy 97.067693 -45.708092) (xy 97.133211 -45.848071) (xy 97.191435 -45.991237) (xy 97.242212 -46.13721)
			(xy 97.285407 -46.285604) (xy 97.320906 -46.436025) (xy 97.329238 -46.481746) (xy 178.630072 -46.481746)
			(xy 178.630072 -45.618146) (xy 178.630558 -45.590895) (xy 178.638314 -45.536947) (xy 178.653669 -45.484652)
			(xy 178.676311 -45.435075) (xy 178.705777 -45.389225) (xy 178.741468 -45.348034) (xy 178.782659 -45.312343)
			(xy 178.828509 -45.282877) (xy 178.878086 -45.260235) (xy 178.930381 -45.24488) (xy 178.984329 -45.237124)
			(xy 179.038831 -45.237124) (xy 179.092779 -45.24488) (xy 179.145074 -45.260235) (xy 179.194651 -45.282877)
			(xy 179.240501 -45.312343) (xy 179.281692 -45.348034) (xy 179.317383 -45.389225) (xy 179.346849 -45.435075)
			(xy 179.369491 -45.484652) (xy 179.384846 -45.536947) (xy 179.392602 -45.590895) (xy 179.393088 -45.618146)
			(xy 179.393088 -46.481746) (xy 179.392602 -46.508997) (xy 179.384846 -46.562945) (xy 179.369491 -46.61524)
			(xy 179.346849 -46.664817) (xy 179.317383 -46.710667) (xy 179.281692 -46.751858) (xy 179.240501 -46.787549)
			(xy 179.194651 -46.817015) (xy 179.145074 -46.839657) (xy 179.092779 -46.855012) (xy 179.038831 -46.862768)
			(xy 178.984329 -46.862768) (xy 178.930381 -46.855012) (xy 178.878086 -46.839657) (xy 178.828509 -46.817015)
			(xy 178.782659 -46.787549) (xy 178.741468 -46.751858) (xy 178.705777 -46.710667) (xy 178.676311 -46.664817)
			(xy 178.653669 -46.61524) (xy 178.638314 -46.562945) (xy 178.630558 -46.508997) (xy 178.630072 -46.481746)
			(xy 97.329238 -46.481746) (xy 97.348615 -46.588073) (xy 97.368459 -46.741347) (xy 97.380387 -46.895438)
			(xy 97.384366 -47.04994) (xy 97.380387 -47.204442) (xy 97.368459 -47.358533) (xy 97.348615 -47.511807)
			(xy 97.320906 -47.663855) (xy 97.285407 -47.814276) (xy 97.242212 -47.96267) (xy 97.239575 -47.97025)
			(xy 155.567386 -47.97025) (xy 155.567386 -47.91575) (xy 155.575142 -47.861805) (xy 155.590495 -47.809513)
			(xy 155.613135 -47.759938) (xy 155.642598 -47.71409) (xy 155.678287 -47.672901) (xy 155.719474 -47.63721)
			(xy 155.765321 -47.607744) (xy 155.814895 -47.585102) (xy 155.867186 -47.569746) (xy 155.92113 -47.561987)
			(xy 155.94838 -47.5615) (xy 156.81198 -47.5615) (xy 156.839234 -47.561946) (xy 156.893189 -47.569701)
			(xy 156.94549 -47.585055) (xy 156.995074 -47.607697) (xy 157.04093 -47.637165) (xy 157.082126 -47.67286)
			(xy 157.117823 -47.714054) (xy 157.147293 -47.759909) (xy 157.169938 -47.809491) (xy 157.185295 -47.861792)
			(xy 157.193053 -47.915746) (xy 157.193053 -47.970249) (xy 158.785586 -47.970249) (xy 158.785586 -47.915751)
			(xy 158.793341 -47.861808) (xy 158.808694 -47.809518) (xy 158.831331 -47.759944) (xy 158.860793 -47.714097)
			(xy 158.89648 -47.672908) (xy 158.937664 -47.637217) (xy 158.983509 -47.607751) (xy 159.03308 -47.585108)
			(xy 159.085369 -47.569749) (xy 159.139311 -47.561988) (xy 159.16656 -47.5615) (xy 160.03016 -47.5615)
			(xy 160.057415 -47.561945) (xy 160.111372 -47.569697) (xy 160.163675 -47.58505) (xy 160.213262 -47.607691)
			(xy 160.259121 -47.637158) (xy 160.300319 -47.672853) (xy 160.336018 -47.714047) (xy 160.36549 -47.759903)
			(xy 160.388136 -47.809487) (xy 160.403494 -47.861789) (xy 160.411253 -47.915745) (xy 160.411253 -47.970255)
			(xy 160.403494 -48.024211) (xy 160.402353 -48.028098) (xy 181.659784 -48.028098) (xy 181.659784 -47.164498)
			(xy 181.66027 -47.137247) (xy 181.668026 -47.083299) (xy 181.683381 -47.031004) (xy 181.706023 -46.981427)
			(xy 181.735489 -46.935577) (xy 181.77118 -46.894386) (xy 181.812371 -46.858695) (xy 181.858221 -46.829229)
			(xy 181.907798 -46.806587) (xy 181.960093 -46.791232) (xy 182.014041 -46.783476) (xy 182.068543 -46.783476)
			(xy 182.122491 -46.791232) (xy 182.174786 -46.806587) (xy 182.224363 -46.829229) (xy 182.225669 -46.830068)
			(xy 356.445326 -46.830068) (xy 356.445326 -46.775532) (xy 356.453087 -46.721552) (xy 356.468451 -46.669225)
			(xy 356.491104 -46.619618) (xy 356.520587 -46.573739) (xy 356.556298 -46.532522) (xy 356.597512 -46.496807)
			(xy 356.643388 -46.467321) (xy 356.692994 -46.444663) (xy 356.745319 -46.429294) (xy 356.799298 -46.421529)
			(xy 356.826566 -46.42104) (xy 357.690166 -46.42104) (xy 357.717439 -46.421497) (xy 357.77143 -46.429255)
			(xy 357.823767 -46.444619) (xy 357.873384 -46.467275) (xy 357.919272 -46.496761) (xy 357.960497 -46.532479)
			(xy 357.996218 -46.5737) (xy 358.025709 -46.619586) (xy 358.048369 -46.669202) (xy 358.063737 -46.721537)
			(xy 358.0715 -46.775527) (xy 358.0715 -46.830069) (xy 358.762026 -46.830069) (xy 358.762026 -46.775531)
			(xy 358.769788 -46.721547) (xy 358.785153 -46.669218) (xy 358.807809 -46.619608) (xy 358.837295 -46.573728)
			(xy 358.87301 -46.53251) (xy 358.914228 -46.496795) (xy 358.960108 -46.467309) (xy 359.009718 -46.444653)
			(xy 359.062047 -46.429288) (xy 359.116031 -46.421526) (xy 359.1433 -46.42104) (xy 360.0069 -46.42104)
			(xy 360.03417 -46.421522) (xy 360.088153 -46.429284) (xy 360.140483 -46.44465) (xy 360.190094 -46.467306)
			(xy 360.235975 -46.496792) (xy 360.277193 -46.532507) (xy 360.312908 -46.573725) (xy 360.342394 -46.619606)
			(xy 360.36505 -46.669217) (xy 360.380416 -46.721547) (xy 360.388178 -46.77553) (xy 360.388178 -46.83007)
			(xy 360.388178 -46.830073) (xy 361.088604 -46.830073) (xy 361.088604 -46.775527) (xy 361.096367 -46.721537)
			(xy 361.111735 -46.669202) (xy 361.134395 -46.619586) (xy 361.163887 -46.573701) (xy 361.199608 -46.53248)
			(xy 361.240833 -46.496763) (xy 361.286721 -46.467276) (xy 361.336339 -46.444621) (xy 361.388676 -46.429258)
			(xy 361.442667 -46.421501) (xy 361.46994 -46.42104) (xy 362.33354 -46.42104) (xy 362.360808 -46.421525)
			(xy 362.414787 -46.429291) (xy 362.467112 -46.44466) (xy 362.516718 -46.467319) (xy 362.562594 -46.496806)
			(xy 362.603807 -46.532522) (xy 362.639518 -46.573738) (xy 362.669 -46.619618) (xy 362.691654 -46.669225)
			(xy 362.707017 -46.721552) (xy 362.714778 -46.775532) (xy 362.714778 -46.830068) (xy 362.707017 -46.884048)
			(xy 362.691654 -46.936375) (xy 362.672751 -46.977768) (xy 396.642323 -46.977768) (xy 396.642323 -46.891996)
			(xy 396.650237 -46.806588) (xy 396.665998 -46.722276) (xy 396.689471 -46.639777) (xy 396.720456 -46.559796)
			(xy 396.758688 -46.483015) (xy 396.803842 -46.41009) (xy 396.855532 -46.341642) (xy 396.913317 -46.278255)
			(xy 396.976704 -46.22047) (xy 397.045152 -46.16878) (xy 397.118077 -46.123626) (xy 397.194858 -46.085394)
			(xy 397.274839 -46.054409) (xy 397.357338 -46.030936) (xy 397.44165 -46.015175) (xy 397.527058 -46.007261)
			(xy 397.61283 -46.007261) (xy 397.698238 -46.015175) (xy 397.78255 -46.030936) (xy 397.865049 -46.054409)
			(xy 397.94503 -46.085394) (xy 398.021811 -46.123626) (xy 398.094736 -46.16878) (xy 398.163184 -46.22047)
			(xy 398.226571 -46.278255) (xy 398.284356 -46.341642) (xy 398.336046 -46.41009) (xy 398.3812 -46.483015)
			(xy 398.419432 -46.559796) (xy 398.450417 -46.639777) (xy 398.47389 -46.722276) (xy 398.489651 -46.806588)
			(xy 398.497565 -46.891996) (xy 398.49806 -46.934882) (xy 398.497565 -46.977768) (xy 398.489651 -47.063176)
			(xy 398.47389 -47.147488) (xy 398.450417 -47.229987) (xy 398.419432 -47.309968) (xy 398.3812 -47.386749)
			(xy 398.336046 -47.459674) (xy 398.284356 -47.528122) (xy 398.226571 -47.591509) (xy 398.163184 -47.649294)
			(xy 398.094736 -47.700984) (xy 398.021811 -47.746138) (xy 397.94503 -47.78437) (xy 397.865049 -47.815355)
			(xy 397.78255 -47.838828) (xy 397.698238 -47.854589) (xy 397.61283 -47.862503) (xy 397.527058 -47.862503)
			(xy 397.44165 -47.854589) (xy 397.357338 -47.838828) (xy 397.274839 -47.815355) (xy 397.194858 -47.78437)
			(xy 397.118077 -47.746138) (xy 397.045152 -47.700984) (xy 396.976704 -47.649294) (xy 396.913317 -47.591509)
			(xy 396.855532 -47.528122) (xy 396.803842 -47.459674) (xy 396.758688 -47.386749) (xy 396.720456 -47.309968)
			(xy 396.689471 -47.229987) (xy 396.665998 -47.147488) (xy 396.650237 -47.063176) (xy 396.642323 -46.977768)
			(xy 362.672751 -46.977768) (xy 362.669 -46.985982) (xy 362.639518 -47.031862) (xy 362.603807 -47.073078)
			(xy 362.562594 -47.108794) (xy 362.516718 -47.138281) (xy 362.467112 -47.16094) (xy 362.414787 -47.176309)
			(xy 362.360808 -47.184075) (xy 362.33354 -47.184564) (xy 361.46994 -47.184564) (xy 361.442667 -47.184099)
			(xy 361.388676 -47.176342) (xy 361.336339 -47.160979) (xy 361.286721 -47.138324) (xy 361.240833 -47.108837)
			(xy 361.199608 -47.07312) (xy 361.163887 -47.031899) (xy 361.134395 -46.986014) (xy 361.111735 -46.936398)
			(xy 361.096367 -46.884063) (xy 361.088604 -46.830073) (xy 360.388178 -46.830073) (xy 360.380416 -46.884053)
			(xy 360.36505 -46.936383) (xy 360.342394 -46.985994) (xy 360.312908 -47.031875) (xy 360.277193 -47.073093)
			(xy 360.235975 -47.108808) (xy 360.190094 -47.138294) (xy 360.140483 -47.16095) (xy 360.088153 -47.176316)
			(xy 360.03417 -47.184078) (xy 360.0069 -47.184564) (xy 359.1433 -47.184564) (xy 359.116031 -47.184074)
			(xy 359.062047 -47.176312) (xy 359.009718 -47.160947) (xy 358.960108 -47.138291) (xy 358.914228 -47.108805)
			(xy 358.87301 -47.07309) (xy 358.837295 -47.031872) (xy 358.807809 -46.985992) (xy 358.785153 -46.936382)
			(xy 358.769788 -46.884053) (xy 358.762026 -46.830069) (xy 358.0715 -46.830069) (xy 358.0715 -46.830073)
			(xy 358.063737 -46.884063) (xy 358.048369 -46.936398) (xy 358.025709 -46.986014) (xy 357.996218 -47.0319)
			(xy 357.960497 -47.073121) (xy 357.919272 -47.108839) (xy 357.873384 -47.138325) (xy 357.823767 -47.160981)
			(xy 357.77143 -47.176345) (xy 357.717439 -47.184103) (xy 357.690166 -47.184564) (xy 356.826566 -47.184564)
			(xy 356.799298 -47.184071) (xy 356.745319 -47.176306) (xy 356.692994 -47.160937) (xy 356.643388 -47.138279)
			(xy 356.597512 -47.108793) (xy 356.556298 -47.073078) (xy 356.520587 -47.031861) (xy 356.491104 -46.985982)
			(xy 356.468451 -46.936375) (xy 356.453087 -46.884048) (xy 356.445326 -46.830068) (xy 182.225669 -46.830068)
			(xy 182.270213 -46.858695) (xy 182.311404 -46.894386) (xy 182.347095 -46.935577) (xy 182.376561 -46.981427)
			(xy 182.399203 -47.031004) (xy 182.414558 -47.083299) (xy 182.422314 -47.137247) (xy 182.4228 -47.164498)
			(xy 182.4228 -48.028098) (xy 182.422314 -48.055349) (xy 182.414558 -48.109297) (xy 182.399203 -48.161592)
			(xy 182.376561 -48.211169) (xy 182.347095 -48.257019) (xy 182.311404 -48.29821) (xy 182.270213 -48.333901)
			(xy 182.224363 -48.363367) (xy 182.174786 -48.386009) (xy 182.122491 -48.401364) (xy 182.068543 -48.40912)
			(xy 182.014041 -48.40912) (xy 181.960093 -48.401364) (xy 181.907798 -48.386009) (xy 181.858221 -48.363367)
			(xy 181.812371 -48.333901) (xy 181.77118 -48.29821) (xy 181.735489 -48.257019) (xy 181.706023 -48.211169)
			(xy 181.683381 -48.161592) (xy 181.668026 -48.109297) (xy 181.66027 -48.055349) (xy 181.659784 -48.028098)
			(xy 160.402353 -48.028098) (xy 160.388136 -48.076513) (xy 160.36549 -48.126097) (xy 160.336018 -48.171953)
			(xy 160.300319 -48.213147) (xy 160.259121 -48.248842) (xy 160.213262 -48.278309) (xy 160.163675 -48.30095)
			(xy 160.111372 -48.316303) (xy 160.057415 -48.324055) (xy 160.03016 -48.324516) (xy 159.16656 -48.324516)
			(xy 159.139311 -48.324012) (xy 159.085369 -48.316251) (xy 159.03308 -48.300892) (xy 158.983509 -48.278249)
			(xy 158.937664 -48.248783) (xy 158.89648 -48.213092) (xy 158.860793 -48.171903) (xy 158.831331 -48.126056)
			(xy 158.808694 -48.076482) (xy 158.793341 -48.024192) (xy 158.785586 -47.970249) (xy 157.193053 -47.970249)
			(xy 157.193053 -47.970254) (xy 157.185295 -48.024208) (xy 157.169938 -48.076509) (xy 157.147293 -48.126091)
			(xy 157.117823 -48.171946) (xy 157.082126 -48.21314) (xy 157.04093 -48.248835) (xy 156.995074 -48.278303)
			(xy 156.94549 -48.300945) (xy 156.893189 -48.316299) (xy 156.839234 -48.324054) (xy 156.81198 -48.324516)
			(xy 155.94838 -48.324516) (xy 155.92113 -48.324013) (xy 155.867186 -48.316254) (xy 155.814895 -48.300898)
			(xy 155.765321 -48.278256) (xy 155.719474 -48.24879) (xy 155.678287 -48.213099) (xy 155.642598 -48.17191)
			(xy 155.613135 -48.126062) (xy 155.590495 -48.076487) (xy 155.575142 -48.024195) (xy 155.567386 -47.97025)
			(xy 97.239575 -47.97025) (xy 97.191435 -48.108643) (xy 97.133211 -48.251809) (xy 97.067693 -48.391788)
			(xy 96.995057 -48.528208) (xy 96.915495 -48.660709) (xy 96.829216 -48.788937) (xy 96.736452 -48.912555)
			(xy 96.637446 -49.031233) (xy 96.532463 -49.144657) (xy 96.421779 -49.252526) (xy 96.30569 -49.354554)
			(xy 96.184502 -49.450471) (xy 96.140518 -49.48174) (xy 178.630072 -49.48174) (xy 178.630072 -48.61814)
			(xy 178.630558 -48.590889) (xy 178.638314 -48.536941) (xy 178.653669 -48.484646) (xy 178.676311 -48.435069)
			(xy 178.705777 -48.389219) (xy 178.741468 -48.348028) (xy 178.782659 -48.312337) (xy 178.828509 -48.282871)
			(xy 178.878086 -48.260229) (xy 178.930381 -48.244874) (xy 178.984329 -48.237118) (xy 179.038831 -48.237118)
			(xy 179.092779 -48.244874) (xy 179.145074 -48.260229) (xy 179.194651 -48.282871) (xy 179.240501 -48.312337)
			(xy 179.281692 -48.348028) (xy 179.317383 -48.389219) (xy 179.346849 -48.435069) (xy 179.369491 -48.484646)
			(xy 179.384846 -48.536941) (xy 179.392602 -48.590889) (xy 179.393088 -48.61814) (xy 179.393088 -49.48174)
			(xy 179.392602 -49.508991) (xy 179.384846 -49.562939) (xy 179.369491 -49.615234) (xy 179.346849 -49.664811)
			(xy 179.317383 -49.710661) (xy 179.281692 -49.751852) (xy 179.240501 -49.787543) (xy 179.194651 -49.817009)
			(xy 179.145074 -49.839651) (xy 179.092779 -49.855006) (xy 179.038831 -49.862762) (xy 178.984329 -49.862762)
			(xy 178.930381 -49.855006) (xy 178.878086 -49.839651) (xy 178.828509 -49.817009) (xy 178.782659 -49.787543)
			(xy 178.741468 -49.751852) (xy 178.705777 -49.710661) (xy 178.676311 -49.664811) (xy 178.653669 -49.615234)
			(xy 178.638314 -49.562939) (xy 178.630558 -49.508991) (xy 178.630072 -49.48174) (xy 96.140518 -49.48174)
			(xy 96.058537 -49.540022) (xy 95.928129 -49.62297) (xy 95.793624 -49.699095) (xy 95.655379 -49.768194)
			(xy 95.513759 -49.830085) (xy 95.369142 -49.884604) (xy 95.221909 -49.931606) (xy 95.072452 -49.970966)
			(xy 94.921168 -50.00258) (xy 94.768456 -50.026364) (xy 94.614722 -50.042255) (xy 94.460374 -50.050211)
			(xy 94.383098 -50.0507) (xy 92.782898 -50.0507) (xy 92.705622 -50.050194) (xy 92.551275 -50.042238)
			(xy 92.397543 -50.026347) (xy 92.244832 -50.002563) (xy 92.093548 -49.970949) (xy 91.944092 -49.931589)
			(xy 91.796861 -49.884587) (xy 91.652244 -49.830069) (xy 91.510626 -49.768178) (xy 91.372381 -49.699079)
			(xy 91.237877 -49.622954) (xy 91.10747 -49.540007) (xy 90.981506 -49.450456) (xy 90.860319 -49.35454)
			(xy 90.74423 -49.252512) (xy 90.633548 -49.144644) (xy 90.528565 -49.031221) (xy 90.42956 -48.912543)
			(xy 90.336796 -48.788927) (xy 90.250519 -48.660699) (xy 90.170957 -48.528199) (xy 90.098321 -48.391779)
			(xy 90.032804 -48.251802) (xy 89.97458 -48.108637) (xy 89.923803 -47.962664) (xy 89.880608 -47.814271)
			(xy 89.84511 -47.663852) (xy 89.817402 -47.511804) (xy 89.797557 -47.358531) (xy 89.78563 -47.204441)
			(xy 89.78165 -47.04994) (xy 67.384154 -47.04994) (xy 67.384157 -47.050067) (xy 67.380172 -47.204564)
			(xy 67.368238 -47.35865) (xy 67.348389 -47.511918) (xy 67.320675 -47.663961) (xy 67.285172 -47.814376)
			(xy 67.241973 -47.962763) (xy 67.191193 -48.108731) (xy 67.132966 -48.25189) (xy 67.067447 -48.391863)
			(xy 66.994809 -48.528277) (xy 66.915245 -48.660771) (xy 66.828966 -48.788993) (xy 66.736201 -48.912605)
			(xy 66.637196 -49.031277) (xy 66.532213 -49.144695) (xy 66.421531 -49.252559) (xy 66.305444 -49.354582)
			(xy 66.184258 -49.450493) (xy 66.058295 -49.54004) (xy 65.927891 -49.622983) (xy 65.793389 -49.699104)
			(xy 65.655147 -49.768199) (xy 65.513531 -49.830087) (xy 65.368918 -49.884603) (xy 65.22169 -49.931602)
			(xy 65.072237 -49.970961) (xy 64.920957 -50.002573) (xy 64.76825 -50.026356) (xy 64.614521 -50.042247)
			(xy 64.460178 -50.050202) (xy 64.382904 -50.0507) (xy 62.78245 -50.0507) (xy 62.705176 -50.050188)
			(xy 62.550834 -50.04222) (xy 62.397107 -50.026316) (xy 62.244402 -50.002521) (xy 62.093124 -49.970896)
			(xy 61.943675 -49.931526) (xy 61.796451 -49.884514) (xy 61.651842 -49.829987) (xy 61.510232 -49.768087)
			(xy 61.371996 -49.69898) (xy 61.2375 -49.622848) (xy 61.107102 -49.539894) (xy 60.981148 -49.450337)
			(xy 60.85997 -49.354416) (xy 60.743891 -49.252383) (xy 60.633218 -49.14451) (xy 60.528245 -49.031083)
			(xy 60.429249 -48.912403) (xy 60.336495 -48.788784) (xy 60.250227 -48.660555) (xy 60.170674 -48.528054)
			(xy 60.098048 -48.391634) (xy 60.032541 -48.251656) (xy 59.974326 -48.108492) (xy 59.923558 -47.96252)
			(xy 59.880371 -47.814129) (xy 59.844881 -47.663712) (xy 59.81718 -47.511667) (xy 59.797344 -47.358397)
			(xy 59.785423 -47.20431) (xy 59.781451 -47.049813) (xy 0.509016 -47.049813) (xy 0.509016 -50.949098)
			(xy 181.659784 -50.949098) (xy 181.659784 -50.085498) (xy 181.66027 -50.058247) (xy 181.668026 -50.004299)
			(xy 181.683381 -49.952004) (xy 181.706023 -49.902427) (xy 181.735489 -49.856577) (xy 181.77118 -49.815386)
			(xy 181.812371 -49.779695) (xy 181.858221 -49.750229) (xy 181.907798 -49.727587) (xy 181.960093 -49.712232)
			(xy 182.014041 -49.704476) (xy 182.068543 -49.704476) (xy 182.122491 -49.712232) (xy 182.174786 -49.727587)
			(xy 182.224363 -49.750229) (xy 182.270213 -49.779695) (xy 182.311404 -49.815386) (xy 182.347095 -49.856577)
			(xy 182.376561 -49.902427) (xy 182.399203 -49.952004) (xy 182.414558 -50.004299) (xy 182.422314 -50.058247)
			(xy 182.4228 -50.085498) (xy 182.4228 -50.949098) (xy 182.422314 -50.976349) (xy 182.414558 -51.030297)
			(xy 182.399203 -51.082592) (xy 182.376561 -51.132169) (xy 182.347095 -51.178019) (xy 182.311404 -51.21921)
			(xy 182.270213 -51.254901) (xy 182.224363 -51.284367) (xy 182.174786 -51.307009) (xy 182.122491 -51.322364)
			(xy 182.068543 -51.33012) (xy 182.014041 -51.33012) (xy 181.960093 -51.322364) (xy 181.907798 -51.307009)
			(xy 181.858221 -51.284367) (xy 181.812371 -51.254901) (xy 181.77118 -51.21921) (xy 181.735489 -51.178019)
			(xy 181.706023 -51.132169) (xy 181.683381 -51.082592) (xy 181.668026 -51.030297) (xy 181.66027 -50.976349)
			(xy 181.659784 -50.949098) (xy 0.509016 -50.949098) (xy 0.509016 -52.481734) (xy 178.630072 -52.481734)
			(xy 178.630072 -51.618134) (xy 178.630558 -51.590883) (xy 178.638314 -51.536935) (xy 178.653669 -51.48464)
			(xy 178.676311 -51.435063) (xy 178.705777 -51.389213) (xy 178.741468 -51.348022) (xy 178.782659 -51.312331)
			(xy 178.828509 -51.282865) (xy 178.878086 -51.260223) (xy 178.930381 -51.244868) (xy 178.984329 -51.237112)
			(xy 179.038831 -51.237112) (xy 179.092779 -51.244868) (xy 179.145074 -51.260223) (xy 179.194651 -51.282865)
			(xy 179.240501 -51.312331) (xy 179.281692 -51.348022) (xy 179.317383 -51.389213) (xy 179.346849 -51.435063)
			(xy 179.369491 -51.48464) (xy 179.384846 -51.536935) (xy 179.392602 -51.590883) (xy 179.393088 -51.618134)
			(xy 179.393088 -51.999896) (xy 201.367397 -51.999896) (xy 201.371407 -51.837793) (xy 201.38343 -51.676088)
			(xy 201.403434 -51.515174) (xy 201.431372 -51.355447) (xy 201.467175 -51.197297) (xy 201.510755 -51.041111)
			(xy 201.562006 -50.887271) (xy 201.620802 -50.736154) (xy 201.687 -50.58813) (xy 201.760436 -50.44356)
			(xy 201.840933 -50.302799) (xy 201.928292 -50.166191) (xy 202.0223 -50.034071) (xy 202.122727 -49.906761)
			(xy 202.229327 -49.784573) (xy 202.341839 -49.667807) (xy 202.459987 -49.556748) (xy 202.583484 -49.451667)
			(xy 202.712026 -49.352823) (xy 202.845299 -49.260456) (xy 202.982977 -49.174793) (xy 203.124723 -49.096044)
			(xy 203.27019 -49.024401) (xy 203.419022 -48.960039) (xy 203.570854 -48.903117) (xy 203.725316 -48.853773)
			(xy 203.882029 -48.812128) (xy 204.04061 -48.778283) (xy 204.200671 -48.752323) (xy 204.361819 -48.73431)
			(xy 204.523661 -48.724289) (xy 204.685801 -48.722283) (xy 204.847842 -48.728299) (xy 205.009386 -48.74232)
			(xy 205.17004 -48.764313) (xy 205.32941 -48.794225) (xy 205.487105 -48.831981) (xy 205.64274 -48.877489)
			(xy 205.795934 -48.930639) (xy 205.946312 -48.9913) (xy 206.093507 -49.059323) (xy 206.237157 -49.134542)
			(xy 206.376912 -49.216773) (xy 206.512428 -49.305815) (xy 206.643376 -49.40145) (xy 206.769434 -49.503444)
			(xy 206.890294 -49.611547) (xy 207.00566 -49.725494) (xy 207.115249 -49.845008) (xy 207.218794 -49.969795)
			(xy 207.316041 -50.09955) (xy 207.406753 -50.233955) (xy 207.424818 -50.263806) (xy 239.457992 -50.263806)
			(xy 239.457992 -49.400206) (xy 239.458478 -49.372955) (xy 239.466234 -49.319007) (xy 239.481589 -49.266712)
			(xy 239.504231 -49.217135) (xy 239.533697 -49.171285) (xy 239.569388 -49.130094) (xy 239.610579 -49.094403)
			(xy 239.656429 -49.064937) (xy 239.706006 -49.042295) (xy 239.758301 -49.02694) (xy 239.812249 -49.019184)
			(xy 239.866751 -49.019184) (xy 239.920699 -49.02694) (xy 239.972994 -49.042295) (xy 240.022571 -49.064937)
			(xy 240.068421 -49.094403) (xy 240.109612 -49.130094) (xy 240.145303 -49.171285) (xy 240.174769 -49.217135)
			(xy 240.197411 -49.266712) (xy 240.212766 -49.319007) (xy 240.220522 -49.372955) (xy 240.221008 -49.400206)
			(xy 240.221008 -50.263806) (xy 240.220522 -50.291057) (xy 240.212766 -50.345005) (xy 240.197411 -50.3973)
			(xy 240.174769 -50.446877) (xy 240.145303 -50.492727) (xy 240.109612 -50.533918) (xy 240.068421 -50.569609)
			(xy 240.022571 -50.599075) (xy 239.972994 -50.621717) (xy 239.920699 -50.637072) (xy 239.866751 -50.644828)
			(xy 239.812249 -50.644828) (xy 239.758301 -50.637072) (xy 239.706006 -50.621717) (xy 239.656429 -50.599075)
			(xy 239.610579 -50.569609) (xy 239.569388 -50.533918) (xy 239.533697 -50.492727) (xy 239.504231 -50.446877)
			(xy 239.481589 -50.3973) (xy 239.466234 -50.345005) (xy 239.458478 -50.291057) (xy 239.457992 -50.263806)
			(xy 207.424818 -50.263806) (xy 207.490706 -50.372682) (xy 207.567696 -50.515391) (xy 207.637535 -50.661732)
			(xy 207.70005 -50.811349) (xy 207.755091 -50.963874) (xy 207.802521 -51.118934) (xy 207.842224 -51.27615)
			(xy 207.874105 -51.435138) (xy 207.898083 -51.595507) (xy 207.914102 -51.756866) (xy 207.922121 -51.91882)
			(xy 207.922622 -51.999896) (xy 207.922121 -52.080972) (xy 207.914102 -52.242926) (xy 207.898083 -52.404285)
			(xy 207.874105 -52.564654) (xy 207.842224 -52.723642) (xy 207.802521 -52.880858) (xy 207.794624 -52.906676)
			(xy 228.815392 -52.906676) (xy 228.815392 -52.043076) (xy 228.815878 -52.015825) (xy 228.823634 -51.961877)
			(xy 228.838989 -51.909582) (xy 228.861631 -51.860005) (xy 228.891097 -51.814155) (xy 228.926788 -51.772964)
			(xy 228.967979 -51.737273) (xy 229.013829 -51.707807) (xy 229.063406 -51.685165) (xy 229.115701 -51.66981)
			(xy 229.169649 -51.662054) (xy 229.224151 -51.662054) (xy 229.278099 -51.66981) (xy 229.330394 -51.685165)
			(xy 229.379971 -51.707807) (xy 229.425821 -51.737273) (xy 229.467012 -51.772964) (xy 229.502703 -51.814155)
			(xy 229.532169 -51.860005) (xy 229.554811 -51.909582) (xy 229.570166 -51.961877) (xy 229.577922 -52.015825)
			(xy 229.578408 -52.043076) (xy 229.578408 -52.90185) (xy 241.926872 -52.90185) (xy 241.926872 -52.03825)
			(xy 241.927358 -52.010999) (xy 241.935114 -51.957051) (xy 241.950469 -51.904756) (xy 241.973111 -51.855179)
			(xy 242.002577 -51.809329) (xy 242.038268 -51.768138) (xy 242.079459 -51.732447) (xy 242.125309 -51.702981)
			(xy 242.174886 -51.680339) (xy 242.227181 -51.664984) (xy 242.281129 -51.657228) (xy 242.335631 -51.657228)
			(xy 242.389579 -51.664984) (xy 242.441874 -51.680339) (xy 242.491451 -51.702981) (xy 242.537301 -51.732447)
			(xy 242.578492 -51.768138) (xy 242.614183 -51.809329) (xy 242.643649 -51.855179) (xy 242.666291 -51.904756)
			(xy 242.681646 -51.957051) (xy 242.687806 -51.999896) (xy 265.367269 -51.999896) (xy 265.371279 -51.837793)
			(xy 265.383302 -51.676088) (xy 265.403306 -51.515174) (xy 265.431244 -51.355447) (xy 265.467047 -51.197297)
			(xy 265.510627 -51.041111) (xy 265.561878 -50.887271) (xy 265.620674 -50.736154) (xy 265.686872 -50.58813)
			(xy 265.760308 -50.44356) (xy 265.840805 -50.302799) (xy 265.928164 -50.166191) (xy 266.022172 -50.034071)
			(xy 266.122599 -49.906761) (xy 266.229199 -49.784573) (xy 266.341711 -49.667807) (xy 266.459859 -49.556748)
			(xy 266.583356 -49.451667) (xy 266.711898 -49.352823) (xy 266.845171 -49.260456) (xy 266.982849 -49.174793)
			(xy 267.124595 -49.096044) (xy 267.270062 -49.024401) (xy 267.418894 -48.960039) (xy 267.570726 -48.903117)
			(xy 267.725188 -48.853773) (xy 267.881901 -48.812128) (xy 268.040482 -48.778283) (xy 268.200543 -48.752323)
			(xy 268.361691 -48.73431) (xy 268.523533 -48.724289) (xy 268.685673 -48.722283) (xy 268.847714 -48.728299)
			(xy 269.009258 -48.74232) (xy 269.169912 -48.764313) (xy 269.329282 -48.794225) (xy 269.486977 -48.831981)
			(xy 269.642612 -48.877489) (xy 269.795806 -48.930639) (xy 269.946184 -48.9913) (xy 270.093379 -49.059323)
			(xy 270.237029 -49.134542) (xy 270.376784 -49.216773) (xy 270.5123 -49.305815) (xy 270.643248 -49.40145)
			(xy 270.769306 -49.503444) (xy 270.890166 -49.611547) (xy 271.005532 -49.725494) (xy 271.115121 -49.845008)
			(xy 271.218666 -49.969795) (xy 271.315913 -50.09955) (xy 271.406625 -50.233955) (xy 271.40723 -50.234955)
			(xy 350.291827 -50.234955) (xy 350.291827 -50.180445) (xy 350.299585 -50.126489) (xy 350.314942 -50.074187)
			(xy 350.337587 -50.024602) (xy 350.367058 -49.978745) (xy 350.402755 -49.937549) (xy 350.443952 -49.901853)
			(xy 350.489809 -49.872383) (xy 350.539394 -49.849739) (xy 350.591697 -49.834383) (xy 350.645653 -49.826626)
			(xy 350.672908 -49.826164) (xy 351.536508 -49.826164) (xy 351.563757 -49.826707) (xy 351.6177 -49.834464)
			(xy 351.66999 -49.849818) (xy 351.719562 -49.872458) (xy 351.765408 -49.901922) (xy 351.806594 -49.937611)
			(xy 351.842282 -49.978798) (xy 351.871746 -50.024645) (xy 351.894385 -50.074218) (xy 351.909738 -50.126508)
			(xy 351.917494 -50.180451) (xy 351.917494 -50.234949) (xy 351.917493 -50.234956) (xy 352.489927 -50.234956)
			(xy 352.489927 -50.180444) (xy 352.497685 -50.126487) (xy 352.513044 -50.074183) (xy 352.535689 -50.024598)
			(xy 352.565162 -49.97874) (xy 352.600861 -49.937544) (xy 352.642059 -49.901848) (xy 352.687919 -49.872378)
			(xy 352.737506 -49.849735) (xy 352.78981 -49.83438) (xy 352.843768 -49.826625) (xy 352.871024 -49.826164)
			(xy 353.734624 -49.826164) (xy 353.761872 -49.826708) (xy 353.815813 -49.834467) (xy 353.868101 -49.849823)
			(xy 353.917672 -49.872463) (xy 353.963516 -49.901928) (xy 354.0047 -49.937617) (xy 354.040386 -49.978804)
			(xy 354.069848 -50.024649) (xy 354.092486 -50.074221) (xy 354.107839 -50.12651) (xy 354.115594 -50.180452)
			(xy 354.115594 -50.234948) (xy 354.115593 -50.234956) (xy 354.712427 -50.234956) (xy 354.712427 -50.180444)
			(xy 354.720185 -50.126487) (xy 354.735544 -50.074183) (xy 354.758189 -50.024598) (xy 354.787662 -49.97874)
			(xy 354.823361 -49.937544) (xy 354.864559 -49.901848) (xy 354.910419 -49.872378) (xy 354.960006 -49.849735)
			(xy 355.01231 -49.83438) (xy 355.066268 -49.826625) (xy 355.093524 -49.826164) (xy 355.957124 -49.826164)
			(xy 355.984372 -49.826708) (xy 356.038313 -49.834467) (xy 356.090601 -49.849823) (xy 356.140172 -49.872463)
			(xy 356.186016 -49.901928) (xy 356.2272 -49.937617) (xy 356.262886 -49.978804) (xy 356.292348 -50.024649)
			(xy 356.314986 -50.074221) (xy 356.330339 -50.12651) (xy 356.338094 -50.180452) (xy 356.338094 -50.234948)
			(xy 356.338093 -50.234957) (xy 356.942527 -50.234957) (xy 356.942527 -50.180443) (xy 356.950286 -50.126484)
			(xy 356.965645 -50.074179) (xy 356.988293 -50.024592) (xy 357.017767 -49.978734) (xy 357.053468 -49.937537)
			(xy 357.094669 -49.90184) (xy 357.140531 -49.872371) (xy 357.19012 -49.84973) (xy 357.242427 -49.834376)
			(xy 357.296387 -49.826624) (xy 357.323644 -49.826164) (xy 358.187244 -49.826164) (xy 358.214491 -49.826709)
			(xy 358.26843 -49.83447) (xy 358.320716 -49.849828) (xy 358.370284 -49.87247) (xy 358.416125 -49.901935)
			(xy 358.457307 -49.937624) (xy 358.492991 -49.97881) (xy 358.522451 -50.024655) (xy 358.545087 -50.074226)
			(xy 358.560439 -50.126513) (xy 358.568194 -50.180453) (xy 358.568194 -50.234947) (xy 358.560439 -50.288887)
			(xy 358.545087 -50.341174) (xy 358.522451 -50.390745) (xy 358.492991 -50.43659) (xy 358.457307 -50.477776)
			(xy 358.416125 -50.513465) (xy 358.370284 -50.54293) (xy 358.320716 -50.565572) (xy 358.26843 -50.58093)
			(xy 358.214491 -50.588691) (xy 358.187244 -50.58918) (xy 357.323644 -50.58918) (xy 357.296387 -50.588776)
			(xy 357.242427 -50.581024) (xy 357.19012 -50.56567) (xy 357.140531 -50.543029) (xy 357.094669 -50.51356)
			(xy 357.053468 -50.477863) (xy 357.017767 -50.436666) (xy 356.988293 -50.390808) (xy 356.965645 -50.341221)
			(xy 356.950286 -50.288916) (xy 356.942527 -50.234957) (xy 356.338093 -50.234957) (xy 356.330339 -50.28889)
			(xy 356.314986 -50.341179) (xy 356.292348 -50.390751) (xy 356.262886 -50.436596) (xy 356.2272 -50.477783)
			(xy 356.186016 -50.513472) (xy 356.140172 -50.542937) (xy 356.090601 -50.565577) (xy 356.038313 -50.580933)
			(xy 355.984372 -50.588692) (xy 355.957124 -50.58918) (xy 355.093524 -50.58918) (xy 355.066268 -50.588775)
			(xy 355.01231 -50.58102) (xy 354.960006 -50.565665) (xy 354.910419 -50.543022) (xy 354.864559 -50.513552)
			(xy 354.823361 -50.477856) (xy 354.787662 -50.43666) (xy 354.758189 -50.390802) (xy 354.735544 -50.341217)
			(xy 354.720185 -50.288913) (xy 354.712427 -50.234956) (xy 354.115593 -50.234956) (xy 354.107839 -50.28889)
			(xy 354.092486 -50.341179) (xy 354.069848 -50.390751) (xy 354.040386 -50.436596) (xy 354.0047 -50.477783)
			(xy 353.963516 -50.513472) (xy 353.917672 -50.542937) (xy 353.868101 -50.565577) (xy 353.815813 -50.580933)
			(xy 353.761872 -50.588692) (xy 353.734624 -50.58918) (xy 352.871024 -50.58918) (xy 352.843768 -50.588775)
			(xy 352.78981 -50.58102) (xy 352.737506 -50.565665) (xy 352.687919 -50.543022) (xy 352.642059 -50.513552)
			(xy 352.600861 -50.477856) (xy 352.565162 -50.43666) (xy 352.535689 -50.390802) (xy 352.513044 -50.341217)
			(xy 352.497685 -50.288913) (xy 352.489927 -50.234956) (xy 351.917493 -50.234956) (xy 351.909738 -50.288892)
			(xy 351.894385 -50.341182) (xy 351.871746 -50.390755) (xy 351.842282 -50.436602) (xy 351.806594 -50.477789)
			(xy 351.765408 -50.513477) (xy 351.719562 -50.542942) (xy 351.66999 -50.565582) (xy 351.6177 -50.580936)
			(xy 351.563757 -50.588693) (xy 351.536508 -50.58918) (xy 350.672908 -50.58918) (xy 350.645653 -50.588774)
			(xy 350.591697 -50.581017) (xy 350.539394 -50.565661) (xy 350.489809 -50.543017) (xy 350.443952 -50.513547)
			(xy 350.402755 -50.477851) (xy 350.367058 -50.436655) (xy 350.337587 -50.390798) (xy 350.314942 -50.341213)
			(xy 350.299585 -50.288911) (xy 350.291827 -50.234955) (xy 271.40723 -50.234955) (xy 271.490578 -50.372682)
			(xy 271.567568 -50.515391) (xy 271.637407 -50.661732) (xy 271.699922 -50.811349) (xy 271.754963 -50.963874)
			(xy 271.802393 -51.118934) (xy 271.842096 -51.27615) (xy 271.873977 -51.435138) (xy 271.897955 -51.595507)
			(xy 271.913974 -51.756866) (xy 271.921993 -51.91882) (xy 271.922494 -51.999896) (xy 271.921993 -52.080972)
			(xy 271.913974 -52.242926) (xy 271.897955 -52.404285) (xy 271.873977 -52.564654) (xy 271.842096 -52.723642)
			(xy 271.802393 -52.880858) (xy 271.754963 -53.035918) (xy 271.699922 -53.188443) (xy 271.637407 -53.33806)
			(xy 271.567568 -53.484401) (xy 271.490578 -53.62711) (xy 271.406625 -53.765837) (xy 271.315913 -53.900242)
			(xy 271.218666 -54.029997) (xy 271.115121 -54.154784) (xy 271.005532 -54.274298) (xy 270.890166 -54.388245)
			(xy 270.769306 -54.496348) (xy 270.643248 -54.598342) (xy 270.5123 -54.693977) (xy 270.376784 -54.783019)
			(xy 270.237029 -54.86525) (xy 270.093379 -54.940469) (xy 269.946184 -55.008492) (xy 269.795806 -55.069153)
			(xy 269.642612 -55.122303) (xy 269.486977 -55.167811) (xy 269.329282 -55.205567) (xy 269.169912 -55.235479)
			(xy 269.009258 -55.257472) (xy 268.847714 -55.271493) (xy 268.685673 -55.277509) (xy 268.523533 -55.275503)
			(xy 268.361691 -55.265482) (xy 268.200543 -55.247469) (xy 268.040482 -55.221509) (xy 267.881901 -55.187664)
			(xy 267.725188 -55.146019) (xy 267.570726 -55.096675) (xy 267.418894 -55.039753) (xy 267.270062 -54.975391)
			(xy 267.124595 -54.903748) (xy 266.982849 -54.824999) (xy 266.845171 -54.739336) (xy 266.711898 -54.646969)
			(xy 266.583356 -54.548125) (xy 266.459859 -54.443044) (xy 266.341711 -54.331985) (xy 266.229199 -54.215219)
			(xy 266.122599 -54.093031) (xy 266.022172 -53.965721) (xy 265.928164 -53.833601) (xy 265.840805 -53.696993)
			(xy 265.760308 -53.556232) (xy 265.686872 -53.411662) (xy 265.620674 -53.263638) (xy 265.561878 -53.112521)
			(xy 265.510627 -52.958681) (xy 265.467047 -52.802495) (xy 265.431244 -52.644345) (xy 265.403306 -52.484618)
			(xy 265.383302 -52.323704) (xy 265.371279 -52.161999) (xy 265.367269 -51.999896) (xy 242.687806 -51.999896)
			(xy 242.689402 -52.010999) (xy 242.689888 -52.03825) (xy 242.689888 -52.90185) (xy 242.689402 -52.929101)
			(xy 242.681646 -52.983049) (xy 242.666291 -53.035344) (xy 242.643649 -53.084921) (xy 242.614183 -53.130771)
			(xy 242.578492 -53.171962) (xy 242.537301 -53.207653) (xy 242.491451 -53.237119) (xy 242.441874 -53.259761)
			(xy 242.389579 -53.275116) (xy 242.335631 -53.282872) (xy 242.281129 -53.282872) (xy 242.227181 -53.275116)
			(xy 242.174886 -53.259761) (xy 242.125309 -53.237119) (xy 242.079459 -53.207653) (xy 242.038268 -53.171962)
			(xy 242.002577 -53.130771) (xy 241.973111 -53.084921) (xy 241.950469 -53.035344) (xy 241.935114 -52.983049)
			(xy 241.927358 -52.929101) (xy 241.926872 -52.90185) (xy 229.578408 -52.90185) (xy 229.578408 -52.906676)
			(xy 229.577922 -52.933927) (xy 229.570166 -52.987875) (xy 229.554811 -53.04017) (xy 229.532169 -53.089747)
			(xy 229.502703 -53.135597) (xy 229.467012 -53.176788) (xy 229.425821 -53.212479) (xy 229.379971 -53.241945)
			(xy 229.330394 -53.264587) (xy 229.278099 -53.279942) (xy 229.224151 -53.287698) (xy 229.169649 -53.287698)
			(xy 229.115701 -53.279942) (xy 229.063406 -53.264587) (xy 229.013829 -53.241945) (xy 228.967979 -53.212479)
			(xy 228.926788 -53.176788) (xy 228.891097 -53.135597) (xy 228.861631 -53.089747) (xy 228.838989 -53.04017)
			(xy 228.823634 -52.987875) (xy 228.815878 -52.933927) (xy 228.815392 -52.906676) (xy 207.794624 -52.906676)
			(xy 207.755091 -53.035918) (xy 207.70005 -53.188443) (xy 207.637535 -53.33806) (xy 207.567696 -53.484401)
			(xy 207.490706 -53.62711) (xy 207.406753 -53.765837) (xy 207.316041 -53.900242) (xy 207.218794 -54.029997)
			(xy 207.115249 -54.154784) (xy 207.00566 -54.274298) (xy 206.890294 -54.388245) (xy 206.769434 -54.496348)
			(xy 206.643376 -54.598342) (xy 206.512428 -54.693977) (xy 206.493338 -54.70652) (xy 230.115872 -54.70652)
			(xy 230.115872 -53.84292) (xy 230.116358 -53.815669) (xy 230.124114 -53.761721) (xy 230.139469 -53.709426)
			(xy 230.162111 -53.659849) (xy 230.191577 -53.613999) (xy 230.227268 -53.572808) (xy 230.268459 -53.537117)
			(xy 230.314309 -53.507651) (xy 230.363886 -53.485009) (xy 230.416181 -53.469654) (xy 230.470129 -53.461898)
			(xy 230.524631 -53.461898) (xy 230.578579 -53.469654) (xy 230.630874 -53.485009) (xy 230.680451 -53.507651)
			(xy 230.726301 -53.537117) (xy 230.767492 -53.572808) (xy 230.803183 -53.613999) (xy 230.832649 -53.659849)
			(xy 230.855291 -53.709426) (xy 230.870646 -53.761721) (xy 230.878402 -53.815669) (xy 230.878888 -53.84292)
			(xy 230.878888 -54.70652) (xy 230.878811 -54.710838) (xy 240.282476 -54.710838) (xy 240.282476 -53.847238)
			(xy 240.282962 -53.819987) (xy 240.290718 -53.766039) (xy 240.306073 -53.713744) (xy 240.328715 -53.664167)
			(xy 240.358181 -53.618317) (xy 240.393872 -53.577126) (xy 240.435063 -53.541435) (xy 240.480913 -53.511969)
			(xy 240.53049 -53.489327) (xy 240.582785 -53.473972) (xy 240.636733 -53.466216) (xy 240.691235 -53.466216)
			(xy 240.745183 -53.473972) (xy 240.797478 -53.489327) (xy 240.847055 -53.511969) (xy 240.892905 -53.541435)
			(xy 240.934096 -53.577126) (xy 240.969787 -53.618317) (xy 240.999253 -53.664167) (xy 241.021895 -53.713744)
			(xy 241.03725 -53.766039) (xy 241.045006 -53.819987) (xy 241.045492 -53.847238) (xy 241.045492 -54.710838)
			(xy 241.045006 -54.738089) (xy 241.03725 -54.792037) (xy 241.021895 -54.844332) (xy 240.999253 -54.893909)
			(xy 240.969787 -54.939759) (xy 240.934096 -54.98095) (xy 240.892905 -55.016641) (xy 240.847055 -55.046107)
			(xy 240.797478 -55.068749) (xy 240.745183 -55.084104) (xy 240.691235 -55.09186) (xy 240.636733 -55.09186)
			(xy 240.582785 -55.084104) (xy 240.53049 -55.068749) (xy 240.480913 -55.046107) (xy 240.435063 -55.016641)
			(xy 240.393872 -54.98095) (xy 240.358181 -54.939759) (xy 240.328715 -54.893909) (xy 240.306073 -54.844332)
			(xy 240.290718 -54.792037) (xy 240.282962 -54.738089) (xy 240.282476 -54.710838) (xy 230.878811 -54.710838)
			(xy 230.878402 -54.733771) (xy 230.870646 -54.787719) (xy 230.855291 -54.840014) (xy 230.832649 -54.889591)
			(xy 230.803183 -54.935441) (xy 230.767492 -54.976632) (xy 230.726301 -55.012323) (xy 230.680451 -55.041789)
			(xy 230.630874 -55.064431) (xy 230.578579 -55.079786) (xy 230.524631 -55.087542) (xy 230.470129 -55.087542)
			(xy 230.416181 -55.079786) (xy 230.363886 -55.064431) (xy 230.314309 -55.041789) (xy 230.268459 -55.012323)
			(xy 230.227268 -54.976632) (xy 230.191577 -54.935441) (xy 230.162111 -54.889591) (xy 230.139469 -54.840014)
			(xy 230.124114 -54.787719) (xy 230.116358 -54.733771) (xy 230.115872 -54.70652) (xy 206.493338 -54.70652)
			(xy 206.376912 -54.783019) (xy 206.237157 -54.86525) (xy 206.093507 -54.940469) (xy 205.946312 -55.008492)
			(xy 205.795934 -55.069153) (xy 205.64274 -55.122303) (xy 205.487105 -55.167811) (xy 205.32941 -55.205567)
			(xy 205.17004 -55.235479) (xy 205.009386 -55.257472) (xy 204.847842 -55.271493) (xy 204.685801 -55.277509)
			(xy 204.523661 -55.275503) (xy 204.361819 -55.265482) (xy 204.200671 -55.247469) (xy 204.04061 -55.221509)
			(xy 203.882029 -55.187664) (xy 203.725316 -55.146019) (xy 203.570854 -55.096675) (xy 203.419022 -55.039753)
			(xy 203.27019 -54.975391) (xy 203.124723 -54.903748) (xy 202.982977 -54.824999) (xy 202.845299 -54.739336)
			(xy 202.712026 -54.646969) (xy 202.583484 -54.548125) (xy 202.459987 -54.443044) (xy 202.341839 -54.331985)
			(xy 202.229327 -54.215219) (xy 202.122727 -54.093031) (xy 202.0223 -53.965721) (xy 201.928292 -53.833601)
			(xy 201.840933 -53.696993) (xy 201.760436 -53.556232) (xy 201.687 -53.411662) (xy 201.620802 -53.263638)
			(xy 201.562006 -53.112521) (xy 201.510755 -52.958681) (xy 201.467175 -52.802495) (xy 201.431372 -52.644345)
			(xy 201.403434 -52.484618) (xy 201.38343 -52.323704) (xy 201.371407 -52.161999) (xy 201.367397 -51.999896)
			(xy 179.393088 -51.999896) (xy 179.393088 -52.481734) (xy 179.392602 -52.508985) (xy 179.384846 -52.562933)
			(xy 179.369491 -52.615228) (xy 179.346849 -52.664805) (xy 179.317383 -52.710655) (xy 179.281692 -52.751846)
			(xy 179.240501 -52.787537) (xy 179.194651 -52.817003) (xy 179.145074 -52.839645) (xy 179.092779 -52.855)
			(xy 179.038831 -52.862756) (xy 178.984329 -52.862756) (xy 178.930381 -52.855) (xy 178.878086 -52.839645)
			(xy 178.828509 -52.817003) (xy 178.782659 -52.787537) (xy 178.741468 -52.751846) (xy 178.705777 -52.710655)
			(xy 178.676311 -52.664805) (xy 178.653669 -52.615228) (xy 178.638314 -52.562933) (xy 178.630558 -52.508985)
			(xy 178.630072 -52.481734) (xy 0.509016 -52.481734) (xy 0.509016 -53.954934) (xy 181.659784 -53.954934)
			(xy 181.659784 -53.091334) (xy 181.66027 -53.064083) (xy 181.668026 -53.010135) (xy 181.683381 -52.95784)
			(xy 181.706023 -52.908263) (xy 181.735489 -52.862413) (xy 181.77118 -52.821222) (xy 181.812371 -52.785531)
			(xy 181.858221 -52.756065) (xy 181.907798 -52.733423) (xy 181.960093 -52.718068) (xy 182.014041 -52.710312)
			(xy 182.068543 -52.710312) (xy 182.122491 -52.718068) (xy 182.174786 -52.733423) (xy 182.224363 -52.756065)
			(xy 182.270213 -52.785531) (xy 182.311404 -52.821222) (xy 182.347095 -52.862413) (xy 182.376561 -52.908263)
			(xy 182.399203 -52.95784) (xy 182.414558 -53.010135) (xy 182.422314 -53.064083) (xy 182.4228 -53.091334)
			(xy 182.4228 -53.954934) (xy 182.422314 -53.982185) (xy 182.414558 -54.036133) (xy 182.399203 -54.088428)
			(xy 182.376561 -54.138005) (xy 182.347095 -54.183855) (xy 182.311404 -54.225046) (xy 182.270213 -54.260737)
			(xy 182.224363 -54.290203) (xy 182.174786 -54.312845) (xy 182.122491 -54.3282) (xy 182.068543 -54.335956)
			(xy 182.014041 -54.335956) (xy 181.960093 -54.3282) (xy 181.907798 -54.312845) (xy 181.858221 -54.290203)
			(xy 181.812371 -54.260737) (xy 181.77118 -54.225046) (xy 181.735489 -54.183855) (xy 181.706023 -54.138005)
			(xy 181.683381 -54.088428) (xy 181.668026 -54.036133) (xy 181.66027 -53.982185) (xy 181.659784 -53.954934)
			(xy 0.509016 -53.954934) (xy 0.509016 -55.481728) (xy 178.630072 -55.481728) (xy 178.630072 -54.618128)
			(xy 178.630558 -54.590877) (xy 178.638314 -54.536929) (xy 178.653669 -54.484634) (xy 178.676311 -54.435057)
			(xy 178.705777 -54.389207) (xy 178.741468 -54.348016) (xy 178.782659 -54.312325) (xy 178.828509 -54.282859)
			(xy 178.878086 -54.260217) (xy 178.930381 -54.244862) (xy 178.984329 -54.237106) (xy 179.038831 -54.237106)
			(xy 179.092779 -54.244862) (xy 179.145074 -54.260217) (xy 179.194651 -54.282859) (xy 179.240501 -54.312325)
			(xy 179.281692 -54.348016) (xy 179.317383 -54.389207) (xy 179.346849 -54.435057) (xy 179.369491 -54.484634)
			(xy 179.384846 -54.536929) (xy 179.392602 -54.590877) (xy 179.393088 -54.618128) (xy 179.393088 -55.481728)
			(xy 179.392602 -55.508979) (xy 179.384846 -55.562927) (xy 179.369491 -55.615222) (xy 179.346849 -55.664799)
			(xy 179.317383 -55.710649) (xy 179.281692 -55.75184) (xy 179.240501 -55.787531) (xy 179.194651 -55.816997)
			(xy 179.145074 -55.839639) (xy 179.092779 -55.854994) (xy 179.038831 -55.86275) (xy 178.984329 -55.86275)
			(xy 178.930381 -55.854994) (xy 178.878086 -55.839639) (xy 178.828509 -55.816997) (xy 178.782659 -55.787531)
			(xy 178.741468 -55.75184) (xy 178.705777 -55.710649) (xy 178.676311 -55.664799) (xy 178.653669 -55.615222)
			(xy 178.638314 -55.562927) (xy 178.630558 -55.508979) (xy 178.630072 -55.481728) (xy 0.509016 -55.481728)
			(xy 0.509016 -57.094435) (xy 170.841915 -57.094435) (xy 170.841915 -57.005413) (xy 170.849895 -56.916749)
			(xy 170.865791 -56.829158) (xy 170.889474 -56.743343) (xy 170.920754 -56.659998) (xy 170.95938 -56.579792)
			(xy 171.005039 -56.503371) (xy 171.057365 -56.43135) (xy 171.115936 -56.36431) (xy 171.180281 -56.30279)
			(xy 171.249881 -56.247286) (xy 171.324177 -56.198244) (xy 171.402569 -56.156059) (xy 171.484428 -56.121071)
			(xy 171.569093 -56.093562) (xy 171.655883 -56.073752) (xy 171.744099 -56.061802) (xy 171.833032 -56.057809)
			(xy 171.921965 -56.061802) (xy 172.010181 -56.073752) (xy 172.096971 -56.093562) (xy 172.181636 -56.121071)
			(xy 172.263495 -56.156059) (xy 172.341887 -56.198244) (xy 172.416183 -56.247286) (xy 172.485783 -56.30279)
			(xy 172.550128 -56.36431) (xy 172.608699 -56.43135) (xy 172.661025 -56.503371) (xy 172.663117 -56.506872)
			(xy 228.815392 -56.506872) (xy 228.815392 -55.643272) (xy 228.815878 -55.616021) (xy 228.823634 -55.562073)
			(xy 228.838989 -55.509778) (xy 228.861631 -55.460201) (xy 228.891097 -55.414351) (xy 228.926788 -55.37316)
			(xy 228.967979 -55.337469) (xy 229.013829 -55.308003) (xy 229.063406 -55.285361) (xy 229.115701 -55.270006)
			(xy 229.169649 -55.26225) (xy 229.224151 -55.26225) (xy 229.278099 -55.270006) (xy 229.330394 -55.285361)
			(xy 229.379971 -55.308003) (xy 229.425821 -55.337469) (xy 229.467012 -55.37316) (xy 229.502703 -55.414351)
			(xy 229.532169 -55.460201) (xy 229.554811 -55.509778) (xy 229.570166 -55.562073) (xy 229.577922 -55.616021)
			(xy 229.578408 -55.643272) (xy 229.578408 -55.911852) (xy 357.10365 -55.911852) (xy 357.10365 -55.857348)
			(xy 357.111406 -55.803398) (xy 357.126762 -55.751101) (xy 357.149403 -55.701521) (xy 357.17887 -55.655668)
			(xy 357.214562 -55.614476) (xy 357.255752 -55.578782) (xy 357.301604 -55.549313) (xy 357.351182 -55.526669)
			(xy 357.403478 -55.511311) (xy 357.457428 -55.503551) (xy 357.48468 -55.503064) (xy 358.34828 -55.503064)
			(xy 358.375532 -55.503582) (xy 358.429481 -55.511336) (xy 358.481777 -55.526689) (xy 358.531356 -55.549329)
			(xy 358.577209 -55.578794) (xy 358.618401 -55.614485) (xy 358.654094 -55.655675) (xy 358.683562 -55.701526)
			(xy 358.706204 -55.751104) (xy 358.72156 -55.8034) (xy 358.729317 -55.857348) (xy 358.729317 -55.911852)
			(xy 358.729316 -55.911856) (xy 359.950927 -55.911856) (xy 359.950927 -55.857344) (xy 359.958685 -55.803388)
			(xy 359.974043 -55.751084) (xy 359.996689 -55.701499) (xy 360.026161 -55.655642) (xy 360.061859 -55.614445)
			(xy 360.103058 -55.578749) (xy 360.148917 -55.549279) (xy 360.198503 -55.526636) (xy 360.250807 -55.511281)
			(xy 360.304764 -55.503526) (xy 360.33202 -55.503064) (xy 361.19562 -55.503064) (xy 361.222868 -55.503608)
			(xy 361.27681 -55.511366) (xy 361.329098 -55.526722) (xy 361.378669 -55.549362) (xy 361.424514 -55.578827)
			(xy 361.465699 -55.614516) (xy 361.501385 -55.655702) (xy 361.530847 -55.701548) (xy 361.553485 -55.75112)
			(xy 361.568838 -55.80341) (xy 361.576594 -55.857352) (xy 361.576594 -55.911848) (xy 361.576593 -55.911857)
			(xy 363.514527 -55.911857) (xy 363.514527 -55.857343) (xy 363.522286 -55.803385) (xy 363.537645 -55.75108)
			(xy 363.560292 -55.701493) (xy 363.589766 -55.655635) (xy 363.625466 -55.614438) (xy 363.666667 -55.578742)
			(xy 363.712529 -55.549273) (xy 363.762117 -55.526631) (xy 363.814424 -55.511277) (xy 363.868383 -55.503524)
			(xy 363.89564 -55.503064) (xy 364.75924 -55.503064) (xy 364.786487 -55.503609) (xy 364.840427 -55.511369)
			(xy 364.892713 -55.526727) (xy 364.942281 -55.549369) (xy 364.988123 -55.578834) (xy 365.029306 -55.614523)
			(xy 365.06499 -55.655709) (xy 365.094451 -55.701554) (xy 365.117087 -55.751125) (xy 365.132439 -55.803412)
			(xy 365.140194 -55.857353) (xy 365.140194 -55.911847) (xy 365.132439 -55.965788) (xy 365.117087 -56.018075)
			(xy 365.094451 -56.067646) (xy 365.06499 -56.113491) (xy 365.029306 -56.154677) (xy 364.988123 -56.190366)
			(xy 364.942281 -56.219831) (xy 364.892713 -56.242473) (xy 364.840427 -56.257831) (xy 364.786487 -56.265591)
			(xy 364.75924 -56.26608) (xy 363.89564 -56.26608) (xy 363.868383 -56.265676) (xy 363.814424 -56.257923)
			(xy 363.762117 -56.242569) (xy 363.712529 -56.219927) (xy 363.666667 -56.190458) (xy 363.625466 -56.154762)
			(xy 363.589766 -56.113565) (xy 363.560292 -56.067707) (xy 363.537645 -56.01812) (xy 363.522286 -55.965815)
			(xy 363.514527 -55.911857) (xy 361.576593 -55.911857) (xy 361.568838 -55.96579) (xy 361.553485 -56.01808)
			(xy 361.530847 -56.067652) (xy 361.501385 -56.113498) (xy 361.465699 -56.154684) (xy 361.424514 -56.190373)
			(xy 361.378669 -56.219838) (xy 361.329098 -56.242478) (xy 361.27681 -56.257834) (xy 361.222868 -56.265592)
			(xy 361.19562 -56.26608) (xy 360.33202 -56.26608) (xy 360.304764 -56.265674) (xy 360.250807 -56.257919)
			(xy 360.198503 -56.242564) (xy 360.148917 -56.219921) (xy 360.103058 -56.190451) (xy 360.061859 -56.154755)
			(xy 360.026161 -56.113558) (xy 359.996689 -56.067701) (xy 359.974043 -56.018116) (xy 359.958685 -55.965812)
			(xy 359.950927 -55.911856) (xy 358.729316 -55.911856) (xy 358.72156 -55.9658) (xy 358.706204 -56.018096)
			(xy 358.683562 -56.067674) (xy 358.654094 -56.113525) (xy 358.618401 -56.154715) (xy 358.577209 -56.190406)
			(xy 358.531356 -56.219871) (xy 358.481777 -56.242511) (xy 358.429481 -56.257864) (xy 358.375532 -56.265618)
			(xy 358.34828 -56.26608) (xy 357.48468 -56.26608) (xy 357.457428 -56.265649) (xy 357.403478 -56.257889)
			(xy 357.351182 -56.242531) (xy 357.301604 -56.219887) (xy 357.255752 -56.190418) (xy 357.214562 -56.154724)
			(xy 357.17887 -56.113532) (xy 357.149403 -56.067679) (xy 357.126762 -56.018099) (xy 357.111406 -55.965802)
			(xy 357.10365 -55.911852) (xy 229.578408 -55.911852) (xy 229.578408 -56.506872) (xy 229.577922 -56.534123)
			(xy 229.570166 -56.588071) (xy 229.554811 -56.640366) (xy 229.532169 -56.689943) (xy 229.502703 -56.735793)
			(xy 229.467012 -56.776984) (xy 229.425821 -56.812675) (xy 229.379971 -56.842141) (xy 229.330394 -56.864783)
			(xy 229.278099 -56.880138) (xy 229.224151 -56.887894) (xy 229.169649 -56.887894) (xy 229.115701 -56.880138)
			(xy 229.063406 -56.864783) (xy 229.013829 -56.842141) (xy 228.967979 -56.812675) (xy 228.926788 -56.776984)
			(xy 228.891097 -56.735793) (xy 228.861631 -56.689943) (xy 228.838989 -56.640366) (xy 228.823634 -56.588071)
			(xy 228.815878 -56.534123) (xy 228.815392 -56.506872) (xy 172.663117 -56.506872) (xy 172.706684 -56.579792)
			(xy 172.74531 -56.659998) (xy 172.77659 -56.743343) (xy 172.800273 -56.829158) (xy 172.816169 -56.916749)
			(xy 172.824149 -57.005413) (xy 172.824648 -57.049924) (xy 172.824149 -57.094435) (xy 172.816169 -57.183099)
			(xy 172.800273 -57.27069) (xy 172.77659 -57.356505) (xy 172.74531 -57.43985) (xy 172.706684 -57.520056)
			(xy 172.661025 -57.596477) (xy 172.608699 -57.668498) (xy 172.550128 -57.735538) (xy 172.485783 -57.797058)
			(xy 172.416183 -57.852562) (xy 172.341887 -57.901604) (xy 172.263495 -57.943789) (xy 172.181636 -57.978777)
			(xy 172.096971 -58.006286) (xy 172.010181 -58.026096) (xy 171.921965 -58.038046) (xy 171.833032 -58.04204)
			(xy 171.744099 -58.038046) (xy 171.655883 -58.026096) (xy 171.569093 -58.006286) (xy 171.484428 -57.978777)
			(xy 171.402569 -57.943789) (xy 171.324177 -57.901604) (xy 171.249881 -57.852562) (xy 171.180281 -57.797058)
			(xy 171.115936 -57.735538) (xy 171.057365 -57.668498) (xy 171.005039 -57.596477) (xy 170.95938 -57.520056)
			(xy 170.920754 -57.43985) (xy 170.889474 -57.356505) (xy 170.865791 -57.27069) (xy 170.849895 -57.183099)
			(xy 170.841915 -57.094435) (xy 0.509016 -57.094435) (xy 0.509016 -58.306716) (xy 230.115872 -58.306716)
			(xy 230.115872 -57.443116) (xy 230.116358 -57.415865) (xy 230.124114 -57.361917) (xy 230.139469 -57.309622)
			(xy 230.162111 -57.260045) (xy 230.191577 -57.214195) (xy 230.227268 -57.173004) (xy 230.268459 -57.137313)
			(xy 230.314309 -57.107847) (xy 230.363886 -57.085205) (xy 230.416181 -57.06985) (xy 230.470129 -57.062094)
			(xy 230.524631 -57.062094) (xy 230.578579 -57.06985) (xy 230.630874 -57.085205) (xy 230.680451 -57.107847)
			(xy 230.726301 -57.137313) (xy 230.767492 -57.173004) (xy 230.803183 -57.214195) (xy 230.832649 -57.260045)
			(xy 230.855291 -57.309622) (xy 230.870646 -57.361917) (xy 230.878402 -57.415865) (xy 230.878888 -57.443116)
			(xy 230.878888 -58.30189) (xy 240.282476 -58.30189) (xy 240.282476 -57.43829) (xy 240.282962 -57.411039)
			(xy 240.290718 -57.357091) (xy 240.306073 -57.304796) (xy 240.328715 -57.255219) (xy 240.358181 -57.209369)
			(xy 240.393872 -57.168178) (xy 240.435063 -57.132487) (xy 240.480913 -57.103021) (xy 240.53049 -57.080379)
			(xy 240.582785 -57.065024) (xy 240.636733 -57.057268) (xy 240.691235 -57.057268) (xy 240.745183 -57.065024)
			(xy 240.797478 -57.080379) (xy 240.847055 -57.103021) (xy 240.892905 -57.132487) (xy 240.934096 -57.168178)
			(xy 240.969787 -57.209369) (xy 240.999253 -57.255219) (xy 241.021895 -57.304796) (xy 241.03725 -57.357091)
			(xy 241.045006 -57.411039) (xy 241.045492 -57.43829) (xy 241.045492 -58.30189) (xy 241.045006 -58.329141)
			(xy 241.03725 -58.383089) (xy 241.021895 -58.435384) (xy 240.999253 -58.484961) (xy 240.969787 -58.530811)
			(xy 240.941894 -58.563002) (xy 242.736116 -58.563002) (xy 242.736116 -57.699402) (xy 242.736602 -57.672151)
			(xy 242.744358 -57.618203) (xy 242.759713 -57.565908) (xy 242.782355 -57.516331) (xy 242.811821 -57.470481)
			(xy 242.847512 -57.42929) (xy 242.888703 -57.393599) (xy 242.934553 -57.364133) (xy 242.98413 -57.341491)
			(xy 243.036425 -57.326136) (xy 243.090373 -57.31838) (xy 243.144875 -57.31838) (xy 243.198823 -57.326136)
			(xy 243.251118 -57.341491) (xy 243.300695 -57.364133) (xy 243.346545 -57.393599) (xy 243.387736 -57.42929)
			(xy 243.423427 -57.470481) (xy 243.452893 -57.516331) (xy 243.475535 -57.565908) (xy 243.49089 -57.618203)
			(xy 243.498646 -57.672151) (xy 243.499132 -57.699402) (xy 243.499132 -58.563002) (xy 243.498646 -58.590253)
			(xy 243.49089 -58.644201) (xy 243.475535 -58.696496) (xy 243.452893 -58.746073) (xy 243.423427 -58.791923)
			(xy 243.387736 -58.833114) (xy 243.346545 -58.868805) (xy 243.300695 -58.898271) (xy 243.251118 -58.920913)
			(xy 243.198823 -58.936268) (xy 243.144875 -58.944024) (xy 243.090373 -58.944024) (xy 243.036425 -58.936268)
			(xy 242.98413 -58.920913) (xy 242.934553 -58.898271) (xy 242.888703 -58.868805) (xy 242.847512 -58.833114)
			(xy 242.811821 -58.791923) (xy 242.782355 -58.746073) (xy 242.759713 -58.696496) (xy 242.744358 -58.644201)
			(xy 242.736602 -58.590253) (xy 242.736116 -58.563002) (xy 240.941894 -58.563002) (xy 240.934096 -58.572002)
			(xy 240.892905 -58.607693) (xy 240.847055 -58.637159) (xy 240.797478 -58.659801) (xy 240.745183 -58.675156)
			(xy 240.691235 -58.682912) (xy 240.636733 -58.682912) (xy 240.582785 -58.675156) (xy 240.53049 -58.659801)
			(xy 240.480913 -58.637159) (xy 240.435063 -58.607693) (xy 240.393872 -58.572002) (xy 240.358181 -58.530811)
			(xy 240.328715 -58.484961) (xy 240.306073 -58.435384) (xy 240.290718 -58.383089) (xy 240.282962 -58.329141)
			(xy 240.282476 -58.30189) (xy 230.878888 -58.30189) (xy 230.878888 -58.306716) (xy 230.878402 -58.333967)
			(xy 230.870646 -58.387915) (xy 230.855291 -58.44021) (xy 230.832649 -58.489787) (xy 230.803183 -58.535637)
			(xy 230.767492 -58.576828) (xy 230.726301 -58.612519) (xy 230.680451 -58.641985) (xy 230.630874 -58.664627)
			(xy 230.578579 -58.679982) (xy 230.524631 -58.687738) (xy 230.470129 -58.687738) (xy 230.416181 -58.679982)
			(xy 230.363886 -58.664627) (xy 230.314309 -58.641985) (xy 230.268459 -58.612519) (xy 230.227268 -58.576828)
			(xy 230.191577 -58.535637) (xy 230.162111 -58.489787) (xy 230.139469 -58.44021) (xy 230.124114 -58.387915)
			(xy 230.116358 -58.333967) (xy 230.115872 -58.306716) (xy 0.509016 -58.306716) (xy 0.509016 -59.99988)
			(xy 16.983969 -59.99988) (xy 16.987993 -59.914112) (xy 17.000031 -59.829098) (xy 17.019978 -59.745584)
			(xy 17.047657 -59.664305) (xy 17.082825 -59.585976) (xy 17.125174 -59.511283) (xy 17.174331 -59.440885)
			(xy 17.229864 -59.375399) (xy 17.291286 -59.315401) (xy 17.358055 -59.261418) (xy 17.429587 -59.213925)
			(xy 17.505251 -59.173339) (xy 17.584384 -59.140016) (xy 17.666289 -59.11425) (xy 17.750247 -59.096267)
			(xy 17.835521 -59.086225) (xy 17.92136 -59.084212) (xy 18.00701 -59.090246) (xy 18.091718 -59.104274)
			(xy 18.174741 -59.126173) (xy 18.255349 -59.15575) (xy 18.332833 -59.192745) (xy 18.406512 -59.236833)
			(xy 18.475738 -59.287627) (xy 18.539905 -59.34468) (xy 18.598446 -59.407491) (xy 18.650849 -59.475508)
			(xy 18.696652 -59.548133) (xy 18.735453 -59.624728) (xy 18.766912 -59.70462) (xy 18.790751 -59.787107)
			(xy 18.806761 -59.871464) (xy 18.814801 -59.956949) (xy 18.815304 -59.99988) (xy 18.814801 -60.042811)
			(xy 18.806761 -60.128296) (xy 18.790751 -60.212653) (xy 18.766912 -60.29514) (xy 18.735453 -60.375032)
			(xy 18.73545 -60.375038) (xy 233.333297 -60.375038) (xy 233.337302 -60.28713) (xy 233.349285 -60.19995)
			(xy 233.369145 -60.114221) (xy 233.39672 -60.030653) (xy 233.431779 -59.949939) (xy 233.474032 -59.872747)
			(xy 233.52313 -59.799718) (xy 233.578666 -59.731456) (xy 233.640178 -59.668526) (xy 233.707159 -59.611452)
			(xy 233.779052 -59.560704) (xy 233.855261 -59.516704) (xy 233.935156 -59.479817) (xy 234.018075 -59.450348)
			(xy 234.10333 -59.428541) (xy 234.190214 -59.414577) (xy 234.278008 -59.408571) (xy 234.365985 -59.410575)
			(xy 234.453415 -59.42057) (xy 234.539574 -59.438474) (xy 234.623748 -59.464138) (xy 234.705239 -59.497351)
			(xy 234.783373 -59.537837) (xy 234.857501 -59.585259) (xy 234.927009 -59.639226) (xy 234.991323 -59.699291)
			(xy 235.049907 -59.764955) (xy 235.102278 -59.835674) (xy 235.148001 -59.910862) (xy 235.186698 -59.989897)
			(xy 235.218047 -60.072123) (xy 235.241789 -60.156859) (xy 235.257727 -60.243403) (xy 235.265729 -60.331038)
			(xy 235.26623 -60.375038) (xy 235.265729 -60.419038) (xy 235.257727 -60.506673) (xy 235.241789 -60.593217)
			(xy 235.218047 -60.677953) (xy 235.186698 -60.760179) (xy 235.148001 -60.839214) (xy 235.102278 -60.914402)
			(xy 235.049907 -60.985121) (xy 234.991323 -61.050785) (xy 234.927009 -61.11085) (xy 234.857501 -61.164817)
			(xy 234.783373 -61.212239) (xy 234.705239 -61.252725) (xy 234.623748 -61.285938) (xy 234.539574 -61.311602)
			(xy 234.453415 -61.329506) (xy 234.365985 -61.339501) (xy 234.278008 -61.341505) (xy 234.190214 -61.335499)
			(xy 234.10333 -61.321535) (xy 234.018075 -61.299728) (xy 233.935156 -61.270259) (xy 233.855261 -61.233372)
			(xy 233.779052 -61.189372) (xy 233.707159 -61.138624) (xy 233.640178 -61.08155) (xy 233.578666 -61.01862)
			(xy 233.52313 -60.950358) (xy 233.474032 -60.877329) (xy 233.431779 -60.800137) (xy 233.39672 -60.719423)
			(xy 233.369145 -60.635855) (xy 233.349285 -60.550126) (xy 233.337302 -60.462946) (xy 233.333297 -60.375038)
			(xy 18.73545 -60.375038) (xy 18.696652 -60.451627) (xy 18.650849 -60.524252) (xy 18.598446 -60.592269)
			(xy 18.539905 -60.65508) (xy 18.475738 -60.712133) (xy 18.406512 -60.762927) (xy 18.332833 -60.807015)
			(xy 18.255349 -60.84401) (xy 18.174741 -60.873587) (xy 18.091718 -60.895486) (xy 18.00701 -60.909514)
			(xy 17.92136 -60.915548) (xy 17.835521 -60.913535) (xy 17.750247 -60.903493) (xy 17.666289 -60.88551)
			(xy 17.584384 -60.859744) (xy 17.505251 -60.826421) (xy 17.429587 -60.785835) (xy 17.358055 -60.738342)
			(xy 17.291286 -60.684359) (xy 17.229864 -60.624361) (xy 17.174331 -60.558875) (xy 17.125174 -60.488477)
			(xy 17.082825 -60.413784) (xy 17.047657 -60.335455) (xy 17.019978 -60.254176) (xy 17.000031 -60.170662)
			(xy 16.987993 -60.085648) (xy 16.983969 -59.99988) (xy 0.509016 -59.99988) (xy 0.509016 -74.760836)
			(xy 39.554404 -74.760836) (xy 39.554404 -66.060828) (xy 39.554909 -65.955304) (xy 39.562993 -65.74441)
			(xy 39.579149 -65.533981) (xy 39.603352 -65.324324) (xy 39.635569 -65.115749) (xy 39.675751 -64.908561)
			(xy 39.723839 -64.703064) (xy 39.779763 -64.49956) (xy 39.84344 -64.298347) (xy 39.914778 -64.09972)
			(xy 39.993672 -63.903972) (xy 40.080005 -63.71139) (xy 40.173652 -63.522255) (xy 40.274474 -63.336846)
			(xy 40.382324 -63.155435) (xy 40.497043 -62.978288) (xy 40.618463 -62.805666) (xy 40.746406 -62.63782)
			(xy 40.880684 -62.474998) (xy 41.0211 -62.317439) (xy 41.167448 -62.165374) (xy 41.319513 -62.019026)
			(xy 41.477072 -61.87861) (xy 41.639894 -61.744332) (xy 41.80774 -61.616389) (xy 41.980362 -61.494969)
			(xy 42.157509 -61.38025) (xy 42.33892 -61.2724) (xy 42.524329 -61.171578) (xy 42.713464 -61.077931)
			(xy 42.906046 -60.991598) (xy 43.101794 -60.912704) (xy 43.300421 -60.841366) (xy 43.501634 -60.777689)
			(xy 43.705138 -60.721765) (xy 43.910635 -60.673677) (xy 44.117823 -60.633495) (xy 44.326398 -60.601278)
			(xy 44.536055 -60.577075) (xy 44.746484 -60.560919) (xy 44.957378 -60.552835) (xy 45.168426 -60.552835)
			(xy 45.37932 -60.560919) (xy 45.589749 -60.577075) (xy 45.799406 -60.601278) (xy 46.007981 -60.633495)
			(xy 46.215169 -60.673677) (xy 46.420666 -60.721765) (xy 46.62417 -60.777689) (xy 46.825383 -60.841366)
			(xy 47.02401 -60.912704) (xy 47.219758 -60.991598) (xy 47.41234 -61.077931) (xy 47.601475 -61.171578)
			(xy 47.786884 -61.2724) (xy 47.968295 -61.38025) (xy 48.145442 -61.494969) (xy 48.318064 -61.616389)
			(xy 48.48591 -61.744332) (xy 48.648732 -61.87861) (xy 48.806291 -62.019026) (xy 48.958356 -62.165374)
			(xy 49.104704 -62.317439) (xy 49.24512 -62.474998) (xy 49.379398 -62.63782) (xy 49.507341 -62.805666)
			(xy 49.628761 -62.978288) (xy 49.74348 -63.155435) (xy 49.85133 -63.336846) (xy 49.952152 -63.522255)
			(xy 50.045799 -63.71139) (xy 50.132132 -63.903972) (xy 50.211026 -64.09972) (xy 50.282364 -64.298347)
			(xy 50.346041 -64.49956) (xy 50.401965 -64.703064) (xy 50.450053 -64.908561) (xy 50.490235 -65.115749)
			(xy 50.522452 -65.324324) (xy 50.546655 -65.533981) (xy 50.562811 -65.74441) (xy 50.570895 -65.955304)
			(xy 50.5714 -66.060828) (xy 50.5714 -74.760836) (xy 50.571366 -74.767948) (xy 173.354492 -74.767948)
			(xy 173.354492 -66.06794) (xy 173.354997 -65.962416) (xy 173.363081 -65.751522) (xy 173.379237 -65.541093)
			(xy 173.40344 -65.331436) (xy 173.435657 -65.122861) (xy 173.475839 -64.915673) (xy 173.523927 -64.710176)
			(xy 173.579851 -64.506672) (xy 173.643528 -64.305459) (xy 173.714866 -64.106832) (xy 173.79376 -63.911084)
			(xy 173.880093 -63.718502) (xy 173.97374 -63.529367) (xy 174.074562 -63.343958) (xy 174.182412 -63.162547)
			(xy 174.297131 -62.9854) (xy 174.418551 -62.812778) (xy 174.546494 -62.644932) (xy 174.680772 -62.48211)
			(xy 174.821188 -62.324551) (xy 174.967536 -62.172486) (xy 175.119601 -62.026138) (xy 175.27716 -61.885722)
			(xy 175.439982 -61.751444) (xy 175.607828 -61.623501) (xy 175.78045 -61.502081) (xy 175.957597 -61.387362)
			(xy 176.139008 -61.279512) (xy 176.324417 -61.17869) (xy 176.513552 -61.085043) (xy 176.706134 -60.99871)
			(xy 176.901882 -60.919816) (xy 177.100509 -60.848478) (xy 177.301722 -60.784801) (xy 177.505226 -60.728877)
			(xy 177.710723 -60.680789) (xy 177.917911 -60.640607) (xy 178.126486 -60.60839) (xy 178.336143 -60.584187)
			(xy 178.546572 -60.568031) (xy 178.757466 -60.559947) (xy 178.968514 -60.559947) (xy 179.179408 -60.568031)
			(xy 179.389837 -60.584187) (xy 179.599494 -60.60839) (xy 179.808069 -60.640607) (xy 180.015257 -60.680789)
			(xy 180.220754 -60.728877) (xy 180.424258 -60.784801) (xy 180.625471 -60.848478) (xy 180.824098 -60.919816)
			(xy 181.019846 -60.99871) (xy 181.212428 -61.085043) (xy 181.401563 -61.17869) (xy 181.586972 -61.279512)
			(xy 181.768383 -61.387362) (xy 181.94553 -61.502081) (xy 182.118152 -61.623501) (xy 182.285998 -61.751444)
			(xy 182.44882 -61.885722) (xy 182.606379 -62.026138) (xy 182.758444 -62.172486) (xy 182.904792 -62.324551)
			(xy 183.045208 -62.48211) (xy 183.179486 -62.644932) (xy 183.307429 -62.812778) (xy 183.428849 -62.9854)
			(xy 183.543568 -63.162547) (xy 183.651418 -63.343958) (xy 183.75224 -63.529367) (xy 183.845887 -63.718502)
			(xy 183.93222 -63.911084) (xy 184.011114 -64.106832) (xy 184.082452 -64.305459) (xy 184.146129 -64.506672)
			(xy 184.202053 -64.710176) (xy 184.250141 -64.915673) (xy 184.290323 -65.122861) (xy 184.32254 -65.331436)
			(xy 184.346743 -65.541093) (xy 184.362899 -65.751522) (xy 184.370983 -65.962416) (xy 184.371488 -66.06794)
			(xy 184.371488 -74.760836) (xy 287.494472 -74.760836) (xy 287.494472 -66.060828) (xy 287.494977 -65.955304)
			(xy 287.503061 -65.74441) (xy 287.519217 -65.533981) (xy 287.54342 -65.324324) (xy 287.575637 -65.115749)
			(xy 287.615819 -64.908561) (xy 287.663907 -64.703064) (xy 287.719831 -64.49956) (xy 287.783508 -64.298347)
			(xy 287.854846 -64.09972) (xy 287.93374 -63.903972) (xy 288.020073 -63.71139) (xy 288.11372 -63.522255)
			(xy 288.214542 -63.336846) (xy 288.322392 -63.155435) (xy 288.437111 -62.978288) (xy 288.558531 -62.805666)
			(xy 288.686474 -62.63782) (xy 288.820752 -62.474998) (xy 288.961168 -62.317439) (xy 289.107516 -62.165374)
			(xy 289.259581 -62.019026) (xy 289.41714 -61.87861) (xy 289.579962 -61.744332) (xy 289.747808 -61.616389)
			(xy 289.92043 -61.494969) (xy 290.097577 -61.38025) (xy 290.278988 -61.2724) (xy 290.464397 -61.171578)
			(xy 290.653532 -61.077931) (xy 290.846114 -60.991598) (xy 291.041862 -60.912704) (xy 291.240489 -60.841366)
			(xy 291.441702 -60.777689) (xy 291.645206 -60.721765) (xy 291.850703 -60.673677) (xy 292.057891 -60.633495)
			(xy 292.266466 -60.601278) (xy 292.476123 -60.577075) (xy 292.686552 -60.560919) (xy 292.897446 -60.552835)
			(xy 293.108494 -60.552835) (xy 293.319388 -60.560919) (xy 293.529817 -60.577075) (xy 293.739474 -60.601278)
			(xy 293.948049 -60.633495) (xy 294.155237 -60.673677) (xy 294.360734 -60.721765) (xy 294.564238 -60.777689)
			(xy 294.765451 -60.841366) (xy 294.964078 -60.912704) (xy 295.159826 -60.991598) (xy 295.352408 -61.077931)
			(xy 295.541543 -61.171578) (xy 295.726952 -61.2724) (xy 295.908363 -61.38025) (xy 296.063868 -61.480954)
			(xy 351.822512 -61.480954) (xy 351.822512 -60.617354) (xy 351.822998 -60.590103) (xy 351.830754 -60.536155)
			(xy 351.846109 -60.48386) (xy 351.868751 -60.434283) (xy 351.898217 -60.388433) (xy 351.933908 -60.347242)
			(xy 351.975099 -60.311551) (xy 352.020949 -60.282085) (xy 352.070526 -60.259443) (xy 352.122821 -60.244088)
			(xy 352.176769 -60.236332) (xy 352.231271 -60.236332) (xy 352.285219 -60.244088) (xy 352.337514 -60.259443)
			(xy 352.387091 -60.282085) (xy 352.432941 -60.311551) (xy 352.474132 -60.347242) (xy 352.509823 -60.388433)
			(xy 352.539289 -60.434283) (xy 352.561931 -60.48386) (xy 352.577286 -60.536155) (xy 352.585042 -60.590103)
			(xy 352.585528 -60.617354) (xy 352.585528 -61.223271) (xy 355.46889 -61.223271) (xy 355.46889 -61.168729)
			(xy 355.476653 -61.114741) (xy 355.492019 -61.062408) (xy 355.514676 -61.012794) (xy 355.544164 -60.966909)
			(xy 355.579881 -60.925688) (xy 355.621101 -60.88997) (xy 355.666985 -60.860481) (xy 355.716598 -60.837822)
			(xy 355.768931 -60.822455) (xy 355.822919 -60.814691) (xy 355.85019 -60.814204) (xy 356.71379 -60.814204)
			(xy 356.741059 -60.814735) (xy 356.795042 -60.822495) (xy 356.847371 -60.837859) (xy 356.896981 -60.860514)
			(xy 356.942862 -60.889999) (xy 356.98408 -60.925713) (xy 357.019795 -60.96693) (xy 357.049281 -61.01281)
			(xy 357.071937 -61.062419) (xy 357.087303 -61.114748) (xy 357.095065 -61.168731) (xy 357.095065 -61.223269)
			(xy 357.087303 -61.277252) (xy 357.071937 -61.329581) (xy 357.049281 -61.37919) (xy 357.019795 -61.42507)
			(xy 356.98408 -61.466287) (xy 356.942862 -61.502001) (xy 356.896981 -61.531486) (xy 356.847371 -61.554141)
			(xy 356.795042 -61.569505) (xy 356.741059 -61.577265) (xy 356.71379 -61.577728) (xy 355.85019 -61.577728)
			(xy 355.822919 -61.577309) (xy 355.768931 -61.569545) (xy 355.716598 -61.554178) (xy 355.666985 -61.531519)
			(xy 355.621101 -61.50203) (xy 355.579881 -61.466312) (xy 355.544164 -61.425091) (xy 355.514676 -61.379206)
			(xy 355.492019 -61.329592) (xy 355.476653 -61.277259) (xy 355.46889 -61.223271) (xy 352.585528 -61.223271)
			(xy 352.585528 -61.480954) (xy 352.585042 -61.508205) (xy 352.577286 -61.562153) (xy 352.561931 -61.614448)
			(xy 352.539289 -61.664025) (xy 352.509823 -61.709875) (xy 352.474132 -61.751066) (xy 352.432941 -61.786757)
			(xy 352.387091 -61.816223) (xy 352.337514 -61.838865) (xy 352.285219 -61.85422) (xy 352.231271 -61.861976)
			(xy 352.176769 -61.861976) (xy 352.122821 -61.85422) (xy 352.070526 -61.838865) (xy 352.020949 -61.816223)
			(xy 351.975099 -61.786757) (xy 351.933908 -61.751066) (xy 351.898217 -61.709875) (xy 351.868751 -61.664025)
			(xy 351.846109 -61.614448) (xy 351.830754 -61.562153) (xy 351.822998 -61.508205) (xy 351.822512 -61.480954)
			(xy 296.063868 -61.480954) (xy 296.08551 -61.494969) (xy 296.258132 -61.616389) (xy 296.425978 -61.744332)
			(xy 296.5888 -61.87861) (xy 296.746359 -62.019026) (xy 296.898424 -62.165374) (xy 297.044772 -62.317439)
			(xy 297.185188 -62.474998) (xy 297.319466 -62.63782) (xy 297.447409 -62.805666) (xy 297.568829 -62.978288)
			(xy 297.683548 -63.155435) (xy 297.751584 -63.269876) (xy 350.300544 -63.269876) (xy 350.300544 -62.406276)
			(xy 350.30103 -62.379025) (xy 350.308786 -62.325077) (xy 350.324141 -62.272782) (xy 350.346783 -62.223205)
			(xy 350.376249 -62.177355) (xy 350.41194 -62.136164) (xy 350.453131 -62.100473) (xy 350.498981 -62.071007)
			(xy 350.548558 -62.048365) (xy 350.600853 -62.03301) (xy 350.654801 -62.025254) (xy 350.709303 -62.025254)
			(xy 350.763251 -62.03301) (xy 350.815546 -62.048365) (xy 350.865123 -62.071007) (xy 350.910973 -62.100473)
			(xy 350.952164 -62.136164) (xy 350.987855 -62.177355) (xy 351.017321 -62.223205) (xy 351.039963 -62.272782)
			(xy 351.055318 -62.325077) (xy 351.063074 -62.379025) (xy 351.06356 -62.406276) (xy 351.06356 -63.269876)
			(xy 351.063074 -63.297127) (xy 351.055318 -63.351075) (xy 351.039963 -63.40337) (xy 351.017321 -63.452947)
			(xy 350.987855 -63.498797) (xy 350.952164 -63.539988) (xy 350.910973 -63.575679) (xy 350.865123 -63.605145)
			(xy 350.815546 -63.627787) (xy 350.763251 -63.643142) (xy 350.709303 -63.650898) (xy 350.654801 -63.650898)
			(xy 350.600853 -63.643142) (xy 350.548558 -63.627787) (xy 350.498981 -63.605145) (xy 350.453131 -63.575679)
			(xy 350.41194 -63.539988) (xy 350.376249 -63.498797) (xy 350.346783 -63.452947) (xy 350.324141 -63.40337)
			(xy 350.308786 -63.351075) (xy 350.30103 -63.297127) (xy 350.300544 -63.269876) (xy 297.751584 -63.269876)
			(xy 297.791398 -63.336846) (xy 297.89222 -63.522255) (xy 297.985867 -63.71139) (xy 298.0722 -63.903972)
			(xy 298.151094 -64.09972) (xy 298.222432 -64.298347) (xy 298.286109 -64.49956) (xy 298.342033 -64.703064)
			(xy 298.390121 -64.908561) (xy 298.396302 -64.940434) (xy 325.410068 -64.940434) (xy 325.410068 -64.076834)
			(xy 325.410554 -64.049565) (xy 325.418316 -63.995581) (xy 325.433681 -63.943251) (xy 325.456338 -63.893641)
			(xy 325.485824 -63.84776) (xy 325.521539 -63.806543) (xy 325.562756 -63.770828) (xy 325.608637 -63.741342)
			(xy 325.658247 -63.718685) (xy 325.710577 -63.70332) (xy 325.764561 -63.695558) (xy 325.819099 -63.695558)
			(xy 325.873083 -63.70332) (xy 325.925413 -63.718685) (xy 325.975023 -63.741342) (xy 326.020904 -63.770828)
			(xy 326.062121 -63.806543) (xy 326.097836 -63.84776) (xy 326.127322 -63.893641) (xy 326.149979 -63.943251)
			(xy 326.165344 -63.995581) (xy 326.173106 -64.049565) (xy 326.173592 -64.076834) (xy 326.173592 -64.940434)
			(xy 326.173106 -64.967703) (xy 326.165344 -65.021687) (xy 326.149979 -65.074017) (xy 326.127322 -65.123627)
			(xy 326.097836 -65.169508) (xy 326.062121 -65.210725) (xy 326.020904 -65.24644) (xy 325.975023 -65.275926)
			(xy 325.925413 -65.298583) (xy 325.873083 -65.313948) (xy 325.819099 -65.32171) (xy 325.764561 -65.32171)
			(xy 325.710577 -65.313948) (xy 325.658247 -65.298583) (xy 325.608637 -65.275926) (xy 325.562756 -65.24644)
			(xy 325.521539 -65.210725) (xy 325.485824 -65.169508) (xy 325.456338 -65.123627) (xy 325.433681 -65.074017)
			(xy 325.418316 -65.021687) (xy 325.410554 -64.967703) (xy 325.410068 -64.940434) (xy 298.396302 -64.940434)
			(xy 298.430303 -65.115749) (xy 298.46252 -65.324324) (xy 298.463125 -65.329562) (xy 352.362008 -65.329562)
			(xy 352.362008 -64.465962) (xy 352.362494 -64.438711) (xy 352.37025 -64.384763) (xy 352.385605 -64.332468)
			(xy 352.408247 -64.282891) (xy 352.437713 -64.237041) (xy 352.473404 -64.19585) (xy 352.514595 -64.160159)
			(xy 352.560445 -64.130693) (xy 352.610022 -64.108051) (xy 352.662317 -64.092696) (xy 352.716265 -64.08494)
			(xy 352.770767 -64.08494) (xy 352.824715 -64.092696) (xy 352.87701 -64.108051) (xy 352.926587 -64.130693)
			(xy 352.972437 -64.160159) (xy 353.013628 -64.19585) (xy 353.049319 -64.237041) (xy 353.078785 -64.282891)
			(xy 353.101427 -64.332468) (xy 353.116782 -64.384763) (xy 353.124538 -64.438711) (xy 353.125024 -64.465962)
			(xy 353.125024 -65.329562) (xy 353.124538 -65.356813) (xy 353.116782 -65.410761) (xy 353.101427 -65.463056)
			(xy 353.078785 -65.512633) (xy 353.049319 -65.558483) (xy 353.013628 -65.599674) (xy 352.972437 -65.635365)
			(xy 352.926587 -65.664831) (xy 352.87701 -65.687473) (xy 352.824715 -65.702828) (xy 352.770767 -65.710584)
			(xy 352.716265 -65.710584) (xy 352.662317 -65.702828) (xy 352.610022 -65.687473) (xy 352.560445 -65.664831)
			(xy 352.514595 -65.635365) (xy 352.473404 -65.599674) (xy 352.437713 -65.558483) (xy 352.408247 -65.512633)
			(xy 352.385605 -65.463056) (xy 352.37025 -65.410761) (xy 352.362494 -65.356813) (xy 352.362008 -65.329562)
			(xy 298.463125 -65.329562) (xy 298.486723 -65.533981) (xy 298.502879 -65.74441) (xy 298.510963 -65.955304)
			(xy 298.511468 -66.060828) (xy 298.511468 -68.449952) (xy 314.840884 -68.449952) (xy 314.844867 -68.321934)
			(xy 314.856802 -68.194412) (xy 314.876641 -68.067878) (xy 314.904308 -67.942822) (xy 314.939697 -67.819729)
			(xy 314.98267 -67.699073) (xy 315.033061 -67.581323) (xy 315.090675 -67.466933) (xy 315.155289 -67.356346)
			(xy 315.226653 -67.24999) (xy 315.304491 -67.148277) (xy 315.388502 -67.051599) (xy 315.478361 -66.960332)
			(xy 315.57372 -66.874827) (xy 315.674211 -66.795417) (xy 315.779444 -66.722407) (xy 315.889013 -66.656081)
			(xy 316.002493 -66.596695) (xy 316.119445 -66.544479) (xy 316.239418 -66.499635) (xy 316.361946 -66.462337)
			(xy 316.486557 -66.432728) (xy 316.612766 -66.410923) (xy 316.740088 -66.397007) (xy 316.868028 -66.391033)
			(xy 316.996092 -66.393025) (xy 317.123785 -66.402975) (xy 317.250612 -66.420844) (xy 317.376083 -66.446563)
			(xy 317.499712 -66.480033) (xy 317.621021 -66.521124) (xy 317.739541 -66.569678) (xy 317.854813 -66.625506)
			(xy 317.966391 -66.688392) (xy 318.073844 -66.758094) (xy 318.176756 -66.834341) (xy 318.274728 -66.916838)
			(xy 318.323666 -66.963544) (xy 350.27108 -66.963544) (xy 350.27108 -66.099944) (xy 350.271566 -66.072693)
			(xy 350.279322 -66.018745) (xy 350.294677 -65.96645) (xy 350.317319 -65.916873) (xy 350.346785 -65.871023)
			(xy 350.382476 -65.829832) (xy 350.423667 -65.794141) (xy 350.469517 -65.764675) (xy 350.519094 -65.742033)
			(xy 350.571389 -65.726678) (xy 350.625337 -65.718922) (xy 350.679839 -65.718922) (xy 350.733787 -65.726678)
			(xy 350.786082 -65.742033) (xy 350.835659 -65.764675) (xy 350.881509 -65.794141) (xy 350.9227 -65.829832)
			(xy 350.958391 -65.871023) (xy 350.987857 -65.916873) (xy 351.010499 -65.96645) (xy 351.025854 -66.018745)
			(xy 351.03361 -66.072693) (xy 351.034096 -66.099944) (xy 351.034096 -66.963544) (xy 351.03361 -66.990795)
			(xy 351.025854 -67.044743) (xy 351.010499 -67.097038) (xy 351.005595 -67.107776) (xy 396.642323 -67.107776)
			(xy 396.642323 -67.022004) (xy 396.650237 -66.936596) (xy 396.665998 -66.852284) (xy 396.689471 -66.769785)
			(xy 396.720456 -66.689804) (xy 396.758688 -66.613023) (xy 396.803842 -66.540098) (xy 396.855532 -66.47165)
			(xy 396.913317 -66.408263) (xy 396.976704 -66.350478) (xy 397.045152 -66.298788) (xy 397.118077 -66.253634)
			(xy 397.194858 -66.215402) (xy 397.274839 -66.184417) (xy 397.357338 -66.160944) (xy 397.44165 -66.145183)
			(xy 397.527058 -66.137269) (xy 397.61283 -66.137269) (xy 397.698238 -66.145183) (xy 397.78255 -66.160944)
			(xy 397.865049 -66.184417) (xy 397.94503 -66.215402) (xy 398.021811 -66.253634) (xy 398.094736 -66.298788)
			(xy 398.163184 -66.350478) (xy 398.226571 -66.408263) (xy 398.284356 -66.47165) (xy 398.336046 -66.540098)
			(xy 398.3812 -66.613023) (xy 398.419432 -66.689804) (xy 398.450417 -66.769785) (xy 398.47389 -66.852284)
			(xy 398.489651 -66.936596) (xy 398.497565 -67.022004) (xy 398.49806 -67.06489) (xy 398.497565 -67.107776)
			(xy 398.489651 -67.193184) (xy 398.47389 -67.277496) (xy 398.450417 -67.359995) (xy 398.419432 -67.439976)
			(xy 398.3812 -67.516757) (xy 398.336046 -67.589682) (xy 398.284356 -67.65813) (xy 398.226571 -67.721517)
			(xy 398.163184 -67.779302) (xy 398.094736 -67.830992) (xy 398.021811 -67.876146) (xy 397.94503 -67.914378)
			(xy 397.865049 -67.945363) (xy 397.78255 -67.968836) (xy 397.698238 -67.984597) (xy 397.61283 -67.992511)
			(xy 397.527058 -67.992511) (xy 397.44165 -67.984597) (xy 397.357338 -67.968836) (xy 397.274839 -67.945363)
			(xy 397.194858 -67.914378) (xy 397.118077 -67.876146) (xy 397.045152 -67.830992) (xy 396.976704 -67.779302)
			(xy 396.913317 -67.721517) (xy 396.855532 -67.65813) (xy 396.803842 -67.589682) (xy 396.758688 -67.516757)
			(xy 396.720456 -67.439976) (xy 396.689471 -67.359995) (xy 396.665998 -67.277496) (xy 396.650237 -67.193184)
			(xy 396.642323 -67.107776) (xy 351.005595 -67.107776) (xy 350.987857 -67.146615) (xy 350.958391 -67.192465)
			(xy 350.9227 -67.233656) (xy 350.881509 -67.269347) (xy 350.835659 -67.298813) (xy 350.786082 -67.321455)
			(xy 350.733787 -67.33681) (xy 350.679839 -67.344566) (xy 350.625337 -67.344566) (xy 350.571389 -67.33681)
			(xy 350.519094 -67.321455) (xy 350.469517 -67.298813) (xy 350.423667 -67.269347) (xy 350.382476 -67.233656)
			(xy 350.346785 -67.192465) (xy 350.317319 -67.146615) (xy 350.294677 -67.097038) (xy 350.279322 -67.044743)
			(xy 350.271566 -66.990795) (xy 350.27108 -66.963544) (xy 318.323666 -66.963544) (xy 318.367382 -67.005267)
			(xy 318.454359 -67.099285) (xy 318.535323 -67.198528) (xy 318.60996 -67.302613) (xy 318.677982 -67.411137)
			(xy 318.739126 -67.52368) (xy 318.793154 -67.639806) (xy 318.839859 -67.759067) (xy 318.879059 -67.881)
			(xy 318.910602 -68.005135) (xy 318.934367 -68.130991) (xy 318.950261 -68.25808) (xy 318.958224 -68.385912)
			(xy 318.958722 -68.449952) (xy 318.958224 -68.513992) (xy 318.950261 -68.641824) (xy 318.934367 -68.768913)
			(xy 318.910602 -68.894769) (xy 318.879059 -69.018904) (xy 318.851129 -69.10578) (xy 351.73158 -69.10578)
			(xy 351.73158 -68.24218) (xy 351.732066 -68.214911) (xy 351.739828 -68.160927) (xy 351.755193 -68.108597)
			(xy 351.77785 -68.058987) (xy 351.807336 -68.013106) (xy 351.843051 -67.971889) (xy 351.884268 -67.936174)
			(xy 351.930149 -67.906688) (xy 351.979759 -67.884031) (xy 352.032089 -67.868666) (xy 352.086073 -67.860904)
			(xy 352.140611 -67.860904) (xy 352.194595 -67.868666) (xy 352.246925 -67.884031) (xy 352.296535 -67.906688)
			(xy 352.342416 -67.936174) (xy 352.383633 -67.971889) (xy 352.419348 -68.013106) (xy 352.448834 -68.058987)
			(xy 352.471491 -68.108597) (xy 352.486856 -68.160927) (xy 352.494618 -68.214911) (xy 352.495104 -68.24218)
			(xy 352.495104 -69.10578) (xy 352.494618 -69.133049) (xy 352.486856 -69.187033) (xy 352.471491 -69.239363)
			(xy 352.448834 -69.288973) (xy 352.419348 -69.334854) (xy 352.383633 -69.376071) (xy 352.342416 -69.411786)
			(xy 352.296535 -69.441272) (xy 352.246925 -69.463929) (xy 352.194595 -69.479294) (xy 352.140611 -69.487056)
			(xy 352.086073 -69.487056) (xy 352.032089 -69.479294) (xy 351.979759 -69.463929) (xy 351.930149 -69.441272)
			(xy 351.884268 -69.411786) (xy 351.843051 -69.376071) (xy 351.807336 -69.334854) (xy 351.77785 -69.288973)
			(xy 351.755193 -69.239363) (xy 351.739828 -69.187033) (xy 351.732066 -69.133049) (xy 351.73158 -69.10578)
			(xy 318.851129 -69.10578) (xy 318.839859 -69.140837) (xy 318.793154 -69.260098) (xy 318.739126 -69.376224)
			(xy 318.677982 -69.488767) (xy 318.60996 -69.597291) (xy 318.535323 -69.701376) (xy 318.454359 -69.800619)
			(xy 318.367382 -69.894637) (xy 318.274728 -69.983066) (xy 318.176756 -70.065563) (xy 318.073844 -70.14181)
			(xy 317.966391 -70.211512) (xy 317.854813 -70.274398) (xy 317.739541 -70.330226) (xy 317.621021 -70.37878)
			(xy 317.499712 -70.419871) (xy 317.376083 -70.453341) (xy 317.250612 -70.47906) (xy 317.123785 -70.496929)
			(xy 316.996092 -70.506879) (xy 316.868028 -70.508871) (xy 316.740088 -70.502897) (xy 316.612766 -70.488981)
			(xy 316.486557 -70.467176) (xy 316.361946 -70.437567) (xy 316.239418 -70.400269) (xy 316.119445 -70.355425)
			(xy 316.002493 -70.303209) (xy 315.889013 -70.243823) (xy 315.779444 -70.177497) (xy 315.674211 -70.104487)
			(xy 315.57372 -70.025077) (xy 315.478361 -69.939572) (xy 315.388502 -69.848305) (xy 315.304491 -69.751627)
			(xy 315.226653 -69.649914) (xy 315.155289 -69.543558) (xy 315.090675 -69.432971) (xy 315.033061 -69.318581)
			(xy 314.98267 -69.200831) (xy 314.939697 -69.080175) (xy 314.904308 -68.957082) (xy 314.876641 -68.832026)
			(xy 314.856802 -68.705492) (xy 314.844867 -68.57797) (xy 314.840884 -68.449952) (xy 298.511468 -68.449952)
			(xy 298.511468 -71.213074) (xy 341.168388 -71.213074) (xy 341.168388 -71.158526) (xy 341.176151 -71.104534)
			(xy 341.19152 -71.052197) (xy 341.214181 -71.00258) (xy 341.243673 -70.956692) (xy 341.279395 -70.91547)
			(xy 341.320621 -70.879751) (xy 341.366511 -70.850263) (xy 341.416131 -70.827607) (xy 341.46847 -70.812243)
			(xy 341.522462 -70.804485) (xy 341.549736 -70.804024) (xy 342.413336 -70.804024) (xy 342.440603 -70.804541)
			(xy 342.49458 -70.812306) (xy 342.546904 -70.827674) (xy 342.596508 -70.850332) (xy 342.642382 -70.879817)
			(xy 342.683594 -70.915531) (xy 342.719304 -70.956747) (xy 342.748786 -71.002624) (xy 342.771438 -71.05223)
			(xy 342.786801 -71.104555) (xy 342.794562 -71.158533) (xy 342.794562 -71.213067) (xy 342.786801 -71.267045)
			(xy 342.771438 -71.31937) (xy 342.748786 -71.368976) (xy 342.719304 -71.414853) (xy 342.683594 -71.456069)
			(xy 342.642382 -71.491783) (xy 342.596508 -71.521268) (xy 342.546904 -71.543926) (xy 342.49458 -71.559294)
			(xy 342.440603 -71.567059) (xy 342.413336 -71.567548) (xy 341.549736 -71.567548) (xy 341.522462 -71.567115)
			(xy 341.46847 -71.559357) (xy 341.416131 -71.543993) (xy 341.366511 -71.521337) (xy 341.320621 -71.491849)
			(xy 341.279395 -71.45613) (xy 341.243673 -71.414908) (xy 341.214181 -71.36902) (xy 341.19152 -71.319403)
			(xy 341.176151 -71.267066) (xy 341.168388 -71.213074) (xy 298.511468 -71.213074) (xy 298.511468 -71.844253)
			(xy 346.360454 -71.844253) (xy 346.360454 -71.789747) (xy 346.368211 -71.735796) (xy 346.383567 -71.683499)
			(xy 346.406209 -71.633919) (xy 346.435677 -71.588066) (xy 346.47137 -71.546873) (xy 346.512562 -71.511179)
			(xy 346.558415 -71.481711) (xy 346.607995 -71.459068) (xy 346.660293 -71.443712) (xy 346.714243 -71.435954)
			(xy 346.741496 -71.435468) (xy 347.605096 -71.435468) (xy 347.632347 -71.435979) (xy 347.686295 -71.443735)
			(xy 347.73859 -71.45909) (xy 347.788168 -71.481731) (xy 347.834019 -71.511197) (xy 347.875209 -71.546888)
			(xy 347.910901 -71.588078) (xy 347.940367 -71.633929) (xy 347.963009 -71.683506) (xy 347.978364 -71.735801)
			(xy 347.986121 -71.789749) (xy 347.986121 -71.844251) (xy 347.978364 -71.898199) (xy 347.963009 -71.950494)
			(xy 347.940367 -72.000071) (xy 347.910901 -72.045922) (xy 347.875209 -72.087112) (xy 347.834019 -72.122803)
			(xy 347.788168 -72.152269) (xy 347.73859 -72.17491) (xy 347.686295 -72.190265) (xy 347.632347 -72.198021)
			(xy 347.605096 -72.198484) (xy 346.741496 -72.198484) (xy 346.714243 -72.198046) (xy 346.660293 -72.190288)
			(xy 346.607995 -72.174932) (xy 346.558415 -72.152289) (xy 346.512562 -72.122821) (xy 346.47137 -72.087127)
			(xy 346.435677 -72.045934) (xy 346.406209 -72.000081) (xy 346.383567 -71.950501) (xy 346.368211 -71.898204)
			(xy 346.360454 -71.844253) (xy 298.511468 -71.844253) (xy 298.511468 -72.404055) (xy 332.037847 -72.404055)
			(xy 332.037847 -72.349545) (xy 332.045606 -72.295589) (xy 332.060964 -72.243286) (xy 332.083611 -72.193702)
			(xy 332.113083 -72.147846) (xy 332.148782 -72.106651) (xy 332.189981 -72.070957) (xy 332.235841 -72.041489)
			(xy 332.285427 -72.018849) (xy 332.337732 -72.003496) (xy 332.391689 -71.995744) (xy 332.418944 -71.995284)
			(xy 333.282544 -71.995284) (xy 333.309793 -71.995789) (xy 333.363734 -72.00355) (xy 333.416023 -72.018909)
			(xy 333.465593 -72.041552) (xy 333.511437 -72.071019) (xy 333.552622 -72.10671) (xy 333.588308 -72.147898)
			(xy 333.617769 -72.193745) (xy 333.640407 -72.243318) (xy 333.655759 -72.295609) (xy 333.660251 -72.326853)
			(xy 343.845854 -72.326853) (xy 343.845854 -72.272347) (xy 343.853611 -72.218396) (xy 343.868967 -72.166099)
			(xy 343.891609 -72.116519) (xy 343.921077 -72.070666) (xy 343.95677 -72.029473) (xy 343.997962 -71.993779)
			(xy 344.043815 -71.964311) (xy 344.093395 -71.941668) (xy 344.145693 -71.926312) (xy 344.199643 -71.918554)
			(xy 344.226896 -71.918068) (xy 345.090496 -71.918068) (xy 345.117747 -71.918579) (xy 345.171695 -71.926335)
			(xy 345.22399 -71.94169) (xy 345.273568 -71.964331) (xy 345.319419 -71.993797) (xy 345.360609 -72.029488)
			(xy 345.396301 -72.070678) (xy 345.425767 -72.116529) (xy 345.448409 -72.166106) (xy 345.463764 -72.218401)
			(xy 345.471521 -72.272349) (xy 345.471521 -72.326851) (xy 345.463764 -72.380799) (xy 345.448409 -72.433094)
			(xy 345.425767 -72.482671) (xy 345.396301 -72.528522) (xy 345.360609 -72.569712) (xy 345.319419 -72.605403)
			(xy 345.273568 -72.634869) (xy 345.22399 -72.65751) (xy 345.171695 -72.672865) (xy 345.117747 -72.680621)
			(xy 345.090496 -72.681084) (xy 344.226896 -72.681084) (xy 344.199643 -72.680646) (xy 344.145693 -72.672888)
			(xy 344.093395 -72.657532) (xy 344.043815 -72.634889) (xy 343.997962 -72.605421) (xy 343.95677 -72.569727)
			(xy 343.921077 -72.528534) (xy 343.891609 -72.482681) (xy 343.868967 -72.433101) (xy 343.853611 -72.380804)
			(xy 343.845854 -72.326853) (xy 333.660251 -72.326853) (xy 333.663514 -72.349551) (xy 333.663514 -72.404049)
			(xy 333.655759 -72.457991) (xy 333.640407 -72.510282) (xy 333.617769 -72.559855) (xy 333.588308 -72.605702)
			(xy 333.552622 -72.64689) (xy 333.511437 -72.682581) (xy 333.465593 -72.712048) (xy 333.416023 -72.734691)
			(xy 333.363734 -72.75005) (xy 333.309793 -72.757811) (xy 333.282544 -72.7583) (xy 332.418944 -72.7583)
			(xy 332.391689 -72.757856) (xy 332.337732 -72.750104) (xy 332.285427 -72.734751) (xy 332.235841 -72.712111)
			(xy 332.189981 -72.682643) (xy 332.148782 -72.646949) (xy 332.113083 -72.605754) (xy 332.083611 -72.559898)
			(xy 332.060964 -72.510314) (xy 332.045606 -72.458011) (xy 332.037847 -72.404055) (xy 298.511468 -72.404055)
			(xy 298.511468 -74.617072) (xy 327.277726 -74.617072) (xy 327.281813 -74.561227) (xy 327.293988 -74.506573)
			(xy 327.31399 -74.454274) (xy 327.341395 -74.405445) (xy 327.375617 -74.361126) (xy 327.415927 -74.322262)
			(xy 327.461466 -74.289681) (xy 327.511264 -74.264078) (xy 327.564259 -74.245999) (xy 327.619321 -74.235828)
			(xy 327.675278 -74.233783) (xy 327.730936 -74.239908) (xy 327.785109 -74.25407) (xy 327.836643 -74.27597)
			(xy 327.884439 -74.305139) (xy 327.927478 -74.340957) (xy 327.941626 -74.356747) (xy 330.744122 -74.356747)
			(xy 330.744122 -74.302253) (xy 330.751877 -74.248315) (xy 330.767229 -74.196029) (xy 330.789865 -74.146459)
			(xy 330.819325 -74.100616) (xy 330.855009 -74.059431) (xy 330.89619 -74.023744) (xy 330.942031 -73.99428)
			(xy 330.991599 -73.97164) (xy 331.043883 -73.956284) (xy 331.097821 -73.948524) (xy 331.125068 -73.948036)
			(xy 331.988668 -73.948036) (xy 332.015926 -73.948409) (xy 332.069886 -73.956163) (xy 332.122194 -73.971518)
			(xy 332.171784 -73.994161) (xy 332.217646 -74.023632) (xy 332.258848 -74.05933) (xy 332.294549 -74.100528)
			(xy 332.324023 -74.146388) (xy 332.346671 -74.195976) (xy 332.36203 -74.248283) (xy 332.369789 -74.302243)
			(xy 332.369789 -74.356757) (xy 332.36203 -74.410717) (xy 332.346671 -74.463024) (xy 332.324023 -74.512612)
			(xy 332.294549 -74.558472) (xy 332.26684 -74.590448) (xy 336.274202 -74.590448) (xy 336.274202 -74.535953)
			(xy 336.281957 -74.482012) (xy 336.297309 -74.429724) (xy 336.319945 -74.380153) (xy 336.349406 -74.334308)
			(xy 336.38509 -74.293121) (xy 336.426272 -74.257432) (xy 336.472114 -74.227966) (xy 336.521683 -74.205324)
			(xy 336.573969 -74.189966) (xy 336.627909 -74.182205) (xy 336.655156 -74.181716) (xy 337.518756 -74.181716)
			(xy 337.546013 -74.182128) (xy 337.599972 -74.18988) (xy 337.652278 -74.205233) (xy 337.701867 -74.227875)
			(xy 337.747729 -74.257344) (xy 337.788929 -74.29304) (xy 337.82463 -74.334236) (xy 337.854104 -74.380094)
			(xy 337.876751 -74.42968) (xy 337.89211 -74.481985) (xy 337.899869 -74.535943) (xy 337.899869 -74.55185)
			(xy 339.156294 -74.55185) (xy 339.156294 -74.49735) (xy 339.16405 -74.443405) (xy 339.179404 -74.391113)
			(xy 339.202044 -74.341539) (xy 339.231509 -74.29569) (xy 339.267198 -74.254502) (xy 339.308386 -74.218812)
			(xy 339.354233 -74.189347) (xy 339.403808 -74.166707) (xy 339.456099 -74.151352) (xy 339.510044 -74.143595)
			(xy 339.537294 -74.143108) (xy 340.400894 -74.143108) (xy 340.428148 -74.143538) (xy 340.482102 -74.151295)
			(xy 340.534403 -74.166651) (xy 340.583986 -74.189294) (xy 340.629842 -74.218763) (xy 340.671037 -74.254459)
			(xy 340.706733 -74.295653) (xy 340.736203 -74.341509) (xy 340.758847 -74.391091) (xy 340.774204 -74.443392)
			(xy 340.781961 -74.497346) (xy 340.781961 -74.551854) (xy 340.774204 -74.605808) (xy 340.758847 -74.658109)
			(xy 340.736203 -74.707691) (xy 340.706733 -74.753547) (xy 340.694254 -74.767948) (xy 421.29456 -74.767948)
			(xy 421.29456 -66.06794) (xy 421.295065 -65.962416) (xy 421.303149 -65.751522) (xy 421.319305 -65.541093)
			(xy 421.343508 -65.331436) (xy 421.375725 -65.122861) (xy 421.415907 -64.915673) (xy 421.463995 -64.710176)
			(xy 421.519919 -64.506672) (xy 421.583596 -64.305459) (xy 421.654934 -64.106832) (xy 421.733828 -63.911084)
			(xy 421.820161 -63.718502) (xy 421.913808 -63.529367) (xy 422.01463 -63.343958) (xy 422.12248 -63.162547)
			(xy 422.237199 -62.9854) (xy 422.358619 -62.812778) (xy 422.486562 -62.644932) (xy 422.62084 -62.48211)
			(xy 422.761256 -62.324551) (xy 422.907604 -62.172486) (xy 423.059669 -62.026138) (xy 423.217228 -61.885722)
			(xy 423.38005 -61.751444) (xy 423.547896 -61.623501) (xy 423.720518 -61.502081) (xy 423.897665 -61.387362)
			(xy 424.079076 -61.279512) (xy 424.264485 -61.17869) (xy 424.45362 -61.085043) (xy 424.646202 -60.99871)
			(xy 424.84195 -60.919816) (xy 425.040577 -60.848478) (xy 425.24179 -60.784801) (xy 425.445294 -60.728877)
			(xy 425.650791 -60.680789) (xy 425.857979 -60.640607) (xy 426.066554 -60.60839) (xy 426.276211 -60.584187)
			(xy 426.48664 -60.568031) (xy 426.697534 -60.559947) (xy 426.908582 -60.559947) (xy 427.119476 -60.568031)
			(xy 427.329905 -60.584187) (xy 427.539562 -60.60839) (xy 427.748137 -60.640607) (xy 427.955325 -60.680789)
			(xy 428.160822 -60.728877) (xy 428.364326 -60.784801) (xy 428.565539 -60.848478) (xy 428.764166 -60.919816)
			(xy 428.959914 -60.99871) (xy 429.152496 -61.085043) (xy 429.341631 -61.17869) (xy 429.52704 -61.279512)
			(xy 429.708451 -61.387362) (xy 429.885598 -61.502081) (xy 430.05822 -61.623501) (xy 430.226066 -61.751444)
			(xy 430.388888 -61.885722) (xy 430.546447 -62.026138) (xy 430.698512 -62.172486) (xy 430.84486 -62.324551)
			(xy 430.985276 -62.48211) (xy 431.119554 -62.644932) (xy 431.247497 -62.812778) (xy 431.368917 -62.9854)
			(xy 431.483636 -63.162547) (xy 431.591486 -63.343958) (xy 431.692308 -63.529367) (xy 431.785955 -63.718502)
			(xy 431.872288 -63.911084) (xy 431.951182 -64.106832) (xy 432.02252 -64.305459) (xy 432.086197 -64.506672)
			(xy 432.142121 -64.710176) (xy 432.190209 -64.915673) (xy 432.230391 -65.122861) (xy 432.262608 -65.331436)
			(xy 432.286811 -65.541093) (xy 432.302967 -65.751522) (xy 432.311051 -65.962416) (xy 432.311556 -66.06794)
			(xy 432.311556 -74.767948) (xy 432.311051 -74.873472) (xy 432.302967 -75.084366) (xy 432.286811 -75.294795)
			(xy 432.262608 -75.504452) (xy 432.230391 -75.713027) (xy 432.190209 -75.920215) (xy 432.142121 -76.125712)
			(xy 432.086197 -76.329216) (xy 432.02252 -76.530429) (xy 431.951182 -76.729056) (xy 431.872288 -76.924804)
			(xy 431.785955 -77.117386) (xy 431.692308 -77.306521) (xy 431.591486 -77.49193) (xy 431.483636 -77.673341)
			(xy 431.368917 -77.850488) (xy 431.247497 -78.02311) (xy 431.119554 -78.190956) (xy 430.985276 -78.353778)
			(xy 430.84486 -78.511337) (xy 430.698512 -78.663402) (xy 430.546447 -78.80975) (xy 430.388888 -78.950166)
			(xy 430.226066 -79.084444) (xy 430.05822 -79.212387) (xy 429.885598 -79.333807) (xy 429.708451 -79.448526)
			(xy 429.52704 -79.556376) (xy 429.341631 -79.657198) (xy 429.152496 -79.750845) (xy 428.959914 -79.837178)
			(xy 428.764166 -79.916072) (xy 428.565539 -79.98741) (xy 428.364326 -80.051087) (xy 428.160822 -80.107011)
			(xy 427.955325 -80.155099) (xy 427.748137 -80.195281) (xy 427.539562 -80.227498) (xy 427.329905 -80.251701)
			(xy 427.119476 -80.267857) (xy 426.908582 -80.275941) (xy 426.697534 -80.275941) (xy 426.48664 -80.267857)
			(xy 426.276211 -80.251701) (xy 426.066554 -80.227498) (xy 425.857979 -80.195281) (xy 425.650791 -80.155099)
			(xy 425.445294 -80.107011) (xy 425.24179 -80.051087) (xy 425.040577 -79.98741) (xy 424.84195 -79.916072)
			(xy 424.646202 -79.837178) (xy 424.45362 -79.750845) (xy 424.264485 -79.657198) (xy 424.079076 -79.556376)
			(xy 423.897665 -79.448526) (xy 423.720518 -79.333807) (xy 423.547896 -79.212387) (xy 423.38005 -79.084444)
			(xy 423.217228 -78.950166) (xy 423.059669 -78.80975) (xy 422.907604 -78.663402) (xy 422.761256 -78.511337)
			(xy 422.62084 -78.353778) (xy 422.486562 -78.190956) (xy 422.358619 -78.02311) (xy 422.237199 -77.850488)
			(xy 422.12248 -77.673341) (xy 422.01463 -77.49193) (xy 421.913808 -77.306521) (xy 421.820161 -77.117386)
			(xy 421.733828 -76.924804) (xy 421.654934 -76.729056) (xy 421.583596 -76.530429) (xy 421.519919 -76.329216)
			(xy 421.463995 -76.125712) (xy 421.415907 -75.920215) (xy 421.375725 -75.713027) (xy 421.343508 -75.504452)
			(xy 421.319305 -75.294795) (xy 421.303149 -75.084366) (xy 421.295065 -74.873472) (xy 421.29456 -74.767948)
			(xy 340.694254 -74.767948) (xy 340.671037 -74.794741) (xy 340.629842 -74.830437) (xy 340.583986 -74.859906)
			(xy 340.534403 -74.882549) (xy 340.482102 -74.897905) (xy 340.428148 -74.905662) (xy 340.400894 -74.906124)
			(xy 339.537294 -74.906124) (xy 339.510044 -74.905605) (xy 339.456099 -74.897848) (xy 339.403808 -74.882493)
			(xy 339.354233 -74.859853) (xy 339.308386 -74.830388) (xy 339.267198 -74.794698) (xy 339.231509 -74.75351)
			(xy 339.202044 -74.707661) (xy 339.179404 -74.658087) (xy 339.16405 -74.605795) (xy 339.156294 -74.55185)
			(xy 337.899869 -74.55185) (xy 337.899869 -74.590457) (xy 337.89211 -74.644415) (xy 337.876751 -74.69672)
			(xy 337.854104 -74.746306) (xy 337.82463 -74.792164) (xy 337.788929 -74.83336) (xy 337.747729 -74.869056)
			(xy 337.701867 -74.898525) (xy 337.652278 -74.921167) (xy 337.599972 -74.93652) (xy 337.546013 -74.944272)
			(xy 337.518756 -74.944732) (xy 336.655156 -74.944732) (xy 336.627909 -74.944195) (xy 336.573969 -74.936434)
			(xy 336.521683 -74.921076) (xy 336.472114 -74.898434) (xy 336.426272 -74.868968) (xy 336.38509 -74.833279)
			(xy 336.349406 -74.792092) (xy 336.319945 -74.746247) (xy 336.297309 -74.696676) (xy 336.281957 -74.644388)
			(xy 336.274202 -74.590448) (xy 332.26684 -74.590448) (xy 332.258848 -74.59967) (xy 332.217646 -74.635368)
			(xy 332.171784 -74.664839) (xy 332.122194 -74.687482) (xy 332.069886 -74.702837) (xy 332.015926 -74.710591)
			(xy 331.988668 -74.711052) (xy 331.125068 -74.711052) (xy 331.097821 -74.710476) (xy 331.043883 -74.702716)
			(xy 330.991599 -74.68736) (xy 330.942031 -74.66472) (xy 330.89619 -74.635256) (xy 330.855009 -74.599569)
			(xy 330.819325 -74.558384) (xy 330.789865 -74.512541) (xy 330.767229 -74.462971) (xy 330.751877 -74.410685)
			(xy 330.744122 -74.356747) (xy 327.941626 -74.356747) (xy 327.964844 -74.38266) (xy 327.99574 -74.429358)
			(xy 328.019507 -74.480058) (xy 328.035639 -74.533678) (xy 328.043791 -74.589075) (xy 328.044302 -74.617072)
			(xy 328.043791 -74.645069) (xy 328.035639 -74.700466) (xy 328.019507 -74.754086) (xy 327.99574 -74.804786)
			(xy 327.964844 -74.851484) (xy 327.927478 -74.893187) (xy 327.884439 -74.929005) (xy 327.836643 -74.958174)
			(xy 327.785109 -74.980074) (xy 327.730936 -74.994236) (xy 327.675278 -75.000361) (xy 327.619321 -74.998316)
			(xy 327.564259 -74.988145) (xy 327.511264 -74.970066) (xy 327.461466 -74.944463) (xy 327.415927 -74.911882)
			(xy 327.375617 -74.873018) (xy 327.341395 -74.828699) (xy 327.31399 -74.77987) (xy 327.293988 -74.727571)
			(xy 327.281813 -74.672917) (xy 327.277726 -74.617072) (xy 298.511468 -74.617072) (xy 298.511468 -74.760836)
			(xy 298.510963 -74.86636) (xy 298.502879 -75.077254) (xy 298.486723 -75.287683) (xy 298.46252 -75.49734)
			(xy 298.430303 -75.705915) (xy 298.390121 -75.913103) (xy 298.342033 -76.1186) (xy 298.333664 -76.149054)
			(xy 327.558346 -76.149054) (xy 327.558346 -76.094546) (xy 327.566103 -76.040594) (xy 327.581459 -75.988295)
			(xy 327.604102 -75.938714) (xy 327.633571 -75.892859) (xy 327.669266 -75.851666) (xy 327.710459 -75.815971)
			(xy 327.756314 -75.786502) (xy 327.805895 -75.763859) (xy 327.858194 -75.748503) (xy 327.912146 -75.740746)
			(xy 327.9394 -75.74026) (xy 328.803 -75.74026) (xy 328.830249 -75.74081) (xy 328.884192 -75.748566)
			(xy 328.936482 -75.76392) (xy 328.986055 -75.786559) (xy 329.031902 -75.816023) (xy 329.073089 -75.851711)
			(xy 329.108777 -75.892898) (xy 329.138241 -75.938745) (xy 329.16088 -75.988318) (xy 329.169581 -76.017949)
			(xy 334.874382 -76.017949) (xy 334.874382 -75.963451) (xy 334.882137 -75.909507) (xy 334.89749 -75.857216)
			(xy 334.920128 -75.807642) (xy 334.949591 -75.761793) (xy 334.985278 -75.720605) (xy 335.026463 -75.684914)
			(xy 335.072308 -75.655447) (xy 335.12188 -75.632803) (xy 335.17417 -75.617445) (xy 335.228113 -75.609684)
			(xy 335.255362 -75.609196) (xy 336.118962 -75.609196) (xy 336.146217 -75.609649) (xy 336.200173 -75.617401)
			(xy 336.252475 -75.632754) (xy 336.302061 -75.655395) (xy 336.347919 -75.684862) (xy 336.389117 -75.720556)
			(xy 336.424815 -75.76175) (xy 336.454287 -75.807606) (xy 336.476932 -75.857189) (xy 336.49229 -75.90949)
			(xy 336.500049 -75.963445) (xy 336.500049 -76.017955) (xy 336.49229 -76.07191) (xy 336.476932 -76.124211)
			(xy 336.454287 -76.173794) (xy 336.424815 -76.21965) (xy 336.389117 -76.260844) (xy 336.347919 -76.296538)
			(xy 336.302061 -76.326005) (xy 336.252475 -76.348646) (xy 336.200173 -76.363999) (xy 336.146217 -76.371751)
			(xy 336.118962 -76.372212) (xy 335.255362 -76.372212) (xy 335.228113 -76.371716) (xy 335.17417 -76.363955)
			(xy 335.12188 -76.348597) (xy 335.072308 -76.325953) (xy 335.026463 -76.296486) (xy 334.985278 -76.260795)
			(xy 334.949591 -76.219607) (xy 334.920128 -76.173758) (xy 334.89749 -76.124184) (xy 334.882137 -76.071893)
			(xy 334.874382 -76.017949) (xy 329.169581 -76.017949) (xy 329.176234 -76.040608) (xy 329.18399 -76.094551)
			(xy 329.18399 -76.149049) (xy 329.176234 -76.202992) (xy 329.16088 -76.255282) (xy 329.138241 -76.304855)
			(xy 329.108777 -76.350702) (xy 329.073089 -76.391889) (xy 329.031902 -76.427577) (xy 328.986055 -76.457041)
			(xy 328.936482 -76.47968) (xy 328.884192 -76.495034) (xy 328.830249 -76.50279) (xy 328.803 -76.503276)
			(xy 327.9394 -76.503276) (xy 327.912146 -76.502854) (xy 327.858194 -76.495097) (xy 327.805895 -76.479741)
			(xy 327.756314 -76.457098) (xy 327.710459 -76.427629) (xy 327.669266 -76.391934) (xy 327.633571 -76.350741)
			(xy 327.604102 -76.304886) (xy 327.581459 -76.255305) (xy 327.566103 -76.203006) (xy 327.558346 -76.149054)
			(xy 298.333664 -76.149054) (xy 298.286109 -76.322104) (xy 298.222432 -76.523317) (xy 298.151094 -76.721944)
			(xy 298.0722 -76.917692) (xy 297.985867 -77.110274) (xy 297.89222 -77.299409) (xy 297.791398 -77.484818)
			(xy 297.683548 -77.666229) (xy 297.568829 -77.843376) (xy 297.455321 -78.00475) (xy 330.84567 -78.00475)
			(xy 330.84567 -77.95025) (xy 330.853426 -77.896304) (xy 330.868779 -77.84401) (xy 330.891419 -77.794434)
			(xy 330.920883 -77.748584) (xy 330.956571 -77.707394) (xy 330.997759 -77.671702) (xy 331.043606 -77.642234)
			(xy 331.09318 -77.619591) (xy 331.145472 -77.604232) (xy 331.199418 -77.596472) (xy 331.226668 -77.595984)
			(xy 332.090268 -77.595984) (xy 332.117522 -77.596461) (xy 332.171475 -77.604214) (xy 332.223776 -77.619567)
			(xy 332.273359 -77.642207) (xy 332.319215 -77.671674) (xy 332.360411 -77.707367) (xy 332.396107 -77.748559)
			(xy 332.425577 -77.794413) (xy 332.448222 -77.843994) (xy 332.463579 -77.896294) (xy 332.471337 -77.950246)
			(xy 332.471337 -78.004754) (xy 332.463579 -78.058706) (xy 332.448222 -78.111006) (xy 332.425577 -78.160587)
			(xy 332.396107 -78.206441) (xy 332.360411 -78.247633) (xy 332.319215 -78.283326) (xy 332.273359 -78.312793)
			(xy 332.223776 -78.335433) (xy 332.171475 -78.350786) (xy 332.117522 -78.358539) (xy 332.090268 -78.359)
			(xy 331.226668 -78.359) (xy 331.199418 -78.358528) (xy 331.145472 -78.350768) (xy 331.09318 -78.335409)
			(xy 331.043606 -78.312766) (xy 330.997759 -78.283298) (xy 330.956571 -78.247606) (xy 330.920883 -78.206416)
			(xy 330.891419 -78.160566) (xy 330.868779 -78.11099) (xy 330.853426 -78.058696) (xy 330.84567 -78.00475)
			(xy 297.455321 -78.00475) (xy 297.447409 -78.015998) (xy 297.319466 -78.183844) (xy 297.185188 -78.346666)
			(xy 297.044772 -78.504225) (xy 296.898424 -78.65629) (xy 296.746359 -78.802638) (xy 296.5888 -78.943054)
			(xy 296.425978 -79.077332) (xy 296.258132 -79.205275) (xy 296.08551 -79.326695) (xy 295.908363 -79.441414)
			(xy 295.726952 -79.549264) (xy 295.541543 -79.650086) (xy 295.352408 -79.743733) (xy 295.159826 -79.830066)
			(xy 294.964078 -79.90896) (xy 294.765451 -79.980298) (xy 294.564238 -80.043975) (xy 294.360734 -80.099899)
			(xy 294.155237 -80.147987) (xy 293.948049 -80.188169) (xy 293.739474 -80.220386) (xy 293.529817 -80.244589)
			(xy 293.319388 -80.260745) (xy 293.108494 -80.268829) (xy 292.897446 -80.268829) (xy 292.686552 -80.260745)
			(xy 292.476123 -80.244589) (xy 292.266466 -80.220386) (xy 292.057891 -80.188169) (xy 291.850703 -80.147987)
			(xy 291.645206 -80.099899) (xy 291.441702 -80.043975) (xy 291.240489 -79.980298) (xy 291.041862 -79.90896)
			(xy 290.846114 -79.830066) (xy 290.653532 -79.743733) (xy 290.464397 -79.650086) (xy 290.278988 -79.549264)
			(xy 290.097577 -79.441414) (xy 289.92043 -79.326695) (xy 289.747808 -79.205275) (xy 289.579962 -79.077332)
			(xy 289.41714 -78.943054) (xy 289.259581 -78.802638) (xy 289.107516 -78.65629) (xy 288.961168 -78.504225)
			(xy 288.820752 -78.346666) (xy 288.686474 -78.183844) (xy 288.558531 -78.015998) (xy 288.437111 -77.843376)
			(xy 288.322392 -77.666229) (xy 288.214542 -77.484818) (xy 288.11372 -77.299409) (xy 288.020073 -77.110274)
			(xy 287.93374 -76.917692) (xy 287.854846 -76.721944) (xy 287.783508 -76.523317) (xy 287.719831 -76.322104)
			(xy 287.663907 -76.1186) (xy 287.615819 -75.913103) (xy 287.575637 -75.705915) (xy 287.54342 -75.49734)
			(xy 287.519217 -75.287683) (xy 287.503061 -75.077254) (xy 287.494977 -74.86636) (xy 287.494472 -74.760836)
			(xy 184.371488 -74.760836) (xy 184.371488 -74.767948) (xy 184.370983 -74.873472) (xy 184.362899 -75.084366)
			(xy 184.346743 -75.294795) (xy 184.32254 -75.504452) (xy 184.290323 -75.713027) (xy 184.250141 -75.920215)
			(xy 184.202053 -76.125712) (xy 184.146129 -76.329216) (xy 184.082452 -76.530429) (xy 184.011114 -76.729056)
			(xy 183.93222 -76.924804) (xy 183.845887 -77.117386) (xy 183.75224 -77.306521) (xy 183.651418 -77.49193)
			(xy 183.543568 -77.673341) (xy 183.428849 -77.850488) (xy 183.307429 -78.02311) (xy 183.179486 -78.190956)
			(xy 183.045208 -78.353778) (xy 182.904792 -78.511337) (xy 182.758444 -78.663402) (xy 182.606379 -78.80975)
			(xy 182.44882 -78.950166) (xy 182.285998 -79.084444) (xy 182.118152 -79.212387) (xy 181.94553 -79.333807)
			(xy 181.768383 -79.448526) (xy 181.586972 -79.556376) (xy 181.401563 -79.657198) (xy 181.212428 -79.750845)
			(xy 181.019846 -79.837178) (xy 180.824098 -79.916072) (xy 180.625471 -79.98741) (xy 180.424258 -80.051087)
			(xy 180.220754 -80.107011) (xy 180.015257 -80.155099) (xy 179.808069 -80.195281) (xy 179.599494 -80.227498)
			(xy 179.389837 -80.251701) (xy 179.179408 -80.267857) (xy 178.968514 -80.275941) (xy 178.757466 -80.275941)
			(xy 178.546572 -80.267857) (xy 178.336143 -80.251701) (xy 178.126486 -80.227498) (xy 177.917911 -80.195281)
			(xy 177.710723 -80.155099) (xy 177.505226 -80.107011) (xy 177.301722 -80.051087) (xy 177.100509 -79.98741)
			(xy 176.901882 -79.916072) (xy 176.706134 -79.837178) (xy 176.513552 -79.750845) (xy 176.324417 -79.657198)
			(xy 176.139008 -79.556376) (xy 175.957597 -79.448526) (xy 175.78045 -79.333807) (xy 175.607828 -79.212387)
			(xy 175.439982 -79.084444) (xy 175.27716 -78.950166) (xy 175.119601 -78.80975) (xy 174.967536 -78.663402)
			(xy 174.821188 -78.511337) (xy 174.680772 -78.353778) (xy 174.546494 -78.190956) (xy 174.418551 -78.02311)
			(xy 174.297131 -77.850488) (xy 174.182412 -77.673341) (xy 174.074562 -77.49193) (xy 173.97374 -77.306521)
			(xy 173.880093 -77.117386) (xy 173.79376 -76.924804) (xy 173.714866 -76.729056) (xy 173.643528 -76.530429)
			(xy 173.579851 -76.329216) (xy 173.523927 -76.125712) (xy 173.475839 -75.920215) (xy 173.435657 -75.713027)
			(xy 173.40344 -75.504452) (xy 173.379237 -75.294795) (xy 173.363081 -75.084366) (xy 173.354997 -74.873472)
			(xy 173.354492 -74.767948) (xy 50.571366 -74.767948) (xy 50.570895 -74.86636) (xy 50.562811 -75.077254)
			(xy 50.546655 -75.287683) (xy 50.522452 -75.49734) (xy 50.490235 -75.705915) (xy 50.450053 -75.913103)
			(xy 50.401965 -76.1186) (xy 50.346041 -76.322104) (xy 50.282364 -76.523317) (xy 50.211026 -76.721944)
			(xy 50.132132 -76.917692) (xy 50.045799 -77.110274) (xy 49.952152 -77.299409) (xy 49.85133 -77.484818)
			(xy 49.74348 -77.666229) (xy 49.628761 -77.843376) (xy 49.507341 -78.015998) (xy 49.379398 -78.183844)
			(xy 49.24512 -78.346666) (xy 49.104704 -78.504225) (xy 48.958356 -78.65629) (xy 48.806291 -78.802638)
			(xy 48.648732 -78.943054) (xy 48.48591 -79.077332) (xy 48.318064 -79.205275) (xy 48.145442 -79.326695)
			(xy 47.968295 -79.441414) (xy 47.786884 -79.549264) (xy 47.601475 -79.650086) (xy 47.41234 -79.743733)
			(xy 47.219758 -79.830066) (xy 47.02401 -79.90896) (xy 46.825383 -79.980298) (xy 46.62417 -80.043975)
			(xy 46.420666 -80.099899) (xy 46.215169 -80.147987) (xy 46.007981 -80.188169) (xy 45.799406 -80.220386)
			(xy 45.589749 -80.244589) (xy 45.37932 -80.260745) (xy 45.168426 -80.268829) (xy 44.957378 -80.268829)
			(xy 44.746484 -80.260745) (xy 44.536055 -80.244589) (xy 44.326398 -80.220386) (xy 44.117823 -80.188169)
			(xy 43.910635 -80.147987) (xy 43.705138 -80.099899) (xy 43.501634 -80.043975) (xy 43.300421 -79.980298)
			(xy 43.101794 -79.90896) (xy 42.906046 -79.830066) (xy 42.713464 -79.743733) (xy 42.524329 -79.650086)
			(xy 42.33892 -79.549264) (xy 42.157509 -79.441414) (xy 41.980362 -79.326695) (xy 41.80774 -79.205275)
			(xy 41.639894 -79.077332) (xy 41.477072 -78.943054) (xy 41.319513 -78.802638) (xy 41.167448 -78.65629)
			(xy 41.0211 -78.504225) (xy 40.880684 -78.346666) (xy 40.746406 -78.183844) (xy 40.618463 -78.015998)
			(xy 40.497043 -77.843376) (xy 40.382324 -77.666229) (xy 40.274474 -77.484818) (xy 40.173652 -77.299409)
			(xy 40.080005 -77.110274) (xy 39.993672 -76.917692) (xy 39.914778 -76.721944) (xy 39.84344 -76.523317)
			(xy 39.779763 -76.322104) (xy 39.723839 -76.1186) (xy 39.675751 -75.913103) (xy 39.635569 -75.705915)
			(xy 39.603352 -75.49734) (xy 39.579149 -75.287683) (xy 39.562993 -75.077254) (xy 39.554909 -74.86636)
			(xy 39.554404 -74.760836) (xy 0.509016 -74.760836) (xy 0.509016 -77.671676) (xy 0.509504 -77.724899)
			(xy 0.51712 -77.831071) (xy 0.532286 -77.93643) (xy 0.554925 -78.04044) (xy 0.584921 -78.142572)
			(xy 0.622123 -78.242305) (xy 0.666339 -78.339132) (xy 0.717347 -78.43256) (xy 0.774885 -78.522114)
			(xy 0.838661 -78.607338) (xy 0.908351 -78.687799) (xy 0.945642 -78.725776) (xy 1.77419 -79.554324)
			(xy 1.823602 -79.604436) (xy 1.917388 -79.709385) (xy 2.005143 -79.819428) (xy 2.08659 -79.934217)
			(xy 2.161473 -80.053392) (xy 2.229556 -80.176578) (xy 2.290626 -80.303388) (xy 2.344491 -80.433422)
			(xy 2.39098 -80.566271) (xy 2.429948 -80.701518) (xy 2.461272 -80.838737) (xy 2.484853 -80.977496)
			(xy 2.500618 -81.117359) (xy 2.508516 -81.257886) (xy 2.509012 -81.32826) (xy 2.509012 -81.69181)
			(xy 232.140667 -81.69181) (xy 232.145062 -81.517977) (xy 232.15749 -81.344533) (xy 232.177927 -81.171849)
			(xy 232.206328 -81.000295) (xy 232.242632 -80.830238) (xy 232.286762 -80.662042) (xy 232.338623 -80.496067)
			(xy 232.398104 -80.332668) (xy 232.465078 -80.172194) (xy 232.539402 -80.01499) (xy 232.620917 -79.86139)
			(xy 232.709448 -79.711725) (xy 232.804805 -79.566315) (xy 232.906785 -79.425469) (xy 233.01517 -79.289491)
			(xy 233.129727 -79.158671) (xy 233.250212 -79.033288) (xy 233.376366 -78.913612) (xy 233.50792 -78.799897)
			(xy 233.644592 -78.692389) (xy 233.715052 -78.641448) (xy 238.08436 -78.641448) (xy 238.15482 -78.692389)
			(xy 238.291492 -78.799897) (xy 238.423046 -78.913612) (xy 238.5492 -79.033288) (xy 238.669685 -79.158671)
			(xy 238.784242 -79.289491) (xy 238.892627 -79.425469) (xy 238.994607 -79.566315) (xy 239.089964 -79.711725)
			(xy 239.178495 -79.86139) (xy 239.26001 -80.01499) (xy 239.334334 -80.172194) (xy 239.401308 -80.332668)
			(xy 239.460789 -80.496067) (xy 239.51265 -80.662042) (xy 239.553507 -80.817765) (xy 333.938166 -80.817765)
			(xy 333.938166 -80.763235) (xy 333.945926 -80.70926) (xy 333.961289 -80.656938) (xy 333.98394 -80.607335)
			(xy 334.01342 -80.561461) (xy 334.049129 -80.520248) (xy 334.090338 -80.484537) (xy 334.136211 -80.455054)
			(xy 334.185812 -80.432398) (xy 334.238132 -80.417032) (xy 334.292107 -80.409268) (xy 334.319372 -80.40878)
			(xy 335.182972 -80.40878) (xy 335.210247 -80.409158) (xy 335.264243 -80.416917) (xy 335.316585 -80.432283)
			(xy 335.366207 -80.454941) (xy 335.412099 -80.484432) (xy 335.453327 -80.520153) (xy 335.489052 -80.561378)
			(xy 335.518545 -80.607268) (xy 335.541207 -80.656889) (xy 335.556577 -80.709229) (xy 335.56434 -80.763225)
			(xy 335.56434 -80.817775) (xy 335.556577 -80.871771) (xy 335.541207 -80.924111) (xy 335.518545 -80.973732)
			(xy 335.489052 -81.019622) (xy 335.453327 -81.060847) (xy 335.412099 -81.096568) (xy 335.366207 -81.126059)
			(xy 335.316585 -81.148717) (xy 335.264243 -81.164083) (xy 335.210247 -81.171842) (xy 335.182972 -81.172304)
			(xy 334.319372 -81.172304) (xy 334.292107 -81.171732) (xy 334.238132 -81.163968) (xy 334.185812 -81.148602)
			(xy 334.136211 -81.125946) (xy 334.090338 -81.096463) (xy 334.049129 -81.060752) (xy 334.01342 -81.019539)
			(xy 333.98394 -80.973665) (xy 333.961289 -80.924062) (xy 333.945926 -80.87174) (xy 333.938166 -80.817765)
			(xy 239.553507 -80.817765) (xy 239.55678 -80.830238) (xy 239.593084 -81.000295) (xy 239.621485 -81.171849)
			(xy 239.641922 -81.344533) (xy 239.65435 -81.517977) (xy 239.658745 -81.69181) (xy 239.655095 -81.865661)
			(xy 239.643409 -82.039157) (xy 239.640092 -82.06825) (xy 331.768962 -82.06825) (xy 331.768962 -82.01375)
			(xy 331.776717 -81.959803) (xy 331.792071 -81.90751) (xy 331.81471 -81.857933) (xy 331.844174 -81.812083)
			(xy 331.879862 -81.770892) (xy 331.921049 -81.735199) (xy 331.966896 -81.70573) (xy 332.01647 -81.683086)
			(xy 332.068762 -81.667726) (xy 332.122708 -81.659965) (xy 332.149958 -81.659476) (xy 333.013558 -81.659476)
			(xy 333.040812 -81.659968) (xy 333.094765 -81.66772) (xy 333.147066 -81.683072) (xy 333.196649 -81.705711)
			(xy 333.242505 -81.735177) (xy 333.283701 -81.770869) (xy 333.319398 -81.812061) (xy 333.348869 -81.857914)
			(xy 333.371513 -81.907495) (xy 333.386871 -81.959794) (xy 333.394629 -82.013746) (xy 333.394629 -82.068254)
			(xy 333.386871 -82.122206) (xy 333.371513 -82.174505) (xy 333.348869 -82.224086) (xy 333.319398 -82.269939)
			(xy 333.294774 -82.298353) (xy 336.189263 -82.298353) (xy 336.189263 -82.243847) (xy 336.197021 -82.189895)
			(xy 336.212377 -82.137597) (xy 336.235021 -82.088017) (xy 336.26449 -82.042163) (xy 336.300185 -82.000971)
			(xy 336.341379 -81.965278) (xy 336.387234 -81.935811) (xy 336.436816 -81.91317) (xy 336.489115 -81.897816)
			(xy 336.543067 -81.890062) (xy 336.57032 -81.8896) (xy 337.43392 -81.8896) (xy 337.461171 -81.890071)
			(xy 337.515118 -81.89783) (xy 337.567411 -81.913187) (xy 337.616987 -81.93583) (xy 337.662836 -81.965298)
			(xy 337.692804 -81.991267) (xy 339.478646 -81.991267) (xy 339.478646 -81.936733) (xy 339.486407 -81.882755)
			(xy 339.50177 -81.830431) (xy 339.524423 -81.780825) (xy 339.553905 -81.734948) (xy 339.589615 -81.693734)
			(xy 339.630827 -81.65802) (xy 339.676702 -81.628535) (xy 339.726306 -81.605879) (xy 339.77863 -81.590512)
			(xy 339.832607 -81.582748) (xy 339.859874 -81.58226) (xy 340.723474 -81.58226) (xy 340.750748 -81.582678)
			(xy 340.804741 -81.590437) (xy 340.857079 -81.605802) (xy 340.906699 -81.62846) (xy 340.952588 -81.657948)
			(xy 340.993814 -81.693668) (xy 341.029536 -81.734891) (xy 341.059028 -81.780778) (xy 341.081689 -81.830396)
			(xy 341.097057 -81.882734) (xy 341.10482 -81.936726) (xy 341.10482 -81.991274) (xy 341.097057 -82.045266)
			(xy 341.081689 -82.097604) (xy 341.059028 -82.147222) (xy 341.029536 -82.193109) (xy 340.993814 -82.234332)
			(xy 340.952588 -82.270052) (xy 340.906699 -82.29954) (xy 340.857079 -82.322198) (xy 340.804741 -82.337563)
			(xy 340.750748 -82.345322) (xy 340.723474 -82.345784) (xy 339.859874 -82.345784) (xy 339.832607 -82.345252)
			(xy 339.77863 -82.337488) (xy 339.726306 -82.322121) (xy 339.676702 -82.299465) (xy 339.630827 -82.26998)
			(xy 339.589615 -82.234266) (xy 339.553905 -82.193052) (xy 339.524423 -82.147175) (xy 339.50177 -82.097569)
			(xy 339.486407 -82.045245) (xy 339.478646 -81.991267) (xy 337.692804 -81.991267) (xy 337.704024 -82.00099)
			(xy 337.739714 -82.04218) (xy 337.76918 -82.088031) (xy 337.79182 -82.137608) (xy 337.807174 -82.189902)
			(xy 337.81493 -82.243849) (xy 337.81493 -82.298351) (xy 337.807174 -82.352298) (xy 337.79182 -82.404592)
			(xy 337.769179 -82.454169) (xy 337.739714 -82.50002) (xy 337.704024 -82.54121) (xy 337.662836 -82.576902)
			(xy 337.616987 -82.60637) (xy 337.567411 -82.629013) (xy 337.515118 -82.64437) (xy 337.461171 -82.652129)
			(xy 337.43392 -82.652616) (xy 336.57032 -82.652616) (xy 336.543067 -82.652138) (xy 336.489115 -82.644384)
			(xy 336.436816 -82.62903) (xy 336.387234 -82.606389) (xy 336.341379 -82.576922) (xy 336.300185 -82.541229)
			(xy 336.26449 -82.500037) (xy 336.235021 -82.454183) (xy 336.212377 -82.404603) (xy 336.197021 -82.352305)
			(xy 336.189263 -82.298353) (xy 333.294774 -82.298353) (xy 333.283701 -82.311131) (xy 333.242505 -82.346823)
			(xy 333.196649 -82.376289) (xy 333.147066 -82.398928) (xy 333.094765 -82.41428) (xy 333.040812 -82.422032)
			(xy 333.013558 -82.422492) (xy 332.149958 -82.422492) (xy 332.122708 -82.422035) (xy 332.068762 -82.414274)
			(xy 332.01647 -82.398914) (xy 331.966896 -82.37627) (xy 331.921049 -82.346801) (xy 331.879862 -82.311108)
			(xy 331.844174 -82.269917) (xy 331.81471 -82.224067) (xy 331.792071 -82.17449) (xy 331.776717 -82.122197)
			(xy 331.768962 -82.06825) (xy 239.640092 -82.06825) (xy 239.623713 -82.211927) (xy 239.596047 -82.383601)
			(xy 239.560472 -82.553811) (xy 239.517063 -82.722195) (xy 239.465913 -82.888391) (xy 239.407133 -83.052043)
			(xy 239.340846 -83.212802) (xy 239.267197 -83.370324) (xy 239.186341 -83.524271) (xy 239.148735 -83.588471)
			(xy 341.356398 -83.588471) (xy 341.356398 -83.533929) (xy 341.364161 -83.479942) (xy 341.379527 -83.427609)
			(xy 341.402184 -83.377996) (xy 341.431672 -83.332112) (xy 341.467389 -83.290892) (xy 341.508609 -83.255174)
			(xy 341.554492 -83.225686) (xy 341.604106 -83.203028) (xy 341.656438 -83.187661) (xy 341.710425 -83.179899)
			(xy 341.737696 -83.179412) (xy 342.601296 -83.179412) (xy 342.628565 -83.179927) (xy 342.682549 -83.187688)
			(xy 342.734879 -83.203053) (xy 342.784489 -83.225709) (xy 342.83037 -83.255194) (xy 342.871588 -83.290909)
			(xy 342.907303 -83.332127) (xy 342.936789 -83.378008) (xy 342.959445 -83.427618) (xy 342.974811 -83.479947)
			(xy 342.982573 -83.533931) (xy 342.982573 -83.588469) (xy 342.974811 -83.642453) (xy 342.959445 -83.694782)
			(xy 342.936789 -83.744392) (xy 342.907303 -83.790273) (xy 342.871588 -83.831491) (xy 342.83037 -83.867206)
			(xy 342.784489 -83.896691) (xy 342.734879 -83.919347) (xy 342.682549 -83.934712) (xy 342.628565 -83.942473)
			(xy 342.601296 -83.942936) (xy 341.737696 -83.942936) (xy 341.710425 -83.942501) (xy 341.656438 -83.934739)
			(xy 341.604106 -83.919372) (xy 341.554492 -83.896714) (xy 341.508609 -83.867226) (xy 341.467389 -83.831508)
			(xy 341.431672 -83.790288) (xy 341.402184 -83.744404) (xy 341.379527 -83.694791) (xy 341.364161 -83.642458)
			(xy 341.356398 -83.588471) (xy 239.148735 -83.588471) (xy 239.098452 -83.674314) (xy 239.003718 -83.820132)
			(xy 238.902342 -83.961413) (xy 238.794541 -84.097854) (xy 238.680545 -84.229164) (xy 238.560599 -84.355062)
			(xy 238.434958 -84.475277) (xy 238.393119 -84.511757) (xy 337.882119 -84.511757) (xy 337.882119 -84.457243)
			(xy 337.889878 -84.403284) (xy 337.905237 -84.350979) (xy 337.927883 -84.301392) (xy 337.957357 -84.255533)
			(xy 337.993057 -84.214336) (xy 338.034257 -84.178639) (xy 338.080119 -84.149169) (xy 338.129707 -84.126526)
			(xy 338.182014 -84.111171) (xy 338.235973 -84.103417) (xy 338.26323 -84.102956) (xy 339.12683 -84.102956)
			(xy 339.154077 -84.103516) (xy 339.208017 -84.111275) (xy 339.260303 -84.126632) (xy 339.309871 -84.149272)
			(xy 339.355714 -84.178737) (xy 339.396896 -84.214425) (xy 339.432581 -84.25561) (xy 339.462042 -84.301455)
			(xy 339.484679 -84.351025) (xy 339.500031 -84.403313) (xy 339.503159 -84.425069) (xy 344.644951 -84.425069)
			(xy 344.644951 -84.370531) (xy 344.652713 -84.316548) (xy 344.668079 -84.26422) (xy 344.690737 -84.214611)
			(xy 344.720223 -84.168731) (xy 344.75594 -84.127516) (xy 344.797159 -84.091803) (xy 344.843041 -84.06232)
			(xy 344.892652 -84.039668) (xy 344.944981 -84.024306) (xy 344.998965 -84.016549) (xy 345.026234 -84.016088)
			(xy 345.889834 -84.016088) (xy 345.917105 -84.016477) (xy 345.971092 -84.024243) (xy 346.023425 -84.039614)
			(xy 346.073037 -84.062275) (xy 346.11892 -84.091766) (xy 346.160139 -84.127485) (xy 346.195855 -84.168708)
			(xy 346.225341 -84.214593) (xy 346.247998 -84.264207) (xy 346.263364 -84.316541) (xy 346.271126 -84.370529)
			(xy 346.271126 -84.425071) (xy 346.263364 -84.479059) (xy 346.247998 -84.531393) (xy 346.225341 -84.581007)
			(xy 346.195855 -84.626892) (xy 346.160139 -84.668115) (xy 346.11892 -84.703834) (xy 346.073037 -84.733325)
			(xy 346.023425 -84.755986) (xy 345.971092 -84.771357) (xy 345.917105 -84.779123) (xy 345.889834 -84.779612)
			(xy 345.026234 -84.779612) (xy 344.998965 -84.779051) (xy 344.944981 -84.771294) (xy 344.892652 -84.755932)
			(xy 344.843041 -84.73328) (xy 344.797159 -84.703797) (xy 344.75594 -84.668084) (xy 344.720223 -84.626869)
			(xy 344.690737 -84.580989) (xy 344.668079 -84.53138) (xy 344.652713 -84.479052) (xy 344.644951 -84.425069)
			(xy 339.503159 -84.425069) (xy 339.507786 -84.457253) (xy 339.507786 -84.511747) (xy 339.500031 -84.565687)
			(xy 339.484679 -84.617975) (xy 339.462042 -84.667545) (xy 339.432581 -84.71339) (xy 339.396896 -84.754575)
			(xy 339.355714 -84.790263) (xy 339.309871 -84.819728) (xy 339.260303 -84.842368) (xy 339.208017 -84.857725)
			(xy 339.154077 -84.865484) (xy 339.12683 -84.865972) (xy 338.26323 -84.865972) (xy 338.235973 -84.865583)
			(xy 338.182014 -84.857829) (xy 338.129707 -84.842474) (xy 338.080119 -84.819831) (xy 338.034257 -84.790361)
			(xy 337.993057 -84.754664) (xy 337.957357 -84.713467) (xy 337.927883 -84.667608) (xy 337.905237 -84.618021)
			(xy 337.889878 -84.565716) (xy 337.882119 -84.511757) (xy 238.393119 -84.511757) (xy 238.303893 -84.589554)
			(xy 238.167683 -84.697647) (xy 238.02662 -84.799326) (xy 237.881005 -84.894371) (xy 237.73115 -84.982581)
			(xy 237.577377 -85.063767) (xy 237.420014 -85.137754) (xy 237.259397 -85.204384) (xy 237.095871 -85.263515)
			(xy 236.929785 -85.315021) (xy 236.761494 -85.35879) (xy 236.59136 -85.39473) (xy 236.419746 -85.422763)
			(xy 236.247019 -85.44283) (xy 236.073548 -85.454887) (xy 235.899706 -85.458909) (xy 235.725864 -85.454887)
			(xy 235.552393 -85.44283) (xy 235.379666 -85.422763) (xy 235.208052 -85.39473) (xy 235.037918 -85.35879)
			(xy 234.869627 -85.315021) (xy 234.703541 -85.263515) (xy 234.540015 -85.204384) (xy 234.379398 -85.137754)
			(xy 234.222035 -85.063767) (xy 234.068262 -84.982581) (xy 233.918407 -84.894371) (xy 233.772792 -84.799326)
			(xy 233.631729 -84.697647) (xy 233.495519 -84.589554) (xy 233.364454 -84.475277) (xy 233.238813 -84.355062)
			(xy 233.118867 -84.229164) (xy 233.004871 -84.097854) (xy 232.89707 -83.961413) (xy 232.795694 -83.820132)
			(xy 232.70096 -83.674314) (xy 232.613071 -83.524271) (xy 232.532215 -83.370324) (xy 232.458566 -83.212802)
			(xy 232.392279 -83.052043) (xy 232.333499 -82.888391) (xy 232.282349 -82.722195) (xy 232.23894 -82.553811)
			(xy 232.203365 -82.383601) (xy 232.175699 -82.211927) (xy 232.156003 -82.039157) (xy 232.144317 -81.865661)
			(xy 232.140667 -81.69181) (xy 2.509012 -81.69181) (xy 2.509012 -85.764678) (xy 10.421355 -85.764678)
			(xy 10.421355 -85.635538) (xy 10.429305 -85.506643) (xy 10.445175 -85.378483) (xy 10.468904 -85.251542)
			(xy 10.500403 -85.126303) (xy 10.539552 -85.00324) (xy 10.586203 -84.882821) (xy 10.640178 -84.765502)
			(xy 10.701273 -84.651728) (xy 10.769256 -84.541931) (xy 10.84387 -84.436528) (xy 10.924831 -84.335918)
			(xy 11.011831 -84.240483) (xy 11.104542 -84.150584) (xy 11.202612 -84.066563) (xy 11.305667 -83.988739)
			(xy 11.413318 -83.917407) (xy 11.525157 -83.852837) (xy 11.640758 -83.795275) (xy 11.759683 -83.744938)
			(xy 11.881482 -83.702018) (xy 12.005692 -83.666677) (xy 12.131841 -83.63905) (xy 12.259453 -83.619241)
			(xy 12.388042 -83.607325) (xy 12.51712 -83.603349) (xy 12.646198 -83.607325) (xy 12.774787 -83.619241)
			(xy 12.902399 -83.63905) (xy 13.028548 -83.666677) (xy 13.152758 -83.702018) (xy 13.274557 -83.744938)
			(xy 13.393482 -83.795275) (xy 13.509083 -83.852837) (xy 13.620922 -83.917407) (xy 13.728573 -83.988739)
			(xy 13.831628 -84.066563) (xy 13.929698 -84.150584) (xy 14.022409 -84.240483) (xy 14.109409 -84.335918)
			(xy 14.19037 -84.436528) (xy 14.264984 -84.541931) (xy 14.332967 -84.651728) (xy 14.394062 -84.765502)
			(xy 14.448037 -84.882821) (xy 14.494688 -85.00324) (xy 14.533837 -85.126303) (xy 14.565336 -85.251542)
			(xy 14.589065 -85.378483) (xy 14.604935 -85.506643) (xy 14.612885 -85.635538) (xy 14.613382 -85.700108)
			(xy 14.612885 -85.764678) (xy 14.608278 -85.839368) (xy 342.975946 -85.839368) (xy 342.975946 -85.784832)
			(xy 342.983708 -85.730852) (xy 342.999072 -85.678525) (xy 343.021727 -85.628918) (xy 343.051211 -85.58304)
			(xy 343.086924 -85.541824) (xy 343.12814 -85.506111) (xy 343.174018 -85.476627) (xy 343.223625 -85.453972)
			(xy 343.275952 -85.438608) (xy 343.329932 -85.430846) (xy 343.3572 -85.43036) (xy 344.2208 -85.43036)
			(xy 344.248071 -85.430802) (xy 344.302058 -85.438565) (xy 344.35439 -85.453931) (xy 344.404003 -85.476588)
			(xy 344.449887 -85.506076) (xy 344.491107 -85.541793) (xy 344.526824 -85.583013) (xy 344.556312 -85.628897)
			(xy 344.578969 -85.67851) (xy 344.594335 -85.730842) (xy 344.602098 -85.784829) (xy 344.602098 -85.839371)
			(xy 344.594335 -85.893358) (xy 344.578969 -85.94569) (xy 344.556312 -85.995303) (xy 344.526824 -86.041187)
			(xy 344.491107 -86.082407) (xy 344.449887 -86.118124) (xy 344.404003 -86.147612) (xy 344.35439 -86.170269)
			(xy 344.302058 -86.185635) (xy 344.248071 -86.193398) (xy 344.2208 -86.193884) (xy 343.3572 -86.193884)
			(xy 343.329932 -86.193354) (xy 343.275952 -86.185592) (xy 343.223625 -86.170228) (xy 343.174018 -86.147573)
			(xy 343.12814 -86.118089) (xy 343.086924 -86.082376) (xy 343.051211 -86.04116) (xy 343.021727 -85.995282)
			(xy 342.999072 -85.945675) (xy 342.983708 -85.893348) (xy 342.975946 -85.839368) (xy 14.608278 -85.839368)
			(xy 14.604935 -85.893573) (xy 14.589065 -86.021733) (xy 14.565336 -86.148674) (xy 14.533837 -86.273913)
			(xy 14.494688 -86.396976) (xy 14.448037 -86.517395) (xy 14.394062 -86.634714) (xy 14.332967 -86.748488)
			(xy 14.264984 -86.858285) (xy 14.19037 -86.963688) (xy 14.109409 -87.064298) (xy 14.022409 -87.159733)
			(xy 13.929698 -87.249632) (xy 13.831628 -87.333653) (xy 13.728573 -87.411477) (xy 13.620922 -87.482809)
			(xy 13.509083 -87.547379) (xy 13.393482 -87.604941) (xy 13.274557 -87.655278) (xy 13.152758 -87.698198)
			(xy 13.028548 -87.733539) (xy 12.902399 -87.761166) (xy 12.774787 -87.780975) (xy 12.646198 -87.792891)
			(xy 12.51712 -87.796868) (xy 12.388042 -87.792891) (xy 12.259453 -87.780975) (xy 12.131841 -87.761166)
			(xy 12.005692 -87.733539) (xy 11.881482 -87.698198) (xy 11.759683 -87.655278) (xy 11.640758 -87.604941)
			(xy 11.525157 -87.547379) (xy 11.413318 -87.482809) (xy 11.305667 -87.411477) (xy 11.202612 -87.333653)
			(xy 11.104542 -87.249632) (xy 11.011831 -87.159733) (xy 10.924831 -87.064298) (xy 10.84387 -86.963688)
			(xy 10.769256 -86.858285) (xy 10.701273 -86.748488) (xy 10.640178 -86.634714) (xy 10.586203 -86.517395)
			(xy 10.539552 -86.396976) (xy 10.500403 -86.273913) (xy 10.468904 -86.148674) (xy 10.445175 -86.021733)
			(xy 10.429305 -85.893573) (xy 10.421355 -85.764678) (xy 2.509012 -85.764678) (xy 2.509012 -98.341434)
			(xy 261.733792 -98.341434) (xy 261.733792 -97.477834) (xy 261.734278 -97.450583) (xy 261.742034 -97.396635)
			(xy 261.757389 -97.34434) (xy 261.780031 -97.294763) (xy 261.809497 -97.248913) (xy 261.845188 -97.207722)
			(xy 261.886379 -97.172031) (xy 261.932229 -97.142565) (xy 261.981806 -97.119923) (xy 262.034101 -97.104568)
			(xy 262.088049 -97.096812) (xy 262.142551 -97.096812) (xy 262.196499 -97.104568) (xy 262.248794 -97.119923)
			(xy 262.298371 -97.142565) (xy 262.344221 -97.172031) (xy 262.385412 -97.207722) (xy 262.421103 -97.248913)
			(xy 262.450569 -97.294763) (xy 262.473211 -97.34434) (xy 262.488566 -97.396635) (xy 262.496322 -97.450583)
			(xy 262.496808 -97.477834) (xy 262.496808 -98.341434) (xy 262.496322 -98.368685) (xy 262.488566 -98.422633)
			(xy 262.473211 -98.474928) (xy 262.450569 -98.524505) (xy 262.421103 -98.570355) (xy 262.385412 -98.611546)
			(xy 262.344221 -98.647237) (xy 262.298371 -98.676703) (xy 262.248794 -98.699345) (xy 262.196499 -98.7147)
			(xy 262.142551 -98.722456) (xy 262.088049 -98.722456) (xy 262.034101 -98.7147) (xy 261.981806 -98.699345)
			(xy 261.932229 -98.676703) (xy 261.886379 -98.647237) (xy 261.845188 -98.611546) (xy 261.809497 -98.570355)
			(xy 261.780031 -98.524505) (xy 261.757389 -98.474928) (xy 261.742034 -98.422633) (xy 261.734278 -98.368685)
			(xy 261.733792 -98.341434) (xy 2.509012 -98.341434) (xy 2.509012 -106.40187) (xy 11.713464 -106.40187)
			(xy 11.713464 -105.53827) (xy 11.71395 -105.511001) (xy 11.721712 -105.457017) (xy 11.737077 -105.404687)
			(xy 11.759734 -105.355077) (xy 11.78922 -105.309196) (xy 11.824935 -105.267979) (xy 11.866152 -105.232264)
			(xy 11.912033 -105.202778) (xy 11.961643 -105.180121) (xy 12.013973 -105.164756) (xy 12.067957 -105.156994)
			(xy 12.122495 -105.156994) (xy 12.176479 -105.164756) (xy 12.228809 -105.180121) (xy 12.278419 -105.202778)
			(xy 12.3243 -105.232264) (xy 12.365517 -105.267979) (xy 12.401232 -105.309196) (xy 12.430718 -105.355077)
			(xy 12.453375 -105.404687) (xy 12.46874 -105.457017) (xy 12.476502 -105.511001) (xy 12.476988 -105.53827)
			(xy 12.476988 -105.664) (xy 15.57274 -105.664) (xy 15.57274 -104.8004) (xy 15.573226 -104.773131)
			(xy 15.580988 -104.719147) (xy 15.596353 -104.666817) (xy 15.61901 -104.617207) (xy 15.648496 -104.571326)
			(xy 15.684211 -104.530109) (xy 15.725428 -104.494394) (xy 15.771309 -104.464908) (xy 15.820919 -104.442251)
			(xy 15.873249 -104.426886) (xy 15.927233 -104.419124) (xy 15.981771 -104.419124) (xy 16.035755 -104.426886)
			(xy 16.088085 -104.442251) (xy 16.137695 -104.464908) (xy 16.183576 -104.494394) (xy 16.224793 -104.530109)
			(xy 16.260508 -104.571326) (xy 16.289994 -104.617207) (xy 16.312651 -104.666817) (xy 16.328016 -104.719147)
			(xy 16.335778 -104.773131) (xy 16.336264 -104.8004) (xy 16.336264 -105.664) (xy 16.335778 -105.691269)
			(xy 16.328016 -105.745253) (xy 16.312651 -105.797583) (xy 16.289994 -105.847193) (xy 16.260508 -105.893074)
			(xy 16.224793 -105.934291) (xy 16.183576 -105.970006) (xy 16.137695 -105.999492) (xy 16.088085 -106.022149)
			(xy 16.035755 -106.037514) (xy 15.981771 -106.045276) (xy 15.927233 -106.045276) (xy 15.873249 -106.037514)
			(xy 15.820919 -106.022149) (xy 15.771309 -105.999492) (xy 15.725428 -105.970006) (xy 15.684211 -105.934291)
			(xy 15.648496 -105.893074) (xy 15.61901 -105.847193) (xy 15.596353 -105.797583) (xy 15.580988 -105.745253)
			(xy 15.573226 -105.691269) (xy 15.57274 -105.664) (xy 12.476988 -105.664) (xy 12.476988 -106.40187)
			(xy 12.476502 -106.429139) (xy 12.46874 -106.483123) (xy 12.453375 -106.535453) (xy 12.430718 -106.585063)
			(xy 12.401232 -106.630944) (xy 12.365517 -106.672161) (xy 12.3243 -106.707876) (xy 12.278419 -106.737362)
			(xy 12.228809 -106.760019) (xy 12.176479 -106.775384) (xy 12.122495 -106.783146) (xy 12.067957 -106.783146)
			(xy 12.013973 -106.775384) (xy 11.961643 -106.760019) (xy 11.912033 -106.737362) (xy 11.866152 -106.707876)
			(xy 11.824935 -106.672161) (xy 11.78922 -106.630944) (xy 11.759734 -106.585063) (xy 11.737077 -106.535453)
			(xy 11.721712 -106.483123) (xy 11.71395 -106.429139) (xy 11.713464 -106.40187) (xy 2.509012 -106.40187)
			(xy 2.509012 -108.943971) (xy 11.292822 -108.943971) (xy 11.292822 -108.889469) (xy 11.300578 -108.835522)
			(xy 11.315933 -108.783228) (xy 11.338574 -108.733651) (xy 11.36804 -108.687801) (xy 11.403731 -108.646611)
			(xy 11.444921 -108.61092) (xy 11.490771 -108.581454) (xy 11.540348 -108.558813) (xy 11.592642 -108.543458)
			(xy 11.646589 -108.535702) (xy 11.67384 -108.535216) (xy 12.53744 -108.535216) (xy 12.564692 -108.535694)
			(xy 12.61864 -108.54345) (xy 12.670935 -108.558806) (xy 12.720513 -108.581447) (xy 12.766364 -108.610914)
			(xy 12.807554 -108.646606) (xy 12.843246 -108.687796) (xy 12.872713 -108.733647) (xy 12.895354 -108.783225)
			(xy 12.91071 -108.83552) (xy 12.918466 -108.889468) (xy 12.918466 -108.943972) (xy 12.918466 -108.943973)
			(xy 15.156389 -108.943973) (xy 15.156389 -108.889467) (xy 15.164146 -108.835517) (xy 15.179502 -108.783219)
			(xy 15.202145 -108.733639) (xy 15.231613 -108.687786) (xy 15.267307 -108.646594) (xy 15.308499 -108.610901)
			(xy 15.354353 -108.581433) (xy 15.403933 -108.558791) (xy 15.45623 -108.543435) (xy 15.510181 -108.535679)
			(xy 15.537434 -108.535216) (xy 16.401034 -108.535216) (xy 16.428285 -108.535694) (xy 16.482233 -108.543451)
			(xy 16.534528 -108.558807) (xy 16.584105 -108.581448) (xy 16.629956 -108.610915) (xy 16.671146 -108.646607)
			(xy 16.706837 -108.687798) (xy 16.707863 -108.689394) (xy 238.647224 -108.689394) (xy 238.647224 -107.825794)
			(xy 238.64771 -107.798525) (xy 238.655472 -107.744541) (xy 238.670837 -107.692211) (xy 238.693494 -107.642601)
			(xy 238.72298 -107.59672) (xy 238.758695 -107.555503) (xy 238.799912 -107.519788) (xy 238.845793 -107.490302)
			(xy 238.895403 -107.467645) (xy 238.947733 -107.45228) (xy 239.001717 -107.444518) (xy 239.056255 -107.444518)
			(xy 239.110239 -107.45228) (xy 239.162569 -107.467645) (xy 239.212179 -107.490302) (xy 239.25806 -107.519788)
			(xy 239.299277 -107.555503) (xy 239.334992 -107.59672) (xy 239.364478 -107.642601) (xy 239.387135 -107.692211)
			(xy 239.4025 -107.744541) (xy 239.410262 -107.798525) (xy 239.410748 -107.825794) (xy 239.410748 -108.689394)
			(xy 239.410262 -108.716663) (xy 239.4025 -108.770647) (xy 239.387135 -108.822977) (xy 239.364478 -108.872587)
			(xy 239.334992 -108.918468) (xy 239.299277 -108.959685) (xy 239.25806 -108.9954) (xy 239.212179 -109.024886)
			(xy 239.162569 -109.047543) (xy 239.110239 -109.062908) (xy 239.056255 -109.07067) (xy 239.001717 -109.07067)
			(xy 238.947733 -109.062908) (xy 238.895403 -109.047543) (xy 238.845793 -109.024886) (xy 238.799912 -108.9954)
			(xy 238.758695 -108.959685) (xy 238.72298 -108.918468) (xy 238.693494 -108.872587) (xy 238.670837 -108.822977)
			(xy 238.655472 -108.770647) (xy 238.64771 -108.716663) (xy 238.647224 -108.689394) (xy 16.707863 -108.689394)
			(xy 16.736304 -108.733648) (xy 16.758945 -108.783226) (xy 16.7743 -108.835521) (xy 16.782056 -108.889469)
			(xy 16.782056 -108.943971) (xy 16.7743 -108.997919) (xy 16.758945 -109.050214) (xy 16.736304 -109.099792)
			(xy 16.706837 -109.145642) (xy 16.671146 -109.186833) (xy 16.629956 -109.222525) (xy 16.584105 -109.251992)
			(xy 16.534528 -109.274633) (xy 16.482233 -109.289989) (xy 16.428285 -109.297746) (xy 16.401034 -109.298232)
			(xy 15.537434 -109.298232) (xy 15.510181 -109.297761) (xy 15.45623 -109.290005) (xy 15.403933 -109.274649)
			(xy 15.354353 -109.252007) (xy 15.308499 -109.222539) (xy 15.267307 -109.186846) (xy 15.231613 -109.145654)
			(xy 15.202145 -109.099801) (xy 15.179502 -109.050221) (xy 15.164146 -108.997923) (xy 15.156389 -108.943973)
			(xy 12.918466 -108.943973) (xy 12.91071 -108.99792) (xy 12.895354 -109.050215) (xy 12.872713 -109.099793)
			(xy 12.843246 -109.145644) (xy 12.807554 -109.186834) (xy 12.766364 -109.222526) (xy 12.720513 -109.251993)
			(xy 12.670935 -109.274634) (xy 12.61864 -109.28999) (xy 12.564692 -109.297746) (xy 12.53744 -109.298232)
			(xy 11.67384 -109.298232) (xy 11.646589 -109.297738) (xy 11.592642 -109.289982) (xy 11.540348 -109.274627)
			(xy 11.490771 -109.251986) (xy 11.444921 -109.22252) (xy 11.403731 -109.186829) (xy 11.36804 -109.145639)
			(xy 11.338574 -109.099789) (xy 11.315933 -109.050212) (xy 11.300578 -108.997918) (xy 11.292822 -108.943971)
			(xy 2.509012 -108.943971) (xy 2.509012 -109.550266) (xy 250.428546 -109.550266) (xy 250.428546 -109.495734)
			(xy 250.436306 -109.441757) (xy 250.451669 -109.389434) (xy 250.474321 -109.339829) (xy 250.503801 -109.293953)
			(xy 250.53951 -109.252739) (xy 250.580721 -109.217025) (xy 250.626594 -109.18754) (xy 250.676196 -109.164883)
			(xy 250.728518 -109.149515) (xy 250.782494 -109.141749) (xy 250.80976 -109.14126) (xy 251.67336 -109.14126)
			(xy 251.700634 -109.141677) (xy 251.754629 -109.149435) (xy 251.806969 -109.164798) (xy 251.85659 -109.187455)
			(xy 251.902482 -109.216943) (xy 251.943709 -109.252663) (xy 251.979433 -109.293886) (xy 252.008926 -109.339775)
			(xy 252.031588 -109.389393) (xy 252.046957 -109.441732) (xy 252.05472 -109.495726) (xy 252.05472 -109.550274)
			(xy 252.046957 -109.604268) (xy 252.031588 -109.656607) (xy 252.008926 -109.706225) (xy 251.979433 -109.752114)
			(xy 251.943709 -109.793337) (xy 251.902482 -109.829057) (xy 251.85659 -109.858545) (xy 251.806969 -109.881202)
			(xy 251.754629 -109.896565) (xy 251.700634 -109.904323) (xy 251.67336 -109.904784) (xy 250.80976 -109.904784)
			(xy 250.782494 -109.904251) (xy 250.728518 -109.896485) (xy 250.676196 -109.881117) (xy 250.626594 -109.85846)
			(xy 250.580721 -109.828975) (xy 250.53951 -109.793262) (xy 250.503801 -109.752047) (xy 250.474321 -109.706171)
			(xy 250.451669 -109.656566) (xy 250.436306 -109.604243) (xy 250.428546 -109.550266) (xy 2.509012 -109.550266)
			(xy 2.509012 -111.158274) (xy 239.40262 -111.158274) (xy 239.40262 -110.294674) (xy 239.403106 -110.267423)
			(xy 239.410862 -110.213475) (xy 239.426217 -110.16118) (xy 239.448859 -110.111603) (xy 239.478325 -110.065753)
			(xy 239.514016 -110.024562) (xy 239.555207 -109.988871) (xy 239.601057 -109.959405) (xy 239.650634 -109.936763)
			(xy 239.702929 -109.921408) (xy 239.756877 -109.913652) (xy 239.811379 -109.913652) (xy 239.865327 -109.921408)
			(xy 239.917622 -109.936763) (xy 239.967199 -109.959405) (xy 240.000574 -109.980854) (xy 256.88563 -109.980854)
			(xy 256.88563 -109.926346) (xy 256.893387 -109.872392) (xy 256.908744 -109.820091) (xy 256.931388 -109.770508)
			(xy 256.960857 -109.724652) (xy 256.996552 -109.683457) (xy 257.037747 -109.647761) (xy 257.083602 -109.61829)
			(xy 257.133185 -109.595646) (xy 257.185486 -109.580288) (xy 257.23944 -109.57253) (xy 257.266694 -109.572044)
			(xy 258.130294 -109.572044) (xy 258.157544 -109.572603) (xy 258.211488 -109.580358) (xy 258.26378 -109.595712)
			(xy 258.313355 -109.618351) (xy 258.359203 -109.647815) (xy 258.400391 -109.683504) (xy 258.436081 -109.724692)
			(xy 258.465546 -109.77054) (xy 258.488186 -109.820114) (xy 258.503541 -109.872406) (xy 258.511297 -109.92635)
			(xy 258.511297 -109.98085) (xy 258.503541 -110.034794) (xy 258.488186 -110.087086) (xy 258.465546 -110.13666)
			(xy 258.436081 -110.182508) (xy 258.400391 -110.223696) (xy 258.359203 -110.259385) (xy 258.313355 -110.288849)
			(xy 258.26378 -110.311488) (xy 258.211488 -110.326842) (xy 258.157544 -110.334597) (xy 258.130294 -110.33506)
			(xy 257.266694 -110.33506) (xy 257.23944 -110.33467) (xy 257.185486 -110.326912) (xy 257.133185 -110.311554)
			(xy 257.083602 -110.28891) (xy 257.037747 -110.259439) (xy 256.996552 -110.223743) (xy 256.960857 -110.182548)
			(xy 256.931388 -110.136692) (xy 256.908744 -110.087109) (xy 256.893387 -110.034808) (xy 256.88563 -109.980854)
			(xy 240.000574 -109.980854) (xy 240.013049 -109.988871) (xy 240.05424 -110.024562) (xy 240.089931 -110.065753)
			(xy 240.119397 -110.111603) (xy 240.142039 -110.16118) (xy 240.157394 -110.213475) (xy 240.16515 -110.267423)
			(xy 240.165636 -110.294674) (xy 240.165636 -111.158274) (xy 240.16515 -111.185525) (xy 240.157394 -111.239473)
			(xy 240.142039 -111.291768) (xy 240.119397 -111.341345) (xy 240.089931 -111.387195) (xy 240.05424 -111.428386)
			(xy 240.013049 -111.464077) (xy 239.967199 -111.493543) (xy 239.917622 -111.516185) (xy 239.865327 -111.53154)
			(xy 239.811379 -111.539296) (xy 239.756877 -111.539296) (xy 239.702929 -111.53154) (xy 239.650634 -111.516185)
			(xy 239.601057 -111.493543) (xy 239.555207 -111.464077) (xy 239.514016 -111.428386) (xy 239.478325 -111.387195)
			(xy 239.448859 -111.341345) (xy 239.426217 -111.291768) (xy 239.410862 -111.239473) (xy 239.403106 -111.185525)
			(xy 239.40262 -111.158274) (xy 2.509012 -111.158274) (xy 2.509012 -114.734161) (xy 11.255226 -114.734161)
			(xy 11.255226 -114.679659) (xy 11.262982 -114.625711) (xy 11.278337 -114.573416) (xy 11.300979 -114.523839)
			(xy 11.330445 -114.477988) (xy 11.366136 -114.436798) (xy 11.407326 -114.401106) (xy 11.453177 -114.371639)
			(xy 11.502754 -114.348998) (xy 11.555049 -114.333643) (xy 11.608997 -114.325886) (xy 11.636248 -114.3254)
			(xy 12.499848 -114.3254) (xy 12.527101 -114.325867) (xy 12.581052 -114.333624) (xy 12.633349 -114.34898)
			(xy 12.68293 -114.371622) (xy 12.728783 -114.40109) (xy 12.769975 -114.436783) (xy 12.805669 -114.477976)
			(xy 12.835137 -114.523829) (xy 12.85778 -114.573409) (xy 12.873136 -114.625706) (xy 12.880893 -114.679657)
			(xy 12.880893 -114.734163) (xy 12.873136 -114.788114) (xy 12.85778 -114.840411) (xy 12.835137 -114.889991)
			(xy 12.805669 -114.935844) (xy 12.769975 -114.977037) (xy 12.728783 -115.01273) (xy 12.68293 -115.042198)
			(xy 12.633349 -115.06484) (xy 12.581052 -115.080196) (xy 12.527101 -115.087953) (xy 12.499848 -115.088416)
			(xy 11.636248 -115.088416) (xy 11.608997 -115.087934) (xy 11.555049 -115.080177) (xy 11.502754 -115.064822)
			(xy 11.453177 -115.042181) (xy 11.407326 -115.012714) (xy 11.366136 -114.977022) (xy 11.330445 -114.935832)
			(xy 11.300979 -114.889981) (xy 11.278337 -114.840404) (xy 11.262982 -114.788109) (xy 11.255226 -114.734161)
			(xy 2.509012 -114.734161) (xy 2.509012 -116.393573) (xy 230.652992 -116.393573) (xy 230.652992 -116.339027)
			(xy 230.660755 -116.285035) (xy 230.676123 -116.232698) (xy 230.698784 -116.183081) (xy 230.728276 -116.137195)
			(xy 230.763998 -116.095973) (xy 230.805224 -116.060254) (xy 230.851113 -116.030767) (xy 230.900732 -116.008111)
			(xy 230.95307 -115.992747) (xy 231.007063 -115.984989) (xy 231.034336 -115.984528) (xy 231.897936 -115.984528)
			(xy 231.925203 -115.985037) (xy 231.979181 -115.992802) (xy 232.031505 -116.008171) (xy 232.081109 -116.030828)
			(xy 232.126985 -116.060314) (xy 232.168197 -116.096029) (xy 232.203907 -116.137244) (xy 232.233389 -116.183122)
			(xy 232.256042 -116.232729) (xy 232.271405 -116.285054) (xy 232.277026 -116.324151) (xy 236.866903 -116.324151)
			(xy 236.866903 -116.269649) (xy 236.87466 -116.215701) (xy 236.890016 -116.163407) (xy 236.912659 -116.113831)
			(xy 236.942127 -116.067981) (xy 236.97782 -116.026793) (xy 237.019012 -115.991104) (xy 237.064864 -115.961641)
			(xy 237.114443 -115.939003) (xy 237.166739 -115.923652) (xy 237.220687 -115.915901) (xy 237.247938 -115.91544)
			(xy 238.111538 -115.91544) (xy 238.138791 -115.915832) (xy 238.192741 -115.923594) (xy 238.245038 -115.938955)
			(xy 238.294617 -115.961601) (xy 238.340468 -115.991072) (xy 238.381659 -116.026768) (xy 238.417351 -116.067962)
			(xy 238.446817 -116.113817) (xy 238.469459 -116.163398) (xy 238.484814 -116.215696) (xy 238.49257 -116.269647)
			(xy 238.49257 -116.324153) (xy 238.484814 -116.378104) (xy 238.469459 -116.430402) (xy 238.446817 -116.479983)
			(xy 238.417351 -116.525838) (xy 238.381659 -116.567032) (xy 238.340468 -116.602728) (xy 238.294617 -116.632199)
			(xy 238.245038 -116.654845) (xy 238.192741 -116.670206) (xy 238.138791 -116.677968) (xy 238.111538 -116.678456)
			(xy 237.247938 -116.678456) (xy 237.220687 -116.677899) (xy 237.166739 -116.670148) (xy 237.114443 -116.654797)
			(xy 237.064864 -116.632159) (xy 237.019012 -116.602696) (xy 236.97782 -116.567007) (xy 236.942127 -116.525819)
			(xy 236.912659 -116.479969) (xy 236.890016 -116.430393) (xy 236.87466 -116.378099) (xy 236.866903 -116.324151)
			(xy 232.277026 -116.324151) (xy 232.279166 -116.339033) (xy 232.279166 -116.393567) (xy 232.271405 -116.447546)
			(xy 232.256042 -116.499871) (xy 232.233389 -116.549478) (xy 232.203907 -116.595356) (xy 232.168197 -116.636571)
			(xy 232.126985 -116.672286) (xy 232.081109 -116.701772) (xy 232.031505 -116.724429) (xy 231.979181 -116.739798)
			(xy 231.925203 -116.747563) (xy 231.897936 -116.748052) (xy 231.034336 -116.748052) (xy 231.007063 -116.747611)
			(xy 230.95307 -116.739853) (xy 230.900732 -116.724489) (xy 230.851113 -116.701833) (xy 230.805224 -116.672346)
			(xy 230.763998 -116.636627) (xy 230.728276 -116.595405) (xy 230.698784 -116.549519) (xy 230.676123 -116.499902)
			(xy 230.660755 -116.447565) (xy 230.652992 -116.393573) (xy 2.509012 -116.393573) (xy 2.509012 -117.632251)
			(xy 233.564903 -117.632251) (xy 233.564903 -117.577749) (xy 233.57266 -117.523801) (xy 233.588016 -117.471507)
			(xy 233.610659 -117.421931) (xy 233.640127 -117.376081) (xy 233.67582 -117.334893) (xy 233.717012 -117.299204)
			(xy 233.762864 -117.269741) (xy 233.812443 -117.247103) (xy 233.864739 -117.231752) (xy 233.918687 -117.224001)
			(xy 233.945938 -117.22354) (xy 234.809538 -117.22354) (xy 234.836791 -117.223932) (xy 234.890741 -117.231694)
			(xy 234.943038 -117.247055) (xy 234.992617 -117.269701) (xy 235.038468 -117.299172) (xy 235.079659 -117.334868)
			(xy 235.115351 -117.376062) (xy 235.144817 -117.421917) (xy 235.167459 -117.471498) (xy 235.182814 -117.523796)
			(xy 235.19057 -117.577747) (xy 235.19057 -117.632251) (xy 238.898903 -117.632251) (xy 238.898903 -117.577749)
			(xy 238.90666 -117.523801) (xy 238.922016 -117.471507) (xy 238.944659 -117.421931) (xy 238.974127 -117.376081)
			(xy 239.00982 -117.334893) (xy 239.051012 -117.299204) (xy 239.096864 -117.269741) (xy 239.146443 -117.247103)
			(xy 239.198739 -117.231752) (xy 239.252687 -117.224001) (xy 239.279938 -117.22354) (xy 240.143538 -117.22354)
			(xy 240.170791 -117.223932) (xy 240.224741 -117.231694) (xy 240.277038 -117.247055) (xy 240.326617 -117.269701)
			(xy 240.372468 -117.299172) (xy 240.413659 -117.334868) (xy 240.449351 -117.376062) (xy 240.478817 -117.421917)
			(xy 240.501459 -117.471498) (xy 240.516814 -117.523796) (xy 240.52457 -117.577747) (xy 240.52457 -117.632253)
			(xy 240.516814 -117.686204) (xy 240.501459 -117.738502) (xy 240.478817 -117.788083) (xy 240.449351 -117.833938)
			(xy 240.413659 -117.875132) (xy 240.372468 -117.910828) (xy 240.326617 -117.940299) (xy 240.277038 -117.962945)
			(xy 240.224741 -117.978306) (xy 240.170791 -117.986068) (xy 240.143538 -117.986556) (xy 239.279938 -117.986556)
			(xy 239.252687 -117.985999) (xy 239.198739 -117.978248) (xy 239.146443 -117.962897) (xy 239.096864 -117.940259)
			(xy 239.051012 -117.910796) (xy 239.00982 -117.875107) (xy 238.974127 -117.833919) (xy 238.944659 -117.788069)
			(xy 238.922016 -117.738493) (xy 238.90666 -117.686199) (xy 238.898903 -117.632251) (xy 235.19057 -117.632251)
			(xy 235.19057 -117.632253) (xy 235.182814 -117.686204) (xy 235.167459 -117.738502) (xy 235.144817 -117.788083)
			(xy 235.115351 -117.833938) (xy 235.079659 -117.875132) (xy 235.038468 -117.910828) (xy 234.992617 -117.940299)
			(xy 234.943038 -117.962945) (xy 234.890741 -117.978306) (xy 234.836791 -117.986068) (xy 234.809538 -117.986556)
			(xy 233.945938 -117.986556) (xy 233.918687 -117.985999) (xy 233.864739 -117.978248) (xy 233.812443 -117.962897)
			(xy 233.762864 -117.940259) (xy 233.717012 -117.910796) (xy 233.67582 -117.875107) (xy 233.640127 -117.833919)
			(xy 233.610659 -117.788069) (xy 233.588016 -117.738493) (xy 233.57266 -117.686199) (xy 233.564903 -117.632251)
			(xy 2.509012 -117.632251) (xy 2.509012 -123.093988) (xy 227.217732 -123.093988) (xy 227.217732 -122.230388)
			(xy 227.218218 -122.203137) (xy 227.225974 -122.149189) (xy 227.241329 -122.096894) (xy 227.263971 -122.047317)
			(xy 227.293437 -122.001467) (xy 227.329128 -121.960276) (xy 227.370319 -121.924585) (xy 227.416169 -121.895119)
			(xy 227.465746 -121.872477) (xy 227.518041 -121.857122) (xy 227.571989 -121.849366) (xy 227.626491 -121.849366)
			(xy 227.680439 -121.857122) (xy 227.732734 -121.872477) (xy 227.782311 -121.895119) (xy 227.828161 -121.924585)
			(xy 227.869352 -121.960276) (xy 227.905043 -122.001467) (xy 227.934509 -122.047317) (xy 227.957151 -122.096894)
			(xy 227.972506 -122.149189) (xy 227.980262 -122.203137) (xy 227.980748 -122.230388) (xy 227.980748 -122.921014)
			(xy 245.563136 -122.921014) (xy 245.563136 -122.057414) (xy 245.563622 -122.030163) (xy 245.571378 -121.976215)
			(xy 245.586733 -121.92392) (xy 245.609375 -121.874343) (xy 245.638841 -121.828493) (xy 245.674532 -121.787302)
			(xy 245.715723 -121.751611) (xy 245.761573 -121.722145) (xy 245.81115 -121.699503) (xy 245.863445 -121.684148)
			(xy 245.917393 -121.676392) (xy 245.971895 -121.676392) (xy 246.025843 -121.684148) (xy 246.078138 -121.699503)
			(xy 246.127715 -121.722145) (xy 246.173565 -121.751611) (xy 246.214756 -121.787302) (xy 246.250447 -121.828493)
			(xy 246.279913 -121.874343) (xy 246.302555 -121.92392) (xy 246.31791 -121.976215) (xy 246.325666 -122.030163)
			(xy 246.326152 -122.057414) (xy 246.326152 -122.921014) (xy 246.325666 -122.948265) (xy 246.31791 -123.002213)
			(xy 246.302555 -123.054508) (xy 246.279913 -123.104085) (xy 246.250447 -123.149935) (xy 246.214756 -123.191126)
			(xy 246.173565 -123.226817) (xy 246.127715 -123.256283) (xy 246.078138 -123.278925) (xy 246.025843 -123.29428)
			(xy 245.971895 -123.302036) (xy 245.917393 -123.302036) (xy 245.863445 -123.29428) (xy 245.81115 -123.278925)
			(xy 245.761573 -123.256283) (xy 245.715723 -123.226817) (xy 245.674532 -123.191126) (xy 245.638841 -123.149935)
			(xy 245.609375 -123.104085) (xy 245.586733 -123.054508) (xy 245.571378 -123.002213) (xy 245.563622 -122.948265)
			(xy 245.563136 -122.921014) (xy 227.980748 -122.921014) (xy 227.980748 -123.093988) (xy 227.980262 -123.121239)
			(xy 227.972506 -123.175187) (xy 227.957151 -123.227482) (xy 227.934509 -123.277059) (xy 227.905043 -123.322909)
			(xy 227.869352 -123.3641) (xy 227.828161 -123.399791) (xy 227.782311 -123.429257) (xy 227.732734 -123.451899)
			(xy 227.680439 -123.467254) (xy 227.626491 -123.47501) (xy 227.571989 -123.47501) (xy 227.518041 -123.467254)
			(xy 227.465746 -123.451899) (xy 227.416169 -123.429257) (xy 227.370319 -123.399791) (xy 227.329128 -123.3641)
			(xy 227.293437 -123.322909) (xy 227.263971 -123.277059) (xy 227.241329 -123.227482) (xy 227.225974 -123.175187)
			(xy 227.218218 -123.121239) (xy 227.217732 -123.093988) (xy 2.509012 -123.093988) (xy 2.509012 -125.221746)
			(xy 225.535744 -125.221746) (xy 225.535744 -124.358146) (xy 225.53623 -124.330877) (xy 225.543992 -124.276893)
			(xy 225.559357 -124.224563) (xy 225.582014 -124.174953) (xy 225.6115 -124.129072) (xy 225.647215 -124.087855)
			(xy 225.688432 -124.05214) (xy 225.734313 -124.022654) (xy 225.783923 -123.999997) (xy 225.836253 -123.984632)
			(xy 225.890237 -123.97687) (xy 225.944775 -123.97687) (xy 225.998759 -123.984632) (xy 226.051089 -123.999997)
			(xy 226.100699 -124.022654) (xy 226.14658 -124.05214) (xy 226.187797 -124.087855) (xy 226.223512 -124.129072)
			(xy 226.252998 -124.174953) (xy 226.275655 -124.224563) (xy 226.29102 -124.276893) (xy 226.298782 -124.330877)
			(xy 226.299268 -124.358146) (xy 226.299268 -125.221746) (xy 226.298782 -125.249015) (xy 226.29102 -125.302999)
			(xy 226.275655 -125.355329) (xy 226.252998 -125.404939) (xy 226.223512 -125.45082) (xy 226.187797 -125.492037)
			(xy 226.14658 -125.527752) (xy 226.100699 -125.557238) (xy 226.051089 -125.579895) (xy 225.998759 -125.59526)
			(xy 225.944775 -125.603022) (xy 225.890237 -125.603022) (xy 225.836253 -125.59526) (xy 225.783923 -125.579895)
			(xy 225.734313 -125.557238) (xy 225.688432 -125.527752) (xy 225.647215 -125.492037) (xy 225.6115 -125.45082)
			(xy 225.582014 -125.404939) (xy 225.559357 -125.355329) (xy 225.543992 -125.302999) (xy 225.53623 -125.249015)
			(xy 225.535744 -125.221746) (xy 2.509012 -125.221746) (xy 2.509012 -127.325628) (xy 227.034852 -127.325628)
			(xy 227.034852 -126.462028) (xy 227.035338 -126.434777) (xy 227.043094 -126.380829) (xy 227.058449 -126.328534)
			(xy 227.081091 -126.278957) (xy 227.110557 -126.233107) (xy 227.146248 -126.191916) (xy 227.187439 -126.156225)
			(xy 227.233289 -126.126759) (xy 227.282866 -126.104117) (xy 227.335161 -126.088762) (xy 227.389109 -126.081006)
			(xy 227.443611 -126.081006) (xy 227.497559 -126.088762) (xy 227.549854 -126.104117) (xy 227.599431 -126.126759)
			(xy 227.645281 -126.156225) (xy 227.686472 -126.191916) (xy 227.722163 -126.233107) (xy 227.751629 -126.278957)
			(xy 227.774271 -126.328534) (xy 227.789626 -126.380829) (xy 227.797382 -126.434777) (xy 227.797868 -126.462028)
			(xy 227.797868 -127.140208) (xy 242.041172 -127.140208) (xy 242.041172 -126.276608) (xy 242.041658 -126.249357)
			(xy 242.049414 -126.195409) (xy 242.064769 -126.143114) (xy 242.087411 -126.093537) (xy 242.116877 -126.047687)
			(xy 242.152568 -126.006496) (xy 242.193759 -125.970805) (xy 242.239609 -125.941339) (xy 242.289186 -125.918697)
			(xy 242.341481 -125.903342) (xy 242.395429 -125.895586) (xy 242.449931 -125.895586) (xy 242.503879 -125.903342)
			(xy 242.556174 -125.918697) (xy 242.605751 -125.941339) (xy 242.651601 -125.970805) (xy 242.692792 -126.006496)
			(xy 242.728483 -126.047687) (xy 242.757949 -126.093537) (xy 242.780591 -126.143114) (xy 242.795946 -126.195409)
			(xy 242.803702 -126.249357) (xy 242.804188 -126.276608) (xy 242.804188 -127.140208) (xy 242.803702 -127.167459)
			(xy 242.795946 -127.221407) (xy 242.780591 -127.273702) (xy 242.757949 -127.323279) (xy 242.728483 -127.369129)
			(xy 242.692792 -127.41032) (xy 242.651601 -127.446011) (xy 242.605751 -127.475477) (xy 242.556174 -127.498119)
			(xy 242.503879 -127.513474) (xy 242.449931 -127.52123) (xy 242.395429 -127.52123) (xy 242.341481 -127.513474)
			(xy 242.289186 -127.498119) (xy 242.239609 -127.475477) (xy 242.193759 -127.446011) (xy 242.152568 -127.41032)
			(xy 242.116877 -127.369129) (xy 242.087411 -127.323279) (xy 242.064769 -127.273702) (xy 242.049414 -127.221407)
			(xy 242.041658 -127.167459) (xy 242.041172 -127.140208) (xy 227.797868 -127.140208) (xy 227.797868 -127.325628)
			(xy 227.797382 -127.352879) (xy 227.789626 -127.406827) (xy 227.774271 -127.459122) (xy 227.751629 -127.508699)
			(xy 227.722163 -127.554549) (xy 227.686472 -127.59574) (xy 227.645281 -127.631431) (xy 227.599431 -127.660897)
			(xy 227.549854 -127.683539) (xy 227.519478 -127.692458) (xy 458.401155 -127.692458) (xy 458.401155 -127.563318)
			(xy 458.409105 -127.434423) (xy 458.424975 -127.306263) (xy 458.448704 -127.179322) (xy 458.480203 -127.054083)
			(xy 458.519352 -126.93102) (xy 458.566003 -126.810601) (xy 458.619978 -126.693282) (xy 458.681073 -126.579508)
			(xy 458.749056 -126.469711) (xy 458.82367 -126.364308) (xy 458.904631 -126.263698) (xy 458.991631 -126.168263)
			(xy 459.084342 -126.078364) (xy 459.182412 -125.994343) (xy 459.285467 -125.916519) (xy 459.393118 -125.845187)
			(xy 459.504957 -125.780617) (xy 459.620558 -125.723055) (xy 459.739483 -125.672718) (xy 459.861282 -125.629798)
			(xy 459.985492 -125.594457) (xy 460.111641 -125.56683) (xy 460.239253 -125.547021) (xy 460.367842 -125.535105)
			(xy 460.49692 -125.531129) (xy 460.625998 -125.535105) (xy 460.754587 -125.547021) (xy 460.882199 -125.56683)
			(xy 461.008348 -125.594457) (xy 461.132558 -125.629798) (xy 461.254357 -125.672718) (xy 461.373282 -125.723055)
			(xy 461.488883 -125.780617) (xy 461.600722 -125.845187) (xy 461.708373 -125.916519) (xy 461.811428 -125.994343)
			(xy 461.909498 -126.078364) (xy 462.002209 -126.168263) (xy 462.089209 -126.263698) (xy 462.17017 -126.364308)
			(xy 462.244784 -126.469711) (xy 462.312767 -126.579508) (xy 462.373862 -126.693282) (xy 462.427837 -126.810601)
			(xy 462.474488 -126.93102) (xy 462.513637 -127.054083) (xy 462.545136 -127.179322) (xy 462.568865 -127.306263)
			(xy 462.584735 -127.434423) (xy 462.592685 -127.563318) (xy 462.593182 -127.627888) (xy 462.592685 -127.692458)
			(xy 462.584735 -127.821353) (xy 462.568865 -127.949513) (xy 462.545136 -128.076454) (xy 462.513637 -128.201693)
			(xy 462.474488 -128.324756) (xy 462.427837 -128.445175) (xy 462.373862 -128.562494) (xy 462.312767 -128.676268)
			(xy 462.244784 -128.786065) (xy 462.17017 -128.891468) (xy 462.089209 -128.992078) (xy 462.002209 -129.087513)
			(xy 461.909498 -129.177412) (xy 461.811428 -129.261433) (xy 461.708373 -129.339257) (xy 461.600722 -129.410589)
			(xy 461.488883 -129.475159) (xy 461.373282 -129.532721) (xy 461.254357 -129.583058) (xy 461.132558 -129.625978)
			(xy 461.008348 -129.661319) (xy 460.882199 -129.688946) (xy 460.754587 -129.708755) (xy 460.625998 -129.720671)
			(xy 460.49692 -129.724648) (xy 460.367842 -129.720671) (xy 460.239253 -129.708755) (xy 460.111641 -129.688946)
			(xy 459.985492 -129.661319) (xy 459.861282 -129.625978) (xy 459.739483 -129.583058) (xy 459.620558 -129.532721)
			(xy 459.504957 -129.475159) (xy 459.393118 -129.410589) (xy 459.285467 -129.339257) (xy 459.182412 -129.261433)
			(xy 459.084342 -129.177412) (xy 458.991631 -129.087513) (xy 458.904631 -128.992078) (xy 458.82367 -128.891468)
			(xy 458.749056 -128.786065) (xy 458.681073 -128.676268) (xy 458.619978 -128.562494) (xy 458.566003 -128.445175)
			(xy 458.519352 -128.324756) (xy 458.480203 -128.201693) (xy 458.448704 -128.076454) (xy 458.424975 -127.949513)
			(xy 458.409105 -127.821353) (xy 458.401155 -127.692458) (xy 227.519478 -127.692458) (xy 227.497559 -127.698894)
			(xy 227.443611 -127.70665) (xy 227.389109 -127.70665) (xy 227.335161 -127.698894) (xy 227.282866 -127.683539)
			(xy 227.233289 -127.660897) (xy 227.187439 -127.631431) (xy 227.146248 -127.59574) (xy 227.110557 -127.554549)
			(xy 227.081091 -127.508699) (xy 227.058449 -127.459122) (xy 227.043094 -127.406827) (xy 227.035338 -127.352879)
			(xy 227.034852 -127.325628) (xy 2.509012 -127.325628) (xy 2.509012 -129.073148) (xy 223.562672 -129.073148)
			(xy 223.562672 -128.209548) (xy 223.563115 -128.182788) (xy 223.570596 -128.129795) (xy 223.585403 -128.078365)
			(xy 223.607247 -128.029506) (xy 223.621092 -128.006602) (xy 223.636032 -127.983032) (xy 223.671662 -127.940084)
			(xy 223.713174 -127.902792) (xy 223.759681 -127.871951) (xy 223.810187 -127.848221) (xy 223.863614 -127.832109)
			(xy 223.918819 -127.823961) (xy 223.94672 -127.823468) (xy 223.973934 -127.823967) (xy 224.027808 -127.831715)
			(xy 224.080031 -127.84705) (xy 224.12954 -127.869661) (xy 224.175327 -127.899088) (xy 224.216462 -127.93473)
			(xy 224.252105 -127.975863) (xy 224.281533 -128.02165) (xy 224.304145 -128.071158) (xy 224.319483 -128.123381)
			(xy 224.327232 -128.177254) (xy 224.32772 -128.204468) (xy 224.32772 -128.204722) (xy 224.325942 -128.241552)
			(xy 224.325688 -128.243838) (xy 224.325688 -129.019808) (xy 240.086896 -129.019808) (xy 240.086896 -128.156208)
			(xy 240.087382 -128.128939) (xy 240.095144 -128.074955) (xy 240.110509 -128.022625) (xy 240.133166 -127.973015)
			(xy 240.162652 -127.927134) (xy 240.198367 -127.885917) (xy 240.239584 -127.850202) (xy 240.285465 -127.820716)
			(xy 240.335075 -127.798059) (xy 240.387405 -127.782694) (xy 240.441389 -127.774932) (xy 240.495927 -127.774932)
			(xy 240.549911 -127.782694) (xy 240.602241 -127.798059) (xy 240.651851 -127.820716) (xy 240.697732 -127.850202)
			(xy 240.738949 -127.885917) (xy 240.774664 -127.927134) (xy 240.80415 -127.973015) (xy 240.826807 -128.022625)
			(xy 240.842172 -128.074955) (xy 240.849934 -128.128939) (xy 240.85042 -128.156208) (xy 240.85042 -129.019808)
			(xy 240.849934 -129.047077) (xy 240.842172 -129.101061) (xy 240.826807 -129.153391) (xy 240.80415 -129.203001)
			(xy 240.774664 -129.248882) (xy 240.738949 -129.290099) (xy 240.697732 -129.325814) (xy 240.651851 -129.3553)
			(xy 240.602241 -129.377957) (xy 240.549911 -129.393322) (xy 240.495927 -129.401084) (xy 240.441389 -129.401084)
			(xy 240.387405 -129.393322) (xy 240.335075 -129.377957) (xy 240.285465 -129.3553) (xy 240.239584 -129.325814)
			(xy 240.198367 -129.290099) (xy 240.162652 -129.248882) (xy 240.133166 -129.203001) (xy 240.110509 -129.153391)
			(xy 240.095144 -129.101061) (xy 240.087382 -129.047077) (xy 240.086896 -129.019808) (xy 224.325688 -129.019808)
			(xy 224.325942 -129.022602) (xy 224.327226 -129.033861) (xy 224.328622 -129.056482) (xy 224.328736 -129.067814)
			(xy 224.328736 -129.068068) (xy 224.328226 -129.095352) (xy 224.320425 -129.14936) (xy 224.305035 -129.201713)
			(xy 224.282367 -129.251351) (xy 224.26803 -129.27457) (xy 224.253042 -129.297814) (xy 224.217376 -129.340083)
			(xy 224.175977 -129.376756) (xy 224.129714 -129.407061) (xy 224.079557 -129.430365) (xy 224.026559 -129.446176)
			(xy 223.971833 -129.454165) (xy 223.94418 -129.454656) (xy 223.91693 -129.454141) (xy 223.862986 -129.446383)
			(xy 223.810695 -129.431028) (xy 223.761121 -129.408388) (xy 223.715273 -129.378924) (xy 223.674084 -129.343236)
			(xy 223.638393 -129.30205) (xy 223.608926 -129.256204) (xy 223.586282 -129.206631) (xy 223.570923 -129.154341)
			(xy 223.563161 -129.100398) (xy 223.562672 -129.073148) (xy 2.509012 -129.073148) (xy 2.509012 -131.09702)
			(xy 228.682804 -131.09702) (xy 228.682804 -130.23342) (xy 228.68329 -130.206151) (xy 228.691052 -130.152167)
			(xy 228.706417 -130.099837) (xy 228.729074 -130.050227) (xy 228.75856 -130.004346) (xy 228.794275 -129.963129)
			(xy 228.835492 -129.927414) (xy 228.881373 -129.897928) (xy 228.930983 -129.875271) (xy 228.983313 -129.859906)
			(xy 229.037297 -129.852144) (xy 229.091835 -129.852144) (xy 229.145819 -129.859906) (xy 229.198149 -129.875271)
			(xy 229.247759 -129.897928) (xy 229.29364 -129.927414) (xy 229.334857 -129.963129) (xy 229.370572 -130.004346)
			(xy 229.400058 -130.050227) (xy 229.422715 -130.099837) (xy 229.43808 -130.152167) (xy 229.445842 -130.206151)
			(xy 229.446328 -130.23342) (xy 229.446328 -130.721608) (xy 242.041172 -130.721608) (xy 242.041172 -129.858008)
			(xy 242.041658 -129.830757) (xy 242.049414 -129.776809) (xy 242.064769 -129.724514) (xy 242.087411 -129.674937)
			(xy 242.116877 -129.629087) (xy 242.152568 -129.587896) (xy 242.193759 -129.552205) (xy 242.239609 -129.522739)
			(xy 242.289186 -129.500097) (xy 242.341481 -129.484742) (xy 242.395429 -129.476986) (xy 242.449931 -129.476986)
			(xy 242.503879 -129.484742) (xy 242.556174 -129.500097) (xy 242.605751 -129.522739) (xy 242.651601 -129.552205)
			(xy 242.692792 -129.587896) (xy 242.728483 -129.629087) (xy 242.757949 -129.674937) (xy 242.780591 -129.724514)
			(xy 242.795946 -129.776809) (xy 242.803702 -129.830757) (xy 242.804188 -129.858008) (xy 242.804188 -130.721608)
			(xy 242.803702 -130.748859) (xy 242.795946 -130.802807) (xy 242.780591 -130.855102) (xy 242.757949 -130.904679)
			(xy 242.728483 -130.950529) (xy 242.692792 -130.99172) (xy 242.651601 -131.027411) (xy 242.605751 -131.056877)
			(xy 242.556174 -131.079519) (xy 242.503879 -131.094874) (xy 242.449931 -131.10263) (xy 242.395429 -131.10263)
			(xy 242.341481 -131.094874) (xy 242.289186 -131.079519) (xy 242.239609 -131.056877) (xy 242.193759 -131.027411)
			(xy 242.152568 -130.99172) (xy 242.116877 -130.950529) (xy 242.087411 -130.904679) (xy 242.064769 -130.855102)
			(xy 242.049414 -130.802807) (xy 242.041658 -130.748859) (xy 242.041172 -130.721608) (xy 229.446328 -130.721608)
			(xy 229.446328 -131.09702) (xy 229.445842 -131.124289) (xy 229.43808 -131.178273) (xy 229.422715 -131.230603)
			(xy 229.400058 -131.280213) (xy 229.370572 -131.326094) (xy 229.334857 -131.367311) (xy 229.29364 -131.403026)
			(xy 229.247759 -131.432512) (xy 229.198149 -131.455169) (xy 229.145819 -131.470534) (xy 229.091835 -131.478296)
			(xy 229.037297 -131.478296) (xy 228.983313 -131.470534) (xy 228.930983 -131.455169) (xy 228.881373 -131.432512)
			(xy 228.835492 -131.403026) (xy 228.794275 -131.367311) (xy 228.75856 -131.326094) (xy 228.729074 -131.280213)
			(xy 228.706417 -131.230603) (xy 228.691052 -131.178273) (xy 228.68329 -131.124289) (xy 228.682804 -131.09702)
			(xy 2.509012 -131.09702) (xy 2.509012 -132.529347) (xy 231.621126 -132.529347) (xy 231.621126 -132.474853)
			(xy 231.628881 -132.420915) (xy 231.644233 -132.368628) (xy 231.666869 -132.319059) (xy 231.69633 -132.273216)
			(xy 231.732014 -132.232031) (xy 231.773196 -132.196344) (xy 231.819038 -132.166881) (xy 231.868606 -132.144241)
			(xy 231.920891 -132.128886) (xy 231.974829 -132.121128) (xy 232.002076 -132.12064) (xy 232.865676 -132.12064)
			(xy 232.892933 -132.121005) (xy 232.946894 -132.128761) (xy 232.999201 -132.144116) (xy 233.048791 -132.16676)
			(xy 233.094653 -132.196231) (xy 233.135853 -132.23193) (xy 233.171554 -132.273128) (xy 233.201028 -132.318988)
			(xy 233.223675 -132.368576) (xy 233.239034 -132.420883) (xy 233.246793 -132.474843) (xy 233.246793 -132.529357)
			(xy 233.239034 -132.583317) (xy 233.223675 -132.635624) (xy 233.201028 -132.685212) (xy 233.171554 -132.731072)
			(xy 233.135853 -132.77227) (xy 233.094653 -132.807968) (xy 233.048791 -132.83744) (xy 232.999201 -132.860084)
			(xy 232.946894 -132.875439) (xy 232.892933 -132.883195) (xy 232.865676 -132.883656) (xy 232.002076 -132.883656)
			(xy 231.974829 -132.883072) (xy 231.920891 -132.875314) (xy 231.868606 -132.859959) (xy 231.819038 -132.837319)
			(xy 231.773196 -132.807856) (xy 231.732014 -132.772169) (xy 231.69633 -132.730984) (xy 231.666869 -132.685141)
			(xy 231.644233 -132.635572) (xy 231.628881 -132.583285) (xy 231.621126 -132.529347) (xy 2.509012 -132.529347)
			(xy 2.509012 -135.31065) (xy 225.204003 -135.31065) (xy 225.204003 -135.25615) (xy 225.21176 -135.202204)
			(xy 225.227115 -135.149911) (xy 225.249756 -135.100336) (xy 225.279222 -135.054487) (xy 225.314914 -135.013299)
			(xy 225.356103 -134.97761) (xy 225.401953 -134.948146) (xy 225.45153 -134.925508) (xy 225.503823 -134.910156)
			(xy 225.55777 -134.902402) (xy 225.58502 -134.90194) (xy 226.44862 -134.90194) (xy 226.475874 -134.902331)
			(xy 226.529826 -134.910091) (xy 226.582125 -134.92545) (xy 226.631706 -134.948095) (xy 226.67756 -134.977566)
			(xy 226.718753 -135.013262) (xy 226.754446 -135.054456) (xy 226.755856 -135.05665) (xy 228.531403 -135.05665)
			(xy 228.531403 -135.00215) (xy 228.53916 -134.948204) (xy 228.554515 -134.895911) (xy 228.577156 -134.846336)
			(xy 228.606622 -134.800487) (xy 228.642314 -134.759299) (xy 228.683503 -134.72361) (xy 228.729353 -134.694146)
			(xy 228.77893 -134.671508) (xy 228.831223 -134.656156) (xy 228.88517 -134.648402) (xy 228.91242 -134.64794)
			(xy 229.77602 -134.64794) (xy 229.803274 -134.648331) (xy 229.857226 -134.656091) (xy 229.909525 -134.67145)
			(xy 229.959106 -134.694095) (xy 230.00496 -134.723566) (xy 230.046153 -134.759262) (xy 230.081846 -134.800456)
			(xy 230.111315 -134.846312) (xy 230.133957 -134.895894) (xy 230.149313 -134.948193) (xy 230.15707 -135.002146)
			(xy 230.15707 -135.056654) (xy 230.149313 -135.110607) (xy 230.145996 -135.121904) (xy 234.029504 -135.121904)
			(xy 234.029504 -134.258304) (xy 234.02999 -134.231035) (xy 234.037752 -134.177051) (xy 234.053117 -134.124721)
			(xy 234.075774 -134.075111) (xy 234.10526 -134.02923) (xy 234.140975 -133.988013) (xy 234.182192 -133.952298)
			(xy 234.228073 -133.922812) (xy 234.277683 -133.900155) (xy 234.330013 -133.88479) (xy 234.383997 -133.877028)
			(xy 234.438535 -133.877028) (xy 234.492519 -133.88479) (xy 234.544849 -133.900155) (xy 234.594459 -133.922812)
			(xy 234.64034 -133.952298) (xy 234.681557 -133.988013) (xy 234.717272 -134.02923) (xy 234.746758 -134.075111)
			(xy 234.769415 -134.124721) (xy 234.78478 -134.177051) (xy 234.792542 -134.231035) (xy 234.793028 -134.258304)
			(xy 234.793028 -134.768971) (xy 236.02439 -134.768971) (xy 236.02439 -134.714429) (xy 236.032152 -134.660443)
			(xy 236.047518 -134.608111) (xy 236.070174 -134.558498) (xy 236.09966 -134.512615) (xy 236.135376 -134.471394)
			(xy 236.176594 -134.435676) (xy 236.222475 -134.406186) (xy 236.272087 -134.383527) (xy 236.324418 -134.368158)
			(xy 236.378403 -134.360392) (xy 236.405674 -134.359904) (xy 237.178342 -134.359904) (xy 237.205607 -134.360461)
			(xy 237.259581 -134.368227) (xy 237.311901 -134.383595) (xy 237.361502 -134.406251) (xy 237.407373 -134.435736)
			(xy 237.448582 -134.471448) (xy 237.48429 -134.512661) (xy 237.513769 -134.558535) (xy 237.53642 -134.608138)
			(xy 237.551782 -134.66046) (xy 237.559542 -134.714435) (xy 237.559542 -134.768965) (xy 237.551782 -134.82294)
			(xy 237.53642 -134.875262) (xy 237.513769 -134.924865) (xy 237.48429 -134.970739) (xy 237.448582 -135.011952)
			(xy 237.407373 -135.047664) (xy 237.361502 -135.077149) (xy 237.311901 -135.099805) (xy 237.259581 -135.115173)
			(xy 237.205607 -135.122939) (xy 237.178342 -135.123428) (xy 236.405674 -135.123428) (xy 236.378403 -135.123008)
			(xy 236.324418 -135.115242) (xy 236.272087 -135.099873) (xy 236.222475 -135.077214) (xy 236.176594 -135.047724)
			(xy 236.135376 -135.012006) (xy 236.09966 -134.970785) (xy 236.070174 -134.924902) (xy 236.047518 -134.875289)
			(xy 236.032152 -134.822957) (xy 236.02439 -134.768971) (xy 234.793028 -134.768971) (xy 234.793028 -135.121904)
			(xy 234.792542 -135.149173) (xy 234.786383 -135.192008) (xy 238.645192 -135.192008) (xy 238.645192 -134.328408)
			(xy 238.645678 -134.301157) (xy 238.653434 -134.247209) (xy 238.668789 -134.194914) (xy 238.691431 -134.145337)
			(xy 238.720897 -134.099487) (xy 238.756588 -134.058296) (xy 238.797779 -134.022605) (xy 238.843629 -133.993139)
			(xy 238.893206 -133.970497) (xy 238.945501 -133.955142) (xy 238.999449 -133.947386) (xy 239.053951 -133.947386)
			(xy 239.107899 -133.955142) (xy 239.160194 -133.970497) (xy 239.209771 -133.993139) (xy 239.255621 -134.022605)
			(xy 239.271831 -134.036651) (xy 242.034062 -134.036651) (xy 242.034062 -133.982149) (xy 242.041817 -133.928203)
			(xy 242.057171 -133.875909) (xy 242.07981 -133.826333) (xy 242.109274 -133.780482) (xy 242.144963 -133.739291)
			(xy 242.18615 -133.703598) (xy 242.231997 -133.67413) (xy 242.281572 -133.651485) (xy 242.333864 -133.636126)
			(xy 242.387809 -133.628365) (xy 242.41506 -133.627876) (xy 243.27866 -133.627876) (xy 243.305914 -133.628369)
			(xy 243.359867 -133.636121) (xy 243.412167 -133.651473) (xy 243.46175 -133.674112) (xy 243.507606 -133.703577)
			(xy 243.548802 -133.73927) (xy 243.584499 -133.780462) (xy 243.613969 -133.826315) (xy 243.636613 -133.875895)
			(xy 243.651971 -133.928194) (xy 243.659729 -133.982146) (xy 243.659729 -134.036654) (xy 243.651971 -134.090606)
			(xy 243.636613 -134.142905) (xy 243.613969 -134.192485) (xy 243.584499 -134.238338) (xy 243.548802 -134.27953)
			(xy 243.507606 -134.315223) (xy 243.46175 -134.344688) (xy 243.412167 -134.367327) (xy 243.359867 -134.382679)
			(xy 243.305914 -134.390431) (xy 243.27866 -134.390892) (xy 242.41506 -134.390892) (xy 242.387809 -134.390435)
			(xy 242.333864 -134.382674) (xy 242.281572 -134.367315) (xy 242.231997 -134.34467) (xy 242.18615 -134.315202)
			(xy 242.144963 -134.279509) (xy 242.109274 -134.238318) (xy 242.07981 -134.192467) (xy 242.057171 -134.142891)
			(xy 242.041817 -134.090597) (xy 242.034062 -134.036651) (xy 239.271831 -134.036651) (xy 239.296812 -134.058296)
			(xy 239.332503 -134.099487) (xy 239.361969 -134.145337) (xy 239.384611 -134.194914) (xy 239.399966 -134.247209)
			(xy 239.407722 -134.301157) (xy 239.408208 -134.328408) (xy 239.408208 -135.192008) (xy 239.407722 -135.219259)
			(xy 239.399966 -135.273207) (xy 239.384611 -135.325502) (xy 239.361969 -135.375079) (xy 239.332503 -135.420929)
			(xy 239.296812 -135.46212) (xy 239.255621 -135.497811) (xy 239.250425 -135.50115) (xy 244.457203 -135.50115)
			(xy 244.457203 -135.44665) (xy 244.46496 -135.392704) (xy 244.480315 -135.340411) (xy 244.502956 -135.290836)
			(xy 244.532422 -135.244987) (xy 244.568114 -135.203799) (xy 244.609303 -135.16811) (xy 244.655153 -135.138646)
			(xy 244.70473 -135.116008) (xy 244.757023 -135.100656) (xy 244.81097 -135.092902) (xy 244.83822 -135.09244)
			(xy 245.70182 -135.09244) (xy 245.729074 -135.092831) (xy 245.783026 -135.100591) (xy 245.835325 -135.11595)
			(xy 245.884906 -135.138595) (xy 245.93076 -135.168066) (xy 245.971953 -135.203762) (xy 246.007646 -135.244956)
			(xy 246.037115 -135.290812) (xy 246.059757 -135.340394) (xy 246.075113 -135.392693) (xy 246.08287 -135.446646)
			(xy 246.08287 -135.501154) (xy 246.075113 -135.555107) (xy 246.059757 -135.607406) (xy 246.037115 -135.656988)
			(xy 246.007646 -135.702844) (xy 245.971953 -135.744038) (xy 245.93076 -135.779734) (xy 245.884906 -135.809205)
			(xy 245.835325 -135.83185) (xy 245.783026 -135.847209) (xy 245.729074 -135.854969) (xy 245.70182 -135.855456)
			(xy 244.83822 -135.855456) (xy 244.81097 -135.854898) (xy 244.757023 -135.847144) (xy 244.70473 -135.831792)
			(xy 244.655153 -135.809154) (xy 244.609303 -135.77969) (xy 244.568114 -135.744001) (xy 244.532422 -135.702813)
			(xy 244.502956 -135.656964) (xy 244.480315 -135.607389) (xy 244.46496 -135.555096) (xy 244.457203 -135.50115)
			(xy 239.250425 -135.50115) (xy 239.209771 -135.527277) (xy 239.160194 -135.549919) (xy 239.107899 -135.565274)
			(xy 239.053951 -135.57303) (xy 238.999449 -135.57303) (xy 238.945501 -135.565274) (xy 238.893206 -135.549919)
			(xy 238.843629 -135.527277) (xy 238.797779 -135.497811) (xy 238.756588 -135.46212) (xy 238.720897 -135.420929)
			(xy 238.691431 -135.375079) (xy 238.668789 -135.325502) (xy 238.653434 -135.273207) (xy 238.645678 -135.219259)
			(xy 238.645192 -135.192008) (xy 234.786383 -135.192008) (xy 234.78478 -135.203157) (xy 234.769415 -135.255487)
			(xy 234.746758 -135.305097) (xy 234.717272 -135.350978) (xy 234.681557 -135.392195) (xy 234.64034 -135.42791)
			(xy 234.594459 -135.457396) (xy 234.544849 -135.480053) (xy 234.492519 -135.495418) (xy 234.438535 -135.50318)
			(xy 234.383997 -135.50318) (xy 234.330013 -135.495418) (xy 234.277683 -135.480053) (xy 234.228073 -135.457396)
			(xy 234.182192 -135.42791) (xy 234.140975 -135.392195) (xy 234.10526 -135.350978) (xy 234.075774 -135.305097)
			(xy 234.053117 -135.255487) (xy 234.037752 -135.203157) (xy 234.02999 -135.149173) (xy 234.029504 -135.121904)
			(xy 230.145996 -135.121904) (xy 230.133957 -135.162906) (xy 230.111315 -135.212488) (xy 230.081846 -135.258344)
			(xy 230.046153 -135.299538) (xy 230.00496 -135.335234) (xy 229.959106 -135.364705) (xy 229.909525 -135.38735)
			(xy 229.857226 -135.402709) (xy 229.803274 -135.410469) (xy 229.77602 -135.410956) (xy 228.91242 -135.410956)
			(xy 228.88517 -135.410398) (xy 228.831223 -135.402644) (xy 228.77893 -135.387292) (xy 228.729353 -135.364654)
			(xy 228.683503 -135.33519) (xy 228.642314 -135.299501) (xy 228.606622 -135.258313) (xy 228.577156 -135.212464)
			(xy 228.554515 -135.162889) (xy 228.53916 -135.110596) (xy 228.531403 -135.05665) (xy 226.755856 -135.05665)
			(xy 226.783915 -135.100312) (xy 226.806557 -135.149894) (xy 226.821913 -135.202193) (xy 226.82967 -135.256146)
			(xy 226.82967 -135.310654) (xy 226.821913 -135.364607) (xy 226.806557 -135.416906) (xy 226.783915 -135.466488)
			(xy 226.754446 -135.512344) (xy 226.718753 -135.553538) (xy 226.67756 -135.589234) (xy 226.631706 -135.618705)
			(xy 226.582125 -135.64135) (xy 226.529826 -135.656709) (xy 226.475874 -135.664469) (xy 226.44862 -135.664956)
			(xy 225.58502 -135.664956) (xy 225.55777 -135.664398) (xy 225.503823 -135.656644) (xy 225.45153 -135.641292)
			(xy 225.401953 -135.618654) (xy 225.356103 -135.58919) (xy 225.314914 -135.553501) (xy 225.279222 -135.512313)
			(xy 225.249756 -135.466464) (xy 225.227115 -135.416889) (xy 225.21176 -135.364596) (xy 225.204003 -135.31065)
			(xy 2.509012 -135.31065) (xy 2.509012 -137.199664) (xy 337.46447 -137.199664) (xy 337.46447 -137.145136)
			(xy 337.47223 -137.091163) (xy 337.487591 -137.038843) (xy 337.510241 -136.989242) (xy 337.539719 -136.943369)
			(xy 337.575425 -136.902158) (xy 337.616632 -136.866447) (xy 337.662502 -136.836963) (xy 337.7121 -136.814307)
			(xy 337.764418 -136.79894) (xy 337.81839 -136.791173) (xy 337.845654 -136.790684) (xy 338.618322 -136.790684)
			(xy 338.645594 -136.79108) (xy 338.699581 -136.798845) (xy 338.751915 -136.814214) (xy 338.801528 -136.836874)
			(xy 338.847412 -136.866364) (xy 338.888632 -136.902084) (xy 338.924349 -136.943306) (xy 338.953836 -136.989191)
			(xy 338.976493 -137.038806) (xy 338.991859 -137.09114) (xy 338.999622 -137.145128) (xy 338.999622 -137.199672)
			(xy 338.991859 -137.25366) (xy 338.976493 -137.305994) (xy 338.953836 -137.355609) (xy 338.924349 -137.401494)
			(xy 338.888632 -137.442716) (xy 338.847412 -137.478436) (xy 338.801528 -137.507926) (xy 338.751915 -137.530586)
			(xy 338.699581 -137.545955) (xy 338.645594 -137.55372) (xy 338.618322 -137.554208) (xy 337.845654 -137.554208)
			(xy 337.81839 -137.553627) (xy 337.764418 -137.54586) (xy 337.7121 -137.530493) (xy 337.662502 -137.507837)
			(xy 337.616632 -137.478353) (xy 337.575425 -137.442642) (xy 337.539719 -137.401431) (xy 337.510241 -137.355558)
			(xy 337.487591 -137.305957) (xy 337.47223 -137.253637) (xy 337.46447 -137.199664) (xy 2.509012 -137.199664)
			(xy 2.509012 -137.622788) (xy 340.085172 -137.622788) (xy 340.085172 -136.759188) (xy 340.085658 -136.731937)
			(xy 340.093414 -136.677989) (xy 340.108769 -136.625694) (xy 340.131411 -136.576117) (xy 340.160877 -136.530267)
			(xy 340.196568 -136.489076) (xy 340.237759 -136.453385) (xy 340.283609 -136.423919) (xy 340.333186 -136.401277)
			(xy 340.385481 -136.385922) (xy 340.439429 -136.378166) (xy 340.493931 -136.378166) (xy 340.547879 -136.385922)
			(xy 340.600174 -136.401277) (xy 340.649751 -136.423919) (xy 340.695601 -136.453385) (xy 340.736792 -136.489076)
			(xy 340.772483 -136.530267) (xy 340.801949 -136.576117) (xy 340.824591 -136.625694) (xy 340.839946 -136.677989)
			(xy 340.847702 -136.731937) (xy 340.848188 -136.759188) (xy 340.848188 -137.622788) (xy 340.847702 -137.650039)
			(xy 340.839946 -137.703987) (xy 340.824591 -137.756282) (xy 340.801949 -137.805859) (xy 340.772483 -137.851709)
			(xy 340.736792 -137.8929) (xy 340.695601 -137.928591) (xy 340.649751 -137.958057) (xy 340.600174 -137.980699)
			(xy 340.547879 -137.996054) (xy 340.493931 -138.00381) (xy 340.439429 -138.00381) (xy 340.385481 -137.996054)
			(xy 340.333186 -137.980699) (xy 340.283609 -137.958057) (xy 340.237759 -137.928591) (xy 340.196568 -137.8929)
			(xy 340.160877 -137.851709) (xy 340.131411 -137.805859) (xy 340.108769 -137.756282) (xy 340.093414 -137.703987)
			(xy 340.085658 -137.650039) (xy 340.085172 -137.622788) (xy 2.509012 -137.622788) (xy 2.509012 -153.766012)
			(xy 24.445731 -153.766012) (xy 24.449724 -153.556271) (xy 24.4617 -153.346834) (xy 24.481641 -153.138005)
			(xy 24.509518 -152.930086) (xy 24.54529 -152.723379) (xy 24.588905 -152.518184) (xy 24.640301 -152.314799)
			(xy 24.699403 -152.113517) (xy 24.766125 -151.914631) (xy 24.84037 -151.71843) (xy 24.92203 -151.525198)
			(xy 25.010988 -151.335214) (xy 25.107115 -151.148755) (xy 25.21027 -150.966091) (xy 25.320305 -150.787486)
			(xy 25.437059 -150.6132) (xy 25.560364 -150.443485) (xy 25.690041 -150.278587) (xy 25.825902 -150.118746)
			(xy 25.967749 -149.964193) (xy 26.115378 -149.815153) (xy 26.268573 -149.67184) (xy 26.427114 -149.534464)
			(xy 26.590769 -149.403223) (xy 26.759303 -149.278308) (xy 26.932469 -149.1599) (xy 27.110019 -149.04817)
			(xy 27.291693 -148.94328) (xy 27.477228 -148.845383) (xy 27.666356 -148.754621) (xy 27.858803 -148.671124)
			(xy 28.054288 -148.595014) (xy 28.25253 -148.526402) (xy 28.45324 -148.465387) (xy 28.656127 -148.412058)
			(xy 28.860897 -148.366491) (xy 29.067254 -148.328752) (xy 29.274898 -148.298898) (xy 29.483528 -148.27697)
			(xy 29.692841 -148.263001) (xy 29.902535 -148.25701) (xy 30.112304 -148.259007) (xy 30.321846 -148.268989)
			(xy 30.530856 -148.286941) (xy 30.73903 -148.312837) (xy 30.946068 -148.346639) (xy 31.151669 -148.388299)
			(xy 31.355535 -148.437757) (xy 31.55737 -148.49494) (xy 31.756882 -148.559765) (xy 31.953781 -148.632139)
			(xy 32.147782 -148.711956) (xy 32.338604 -148.799102) (xy 32.52597 -148.893449) (xy 32.709608 -148.99486)
			(xy 32.889252 -149.10319) (xy 33.064642 -149.21828) (xy 33.235523 -149.339964) (xy 33.401647 -149.468065)
			(xy 33.562774 -149.602398) (xy 33.718671 -149.742767) (xy 33.86911 -149.88897) (xy 34.013874 -150.040794)
			(xy 34.152753 -150.19802) (xy 34.285546 -150.360419) (xy 34.41206 -150.527755) (xy 34.532112 -150.699787)
			(xy 34.645527 -150.876264) (xy 34.752141 -151.056932) (xy 34.8518 -151.241527) (xy 34.944359 -151.429782)
			(xy 35.029684 -151.621425) (xy 35.107651 -151.816177) (xy 35.178147 -152.013757) (xy 35.24107 -152.213876)
			(xy 35.296329 -152.416247) (xy 35.343843 -152.620574) (xy 35.383544 -152.826562) (xy 35.415374 -153.033913)
			(xy 35.439287 -153.242324) (xy 35.455248 -153.451495) (xy 35.463235 -153.661122) (xy 35.463734 -153.766012)
			(xy 35.463235 -153.870902) (xy 35.455248 -154.080529) (xy 35.44312 -154.239468) (xy 186.742832 -154.239468)
			(xy 186.742832 -153.375868) (xy 186.743318 -153.348617) (xy 186.751074 -153.294669) (xy 186.766429 -153.242374)
			(xy 186.789071 -153.192797) (xy 186.818537 -153.146947) (xy 186.854228 -153.105756) (xy 186.895419 -153.070065)
			(xy 186.941269 -153.040599) (xy 186.990846 -153.017957) (xy 187.043141 -153.002602) (xy 187.097089 -152.994846)
			(xy 187.151591 -152.994846) (xy 187.205539 -153.002602) (xy 187.257834 -153.017957) (xy 187.307411 -153.040599)
			(xy 187.353261 -153.070065) (xy 187.394452 -153.105756) (xy 187.430143 -153.146947) (xy 187.459609 -153.192797)
			(xy 187.482251 -153.242374) (xy 187.497606 -153.294669) (xy 187.505362 -153.348617) (xy 187.505848 -153.375868)
			(xy 187.505848 -153.774902) (xy 188.445657 -153.774902) (xy 188.44965 -153.565161) (xy 188.461626 -153.355724)
			(xy 188.481567 -153.146895) (xy 188.509444 -152.938976) (xy 188.545216 -152.732269) (xy 188.588831 -152.527074)
			(xy 188.640227 -152.323689) (xy 188.699329 -152.122407) (xy 188.766051 -151.923521) (xy 188.840296 -151.72732)
			(xy 188.921956 -151.534088) (xy 189.010914 -151.344104) (xy 189.107041 -151.157645) (xy 189.210196 -150.974981)
			(xy 189.320231 -150.796376) (xy 189.436985 -150.62209) (xy 189.56029 -150.452375) (xy 189.689967 -150.287477)
			(xy 189.825828 -150.127636) (xy 189.967675 -149.973083) (xy 190.115304 -149.824043) (xy 190.268499 -149.68073)
			(xy 190.42704 -149.543354) (xy 190.590695 -149.412113) (xy 190.759229 -149.287198) (xy 190.932395 -149.16879)
			(xy 191.109945 -149.05706) (xy 191.291619 -148.95217) (xy 191.477154 -148.854273) (xy 191.666282 -148.763511)
			(xy 191.858729 -148.680014) (xy 192.054214 -148.603904) (xy 192.252456 -148.535292) (xy 192.453166 -148.474277)
			(xy 192.656053 -148.420948) (xy 192.860823 -148.375381) (xy 193.06718 -148.337642) (xy 193.274824 -148.307788)
			(xy 193.483454 -148.28586) (xy 193.692767 -148.271891) (xy 193.902461 -148.2659) (xy 194.11223 -148.267897)
			(xy 194.321772 -148.277879) (xy 194.530782 -148.295831) (xy 194.738956 -148.321727) (xy 194.945994 -148.355529)
			(xy 195.151595 -148.397189) (xy 195.355461 -148.446647) (xy 195.557296 -148.50383) (xy 195.756808 -148.568655)
			(xy 195.953707 -148.641029) (xy 196.147708 -148.720846) (xy 196.33853 -148.807992) (xy 196.525896 -148.902339)
			(xy 196.709534 -149.00375) (xy 196.889178 -149.11208) (xy 197.064568 -149.22717) (xy 197.235449 -149.348854)
			(xy 197.401573 -149.476955) (xy 197.5627 -149.611288) (xy 197.718597 -149.751657) (xy 197.869036 -149.89786)
			(xy 198.0138 -150.049684) (xy 198.152679 -150.20691) (xy 198.285472 -150.369309) (xy 198.411986 -150.536645)
			(xy 198.532038 -150.708677) (xy 198.645453 -150.885154) (xy 198.752067 -151.065822) (xy 198.851726 -151.250417)
			(xy 198.944285 -151.438672) (xy 199.02961 -151.630315) (xy 199.107577 -151.825067) (xy 199.178073 -152.022647)
			(xy 199.240996 -152.222766) (xy 199.296255 -152.425137) (xy 199.343769 -152.629464) (xy 199.38347 -152.835452)
			(xy 199.4153 -153.042803) (xy 199.439213 -153.251214) (xy 199.455174 -153.460385) (xy 199.463161 -153.670012)
			(xy 199.463618 -153.766012) (xy 272.385799 -153.766012) (xy 272.389792 -153.556271) (xy 272.401768 -153.346834)
			(xy 272.421709 -153.138005) (xy 272.449586 -152.930086) (xy 272.485358 -152.723379) (xy 272.528973 -152.518184)
			(xy 272.580369 -152.314799) (xy 272.639471 -152.113517) (xy 272.706193 -151.914631) (xy 272.780438 -151.71843)
			(xy 272.862098 -151.525198) (xy 272.951056 -151.335214) (xy 273.047183 -151.148755) (xy 273.150338 -150.966091)
			(xy 273.260373 -150.787486) (xy 273.377127 -150.6132) (xy 273.500432 -150.443485) (xy 273.630109 -150.278587)
			(xy 273.76597 -150.118746) (xy 273.907817 -149.964193) (xy 274.055446 -149.815153) (xy 274.208641 -149.67184)
			(xy 274.367182 -149.534464) (xy 274.530837 -149.403223) (xy 274.699371 -149.278308) (xy 274.872537 -149.1599)
			(xy 275.050087 -149.04817) (xy 275.231761 -148.94328) (xy 275.417296 -148.845383) (xy 275.606424 -148.754621)
			(xy 275.798871 -148.671124) (xy 275.994356 -148.595014) (xy 276.192598 -148.526402) (xy 276.393308 -148.465387)
			(xy 276.596195 -148.412058) (xy 276.800965 -148.366491) (xy 277.007322 -148.328752) (xy 277.214966 -148.298898)
			(xy 277.423596 -148.27697) (xy 277.632909 -148.263001) (xy 277.842603 -148.25701) (xy 278.052372 -148.259007)
			(xy 278.261914 -148.268989) (xy 278.470924 -148.286941) (xy 278.679098 -148.312837) (xy 278.886136 -148.346639)
			(xy 279.091737 -148.388299) (xy 279.295603 -148.437757) (xy 279.497438 -148.49494) (xy 279.69695 -148.559765)
			(xy 279.893849 -148.632139) (xy 280.08785 -148.711956) (xy 280.278672 -148.799102) (xy 280.466038 -148.893449)
			(xy 280.649676 -148.99486) (xy 280.82932 -149.10319) (xy 281.00471 -149.21828) (xy 281.175591 -149.339964)
			(xy 281.341715 -149.468065) (xy 281.502842 -149.602398) (xy 281.658739 -149.742767) (xy 281.809178 -149.88897)
			(xy 281.953942 -150.040794) (xy 282.092821 -150.19802) (xy 282.225614 -150.360419) (xy 282.352128 -150.527755)
			(xy 282.47218 -150.699787) (xy 282.585595 -150.876264) (xy 282.692209 -151.056932) (xy 282.791868 -151.241527)
			(xy 282.884427 -151.429782) (xy 282.969752 -151.621425) (xy 283.047719 -151.816177) (xy 283.118215 -152.013757)
			(xy 283.181138 -152.213876) (xy 283.236397 -152.416247) (xy 283.283911 -152.620574) (xy 283.323612 -152.826562)
			(xy 283.355442 -153.033913) (xy 283.379355 -153.242324) (xy 283.395316 -153.451495) (xy 283.403303 -153.661122)
			(xy 283.403802 -153.766012) (xy 283.40376 -153.774902) (xy 436.385725 -153.774902) (xy 436.389718 -153.565161)
			(xy 436.401694 -153.355724) (xy 436.421635 -153.146895) (xy 436.449512 -152.938976) (xy 436.485284 -152.732269)
			(xy 436.528899 -152.527074) (xy 436.580295 -152.323689) (xy 436.639397 -152.122407) (xy 436.706119 -151.923521)
			(xy 436.780364 -151.72732) (xy 436.862024 -151.534088) (xy 436.950982 -151.344104) (xy 437.047109 -151.157645)
			(xy 437.150264 -150.974981) (xy 437.260299 -150.796376) (xy 437.377053 -150.62209) (xy 437.500358 -150.452375)
			(xy 437.630035 -150.287477) (xy 437.765896 -150.127636) (xy 437.907743 -149.973083) (xy 438.055372 -149.824043)
			(xy 438.208567 -149.68073) (xy 438.367108 -149.543354) (xy 438.530763 -149.412113) (xy 438.699297 -149.287198)
			(xy 438.872463 -149.16879) (xy 439.050013 -149.05706) (xy 439.231687 -148.95217) (xy 439.417222 -148.854273)
			(xy 439.60635 -148.763511) (xy 439.798797 -148.680014) (xy 439.994282 -148.603904) (xy 440.192524 -148.535292)
			(xy 440.393234 -148.474277) (xy 440.596121 -148.420948) (xy 440.800891 -148.375381) (xy 441.007248 -148.337642)
			(xy 441.214892 -148.307788) (xy 441.423522 -148.28586) (xy 441.632835 -148.271891) (xy 441.842529 -148.2659)
			(xy 442.052298 -148.267897) (xy 442.26184 -148.277879) (xy 442.47085 -148.295831) (xy 442.679024 -148.321727)
			(xy 442.886062 -148.355529) (xy 443.091663 -148.397189) (xy 443.295529 -148.446647) (xy 443.497364 -148.50383)
			(xy 443.696876 -148.568655) (xy 443.893775 -148.641029) (xy 444.087776 -148.720846) (xy 444.278598 -148.807992)
			(xy 444.465964 -148.902339) (xy 444.649602 -149.00375) (xy 444.829246 -149.11208) (xy 445.004636 -149.22717)
			(xy 445.175517 -149.348854) (xy 445.341641 -149.476955) (xy 445.502768 -149.611288) (xy 445.658665 -149.751657)
			(xy 445.809104 -149.89786) (xy 445.953868 -150.049684) (xy 446.092747 -150.20691) (xy 446.22554 -150.369309)
			(xy 446.352054 -150.536645) (xy 446.472106 -150.708677) (xy 446.585521 -150.885154) (xy 446.692135 -151.065822)
			(xy 446.791794 -151.250417) (xy 446.884353 -151.438672) (xy 446.969678 -151.630315) (xy 447.047645 -151.825067)
			(xy 447.118141 -152.022647) (xy 447.181064 -152.222766) (xy 447.236323 -152.425137) (xy 447.283837 -152.629464)
			(xy 447.323538 -152.835452) (xy 447.355368 -153.042803) (xy 447.379281 -153.251214) (xy 447.395242 -153.460385)
			(xy 447.403229 -153.670012) (xy 447.403728 -153.774902) (xy 447.403229 -153.879792) (xy 447.395242 -154.089419)
			(xy 447.379281 -154.29859) (xy 447.355368 -154.507001) (xy 447.323538 -154.714352) (xy 447.283837 -154.92034)
			(xy 447.236323 -155.124667) (xy 447.181064 -155.327038) (xy 447.118141 -155.527157) (xy 447.047645 -155.724737)
			(xy 446.969678 -155.919489) (xy 446.884353 -156.111132) (xy 446.791794 -156.299387) (xy 446.692135 -156.483982)
			(xy 446.585521 -156.66465) (xy 446.472106 -156.841127) (xy 446.352054 -157.013159) (xy 446.22554 -157.180495)
			(xy 446.092747 -157.342894) (xy 445.953868 -157.50012) (xy 445.809104 -157.651944) (xy 445.658665 -157.798147)
			(xy 445.502768 -157.938516) (xy 445.341641 -158.072849) (xy 445.175517 -158.20095) (xy 445.004636 -158.322634)
			(xy 444.829246 -158.437724) (xy 444.649602 -158.546054) (xy 444.465964 -158.647465) (xy 444.278598 -158.741812)
			(xy 444.087776 -158.828958) (xy 443.893775 -158.908775) (xy 443.696876 -158.981149) (xy 443.497364 -159.045974)
			(xy 443.295529 -159.103157) (xy 443.091663 -159.152615) (xy 442.886062 -159.194275) (xy 442.679024 -159.228077)
			(xy 442.47085 -159.253973) (xy 442.26184 -159.271925) (xy 442.052298 -159.281907) (xy 441.842529 -159.283904)
			(xy 441.632835 -159.277913) (xy 441.423522 -159.263944) (xy 441.214892 -159.242016) (xy 441.007248 -159.212162)
			(xy 440.800891 -159.174423) (xy 440.596121 -159.128856) (xy 440.393234 -159.075527) (xy 440.192524 -159.014512)
			(xy 439.994282 -158.9459) (xy 439.798797 -158.86979) (xy 439.60635 -158.786293) (xy 439.417222 -158.695531)
			(xy 439.231687 -158.597634) (xy 439.050013 -158.492744) (xy 438.872463 -158.381014) (xy 438.699297 -158.262606)
			(xy 438.530763 -158.137691) (xy 438.367108 -158.00645) (xy 438.208567 -157.869074) (xy 438.055372 -157.725761)
			(xy 437.907743 -157.576721) (xy 437.765896 -157.422168) (xy 437.630035 -157.262327) (xy 437.500358 -157.097429)
			(xy 437.377053 -156.927714) (xy 437.260299 -156.753428) (xy 437.150264 -156.574823) (xy 437.047109 -156.392159)
			(xy 436.950982 -156.2057) (xy 436.862024 -156.015716) (xy 436.780364 -155.822484) (xy 436.706119 -155.626283)
			(xy 436.639397 -155.427397) (xy 436.580295 -155.226115) (xy 436.528899 -155.02273) (xy 436.485284 -154.817535)
			(xy 436.449512 -154.610828) (xy 436.421635 -154.402909) (xy 436.401694 -154.19408) (xy 436.389718 -153.984643)
			(xy 436.385725 -153.774902) (xy 283.40376 -153.774902) (xy 283.403303 -153.870902) (xy 283.395316 -154.080529)
			(xy 283.379355 -154.2897) (xy 283.355442 -154.498111) (xy 283.323612 -154.705462) (xy 283.283911 -154.91145)
			(xy 283.236397 -155.115777) (xy 283.181138 -155.318148) (xy 283.118215 -155.518267) (xy 283.047719 -155.715847)
			(xy 282.969752 -155.910599) (xy 282.884427 -156.102242) (xy 282.791868 -156.290497) (xy 282.692209 -156.475092)
			(xy 282.585595 -156.65576) (xy 282.47218 -156.832237) (xy 282.352128 -157.004269) (xy 282.225614 -157.171605)
			(xy 282.092821 -157.334004) (xy 281.953942 -157.49123) (xy 281.809178 -157.643054) (xy 281.658739 -157.789257)
			(xy 281.502842 -157.929626) (xy 281.341715 -158.063959) (xy 281.175591 -158.19206) (xy 281.00471 -158.313744)
			(xy 280.82932 -158.428834) (xy 280.649676 -158.537164) (xy 280.466038 -158.638575) (xy 280.278672 -158.732922)
			(xy 280.08785 -158.820068) (xy 279.893849 -158.899885) (xy 279.69695 -158.972259) (xy 279.497438 -159.037084)
			(xy 279.295603 -159.094267) (xy 279.091737 -159.143725) (xy 278.886136 -159.185385) (xy 278.679098 -159.219187)
			(xy 278.470924 -159.245083) (xy 278.261914 -159.263035) (xy 278.052372 -159.273017) (xy 277.842603 -159.275014)
			(xy 277.632909 -159.269023) (xy 277.423596 -159.255054) (xy 277.214966 -159.233126) (xy 277.007322 -159.203272)
			(xy 276.800965 -159.165533) (xy 276.596195 -159.119966) (xy 276.393308 -159.066637) (xy 276.192598 -159.005622)
			(xy 275.994356 -158.93701) (xy 275.798871 -158.8609) (xy 275.606424 -158.777403) (xy 275.417296 -158.686641)
			(xy 275.231761 -158.588744) (xy 275.050087 -158.483854) (xy 274.872537 -158.372124) (xy 274.699371 -158.253716)
			(xy 274.530837 -158.128801) (xy 274.367182 -157.99756) (xy 274.208641 -157.860184) (xy 274.055446 -157.716871)
			(xy 273.907817 -157.567831) (xy 273.76597 -157.413278) (xy 273.630109 -157.253437) (xy 273.500432 -157.088539)
			(xy 273.377127 -156.918824) (xy 273.260373 -156.744538) (xy 273.150338 -156.565933) (xy 273.047183 -156.383269)
			(xy 272.951056 -156.19681) (xy 272.862098 -156.006826) (xy 272.780438 -155.813594) (xy 272.706193 -155.617393)
			(xy 272.639471 -155.418507) (xy 272.580369 -155.217225) (xy 272.528973 -155.01384) (xy 272.485358 -154.808645)
			(xy 272.449586 -154.601938) (xy 272.421709 -154.394019) (xy 272.401768 -154.18519) (xy 272.389792 -153.975753)
			(xy 272.385799 -153.766012) (xy 199.463618 -153.766012) (xy 199.46366 -153.774902) (xy 199.463161 -153.879792)
			(xy 199.455174 -154.089419) (xy 199.439213 -154.29859) (xy 199.4153 -154.507001) (xy 199.38347 -154.714352)
			(xy 199.343769 -154.92034) (xy 199.296255 -155.124667) (xy 199.240996 -155.327038) (xy 199.178073 -155.527157)
			(xy 199.107577 -155.724737) (xy 199.02961 -155.919489) (xy 198.944285 -156.111132) (xy 198.851726 -156.299387)
			(xy 198.752067 -156.483982) (xy 198.645453 -156.66465) (xy 198.532038 -156.841127) (xy 198.411986 -157.013159)
			(xy 198.285472 -157.180495) (xy 198.152679 -157.342894) (xy 198.0138 -157.50012) (xy 197.869036 -157.651944)
			(xy 197.718597 -157.798147) (xy 197.5627 -157.938516) (xy 197.401573 -158.072849) (xy 197.235449 -158.20095)
			(xy 197.064568 -158.322634) (xy 196.889178 -158.437724) (xy 196.709534 -158.546054) (xy 196.525896 -158.647465)
			(xy 196.33853 -158.741812) (xy 196.147708 -158.828958) (xy 195.953707 -158.908775) (xy 195.756808 -158.981149)
			(xy 195.557296 -159.045974) (xy 195.355461 -159.103157) (xy 195.151595 -159.152615) (xy 194.945994 -159.194275)
			(xy 194.738956 -159.228077) (xy 194.530782 -159.253973) (xy 194.321772 -159.271925) (xy 194.11223 -159.281907)
			(xy 193.902461 -159.283904) (xy 193.692767 -159.277913) (xy 193.483454 -159.263944) (xy 193.274824 -159.242016)
			(xy 193.06718 -159.212162) (xy 192.860823 -159.174423) (xy 192.656053 -159.128856) (xy 192.453166 -159.075527)
			(xy 192.252456 -159.014512) (xy 192.054214 -158.9459) (xy 191.858729 -158.86979) (xy 191.666282 -158.786293)
			(xy 191.477154 -158.695531) (xy 191.291619 -158.597634) (xy 191.109945 -158.492744) (xy 190.932395 -158.381014)
			(xy 190.759229 -158.262606) (xy 190.590695 -158.137691) (xy 190.42704 -158.00645) (xy 190.268499 -157.869074)
			(xy 190.115304 -157.725761) (xy 189.967675 -157.576721) (xy 189.825828 -157.422168) (xy 189.689967 -157.262327)
			(xy 189.56029 -157.097429) (xy 189.436985 -156.927714) (xy 189.320231 -156.753428) (xy 189.210196 -156.574823)
			(xy 189.107041 -156.392159) (xy 189.010914 -156.2057) (xy 188.921956 -156.015716) (xy 188.840296 -155.822484)
			(xy 188.766051 -155.626283) (xy 188.699329 -155.427397) (xy 188.640227 -155.226115) (xy 188.588831 -155.02273)
			(xy 188.545216 -154.817535) (xy 188.509444 -154.610828) (xy 188.481567 -154.402909) (xy 188.461626 -154.19408)
			(xy 188.44965 -153.984643) (xy 188.445657 -153.774902) (xy 187.505848 -153.774902) (xy 187.505848 -154.239468)
			(xy 187.505362 -154.266719) (xy 187.497606 -154.320667) (xy 187.482251 -154.372962) (xy 187.459609 -154.422539)
			(xy 187.430143 -154.468389) (xy 187.394452 -154.50958) (xy 187.353261 -154.545271) (xy 187.307411 -154.574737)
			(xy 187.257834 -154.597379) (xy 187.205539 -154.612734) (xy 187.151591 -154.62049) (xy 187.097089 -154.62049)
			(xy 187.043141 -154.612734) (xy 186.990846 -154.597379) (xy 186.941269 -154.574737) (xy 186.895419 -154.545271)
			(xy 186.854228 -154.50958) (xy 186.818537 -154.468389) (xy 186.789071 -154.422539) (xy 186.766429 -154.372962)
			(xy 186.751074 -154.320667) (xy 186.743318 -154.266719) (xy 186.742832 -154.239468) (xy 35.44312 -154.239468)
			(xy 35.439287 -154.2897) (xy 35.415374 -154.498111) (xy 35.383544 -154.705462) (xy 35.343843 -154.91145)
			(xy 35.296329 -155.115777) (xy 35.24107 -155.318148) (xy 35.178147 -155.518267) (xy 35.107651 -155.715847)
			(xy 35.029684 -155.910599) (xy 34.944359 -156.102242) (xy 34.8518 -156.290497) (xy 34.752141 -156.475092)
			(xy 34.645527 -156.65576) (xy 34.532112 -156.832237) (xy 34.41206 -157.004269) (xy 34.285546 -157.171605)
			(xy 34.152753 -157.334004) (xy 34.013874 -157.49123) (xy 33.86911 -157.643054) (xy 33.718671 -157.789257)
			(xy 33.562774 -157.929626) (xy 33.401647 -158.063959) (xy 33.235523 -158.19206) (xy 33.064642 -158.313744)
			(xy 32.889252 -158.428834) (xy 32.709608 -158.537164) (xy 32.52597 -158.638575) (xy 32.338604 -158.732922)
			(xy 32.147782 -158.820068) (xy 31.953781 -158.899885) (xy 31.756882 -158.972259) (xy 31.55737 -159.037084)
			(xy 31.355535 -159.094267) (xy 31.151669 -159.143725) (xy 30.946068 -159.185385) (xy 30.73903 -159.219187)
			(xy 30.530856 -159.245083) (xy 30.321846 -159.263035) (xy 30.112304 -159.273017) (xy 29.902535 -159.275014)
			(xy 29.692841 -159.269023) (xy 29.483528 -159.255054) (xy 29.274898 -159.233126) (xy 29.067254 -159.203272)
			(xy 28.860897 -159.165533) (xy 28.656127 -159.119966) (xy 28.45324 -159.066637) (xy 28.25253 -159.005622)
			(xy 28.054288 -158.93701) (xy 27.858803 -158.8609) (xy 27.666356 -158.777403) (xy 27.477228 -158.686641)
			(xy 27.291693 -158.588744) (xy 27.110019 -158.483854) (xy 26.932469 -158.372124) (xy 26.759303 -158.253716)
			(xy 26.590769 -158.128801) (xy 26.427114 -157.99756) (xy 26.268573 -157.860184) (xy 26.115378 -157.716871)
			(xy 25.967749 -157.567831) (xy 25.825902 -157.413278) (xy 25.690041 -157.253437) (xy 25.560364 -157.088539)
			(xy 25.437059 -156.918824) (xy 25.320305 -156.744538) (xy 25.21027 -156.565933) (xy 25.107115 -156.383269)
			(xy 25.010988 -156.19681) (xy 24.92203 -156.006826) (xy 24.84037 -155.813594) (xy 24.766125 -155.617393)
			(xy 24.699403 -155.418507) (xy 24.640301 -155.217225) (xy 24.588905 -155.01384) (xy 24.54529 -154.808645)
			(xy 24.509518 -154.601938) (xy 24.481641 -154.394019) (xy 24.4617 -154.18519) (xy 24.449724 -153.975753)
			(xy 24.445731 -153.766012) (xy 2.509012 -153.766012) (xy 2.509012 -160.911354) (xy 372.506163 -160.911354)
			(xy 372.506163 -160.856846) (xy 372.513921 -160.802893) (xy 372.529279 -160.750593) (xy 372.551924 -160.701011)
			(xy 372.581395 -160.655157) (xy 372.617092 -160.613964) (xy 372.658289 -160.578271) (xy 372.704146 -160.548805)
			(xy 372.75373 -160.526165) (xy 372.806032 -160.510813) (xy 372.859986 -160.503061) (xy 372.88724 -160.5026)
			(xy 373.75084 -160.5026) (xy 373.77809 -160.503073) (xy 373.832034 -160.510834) (xy 373.884326 -160.526193)
			(xy 373.933899 -160.548837) (xy 373.979745 -160.578305) (xy 374.020931 -160.613997) (xy 374.056619 -160.655187)
			(xy 374.086083 -160.701036) (xy 374.108721 -160.750612) (xy 374.124075 -160.802905) (xy 374.13183 -160.85685)
			(xy 374.13183 -160.91135) (xy 374.124075 -160.965295) (xy 374.108721 -161.017588) (xy 374.086083 -161.067164)
			(xy 374.056619 -161.113013) (xy 374.020931 -161.154203) (xy 373.979745 -161.189895) (xy 373.933899 -161.219363)
			(xy 373.884326 -161.242007) (xy 373.832034 -161.257366) (xy 373.77809 -161.265127) (xy 373.75084 -161.265616)
			(xy 372.88724 -161.265616) (xy 372.859986 -161.265139) (xy 372.806032 -161.257387) (xy 372.75373 -161.242035)
			(xy 372.704146 -161.219395) (xy 372.658289 -161.189929) (xy 372.617092 -161.154236) (xy 372.581395 -161.113043)
			(xy 372.551924 -161.067189) (xy 372.529279 -161.017607) (xy 372.513921 -160.965307) (xy 372.506163 -160.911354)
			(xy 2.509012 -160.911354) (xy 2.509012 -161.58445) (xy 296.753286 -161.58445) (xy 296.753286 -161.52995)
			(xy 296.761042 -161.476005) (xy 296.776395 -161.423713) (xy 296.799035 -161.374138) (xy 296.828498 -161.32829)
			(xy 296.864187 -161.287101) (xy 296.905374 -161.25141) (xy 296.951221 -161.221944) (xy 297.000795 -161.199302)
			(xy 297.053086 -161.183946) (xy 297.10703 -161.176187) (xy 297.13428 -161.1757) (xy 297.99788 -161.1757)
			(xy 298.025134 -161.176146) (xy 298.079089 -161.183901) (xy 298.13139 -161.199255) (xy 298.180974 -161.221897)
			(xy 298.22683 -161.251365) (xy 298.268026 -161.28706) (xy 298.303723 -161.328254) (xy 298.333193 -161.374109)
			(xy 298.355838 -161.423691) (xy 298.371195 -161.475992) (xy 298.378953 -161.529946) (xy 298.378953 -161.584454)
			(xy 298.371195 -161.638408) (xy 298.355838 -161.690709) (xy 298.333193 -161.740291) (xy 298.303723 -161.786146)
			(xy 298.268026 -161.82734) (xy 298.22683 -161.863035) (xy 298.180974 -161.892503) (xy 298.13139 -161.915145)
			(xy 298.079089 -161.930499) (xy 298.025134 -161.938254) (xy 297.99788 -161.938716) (xy 297.13428 -161.938716)
			(xy 297.10703 -161.938213) (xy 297.053086 -161.930454) (xy 297.000795 -161.915098) (xy 296.951221 -161.892456)
			(xy 296.905374 -161.86299) (xy 296.864187 -161.827299) (xy 296.828498 -161.78611) (xy 296.799035 -161.740262)
			(xy 296.776395 -161.690687) (xy 296.761042 -161.638395) (xy 296.753286 -161.58445) (xy 2.509012 -161.58445)
			(xy 2.509012 -162.128053) (xy 292.574946 -162.128053) (xy 292.574946 -162.073547) (xy 292.582702 -162.019597)
			(xy 292.598058 -161.967299) (xy 292.620699 -161.917719) (xy 292.650166 -161.871866) (xy 292.685859 -161.830673)
			(xy 292.72705 -161.794978) (xy 292.772902 -161.765509) (xy 292.822481 -161.742865) (xy 292.874777 -161.727507)
			(xy 292.928727 -161.719747) (xy 292.95598 -161.71926) (xy 293.81958 -161.71926) (xy 293.846832 -161.719786)
			(xy 293.90078 -161.72754) (xy 293.953076 -161.742893) (xy 294.002654 -161.765532) (xy 294.048506 -161.794997)
			(xy 294.089698 -161.830688) (xy 294.125391 -161.871878) (xy 294.154858 -161.917728) (xy 294.1775 -161.967305)
			(xy 294.192856 -162.0196) (xy 294.200613 -162.073549) (xy 294.200613 -162.128051) (xy 294.192856 -162.182)
			(xy 294.1775 -162.234295) (xy 294.154858 -162.283872) (xy 294.125391 -162.329722) (xy 294.089698 -162.370912)
			(xy 294.048506 -162.406603) (xy 294.002654 -162.436068) (xy 293.953076 -162.458707) (xy 293.90078 -162.47406)
			(xy 293.846832 -162.481814) (xy 293.81958 -162.482276) (xy 292.95598 -162.482276) (xy 292.928727 -162.481853)
			(xy 292.874777 -162.474093) (xy 292.822481 -162.458735) (xy 292.772902 -162.436091) (xy 292.72705 -162.406622)
			(xy 292.685859 -162.370927) (xy 292.650166 -162.329734) (xy 292.620699 -162.283881) (xy 292.598058 -162.234301)
			(xy 292.582702 -162.182003) (xy 292.574946 -162.128053) (xy 2.509012 -162.128053) (xy 2.509012 -163.123651)
			(xy 294.731403 -163.123651) (xy 294.731403 -163.069149) (xy 294.73916 -163.015201) (xy 294.754516 -162.962907)
			(xy 294.777159 -162.91333) (xy 294.806627 -162.867481) (xy 294.842321 -162.826292) (xy 294.883513 -162.790603)
			(xy 294.929365 -162.76114) (xy 294.978944 -162.738502) (xy 295.03124 -162.723152) (xy 295.085189 -162.7154)
			(xy 295.11244 -162.71494) (xy 295.97604 -162.71494) (xy 296.003293 -162.715333) (xy 296.057243 -162.723095)
			(xy 296.10954 -162.738455) (xy 296.159118 -162.761102) (xy 296.204969 -162.790573) (xy 296.24616 -162.826269)
			(xy 296.281851 -162.867463) (xy 296.311318 -162.913317) (xy 296.333959 -162.962898) (xy 296.349314 -163.015196)
			(xy 296.35707 -163.069147) (xy 296.35707 -163.110951) (xy 300.192403 -163.110951) (xy 300.192403 -163.056449)
			(xy 300.20016 -163.002501) (xy 300.215516 -162.950207) (xy 300.238159 -162.90063) (xy 300.267627 -162.854781)
			(xy 300.303321 -162.813592) (xy 300.344513 -162.777903) (xy 300.390365 -162.74844) (xy 300.439944 -162.725802)
			(xy 300.49224 -162.710452) (xy 300.546189 -162.7027) (xy 300.57344 -162.70224) (xy 301.43704 -162.70224)
			(xy 301.464293 -162.702633) (xy 301.518243 -162.710395) (xy 301.57054 -162.725755) (xy 301.620118 -162.748402)
			(xy 301.665969 -162.777873) (xy 301.70716 -162.813569) (xy 301.742851 -162.854763) (xy 301.772318 -162.900617)
			(xy 301.794959 -162.950198) (xy 301.810314 -163.002496) (xy 301.81807 -163.056447) (xy 301.81807 -163.110953)
			(xy 301.810314 -163.164904) (xy 301.794959 -163.217202) (xy 301.772318 -163.266783) (xy 301.742851 -163.312637)
			(xy 301.70716 -163.353831) (xy 301.665969 -163.389527) (xy 301.620118 -163.418998) (xy 301.57054 -163.441645)
			(xy 301.518243 -163.457005) (xy 301.464293 -163.464767) (xy 301.43704 -163.465256) (xy 300.57344 -163.465256)
			(xy 300.546189 -163.4647) (xy 300.49224 -163.456948) (xy 300.439944 -163.441598) (xy 300.390365 -163.41896)
			(xy 300.344513 -163.389497) (xy 300.303321 -163.353808) (xy 300.267627 -163.312619) (xy 300.238159 -163.26677)
			(xy 300.215516 -163.217193) (xy 300.20016 -163.164899) (xy 300.192403 -163.110951) (xy 296.35707 -163.110951)
			(xy 296.35707 -163.123653) (xy 296.349314 -163.177604) (xy 296.333959 -163.229902) (xy 296.311318 -163.279483)
			(xy 296.281851 -163.325337) (xy 296.24616 -163.366531) (xy 296.204969 -163.402227) (xy 296.159118 -163.431698)
			(xy 296.10954 -163.454345) (xy 296.057243 -163.469705) (xy 296.003293 -163.477467) (xy 295.97604 -163.477956)
			(xy 295.11244 -163.477956) (xy 295.085189 -163.4774) (xy 295.03124 -163.469648) (xy 294.978944 -163.454298)
			(xy 294.929365 -163.43166) (xy 294.883513 -163.402197) (xy 294.842321 -163.366508) (xy 294.806627 -163.325319)
			(xy 294.777159 -163.27947) (xy 294.754516 -163.229893) (xy 294.73916 -163.177599) (xy 294.731403 -163.123651)
			(xy 2.509012 -163.123651) (xy 2.509012 -167.565832) (xy 348.657164 -167.565832) (xy 348.657658 -167.532531)
			(xy 348.666337 -167.466499) (xy 348.683566 -167.402165) (xy 348.709048 -167.340632) (xy 348.742347 -167.282953)
			(xy 348.782893 -167.230117) (xy 348.829992 -167.183027) (xy 348.882836 -167.142492) (xy 348.911418 -167.125396)
			(xy 349.83547 -166.591742) (xy 349.864533 -166.575642) (xy 349.925937 -166.550271) (xy 349.990123 -166.533114)
			(xy 350.055996 -166.524463) (xy 350.089216 -166.523924) (xy 350.089724 -166.523924) (xy 350.120458 -166.524315)
			(xy 350.181477 -166.531727) (xy 350.241158 -166.54644) (xy 350.29863 -166.56824) (xy 350.353056 -166.596808)
			(xy 350.403641 -166.631729) (xy 350.449648 -166.672492) (xy 350.490406 -166.718503) (xy 350.525321 -166.769092)
			(xy 350.553883 -166.823521) (xy 350.57377 -166.875968) (xy 369.614196 -166.875968) (xy 369.614752 -166.84267)
			(xy 369.623426 -166.776641) (xy 369.640648 -166.71231) (xy 369.666122 -166.650779) (xy 369.699412 -166.593101)
			(xy 369.739949 -166.540263) (xy 369.787038 -166.493171) (xy 369.839873 -166.452631) (xy 369.86845 -166.435532)
			(xy 370.792502 -165.901878) (xy 370.82156 -165.885769) (xy 370.882966 -165.8604) (xy 370.947153 -165.843245)
			(xy 371.013028 -165.834597) (xy 371.046248 -165.83406) (xy 371.046756 -165.83406) (xy 371.077486 -165.834579)
			(xy 371.138498 -165.841982) (xy 371.198173 -165.856685) (xy 371.255641 -165.878475) (xy 371.310063 -165.907032)
			(xy 371.360647 -165.941941) (xy 371.406653 -165.982693) (xy 371.447412 -166.028694) (xy 371.482329 -166.079272)
			(xy 371.510894 -166.133689) (xy 371.532692 -166.191154) (xy 371.547404 -166.250827) (xy 371.554816 -166.311838)
			(xy 371.555264 -166.342568) (xy 371.554757 -166.375868) (xy 371.546077 -166.4419) (xy 371.52885 -166.506232)
			(xy 371.503369 -166.567765) (xy 371.470072 -166.625443) (xy 371.429528 -166.67828) (xy 371.382432 -166.72537)
			(xy 371.329591 -166.765907) (xy 371.30101 -166.783004) (xy 370.964111 -166.977568) (xy 373.398796 -166.977568)
			(xy 373.399226 -166.946836) (xy 373.406638 -166.885821) (xy 373.421351 -166.826144) (xy 373.443149 -166.768676)
			(xy 373.471715 -166.714254) (xy 373.506633 -166.663671) (xy 373.547392 -166.617667) (xy 373.5934 -166.57691)
			(xy 373.643984 -166.541996) (xy 373.698409 -166.513434) (xy 373.755879 -166.49164) (xy 373.815556 -166.476932)
			(xy 373.876572 -166.469524) (xy 373.907304 -166.46906) (xy 373.907812 -166.46906) (xy 373.941031 -166.469606)
			(xy 374.006903 -166.478264) (xy 374.071088 -166.495419) (xy 374.132496 -166.520778) (xy 374.161558 -166.536878)
			(xy 375.08561 -167.070532) (xy 375.114171 -167.087654) (xy 375.166997 -167.128201) (xy 375.214079 -167.175295)
			(xy 375.254613 -167.22813) (xy 375.287906 -167.285802) (xy 375.313388 -167.347326) (xy 375.330623 -167.411649)
			(xy 375.339318 -167.477672) (xy 375.339864 -167.510968) (xy 375.339432 -167.541701) (xy 375.332026 -167.60272)
			(xy 375.317319 -167.6624) (xy 375.295524 -167.719873) (xy 375.266961 -167.774299) (xy 375.232044 -167.824885)
			(xy 375.191284 -167.870893) (xy 375.145275 -167.911651) (xy 375.094689 -167.946567) (xy 375.040262 -167.975129)
			(xy 374.982789 -167.996923) (xy 374.923108 -168.011629) (xy 374.862089 -168.019033) (xy 374.831356 -168.019476)
			(xy 374.830848 -168.019476) (xy 374.797629 -168.018942) (xy 374.731757 -168.01028) (xy 374.667571 -167.993122)
			(xy 374.606164 -167.967759) (xy 374.577102 -167.951658) (xy 373.65305 -167.418004) (xy 373.624495 -167.400872)
			(xy 373.571672 -167.360325) (xy 373.524591 -167.313232) (xy 373.484057 -167.260398) (xy 373.450764 -167.202727)
			(xy 373.42528 -167.141205) (xy 373.408042 -167.076884) (xy 373.399344 -167.010863) (xy 373.398796 -166.977568)
			(xy 370.964111 -166.977568) (xy 370.376958 -167.316658) (xy 370.34791 -167.332786) (xy 370.2865 -167.35815)
			(xy 370.22231 -167.375299) (xy 370.156433 -167.383942) (xy 370.123212 -167.384476) (xy 370.122704 -167.384476)
			(xy 370.091971 -167.384059) (xy 370.030952 -167.37665) (xy 369.971272 -167.36194) (xy 369.9138 -167.340143)
			(xy 369.859375 -167.311577) (xy 369.808789 -167.276659) (xy 369.762782 -167.235898) (xy 369.722023 -167.189889)
			(xy 369.687108 -167.139301) (xy 369.658546 -167.084874) (xy 369.636752 -167.027401) (xy 369.622045 -166.96772)
			(xy 369.61464 -166.906701) (xy 369.614196 -166.875968) (xy 350.57377 -166.875968) (xy 350.575676 -166.880996)
			(xy 350.590383 -166.940678) (xy 350.597788 -167.001698) (xy 350.598232 -167.032432) (xy 350.597712 -167.065732)
			(xy 350.589036 -167.131763) (xy 350.571812 -167.196097) (xy 350.546334 -167.25763) (xy 350.513038 -167.315309)
			(xy 350.472496 -167.368145) (xy 350.4254 -167.415235) (xy 350.372559 -167.455772) (xy 350.343978 -167.472868)
			(xy 349.419926 -168.006522) (xy 349.390862 -168.02262) (xy 349.329459 -168.047992) (xy 349.265273 -168.06515)
			(xy 349.1994 -168.073802) (xy 349.16618 -168.07434) (xy 349.165672 -168.07434) (xy 349.134942 -168.07387)
			(xy 349.073929 -168.066459) (xy 349.014255 -168.051748) (xy 348.956789 -168.029953) (xy 348.902369 -168.001389)
			(xy 348.851788 -167.966475) (xy 348.805784 -167.925719) (xy 348.765027 -167.879715) (xy 348.730113 -167.829135)
			(xy 348.701549 -167.774715) (xy 348.679753 -167.717249) (xy 348.665041 -167.657575) (xy 348.65763 -167.596562)
			(xy 348.657164 -167.565832) (xy 2.509012 -167.565832) (xy 2.509012 -168.302432) (xy 352.441764 -168.302432)
			(xy 352.442268 -168.271702) (xy 352.449672 -168.210689) (xy 352.464377 -168.151013) (xy 352.486168 -168.093545)
			(xy 352.514727 -168.039122) (xy 352.549637 -167.988539) (xy 352.59039 -167.942533) (xy 352.636392 -167.901774)
			(xy 352.686971 -167.866858) (xy 352.74139 -167.838292) (xy 352.798856 -167.816495) (xy 352.85853 -167.801783)
			(xy 352.919542 -167.794371) (xy 352.950272 -167.793924) (xy 352.95078 -167.793924) (xy 352.983998 -167.794489)
			(xy 353.049869 -167.803142) (xy 353.114055 -167.820291) (xy 353.175463 -167.845645) (xy 353.204526 -167.861742)
			(xy 354.128578 -168.395396) (xy 354.157139 -168.412518) (xy 354.209962 -168.453067) (xy 354.257042 -168.500162)
			(xy 354.297574 -168.552998) (xy 354.330866 -168.61067) (xy 354.356349 -168.672193) (xy 354.373586 -168.736515)
			(xy 354.382284 -168.802536) (xy 354.382832 -168.835832) (xy 354.382374 -168.866563) (xy 354.374962 -168.927576)
			(xy 354.360251 -168.987251) (xy 354.338454 -169.044717) (xy 354.30989 -169.099138) (xy 354.274975 -169.149719)
			(xy 354.234218 -169.195723) (xy 354.188213 -169.23648) (xy 354.137631 -169.271394) (xy 354.08321 -169.299957)
			(xy 354.025743 -169.321753) (xy 353.966068 -169.336464) (xy 353.905055 -169.343875) (xy 353.874324 -169.34434)
			(xy 353.873816 -169.34434) (xy 353.840597 -169.343782) (xy 353.774726 -169.335127) (xy 353.710541 -169.317976)
			(xy 353.649132 -169.292621) (xy 353.62007 -169.276522) (xy 352.696018 -168.742868) (xy 352.667463 -168.725735)
			(xy 352.614637 -168.685191) (xy 352.567553 -168.638099) (xy 352.527018 -168.585266) (xy 352.493724 -168.527595)
			(xy 352.468241 -168.466072) (xy 352.451005 -168.40175) (xy 352.44231 -168.335728) (xy 352.441764 -168.302432)
			(xy 2.509012 -168.302432) (xy 2.509012 -170.613832) (xy 348.657164 -170.613832) (xy 348.657658 -170.580531)
			(xy 348.666337 -170.514499) (xy 348.683566 -170.450165) (xy 348.709048 -170.388632) (xy 348.742347 -170.330953)
			(xy 348.782893 -170.278117) (xy 348.829992 -170.231027) (xy 348.882836 -170.190492) (xy 348.911418 -170.173396)
			(xy 349.83547 -169.639742) (xy 349.864533 -169.623642) (xy 349.925937 -169.598271) (xy 349.990123 -169.581114)
			(xy 350.055996 -169.572463) (xy 350.089216 -169.571924) (xy 350.089724 -169.571924) (xy 350.120458 -169.572315)
			(xy 350.181477 -169.579727) (xy 350.241158 -169.59444) (xy 350.29863 -169.61624) (xy 350.353056 -169.644808)
			(xy 350.403641 -169.679729) (xy 350.449648 -169.720492) (xy 350.490406 -169.766503) (xy 350.525321 -169.817092)
			(xy 350.553883 -169.871521) (xy 350.57377 -169.923968) (xy 369.614196 -169.923968) (xy 369.614752 -169.89067)
			(xy 369.623426 -169.824641) (xy 369.640648 -169.76031) (xy 369.666122 -169.698779) (xy 369.699412 -169.641101)
			(xy 369.739949 -169.588263) (xy 369.787038 -169.541171) (xy 369.839873 -169.500631) (xy 369.86845 -169.483532)
			(xy 370.792502 -168.949878) (xy 370.82156 -168.933769) (xy 370.882966 -168.9084) (xy 370.947153 -168.891245)
			(xy 371.013028 -168.882597) (xy 371.046248 -168.88206) (xy 371.046756 -168.88206) (xy 371.077486 -168.882579)
			(xy 371.138498 -168.889982) (xy 371.198173 -168.904685) (xy 371.255641 -168.926475) (xy 371.310063 -168.955032)
			(xy 371.360647 -168.989941) (xy 371.406653 -169.030693) (xy 371.447412 -169.076694) (xy 371.482329 -169.127272)
			(xy 371.510894 -169.181689) (xy 371.532692 -169.239154) (xy 371.547404 -169.298827) (xy 371.554816 -169.359838)
			(xy 371.555264 -169.390568) (xy 371.554757 -169.423868) (xy 371.546077 -169.4899) (xy 371.52885 -169.554232)
			(xy 371.503369 -169.615765) (xy 371.470072 -169.673443) (xy 371.429528 -169.72628) (xy 371.382432 -169.77337)
			(xy 371.329591 -169.813907) (xy 371.30101 -169.831004) (xy 370.376958 -170.364658) (xy 370.34791 -170.380786)
			(xy 370.2865 -170.40615) (xy 370.22231 -170.423299) (xy 370.156433 -170.431942) (xy 370.123212 -170.432476)
			(xy 370.122704 -170.432476) (xy 370.091971 -170.432059) (xy 370.030952 -170.42465) (xy 369.971272 -170.40994)
			(xy 369.9138 -170.388143) (xy 369.859375 -170.359577) (xy 369.808789 -170.324659) (xy 369.762782 -170.283898)
			(xy 369.722023 -170.237889) (xy 369.687108 -170.187301) (xy 369.658546 -170.132874) (xy 369.636752 -170.075401)
			(xy 369.622045 -170.01572) (xy 369.61464 -169.954701) (xy 369.614196 -169.923968) (xy 350.57377 -169.923968)
			(xy 350.575676 -169.928996) (xy 350.590383 -169.988678) (xy 350.597788 -170.049698) (xy 350.598232 -170.080432)
			(xy 350.597712 -170.113732) (xy 350.589036 -170.179763) (xy 350.571812 -170.244097) (xy 350.546334 -170.30563)
			(xy 350.513038 -170.363309) (xy 350.472496 -170.416145) (xy 350.4254 -170.463235) (xy 350.372559 -170.503772)
			(xy 350.343978 -170.520868) (xy 350.10208 -170.660568) (xy 373.398796 -170.660568) (xy 373.399226 -170.629836)
			(xy 373.406638 -170.568821) (xy 373.421351 -170.509144) (xy 373.443149 -170.451676) (xy 373.471715 -170.397254)
			(xy 373.506633 -170.346671) (xy 373.547392 -170.300667) (xy 373.5934 -170.25991) (xy 373.643984 -170.224996)
			(xy 373.698409 -170.196434) (xy 373.755879 -170.17464) (xy 373.815556 -170.159932) (xy 373.876572 -170.152524)
			(xy 373.907304 -170.15206) (xy 373.907812 -170.15206) (xy 373.941031 -170.152606) (xy 374.006903 -170.161264)
			(xy 374.071088 -170.178419) (xy 374.132496 -170.203778) (xy 374.161558 -170.219878) (xy 375.08561 -170.753532)
			(xy 375.114171 -170.770654) (xy 375.166997 -170.811201) (xy 375.214079 -170.858295) (xy 375.254613 -170.91113)
			(xy 375.287906 -170.968802) (xy 375.313388 -171.030326) (xy 375.330623 -171.094649) (xy 375.339318 -171.160672)
			(xy 375.339864 -171.193968) (xy 375.339432 -171.224701) (xy 375.332026 -171.28572) (xy 375.317319 -171.3454)
			(xy 375.295524 -171.402873) (xy 375.266961 -171.457299) (xy 375.232044 -171.507885) (xy 375.191284 -171.553893)
			(xy 375.145275 -171.594651) (xy 375.094689 -171.629567) (xy 375.040262 -171.658129) (xy 374.982789 -171.679923)
			(xy 374.923108 -171.694629) (xy 374.862089 -171.702033) (xy 374.831356 -171.702476) (xy 374.830848 -171.702476)
			(xy 374.797629 -171.701942) (xy 374.731757 -171.69328) (xy 374.667571 -171.676122) (xy 374.606164 -171.650759)
			(xy 374.577102 -171.634658) (xy 373.65305 -171.101004) (xy 373.624495 -171.083872) (xy 373.571672 -171.043325)
			(xy 373.524591 -170.996232) (xy 373.484057 -170.943398) (xy 373.450764 -170.885727) (xy 373.42528 -170.824205)
			(xy 373.408042 -170.759884) (xy 373.399344 -170.693863) (xy 373.398796 -170.660568) (xy 350.10208 -170.660568)
			(xy 349.419926 -171.054522) (xy 349.390862 -171.07062) (xy 349.329459 -171.095992) (xy 349.265273 -171.11315)
			(xy 349.1994 -171.121802) (xy 349.16618 -171.12234) (xy 349.165672 -171.12234) (xy 349.134942 -171.12187)
			(xy 349.073929 -171.114459) (xy 349.014255 -171.099748) (xy 348.956789 -171.077953) (xy 348.902369 -171.049389)
			(xy 348.851788 -171.014475) (xy 348.805784 -170.973719) (xy 348.765027 -170.927715) (xy 348.730113 -170.877135)
			(xy 348.701549 -170.822715) (xy 348.679753 -170.765249) (xy 348.665041 -170.705575) (xy 348.65763 -170.644562)
			(xy 348.657164 -170.613832) (xy 2.509012 -170.613832) (xy 2.509012 -171.985432) (xy 352.441764 -171.985432)
			(xy 352.442268 -171.954702) (xy 352.449672 -171.893689) (xy 352.464377 -171.834013) (xy 352.486168 -171.776545)
			(xy 352.514727 -171.722122) (xy 352.549637 -171.671539) (xy 352.59039 -171.625533) (xy 352.636392 -171.584774)
			(xy 352.686971 -171.549858) (xy 352.74139 -171.521292) (xy 352.798856 -171.499495) (xy 352.85853 -171.484783)
			(xy 352.919542 -171.477371) (xy 352.950272 -171.476924) (xy 352.95078 -171.476924) (xy 352.983998 -171.477489)
			(xy 353.049869 -171.486142) (xy 353.114055 -171.503291) (xy 353.175463 -171.528645) (xy 353.204526 -171.544742)
			(xy 354.128578 -172.078396) (xy 354.157139 -172.095518) (xy 354.209962 -172.136067) (xy 354.257042 -172.183162)
			(xy 354.297574 -172.235998) (xy 354.330866 -172.29367) (xy 354.356349 -172.355193) (xy 354.373586 -172.419515)
			(xy 354.382284 -172.485536) (xy 354.382832 -172.518832) (xy 354.382374 -172.549563) (xy 354.374962 -172.610576)
			(xy 354.360251 -172.670251) (xy 354.338454 -172.727717) (xy 354.30989 -172.782138) (xy 354.274975 -172.832719)
			(xy 354.234218 -172.878723) (xy 354.188213 -172.91948) (xy 354.137631 -172.954394) (xy 354.104147 -172.971968)
			(xy 369.614196 -172.971968) (xy 369.614752 -172.93867) (xy 369.623426 -172.872641) (xy 369.640648 -172.80831)
			(xy 369.666122 -172.746779) (xy 369.699412 -172.689101) (xy 369.739949 -172.636263) (xy 369.787038 -172.589171)
			(xy 369.839873 -172.548631) (xy 369.86845 -172.531532) (xy 370.792502 -171.997878) (xy 370.82156 -171.981769)
			(xy 370.882966 -171.9564) (xy 370.947153 -171.939245) (xy 371.013028 -171.930597) (xy 371.046248 -171.93006)
			(xy 371.046756 -171.93006) (xy 371.077486 -171.930579) (xy 371.138498 -171.937982) (xy 371.198173 -171.952685)
			(xy 371.255641 -171.974475) (xy 371.310063 -172.003032) (xy 371.360647 -172.037941) (xy 371.406653 -172.078693)
			(xy 371.447412 -172.124694) (xy 371.482329 -172.175272) (xy 371.510894 -172.229689) (xy 371.532692 -172.287154)
			(xy 371.547404 -172.346827) (xy 371.554816 -172.407838) (xy 371.555264 -172.438568) (xy 371.554757 -172.471868)
			(xy 371.546077 -172.5379) (xy 371.52885 -172.602232) (xy 371.503369 -172.663765) (xy 371.470072 -172.721443)
			(xy 371.429528 -172.77428) (xy 371.382432 -172.82137) (xy 371.329591 -172.861907) (xy 371.30101 -172.879004)
			(xy 370.376958 -173.412658) (xy 370.34791 -173.428786) (xy 370.2865 -173.45415) (xy 370.22231 -173.471299)
			(xy 370.156433 -173.479942) (xy 370.123212 -173.480476) (xy 370.122704 -173.480476) (xy 370.091971 -173.480059)
			(xy 370.030952 -173.47265) (xy 369.971272 -173.45794) (xy 369.9138 -173.436143) (xy 369.859375 -173.407577)
			(xy 369.808789 -173.372659) (xy 369.762782 -173.331898) (xy 369.722023 -173.285889) (xy 369.687108 -173.235301)
			(xy 369.658546 -173.180874) (xy 369.636752 -173.123401) (xy 369.622045 -173.06372) (xy 369.61464 -173.002701)
			(xy 369.614196 -172.971968) (xy 354.104147 -172.971968) (xy 354.08321 -172.982957) (xy 354.025743 -173.004753)
			(xy 353.966068 -173.019464) (xy 353.905055 -173.026875) (xy 353.874324 -173.02734) (xy 353.873816 -173.02734)
			(xy 353.840597 -173.026782) (xy 353.774726 -173.018127) (xy 353.710541 -173.000976) (xy 353.649132 -172.975621)
			(xy 353.62007 -172.959522) (xy 352.696018 -172.425868) (xy 352.667463 -172.408735) (xy 352.614637 -172.368191)
			(xy 352.567553 -172.321099) (xy 352.527018 -172.268266) (xy 352.493724 -172.210595) (xy 352.468241 -172.149072)
			(xy 352.451005 -172.08475) (xy 352.44231 -172.018728) (xy 352.441764 -171.985432) (xy 2.509012 -171.985432)
			(xy 2.509012 -173.661832) (xy 348.657164 -173.661832) (xy 348.657658 -173.628531) (xy 348.666337 -173.562499)
			(xy 348.683566 -173.498165) (xy 348.709048 -173.436632) (xy 348.742347 -173.378953) (xy 348.782893 -173.326117)
			(xy 348.829992 -173.279027) (xy 348.882836 -173.238492) (xy 348.911418 -173.221396) (xy 349.83547 -172.687742)
			(xy 349.864533 -172.671642) (xy 349.925937 -172.646271) (xy 349.990123 -172.629114) (xy 350.055996 -172.620463)
			(xy 350.089216 -172.619924) (xy 350.089724 -172.619924) (xy 350.120458 -172.620315) (xy 350.181477 -172.627727)
			(xy 350.241158 -172.64244) (xy 350.29863 -172.66424) (xy 350.353056 -172.692808) (xy 350.403641 -172.727729)
			(xy 350.449648 -172.768492) (xy 350.490406 -172.814503) (xy 350.525321 -172.865092) (xy 350.553883 -172.919521)
			(xy 350.575676 -172.976996) (xy 350.590383 -173.036678) (xy 350.597788 -173.097698) (xy 350.598232 -173.128432)
			(xy 350.597712 -173.161732) (xy 350.589036 -173.227763) (xy 350.571812 -173.292097) (xy 350.546334 -173.35363)
			(xy 350.513038 -173.411309) (xy 350.472496 -173.464145) (xy 350.4254 -173.511235) (xy 350.372559 -173.551772)
			(xy 350.343978 -173.568868) (xy 349.419926 -174.102522) (xy 349.390862 -174.11862) (xy 349.329459 -174.143992)
			(xy 349.265273 -174.16115) (xy 349.1994 -174.169802) (xy 349.16618 -174.17034) (xy 349.165672 -174.17034)
			(xy 349.134942 -174.16987) (xy 349.073929 -174.162459) (xy 349.014255 -174.147748) (xy 348.956789 -174.125953)
			(xy 348.902369 -174.097389) (xy 348.851788 -174.062475) (xy 348.805784 -174.021719) (xy 348.765027 -173.975715)
			(xy 348.730113 -173.925135) (xy 348.701549 -173.870715) (xy 348.679753 -173.813249) (xy 348.665041 -173.753575)
			(xy 348.65763 -173.692562) (xy 348.657164 -173.661832) (xy 2.509012 -173.661832) (xy 2.509012 -174.343568)
			(xy 373.398796 -174.343568) (xy 373.399226 -174.312836) (xy 373.406638 -174.251821) (xy 373.421351 -174.192144)
			(xy 373.443149 -174.134676) (xy 373.471715 -174.080254) (xy 373.506633 -174.029671) (xy 373.547392 -173.983667)
			(xy 373.5934 -173.94291) (xy 373.643984 -173.907996) (xy 373.698409 -173.879434) (xy 373.755879 -173.85764)
			(xy 373.815556 -173.842932) (xy 373.876572 -173.835524) (xy 373.907304 -173.83506) (xy 373.907812 -173.83506)
			(xy 373.941031 -173.835606) (xy 374.006903 -173.844264) (xy 374.071088 -173.861419) (xy 374.132496 -173.886778)
			(xy 374.161558 -173.902878) (xy 375.08561 -174.436532) (xy 375.114171 -174.453654) (xy 375.166997 -174.494201)
			(xy 375.214079 -174.541295) (xy 375.254613 -174.59413) (xy 375.287906 -174.651802) (xy 375.313388 -174.713326)
			(xy 375.330623 -174.777649) (xy 375.339318 -174.843672) (xy 375.339864 -174.876968) (xy 375.339432 -174.907701)
			(xy 375.332026 -174.96872) (xy 375.317319 -175.0284) (xy 375.295524 -175.085873) (xy 375.266961 -175.140299)
			(xy 375.232044 -175.190885) (xy 375.191284 -175.236893) (xy 375.145275 -175.277651) (xy 375.094689 -175.312567)
			(xy 375.040262 -175.341129) (xy 374.982789 -175.362923) (xy 374.923108 -175.377629) (xy 374.862089 -175.385033)
			(xy 374.831356 -175.385476) (xy 374.830848 -175.385476) (xy 374.797629 -175.384942) (xy 374.731757 -175.37628)
			(xy 374.667571 -175.359122) (xy 374.606164 -175.333759) (xy 374.577102 -175.317658) (xy 373.65305 -174.784004)
			(xy 373.624495 -174.766872) (xy 373.571672 -174.726325) (xy 373.524591 -174.679232) (xy 373.484057 -174.626398)
			(xy 373.450764 -174.568727) (xy 373.42528 -174.507205) (xy 373.408042 -174.442884) (xy 373.399344 -174.376863)
			(xy 373.398796 -174.343568) (xy 2.509012 -174.343568) (xy 2.509012 -175.83404) (xy 23.37714 -175.83404)
			(xy 23.381229 -175.778158) (xy 23.393412 -175.723468) (xy 23.413428 -175.671134) (xy 23.440851 -175.622272)
			(xy 23.475096 -175.577924) (xy 23.515432 -175.539034) (xy 23.561002 -175.506432) (xy 23.610833 -175.480813)
			(xy 23.663863 -175.462721) (xy 23.718961 -175.452544) (xy 23.774955 -175.450498) (xy 23.83065 -175.456626)
			(xy 23.884859 -175.470798) (xy 23.936427 -175.492712) (xy 23.984255 -175.521901) (xy 24.027323 -175.557742)
			(xy 24.064713 -175.599472) (xy 24.095629 -175.646202) (xy 24.119412 -175.696935) (xy 24.135554 -175.750591)
			(xy 24.143713 -175.806025) (xy 24.144224 -175.83404) (xy 24.143713 -175.862055) (xy 24.135554 -175.917489)
			(xy 24.119412 -175.971145) (xy 24.095629 -176.021878) (xy 24.064713 -176.068608) (xy 24.027323 -176.110338)
			(xy 23.984255 -176.146179) (xy 23.936427 -176.175368) (xy 23.884859 -176.197282) (xy 23.83065 -176.211454)
			(xy 23.774955 -176.217582) (xy 23.718961 -176.215536) (xy 23.663863 -176.205359) (xy 23.610833 -176.187267)
			(xy 23.561002 -176.161648) (xy 23.515432 -176.129046) (xy 23.475096 -176.090156) (xy 23.440851 -176.045808)
			(xy 23.413428 -175.996946) (xy 23.393412 -175.944612) (xy 23.381229 -175.889922) (xy 23.37714 -175.83404)
			(xy 2.509012 -175.83404) (xy 2.509012 -176.709832) (xy 348.657164 -176.709832) (xy 348.657658 -176.676531)
			(xy 348.666337 -176.610499) (xy 348.683566 -176.546165) (xy 348.709048 -176.484632) (xy 348.742347 -176.426953)
			(xy 348.782893 -176.374117) (xy 348.829992 -176.327027) (xy 348.882836 -176.286492) (xy 348.911418 -176.269396)
			(xy 349.83547 -175.735742) (xy 349.864533 -175.719642) (xy 349.925937 -175.694271) (xy 349.990123 -175.677114)
			(xy 350.055996 -175.668463) (xy 350.089216 -175.667924) (xy 350.089724 -175.667924) (xy 350.120458 -175.668315)
			(xy 350.121421 -175.668432) (xy 352.441764 -175.668432) (xy 352.442268 -175.637702) (xy 352.449672 -175.576689)
			(xy 352.464377 -175.517013) (xy 352.486168 -175.459545) (xy 352.514727 -175.405122) (xy 352.549637 -175.354539)
			(xy 352.59039 -175.308533) (xy 352.636392 -175.267774) (xy 352.686971 -175.232858) (xy 352.74139 -175.204292)
			(xy 352.798856 -175.182495) (xy 352.85853 -175.167783) (xy 352.919542 -175.160371) (xy 352.950272 -175.159924)
			(xy 352.95078 -175.159924) (xy 352.983998 -175.160489) (xy 353.049869 -175.169142) (xy 353.114055 -175.186291)
			(xy 353.175463 -175.211645) (xy 353.204526 -175.227742) (xy 354.128578 -175.761396) (xy 354.157139 -175.778518)
			(xy 354.209962 -175.819067) (xy 354.257042 -175.866162) (xy 354.297574 -175.918998) (xy 354.330866 -175.97667)
			(xy 354.3488 -176.019968) (xy 369.614196 -176.019968) (xy 369.614752 -175.98667) (xy 369.623426 -175.920641)
			(xy 369.640648 -175.85631) (xy 369.666122 -175.794779) (xy 369.699412 -175.737101) (xy 369.739949 -175.684263)
			(xy 369.787038 -175.637171) (xy 369.839873 -175.596631) (xy 369.86845 -175.579532) (xy 370.792502 -175.045878)
			(xy 370.82156 -175.029769) (xy 370.882966 -175.0044) (xy 370.947153 -174.987245) (xy 371.013028 -174.978597)
			(xy 371.046248 -174.97806) (xy 371.046756 -174.97806) (xy 371.077486 -174.978579) (xy 371.138498 -174.985982)
			(xy 371.198173 -175.000685) (xy 371.255641 -175.022475) (xy 371.310063 -175.051032) (xy 371.360647 -175.085941)
			(xy 371.406653 -175.126693) (xy 371.447412 -175.172694) (xy 371.482329 -175.223272) (xy 371.510894 -175.277689)
			(xy 371.532692 -175.335154) (xy 371.547404 -175.394827) (xy 371.554816 -175.455838) (xy 371.555264 -175.486568)
			(xy 371.554757 -175.519868) (xy 371.546077 -175.5859) (xy 371.543089 -175.597058) (xy 434.095902 -175.597058)
			(xy 434.099991 -175.541176) (xy 434.112174 -175.486486) (xy 434.13219 -175.434152) (xy 434.159613 -175.38529)
			(xy 434.193858 -175.340942) (xy 434.234194 -175.302052) (xy 434.279764 -175.26945) (xy 434.329595 -175.243831)
			(xy 434.382625 -175.225739) (xy 434.437723 -175.215562) (xy 434.493717 -175.213516) (xy 434.549412 -175.219644)
			(xy 434.603621 -175.233816) (xy 434.655189 -175.25573) (xy 434.703017 -175.284919) (xy 434.746085 -175.32076)
			(xy 434.783475 -175.36249) (xy 434.814391 -175.40922) (xy 434.838174 -175.459953) (xy 434.854316 -175.513609)
			(xy 434.862475 -175.569043) (xy 434.862986 -175.597058) (xy 434.862475 -175.625073) (xy 434.854316 -175.680507)
			(xy 434.838174 -175.734163) (xy 434.814391 -175.784896) (xy 434.783475 -175.831626) (xy 434.746085 -175.873356)
			(xy 434.703017 -175.909197) (xy 434.655189 -175.938386) (xy 434.603621 -175.9603) (xy 434.549412 -175.974472)
			(xy 434.493717 -175.9806) (xy 434.437723 -175.978554) (xy 434.382625 -175.968377) (xy 434.329595 -175.950285)
			(xy 434.279764 -175.924666) (xy 434.234194 -175.892064) (xy 434.193858 -175.853174) (xy 434.159613 -175.808826)
			(xy 434.13219 -175.759964) (xy 434.112174 -175.70763) (xy 434.099991 -175.65294) (xy 434.095902 -175.597058)
			(xy 371.543089 -175.597058) (xy 371.52885 -175.650232) (xy 371.503369 -175.711765) (xy 371.470072 -175.769443)
			(xy 371.429528 -175.82228) (xy 371.382432 -175.86937) (xy 371.329591 -175.909907) (xy 371.30101 -175.927004)
			(xy 370.376958 -176.460658) (xy 370.34791 -176.476786) (xy 370.2865 -176.50215) (xy 370.22231 -176.519299)
			(xy 370.156433 -176.527942) (xy 370.123212 -176.528476) (xy 370.122704 -176.528476) (xy 370.091971 -176.528059)
			(xy 370.030952 -176.52065) (xy 369.971272 -176.50594) (xy 369.9138 -176.484143) (xy 369.859375 -176.455577)
			(xy 369.808789 -176.420659) (xy 369.762782 -176.379898) (xy 369.722023 -176.333889) (xy 369.687108 -176.283301)
			(xy 369.658546 -176.228874) (xy 369.636752 -176.171401) (xy 369.622045 -176.11172) (xy 369.61464 -176.050701)
			(xy 369.614196 -176.019968) (xy 354.3488 -176.019968) (xy 354.356349 -176.038193) (xy 354.373586 -176.102515)
			(xy 354.382284 -176.168536) (xy 354.382832 -176.201832) (xy 354.382374 -176.232563) (xy 354.374962 -176.293576)
			(xy 354.360251 -176.353251) (xy 354.338454 -176.410717) (xy 354.30989 -176.465138) (xy 354.274975 -176.515719)
			(xy 354.234218 -176.561723) (xy 354.188213 -176.60248) (xy 354.137631 -176.637394) (xy 354.08321 -176.665957)
			(xy 354.025743 -176.687753) (xy 353.966068 -176.702464) (xy 353.905055 -176.709875) (xy 353.874324 -176.71034)
			(xy 353.873816 -176.71034) (xy 353.840597 -176.709782) (xy 353.774726 -176.701127) (xy 353.710541 -176.683976)
			(xy 353.649132 -176.658621) (xy 353.62007 -176.642522) (xy 352.696018 -176.108868) (xy 352.667463 -176.091735)
			(xy 352.614637 -176.051191) (xy 352.567553 -176.004099) (xy 352.527018 -175.951266) (xy 352.493724 -175.893595)
			(xy 352.468241 -175.832072) (xy 352.451005 -175.76775) (xy 352.44231 -175.701728) (xy 352.441764 -175.668432)
			(xy 350.121421 -175.668432) (xy 350.181477 -175.675727) (xy 350.241158 -175.69044) (xy 350.29863 -175.71224)
			(xy 350.353056 -175.740808) (xy 350.403641 -175.775729) (xy 350.449648 -175.816492) (xy 350.490406 -175.862503)
			(xy 350.525321 -175.913092) (xy 350.553883 -175.967521) (xy 350.575676 -176.024996) (xy 350.590383 -176.084678)
			(xy 350.597788 -176.145698) (xy 350.598232 -176.176432) (xy 350.597712 -176.209732) (xy 350.589036 -176.275763)
			(xy 350.571812 -176.340097) (xy 350.546334 -176.40163) (xy 350.513038 -176.459309) (xy 350.472496 -176.512145)
			(xy 350.4254 -176.559235) (xy 350.372559 -176.599772) (xy 350.343978 -176.616868) (xy 349.419926 -177.150522)
			(xy 349.390862 -177.16662) (xy 349.329459 -177.191992) (xy 349.265273 -177.20915) (xy 349.1994 -177.217802)
			(xy 349.16618 -177.21834) (xy 349.165672 -177.21834) (xy 349.134942 -177.21787) (xy 349.073929 -177.210459)
			(xy 349.014255 -177.195748) (xy 348.956789 -177.173953) (xy 348.902369 -177.145389) (xy 348.851788 -177.110475)
			(xy 348.805784 -177.069719) (xy 348.765027 -177.023715) (xy 348.730113 -176.973135) (xy 348.701549 -176.918715)
			(xy 348.679753 -176.861249) (xy 348.665041 -176.801575) (xy 348.65763 -176.740562) (xy 348.657164 -176.709832)
			(xy 2.509012 -176.709832) (xy 2.509012 -179.757832) (xy 348.657164 -179.757832) (xy 348.657658 -179.724531)
			(xy 348.666337 -179.658499) (xy 348.683566 -179.594165) (xy 348.709048 -179.532632) (xy 348.742347 -179.474953)
			(xy 348.782893 -179.422117) (xy 348.829992 -179.375027) (xy 348.882836 -179.334492) (xy 348.911418 -179.317396)
			(xy 349.83547 -178.783742) (xy 349.864533 -178.767642) (xy 349.925937 -178.742271) (xy 349.990123 -178.725114)
			(xy 350.055996 -178.716463) (xy 350.089216 -178.715924) (xy 350.089724 -178.715924) (xy 350.120458 -178.716315)
			(xy 350.181477 -178.723727) (xy 350.241158 -178.73844) (xy 350.29863 -178.76024) (xy 350.353056 -178.788808)
			(xy 350.403641 -178.823729) (xy 350.449648 -178.864492) (xy 350.490406 -178.910503) (xy 350.525321 -178.961092)
			(xy 350.553883 -179.015521) (xy 350.575676 -179.072996) (xy 350.590383 -179.132678) (xy 350.597788 -179.193698)
			(xy 350.598232 -179.224432) (xy 350.597712 -179.257732) (xy 350.589036 -179.323763) (xy 350.581628 -179.351432)
			(xy 352.441764 -179.351432) (xy 352.442268 -179.320702) (xy 352.449672 -179.259689) (xy 352.464377 -179.200013)
			(xy 352.486168 -179.142545) (xy 352.514727 -179.088122) (xy 352.549637 -179.037539) (xy 352.59039 -178.991533)
			(xy 352.636392 -178.950774) (xy 352.686971 -178.915858) (xy 352.74139 -178.887292) (xy 352.798856 -178.865495)
			(xy 352.85853 -178.850783) (xy 352.919542 -178.843371) (xy 352.950272 -178.842924) (xy 352.95078 -178.842924)
			(xy 352.983998 -178.843489) (xy 353.049869 -178.852142) (xy 353.114055 -178.869291) (xy 353.175463 -178.894645)
			(xy 353.204526 -178.910742) (xy 353.476772 -179.067968) (xy 369.614196 -179.067968) (xy 369.614752 -179.03467)
			(xy 369.623426 -178.968641) (xy 369.640648 -178.90431) (xy 369.666122 -178.842779) (xy 369.699412 -178.785101)
			(xy 369.739949 -178.732263) (xy 369.787038 -178.685171) (xy 369.839873 -178.644631) (xy 369.86845 -178.627532)
			(xy 370.792502 -178.093878) (xy 370.82156 -178.077769) (xy 370.882966 -178.0524) (xy 370.947153 -178.035245)
			(xy 371.013028 -178.026597) (xy 371.046248 -178.02606) (xy 371.046756 -178.02606) (xy 371.076835 -178.026568)
			(xy 373.398796 -178.026568) (xy 373.399226 -177.995836) (xy 373.406638 -177.934821) (xy 373.421351 -177.875144)
			(xy 373.443149 -177.817676) (xy 373.471715 -177.763254) (xy 373.506633 -177.712671) (xy 373.547392 -177.666667)
			(xy 373.5934 -177.62591) (xy 373.643984 -177.590996) (xy 373.698409 -177.562434) (xy 373.755879 -177.54064)
			(xy 373.815556 -177.525932) (xy 373.876572 -177.518524) (xy 373.907304 -177.51806) (xy 373.907812 -177.51806)
			(xy 373.941031 -177.518606) (xy 374.006903 -177.527264) (xy 374.071088 -177.544419) (xy 374.132496 -177.569778)
			(xy 374.161558 -177.585878) (xy 375.08561 -178.119532) (xy 375.114171 -178.136654) (xy 375.166997 -178.177201)
			(xy 375.214079 -178.224295) (xy 375.254613 -178.27713) (xy 375.287906 -178.334802) (xy 375.313388 -178.396326)
			(xy 375.330623 -178.460649) (xy 375.339318 -178.526672) (xy 375.339864 -178.559968) (xy 375.339432 -178.590701)
			(xy 375.332026 -178.65172) (xy 375.317319 -178.7114) (xy 375.295524 -178.768873) (xy 375.266961 -178.823299)
			(xy 375.232044 -178.873885) (xy 375.191284 -178.919893) (xy 375.145275 -178.960651) (xy 375.094689 -178.995567)
			(xy 375.040262 -179.024129) (xy 374.982789 -179.045923) (xy 374.923108 -179.060629) (xy 374.862089 -179.068033)
			(xy 374.831356 -179.068476) (xy 374.830848 -179.068476) (xy 374.797629 -179.067942) (xy 374.731757 -179.05928)
			(xy 374.667571 -179.042122) (xy 374.606164 -179.016759) (xy 374.577102 -179.000658) (xy 373.65305 -178.467004)
			(xy 373.624495 -178.449872) (xy 373.571672 -178.409325) (xy 373.524591 -178.362232) (xy 373.484057 -178.309398)
			(xy 373.450764 -178.251727) (xy 373.42528 -178.190205) (xy 373.408042 -178.125884) (xy 373.399344 -178.059863)
			(xy 373.398796 -178.026568) (xy 371.076835 -178.026568) (xy 371.077486 -178.026579) (xy 371.138498 -178.033982)
			(xy 371.198173 -178.048685) (xy 371.255641 -178.070475) (xy 371.310063 -178.099032) (xy 371.360647 -178.133941)
			(xy 371.406653 -178.174693) (xy 371.447412 -178.220694) (xy 371.482329 -178.271272) (xy 371.510894 -178.325689)
			(xy 371.532692 -178.383154) (xy 371.547404 -178.442827) (xy 371.554816 -178.503838) (xy 371.555264 -178.534568)
			(xy 371.554757 -178.567868) (xy 371.546077 -178.6339) (xy 371.52885 -178.698232) (xy 371.503369 -178.759765)
			(xy 371.470072 -178.817443) (xy 371.429528 -178.87028) (xy 371.382432 -178.91737) (xy 371.329591 -178.957907)
			(xy 371.30101 -178.975004) (xy 370.376958 -179.508658) (xy 370.34791 -179.524786) (xy 370.2865 -179.55015)
			(xy 370.22231 -179.567299) (xy 370.156433 -179.575942) (xy 370.123212 -179.576476) (xy 370.122704 -179.576476)
			(xy 370.091971 -179.576059) (xy 370.030952 -179.56865) (xy 369.971272 -179.55394) (xy 369.9138 -179.532143)
			(xy 369.859375 -179.503577) (xy 369.808789 -179.468659) (xy 369.762782 -179.427898) (xy 369.722023 -179.381889)
			(xy 369.687108 -179.331301) (xy 369.658546 -179.276874) (xy 369.636752 -179.219401) (xy 369.622045 -179.15972)
			(xy 369.61464 -179.098701) (xy 369.614196 -179.067968) (xy 353.476772 -179.067968) (xy 354.128578 -179.444396)
			(xy 354.157139 -179.461518) (xy 354.209962 -179.502067) (xy 354.257042 -179.549162) (xy 354.297574 -179.601998)
			(xy 354.330866 -179.65967) (xy 354.356349 -179.721193) (xy 354.373586 -179.785515) (xy 354.382284 -179.851536)
			(xy 354.382832 -179.884832) (xy 354.382374 -179.915563) (xy 354.374962 -179.976576) (xy 354.360251 -180.036251)
			(xy 354.338454 -180.093717) (xy 354.30989 -180.148138) (xy 354.274975 -180.198719) (xy 354.234218 -180.244723)
			(xy 354.188213 -180.28548) (xy 354.137631 -180.320394) (xy 354.08321 -180.348957) (xy 354.025743 -180.370753)
			(xy 353.966068 -180.385464) (xy 353.905055 -180.392875) (xy 353.874324 -180.39334) (xy 353.873816 -180.39334)
			(xy 353.840597 -180.392782) (xy 353.774726 -180.384127) (xy 353.710541 -180.366976) (xy 353.649132 -180.341621)
			(xy 353.62007 -180.325522) (xy 352.696018 -179.791868) (xy 352.667463 -179.774735) (xy 352.614637 -179.734191)
			(xy 352.567553 -179.687099) (xy 352.527018 -179.634266) (xy 352.493724 -179.576595) (xy 352.468241 -179.515072)
			(xy 352.451005 -179.45075) (xy 352.44231 -179.384728) (xy 352.441764 -179.351432) (xy 350.581628 -179.351432)
			(xy 350.571812 -179.388097) (xy 350.546334 -179.44963) (xy 350.513038 -179.507309) (xy 350.472496 -179.560145)
			(xy 350.4254 -179.607235) (xy 350.372559 -179.647772) (xy 350.343978 -179.664868) (xy 349.419926 -180.198522)
			(xy 349.390862 -180.21462) (xy 349.329459 -180.239992) (xy 349.265273 -180.25715) (xy 349.1994 -180.265802)
			(xy 349.16618 -180.26634) (xy 349.165672 -180.26634) (xy 349.134942 -180.26587) (xy 349.073929 -180.258459)
			(xy 349.014255 -180.243748) (xy 348.956789 -180.221953) (xy 348.902369 -180.193389) (xy 348.851788 -180.158475)
			(xy 348.805784 -180.117719) (xy 348.765027 -180.071715) (xy 348.730113 -180.021135) (xy 348.701549 -179.966715)
			(xy 348.679753 -179.909249) (xy 348.665041 -179.849575) (xy 348.65763 -179.788562) (xy 348.657164 -179.757832)
			(xy 2.509012 -179.757832) (xy 2.509012 -182.805832) (xy 348.657164 -182.805832) (xy 348.657658 -182.772531)
			(xy 348.666337 -182.706499) (xy 348.683566 -182.642165) (xy 348.709048 -182.580632) (xy 348.742347 -182.522953)
			(xy 348.782893 -182.470117) (xy 348.829992 -182.423027) (xy 348.882836 -182.382492) (xy 348.911418 -182.365396)
			(xy 349.83547 -181.831742) (xy 349.864533 -181.815642) (xy 349.925937 -181.790271) (xy 349.990123 -181.773114)
			(xy 350.055996 -181.764463) (xy 350.089216 -181.763924) (xy 350.089724 -181.763924) (xy 350.120458 -181.764315)
			(xy 350.181477 -181.771727) (xy 350.241158 -181.78644) (xy 350.29863 -181.80824) (xy 350.353056 -181.836808)
			(xy 350.403641 -181.871729) (xy 350.449648 -181.912492) (xy 350.490406 -181.958503) (xy 350.525321 -182.009092)
			(xy 350.553883 -182.063521) (xy 350.57377 -182.115968) (xy 369.614196 -182.115968) (xy 369.614752 -182.08267)
			(xy 369.623426 -182.016641) (xy 369.640648 -181.95231) (xy 369.666122 -181.890779) (xy 369.699412 -181.833101)
			(xy 369.739949 -181.780263) (xy 369.787038 -181.733171) (xy 369.839873 -181.692631) (xy 369.86845 -181.675532)
			(xy 370.792502 -181.141878) (xy 370.82156 -181.125769) (xy 370.882966 -181.1004) (xy 370.947153 -181.083245)
			(xy 371.013028 -181.074597) (xy 371.046248 -181.07406) (xy 371.046756 -181.07406) (xy 371.077486 -181.074579)
			(xy 371.138498 -181.081982) (xy 371.198173 -181.096685) (xy 371.255641 -181.118475) (xy 371.310063 -181.147032)
			(xy 371.360647 -181.181941) (xy 371.406653 -181.222693) (xy 371.447412 -181.268694) (xy 371.482329 -181.319272)
			(xy 371.510894 -181.373689) (xy 371.532692 -181.431154) (xy 371.547404 -181.490827) (xy 371.554816 -181.551838)
			(xy 371.555264 -181.582568) (xy 371.554757 -181.615868) (xy 371.546077 -181.6819) (xy 371.538668 -181.709568)
			(xy 373.398796 -181.709568) (xy 373.399226 -181.678836) (xy 373.406638 -181.617821) (xy 373.421351 -181.558144)
			(xy 373.443149 -181.500676) (xy 373.471715 -181.446254) (xy 373.506633 -181.395671) (xy 373.547392 -181.349667)
			(xy 373.5934 -181.30891) (xy 373.643984 -181.273996) (xy 373.698409 -181.245434) (xy 373.755879 -181.22364)
			(xy 373.815556 -181.208932) (xy 373.876572 -181.201524) (xy 373.907304 -181.20106) (xy 373.907812 -181.20106)
			(xy 373.941031 -181.201606) (xy 374.006903 -181.210264) (xy 374.071088 -181.227419) (xy 374.132496 -181.252778)
			(xy 374.161558 -181.268878) (xy 375.08561 -181.802532) (xy 375.114171 -181.819654) (xy 375.166997 -181.860201)
			(xy 375.214079 -181.907295) (xy 375.254613 -181.96013) (xy 375.287906 -182.017802) (xy 375.313388 -182.079326)
			(xy 375.330623 -182.143649) (xy 375.339318 -182.209672) (xy 375.339864 -182.242968) (xy 375.339432 -182.273701)
			(xy 375.332026 -182.33472) (xy 375.317319 -182.3944) (xy 375.295524 -182.451873) (xy 375.266961 -182.506299)
			(xy 375.232044 -182.556885) (xy 375.191284 -182.602893) (xy 375.145275 -182.643651) (xy 375.094689 -182.678567)
			(xy 375.040262 -182.707129) (xy 374.982789 -182.728923) (xy 374.923108 -182.743629) (xy 374.862089 -182.751033)
			(xy 374.831356 -182.751476) (xy 374.830848 -182.751476) (xy 374.797629 -182.750942) (xy 374.731757 -182.74228)
			(xy 374.667571 -182.725122) (xy 374.606164 -182.699759) (xy 374.577102 -182.683658) (xy 373.65305 -182.150004)
			(xy 373.624495 -182.132872) (xy 373.571672 -182.092325) (xy 373.524591 -182.045232) (xy 373.484057 -181.992398)
			(xy 373.450764 -181.934727) (xy 373.42528 -181.873205) (xy 373.408042 -181.808884) (xy 373.399344 -181.742863)
			(xy 373.398796 -181.709568) (xy 371.538668 -181.709568) (xy 371.52885 -181.746232) (xy 371.503369 -181.807765)
			(xy 371.470072 -181.865443) (xy 371.429528 -181.91828) (xy 371.382432 -181.96537) (xy 371.329591 -182.005907)
			(xy 371.30101 -182.023004) (xy 370.376958 -182.556658) (xy 370.34791 -182.572786) (xy 370.2865 -182.59815)
			(xy 370.22231 -182.615299) (xy 370.156433 -182.623942) (xy 370.123212 -182.624476) (xy 370.122704 -182.624476)
			(xy 370.091971 -182.624059) (xy 370.030952 -182.61665) (xy 369.971272 -182.60194) (xy 369.9138 -182.580143)
			(xy 369.859375 -182.551577) (xy 369.808789 -182.516659) (xy 369.762782 -182.475898) (xy 369.722023 -182.429889)
			(xy 369.687108 -182.379301) (xy 369.658546 -182.324874) (xy 369.636752 -182.267401) (xy 369.622045 -182.20772)
			(xy 369.61464 -182.146701) (xy 369.614196 -182.115968) (xy 350.57377 -182.115968) (xy 350.575676 -182.120996)
			(xy 350.590383 -182.180678) (xy 350.597788 -182.241698) (xy 350.598232 -182.272432) (xy 350.597712 -182.305732)
			(xy 350.589036 -182.371763) (xy 350.571812 -182.436097) (xy 350.546334 -182.49763) (xy 350.513038 -182.555309)
			(xy 350.472496 -182.608145) (xy 350.4254 -182.655235) (xy 350.372559 -182.695772) (xy 350.343978 -182.712868)
			(xy 349.775297 -183.04129) (xy 352.441764 -183.04129) (xy 352.442192 -183.010552) (xy 352.449601 -182.949525)
			(xy 352.46431 -182.889835) (xy 352.486105 -182.832352) (xy 352.514667 -182.777914) (xy 352.549581 -182.727315)
			(xy 352.590338 -182.681292) (xy 352.636344 -182.640516) (xy 352.686928 -182.60558) (xy 352.741353 -182.576994)
			(xy 352.798826 -182.555175) (xy 352.85851 -182.540441) (xy 352.919534 -182.533005) (xy 352.950272 -182.532528)
			(xy 352.95078 -182.532528) (xy 352.984007 -182.533118) (xy 353.049889 -182.541823) (xy 353.114077 -182.559036)
			(xy 353.175475 -182.584464) (xy 353.204526 -182.6006) (xy 354.128578 -183.134254) (xy 354.157165 -183.151335)
			(xy 354.209988 -183.19189) (xy 354.257067 -183.238991) (xy 354.297597 -183.291832) (xy 354.330886 -183.34951)
			(xy 354.356365 -183.411039) (xy 354.373597 -183.475367) (xy 354.382288 -183.541392) (xy 354.382832 -183.57469)
			(xy 354.382389 -183.605428) (xy 354.374982 -183.666455) (xy 354.360275 -183.726145) (xy 354.338483 -183.783627)
			(xy 354.309922 -183.838065) (xy 354.275009 -183.888665) (xy 354.234254 -183.934688) (xy 354.188249 -183.975465)
			(xy 354.137666 -184.010401) (xy 354.083241 -184.038987) (xy 354.025768 -184.060806) (xy 353.966085 -184.07554)
			(xy 353.905061 -184.082975) (xy 353.874324 -184.083452) (xy 353.873816 -184.083452) (xy 353.840589 -184.082867)
			(xy 353.774706 -184.07416) (xy 353.710519 -184.056946) (xy 353.649121 -184.031517) (xy 353.62007 -184.01538)
			(xy 352.696018 -183.481726) (xy 352.667489 -183.464552) (xy 352.614663 -183.424014) (xy 352.567578 -183.376928)
			(xy 352.527041 -183.324101) (xy 352.493744 -183.266436) (xy 352.468257 -183.204918) (xy 352.451015 -183.140601)
			(xy 352.442314 -183.074584) (xy 352.441764 -183.04129) (xy 349.775297 -183.04129) (xy 349.419926 -183.246522)
			(xy 349.390862 -183.26262) (xy 349.329459 -183.287992) (xy 349.265273 -183.30515) (xy 349.1994 -183.313802)
			(xy 349.16618 -183.31434) (xy 349.165672 -183.31434) (xy 349.134942 -183.31387) (xy 349.073929 -183.306459)
			(xy 349.014255 -183.291748) (xy 348.956789 -183.269953) (xy 348.902369 -183.241389) (xy 348.851788 -183.206475)
			(xy 348.805784 -183.165719) (xy 348.765027 -183.119715) (xy 348.730113 -183.069135) (xy 348.701549 -183.014715)
			(xy 348.679753 -182.957249) (xy 348.665041 -182.897575) (xy 348.65763 -182.836562) (xy 348.657164 -182.805832)
			(xy 2.509012 -182.805832) (xy 2.509012 -185.011568) (xy 372.585996 -185.011568) (xy 372.586426 -184.980836)
			(xy 372.593838 -184.919821) (xy 372.608551 -184.860144) (xy 372.630349 -184.802676) (xy 372.658915 -184.748254)
			(xy 372.693833 -184.697671) (xy 372.734592 -184.651667) (xy 372.7806 -184.61091) (xy 372.831184 -184.575996)
			(xy 372.885609 -184.547434) (xy 372.943079 -184.52564) (xy 373.002756 -184.510932) (xy 373.063772 -184.503524)
			(xy 373.094504 -184.50306) (xy 373.095012 -184.50306) (xy 373.128231 -184.503606) (xy 373.194103 -184.512264)
			(xy 373.258288 -184.529419) (xy 373.319696 -184.554778) (xy 373.348758 -184.570878) (xy 374.27281 -185.104532)
			(xy 374.301371 -185.121654) (xy 374.354197 -185.162201) (xy 374.401279 -185.209295) (xy 374.441813 -185.26213)
			(xy 374.475106 -185.319802) (xy 374.500588 -185.381326) (xy 374.517823 -185.445649) (xy 374.526518 -185.511672)
			(xy 374.527064 -185.544968) (xy 374.526632 -185.575701) (xy 374.519226 -185.63672) (xy 374.504519 -185.6964)
			(xy 374.482724 -185.753873) (xy 374.454161 -185.808299) (xy 374.419244 -185.858885) (xy 374.378484 -185.904893)
			(xy 374.332475 -185.945651) (xy 374.281889 -185.980567) (xy 374.227462 -186.009129) (xy 374.169989 -186.030923)
			(xy 374.110308 -186.045629) (xy 374.049289 -186.053033) (xy 374.018556 -186.053476) (xy 374.018048 -186.053476)
			(xy 373.984829 -186.052942) (xy 373.918957 -186.04428) (xy 373.854771 -186.027122) (xy 373.793364 -186.001759)
			(xy 373.764302 -185.985658) (xy 372.84025 -185.452004) (xy 372.811695 -185.434872) (xy 372.758872 -185.394325)
			(xy 372.711791 -185.347232) (xy 372.671257 -185.294398) (xy 372.637964 -185.236727) (xy 372.61248 -185.175205)
			(xy 372.595242 -185.110884) (xy 372.586544 -185.044863) (xy 372.585996 -185.011568) (xy 2.509012 -185.011568)
			(xy 2.509012 -186.714892) (xy 351.367344 -186.714892) (xy 351.367848 -186.684163) (xy 351.375257 -186.623152)
			(xy 351.389965 -186.563479) (xy 351.411758 -186.506014) (xy 351.440318 -186.451595) (xy 351.475229 -186.401014)
			(xy 351.515982 -186.355011) (xy 351.561983 -186.314254) (xy 351.612561 -186.279339) (xy 351.666978 -186.250774)
			(xy 351.724441 -186.228977) (xy 351.784113 -186.214264) (xy 351.845123 -186.206851) (xy 351.875852 -186.206384)
			(xy 351.87636 -186.206384) (xy 351.90958 -186.206906) (xy 351.975453 -186.215571) (xy 352.039638 -186.232732)
			(xy 352.101045 -186.258098) (xy 352.130106 -186.274202) (xy 353.054158 -186.807856) (xy 353.082741 -186.824943)
			(xy 353.135565 -186.865496) (xy 353.182645 -186.912596) (xy 353.223176 -186.965436) (xy 353.256466 -187.023114)
			(xy 353.281945 -187.084642) (xy 353.299177 -187.148969) (xy 353.307868 -187.214995) (xy 353.308412 -187.248292)
			(xy 353.307955 -187.279024) (xy 353.300547 -187.340039) (xy 353.285839 -187.399717) (xy 353.264044 -187.457187)
			(xy 353.235482 -187.51161) (xy 353.200567 -187.562194) (xy 353.15981 -187.608201) (xy 353.113804 -187.648959)
			(xy 353.063221 -187.683875) (xy 353.008798 -187.712439) (xy 352.951329 -187.734235) (xy 352.891651 -187.748945)
			(xy 352.830636 -187.756354) (xy 352.799904 -187.7568) (xy 352.799396 -187.7568) (xy 352.766177 -187.756256)
			(xy 352.700305 -187.747598) (xy 352.636119 -187.730443) (xy 352.574711 -187.705083) (xy 352.54565 -187.688982)
			(xy 351.621598 -187.155328) (xy 351.593065 -187.13816) (xy 351.54024 -187.09762) (xy 351.493156 -187.050533)
			(xy 351.45262 -186.997705) (xy 351.419323 -186.940039) (xy 351.393837 -186.878521) (xy 351.376595 -186.814204)
			(xy 351.367894 -186.748186) (xy 351.367344 -186.714892) (xy 2.509012 -186.714892) (xy 2.509012 -206.024988)
			(xy 86.700624 -206.024988) (xy 86.704605 -205.891968) (xy 86.716534 -205.759423) (xy 86.736369 -205.62783)
			(xy 86.764038 -205.497658) (xy 86.799442 -205.369373) (xy 86.842455 -205.243436) (xy 86.892922 -205.120297)
			(xy 86.950663 -205.000396) (xy 87.015472 -204.884163) (xy 87.087116 -204.772013) (xy 87.165338 -204.664349)
			(xy 87.249859 -204.561556) (xy 87.340377 -204.464001) (xy 87.436566 -204.372035) (xy 87.538084 -204.285985)
			(xy 87.644565 -204.206161) (xy 87.75563 -204.132848) (xy 87.870881 -204.066308) (xy 87.989905 -204.006779)
			(xy 88.112276 -203.954475) (xy 88.237555 -203.909583) (xy 88.365296 -203.872264) (xy 88.495039 -203.842651)
			(xy 88.626321 -203.82085) (xy 88.758672 -203.80694) (xy 88.891618 -203.800969) (xy 89.024683 -203.80296)
			(xy 89.157391 -203.812905) (xy 89.289267 -203.830769) (xy 89.419838 -203.856487) (xy 89.548638 -203.889968)
			(xy 89.675204 -203.931092) (xy 89.799085 -203.979712) (xy 89.919836 -204.035653) (xy 90.037026 -204.098715)
			(xy 90.150235 -204.168673) (xy 90.259057 -204.245277) (xy 90.363103 -204.328251) (xy 90.462001 -204.417299)
			(xy 90.555396 -204.512102) (xy 90.642954 -204.61232) (xy 90.724363 -204.717596) (xy 90.799329 -204.827552)
			(xy 90.867586 -204.941794) (xy 90.928888 -205.059914) (xy 90.983017 -205.181489) (xy 91.029778 -205.306083)
			(xy 91.069004 -205.433251) (xy 91.100554 -205.562537) (xy 91.124317 -205.693478) (xy 91.140206 -205.825606)
			(xy 91.148164 -205.958448) (xy 91.148662 -206.024988) (xy 132.710692 -206.024988) (xy 132.714673 -205.891968)
			(xy 132.726602 -205.759423) (xy 132.746437 -205.62783) (xy 132.774106 -205.497658) (xy 132.80951 -205.369373)
			(xy 132.852523 -205.243436) (xy 132.90299 -205.120297) (xy 132.960731 -205.000396) (xy 133.02554 -204.884163)
			(xy 133.097184 -204.772013) (xy 133.175406 -204.664349) (xy 133.259927 -204.561556) (xy 133.350445 -204.464001)
			(xy 133.446634 -204.372035) (xy 133.548152 -204.285985) (xy 133.654633 -204.206161) (xy 133.765698 -204.132848)
			(xy 133.880949 -204.066308) (xy 133.999973 -204.006779) (xy 134.122344 -203.954475) (xy 134.247623 -203.909583)
			(xy 134.375364 -203.872264) (xy 134.505107 -203.842651) (xy 134.636389 -203.82085) (xy 134.76874 -203.80694)
			(xy 134.901686 -203.800969) (xy 135.034751 -203.80296) (xy 135.167459 -203.812905) (xy 135.299335 -203.830769)
			(xy 135.429906 -203.856487) (xy 135.558706 -203.889968) (xy 135.685272 -203.931092) (xy 135.809153 -203.979712)
			(xy 135.929904 -204.035653) (xy 136.047094 -204.098715) (xy 136.160303 -204.168673) (xy 136.269125 -204.245277)
			(xy 136.373171 -204.328251) (xy 136.472069 -204.417299) (xy 136.565464 -204.512102) (xy 136.653022 -204.61232)
			(xy 136.734431 -204.717596) (xy 136.809397 -204.827552) (xy 136.877654 -204.941794) (xy 136.938956 -205.059914)
			(xy 136.993085 -205.181489) (xy 137.039846 -205.306083) (xy 137.079072 -205.433251) (xy 137.110622 -205.562537)
			(xy 137.134385 -205.693478) (xy 137.150274 -205.825606) (xy 137.158232 -205.958448) (xy 137.15873 -206.024988)
			(xy 334.640692 -206.024988) (xy 334.644673 -205.891968) (xy 334.656602 -205.759423) (xy 334.676437 -205.62783)
			(xy 334.704106 -205.497658) (xy 334.73951 -205.369373) (xy 334.782523 -205.243436) (xy 334.83299 -205.120297)
			(xy 334.890731 -205.000396) (xy 334.95554 -204.884163) (xy 335.027184 -204.772013) (xy 335.105406 -204.664349)
			(xy 335.189927 -204.561556) (xy 335.280445 -204.464001) (xy 335.376634 -204.372035) (xy 335.478152 -204.285985)
			(xy 335.584633 -204.206161) (xy 335.695698 -204.132848) (xy 335.810949 -204.066308) (xy 335.929973 -204.006779)
			(xy 336.052344 -203.954475) (xy 336.177623 -203.909583) (xy 336.305364 -203.872264) (xy 336.435107 -203.842651)
			(xy 336.566389 -203.82085) (xy 336.69874 -203.80694) (xy 336.831686 -203.800969) (xy 336.964751 -203.80296)
			(xy 337.097459 -203.812905) (xy 337.229335 -203.830769) (xy 337.359906 -203.856487) (xy 337.488706 -203.889968)
			(xy 337.615272 -203.931092) (xy 337.739153 -203.979712) (xy 337.859904 -204.035653) (xy 337.977094 -204.098715)
			(xy 338.090303 -204.168673) (xy 338.199125 -204.245277) (xy 338.303171 -204.328251) (xy 338.402069 -204.417299)
			(xy 338.495464 -204.512102) (xy 338.583022 -204.61232) (xy 338.664431 -204.717596) (xy 338.739397 -204.827552)
			(xy 338.807654 -204.941794) (xy 338.868956 -205.059914) (xy 338.923085 -205.181489) (xy 338.969846 -205.306083)
			(xy 339.009072 -205.433251) (xy 339.040622 -205.562537) (xy 339.064385 -205.693478) (xy 339.080274 -205.825606)
			(xy 339.088232 -205.958448) (xy 339.08873 -206.024988) (xy 380.650506 -206.024988) (xy 380.654487 -205.891968)
			(xy 380.666416 -205.759423) (xy 380.686251 -205.62783) (xy 380.71392 -205.497658) (xy 380.749324 -205.369373)
			(xy 380.792337 -205.243436) (xy 380.842804 -205.120297) (xy 380.900545 -205.000396) (xy 380.965354 -204.884163)
			(xy 381.036998 -204.772013) (xy 381.11522 -204.664349) (xy 381.199741 -204.561556) (xy 381.290259 -204.464001)
			(xy 381.386448 -204.372035) (xy 381.487966 -204.285985) (xy 381.594447 -204.206161) (xy 381.705512 -204.132848)
			(xy 381.820763 -204.066308) (xy 381.939787 -204.006779) (xy 382.062158 -203.954475) (xy 382.187437 -203.909583)
			(xy 382.315178 -203.872264) (xy 382.444921 -203.842651) (xy 382.576203 -203.82085) (xy 382.708554 -203.80694)
			(xy 382.8415 -203.800969) (xy 382.974565 -203.80296) (xy 383.107273 -203.812905) (xy 383.239149 -203.830769)
			(xy 383.36972 -203.856487) (xy 383.49852 -203.889968) (xy 383.625086 -203.931092) (xy 383.748967 -203.979712)
			(xy 383.869718 -204.035653) (xy 383.986908 -204.098715) (xy 384.100117 -204.168673) (xy 384.208939 -204.245277)
			(xy 384.312985 -204.328251) (xy 384.411883 -204.417299) (xy 384.505278 -204.512102) (xy 384.592836 -204.61232)
			(xy 384.674245 -204.717596) (xy 384.749211 -204.827552) (xy 384.817468 -204.941794) (xy 384.87877 -205.059914)
			(xy 384.932899 -205.181489) (xy 384.97966 -205.306083) (xy 385.018886 -205.433251) (xy 385.050436 -205.562537)
			(xy 385.074199 -205.693478) (xy 385.090088 -205.825606) (xy 385.098046 -205.958448) (xy 385.098544 -206.024988)
			(xy 385.098046 -206.091528) (xy 385.090088 -206.22437) (xy 385.074199 -206.356498) (xy 385.050436 -206.487439)
			(xy 385.018886 -206.616725) (xy 384.97966 -206.743893) (xy 384.932899 -206.868487) (xy 384.87877 -206.990062)
			(xy 384.817468 -207.108182) (xy 384.749211 -207.222424) (xy 384.674245 -207.33238) (xy 384.592836 -207.437656)
			(xy 384.505278 -207.537874) (xy 384.411883 -207.632677) (xy 384.312985 -207.721725) (xy 384.208939 -207.804699)
			(xy 384.100117 -207.881303) (xy 383.986908 -207.951261) (xy 383.869718 -208.014323) (xy 383.748967 -208.070264)
			(xy 383.625086 -208.118884) (xy 383.49852 -208.160008) (xy 383.36972 -208.193489) (xy 383.239149 -208.219207)
			(xy 383.107273 -208.237071) (xy 382.974565 -208.247016) (xy 382.8415 -208.249007) (xy 382.708554 -208.243036)
			(xy 382.576203 -208.229126) (xy 382.444921 -208.207325) (xy 382.315178 -208.177712) (xy 382.187437 -208.140393)
			(xy 382.062158 -208.095501) (xy 381.939787 -208.043197) (xy 381.820763 -207.983668) (xy 381.705512 -207.917128)
			(xy 381.594447 -207.843815) (xy 381.487966 -207.763991) (xy 381.386448 -207.677941) (xy 381.290259 -207.585975)
			(xy 381.199741 -207.48842) (xy 381.11522 -207.385627) (xy 381.036998 -207.277963) (xy 380.965354 -207.165813)
			(xy 380.900545 -207.04958) (xy 380.842804 -206.929679) (xy 380.792337 -206.80654) (xy 380.749324 -206.680603)
			(xy 380.71392 -206.552318) (xy 380.686251 -206.422146) (xy 380.666416 -206.290553) (xy 380.654487 -206.158008)
			(xy 380.650506 -206.024988) (xy 339.08873 -206.024988) (xy 339.088232 -206.091528) (xy 339.080274 -206.22437)
			(xy 339.064385 -206.356498) (xy 339.040622 -206.487439) (xy 339.009072 -206.616725) (xy 338.969846 -206.743893)
			(xy 338.923085 -206.868487) (xy 338.868956 -206.990062) (xy 338.807654 -207.108182) (xy 338.739397 -207.222424)
			(xy 338.664431 -207.33238) (xy 338.583022 -207.437656) (xy 338.495464 -207.537874) (xy 338.402069 -207.632677)
			(xy 338.303171 -207.721725) (xy 338.199125 -207.804699) (xy 338.090303 -207.881303) (xy 337.977094 -207.951261)
			(xy 337.859904 -208.014323) (xy 337.739153 -208.070264) (xy 337.615272 -208.118884) (xy 337.488706 -208.160008)
			(xy 337.359906 -208.193489) (xy 337.229335 -208.219207) (xy 337.097459 -208.237071) (xy 336.964751 -208.247016)
			(xy 336.831686 -208.249007) (xy 336.69874 -208.243036) (xy 336.566389 -208.229126) (xy 336.435107 -208.207325)
			(xy 336.305364 -208.177712) (xy 336.177623 -208.140393) (xy 336.052344 -208.095501) (xy 335.929973 -208.043197)
			(xy 335.810949 -207.983668) (xy 335.695698 -207.917128) (xy 335.584633 -207.843815) (xy 335.478152 -207.763991)
			(xy 335.376634 -207.677941) (xy 335.280445 -207.585975) (xy 335.189927 -207.48842) (xy 335.105406 -207.385627)
			(xy 335.027184 -207.277963) (xy 334.95554 -207.165813) (xy 334.890731 -207.04958) (xy 334.83299 -206.929679)
			(xy 334.782523 -206.80654) (xy 334.73951 -206.680603) (xy 334.704106 -206.552318) (xy 334.676437 -206.422146)
			(xy 334.656602 -206.290553) (xy 334.644673 -206.158008) (xy 334.640692 -206.024988) (xy 137.15873 -206.024988)
			(xy 137.158232 -206.091528) (xy 137.150274 -206.22437) (xy 137.134385 -206.356498) (xy 137.110622 -206.487439)
			(xy 137.079072 -206.616725) (xy 137.039846 -206.743893) (xy 136.993085 -206.868487) (xy 136.938956 -206.990062)
			(xy 136.877654 -207.108182) (xy 136.809397 -207.222424) (xy 136.734431 -207.33238) (xy 136.653022 -207.437656)
			(xy 136.565464 -207.537874) (xy 136.472069 -207.632677) (xy 136.373171 -207.721725) (xy 136.269125 -207.804699)
			(xy 136.160303 -207.881303) (xy 136.047094 -207.951261) (xy 135.929904 -208.014323) (xy 135.809153 -208.070264)
			(xy 135.685272 -208.118884) (xy 135.558706 -208.160008) (xy 135.429906 -208.193489) (xy 135.299335 -208.219207)
			(xy 135.167459 -208.237071) (xy 135.034751 -208.247016) (xy 134.901686 -208.249007) (xy 134.76874 -208.243036)
			(xy 134.636389 -208.229126) (xy 134.505107 -208.207325) (xy 134.375364 -208.177712) (xy 134.247623 -208.140393)
			(xy 134.122344 -208.095501) (xy 133.999973 -208.043197) (xy 133.880949 -207.983668) (xy 133.765698 -207.917128)
			(xy 133.654633 -207.843815) (xy 133.548152 -207.763991) (xy 133.446634 -207.677941) (xy 133.350445 -207.585975)
			(xy 133.259927 -207.48842) (xy 133.175406 -207.385627) (xy 133.097184 -207.277963) (xy 133.02554 -207.165813)
			(xy 132.960731 -207.04958) (xy 132.90299 -206.929679) (xy 132.852523 -206.80654) (xy 132.80951 -206.680603)
			(xy 132.774106 -206.552318) (xy 132.746437 -206.422146) (xy 132.726602 -206.290553) (xy 132.714673 -206.158008)
			(xy 132.710692 -206.024988) (xy 91.148662 -206.024988) (xy 91.148164 -206.091528) (xy 91.140206 -206.22437)
			(xy 91.124317 -206.356498) (xy 91.100554 -206.487439) (xy 91.069004 -206.616725) (xy 91.029778 -206.743893)
			(xy 90.983017 -206.868487) (xy 90.928888 -206.990062) (xy 90.867586 -207.108182) (xy 90.799329 -207.222424)
			(xy 90.724363 -207.33238) (xy 90.642954 -207.437656) (xy 90.555396 -207.537874) (xy 90.462001 -207.632677)
			(xy 90.363103 -207.721725) (xy 90.259057 -207.804699) (xy 90.150235 -207.881303) (xy 90.037026 -207.951261)
			(xy 89.919836 -208.014323) (xy 89.799085 -208.070264) (xy 89.675204 -208.118884) (xy 89.548638 -208.160008)
			(xy 89.419838 -208.193489) (xy 89.289267 -208.219207) (xy 89.157391 -208.237071) (xy 89.024683 -208.247016)
			(xy 88.891618 -208.249007) (xy 88.758672 -208.243036) (xy 88.626321 -208.229126) (xy 88.495039 -208.207325)
			(xy 88.365296 -208.177712) (xy 88.237555 -208.140393) (xy 88.112276 -208.095501) (xy 87.989905 -208.043197)
			(xy 87.870881 -207.983668) (xy 87.75563 -207.917128) (xy 87.644565 -207.843815) (xy 87.538084 -207.763991)
			(xy 87.436566 -207.677941) (xy 87.340377 -207.585975) (xy 87.249859 -207.48842) (xy 87.165338 -207.385627)
			(xy 87.087116 -207.277963) (xy 87.015472 -207.165813) (xy 86.950663 -207.04958) (xy 86.892922 -206.929679)
			(xy 86.842455 -206.80654) (xy 86.799442 -206.680603) (xy 86.764038 -206.552318) (xy 86.736369 -206.422146)
			(xy 86.716534 -206.290553) (xy 86.704605 -206.158008) (xy 86.700624 -206.024988) (xy 2.509012 -206.024988)
			(xy 2.509012 -213.732618) (xy 90.165428 -213.732618) (xy 90.165936 -213.706731) (xy 90.174035 -213.655593)
			(xy 90.190034 -213.606353) (xy 90.21354 -213.560221) (xy 90.243972 -213.518334) (xy 90.280582 -213.481724)
			(xy 90.322469 -213.451292) (xy 90.368601 -213.427786) (xy 90.417841 -213.411787) (xy 90.468979 -213.403688)
			(xy 90.520753 -213.403688) (xy 90.571891 -213.411787) (xy 90.621131 -213.427786) (xy 90.667263 -213.451292)
			(xy 90.70915 -213.481724) (xy 90.74576 -213.518334) (xy 90.776192 -213.560221) (xy 90.799698 -213.606353)
			(xy 90.815697 -213.655593) (xy 90.823796 -213.706731) (xy 90.824304 -213.732618) (xy 92.045028 -213.732618)
			(xy 92.045536 -213.706731) (xy 92.053635 -213.655593) (xy 92.069634 -213.606353) (xy 92.09314 -213.560221)
			(xy 92.123572 -213.518334) (xy 92.160182 -213.481724) (xy 92.202069 -213.451292) (xy 92.248201 -213.427786)
			(xy 92.297441 -213.411787) (xy 92.348579 -213.403688) (xy 92.400353 -213.403688) (xy 92.451491 -213.411787)
			(xy 92.500731 -213.427786) (xy 92.546863 -213.451292) (xy 92.58875 -213.481724) (xy 92.62536 -213.518334)
			(xy 92.655792 -213.560221) (xy 92.679298 -213.606353) (xy 92.695297 -213.655593) (xy 92.703396 -213.706731)
			(xy 92.703904 -213.732618) (xy 93.924628 -213.732618) (xy 93.925136 -213.706731) (xy 93.933235 -213.655593)
			(xy 93.949234 -213.606353) (xy 93.97274 -213.560221) (xy 94.003172 -213.518334) (xy 94.039782 -213.481724)
			(xy 94.081669 -213.451292) (xy 94.127801 -213.427786) (xy 94.177041 -213.411787) (xy 94.228179 -213.403688)
			(xy 94.279953 -213.403688) (xy 94.331091 -213.411787) (xy 94.380331 -213.427786) (xy 94.426463 -213.451292)
			(xy 94.46835 -213.481724) (xy 94.50496 -213.518334) (xy 94.535392 -213.560221) (xy 94.558898 -213.606353)
			(xy 94.574897 -213.655593) (xy 94.582996 -213.706731) (xy 94.583504 -213.732618) (xy 95.804228 -213.732618)
			(xy 95.804736 -213.706731) (xy 95.812835 -213.655593) (xy 95.828834 -213.606353) (xy 95.85234 -213.560221)
			(xy 95.882772 -213.518334) (xy 95.919382 -213.481724) (xy 95.961269 -213.451292) (xy 96.007401 -213.427786)
			(xy 96.056641 -213.411787) (xy 96.107779 -213.403688) (xy 96.159553 -213.403688) (xy 96.210691 -213.411787)
			(xy 96.259931 -213.427786) (xy 96.306063 -213.451292) (xy 96.34795 -213.481724) (xy 96.38456 -213.518334)
			(xy 96.414992 -213.560221) (xy 96.438498 -213.606353) (xy 96.454497 -213.655593) (xy 96.462596 -213.706731)
			(xy 96.463104 -213.732618) (xy 97.683828 -213.732618) (xy 97.684336 -213.706731) (xy 97.692435 -213.655593)
			(xy 97.708434 -213.606353) (xy 97.73194 -213.560221) (xy 97.762372 -213.518334) (xy 97.798982 -213.481724)
			(xy 97.840869 -213.451292) (xy 97.887001 -213.427786) (xy 97.936241 -213.411787) (xy 97.987379 -213.403688)
			(xy 98.039153 -213.403688) (xy 98.090291 -213.411787) (xy 98.139531 -213.427786) (xy 98.185663 -213.451292)
			(xy 98.22755 -213.481724) (xy 98.26416 -213.518334) (xy 98.294592 -213.560221) (xy 98.318098 -213.606353)
			(xy 98.334097 -213.655593) (xy 98.342196 -213.706731) (xy 98.342704 -213.732618) (xy 99.563428 -213.732618)
			(xy 99.563936 -213.706731) (xy 99.572035 -213.655593) (xy 99.588034 -213.606353) (xy 99.61154 -213.560221)
			(xy 99.641972 -213.518334) (xy 99.678582 -213.481724) (xy 99.720469 -213.451292) (xy 99.766601 -213.427786)
			(xy 99.815841 -213.411787) (xy 99.866979 -213.403688) (xy 99.918753 -213.403688) (xy 99.969891 -213.411787)
			(xy 100.019131 -213.427786) (xy 100.065263 -213.451292) (xy 100.10715 -213.481724) (xy 100.14376 -213.518334)
			(xy 100.174192 -213.560221) (xy 100.197698 -213.606353) (xy 100.213697 -213.655593) (xy 100.221796 -213.706731)
			(xy 100.222304 -213.732618) (xy 101.443028 -213.732618) (xy 101.443536 -213.706731) (xy 101.451635 -213.655593)
			(xy 101.467634 -213.606353) (xy 101.49114 -213.560221) (xy 101.521572 -213.518334) (xy 101.558182 -213.481724)
			(xy 101.600069 -213.451292) (xy 101.646201 -213.427786) (xy 101.695441 -213.411787) (xy 101.746579 -213.403688)
			(xy 101.798353 -213.403688) (xy 101.849491 -213.411787) (xy 101.898731 -213.427786) (xy 101.944863 -213.451292)
			(xy 101.98675 -213.481724) (xy 102.02336 -213.518334) (xy 102.053792 -213.560221) (xy 102.077298 -213.606353)
			(xy 102.093297 -213.655593) (xy 102.101396 -213.706731) (xy 102.101904 -213.732618) (xy 103.322628 -213.732618)
			(xy 103.323136 -213.706731) (xy 103.331235 -213.655593) (xy 103.347234 -213.606353) (xy 103.37074 -213.560221)
			(xy 103.401172 -213.518334) (xy 103.437782 -213.481724) (xy 103.479669 -213.451292) (xy 103.525801 -213.427786)
			(xy 103.575041 -213.411787) (xy 103.626179 -213.403688) (xy 103.677953 -213.403688) (xy 103.729091 -213.411787)
			(xy 103.778331 -213.427786) (xy 103.824463 -213.451292) (xy 103.86635 -213.481724) (xy 103.90296 -213.518334)
			(xy 103.933392 -213.560221) (xy 103.956898 -213.606353) (xy 103.972897 -213.655593) (xy 103.980996 -213.706731)
			(xy 103.981504 -213.732618) (xy 105.202228 -213.732618) (xy 105.202736 -213.706731) (xy 105.210835 -213.655593)
			(xy 105.226834 -213.606353) (xy 105.25034 -213.560221) (xy 105.280772 -213.518334) (xy 105.317382 -213.481724)
			(xy 105.359269 -213.451292) (xy 105.405401 -213.427786) (xy 105.454641 -213.411787) (xy 105.505779 -213.403688)
			(xy 105.557553 -213.403688) (xy 105.608691 -213.411787) (xy 105.657931 -213.427786) (xy 105.704063 -213.451292)
			(xy 105.74595 -213.481724) (xy 105.78256 -213.518334) (xy 105.812992 -213.560221) (xy 105.836498 -213.606353)
			(xy 105.852497 -213.655593) (xy 105.860596 -213.706731) (xy 105.861104 -213.732618) (xy 107.081828 -213.732618)
			(xy 107.082336 -213.706731) (xy 107.090435 -213.655593) (xy 107.106434 -213.606353) (xy 107.12994 -213.560221)
			(xy 107.160372 -213.518334) (xy 107.196982 -213.481724) (xy 107.238869 -213.451292) (xy 107.285001 -213.427786)
			(xy 107.334241 -213.411787) (xy 107.385379 -213.403688) (xy 107.437153 -213.403688) (xy 107.488291 -213.411787)
			(xy 107.537531 -213.427786) (xy 107.583663 -213.451292) (xy 107.62555 -213.481724) (xy 107.66216 -213.518334)
			(xy 107.692592 -213.560221) (xy 107.716098 -213.606353) (xy 107.732097 -213.655593) (xy 107.740196 -213.706731)
			(xy 107.740704 -213.732618) (xy 114.600228 -213.732618) (xy 114.600736 -213.706731) (xy 114.608835 -213.655593)
			(xy 114.624834 -213.606353) (xy 114.64834 -213.560221) (xy 114.678772 -213.518334) (xy 114.715382 -213.481724)
			(xy 114.757269 -213.451292) (xy 114.803401 -213.427786) (xy 114.852641 -213.411787) (xy 114.903779 -213.403688)
			(xy 114.955553 -213.403688) (xy 115.006691 -213.411787) (xy 115.055931 -213.427786) (xy 115.102063 -213.451292)
			(xy 115.14395 -213.481724) (xy 115.18056 -213.518334) (xy 115.210992 -213.560221) (xy 115.234498 -213.606353)
			(xy 115.250497 -213.655593) (xy 115.258596 -213.706731) (xy 115.259104 -213.732618) (xy 116.479828 -213.732618)
			(xy 116.480336 -213.706731) (xy 116.488435 -213.655593) (xy 116.504434 -213.606353) (xy 116.52794 -213.560221)
			(xy 116.558372 -213.518334) (xy 116.594982 -213.481724) (xy 116.636869 -213.451292) (xy 116.683001 -213.427786)
			(xy 116.732241 -213.411787) (xy 116.783379 -213.403688) (xy 116.835153 -213.403688) (xy 116.886291 -213.411787)
			(xy 116.935531 -213.427786) (xy 116.981663 -213.451292) (xy 117.02355 -213.481724) (xy 117.06016 -213.518334)
			(xy 117.090592 -213.560221) (xy 117.114098 -213.606353) (xy 117.130097 -213.655593) (xy 117.138196 -213.706731)
			(xy 117.138704 -213.732618) (xy 118.359428 -213.732618) (xy 118.359936 -213.706731) (xy 118.368035 -213.655593)
			(xy 118.384034 -213.606353) (xy 118.40754 -213.560221) (xy 118.437972 -213.518334) (xy 118.474582 -213.481724)
			(xy 118.516469 -213.451292) (xy 118.562601 -213.427786) (xy 118.611841 -213.411787) (xy 118.662979 -213.403688)
			(xy 118.714753 -213.403688) (xy 118.765891 -213.411787) (xy 118.815131 -213.427786) (xy 118.861263 -213.451292)
			(xy 118.90315 -213.481724) (xy 118.93976 -213.518334) (xy 118.970192 -213.560221) (xy 118.993698 -213.606353)
			(xy 119.009697 -213.655593) (xy 119.017796 -213.706731) (xy 119.018304 -213.732618) (xy 120.239028 -213.732618)
			(xy 120.239536 -213.706731) (xy 120.247635 -213.655593) (xy 120.263634 -213.606353) (xy 120.28714 -213.560221)
			(xy 120.317572 -213.518334) (xy 120.354182 -213.481724) (xy 120.396069 -213.451292) (xy 120.442201 -213.427786)
			(xy 120.491441 -213.411787) (xy 120.542579 -213.403688) (xy 120.594353 -213.403688) (xy 120.645491 -213.411787)
			(xy 120.694731 -213.427786) (xy 120.740863 -213.451292) (xy 120.78275 -213.481724) (xy 120.81936 -213.518334)
			(xy 120.849792 -213.560221) (xy 120.873298 -213.606353) (xy 120.889297 -213.655593) (xy 120.897396 -213.706731)
			(xy 120.897904 -213.732618) (xy 122.118628 -213.732618) (xy 122.119136 -213.706731) (xy 122.127235 -213.655593)
			(xy 122.143234 -213.606353) (xy 122.16674 -213.560221) (xy 122.197172 -213.518334) (xy 122.233782 -213.481724)
			(xy 122.275669 -213.451292) (xy 122.321801 -213.427786) (xy 122.371041 -213.411787) (xy 122.422179 -213.403688)
			(xy 122.473953 -213.403688) (xy 122.525091 -213.411787) (xy 122.574331 -213.427786) (xy 122.620463 -213.451292)
			(xy 122.66235 -213.481724) (xy 122.69896 -213.518334) (xy 122.729392 -213.560221) (xy 122.752898 -213.606353)
			(xy 122.768897 -213.655593) (xy 122.776996 -213.706731) (xy 122.777504 -213.732618) (xy 123.99772 -213.732618)
			(xy 123.998228 -213.706711) (xy 124.006334 -213.655534) (xy 124.022346 -213.606255) (xy 124.045869 -213.560088)
			(xy 124.076325 -213.518169) (xy 124.112963 -213.481531) (xy 124.154882 -213.451075) (xy 124.201049 -213.427552)
			(xy 124.250328 -213.41154) (xy 124.301505 -213.403434) (xy 124.353319 -213.403434) (xy 124.404496 -213.41154)
			(xy 124.453775 -213.427552) (xy 124.499942 -213.451075) (xy 124.541861 -213.481531) (xy 124.578499 -213.518169)
			(xy 124.608955 -213.560088) (xy 124.632478 -213.606255) (xy 124.64849 -213.655534) (xy 124.656596 -213.706711)
			(xy 124.657104 -213.732618) (xy 125.87732 -213.732618) (xy 125.877828 -213.706711) (xy 125.885934 -213.655534)
			(xy 125.901946 -213.606255) (xy 125.925469 -213.560088) (xy 125.955925 -213.518169) (xy 125.992563 -213.481531)
			(xy 126.034482 -213.451075) (xy 126.080649 -213.427552) (xy 126.129928 -213.41154) (xy 126.181105 -213.403434)
			(xy 126.232919 -213.403434) (xy 126.284096 -213.41154) (xy 126.333375 -213.427552) (xy 126.379542 -213.451075)
			(xy 126.421461 -213.481531) (xy 126.458099 -213.518169) (xy 126.488555 -213.560088) (xy 126.512078 -213.606255)
			(xy 126.52809 -213.655534) (xy 126.536196 -213.706711) (xy 126.536704 -213.732618) (xy 127.757428 -213.732618)
			(xy 127.757936 -213.706731) (xy 127.766035 -213.655593) (xy 127.782034 -213.606353) (xy 127.80554 -213.560221)
			(xy 127.835972 -213.518334) (xy 127.872582 -213.481724) (xy 127.914469 -213.451292) (xy 127.960601 -213.427786)
			(xy 128.009841 -213.411787) (xy 128.060979 -213.403688) (xy 128.112753 -213.403688) (xy 128.163891 -213.411787)
			(xy 128.213131 -213.427786) (xy 128.259263 -213.451292) (xy 128.30115 -213.481724) (xy 128.33776 -213.518334)
			(xy 128.368192 -213.560221) (xy 128.391698 -213.606353) (xy 128.407697 -213.655593) (xy 128.415796 -213.706731)
			(xy 128.416304 -213.732618) (xy 129.637028 -213.732618) (xy 129.637536 -213.706731) (xy 129.645635 -213.655593)
			(xy 129.661634 -213.606353) (xy 129.68514 -213.560221) (xy 129.715572 -213.518334) (xy 129.752182 -213.481724)
			(xy 129.794069 -213.451292) (xy 129.840201 -213.427786) (xy 129.889441 -213.411787) (xy 129.940579 -213.403688)
			(xy 129.992353 -213.403688) (xy 130.043491 -213.411787) (xy 130.092731 -213.427786) (xy 130.138863 -213.451292)
			(xy 130.18075 -213.481724) (xy 130.21736 -213.518334) (xy 130.247792 -213.560221) (xy 130.271298 -213.606353)
			(xy 130.287297 -213.655593) (xy 130.295396 -213.706731) (xy 130.295904 -213.732618) (xy 131.516628 -213.732618)
			(xy 131.517136 -213.706731) (xy 131.525235 -213.655593) (xy 131.541234 -213.606353) (xy 131.56474 -213.560221)
			(xy 131.595172 -213.518334) (xy 131.631782 -213.481724) (xy 131.673669 -213.451292) (xy 131.719801 -213.427786)
			(xy 131.769041 -213.411787) (xy 131.820179 -213.403688) (xy 131.871953 -213.403688) (xy 131.923091 -213.411787)
			(xy 131.972331 -213.427786) (xy 132.018463 -213.451292) (xy 132.06035 -213.481724) (xy 132.09696 -213.518334)
			(xy 132.127392 -213.560221) (xy 132.150898 -213.606353) (xy 132.166897 -213.655593) (xy 132.174996 -213.706731)
			(xy 132.175504 -213.732618) (xy 338.105496 -213.732618) (xy 338.106004 -213.706731) (xy 338.114103 -213.655593)
			(xy 338.130102 -213.606353) (xy 338.153608 -213.560221) (xy 338.18404 -213.518334) (xy 338.22065 -213.481724)
			(xy 338.262537 -213.451292) (xy 338.308669 -213.427786) (xy 338.357909 -213.411787) (xy 338.409047 -213.403688)
			(xy 338.460821 -213.403688) (xy 338.511959 -213.411787) (xy 338.561199 -213.427786) (xy 338.607331 -213.451292)
			(xy 338.649218 -213.481724) (xy 338.685828 -213.518334) (xy 338.71626 -213.560221) (xy 338.739766 -213.606353)
			(xy 338.755765 -213.655593) (xy 338.763864 -213.706731) (xy 338.764372 -213.732618) (xy 339.985096 -213.732618)
			(xy 339.985604 -213.706731) (xy 339.993703 -213.655593) (xy 340.009702 -213.606353) (xy 340.033208 -213.560221)
			(xy 340.06364 -213.518334) (xy 340.10025 -213.481724) (xy 340.142137 -213.451292) (xy 340.188269 -213.427786)
			(xy 340.237509 -213.411787) (xy 340.288647 -213.403688) (xy 340.340421 -213.403688) (xy 340.391559 -213.411787)
			(xy 340.440799 -213.427786) (xy 340.486931 -213.451292) (xy 340.528818 -213.481724) (xy 340.565428 -213.518334)
			(xy 340.59586 -213.560221) (xy 340.619366 -213.606353) (xy 340.635365 -213.655593) (xy 340.643464 -213.706731)
			(xy 340.643972 -213.732618) (xy 341.864696 -213.732618) (xy 341.865204 -213.706731) (xy 341.873303 -213.655593)
			(xy 341.889302 -213.606353) (xy 341.912808 -213.560221) (xy 341.94324 -213.518334) (xy 341.97985 -213.481724)
			(xy 342.021737 -213.451292) (xy 342.067869 -213.427786) (xy 342.117109 -213.411787) (xy 342.168247 -213.403688)
			(xy 342.220021 -213.403688) (xy 342.271159 -213.411787) (xy 342.320399 -213.427786) (xy 342.366531 -213.451292)
			(xy 342.408418 -213.481724) (xy 342.445028 -213.518334) (xy 342.47546 -213.560221) (xy 342.498966 -213.606353)
			(xy 342.514965 -213.655593) (xy 342.523064 -213.706731) (xy 342.523572 -213.732618) (xy 343.744296 -213.732618)
			(xy 343.744804 -213.706731) (xy 343.752903 -213.655593) (xy 343.768902 -213.606353) (xy 343.792408 -213.560221)
			(xy 343.82284 -213.518334) (xy 343.85945 -213.481724) (xy 343.901337 -213.451292) (xy 343.947469 -213.427786)
			(xy 343.996709 -213.411787) (xy 344.047847 -213.403688) (xy 344.099621 -213.403688) (xy 344.150759 -213.411787)
			(xy 344.199999 -213.427786) (xy 344.246131 -213.451292) (xy 344.288018 -213.481724) (xy 344.324628 -213.518334)
			(xy 344.35506 -213.560221) (xy 344.378566 -213.606353) (xy 344.394565 -213.655593) (xy 344.402664 -213.706731)
			(xy 344.403172 -213.732618) (xy 345.623896 -213.732618) (xy 345.624404 -213.706731) (xy 345.632503 -213.655593)
			(xy 345.648502 -213.606353) (xy 345.672008 -213.560221) (xy 345.70244 -213.518334) (xy 345.73905 -213.481724)
			(xy 345.780937 -213.451292) (xy 345.827069 -213.427786) (xy 345.876309 -213.411787) (xy 345.927447 -213.403688)
			(xy 345.979221 -213.403688) (xy 346.030359 -213.411787) (xy 346.079599 -213.427786) (xy 346.125731 -213.451292)
			(xy 346.167618 -213.481724) (xy 346.204228 -213.518334) (xy 346.23466 -213.560221) (xy 346.258166 -213.606353)
			(xy 346.274165 -213.655593) (xy 346.282264 -213.706731) (xy 346.282772 -213.732618) (xy 347.503496 -213.732618)
			(xy 347.504004 -213.706731) (xy 347.512103 -213.655593) (xy 347.528102 -213.606353) (xy 347.551608 -213.560221)
			(xy 347.58204 -213.518334) (xy 347.61865 -213.481724) (xy 347.660537 -213.451292) (xy 347.706669 -213.427786)
			(xy 347.755909 -213.411787) (xy 347.807047 -213.403688) (xy 347.858821 -213.403688) (xy 347.909959 -213.411787)
			(xy 347.959199 -213.427786) (xy 348.005331 -213.451292) (xy 348.047218 -213.481724) (xy 348.083828 -213.518334)
			(xy 348.11426 -213.560221) (xy 348.137766 -213.606353) (xy 348.153765 -213.655593) (xy 348.161864 -213.706731)
			(xy 348.162372 -213.732618) (xy 349.383096 -213.732618) (xy 349.383604 -213.706731) (xy 349.391703 -213.655593)
			(xy 349.407702 -213.606353) (xy 349.431208 -213.560221) (xy 349.46164 -213.518334) (xy 349.49825 -213.481724)
			(xy 349.540137 -213.451292) (xy 349.586269 -213.427786) (xy 349.635509 -213.411787) (xy 349.686647 -213.403688)
			(xy 349.738421 -213.403688) (xy 349.789559 -213.411787) (xy 349.838799 -213.427786) (xy 349.884931 -213.451292)
			(xy 349.926818 -213.481724) (xy 349.963428 -213.518334) (xy 349.99386 -213.560221) (xy 350.017366 -213.606353)
			(xy 350.033365 -213.655593) (xy 350.041464 -213.706731) (xy 350.041972 -213.732618) (xy 351.262696 -213.732618)
			(xy 351.263204 -213.706731) (xy 351.271303 -213.655593) (xy 351.287302 -213.606353) (xy 351.310808 -213.560221)
			(xy 351.34124 -213.518334) (xy 351.37785 -213.481724) (xy 351.419737 -213.451292) (xy 351.465869 -213.427786)
			(xy 351.515109 -213.411787) (xy 351.566247 -213.403688) (xy 351.618021 -213.403688) (xy 351.669159 -213.411787)
			(xy 351.718399 -213.427786) (xy 351.764531 -213.451292) (xy 351.806418 -213.481724) (xy 351.843028 -213.518334)
			(xy 351.87346 -213.560221) (xy 351.896966 -213.606353) (xy 351.912965 -213.655593) (xy 351.921064 -213.706731)
			(xy 351.921572 -213.732618) (xy 353.142296 -213.732618) (xy 353.142804 -213.706731) (xy 353.150903 -213.655593)
			(xy 353.166902 -213.606353) (xy 353.190408 -213.560221) (xy 353.22084 -213.518334) (xy 353.25745 -213.481724)
			(xy 353.299337 -213.451292) (xy 353.345469 -213.427786) (xy 353.394709 -213.411787) (xy 353.445847 -213.403688)
			(xy 353.497621 -213.403688) (xy 353.548759 -213.411787) (xy 353.597999 -213.427786) (xy 353.644131 -213.451292)
			(xy 353.686018 -213.481724) (xy 353.722628 -213.518334) (xy 353.75306 -213.560221) (xy 353.776566 -213.606353)
			(xy 353.792565 -213.655593) (xy 353.800664 -213.706731) (xy 353.801172 -213.732618) (xy 355.021896 -213.732618)
			(xy 355.022404 -213.706731) (xy 355.030503 -213.655593) (xy 355.046502 -213.606353) (xy 355.070008 -213.560221)
			(xy 355.10044 -213.518334) (xy 355.13705 -213.481724) (xy 355.178937 -213.451292) (xy 355.225069 -213.427786)
			(xy 355.274309 -213.411787) (xy 355.325447 -213.403688) (xy 355.377221 -213.403688) (xy 355.428359 -213.411787)
			(xy 355.477599 -213.427786) (xy 355.523731 -213.451292) (xy 355.565618 -213.481724) (xy 355.602228 -213.518334)
			(xy 355.63266 -213.560221) (xy 355.656166 -213.606353) (xy 355.672165 -213.655593) (xy 355.680264 -213.706731)
			(xy 355.680772 -213.732618) (xy 355.680423 -213.755595) (xy 355.674102 -213.801111) (xy 355.661516 -213.845306)
			(xy 355.652578 -213.866476) (xy 355.642672 -213.888828) (xy 355.856286 -214.293958) (xy 355.880416 -214.29853)
			(xy 355.90533 -214.303664) (xy 355.95334 -214.320459) (xy 355.998199 -214.344434) (xy 356.038841 -214.375017)
			(xy 356.074299 -214.411484) (xy 356.103732 -214.452967) (xy 356.12644 -214.49848) (xy 356.141883 -214.546942)
			(xy 356.149695 -214.597202) (xy 356.150164 -214.622634) (xy 356.149656 -214.648521) (xy 356.141557 -214.699659)
			(xy 356.125558 -214.748899) (xy 356.102052 -214.795031) (xy 356.07162 -214.836918) (xy 356.03501 -214.873528)
			(xy 355.993123 -214.90396) (xy 355.946991 -214.927466) (xy 355.897751 -214.943465) (xy 355.846613 -214.951564)
			(xy 355.794839 -214.951564) (xy 355.743701 -214.943465) (xy 355.694461 -214.927466) (xy 355.648329 -214.90396)
			(xy 355.606442 -214.873528) (xy 355.569832 -214.836918) (xy 355.5394 -214.795031) (xy 355.515894 -214.748899)
			(xy 355.499895 -214.699659) (xy 355.491796 -214.648521) (xy 355.491288 -214.622634) (xy 355.491658 -214.599658)
			(xy 355.49797 -214.554143) (xy 355.510548 -214.509947) (xy 355.519482 -214.488776) (xy 355.529388 -214.466424)
			(xy 355.315774 -214.061294) (xy 355.291644 -214.056722) (xy 355.266713 -214.051663) (xy 355.218699 -214.034858)
			(xy 355.173839 -214.010874) (xy 355.133197 -213.980281) (xy 355.097739 -213.943805) (xy 355.068309 -213.902313)
			(xy 355.045605 -213.856791) (xy 355.030167 -213.80832) (xy 355.022362 -213.758053) (xy 355.021896 -213.732618)
			(xy 353.801172 -213.732618) (xy 353.800823 -213.755595) (xy 353.794502 -213.801111) (xy 353.781916 -213.845306)
			(xy 353.772978 -213.866476) (xy 353.763072 -213.888828) (xy 353.976686 -214.293958) (xy 354.000816 -214.29853)
			(xy 354.02573 -214.303664) (xy 354.07374 -214.320459) (xy 354.118599 -214.344434) (xy 354.159241 -214.375017)
			(xy 354.194699 -214.411484) (xy 354.224132 -214.452967) (xy 354.24684 -214.49848) (xy 354.262283 -214.546942)
			(xy 354.270095 -214.597202) (xy 354.270564 -214.622634) (xy 354.270056 -214.648521) (xy 354.261957 -214.699659)
			(xy 354.245958 -214.748899) (xy 354.222452 -214.795031) (xy 354.19202 -214.836918) (xy 354.15541 -214.873528)
			(xy 354.113523 -214.90396) (xy 354.067391 -214.927466) (xy 354.018151 -214.943465) (xy 353.967013 -214.951564)
			(xy 353.915239 -214.951564) (xy 353.864101 -214.943465) (xy 353.814861 -214.927466) (xy 353.768729 -214.90396)
			(xy 353.726842 -214.873528) (xy 353.690232 -214.836918) (xy 353.6598 -214.795031) (xy 353.636294 -214.748899)
			(xy 353.620295 -214.699659) (xy 353.612196 -214.648521) (xy 353.611688 -214.622634) (xy 353.612058 -214.599658)
			(xy 353.61837 -214.554143) (xy 353.630948 -214.509947) (xy 353.639882 -214.488776) (xy 353.649788 -214.466424)
			(xy 353.436174 -214.061294) (xy 353.412044 -214.056722) (xy 353.387113 -214.051663) (xy 353.339099 -214.034858)
			(xy 353.294239 -214.010874) (xy 353.253597 -213.980281) (xy 353.218139 -213.943805) (xy 353.188709 -213.902313)
			(xy 353.166005 -213.856791) (xy 353.150567 -213.80832) (xy 353.142762 -213.758053) (xy 353.142296 -213.732618)
			(xy 351.921572 -213.732618) (xy 351.921223 -213.755595) (xy 351.914902 -213.801111) (xy 351.902316 -213.845306)
			(xy 351.893378 -213.866476) (xy 351.883472 -213.888828) (xy 352.097086 -214.293958) (xy 352.121216 -214.29853)
			(xy 352.14613 -214.303664) (xy 352.19414 -214.320459) (xy 352.238999 -214.344434) (xy 352.279641 -214.375017)
			(xy 352.315099 -214.411484) (xy 352.344532 -214.452967) (xy 352.36724 -214.49848) (xy 352.382683 -214.546942)
			(xy 352.390495 -214.597202) (xy 352.390964 -214.622634) (xy 352.390456 -214.648521) (xy 352.382357 -214.699659)
			(xy 352.366358 -214.748899) (xy 352.342852 -214.795031) (xy 352.31242 -214.836918) (xy 352.27581 -214.873528)
			(xy 352.233923 -214.90396) (xy 352.187791 -214.927466) (xy 352.138551 -214.943465) (xy 352.087413 -214.951564)
			(xy 352.035639 -214.951564) (xy 351.984501 -214.943465) (xy 351.935261 -214.927466) (xy 351.889129 -214.90396)
			(xy 351.847242 -214.873528) (xy 351.810632 -214.836918) (xy 351.7802 -214.795031) (xy 351.756694 -214.748899)
			(xy 351.740695 -214.699659) (xy 351.732596 -214.648521) (xy 351.732088 -214.622634) (xy 351.732458 -214.599658)
			(xy 351.73877 -214.554143) (xy 351.751348 -214.509947) (xy 351.760282 -214.488776) (xy 351.770188 -214.466424)
			(xy 351.556574 -214.061294) (xy 351.532444 -214.056722) (xy 351.507513 -214.051663) (xy 351.459499 -214.034858)
			(xy 351.414639 -214.010874) (xy 351.373997 -213.980281) (xy 351.338539 -213.943805) (xy 351.309109 -213.902313)
			(xy 351.286405 -213.856791) (xy 351.270967 -213.80832) (xy 351.263162 -213.758053) (xy 351.262696 -213.732618)
			(xy 350.041972 -213.732618) (xy 350.041623 -213.755595) (xy 350.035302 -213.801111) (xy 350.022716 -213.845306)
			(xy 350.013778 -213.866476) (xy 350.003872 -213.888828) (xy 350.217486 -214.293958) (xy 350.241616 -214.29853)
			(xy 350.26653 -214.303664) (xy 350.31454 -214.320459) (xy 350.359399 -214.344434) (xy 350.400041 -214.375017)
			(xy 350.435499 -214.411484) (xy 350.464932 -214.452967) (xy 350.48764 -214.49848) (xy 350.503083 -214.546942)
			(xy 350.510895 -214.597202) (xy 350.511364 -214.622634) (xy 350.510856 -214.648521) (xy 350.502757 -214.699659)
			(xy 350.486758 -214.748899) (xy 350.463252 -214.795031) (xy 350.43282 -214.836918) (xy 350.39621 -214.873528)
			(xy 350.354323 -214.90396) (xy 350.308191 -214.927466) (xy 350.258951 -214.943465) (xy 350.207813 -214.951564)
			(xy 350.156039 -214.951564) (xy 350.104901 -214.943465) (xy 350.055661 -214.927466) (xy 350.009529 -214.90396)
			(xy 349.967642 -214.873528) (xy 349.931032 -214.836918) (xy 349.9006 -214.795031) (xy 349.877094 -214.748899)
			(xy 349.861095 -214.699659) (xy 349.852996 -214.648521) (xy 349.852488 -214.622634) (xy 349.852858 -214.599658)
			(xy 349.85917 -214.554143) (xy 349.871748 -214.509947) (xy 349.880682 -214.488776) (xy 349.890588 -214.466424)
			(xy 349.676974 -214.061294) (xy 349.652844 -214.056722) (xy 349.627913 -214.051663) (xy 349.579899 -214.034858)
			(xy 349.535039 -214.010874) (xy 349.494397 -213.980281) (xy 349.458939 -213.943805) (xy 349.429509 -213.902313)
			(xy 349.406805 -213.856791) (xy 349.391367 -213.80832) (xy 349.383562 -213.758053) (xy 349.383096 -213.732618)
			(xy 348.162372 -213.732618) (xy 348.162023 -213.755595) (xy 348.155702 -213.801111) (xy 348.143116 -213.845306)
			(xy 348.134178 -213.866476) (xy 348.124272 -213.888828) (xy 348.337886 -214.293958) (xy 348.362016 -214.29853)
			(xy 348.38693 -214.303664) (xy 348.43494 -214.320459) (xy 348.479799 -214.344434) (xy 348.520441 -214.375017)
			(xy 348.555899 -214.411484) (xy 348.585332 -214.452967) (xy 348.60804 -214.49848) (xy 348.623483 -214.546942)
			(xy 348.631295 -214.597202) (xy 348.631764 -214.622634) (xy 348.631256 -214.648521) (xy 348.623157 -214.699659)
			(xy 348.607158 -214.748899) (xy 348.583652 -214.795031) (xy 348.55322 -214.836918) (xy 348.51661 -214.873528)
			(xy 348.474723 -214.90396) (xy 348.428591 -214.927466) (xy 348.379351 -214.943465) (xy 348.328213 -214.951564)
			(xy 348.276439 -214.951564) (xy 348.225301 -214.943465) (xy 348.176061 -214.927466) (xy 348.129929 -214.90396)
			(xy 348.088042 -214.873528) (xy 348.051432 -214.836918) (xy 348.021 -214.795031) (xy 347.997494 -214.748899)
			(xy 347.981495 -214.699659) (xy 347.973396 -214.648521) (xy 347.972888 -214.622634) (xy 347.973258 -214.599658)
			(xy 347.97957 -214.554143) (xy 347.992148 -214.509947) (xy 348.001082 -214.488776) (xy 348.010988 -214.466424)
			(xy 347.797374 -214.061294) (xy 347.773244 -214.056722) (xy 347.748313 -214.051663) (xy 347.700299 -214.034858)
			(xy 347.655439 -214.010874) (xy 347.614797 -213.980281) (xy 347.579339 -213.943805) (xy 347.549909 -213.902313)
			(xy 347.527205 -213.856791) (xy 347.511767 -213.80832) (xy 347.503962 -213.758053) (xy 347.503496 -213.732618)
			(xy 346.282772 -213.732618) (xy 346.282423 -213.755595) (xy 346.276102 -213.801111) (xy 346.263516 -213.845306)
			(xy 346.254578 -213.866476) (xy 346.244672 -213.888828) (xy 346.458286 -214.293958) (xy 346.482416 -214.29853)
			(xy 346.50733 -214.303664) (xy 346.55534 -214.320459) (xy 346.600199 -214.344434) (xy 346.640841 -214.375017)
			(xy 346.676299 -214.411484) (xy 346.705732 -214.452967) (xy 346.72844 -214.49848) (xy 346.743883 -214.546942)
			(xy 346.751695 -214.597202) (xy 346.752164 -214.622634) (xy 346.751656 -214.648521) (xy 346.743557 -214.699659)
			(xy 346.727558 -214.748899) (xy 346.704052 -214.795031) (xy 346.67362 -214.836918) (xy 346.63701 -214.873528)
			(xy 346.595123 -214.90396) (xy 346.548991 -214.927466) (xy 346.499751 -214.943465) (xy 346.448613 -214.951564)
			(xy 346.396839 -214.951564) (xy 346.345701 -214.943465) (xy 346.296461 -214.927466) (xy 346.250329 -214.90396)
			(xy 346.208442 -214.873528) (xy 346.171832 -214.836918) (xy 346.1414 -214.795031) (xy 346.117894 -214.748899)
			(xy 346.101895 -214.699659) (xy 346.093796 -214.648521) (xy 346.093288 -214.622634) (xy 346.093658 -214.599658)
			(xy 346.09997 -214.554143) (xy 346.112548 -214.509947) (xy 346.121482 -214.488776) (xy 346.131388 -214.466424)
			(xy 345.917774 -214.061294) (xy 345.893644 -214.056722) (xy 345.868713 -214.051663) (xy 345.820699 -214.034858)
			(xy 345.775839 -214.010874) (xy 345.735197 -213.980281) (xy 345.699739 -213.943805) (xy 345.670309 -213.902313)
			(xy 345.647605 -213.856791) (xy 345.632167 -213.80832) (xy 345.624362 -213.758053) (xy 345.623896 -213.732618)
			(xy 344.403172 -213.732618) (xy 344.402823 -213.755595) (xy 344.396502 -213.801111) (xy 344.383916 -213.845306)
			(xy 344.374978 -213.866476) (xy 344.365072 -213.888828) (xy 344.578686 -214.293958) (xy 344.602816 -214.29853)
			(xy 344.62773 -214.303664) (xy 344.67574 -214.320459) (xy 344.720599 -214.344434) (xy 344.761241 -214.375017)
			(xy 344.796699 -214.411484) (xy 344.826132 -214.452967) (xy 344.84884 -214.49848) (xy 344.864283 -214.546942)
			(xy 344.872095 -214.597202) (xy 344.872564 -214.622634) (xy 344.872056 -214.648521) (xy 344.863957 -214.699659)
			(xy 344.847958 -214.748899) (xy 344.824452 -214.795031) (xy 344.79402 -214.836918) (xy 344.75741 -214.873528)
			(xy 344.715523 -214.90396) (xy 344.669391 -214.927466) (xy 344.620151 -214.943465) (xy 344.569013 -214.951564)
			(xy 344.517239 -214.951564) (xy 344.466101 -214.943465) (xy 344.416861 -214.927466) (xy 344.370729 -214.90396)
			(xy 344.328842 -214.873528) (xy 344.292232 -214.836918) (xy 344.2618 -214.795031) (xy 344.238294 -214.748899)
			(xy 344.222295 -214.699659) (xy 344.214196 -214.648521) (xy 344.213688 -214.622634) (xy 344.214058 -214.599658)
			(xy 344.22037 -214.554143) (xy 344.232948 -214.509947) (xy 344.241882 -214.488776) (xy 344.251788 -214.466424)
			(xy 344.038174 -214.061294) (xy 344.014044 -214.056722) (xy 343.989113 -214.051663) (xy 343.941099 -214.034858)
			(xy 343.896239 -214.010874) (xy 343.855597 -213.980281) (xy 343.820139 -213.943805) (xy 343.790709 -213.902313)
			(xy 343.768005 -213.856791) (xy 343.752567 -213.80832) (xy 343.744762 -213.758053) (xy 343.744296 -213.732618)
			(xy 342.523572 -213.732618) (xy 342.523223 -213.755595) (xy 342.516902 -213.801111) (xy 342.504316 -213.845306)
			(xy 342.495378 -213.866476) (xy 342.485472 -213.888828) (xy 342.699086 -214.293958) (xy 342.723216 -214.29853)
			(xy 342.74813 -214.303664) (xy 342.79614 -214.320459) (xy 342.840999 -214.344434) (xy 342.881641 -214.375017)
			(xy 342.917099 -214.411484) (xy 342.946532 -214.452967) (xy 342.96924 -214.49848) (xy 342.984683 -214.546942)
			(xy 342.992495 -214.597202) (xy 342.992964 -214.622634) (xy 342.992456 -214.648521) (xy 342.984357 -214.699659)
			(xy 342.968358 -214.748899) (xy 342.944852 -214.795031) (xy 342.91442 -214.836918) (xy 342.87781 -214.873528)
			(xy 342.835923 -214.90396) (xy 342.789791 -214.927466) (xy 342.740551 -214.943465) (xy 342.689413 -214.951564)
			(xy 342.637639 -214.951564) (xy 342.586501 -214.943465) (xy 342.537261 -214.927466) (xy 342.491129 -214.90396)
			(xy 342.449242 -214.873528) (xy 342.412632 -214.836918) (xy 342.3822 -214.795031) (xy 342.358694 -214.748899)
			(xy 342.342695 -214.699659) (xy 342.334596 -214.648521) (xy 342.334088 -214.622634) (xy 342.334458 -214.599658)
			(xy 342.34077 -214.554143) (xy 342.353348 -214.509947) (xy 342.362282 -214.488776) (xy 342.372188 -214.466424)
			(xy 342.158574 -214.061294) (xy 342.134444 -214.056722) (xy 342.109513 -214.051663) (xy 342.061499 -214.034858)
			(xy 342.016639 -214.010874) (xy 341.975997 -213.980281) (xy 341.940539 -213.943805) (xy 341.911109 -213.902313)
			(xy 341.888405 -213.856791) (xy 341.872967 -213.80832) (xy 341.865162 -213.758053) (xy 341.864696 -213.732618)
			(xy 340.643972 -213.732618) (xy 340.643623 -213.755595) (xy 340.637302 -213.801111) (xy 340.624716 -213.845306)
			(xy 340.615778 -213.866476) (xy 340.605872 -213.888828) (xy 340.819486 -214.293958) (xy 340.843616 -214.29853)
			(xy 340.86853 -214.303664) (xy 340.91654 -214.320459) (xy 340.961399 -214.344434) (xy 341.002041 -214.375017)
			(xy 341.037499 -214.411484) (xy 341.066932 -214.452967) (xy 341.08964 -214.49848) (xy 341.105083 -214.546942)
			(xy 341.112895 -214.597202) (xy 341.113364 -214.622634) (xy 341.112856 -214.648521) (xy 341.104757 -214.699659)
			(xy 341.088758 -214.748899) (xy 341.065252 -214.795031) (xy 341.03482 -214.836918) (xy 340.99821 -214.873528)
			(xy 340.956323 -214.90396) (xy 340.910191 -214.927466) (xy 340.860951 -214.943465) (xy 340.809813 -214.951564)
			(xy 340.758039 -214.951564) (xy 340.706901 -214.943465) (xy 340.657661 -214.927466) (xy 340.611529 -214.90396)
			(xy 340.569642 -214.873528) (xy 340.533032 -214.836918) (xy 340.5026 -214.795031) (xy 340.479094 -214.748899)
			(xy 340.463095 -214.699659) (xy 340.454996 -214.648521) (xy 340.454488 -214.622634) (xy 340.454858 -214.599658)
			(xy 340.46117 -214.554143) (xy 340.473748 -214.509947) (xy 340.482682 -214.488776) (xy 340.492588 -214.466424)
			(xy 340.278974 -214.061294) (xy 340.254844 -214.056722) (xy 340.229913 -214.051663) (xy 340.181899 -214.034858)
			(xy 340.137039 -214.010874) (xy 340.096397 -213.980281) (xy 340.060939 -213.943805) (xy 340.031509 -213.902313)
			(xy 340.008805 -213.856791) (xy 339.993367 -213.80832) (xy 339.985562 -213.758053) (xy 339.985096 -213.732618)
			(xy 338.764372 -213.732618) (xy 338.764023 -213.755595) (xy 338.757702 -213.801111) (xy 338.745116 -213.845306)
			(xy 338.736178 -213.866476) (xy 338.726272 -213.888828) (xy 338.939886 -214.293958) (xy 338.964016 -214.29853)
			(xy 338.98893 -214.303664) (xy 339.03694 -214.320459) (xy 339.081799 -214.344434) (xy 339.122441 -214.375017)
			(xy 339.157899 -214.411484) (xy 339.187332 -214.452967) (xy 339.21004 -214.49848) (xy 339.225483 -214.546942)
			(xy 339.233295 -214.597202) (xy 339.233764 -214.622634) (xy 339.233256 -214.648521) (xy 339.225157 -214.699659)
			(xy 339.209158 -214.748899) (xy 339.185652 -214.795031) (xy 339.15522 -214.836918) (xy 339.11861 -214.873528)
			(xy 339.076723 -214.90396) (xy 339.030591 -214.927466) (xy 338.981351 -214.943465) (xy 338.930213 -214.951564)
			(xy 338.878439 -214.951564) (xy 338.827301 -214.943465) (xy 338.778061 -214.927466) (xy 338.731929 -214.90396)
			(xy 338.690042 -214.873528) (xy 338.653432 -214.836918) (xy 338.623 -214.795031) (xy 338.599494 -214.748899)
			(xy 338.583495 -214.699659) (xy 338.575396 -214.648521) (xy 338.574888 -214.622634) (xy 338.575258 -214.599658)
			(xy 338.58157 -214.554143) (xy 338.594148 -214.509947) (xy 338.603082 -214.488776) (xy 338.612988 -214.466424)
			(xy 338.399374 -214.061294) (xy 338.375244 -214.056722) (xy 338.350313 -214.051663) (xy 338.302299 -214.034858)
			(xy 338.257439 -214.010874) (xy 338.216797 -213.980281) (xy 338.181339 -213.943805) (xy 338.151909 -213.902313)
			(xy 338.129205 -213.856791) (xy 338.113767 -213.80832) (xy 338.105962 -213.758053) (xy 338.105496 -213.732618)
			(xy 132.175504 -213.732618) (xy 132.175153 -213.755595) (xy 132.168832 -213.80111) (xy 132.156248 -213.845306)
			(xy 132.14731 -213.866476) (xy 132.137404 -213.888828) (xy 132.351018 -214.293958) (xy 132.375148 -214.29853)
			(xy 132.400067 -214.303641) (xy 132.448077 -214.320441) (xy 132.492936 -214.344419) (xy 132.533576 -214.375006)
			(xy 132.569034 -214.411476) (xy 132.598466 -214.452961) (xy 132.621173 -214.498476) (xy 132.636615 -214.54694)
			(xy 132.644427 -214.597201) (xy 132.644896 -214.622634) (xy 132.644388 -214.648521) (xy 132.636289 -214.699659)
			(xy 132.62029 -214.748899) (xy 132.596784 -214.795031) (xy 132.566352 -214.836918) (xy 132.529742 -214.873528)
			(xy 132.487855 -214.90396) (xy 132.441723 -214.927466) (xy 132.392483 -214.943465) (xy 132.341345 -214.951564)
			(xy 132.289571 -214.951564) (xy 132.238433 -214.943465) (xy 132.189193 -214.927466) (xy 132.143061 -214.90396)
			(xy 132.101174 -214.873528) (xy 132.064564 -214.836918) (xy 132.034132 -214.795031) (xy 132.010626 -214.748899)
			(xy 131.994627 -214.699659) (xy 131.986528 -214.648521) (xy 131.98602 -214.622634) (xy 131.986387 -214.599658)
			(xy 131.9927 -214.554143) (xy 132.005279 -214.509947) (xy 132.014214 -214.488776) (xy 132.02412 -214.466424)
			(xy 131.810506 -214.061294) (xy 131.786376 -214.056722) (xy 131.76145 -214.051639) (xy 131.713436 -214.034839)
			(xy 131.668575 -214.010859) (xy 131.627932 -213.980269) (xy 131.592474 -213.943796) (xy 131.563043 -213.902307)
			(xy 131.540338 -213.856787) (xy 131.5249 -213.808318) (xy 131.517094 -213.758052) (xy 131.516628 -213.732618)
			(xy 130.295904 -213.732618) (xy 130.295553 -213.755595) (xy 130.289232 -213.80111) (xy 130.276648 -213.845306)
			(xy 130.26771 -213.866476) (xy 130.257804 -213.888828) (xy 130.471418 -214.293958) (xy 130.495548 -214.29853)
			(xy 130.520467 -214.303641) (xy 130.568477 -214.320441) (xy 130.613336 -214.344419) (xy 130.653976 -214.375006)
			(xy 130.689434 -214.411476) (xy 130.718866 -214.452961) (xy 130.741573 -214.498476) (xy 130.757015 -214.54694)
			(xy 130.764827 -214.597201) (xy 130.765296 -214.622634) (xy 130.764788 -214.648521) (xy 130.756689 -214.699659)
			(xy 130.74069 -214.748899) (xy 130.717184 -214.795031) (xy 130.686752 -214.836918) (xy 130.650142 -214.873528)
			(xy 130.608255 -214.90396) (xy 130.562123 -214.927466) (xy 130.512883 -214.943465) (xy 130.461745 -214.951564)
			(xy 130.409971 -214.951564) (xy 130.358833 -214.943465) (xy 130.309593 -214.927466) (xy 130.263461 -214.90396)
			(xy 130.221574 -214.873528) (xy 130.184964 -214.836918) (xy 130.154532 -214.795031) (xy 130.131026 -214.748899)
			(xy 130.115027 -214.699659) (xy 130.106928 -214.648521) (xy 130.10642 -214.622634) (xy 130.106787 -214.599658)
			(xy 130.1131 -214.554143) (xy 130.125679 -214.509947) (xy 130.134614 -214.488776) (xy 130.14452 -214.466424)
			(xy 129.930906 -214.061294) (xy 129.906776 -214.056722) (xy 129.88185 -214.051639) (xy 129.833836 -214.034839)
			(xy 129.788975 -214.010859) (xy 129.748332 -213.980269) (xy 129.712874 -213.943796) (xy 129.683443 -213.902307)
			(xy 129.660738 -213.856787) (xy 129.6453 -213.808318) (xy 129.637494 -213.758052) (xy 129.637028 -213.732618)
			(xy 128.416304 -213.732618) (xy 128.415953 -213.755595) (xy 128.409632 -213.80111) (xy 128.397048 -213.845306)
			(xy 128.38811 -213.866476) (xy 128.378204 -213.888828) (xy 128.591818 -214.293958) (xy 128.615948 -214.29853)
			(xy 128.640867 -214.303641) (xy 128.688877 -214.320441) (xy 128.733736 -214.344419) (xy 128.774376 -214.375006)
			(xy 128.809834 -214.411476) (xy 128.839266 -214.452961) (xy 128.861973 -214.498476) (xy 128.877415 -214.54694)
			(xy 128.885227 -214.597201) (xy 128.885696 -214.622634) (xy 128.885188 -214.648521) (xy 128.877089 -214.699659)
			(xy 128.86109 -214.748899) (xy 128.837584 -214.795031) (xy 128.807152 -214.836918) (xy 128.770542 -214.873528)
			(xy 128.728655 -214.90396) (xy 128.682523 -214.927466) (xy 128.633283 -214.943465) (xy 128.582145 -214.951564)
			(xy 128.530371 -214.951564) (xy 128.479233 -214.943465) (xy 128.429993 -214.927466) (xy 128.383861 -214.90396)
			(xy 128.341974 -214.873528) (xy 128.305364 -214.836918) (xy 128.274932 -214.795031) (xy 128.251426 -214.748899)
			(xy 128.235427 -214.699659) (xy 128.227328 -214.648521) (xy 128.22682 -214.622634) (xy 128.227187 -214.599658)
			(xy 128.2335 -214.554143) (xy 128.246079 -214.509947) (xy 128.255014 -214.488776) (xy 128.26492 -214.466424)
			(xy 128.051306 -214.061294) (xy 128.027176 -214.056722) (xy 128.00225 -214.051639) (xy 127.954236 -214.034839)
			(xy 127.909375 -214.010859) (xy 127.868732 -213.980269) (xy 127.833274 -213.943796) (xy 127.803843 -213.902307)
			(xy 127.781138 -213.856787) (xy 127.7657 -213.808318) (xy 127.757894 -213.758052) (xy 127.757428 -213.732618)
			(xy 126.536704 -213.732618) (xy 126.536283 -213.755559) (xy 126.529855 -213.80099) (xy 126.517209 -213.845096)
			(xy 126.508256 -213.866222) (xy 126.49835 -213.888574) (xy 126.712218 -214.293958) (xy 126.736348 -214.29853)
			(xy 126.761267 -214.303641) (xy 126.809277 -214.320441) (xy 126.854136 -214.344419) (xy 126.894776 -214.375006)
			(xy 126.930234 -214.411476) (xy 126.959666 -214.452961) (xy 126.982373 -214.498476) (xy 126.997815 -214.54694)
			(xy 127.005627 -214.597201) (xy 127.006096 -214.622634) (xy 127.005588 -214.648521) (xy 126.997489 -214.699659)
			(xy 126.98149 -214.748899) (xy 126.957984 -214.795031) (xy 126.927552 -214.836918) (xy 126.890942 -214.873528)
			(xy 126.849055 -214.90396) (xy 126.802923 -214.927466) (xy 126.753683 -214.943465) (xy 126.702545 -214.951564)
			(xy 126.650771 -214.951564) (xy 126.599633 -214.943465) (xy 126.550393 -214.927466) (xy 126.504261 -214.90396)
			(xy 126.462374 -214.873528) (xy 126.425764 -214.836918) (xy 126.395332 -214.795031) (xy 126.371826 -214.748899)
			(xy 126.355827 -214.699659) (xy 126.347728 -214.648521) (xy 126.34722 -214.622634) (xy 126.347587 -214.599658)
			(xy 126.3539 -214.554143) (xy 126.366479 -214.509947) (xy 126.375414 -214.488776) (xy 126.38532 -214.466424)
			(xy 126.171706 -214.061294) (xy 126.147576 -214.056722) (xy 126.12262 -214.051672) (xy 126.074538 -214.034924)
			(xy 126.029605 -214.010979) (xy 125.98889 -213.980407) (xy 125.953363 -213.943936) (xy 125.92387 -213.902434)
			(xy 125.901111 -213.856888) (xy 125.88563 -213.808384) (xy 125.877795 -213.758075) (xy 125.87732 -213.732618)
			(xy 124.657104 -213.732618) (xy 124.656681 -213.756953) (xy 124.649527 -213.805095) (xy 124.635379 -213.851663)
			(xy 124.625354 -213.873842) (xy 124.614432 -213.896448) (xy 124.820172 -214.292942) (xy 124.845826 -214.296752)
			(xy 124.87151 -214.301109) (xy 124.921167 -214.316849) (xy 124.967731 -214.340204) (xy 125.010041 -214.370592)
			(xy 125.047044 -214.407258) (xy 125.077819 -214.449288) (xy 125.101599 -214.495635) (xy 125.117793 -214.545146)
			(xy 125.125998 -214.596588) (xy 125.126496 -214.622634) (xy 125.125988 -214.648521) (xy 125.117889 -214.699659)
			(xy 125.10189 -214.748899) (xy 125.078384 -214.795031) (xy 125.047952 -214.836918) (xy 125.011342 -214.873528)
			(xy 124.969455 -214.90396) (xy 124.923323 -214.927466) (xy 124.874083 -214.943465) (xy 124.822945 -214.951564)
			(xy 124.771171 -214.951564) (xy 124.720033 -214.943465) (xy 124.670793 -214.927466) (xy 124.624661 -214.90396)
			(xy 124.582774 -214.873528) (xy 124.546164 -214.836918) (xy 124.515732 -214.795031) (xy 124.492226 -214.748899)
			(xy 124.476227 -214.699659) (xy 124.468128 -214.648521) (xy 124.46762 -214.622634) (xy 124.468099 -214.597068)
			(xy 124.476002 -214.546552) (xy 124.491623 -214.497866) (xy 124.502672 -214.474806) (xy 124.514102 -214.451438)
			(xy 124.31268 -214.062818) (xy 124.28601 -214.059516) (xy 124.259814 -214.055663) (xy 124.20902 -214.04073)
			(xy 124.161267 -214.017866) (xy 124.117785 -213.987661) (xy 124.079693 -213.950891) (xy 124.047971 -213.908503)
			(xy 124.023436 -213.861587) (xy 124.006718 -213.811352) (xy 123.998249 -213.75909) (xy 123.99772 -213.732618)
			(xy 122.777504 -213.732618) (xy 122.777153 -213.755595) (xy 122.770832 -213.80111) (xy 122.758248 -213.845306)
			(xy 122.74931 -213.866476) (xy 122.739404 -213.888828) (xy 122.953018 -214.293958) (xy 122.977148 -214.29853)
			(xy 123.002067 -214.303641) (xy 123.050077 -214.320441) (xy 123.094936 -214.344419) (xy 123.135576 -214.375006)
			(xy 123.171034 -214.411476) (xy 123.200466 -214.452961) (xy 123.223173 -214.498476) (xy 123.238615 -214.54694)
			(xy 123.246427 -214.597201) (xy 123.246896 -214.622634) (xy 123.246388 -214.648521) (xy 123.238289 -214.699659)
			(xy 123.22229 -214.748899) (xy 123.198784 -214.795031) (xy 123.168352 -214.836918) (xy 123.131742 -214.873528)
			(xy 123.089855 -214.90396) (xy 123.043723 -214.927466) (xy 122.994483 -214.943465) (xy 122.943345 -214.951564)
			(xy 122.891571 -214.951564) (xy 122.840433 -214.943465) (xy 122.791193 -214.927466) (xy 122.745061 -214.90396)
			(xy 122.703174 -214.873528) (xy 122.666564 -214.836918) (xy 122.636132 -214.795031) (xy 122.612626 -214.748899)
			(xy 122.596627 -214.699659) (xy 122.588528 -214.648521) (xy 122.58802 -214.622634) (xy 122.588387 -214.599658)
			(xy 122.5947 -214.554143) (xy 122.607279 -214.509947) (xy 122.616214 -214.488776) (xy 122.62612 -214.466424)
			(xy 122.412506 -214.061294) (xy 122.388376 -214.056722) (xy 122.36345 -214.051639) (xy 122.315436 -214.034839)
			(xy 122.270575 -214.010859) (xy 122.229932 -213.980269) (xy 122.194474 -213.943796) (xy 122.165043 -213.902307)
			(xy 122.142338 -213.856787) (xy 122.1269 -213.808318) (xy 122.119094 -213.758052) (xy 122.118628 -213.732618)
			(xy 120.897904 -213.732618) (xy 120.897553 -213.755595) (xy 120.891232 -213.80111) (xy 120.878648 -213.845306)
			(xy 120.86971 -213.866476) (xy 120.859804 -213.888828) (xy 121.073418 -214.293958) (xy 121.097548 -214.29853)
			(xy 121.122467 -214.303641) (xy 121.170477 -214.320441) (xy 121.215336 -214.344419) (xy 121.255976 -214.375006)
			(xy 121.291434 -214.411476) (xy 121.320866 -214.452961) (xy 121.343573 -214.498476) (xy 121.359015 -214.54694)
			(xy 121.366827 -214.597201) (xy 121.367296 -214.622634) (xy 121.366788 -214.648521) (xy 121.358689 -214.699659)
			(xy 121.34269 -214.748899) (xy 121.319184 -214.795031) (xy 121.288752 -214.836918) (xy 121.252142 -214.873528)
			(xy 121.210255 -214.90396) (xy 121.164123 -214.927466) (xy 121.114883 -214.943465) (xy 121.063745 -214.951564)
			(xy 121.011971 -214.951564) (xy 120.960833 -214.943465) (xy 120.911593 -214.927466) (xy 120.865461 -214.90396)
			(xy 120.823574 -214.873528) (xy 120.786964 -214.836918) (xy 120.756532 -214.795031) (xy 120.733026 -214.748899)
			(xy 120.717027 -214.699659) (xy 120.708928 -214.648521) (xy 120.70842 -214.622634) (xy 120.708787 -214.599658)
			(xy 120.7151 -214.554143) (xy 120.727679 -214.509947) (xy 120.736614 -214.488776) (xy 120.74652 -214.466424)
			(xy 120.532906 -214.061294) (xy 120.508776 -214.056722) (xy 120.48385 -214.051639) (xy 120.435836 -214.034839)
			(xy 120.390975 -214.010859) (xy 120.350332 -213.980269) (xy 120.314874 -213.943796) (xy 120.285443 -213.902307)
			(xy 120.262738 -213.856787) (xy 120.2473 -213.808318) (xy 120.239494 -213.758052) (xy 120.239028 -213.732618)
			(xy 119.018304 -213.732618) (xy 119.017953 -213.755595) (xy 119.011632 -213.80111) (xy 118.999048 -213.845306)
			(xy 118.99011 -213.866476) (xy 118.980204 -213.888828) (xy 119.193818 -214.293958) (xy 119.217948 -214.29853)
			(xy 119.242867 -214.303641) (xy 119.290877 -214.320441) (xy 119.335736 -214.344419) (xy 119.376376 -214.375006)
			(xy 119.411834 -214.411476) (xy 119.441266 -214.452961) (xy 119.463973 -214.498476) (xy 119.479415 -214.54694)
			(xy 119.487227 -214.597201) (xy 119.487696 -214.622634) (xy 119.487188 -214.648521) (xy 119.479089 -214.699659)
			(xy 119.46309 -214.748899) (xy 119.439584 -214.795031) (xy 119.409152 -214.836918) (xy 119.372542 -214.873528)
			(xy 119.330655 -214.90396) (xy 119.284523 -214.927466) (xy 119.235283 -214.943465) (xy 119.184145 -214.951564)
			(xy 119.132371 -214.951564) (xy 119.081233 -214.943465) (xy 119.031993 -214.927466) (xy 118.985861 -214.90396)
			(xy 118.943974 -214.873528) (xy 118.907364 -214.836918) (xy 118.876932 -214.795031) (xy 118.853426 -214.748899)
			(xy 118.837427 -214.699659) (xy 118.829328 -214.648521) (xy 118.82882 -214.622634) (xy 118.829187 -214.599658)
			(xy 118.8355 -214.554143) (xy 118.848079 -214.509947) (xy 118.857014 -214.488776) (xy 118.86692 -214.466424)
			(xy 118.653306 -214.061294) (xy 118.629176 -214.056722) (xy 118.60425 -214.051639) (xy 118.556236 -214.034839)
			(xy 118.511375 -214.010859) (xy 118.470732 -213.980269) (xy 118.435274 -213.943796) (xy 118.405843 -213.902307)
			(xy 118.383138 -213.856787) (xy 118.3677 -213.808318) (xy 118.359894 -213.758052) (xy 118.359428 -213.732618)
			(xy 117.138704 -213.732618) (xy 117.138353 -213.755595) (xy 117.132032 -213.80111) (xy 117.119448 -213.845306)
			(xy 117.11051 -213.866476) (xy 117.100604 -213.888828) (xy 117.314218 -214.293958) (xy 117.338348 -214.29853)
			(xy 117.363267 -214.303641) (xy 117.411277 -214.320441) (xy 117.456136 -214.344419) (xy 117.496776 -214.375006)
			(xy 117.532234 -214.411476) (xy 117.561666 -214.452961) (xy 117.584373 -214.498476) (xy 117.599815 -214.54694)
			(xy 117.607627 -214.597201) (xy 117.608096 -214.622634) (xy 117.607588 -214.648521) (xy 117.599489 -214.699659)
			(xy 117.58349 -214.748899) (xy 117.559984 -214.795031) (xy 117.529552 -214.836918) (xy 117.492942 -214.873528)
			(xy 117.451055 -214.90396) (xy 117.404923 -214.927466) (xy 117.355683 -214.943465) (xy 117.304545 -214.951564)
			(xy 117.252771 -214.951564) (xy 117.201633 -214.943465) (xy 117.152393 -214.927466) (xy 117.106261 -214.90396)
			(xy 117.064374 -214.873528) (xy 117.027764 -214.836918) (xy 116.997332 -214.795031) (xy 116.973826 -214.748899)
			(xy 116.957827 -214.699659) (xy 116.949728 -214.648521) (xy 116.94922 -214.622634) (xy 116.949587 -214.599658)
			(xy 116.9559 -214.554143) (xy 116.968479 -214.509947) (xy 116.977414 -214.488776) (xy 116.98732 -214.466424)
			(xy 116.773706 -214.061294) (xy 116.749576 -214.056722) (xy 116.72465 -214.051639) (xy 116.676636 -214.034839)
			(xy 116.631775 -214.010859) (xy 116.591132 -213.980269) (xy 116.555674 -213.943796) (xy 116.526243 -213.902307)
			(xy 116.503538 -213.856787) (xy 116.4881 -213.808318) (xy 116.480294 -213.758052) (xy 116.479828 -213.732618)
			(xy 115.259104 -213.732618) (xy 115.258753 -213.755595) (xy 115.252432 -213.80111) (xy 115.239848 -213.845306)
			(xy 115.23091 -213.866476) (xy 115.221004 -213.888828) (xy 115.434618 -214.293958) (xy 115.458748 -214.29853)
			(xy 115.483667 -214.303641) (xy 115.531677 -214.320441) (xy 115.576536 -214.344419) (xy 115.617176 -214.375006)
			(xy 115.652634 -214.411476) (xy 115.682066 -214.452961) (xy 115.704773 -214.498476) (xy 115.720215 -214.54694)
			(xy 115.728027 -214.597201) (xy 115.728496 -214.622634) (xy 115.727988 -214.648521) (xy 115.719889 -214.699659)
			(xy 115.70389 -214.748899) (xy 115.680384 -214.795031) (xy 115.649952 -214.836918) (xy 115.613342 -214.873528)
			(xy 115.571455 -214.90396) (xy 115.525323 -214.927466) (xy 115.476083 -214.943465) (xy 115.424945 -214.951564)
			(xy 115.373171 -214.951564) (xy 115.322033 -214.943465) (xy 115.272793 -214.927466) (xy 115.226661 -214.90396)
			(xy 115.184774 -214.873528) (xy 115.148164 -214.836918) (xy 115.117732 -214.795031) (xy 115.094226 -214.748899)
			(xy 115.078227 -214.699659) (xy 115.070128 -214.648521) (xy 115.06962 -214.622634) (xy 115.069987 -214.599658)
			(xy 115.0763 -214.554143) (xy 115.088879 -214.509947) (xy 115.097814 -214.488776) (xy 115.10772 -214.466424)
			(xy 114.894106 -214.061294) (xy 114.869976 -214.056722) (xy 114.84505 -214.051639) (xy 114.797036 -214.034839)
			(xy 114.752175 -214.010859) (xy 114.711532 -213.980269) (xy 114.676074 -213.943796) (xy 114.646643 -213.902307)
			(xy 114.623938 -213.856787) (xy 114.6085 -213.808318) (xy 114.600694 -213.758052) (xy 114.600228 -213.732618)
			(xy 107.740704 -213.732618) (xy 107.740353 -213.755595) (xy 107.734032 -213.80111) (xy 107.721448 -213.845306)
			(xy 107.71251 -213.866476) (xy 107.702604 -213.888828) (xy 107.916218 -214.293958) (xy 107.940348 -214.29853)
			(xy 107.965267 -214.303641) (xy 108.013277 -214.320441) (xy 108.058136 -214.344419) (xy 108.098776 -214.375006)
			(xy 108.134234 -214.411476) (xy 108.163666 -214.452961) (xy 108.186373 -214.498476) (xy 108.201815 -214.54694)
			(xy 108.209627 -214.597201) (xy 108.210096 -214.622634) (xy 108.209588 -214.648521) (xy 108.201489 -214.699659)
			(xy 108.18549 -214.748899) (xy 108.161984 -214.795031) (xy 108.131552 -214.836918) (xy 108.094942 -214.873528)
			(xy 108.053055 -214.90396) (xy 108.006923 -214.927466) (xy 107.957683 -214.943465) (xy 107.906545 -214.951564)
			(xy 107.854771 -214.951564) (xy 107.803633 -214.943465) (xy 107.754393 -214.927466) (xy 107.708261 -214.90396)
			(xy 107.666374 -214.873528) (xy 107.629764 -214.836918) (xy 107.599332 -214.795031) (xy 107.575826 -214.748899)
			(xy 107.559827 -214.699659) (xy 107.551728 -214.648521) (xy 107.55122 -214.622634) (xy 107.551587 -214.599658)
			(xy 107.5579 -214.554143) (xy 107.570479 -214.509947) (xy 107.579414 -214.488776) (xy 107.58932 -214.466424)
			(xy 107.375706 -214.061294) (xy 107.351576 -214.056722) (xy 107.32665 -214.051639) (xy 107.278636 -214.034839)
			(xy 107.233775 -214.010859) (xy 107.193132 -213.980269) (xy 107.157674 -213.943796) (xy 107.128243 -213.902307)
			(xy 107.105538 -213.856787) (xy 107.0901 -213.808318) (xy 107.082294 -213.758052) (xy 107.081828 -213.732618)
			(xy 105.861104 -213.732618) (xy 105.860753 -213.755595) (xy 105.854432 -213.80111) (xy 105.841848 -213.845306)
			(xy 105.83291 -213.866476) (xy 105.823004 -213.888828) (xy 106.036618 -214.293958) (xy 106.060748 -214.29853)
			(xy 106.085667 -214.303641) (xy 106.133677 -214.320441) (xy 106.178536 -214.344419) (xy 106.219176 -214.375006)
			(xy 106.254634 -214.411476) (xy 106.284066 -214.452961) (xy 106.306773 -214.498476) (xy 106.322215 -214.54694)
			(xy 106.330027 -214.597201) (xy 106.330496 -214.622634) (xy 106.329988 -214.648521) (xy 106.321889 -214.699659)
			(xy 106.30589 -214.748899) (xy 106.282384 -214.795031) (xy 106.251952 -214.836918) (xy 106.215342 -214.873528)
			(xy 106.173455 -214.90396) (xy 106.127323 -214.927466) (xy 106.078083 -214.943465) (xy 106.026945 -214.951564)
			(xy 105.975171 -214.951564) (xy 105.924033 -214.943465) (xy 105.874793 -214.927466) (xy 105.828661 -214.90396)
			(xy 105.786774 -214.873528) (xy 105.750164 -214.836918) (xy 105.719732 -214.795031) (xy 105.696226 -214.748899)
			(xy 105.680227 -214.699659) (xy 105.672128 -214.648521) (xy 105.67162 -214.622634) (xy 105.671987 -214.599658)
			(xy 105.6783 -214.554143) (xy 105.690879 -214.509947) (xy 105.699814 -214.488776) (xy 105.70972 -214.466424)
			(xy 105.496106 -214.061294) (xy 105.471976 -214.056722) (xy 105.44705 -214.051639) (xy 105.399036 -214.034839)
			(xy 105.354175 -214.010859) (xy 105.313532 -213.980269) (xy 105.278074 -213.943796) (xy 105.248643 -213.902307)
			(xy 105.225938 -213.856787) (xy 105.2105 -213.808318) (xy 105.202694 -213.758052) (xy 105.202228 -213.732618)
			(xy 103.981504 -213.732618) (xy 103.981153 -213.755595) (xy 103.974832 -213.80111) (xy 103.962248 -213.845306)
			(xy 103.95331 -213.866476) (xy 103.943404 -213.888828) (xy 104.157018 -214.293958) (xy 104.181148 -214.29853)
			(xy 104.206067 -214.303641) (xy 104.254077 -214.320441) (xy 104.298936 -214.344419) (xy 104.339576 -214.375006)
			(xy 104.375034 -214.411476) (xy 104.404466 -214.452961) (xy 104.427173 -214.498476) (xy 104.442615 -214.54694)
			(xy 104.450427 -214.597201) (xy 104.450896 -214.622634) (xy 104.450388 -214.648521) (xy 104.442289 -214.699659)
			(xy 104.42629 -214.748899) (xy 104.402784 -214.795031) (xy 104.372352 -214.836918) (xy 104.335742 -214.873528)
			(xy 104.293855 -214.90396) (xy 104.247723 -214.927466) (xy 104.198483 -214.943465) (xy 104.147345 -214.951564)
			(xy 104.095571 -214.951564) (xy 104.044433 -214.943465) (xy 103.995193 -214.927466) (xy 103.949061 -214.90396)
			(xy 103.907174 -214.873528) (xy 103.870564 -214.836918) (xy 103.840132 -214.795031) (xy 103.816626 -214.748899)
			(xy 103.800627 -214.699659) (xy 103.792528 -214.648521) (xy 103.79202 -214.622634) (xy 103.792387 -214.599658)
			(xy 103.7987 -214.554143) (xy 103.811279 -214.509947) (xy 103.820214 -214.488776) (xy 103.83012 -214.466424)
			(xy 103.616506 -214.061294) (xy 103.592376 -214.056722) (xy 103.56745 -214.051639) (xy 103.519436 -214.034839)
			(xy 103.474575 -214.010859) (xy 103.433932 -213.980269) (xy 103.398474 -213.943796) (xy 103.369043 -213.902307)
			(xy 103.346338 -213.856787) (xy 103.3309 -213.808318) (xy 103.323094 -213.758052) (xy 103.322628 -213.732618)
			(xy 102.101904 -213.732618) (xy 102.101553 -213.755595) (xy 102.095232 -213.80111) (xy 102.082648 -213.845306)
			(xy 102.07371 -213.866476) (xy 102.063804 -213.888828) (xy 102.277418 -214.293958) (xy 102.301548 -214.29853)
			(xy 102.326467 -214.303641) (xy 102.374477 -214.320441) (xy 102.419336 -214.344419) (xy 102.459976 -214.375006)
			(xy 102.495434 -214.411476) (xy 102.524866 -214.452961) (xy 102.547573 -214.498476) (xy 102.563015 -214.54694)
			(xy 102.570827 -214.597201) (xy 102.571296 -214.622634) (xy 102.570788 -214.648521) (xy 102.562689 -214.699659)
			(xy 102.54669 -214.748899) (xy 102.523184 -214.795031) (xy 102.492752 -214.836918) (xy 102.456142 -214.873528)
			(xy 102.414255 -214.90396) (xy 102.368123 -214.927466) (xy 102.318883 -214.943465) (xy 102.267745 -214.951564)
			(xy 102.215971 -214.951564) (xy 102.164833 -214.943465) (xy 102.115593 -214.927466) (xy 102.069461 -214.90396)
			(xy 102.027574 -214.873528) (xy 101.990964 -214.836918) (xy 101.960532 -214.795031) (xy 101.937026 -214.748899)
			(xy 101.921027 -214.699659) (xy 101.912928 -214.648521) (xy 101.91242 -214.622634) (xy 101.912787 -214.599658)
			(xy 101.9191 -214.554143) (xy 101.931679 -214.509947) (xy 101.940614 -214.488776) (xy 101.95052 -214.466424)
			(xy 101.736906 -214.061294) (xy 101.712776 -214.056722) (xy 101.68785 -214.051639) (xy 101.639836 -214.034839)
			(xy 101.594975 -214.010859) (xy 101.554332 -213.980269) (xy 101.518874 -213.943796) (xy 101.489443 -213.902307)
			(xy 101.466738 -213.856787) (xy 101.4513 -213.808318) (xy 101.443494 -213.758052) (xy 101.443028 -213.732618)
			(xy 100.222304 -213.732618) (xy 100.221953 -213.755595) (xy 100.215632 -213.80111) (xy 100.203048 -213.845306)
			(xy 100.19411 -213.866476) (xy 100.184204 -213.888828) (xy 100.397818 -214.293958) (xy 100.421948 -214.29853)
			(xy 100.446867 -214.303641) (xy 100.494877 -214.320441) (xy 100.539736 -214.344419) (xy 100.580376 -214.375006)
			(xy 100.615834 -214.411476) (xy 100.645266 -214.452961) (xy 100.667973 -214.498476) (xy 100.683415 -214.54694)
			(xy 100.691227 -214.597201) (xy 100.691696 -214.622634) (xy 100.691188 -214.648521) (xy 100.683089 -214.699659)
			(xy 100.66709 -214.748899) (xy 100.643584 -214.795031) (xy 100.613152 -214.836918) (xy 100.576542 -214.873528)
			(xy 100.534655 -214.90396) (xy 100.488523 -214.927466) (xy 100.439283 -214.943465) (xy 100.388145 -214.951564)
			(xy 100.336371 -214.951564) (xy 100.285233 -214.943465) (xy 100.235993 -214.927466) (xy 100.189861 -214.90396)
			(xy 100.147974 -214.873528) (xy 100.111364 -214.836918) (xy 100.080932 -214.795031) (xy 100.057426 -214.748899)
			(xy 100.041427 -214.699659) (xy 100.033328 -214.648521) (xy 100.03282 -214.622634) (xy 100.033187 -214.599658)
			(xy 100.0395 -214.554143) (xy 100.052079 -214.509947) (xy 100.061014 -214.488776) (xy 100.07092 -214.466424)
			(xy 99.857306 -214.061294) (xy 99.833176 -214.056722) (xy 99.80825 -214.051639) (xy 99.760236 -214.034839)
			(xy 99.715375 -214.010859) (xy 99.674732 -213.980269) (xy 99.639274 -213.943796) (xy 99.609843 -213.902307)
			(xy 99.587138 -213.856787) (xy 99.5717 -213.808318) (xy 99.563894 -213.758052) (xy 99.563428 -213.732618)
			(xy 98.342704 -213.732618) (xy 98.342353 -213.755595) (xy 98.336032 -213.80111) (xy 98.323448 -213.845306)
			(xy 98.31451 -213.866476) (xy 98.304604 -213.888828) (xy 98.518218 -214.293958) (xy 98.542348 -214.29853)
			(xy 98.567267 -214.303641) (xy 98.615277 -214.320441) (xy 98.660136 -214.344419) (xy 98.700776 -214.375006)
			(xy 98.736234 -214.411476) (xy 98.765666 -214.452961) (xy 98.788373 -214.498476) (xy 98.803815 -214.54694)
			(xy 98.811627 -214.597201) (xy 98.812096 -214.622634) (xy 98.811588 -214.648521) (xy 98.803489 -214.699659)
			(xy 98.78749 -214.748899) (xy 98.763984 -214.795031) (xy 98.733552 -214.836918) (xy 98.696942 -214.873528)
			(xy 98.655055 -214.90396) (xy 98.608923 -214.927466) (xy 98.559683 -214.943465) (xy 98.508545 -214.951564)
			(xy 98.456771 -214.951564) (xy 98.405633 -214.943465) (xy 98.356393 -214.927466) (xy 98.310261 -214.90396)
			(xy 98.268374 -214.873528) (xy 98.231764 -214.836918) (xy 98.201332 -214.795031) (xy 98.177826 -214.748899)
			(xy 98.161827 -214.699659) (xy 98.153728 -214.648521) (xy 98.15322 -214.622634) (xy 98.153587 -214.599658)
			(xy 98.1599 -214.554143) (xy 98.172479 -214.509947) (xy 98.181414 -214.488776) (xy 98.19132 -214.466424)
			(xy 97.977706 -214.061294) (xy 97.953576 -214.056722) (xy 97.92865 -214.051639) (xy 97.880636 -214.034839)
			(xy 97.835775 -214.010859) (xy 97.795132 -213.980269) (xy 97.759674 -213.943796) (xy 97.730243 -213.902307)
			(xy 97.707538 -213.856787) (xy 97.6921 -213.808318) (xy 97.684294 -213.758052) (xy 97.683828 -213.732618)
			(xy 96.463104 -213.732618) (xy 96.462753 -213.755595) (xy 96.456432 -213.80111) (xy 96.443848 -213.845306)
			(xy 96.43491 -213.866476) (xy 96.425004 -213.888828) (xy 96.638618 -214.293958) (xy 96.662748 -214.29853)
			(xy 96.687667 -214.303641) (xy 96.735677 -214.320441) (xy 96.780536 -214.344419) (xy 96.821176 -214.375006)
			(xy 96.856634 -214.411476) (xy 96.886066 -214.452961) (xy 96.908773 -214.498476) (xy 96.924215 -214.54694)
			(xy 96.932027 -214.597201) (xy 96.932496 -214.622634) (xy 96.931988 -214.648521) (xy 96.923889 -214.699659)
			(xy 96.90789 -214.748899) (xy 96.884384 -214.795031) (xy 96.853952 -214.836918) (xy 96.817342 -214.873528)
			(xy 96.775455 -214.90396) (xy 96.729323 -214.927466) (xy 96.680083 -214.943465) (xy 96.628945 -214.951564)
			(xy 96.577171 -214.951564) (xy 96.526033 -214.943465) (xy 96.476793 -214.927466) (xy 96.430661 -214.90396)
			(xy 96.388774 -214.873528) (xy 96.352164 -214.836918) (xy 96.321732 -214.795031) (xy 96.298226 -214.748899)
			(xy 96.282227 -214.699659) (xy 96.274128 -214.648521) (xy 96.27362 -214.622634) (xy 96.273987 -214.599658)
			(xy 96.2803 -214.554143) (xy 96.292879 -214.509947) (xy 96.301814 -214.488776) (xy 96.31172 -214.466424)
			(xy 96.098106 -214.061294) (xy 96.073976 -214.056722) (xy 96.04905 -214.051639) (xy 96.001036 -214.034839)
			(xy 95.956175 -214.010859) (xy 95.915532 -213.980269) (xy 95.880074 -213.943796) (xy 95.850643 -213.902307)
			(xy 95.827938 -213.856787) (xy 95.8125 -213.808318) (xy 95.804694 -213.758052) (xy 95.804228 -213.732618)
			(xy 94.583504 -213.732618) (xy 94.583153 -213.755595) (xy 94.576832 -213.80111) (xy 94.564248 -213.845306)
			(xy 94.55531 -213.866476) (xy 94.545404 -213.888828) (xy 94.759018 -214.293958) (xy 94.783148 -214.29853)
			(xy 94.808067 -214.303641) (xy 94.856077 -214.320441) (xy 94.900936 -214.344419) (xy 94.941576 -214.375006)
			(xy 94.977034 -214.411476) (xy 95.006466 -214.452961) (xy 95.029173 -214.498476) (xy 95.044615 -214.54694)
			(xy 95.052427 -214.597201) (xy 95.052896 -214.622634) (xy 95.052388 -214.648521) (xy 95.044289 -214.699659)
			(xy 95.02829 -214.748899) (xy 95.004784 -214.795031) (xy 94.974352 -214.836918) (xy 94.937742 -214.873528)
			(xy 94.895855 -214.90396) (xy 94.849723 -214.927466) (xy 94.800483 -214.943465) (xy 94.749345 -214.951564)
			(xy 94.697571 -214.951564) (xy 94.646433 -214.943465) (xy 94.597193 -214.927466) (xy 94.551061 -214.90396)
			(xy 94.509174 -214.873528) (xy 94.472564 -214.836918) (xy 94.442132 -214.795031) (xy 94.418626 -214.748899)
			(xy 94.402627 -214.699659) (xy 94.394528 -214.648521) (xy 94.39402 -214.622634) (xy 94.394387 -214.599658)
			(xy 94.4007 -214.554143) (xy 94.413279 -214.509947) (xy 94.422214 -214.488776) (xy 94.43212 -214.466424)
			(xy 94.218506 -214.061294) (xy 94.194376 -214.056722) (xy 94.16945 -214.051639) (xy 94.121436 -214.034839)
			(xy 94.076575 -214.010859) (xy 94.035932 -213.980269) (xy 94.000474 -213.943796) (xy 93.971043 -213.902307)
			(xy 93.948338 -213.856787) (xy 93.9329 -213.808318) (xy 93.925094 -213.758052) (xy 93.924628 -213.732618)
			(xy 92.703904 -213.732618) (xy 92.703553 -213.755595) (xy 92.697232 -213.80111) (xy 92.684648 -213.845306)
			(xy 92.67571 -213.866476) (xy 92.665804 -213.888828) (xy 92.879418 -214.293958) (xy 92.903548 -214.29853)
			(xy 92.928467 -214.303641) (xy 92.976477 -214.320441) (xy 93.021336 -214.344419) (xy 93.061976 -214.375006)
			(xy 93.097434 -214.411476) (xy 93.126866 -214.452961) (xy 93.149573 -214.498476) (xy 93.165015 -214.54694)
			(xy 93.172827 -214.597201) (xy 93.173296 -214.622634) (xy 93.172788 -214.648521) (xy 93.164689 -214.699659)
			(xy 93.14869 -214.748899) (xy 93.125184 -214.795031) (xy 93.094752 -214.836918) (xy 93.058142 -214.873528)
			(xy 93.016255 -214.90396) (xy 92.970123 -214.927466) (xy 92.920883 -214.943465) (xy 92.869745 -214.951564)
			(xy 92.817971 -214.951564) (xy 92.766833 -214.943465) (xy 92.717593 -214.927466) (xy 92.671461 -214.90396)
			(xy 92.629574 -214.873528) (xy 92.592964 -214.836918) (xy 92.562532 -214.795031) (xy 92.539026 -214.748899)
			(xy 92.523027 -214.699659) (xy 92.514928 -214.648521) (xy 92.51442 -214.622634) (xy 92.514787 -214.599658)
			(xy 92.5211 -214.554143) (xy 92.533679 -214.509947) (xy 92.542614 -214.488776) (xy 92.55252 -214.466424)
			(xy 92.338906 -214.061294) (xy 92.314776 -214.056722) (xy 92.28985 -214.051639) (xy 92.241836 -214.034839)
			(xy 92.196975 -214.010859) (xy 92.156332 -213.980269) (xy 92.120874 -213.943796) (xy 92.091443 -213.902307)
			(xy 92.068738 -213.856787) (xy 92.0533 -213.808318) (xy 92.045494 -213.758052) (xy 92.045028 -213.732618)
			(xy 90.824304 -213.732618) (xy 90.823953 -213.755595) (xy 90.817632 -213.80111) (xy 90.805048 -213.845306)
			(xy 90.79611 -213.866476) (xy 90.786204 -213.888828) (xy 90.999818 -214.293958) (xy 91.023948 -214.29853)
			(xy 91.048867 -214.303641) (xy 91.096877 -214.320441) (xy 91.141736 -214.344419) (xy 91.182376 -214.375006)
			(xy 91.217834 -214.411476) (xy 91.247266 -214.452961) (xy 91.269973 -214.498476) (xy 91.285415 -214.54694)
			(xy 91.293227 -214.597201) (xy 91.293696 -214.622634) (xy 91.293188 -214.648521) (xy 91.285089 -214.699659)
			(xy 91.26909 -214.748899) (xy 91.245584 -214.795031) (xy 91.215152 -214.836918) (xy 91.178542 -214.873528)
			(xy 91.136655 -214.90396) (xy 91.090523 -214.927466) (xy 91.041283 -214.943465) (xy 90.990145 -214.951564)
			(xy 90.938371 -214.951564) (xy 90.887233 -214.943465) (xy 90.837993 -214.927466) (xy 90.791861 -214.90396)
			(xy 90.749974 -214.873528) (xy 90.713364 -214.836918) (xy 90.682932 -214.795031) (xy 90.659426 -214.748899)
			(xy 90.643427 -214.699659) (xy 90.635328 -214.648521) (xy 90.63482 -214.622634) (xy 90.635187 -214.599658)
			(xy 90.6415 -214.554143) (xy 90.654079 -214.509947) (xy 90.663014 -214.488776) (xy 90.67292 -214.466424)
			(xy 90.459306 -214.061294) (xy 90.435176 -214.056722) (xy 90.41025 -214.051639) (xy 90.362236 -214.034839)
			(xy 90.317375 -214.010859) (xy 90.276732 -213.980269) (xy 90.241274 -213.943796) (xy 90.211843 -213.902307)
			(xy 90.189138 -213.856787) (xy 90.1737 -213.808318) (xy 90.165894 -213.758052) (xy 90.165428 -213.732618)
			(xy 2.509012 -213.732618) (xy 2.509012 -215.436704) (xy 88.28532 -215.436704) (xy 88.285828 -215.410797)
			(xy 88.293934 -215.35962) (xy 88.309946 -215.310341) (xy 88.333469 -215.264174) (xy 88.363925 -215.222255)
			(xy 88.400563 -215.185617) (xy 88.442482 -215.155161) (xy 88.488649 -215.131638) (xy 88.537928 -215.115626)
			(xy 88.589105 -215.10752) (xy 88.640919 -215.10752) (xy 88.692096 -215.115626) (xy 88.741375 -215.131638)
			(xy 88.787542 -215.155161) (xy 88.829461 -215.185617) (xy 88.866099 -215.222255) (xy 88.896555 -215.264174)
			(xy 88.920078 -215.310341) (xy 88.93609 -215.35962) (xy 88.944196 -215.410797) (xy 88.944704 -215.436704)
			(xy 89.22512 -215.436704) (xy 89.225629 -215.41136) (xy 89.2334 -215.36127) (xy 89.248746 -215.31296)
			(xy 89.271303 -215.267567) (xy 89.300542 -215.226161) (xy 89.335773 -215.189717) (xy 89.376165 -215.159094)
			(xy 89.420769 -215.135013) (xy 89.468532 -215.118041) (xy 89.493344 -215.112854) (xy 89.516204 -215.108536)
			(xy 89.721182 -214.753444) (xy 89.713308 -214.7316) (xy 89.704729 -214.705181) (xy 89.695532 -214.650406)
			(xy 89.69502 -214.622634) (xy 89.695528 -214.596747) (xy 89.703627 -214.545609) (xy 89.719626 -214.496369)
			(xy 89.743132 -214.450237) (xy 89.773564 -214.40835) (xy 89.810174 -214.37174) (xy 89.852061 -214.341308)
			(xy 89.898193 -214.317802) (xy 89.947433 -214.301803) (xy 89.998571 -214.293704) (xy 90.050345 -214.293704)
			(xy 90.101483 -214.301803) (xy 90.150723 -214.317802) (xy 90.196855 -214.341308) (xy 90.238742 -214.37174)
			(xy 90.275352 -214.40835) (xy 90.305784 -214.450237) (xy 90.32929 -214.496369) (xy 90.345289 -214.545609)
			(xy 90.353388 -214.596747) (xy 90.353896 -214.622634) (xy 90.353447 -214.64797) (xy 90.34569 -214.698044)
			(xy 90.330363 -214.746341) (xy 90.307827 -214.791726) (xy 90.278612 -214.833128) (xy 90.243408 -214.869572)
			(xy 90.203042 -214.900202) (xy 90.158465 -214.924296) (xy 90.110727 -214.941286) (xy 90.085926 -214.946484)
			(xy 90.063066 -214.950802) (xy 89.858088 -215.305894) (xy 89.865962 -215.327738) (xy 89.87461 -215.354146)
			(xy 89.883929 -215.408922) (xy 89.884504 -215.436704) (xy 91.10472 -215.436704) (xy 91.105229 -215.41136)
			(xy 91.113 -215.36127) (xy 91.128346 -215.31296) (xy 91.150903 -215.267567) (xy 91.180142 -215.226161)
			(xy 91.215373 -215.189717) (xy 91.255765 -215.159094) (xy 91.300369 -215.135013) (xy 91.348132 -215.118041)
			(xy 91.372944 -215.112854) (xy 91.395804 -215.108536) (xy 91.600782 -214.753444) (xy 91.592908 -214.7316)
			(xy 91.584329 -214.705181) (xy 91.575132 -214.650406) (xy 91.57462 -214.622634) (xy 91.575128 -214.596747)
			(xy 91.583227 -214.545609) (xy 91.599226 -214.496369) (xy 91.622732 -214.450237) (xy 91.653164 -214.40835)
			(xy 91.689774 -214.37174) (xy 91.731661 -214.341308) (xy 91.777793 -214.317802) (xy 91.827033 -214.301803)
			(xy 91.878171 -214.293704) (xy 91.929945 -214.293704) (xy 91.981083 -214.301803) (xy 92.030323 -214.317802)
			(xy 92.076455 -214.341308) (xy 92.118342 -214.37174) (xy 92.154952 -214.40835) (xy 92.185384 -214.450237)
			(xy 92.20889 -214.496369) (xy 92.224889 -214.545609) (xy 92.232988 -214.596747) (xy 92.233496 -214.622634)
			(xy 92.233047 -214.64797) (xy 92.22529 -214.698044) (xy 92.209963 -214.746341) (xy 92.187427 -214.791726)
			(xy 92.158212 -214.833128) (xy 92.123008 -214.869572) (xy 92.082642 -214.900202) (xy 92.038065 -214.924296)
			(xy 91.990327 -214.941286) (xy 91.965526 -214.946484) (xy 91.942666 -214.950802) (xy 91.737688 -215.305894)
			(xy 91.745562 -215.327738) (xy 91.75421 -215.354146) (xy 91.763529 -215.408922) (xy 91.764104 -215.436704)
			(xy 92.98432 -215.436704) (xy 92.984829 -215.41136) (xy 92.9926 -215.36127) (xy 93.007946 -215.31296)
			(xy 93.030503 -215.267567) (xy 93.059742 -215.226161) (xy 93.094973 -215.189717) (xy 93.135365 -215.159094)
			(xy 93.179969 -215.135013) (xy 93.227732 -215.118041) (xy 93.252544 -215.112854) (xy 93.275404 -215.108536)
			(xy 93.480382 -214.753444) (xy 93.472508 -214.7316) (xy 93.463929 -214.705181) (xy 93.454732 -214.650406)
			(xy 93.45422 -214.622634) (xy 93.454728 -214.596747) (xy 93.462827 -214.545609) (xy 93.478826 -214.496369)
			(xy 93.502332 -214.450237) (xy 93.532764 -214.40835) (xy 93.569374 -214.37174) (xy 93.611261 -214.341308)
			(xy 93.657393 -214.317802) (xy 93.706633 -214.301803) (xy 93.757771 -214.293704) (xy 93.809545 -214.293704)
			(xy 93.860683 -214.301803) (xy 93.909923 -214.317802) (xy 93.956055 -214.341308) (xy 93.997942 -214.37174)
			(xy 94.034552 -214.40835) (xy 94.064984 -214.450237) (xy 94.08849 -214.496369) (xy 94.104489 -214.545609)
			(xy 94.112588 -214.596747) (xy 94.113096 -214.622634) (xy 94.112647 -214.64797) (xy 94.10489 -214.698044)
			(xy 94.089563 -214.746341) (xy 94.067027 -214.791726) (xy 94.037812 -214.833128) (xy 94.002608 -214.869572)
			(xy 93.962242 -214.900202) (xy 93.917665 -214.924296) (xy 93.869927 -214.941286) (xy 93.845126 -214.946484)
			(xy 93.822266 -214.950802) (xy 93.617288 -215.305894) (xy 93.625162 -215.327738) (xy 93.63381 -215.354146)
			(xy 93.643129 -215.408922) (xy 93.643704 -215.436704) (xy 94.86392 -215.436704) (xy 94.864429 -215.41136)
			(xy 94.8722 -215.36127) (xy 94.887546 -215.31296) (xy 94.910103 -215.267567) (xy 94.939342 -215.226161)
			(xy 94.974573 -215.189717) (xy 95.014965 -215.159094) (xy 95.059569 -215.135013) (xy 95.107332 -215.118041)
			(xy 95.132144 -215.112854) (xy 95.155004 -215.108536) (xy 95.359982 -214.753444) (xy 95.352108 -214.7316)
			(xy 95.343529 -214.705181) (xy 95.334332 -214.650406) (xy 95.33382 -214.622634) (xy 95.334328 -214.596747)
			(xy 95.342427 -214.545609) (xy 95.358426 -214.496369) (xy 95.381932 -214.450237) (xy 95.412364 -214.40835)
			(xy 95.448974 -214.37174) (xy 95.490861 -214.341308) (xy 95.536993 -214.317802) (xy 95.586233 -214.301803)
			(xy 95.637371 -214.293704) (xy 95.689145 -214.293704) (xy 95.740283 -214.301803) (xy 95.789523 -214.317802)
			(xy 95.835655 -214.341308) (xy 95.877542 -214.37174) (xy 95.914152 -214.40835) (xy 95.944584 -214.450237)
			(xy 95.96809 -214.496369) (xy 95.984089 -214.545609) (xy 95.992188 -214.596747) (xy 95.992696 -214.622634)
			(xy 95.992247 -214.64797) (xy 95.98449 -214.698044) (xy 95.969163 -214.746341) (xy 95.946627 -214.791726)
			(xy 95.917412 -214.833128) (xy 95.882208 -214.869572) (xy 95.841842 -214.900202) (xy 95.797265 -214.924296)
			(xy 95.749527 -214.941286) (xy 95.724726 -214.946484) (xy 95.701866 -214.950802) (xy 95.496888 -215.305894)
			(xy 95.504762 -215.327738) (xy 95.51341 -215.354146) (xy 95.522729 -215.408922) (xy 95.523304 -215.436704)
			(xy 96.74352 -215.436704) (xy 96.744029 -215.41136) (xy 96.7518 -215.36127) (xy 96.767146 -215.31296)
			(xy 96.789703 -215.267567) (xy 96.818942 -215.226161) (xy 96.854173 -215.189717) (xy 96.894565 -215.159094)
			(xy 96.939169 -215.135013) (xy 96.986932 -215.118041) (xy 97.011744 -215.112854) (xy 97.034604 -215.108536)
			(xy 97.239582 -214.753444) (xy 97.231708 -214.7316) (xy 97.223129 -214.705181) (xy 97.213932 -214.650406)
			(xy 97.21342 -214.622634) (xy 97.213928 -214.596747) (xy 97.222027 -214.545609) (xy 97.238026 -214.496369)
			(xy 97.261532 -214.450237) (xy 97.291964 -214.40835) (xy 97.328574 -214.37174) (xy 97.370461 -214.341308)
			(xy 97.416593 -214.317802) (xy 97.465833 -214.301803) (xy 97.516971 -214.293704) (xy 97.568745 -214.293704)
			(xy 97.619883 -214.301803) (xy 97.669123 -214.317802) (xy 97.715255 -214.341308) (xy 97.757142 -214.37174)
			(xy 97.793752 -214.40835) (xy 97.824184 -214.450237) (xy 97.84769 -214.496369) (xy 97.863689 -214.545609)
			(xy 97.871788 -214.596747) (xy 97.872296 -214.622634) (xy 97.871847 -214.64797) (xy 97.86409 -214.698044)
			(xy 97.848763 -214.746341) (xy 97.826227 -214.791726) (xy 97.797012 -214.833128) (xy 97.761808 -214.869572)
			(xy 97.721442 -214.900202) (xy 97.676865 -214.924296) (xy 97.629127 -214.941286) (xy 97.604326 -214.946484)
			(xy 97.581466 -214.950802) (xy 97.376488 -215.305894) (xy 97.384362 -215.327738) (xy 97.39301 -215.354146)
			(xy 97.402329 -215.408922) (xy 97.402904 -215.436704) (xy 98.62312 -215.436704) (xy 98.623629 -215.41136)
			(xy 98.6314 -215.36127) (xy 98.646746 -215.31296) (xy 98.669303 -215.267567) (xy 98.698542 -215.226161)
			(xy 98.733773 -215.189717) (xy 98.774165 -215.159094) (xy 98.818769 -215.135013) (xy 98.866532 -215.118041)
			(xy 98.891344 -215.112854) (xy 98.914204 -215.108536) (xy 99.119182 -214.753444) (xy 99.111308 -214.7316)
			(xy 99.102729 -214.705181) (xy 99.093532 -214.650406) (xy 99.09302 -214.622634) (xy 99.093528 -214.596747)
			(xy 99.101627 -214.545609) (xy 99.117626 -214.496369) (xy 99.141132 -214.450237) (xy 99.171564 -214.40835)
			(xy 99.208174 -214.37174) (xy 99.250061 -214.341308) (xy 99.296193 -214.317802) (xy 99.345433 -214.301803)
			(xy 99.396571 -214.293704) (xy 99.448345 -214.293704) (xy 99.499483 -214.301803) (xy 99.548723 -214.317802)
			(xy 99.594855 -214.341308) (xy 99.636742 -214.37174) (xy 99.673352 -214.40835) (xy 99.703784 -214.450237)
			(xy 99.72729 -214.496369) (xy 99.743289 -214.545609) (xy 99.751388 -214.596747) (xy 99.751896 -214.622634)
			(xy 99.751447 -214.64797) (xy 99.74369 -214.698044) (xy 99.728363 -214.746341) (xy 99.705827 -214.791726)
			(xy 99.676612 -214.833128) (xy 99.641408 -214.869572) (xy 99.601042 -214.900202) (xy 99.556465 -214.924296)
			(xy 99.508727 -214.941286) (xy 99.483926 -214.946484) (xy 99.461066 -214.950802) (xy 99.256088 -215.305894)
			(xy 99.263962 -215.327738) (xy 99.27261 -215.354146) (xy 99.281929 -215.408922) (xy 99.282504 -215.436704)
			(xy 100.50272 -215.436704) (xy 100.503229 -215.41136) (xy 100.511 -215.36127) (xy 100.526346 -215.31296)
			(xy 100.548903 -215.267567) (xy 100.578142 -215.226161) (xy 100.613373 -215.189717) (xy 100.653765 -215.159094)
			(xy 100.698369 -215.135013) (xy 100.746132 -215.118041) (xy 100.770944 -215.112854) (xy 100.793804 -215.108536)
			(xy 100.998782 -214.753444) (xy 100.990908 -214.7316) (xy 100.982329 -214.705181) (xy 100.973132 -214.650406)
			(xy 100.97262 -214.622634) (xy 100.973128 -214.596747) (xy 100.981227 -214.545609) (xy 100.997226 -214.496369)
			(xy 101.020732 -214.450237) (xy 101.051164 -214.40835) (xy 101.087774 -214.37174) (xy 101.129661 -214.341308)
			(xy 101.175793 -214.317802) (xy 101.225033 -214.301803) (xy 101.276171 -214.293704) (xy 101.327945 -214.293704)
			(xy 101.379083 -214.301803) (xy 101.428323 -214.317802) (xy 101.474455 -214.341308) (xy 101.516342 -214.37174)
			(xy 101.552952 -214.40835) (xy 101.583384 -214.450237) (xy 101.60689 -214.496369) (xy 101.622889 -214.545609)
			(xy 101.630988 -214.596747) (xy 101.631496 -214.622634) (xy 101.631047 -214.64797) (xy 101.62329 -214.698044)
			(xy 101.607963 -214.746341) (xy 101.585427 -214.791726) (xy 101.556212 -214.833128) (xy 101.521008 -214.869572)
			(xy 101.480642 -214.900202) (xy 101.436065 -214.924296) (xy 101.388327 -214.941286) (xy 101.363526 -214.946484)
			(xy 101.340666 -214.950802) (xy 101.135688 -215.305894) (xy 101.143562 -215.327738) (xy 101.15221 -215.354146)
			(xy 101.161529 -215.408922) (xy 101.162104 -215.436704) (xy 102.38232 -215.436704) (xy 102.382829 -215.41136)
			(xy 102.3906 -215.36127) (xy 102.405946 -215.31296) (xy 102.428503 -215.267567) (xy 102.457742 -215.226161)
			(xy 102.492973 -215.189717) (xy 102.533365 -215.159094) (xy 102.577969 -215.135013) (xy 102.625732 -215.118041)
			(xy 102.650544 -215.112854) (xy 102.673404 -215.108536) (xy 102.878382 -214.753444) (xy 102.870508 -214.7316)
			(xy 102.861929 -214.705181) (xy 102.852732 -214.650406) (xy 102.85222 -214.622634) (xy 102.852728 -214.596747)
			(xy 102.860827 -214.545609) (xy 102.876826 -214.496369) (xy 102.900332 -214.450237) (xy 102.930764 -214.40835)
			(xy 102.967374 -214.37174) (xy 103.009261 -214.341308) (xy 103.055393 -214.317802) (xy 103.104633 -214.301803)
			(xy 103.155771 -214.293704) (xy 103.207545 -214.293704) (xy 103.258683 -214.301803) (xy 103.307923 -214.317802)
			(xy 103.354055 -214.341308) (xy 103.395942 -214.37174) (xy 103.432552 -214.40835) (xy 103.462984 -214.450237)
			(xy 103.48649 -214.496369) (xy 103.502489 -214.545609) (xy 103.510588 -214.596747) (xy 103.511096 -214.622634)
			(xy 103.510647 -214.64797) (xy 103.50289 -214.698044) (xy 103.487563 -214.746341) (xy 103.465027 -214.791726)
			(xy 103.435812 -214.833128) (xy 103.400608 -214.869572) (xy 103.360242 -214.900202) (xy 103.315665 -214.924296)
			(xy 103.267927 -214.941286) (xy 103.243126 -214.946484) (xy 103.220266 -214.950802) (xy 103.015288 -215.305894)
			(xy 103.023162 -215.327738) (xy 103.03181 -215.354146) (xy 103.041129 -215.408922) (xy 103.041704 -215.436704)
			(xy 104.26192 -215.436704) (xy 104.262429 -215.41136) (xy 104.2702 -215.36127) (xy 104.285546 -215.31296)
			(xy 104.308103 -215.267567) (xy 104.337342 -215.226161) (xy 104.372573 -215.189717) (xy 104.412965 -215.159094)
			(xy 104.457569 -215.135013) (xy 104.505332 -215.118041) (xy 104.530144 -215.112854) (xy 104.553004 -215.108536)
			(xy 104.757982 -214.753444) (xy 104.750108 -214.7316) (xy 104.741529 -214.705181) (xy 104.732332 -214.650406)
			(xy 104.73182 -214.622634) (xy 104.732328 -214.596747) (xy 104.740427 -214.545609) (xy 104.756426 -214.496369)
			(xy 104.779932 -214.450237) (xy 104.810364 -214.40835) (xy 104.846974 -214.37174) (xy 104.888861 -214.341308)
			(xy 104.934993 -214.317802) (xy 104.984233 -214.301803) (xy 105.035371 -214.293704) (xy 105.087145 -214.293704)
			(xy 105.138283 -214.301803) (xy 105.187523 -214.317802) (xy 105.233655 -214.341308) (xy 105.275542 -214.37174)
			(xy 105.312152 -214.40835) (xy 105.342584 -214.450237) (xy 105.36609 -214.496369) (xy 105.382089 -214.545609)
			(xy 105.390188 -214.596747) (xy 105.390696 -214.622634) (xy 105.390247 -214.64797) (xy 105.38249 -214.698044)
			(xy 105.367163 -214.746341) (xy 105.344627 -214.791726) (xy 105.315412 -214.833128) (xy 105.280208 -214.869572)
			(xy 105.239842 -214.900202) (xy 105.195265 -214.924296) (xy 105.147527 -214.941286) (xy 105.122726 -214.946484)
			(xy 105.099866 -214.950802) (xy 104.894888 -215.305894) (xy 104.902762 -215.327738) (xy 104.91141 -215.354146)
			(xy 104.920729 -215.408922) (xy 104.921304 -215.436704) (xy 106.14152 -215.436704) (xy 106.142029 -215.41136)
			(xy 106.1498 -215.36127) (xy 106.165146 -215.31296) (xy 106.187703 -215.267567) (xy 106.216942 -215.226161)
			(xy 106.252173 -215.189717) (xy 106.292565 -215.159094) (xy 106.337169 -215.135013) (xy 106.384932 -215.118041)
			(xy 106.409744 -215.112854) (xy 106.432604 -215.108536) (xy 106.637582 -214.753444) (xy 106.629708 -214.7316)
			(xy 106.621129 -214.705181) (xy 106.611932 -214.650406) (xy 106.61142 -214.622634) (xy 106.611928 -214.596747)
			(xy 106.620027 -214.545609) (xy 106.636026 -214.496369) (xy 106.659532 -214.450237) (xy 106.689964 -214.40835)
			(xy 106.726574 -214.37174) (xy 106.768461 -214.341308) (xy 106.814593 -214.317802) (xy 106.863833 -214.301803)
			(xy 106.914971 -214.293704) (xy 106.966745 -214.293704) (xy 107.017883 -214.301803) (xy 107.067123 -214.317802)
			(xy 107.113255 -214.341308) (xy 107.155142 -214.37174) (xy 107.191752 -214.40835) (xy 107.222184 -214.450237)
			(xy 107.24569 -214.496369) (xy 107.261689 -214.545609) (xy 107.269788 -214.596747) (xy 107.270296 -214.622634)
			(xy 107.269847 -214.64797) (xy 107.26209 -214.698044) (xy 107.246763 -214.746341) (xy 107.224227 -214.791726)
			(xy 107.195012 -214.833128) (xy 107.159808 -214.869572) (xy 107.119442 -214.900202) (xy 107.074865 -214.924296)
			(xy 107.027127 -214.941286) (xy 107.002326 -214.946484) (xy 106.979466 -214.950802) (xy 106.774488 -215.305894)
			(xy 106.782362 -215.327738) (xy 106.79101 -215.354146) (xy 106.800329 -215.408922) (xy 106.800904 -215.436704)
			(xy 108.02112 -215.436704) (xy 108.021629 -215.41136) (xy 108.0294 -215.36127) (xy 108.044746 -215.31296)
			(xy 108.067303 -215.267567) (xy 108.096542 -215.226161) (xy 108.131773 -215.189717) (xy 108.172165 -215.159094)
			(xy 108.216769 -215.135013) (xy 108.264532 -215.118041) (xy 108.289344 -215.112854) (xy 108.312204 -215.108536)
			(xy 108.517182 -214.753444) (xy 108.509308 -214.7316) (xy 108.500729 -214.705181) (xy 108.491532 -214.650406)
			(xy 108.49102 -214.622634) (xy 108.491528 -214.596747) (xy 108.499627 -214.545609) (xy 108.515626 -214.496369)
			(xy 108.539132 -214.450237) (xy 108.569564 -214.40835) (xy 108.606174 -214.37174) (xy 108.648061 -214.341308)
			(xy 108.694193 -214.317802) (xy 108.743433 -214.301803) (xy 108.794571 -214.293704) (xy 108.846345 -214.293704)
			(xy 108.897483 -214.301803) (xy 108.946723 -214.317802) (xy 108.992855 -214.341308) (xy 109.034742 -214.37174)
			(xy 109.071352 -214.40835) (xy 109.101784 -214.450237) (xy 109.12529 -214.496369) (xy 109.141289 -214.545609)
			(xy 109.14142 -214.546434) (xy 110.371128 -214.546434) (xy 110.371636 -214.520547) (xy 110.379735 -214.469409)
			(xy 110.395734 -214.420169) (xy 110.41924 -214.374037) (xy 110.449672 -214.33215) (xy 110.486282 -214.29554)
			(xy 110.528169 -214.265108) (xy 110.574301 -214.241602) (xy 110.623541 -214.225603) (xy 110.674679 -214.217504)
			(xy 110.726453 -214.217504) (xy 110.777591 -214.225603) (xy 110.826831 -214.241602) (xy 110.872963 -214.265108)
			(xy 110.91485 -214.29554) (xy 110.95146 -214.33215) (xy 110.981892 -214.374037) (xy 111.005398 -214.420169)
			(xy 111.021397 -214.469409) (xy 111.029496 -214.520547) (xy 111.030004 -214.546434) (xy 111.030004 -214.546942)
			(xy 111.029596 -214.56979) (xy 111.029246 -214.572283) (xy 112.250803 -214.572283) (xy 112.250803 -214.520517)
			(xy 112.258901 -214.469389) (xy 112.274896 -214.420157) (xy 112.298395 -214.374033) (xy 112.32882 -214.332153)
			(xy 112.365421 -214.295547) (xy 112.407297 -214.265117) (xy 112.453418 -214.241612) (xy 112.502648 -214.22561)
			(xy 112.553775 -214.217507) (xy 112.579658 -214.216996) (xy 112.605169 -214.217509) (xy 112.655581 -214.225363)
			(xy 112.704182 -214.24089) (xy 112.749811 -214.263719) (xy 112.791377 -214.293306) (xy 112.827889 -214.328944)
			(xy 112.843564 -214.349076) (xy 113.255552 -214.349076) (xy 113.271247 -214.328958) (xy 113.307753 -214.293314)
			(xy 113.349314 -214.263719) (xy 113.394938 -214.24088) (xy 113.443536 -214.225342) (xy 113.493947 -214.217476)
			(xy 113.519458 -214.216996) (xy 113.545352 -214.217406) (xy 113.596504 -214.225502) (xy 113.645759 -214.2415)
			(xy 113.691905 -214.265008) (xy 113.733805 -214.295445) (xy 113.770428 -214.332063) (xy 113.80087 -214.373959)
			(xy 113.824384 -214.420102) (xy 113.840388 -214.469355) (xy 113.848491 -214.520506) (xy 113.848491 -214.572294)
			(xy 113.840388 -214.623445) (xy 113.824384 -214.672698) (xy 113.80087 -214.718841) (xy 113.770428 -214.760737)
			(xy 113.733805 -214.797355) (xy 113.691905 -214.827792) (xy 113.645759 -214.8513) (xy 113.596504 -214.867298)
			(xy 113.545352 -214.875394) (xy 113.519458 -214.875872) (xy 113.493944 -214.875433) (xy 113.443527 -214.867566)
			(xy 113.394925 -214.852025) (xy 113.349296 -214.829181) (xy 113.307732 -214.799581) (xy 113.271224 -214.763931)
			(xy 113.255552 -214.743792) (xy 112.843564 -214.743792) (xy 112.827909 -214.763943) (xy 112.791396 -214.799586)
			(xy 112.749827 -214.829178) (xy 112.704195 -214.852012) (xy 112.655589 -214.867542) (xy 112.605171 -214.875398)
			(xy 112.579658 -214.875872) (xy 112.553775 -214.875293) (xy 112.502648 -214.86719) (xy 112.453418 -214.851188)
			(xy 112.407297 -214.827683) (xy 112.365421 -214.797253) (xy 112.32882 -214.760647) (xy 112.298395 -214.718767)
			(xy 112.274896 -214.672643) (xy 112.258901 -214.623411) (xy 112.250803 -214.572283) (xy 111.029246 -214.572283)
			(xy 111.023246 -214.615045) (xy 111.010702 -214.658987) (xy 111.00181 -214.680038) (xy 110.991904 -214.702644)
			(xy 111.205772 -215.108028) (xy 111.229902 -215.1126) (xy 111.254835 -215.117694) (xy 111.302873 -215.134477)
			(xy 111.347761 -215.158443) (xy 111.388433 -215.189024) (xy 111.423922 -215.225492) (xy 111.453384 -215.266981)
			(xy 111.47612 -215.312505) (xy 111.491589 -215.360982) (xy 111.499424 -215.411261) (xy 111.499904 -215.436704)
			(xy 113.65992 -215.436704) (xy 113.660429 -215.41136) (xy 113.6682 -215.36127) (xy 113.683546 -215.31296)
			(xy 113.706103 -215.267567) (xy 113.735342 -215.226161) (xy 113.770573 -215.189717) (xy 113.810965 -215.159094)
			(xy 113.855569 -215.135013) (xy 113.903332 -215.118041) (xy 113.928144 -215.112854) (xy 113.951004 -215.108536)
			(xy 114.156236 -214.753444) (xy 114.148362 -214.731346) (xy 114.139733 -214.704999) (xy 114.130411 -214.650352)
			(xy 114.12982 -214.622634) (xy 114.130328 -214.596727) (xy 114.138434 -214.54555) (xy 114.154446 -214.496271)
			(xy 114.177969 -214.450104) (xy 114.208425 -214.408185) (xy 114.245063 -214.371547) (xy 114.286982 -214.341091)
			(xy 114.333149 -214.317568) (xy 114.382428 -214.301556) (xy 114.433605 -214.29345) (xy 114.485419 -214.29345)
			(xy 114.536596 -214.301556) (xy 114.585875 -214.317568) (xy 114.632042 -214.341091) (xy 114.673961 -214.371547)
			(xy 114.710599 -214.408185) (xy 114.741055 -214.450104) (xy 114.764578 -214.496271) (xy 114.78059 -214.54555)
			(xy 114.788696 -214.596727) (xy 114.789204 -214.622634) (xy 114.78871 -214.647978) (xy 114.780934 -214.698068)
			(xy 114.765584 -214.746377) (xy 114.743024 -214.791769) (xy 114.713783 -214.833174) (xy 114.678552 -214.869617)
			(xy 114.638158 -214.90024) (xy 114.593555 -214.924322) (xy 114.545792 -214.941296) (xy 114.52098 -214.946484)
			(xy 114.49812 -214.950802) (xy 114.292888 -215.305894) (xy 114.300762 -215.327992) (xy 114.309397 -215.354337)
			(xy 114.318716 -215.408986) (xy 114.319304 -215.436704) (xy 115.53952 -215.436704) (xy 115.540029 -215.41136)
			(xy 115.5478 -215.36127) (xy 115.563146 -215.31296) (xy 115.585703 -215.267567) (xy 115.614942 -215.226161)
			(xy 115.650173 -215.189717) (xy 115.690565 -215.159094) (xy 115.735169 -215.135013) (xy 115.782932 -215.118041)
			(xy 115.807744 -215.112854) (xy 115.830604 -215.108536) (xy 116.035582 -214.753444) (xy 116.027708 -214.7316)
			(xy 116.019129 -214.705181) (xy 116.009932 -214.650406) (xy 116.00942 -214.622634) (xy 116.009928 -214.596747)
			(xy 116.018027 -214.545609) (xy 116.034026 -214.496369) (xy 116.057532 -214.450237) (xy 116.087964 -214.40835)
			(xy 116.124574 -214.37174) (xy 116.166461 -214.341308) (xy 116.212593 -214.317802) (xy 116.261833 -214.301803)
			(xy 116.312971 -214.293704) (xy 116.364745 -214.293704) (xy 116.415883 -214.301803) (xy 116.465123 -214.317802)
			(xy 116.511255 -214.341308) (xy 116.553142 -214.37174) (xy 116.589752 -214.40835) (xy 116.620184 -214.450237)
			(xy 116.64369 -214.496369) (xy 116.659689 -214.545609) (xy 116.667788 -214.596747) (xy 116.668296 -214.622634)
			(xy 116.667847 -214.64797) (xy 116.66009 -214.698044) (xy 116.644763 -214.746341) (xy 116.622227 -214.791726)
			(xy 116.593012 -214.833128) (xy 116.557808 -214.869572) (xy 116.517442 -214.900202) (xy 116.472865 -214.924296)
			(xy 116.425127 -214.941286) (xy 116.400326 -214.946484) (xy 116.377466 -214.950802) (xy 116.172488 -215.305894)
			(xy 116.180362 -215.327738) (xy 116.18901 -215.354146) (xy 116.198329 -215.408922) (xy 116.198904 -215.436704)
			(xy 117.41912 -215.436704) (xy 117.419629 -215.41136) (xy 117.4274 -215.36127) (xy 117.442746 -215.31296)
			(xy 117.465303 -215.267567) (xy 117.494542 -215.226161) (xy 117.529773 -215.189717) (xy 117.570165 -215.159094)
			(xy 117.614769 -215.135013) (xy 117.662532 -215.118041) (xy 117.687344 -215.112854) (xy 117.710204 -215.108536)
			(xy 117.915182 -214.753444) (xy 117.907308 -214.7316) (xy 117.898729 -214.705181) (xy 117.889532 -214.650406)
			(xy 117.88902 -214.622634) (xy 117.889528 -214.596747) (xy 117.897627 -214.545609) (xy 117.913626 -214.496369)
			(xy 117.937132 -214.450237) (xy 117.967564 -214.40835) (xy 118.004174 -214.37174) (xy 118.046061 -214.341308)
			(xy 118.092193 -214.317802) (xy 118.141433 -214.301803) (xy 118.192571 -214.293704) (xy 118.244345 -214.293704)
			(xy 118.295483 -214.301803) (xy 118.344723 -214.317802) (xy 118.390855 -214.341308) (xy 118.432742 -214.37174)
			(xy 118.469352 -214.40835) (xy 118.499784 -214.450237) (xy 118.52329 -214.496369) (xy 118.539289 -214.545609)
			(xy 118.547388 -214.596747) (xy 118.547896 -214.622634) (xy 118.547447 -214.64797) (xy 118.53969 -214.698044)
			(xy 118.524363 -214.746341) (xy 118.501827 -214.791726) (xy 118.472612 -214.833128) (xy 118.437408 -214.869572)
			(xy 118.397042 -214.900202) (xy 118.352465 -214.924296) (xy 118.304727 -214.941286) (xy 118.279926 -214.946484)
			(xy 118.257066 -214.950802) (xy 118.052088 -215.305894) (xy 118.059962 -215.327738) (xy 118.06861 -215.354146)
			(xy 118.077929 -215.408922) (xy 118.078504 -215.436704) (xy 119.29872 -215.436704) (xy 119.299229 -215.41136)
			(xy 119.307 -215.36127) (xy 119.322346 -215.31296) (xy 119.344903 -215.267567) (xy 119.374142 -215.226161)
			(xy 119.409373 -215.189717) (xy 119.449765 -215.159094) (xy 119.494369 -215.135013) (xy 119.542132 -215.118041)
			(xy 119.566944 -215.112854) (xy 119.589804 -215.108536) (xy 119.794782 -214.753444) (xy 119.786908 -214.7316)
			(xy 119.778329 -214.705181) (xy 119.769132 -214.650406) (xy 119.76862 -214.622634) (xy 119.769128 -214.596747)
			(xy 119.777227 -214.545609) (xy 119.793226 -214.496369) (xy 119.816732 -214.450237) (xy 119.847164 -214.40835)
			(xy 119.883774 -214.37174) (xy 119.925661 -214.341308) (xy 119.971793 -214.317802) (xy 120.021033 -214.301803)
			(xy 120.072171 -214.293704) (xy 120.123945 -214.293704) (xy 120.175083 -214.301803) (xy 120.224323 -214.317802)
			(xy 120.270455 -214.341308) (xy 120.312342 -214.37174) (xy 120.348952 -214.40835) (xy 120.379384 -214.450237)
			(xy 120.40289 -214.496369) (xy 120.418889 -214.545609) (xy 120.426988 -214.596747) (xy 120.427496 -214.622634)
			(xy 120.427047 -214.64797) (xy 120.41929 -214.698044) (xy 120.403963 -214.746341) (xy 120.381427 -214.791726)
			(xy 120.352212 -214.833128) (xy 120.317008 -214.869572) (xy 120.276642 -214.900202) (xy 120.232065 -214.924296)
			(xy 120.184327 -214.941286) (xy 120.159526 -214.946484) (xy 120.136666 -214.950802) (xy 119.931688 -215.305894)
			(xy 119.939562 -215.327738) (xy 119.94821 -215.354146) (xy 119.957529 -215.408922) (xy 119.958104 -215.436704)
			(xy 121.17832 -215.436704) (xy 121.178829 -215.41136) (xy 121.1866 -215.36127) (xy 121.201946 -215.31296)
			(xy 121.224503 -215.267567) (xy 121.253742 -215.226161) (xy 121.288973 -215.189717) (xy 121.329365 -215.159094)
			(xy 121.373969 -215.135013) (xy 121.421732 -215.118041) (xy 121.446544 -215.112854) (xy 121.469404 -215.108536)
			(xy 121.674382 -214.753444) (xy 121.666508 -214.7316) (xy 121.657929 -214.705181) (xy 121.648732 -214.650406)
			(xy 121.64822 -214.622634) (xy 121.648728 -214.596747) (xy 121.656827 -214.545609) (xy 121.672826 -214.496369)
			(xy 121.696332 -214.450237) (xy 121.726764 -214.40835) (xy 121.763374 -214.37174) (xy 121.805261 -214.341308)
			(xy 121.851393 -214.317802) (xy 121.900633 -214.301803) (xy 121.951771 -214.293704) (xy 122.003545 -214.293704)
			(xy 122.054683 -214.301803) (xy 122.103923 -214.317802) (xy 122.150055 -214.341308) (xy 122.191942 -214.37174)
			(xy 122.228552 -214.40835) (xy 122.258984 -214.450237) (xy 122.28249 -214.496369) (xy 122.298489 -214.545609)
			(xy 122.306588 -214.596747) (xy 122.307096 -214.622634) (xy 122.306647 -214.64797) (xy 122.29889 -214.698044)
			(xy 122.283563 -214.746341) (xy 122.261027 -214.791726) (xy 122.231812 -214.833128) (xy 122.196608 -214.869572)
			(xy 122.156242 -214.900202) (xy 122.111665 -214.924296) (xy 122.063927 -214.941286) (xy 122.039126 -214.946484)
			(xy 122.016266 -214.950802) (xy 121.811288 -215.305894) (xy 121.819162 -215.327738) (xy 121.82781 -215.354146)
			(xy 121.837129 -215.408922) (xy 121.837704 -215.436704) (xy 123.05792 -215.436704) (xy 123.058429 -215.41136)
			(xy 123.0662 -215.36127) (xy 123.081546 -215.31296) (xy 123.104103 -215.267567) (xy 123.133342 -215.226161)
			(xy 123.168573 -215.189717) (xy 123.208965 -215.159094) (xy 123.253569 -215.135013) (xy 123.301332 -215.118041)
			(xy 123.326144 -215.112854) (xy 123.349004 -215.108536) (xy 123.553982 -214.753444) (xy 123.546108 -214.7316)
			(xy 123.537529 -214.705181) (xy 123.528332 -214.650406) (xy 123.52782 -214.622634) (xy 123.528328 -214.596747)
			(xy 123.536427 -214.545609) (xy 123.552426 -214.496369) (xy 123.575932 -214.450237) (xy 123.606364 -214.40835)
			(xy 123.642974 -214.37174) (xy 123.684861 -214.341308) (xy 123.730993 -214.317802) (xy 123.780233 -214.301803)
			(xy 123.831371 -214.293704) (xy 123.883145 -214.293704) (xy 123.934283 -214.301803) (xy 123.983523 -214.317802)
			(xy 124.029655 -214.341308) (xy 124.071542 -214.37174) (xy 124.108152 -214.40835) (xy 124.138584 -214.450237)
			(xy 124.16209 -214.496369) (xy 124.178089 -214.545609) (xy 124.186188 -214.596747) (xy 124.186696 -214.622634)
			(xy 124.186247 -214.64797) (xy 124.17849 -214.698044) (xy 124.163163 -214.746341) (xy 124.140627 -214.791726)
			(xy 124.111412 -214.833128) (xy 124.076208 -214.869572) (xy 124.035842 -214.900202) (xy 123.991265 -214.924296)
			(xy 123.943527 -214.941286) (xy 123.918726 -214.946484) (xy 123.895866 -214.950802) (xy 123.690888 -215.305894)
			(xy 123.698762 -215.327738) (xy 123.70741 -215.354146) (xy 123.716729 -215.408922) (xy 123.717304 -215.436704)
			(xy 124.93752 -215.436704) (xy 124.938029 -215.41136) (xy 124.9458 -215.36127) (xy 124.961146 -215.31296)
			(xy 124.983703 -215.267567) (xy 125.012942 -215.226161) (xy 125.048173 -215.189717) (xy 125.088565 -215.159094)
			(xy 125.133169 -215.135013) (xy 125.180932 -215.118041) (xy 125.205744 -215.112854) (xy 125.228604 -215.108536)
			(xy 125.433582 -214.753444) (xy 125.425708 -214.7316) (xy 125.417129 -214.705181) (xy 125.407932 -214.650406)
			(xy 125.40742 -214.622634) (xy 125.407928 -214.596747) (xy 125.416027 -214.545609) (xy 125.432026 -214.496369)
			(xy 125.455532 -214.450237) (xy 125.485964 -214.40835) (xy 125.522574 -214.37174) (xy 125.564461 -214.341308)
			(xy 125.610593 -214.317802) (xy 125.659833 -214.301803) (xy 125.710971 -214.293704) (xy 125.762745 -214.293704)
			(xy 125.813883 -214.301803) (xy 125.863123 -214.317802) (xy 125.909255 -214.341308) (xy 125.951142 -214.37174)
			(xy 125.987752 -214.40835) (xy 126.018184 -214.450237) (xy 126.04169 -214.496369) (xy 126.057689 -214.545609)
			(xy 126.065788 -214.596747) (xy 126.066296 -214.622634) (xy 126.065847 -214.64797) (xy 126.05809 -214.698044)
			(xy 126.042763 -214.746341) (xy 126.020227 -214.791726) (xy 125.991012 -214.833128) (xy 125.955808 -214.869572)
			(xy 125.915442 -214.900202) (xy 125.870865 -214.924296) (xy 125.823127 -214.941286) (xy 125.798326 -214.946484)
			(xy 125.775466 -214.950802) (xy 125.570488 -215.305894) (xy 125.578362 -215.327738) (xy 125.58701 -215.354146)
			(xy 125.596329 -215.408922) (xy 125.596904 -215.436704) (xy 126.81712 -215.436704) (xy 126.817629 -215.41136)
			(xy 126.8254 -215.36127) (xy 126.840746 -215.31296) (xy 126.863303 -215.267567) (xy 126.892542 -215.226161)
			(xy 126.927773 -215.189717) (xy 126.968165 -215.159094) (xy 127.012769 -215.135013) (xy 127.060532 -215.118041)
			(xy 127.085344 -215.112854) (xy 127.108204 -215.108536) (xy 127.313182 -214.753444) (xy 127.305308 -214.7316)
			(xy 127.296729 -214.705181) (xy 127.287532 -214.650406) (xy 127.28702 -214.622634) (xy 127.287528 -214.596747)
			(xy 127.295627 -214.545609) (xy 127.311626 -214.496369) (xy 127.335132 -214.450237) (xy 127.365564 -214.40835)
			(xy 127.402174 -214.37174) (xy 127.444061 -214.341308) (xy 127.490193 -214.317802) (xy 127.539433 -214.301803)
			(xy 127.590571 -214.293704) (xy 127.642345 -214.293704) (xy 127.693483 -214.301803) (xy 127.742723 -214.317802)
			(xy 127.788855 -214.341308) (xy 127.830742 -214.37174) (xy 127.867352 -214.40835) (xy 127.897784 -214.450237)
			(xy 127.92129 -214.496369) (xy 127.937289 -214.545609) (xy 127.945388 -214.596747) (xy 127.945896 -214.622634)
			(xy 127.945447 -214.64797) (xy 127.93769 -214.698044) (xy 127.922363 -214.746341) (xy 127.899827 -214.791726)
			(xy 127.870612 -214.833128) (xy 127.835408 -214.869572) (xy 127.795042 -214.900202) (xy 127.750465 -214.924296)
			(xy 127.702727 -214.941286) (xy 127.677926 -214.946484) (xy 127.655066 -214.950802) (xy 127.450088 -215.305894)
			(xy 127.457962 -215.327738) (xy 127.46661 -215.354146) (xy 127.475929 -215.408922) (xy 127.476504 -215.436704)
			(xy 128.69672 -215.436704) (xy 128.697229 -215.41136) (xy 128.705 -215.36127) (xy 128.720346 -215.31296)
			(xy 128.742903 -215.267567) (xy 128.772142 -215.226161) (xy 128.807373 -215.189717) (xy 128.847765 -215.159094)
			(xy 128.892369 -215.135013) (xy 128.940132 -215.118041) (xy 128.964944 -215.112854) (xy 128.987804 -215.108536)
			(xy 129.192782 -214.753444) (xy 129.184908 -214.7316) (xy 129.176329 -214.705181) (xy 129.167132 -214.650406)
			(xy 129.16662 -214.622634) (xy 129.167128 -214.596747) (xy 129.175227 -214.545609) (xy 129.191226 -214.496369)
			(xy 129.214732 -214.450237) (xy 129.245164 -214.40835) (xy 129.281774 -214.37174) (xy 129.323661 -214.341308)
			(xy 129.369793 -214.317802) (xy 129.419033 -214.301803) (xy 129.470171 -214.293704) (xy 129.521945 -214.293704)
			(xy 129.573083 -214.301803) (xy 129.622323 -214.317802) (xy 129.668455 -214.341308) (xy 129.710342 -214.37174)
			(xy 129.746952 -214.40835) (xy 129.777384 -214.450237) (xy 129.80089 -214.496369) (xy 129.816889 -214.545609)
			(xy 129.824988 -214.596747) (xy 129.825496 -214.622634) (xy 129.825047 -214.64797) (xy 129.81729 -214.698044)
			(xy 129.801963 -214.746341) (xy 129.779427 -214.791726) (xy 129.750212 -214.833128) (xy 129.715008 -214.869572)
			(xy 129.674642 -214.900202) (xy 129.630065 -214.924296) (xy 129.582327 -214.941286) (xy 129.557526 -214.946484)
			(xy 129.534666 -214.950802) (xy 129.329688 -215.305894) (xy 129.337562 -215.327738) (xy 129.34621 -215.354146)
			(xy 129.355529 -215.408922) (xy 129.356104 -215.436704) (xy 130.57632 -215.436704) (xy 130.576829 -215.41136)
			(xy 130.5846 -215.36127) (xy 130.599946 -215.31296) (xy 130.622503 -215.267567) (xy 130.651742 -215.226161)
			(xy 130.686973 -215.189717) (xy 130.727365 -215.159094) (xy 130.771969 -215.135013) (xy 130.819732 -215.118041)
			(xy 130.844544 -215.112854) (xy 130.867404 -215.108536) (xy 131.072382 -214.753444) (xy 131.064508 -214.7316)
			(xy 131.055929 -214.705181) (xy 131.046732 -214.650406) (xy 131.04622 -214.622634) (xy 131.046728 -214.596747)
			(xy 131.054827 -214.545609) (xy 131.070826 -214.496369) (xy 131.094332 -214.450237) (xy 131.124764 -214.40835)
			(xy 131.161374 -214.37174) (xy 131.203261 -214.341308) (xy 131.249393 -214.317802) (xy 131.298633 -214.301803)
			(xy 131.349771 -214.293704) (xy 131.401545 -214.293704) (xy 131.452683 -214.301803) (xy 131.501923 -214.317802)
			(xy 131.548055 -214.341308) (xy 131.589942 -214.37174) (xy 131.626552 -214.40835) (xy 131.656984 -214.450237)
			(xy 131.68049 -214.496369) (xy 131.696489 -214.545609) (xy 131.704588 -214.596747) (xy 131.705096 -214.622634)
			(xy 131.704647 -214.64797) (xy 131.69689 -214.698044) (xy 131.681563 -214.746341) (xy 131.659027 -214.791726)
			(xy 131.629812 -214.833128) (xy 131.594608 -214.869572) (xy 131.554242 -214.900202) (xy 131.509665 -214.924296)
			(xy 131.461927 -214.941286) (xy 131.437126 -214.946484) (xy 131.414266 -214.950802) (xy 131.209288 -215.305894)
			(xy 131.217162 -215.327738) (xy 131.22581 -215.354146) (xy 131.235129 -215.408922) (xy 131.235704 -215.436704)
			(xy 132.45592 -215.436704) (xy 132.456429 -215.41136) (xy 132.4642 -215.36127) (xy 132.479546 -215.31296)
			(xy 132.502103 -215.267567) (xy 132.531342 -215.226161) (xy 132.566573 -215.189717) (xy 132.606965 -215.159094)
			(xy 132.651569 -215.135013) (xy 132.699332 -215.118041) (xy 132.724144 -215.112854) (xy 132.747004 -215.108536)
			(xy 132.951982 -214.753444) (xy 132.944108 -214.7316) (xy 132.935529 -214.705181) (xy 132.926332 -214.650406)
			(xy 132.92582 -214.622634) (xy 132.926328 -214.596747) (xy 132.934427 -214.545609) (xy 132.950426 -214.496369)
			(xy 132.973932 -214.450237) (xy 133.004364 -214.40835) (xy 133.040974 -214.37174) (xy 133.082861 -214.341308)
			(xy 133.128993 -214.317802) (xy 133.178233 -214.301803) (xy 133.229371 -214.293704) (xy 133.281145 -214.293704)
			(xy 133.332283 -214.301803) (xy 133.381523 -214.317802) (xy 133.427655 -214.341308) (xy 133.469542 -214.37174)
			(xy 133.506152 -214.40835) (xy 133.536584 -214.450237) (xy 133.56009 -214.496369) (xy 133.576089 -214.545609)
			(xy 133.57622 -214.546434) (xy 134.80542 -214.546434) (xy 134.805928 -214.520527) (xy 134.814034 -214.46935)
			(xy 134.830046 -214.420071) (xy 134.853569 -214.373904) (xy 134.884025 -214.331985) (xy 134.920663 -214.295347)
			(xy 134.962582 -214.264891) (xy 135.008749 -214.241368) (xy 135.058028 -214.225356) (xy 135.109205 -214.21725)
			(xy 135.161019 -214.21725) (xy 135.212196 -214.225356) (xy 135.261475 -214.241368) (xy 135.307642 -214.264891)
			(xy 135.349561 -214.295347) (xy 135.386199 -214.331985) (xy 135.416655 -214.373904) (xy 135.440178 -214.420071)
			(xy 135.45619 -214.46935) (xy 135.464296 -214.520527) (xy 135.464804 -214.546434) (xy 135.464102 -214.577275)
			(xy 135.452589 -214.637875) (xy 135.441944 -214.66683) (xy 135.433308 -214.688674) (xy 135.656066 -215.110314)
			(xy 135.678672 -215.115394) (xy 135.702597 -215.121362) (xy 135.748484 -215.139404) (xy 135.791171 -215.164081)
			(xy 135.829706 -215.194841) (xy 135.863229 -215.230999) (xy 135.890992 -215.271747) (xy 135.912374 -215.316176)
			(xy 135.9269 -215.363294) (xy 135.934244 -215.412051) (xy 135.934704 -215.436704) (xy 336.225388 -215.436704)
			(xy 336.225896 -215.410797) (xy 336.234002 -215.35962) (xy 336.250014 -215.310341) (xy 336.273537 -215.264174)
			(xy 336.303993 -215.222255) (xy 336.340631 -215.185617) (xy 336.38255 -215.155161) (xy 336.428717 -215.131638)
			(xy 336.477996 -215.115626) (xy 336.529173 -215.10752) (xy 336.580987 -215.10752) (xy 336.632164 -215.115626)
			(xy 336.681443 -215.131638) (xy 336.72761 -215.155161) (xy 336.769529 -215.185617) (xy 336.806167 -215.222255)
			(xy 336.836623 -215.264174) (xy 336.860146 -215.310341) (xy 336.876158 -215.35962) (xy 336.884264 -215.410797)
			(xy 336.884772 -215.436704) (xy 337.165188 -215.436704) (xy 337.165723 -215.411361) (xy 337.173493 -215.361274)
			(xy 337.188837 -215.312966) (xy 337.211392 -215.267575) (xy 337.240627 -215.226169) (xy 337.275854 -215.189725)
			(xy 337.316243 -215.159101) (xy 337.360842 -215.135018) (xy 337.408601 -215.118043) (xy 337.433412 -215.112854)
			(xy 337.456272 -215.108536) (xy 337.66125 -214.753444) (xy 337.653376 -214.7316) (xy 337.644799 -214.705181)
			(xy 337.6356 -214.650406) (xy 337.635088 -214.622634) (xy 337.635596 -214.596747) (xy 337.643695 -214.545609)
			(xy 337.659694 -214.496369) (xy 337.6832 -214.450237) (xy 337.713632 -214.40835) (xy 337.750242 -214.37174)
			(xy 337.792129 -214.341308) (xy 337.838261 -214.317802) (xy 337.887501 -214.301803) (xy 337.938639 -214.293704)
			(xy 337.990413 -214.293704) (xy 338.041551 -214.301803) (xy 338.090791 -214.317802) (xy 338.136923 -214.341308)
			(xy 338.17881 -214.37174) (xy 338.21542 -214.40835) (xy 338.245852 -214.450237) (xy 338.269358 -214.496369)
			(xy 338.285357 -214.545609) (xy 338.293456 -214.596747) (xy 338.293964 -214.622634) (xy 338.293541 -214.647971)
			(xy 338.285783 -214.698047) (xy 338.270454 -214.746347) (xy 338.247915 -214.791733) (xy 338.218698 -214.833136)
			(xy 338.18349 -214.869581) (xy 338.14312 -214.90021) (xy 338.098539 -214.924301) (xy 338.050797 -214.941288)
			(xy 338.025994 -214.946484) (xy 338.003134 -214.950802) (xy 337.798156 -215.305894) (xy 337.80603 -215.327738)
			(xy 337.814677 -215.354146) (xy 337.823997 -215.408922) (xy 337.824572 -215.436704) (xy 339.044788 -215.436704)
			(xy 339.045323 -215.411361) (xy 339.053093 -215.361274) (xy 339.068437 -215.312966) (xy 339.090992 -215.267575)
			(xy 339.120227 -215.226169) (xy 339.155454 -215.189725) (xy 339.195843 -215.159101) (xy 339.240442 -215.135018)
			(xy 339.288201 -215.118043) (xy 339.313012 -215.112854) (xy 339.335872 -215.108536) (xy 339.54085 -214.753444)
			(xy 339.532976 -214.7316) (xy 339.524399 -214.705181) (xy 339.5152 -214.650406) (xy 339.514688 -214.622634)
			(xy 339.515196 -214.596747) (xy 339.523295 -214.545609) (xy 339.539294 -214.496369) (xy 339.5628 -214.450237)
			(xy 339.593232 -214.40835) (xy 339.629842 -214.37174) (xy 339.671729 -214.341308) (xy 339.717861 -214.317802)
			(xy 339.767101 -214.301803) (xy 339.818239 -214.293704) (xy 339.870013 -214.293704) (xy 339.921151 -214.301803)
			(xy 339.970391 -214.317802) (xy 340.016523 -214.341308) (xy 340.05841 -214.37174) (xy 340.09502 -214.40835)
			(xy 340.125452 -214.450237) (xy 340.148958 -214.496369) (xy 340.164957 -214.545609) (xy 340.173056 -214.596747)
			(xy 340.173564 -214.622634) (xy 340.173141 -214.647971) (xy 340.165383 -214.698047) (xy 340.150054 -214.746347)
			(xy 340.127515 -214.791733) (xy 340.098298 -214.833136) (xy 340.06309 -214.869581) (xy 340.02272 -214.90021)
			(xy 339.978139 -214.924301) (xy 339.930397 -214.941288) (xy 339.905594 -214.946484) (xy 339.882734 -214.950802)
			(xy 339.677756 -215.305894) (xy 339.68563 -215.327738) (xy 339.694277 -215.354146) (xy 339.703597 -215.408922)
			(xy 339.704172 -215.436704) (xy 340.924388 -215.436704) (xy 340.924923 -215.411361) (xy 340.932693 -215.361274)
			(xy 340.948037 -215.312966) (xy 340.970592 -215.267575) (xy 340.999827 -215.226169) (xy 341.035054 -215.189725)
			(xy 341.075443 -215.159101) (xy 341.120042 -215.135018) (xy 341.167801 -215.118043) (xy 341.192612 -215.112854)
			(xy 341.215472 -215.108536) (xy 341.42045 -214.753444) (xy 341.412576 -214.7316) (xy 341.403999 -214.705181)
			(xy 341.3948 -214.650406) (xy 341.394288 -214.622634) (xy 341.394796 -214.596747) (xy 341.402895 -214.545609)
			(xy 341.418894 -214.496369) (xy 341.4424 -214.450237) (xy 341.472832 -214.40835) (xy 341.509442 -214.37174)
			(xy 341.551329 -214.341308) (xy 341.597461 -214.317802) (xy 341.646701 -214.301803) (xy 341.697839 -214.293704)
			(xy 341.749613 -214.293704) (xy 341.800751 -214.301803) (xy 341.849991 -214.317802) (xy 341.896123 -214.341308)
			(xy 341.93801 -214.37174) (xy 341.97462 -214.40835) (xy 342.005052 -214.450237) (xy 342.028558 -214.496369)
			(xy 342.044557 -214.545609) (xy 342.052656 -214.596747) (xy 342.053164 -214.622634) (xy 342.052741 -214.647971)
			(xy 342.044983 -214.698047) (xy 342.029654 -214.746347) (xy 342.007115 -214.791733) (xy 341.977898 -214.833136)
			(xy 341.94269 -214.869581) (xy 341.90232 -214.90021) (xy 341.857739 -214.924301) (xy 341.809997 -214.941288)
			(xy 341.785194 -214.946484) (xy 341.762334 -214.950802) (xy 341.557356 -215.305894) (xy 341.56523 -215.327738)
			(xy 341.573877 -215.354146) (xy 341.583197 -215.408922) (xy 341.583772 -215.436704) (xy 342.803988 -215.436704)
			(xy 342.804523 -215.411361) (xy 342.812293 -215.361274) (xy 342.827637 -215.312966) (xy 342.850192 -215.267575)
			(xy 342.879427 -215.226169) (xy 342.914654 -215.189725) (xy 342.955043 -215.159101) (xy 342.999642 -215.135018)
			(xy 343.047401 -215.118043) (xy 343.072212 -215.112854) (xy 343.095072 -215.108536) (xy 343.30005 -214.753444)
			(xy 343.292176 -214.7316) (xy 343.283599 -214.705181) (xy 343.2744 -214.650406) (xy 343.273888 -214.622634)
			(xy 343.274396 -214.596747) (xy 343.282495 -214.545609) (xy 343.298494 -214.496369) (xy 343.322 -214.450237)
			(xy 343.352432 -214.40835) (xy 343.389042 -214.37174) (xy 343.430929 -214.341308) (xy 343.477061 -214.317802)
			(xy 343.526301 -214.301803) (xy 343.577439 -214.293704) (xy 343.629213 -214.293704) (xy 343.680351 -214.301803)
			(xy 343.729591 -214.317802) (xy 343.775723 -214.341308) (xy 343.81761 -214.37174) (xy 343.85422 -214.40835)
			(xy 343.884652 -214.450237) (xy 343.908158 -214.496369) (xy 343.924157 -214.545609) (xy 343.932256 -214.596747)
			(xy 343.932764 -214.622634) (xy 343.932341 -214.647971) (xy 343.924583 -214.698047) (xy 343.909254 -214.746347)
			(xy 343.886715 -214.791733) (xy 343.857498 -214.833136) (xy 343.82229 -214.869581) (xy 343.78192 -214.90021)
			(xy 343.737339 -214.924301) (xy 343.689597 -214.941288) (xy 343.664794 -214.946484) (xy 343.641934 -214.950802)
			(xy 343.436956 -215.305894) (xy 343.44483 -215.327738) (xy 343.453477 -215.354146) (xy 343.462797 -215.408922)
			(xy 343.463372 -215.436704) (xy 344.683588 -215.436704) (xy 344.684123 -215.411361) (xy 344.691893 -215.361274)
			(xy 344.707237 -215.312966) (xy 344.729792 -215.267575) (xy 344.759027 -215.226169) (xy 344.794254 -215.189725)
			(xy 344.834643 -215.159101) (xy 344.879242 -215.135018) (xy 344.927001 -215.118043) (xy 344.951812 -215.112854)
			(xy 344.974672 -215.108536) (xy 345.17965 -214.753444) (xy 345.171776 -214.7316) (xy 345.163199 -214.705181)
			(xy 345.154 -214.650406) (xy 345.153488 -214.622634) (xy 345.153996 -214.596747) (xy 345.162095 -214.545609)
			(xy 345.178094 -214.496369) (xy 345.2016 -214.450237) (xy 345.232032 -214.40835) (xy 345.268642 -214.37174)
			(xy 345.310529 -214.341308) (xy 345.356661 -214.317802) (xy 345.405901 -214.301803) (xy 345.457039 -214.293704)
			(xy 345.508813 -214.293704) (xy 345.559951 -214.301803) (xy 345.609191 -214.317802) (xy 345.655323 -214.341308)
			(xy 345.69721 -214.37174) (xy 345.73382 -214.40835) (xy 345.764252 -214.450237) (xy 345.787758 -214.496369)
			(xy 345.803757 -214.545609) (xy 345.811856 -214.596747) (xy 345.812364 -214.622634) (xy 345.811941 -214.647971)
			(xy 345.804183 -214.698047) (xy 345.788854 -214.746347) (xy 345.766315 -214.791733) (xy 345.737098 -214.833136)
			(xy 345.70189 -214.869581) (xy 345.66152 -214.90021) (xy 345.616939 -214.924301) (xy 345.569197 -214.941288)
			(xy 345.544394 -214.946484) (xy 345.521534 -214.950802) (xy 345.316556 -215.305894) (xy 345.32443 -215.327738)
			(xy 345.333077 -215.354146) (xy 345.342397 -215.408922) (xy 345.342972 -215.436704) (xy 346.563188 -215.436704)
			(xy 346.563723 -215.411361) (xy 346.571493 -215.361274) (xy 346.586837 -215.312966) (xy 346.609392 -215.267575)
			(xy 346.638627 -215.226169) (xy 346.673854 -215.189725) (xy 346.714243 -215.159101) (xy 346.758842 -215.135018)
			(xy 346.806601 -215.118043) (xy 346.831412 -215.112854) (xy 346.854272 -215.108536) (xy 347.05925 -214.753444)
			(xy 347.051376 -214.7316) (xy 347.042799 -214.705181) (xy 347.0336 -214.650406) (xy 347.033088 -214.622634)
			(xy 347.033596 -214.596747) (xy 347.041695 -214.545609) (xy 347.057694 -214.496369) (xy 347.0812 -214.450237)
			(xy 347.111632 -214.40835) (xy 347.148242 -214.37174) (xy 347.190129 -214.341308) (xy 347.236261 -214.317802)
			(xy 347.285501 -214.301803) (xy 347.336639 -214.293704) (xy 347.388413 -214.293704) (xy 347.439551 -214.301803)
			(xy 347.488791 -214.317802) (xy 347.534923 -214.341308) (xy 347.57681 -214.37174) (xy 347.61342 -214.40835)
			(xy 347.643852 -214.450237) (xy 347.667358 -214.496369) (xy 347.683357 -214.545609) (xy 347.691456 -214.596747)
			(xy 347.691964 -214.622634) (xy 347.691541 -214.647971) (xy 347.683783 -214.698047) (xy 347.668454 -214.746347)
			(xy 347.645915 -214.791733) (xy 347.616698 -214.833136) (xy 347.58149 -214.869581) (xy 347.54112 -214.90021)
			(xy 347.496539 -214.924301) (xy 347.448797 -214.941288) (xy 347.423994 -214.946484) (xy 347.401134 -214.950802)
			(xy 347.196156 -215.305894) (xy 347.20403 -215.327738) (xy 347.212677 -215.354146) (xy 347.221997 -215.408922)
			(xy 347.222572 -215.436704) (xy 348.442788 -215.436704) (xy 348.443323 -215.411361) (xy 348.451093 -215.361274)
			(xy 348.466437 -215.312966) (xy 348.488992 -215.267575) (xy 348.518227 -215.226169) (xy 348.553454 -215.189725)
			(xy 348.593843 -215.159101) (xy 348.638442 -215.135018) (xy 348.686201 -215.118043) (xy 348.711012 -215.112854)
			(xy 348.733872 -215.108536) (xy 348.93885 -214.753444) (xy 348.930976 -214.7316) (xy 348.922399 -214.705181)
			(xy 348.9132 -214.650406) (xy 348.912688 -214.622634) (xy 348.913196 -214.596747) (xy 348.921295 -214.545609)
			(xy 348.937294 -214.496369) (xy 348.9608 -214.450237) (xy 348.991232 -214.40835) (xy 349.027842 -214.37174)
			(xy 349.069729 -214.341308) (xy 349.115861 -214.317802) (xy 349.165101 -214.301803) (xy 349.216239 -214.293704)
			(xy 349.268013 -214.293704) (xy 349.319151 -214.301803) (xy 349.368391 -214.317802) (xy 349.414523 -214.341308)
			(xy 349.45641 -214.37174) (xy 349.49302 -214.40835) (xy 349.523452 -214.450237) (xy 349.546958 -214.496369)
			(xy 349.562957 -214.545609) (xy 349.571056 -214.596747) (xy 349.571564 -214.622634) (xy 349.571141 -214.647971)
			(xy 349.563383 -214.698047) (xy 349.548054 -214.746347) (xy 349.525515 -214.791733) (xy 349.496298 -214.833136)
			(xy 349.46109 -214.869581) (xy 349.42072 -214.90021) (xy 349.376139 -214.924301) (xy 349.328397 -214.941288)
			(xy 349.303594 -214.946484) (xy 349.280734 -214.950802) (xy 349.075756 -215.305894) (xy 349.08363 -215.327738)
			(xy 349.092277 -215.354146) (xy 349.101597 -215.408922) (xy 349.102172 -215.436704) (xy 350.322388 -215.436704)
			(xy 350.322923 -215.411361) (xy 350.330693 -215.361274) (xy 350.346037 -215.312966) (xy 350.368592 -215.267575)
			(xy 350.397827 -215.226169) (xy 350.433054 -215.189725) (xy 350.473443 -215.159101) (xy 350.518042 -215.135018)
			(xy 350.565801 -215.118043) (xy 350.590612 -215.112854) (xy 350.613472 -215.108536) (xy 350.81845 -214.753444)
			(xy 350.810576 -214.7316) (xy 350.801999 -214.705181) (xy 350.7928 -214.650406) (xy 350.792288 -214.622634)
			(xy 350.792796 -214.596747) (xy 350.800895 -214.545609) (xy 350.816894 -214.496369) (xy 350.8404 -214.450237)
			(xy 350.870832 -214.40835) (xy 350.907442 -214.37174) (xy 350.949329 -214.341308) (xy 350.995461 -214.317802)
			(xy 351.044701 -214.301803) (xy 351.095839 -214.293704) (xy 351.147613 -214.293704) (xy 351.198751 -214.301803)
			(xy 351.247991 -214.317802) (xy 351.294123 -214.341308) (xy 351.33601 -214.37174) (xy 351.37262 -214.40835)
			(xy 351.403052 -214.450237) (xy 351.426558 -214.496369) (xy 351.442557 -214.545609) (xy 351.450656 -214.596747)
			(xy 351.451164 -214.622634) (xy 351.450741 -214.647971) (xy 351.442983 -214.698047) (xy 351.427654 -214.746347)
			(xy 351.405115 -214.791733) (xy 351.375898 -214.833136) (xy 351.34069 -214.869581) (xy 351.30032 -214.90021)
			(xy 351.255739 -214.924301) (xy 351.207997 -214.941288) (xy 351.183194 -214.946484) (xy 351.160334 -214.950802)
			(xy 350.955356 -215.305894) (xy 350.96323 -215.327738) (xy 350.971877 -215.354146) (xy 350.981197 -215.408922)
			(xy 350.981772 -215.436704) (xy 352.201988 -215.436704) (xy 352.202523 -215.411361) (xy 352.210293 -215.361274)
			(xy 352.225637 -215.312966) (xy 352.248192 -215.267575) (xy 352.277427 -215.226169) (xy 352.312654 -215.189725)
			(xy 352.353043 -215.159101) (xy 352.397642 -215.135018) (xy 352.445401 -215.118043) (xy 352.470212 -215.112854)
			(xy 352.493072 -215.108536) (xy 352.69805 -214.753444) (xy 352.690176 -214.7316) (xy 352.681599 -214.705181)
			(xy 352.6724 -214.650406) (xy 352.671888 -214.622634) (xy 352.672396 -214.596747) (xy 352.680495 -214.545609)
			(xy 352.696494 -214.496369) (xy 352.72 -214.450237) (xy 352.750432 -214.40835) (xy 352.787042 -214.37174)
			(xy 352.828929 -214.341308) (xy 352.875061 -214.317802) (xy 352.924301 -214.301803) (xy 352.975439 -214.293704)
			(xy 353.027213 -214.293704) (xy 353.078351 -214.301803) (xy 353.127591 -214.317802) (xy 353.173723 -214.341308)
			(xy 353.21561 -214.37174) (xy 353.25222 -214.40835) (xy 353.282652 -214.450237) (xy 353.306158 -214.496369)
			(xy 353.322157 -214.545609) (xy 353.330256 -214.596747) (xy 353.330764 -214.622634) (xy 353.330341 -214.647971)
			(xy 353.322583 -214.698047) (xy 353.307254 -214.746347) (xy 353.284715 -214.791733) (xy 353.255498 -214.833136)
			(xy 353.22029 -214.869581) (xy 353.17992 -214.90021) (xy 353.135339 -214.924301) (xy 353.087597 -214.941288)
			(xy 353.062794 -214.946484) (xy 353.039934 -214.950802) (xy 352.834956 -215.305894) (xy 352.84283 -215.327738)
			(xy 352.851477 -215.354146) (xy 352.860797 -215.408922) (xy 352.861372 -215.436704) (xy 354.081588 -215.436704)
			(xy 354.082123 -215.411361) (xy 354.089893 -215.361274) (xy 354.105237 -215.312966) (xy 354.127792 -215.267575)
			(xy 354.157027 -215.226169) (xy 354.192254 -215.189725) (xy 354.232643 -215.159101) (xy 354.277242 -215.135018)
			(xy 354.325001 -215.118043) (xy 354.349812 -215.112854) (xy 354.372672 -215.108536) (xy 354.57765 -214.753444)
			(xy 354.569776 -214.7316) (xy 354.561199 -214.705181) (xy 354.552 -214.650406) (xy 354.551488 -214.622634)
			(xy 354.551996 -214.596747) (xy 354.560095 -214.545609) (xy 354.576094 -214.496369) (xy 354.5996 -214.450237)
			(xy 354.630032 -214.40835) (xy 354.666642 -214.37174) (xy 354.708529 -214.341308) (xy 354.754661 -214.317802)
			(xy 354.803901 -214.301803) (xy 354.855039 -214.293704) (xy 354.906813 -214.293704) (xy 354.957951 -214.301803)
			(xy 355.007191 -214.317802) (xy 355.053323 -214.341308) (xy 355.09521 -214.37174) (xy 355.13182 -214.40835)
			(xy 355.162252 -214.450237) (xy 355.185758 -214.496369) (xy 355.201757 -214.545609) (xy 355.209856 -214.596747)
			(xy 355.210364 -214.622634) (xy 355.209941 -214.647971) (xy 355.202183 -214.698047) (xy 355.186854 -214.746347)
			(xy 355.164315 -214.791733) (xy 355.135098 -214.833136) (xy 355.09989 -214.869581) (xy 355.05952 -214.90021)
			(xy 355.014939 -214.924301) (xy 354.967197 -214.941288) (xy 354.942394 -214.946484) (xy 354.919534 -214.950802)
			(xy 354.714556 -215.305894) (xy 354.72243 -215.327738) (xy 354.731077 -215.354146) (xy 354.740397 -215.408922)
			(xy 354.740972 -215.436704) (xy 355.961188 -215.436704) (xy 355.961723 -215.411361) (xy 355.969493 -215.361274)
			(xy 355.984837 -215.312966) (xy 356.007392 -215.267575) (xy 356.036627 -215.226169) (xy 356.071854 -215.189725)
			(xy 356.112243 -215.159101) (xy 356.156842 -215.135018) (xy 356.204601 -215.118043) (xy 356.229412 -215.112854)
			(xy 356.252272 -215.108536) (xy 356.45725 -214.753444) (xy 356.449376 -214.7316) (xy 356.440799 -214.705181)
			(xy 356.4316 -214.650406) (xy 356.431088 -214.622634) (xy 356.431596 -214.596747) (xy 356.439695 -214.545609)
			(xy 356.455694 -214.496369) (xy 356.4792 -214.450237) (xy 356.509632 -214.40835) (xy 356.546242 -214.37174)
			(xy 356.588129 -214.341308) (xy 356.634261 -214.317802) (xy 356.683501 -214.301803) (xy 356.734639 -214.293704)
			(xy 356.786413 -214.293704) (xy 356.837551 -214.301803) (xy 356.886791 -214.317802) (xy 356.932923 -214.341308)
			(xy 356.97481 -214.37174) (xy 357.01142 -214.40835) (xy 357.041852 -214.450237) (xy 357.065358 -214.496369)
			(xy 357.081357 -214.545609) (xy 357.089456 -214.596747) (xy 357.089964 -214.622634) (xy 358.310688 -214.622634)
			(xy 358.311196 -214.596747) (xy 358.319295 -214.545609) (xy 358.335294 -214.496369) (xy 358.3588 -214.450237)
			(xy 358.389232 -214.40835) (xy 358.425842 -214.37174) (xy 358.467729 -214.341308) (xy 358.513861 -214.317802)
			(xy 358.563101 -214.301803) (xy 358.614239 -214.293704) (xy 358.666013 -214.293704) (xy 358.717151 -214.301803)
			(xy 358.766391 -214.317802) (xy 358.812523 -214.341308) (xy 358.85441 -214.37174) (xy 358.89102 -214.40835)
			(xy 358.921452 -214.450237) (xy 358.944958 -214.496369) (xy 358.960957 -214.545609) (xy 358.969056 -214.596747)
			(xy 358.969564 -214.622634) (xy 358.969564 -214.623142) (xy 358.968984 -214.650659) (xy 358.959791 -214.70492)
			(xy 358.951276 -214.731092) (xy 358.943656 -214.75319) (xy 359.148888 -215.108536) (xy 359.171748 -215.112854)
			(xy 359.196559 -215.118062) (xy 359.244336 -215.135013) (xy 359.288953 -215.15908) (xy 359.329358 -215.189696)
			(xy 359.364599 -215.226137) (xy 359.393844 -215.267545) (xy 359.416403 -215.312943) (xy 359.431745 -215.36126)
			(xy 359.439507 -215.411357) (xy 359.439972 -215.436704) (xy 359.439464 -215.462611) (xy 359.431358 -215.513788)
			(xy 359.415346 -215.563067) (xy 359.391823 -215.609234) (xy 359.361367 -215.651153) (xy 359.324729 -215.687791)
			(xy 359.28281 -215.718247) (xy 359.236643 -215.74177) (xy 359.187364 -215.757782) (xy 359.136187 -215.765888)
			(xy 359.084373 -215.765888) (xy 359.033196 -215.757782) (xy 358.983917 -215.74177) (xy 358.93775 -215.718247)
			(xy 358.895831 -215.687791) (xy 358.859193 -215.651153) (xy 358.828737 -215.609234) (xy 358.805214 -215.563067)
			(xy 358.789202 -215.513788) (xy 358.781096 -215.462611) (xy 358.780588 -215.436704) (xy 358.781184 -215.408987)
			(xy 358.790506 -215.35434) (xy 358.79913 -215.327992) (xy 358.80675 -215.306148) (xy 358.601772 -214.950802)
			(xy 358.578912 -214.946484) (xy 358.554096 -214.941291) (xy 358.506315 -214.924344) (xy 358.461694 -214.900279)
			(xy 358.421285 -214.869663) (xy 358.386043 -214.833219) (xy 358.356798 -214.791807) (xy 358.33424 -214.746405)
			(xy 358.318903 -214.698083) (xy 358.311148 -214.647983) (xy 358.310688 -214.622634) (xy 357.089964 -214.622634)
			(xy 357.089541 -214.647971) (xy 357.081783 -214.698047) (xy 357.066454 -214.746347) (xy 357.043915 -214.791733)
			(xy 357.014698 -214.833136) (xy 356.97949 -214.869581) (xy 356.93912 -214.90021) (xy 356.894539 -214.924301)
			(xy 356.846797 -214.941288) (xy 356.821994 -214.946484) (xy 356.799134 -214.950802) (xy 356.594156 -215.305894)
			(xy 356.60203 -215.327738) (xy 356.610677 -215.354146) (xy 356.619997 -215.408922) (xy 356.620572 -215.436704)
			(xy 356.620064 -215.462606) (xy 356.90152 -215.462606) (xy 356.90152 -215.410794) (xy 356.909625 -215.35962)
			(xy 356.925635 -215.310344) (xy 356.949157 -215.264178) (xy 356.97961 -215.222261) (xy 357.016246 -215.185623)
			(xy 357.058161 -215.155167) (xy 357.104325 -215.131643) (xy 357.1536 -215.11563) (xy 357.204774 -215.107522)
			(xy 357.23068 -215.107012) (xy 357.256191 -215.107502) (xy 357.306606 -215.11536) (xy 357.355207 -215.130891)
			(xy 357.400836 -215.153725) (xy 357.442402 -215.183316) (xy 357.478912 -215.218958) (xy 357.494586 -215.239092)
			(xy 357.906574 -215.239092) (xy 357.92226 -215.218967) (xy 357.958768 -215.183323) (xy 358.000331 -215.153729)
			(xy 358.045956 -215.130891) (xy 358.094556 -215.115355) (xy 358.144969 -215.107491) (xy 358.17048 -215.107012)
			(xy 358.196391 -215.107484) (xy 358.247575 -215.115588) (xy 358.296861 -215.131599) (xy 358.343035 -215.155124)
			(xy 358.38496 -215.185582) (xy 358.421605 -215.222224) (xy 358.452066 -215.264148) (xy 358.475593 -215.310321)
			(xy 358.491607 -215.359606) (xy 358.499714 -215.410789) (xy 358.499714 -215.462611) (xy 358.491607 -215.513794)
			(xy 358.475593 -215.563079) (xy 358.452066 -215.609252) (xy 358.421605 -215.651176) (xy 358.38496 -215.687818)
			(xy 358.343035 -215.718276) (xy 358.296861 -215.741801) (xy 358.247575 -215.757812) (xy 358.196391 -215.765916)
			(xy 358.17048 -215.766396) (xy 358.144968 -215.765932) (xy 358.094552 -215.758068) (xy 358.04595 -215.742532)
			(xy 358.000322 -215.719693) (xy 357.958757 -215.690098) (xy 357.922247 -215.654452) (xy 357.906574 -215.634316)
			(xy 357.494586 -215.634316) (xy 357.478925 -215.654461) (xy 357.442412 -215.690104) (xy 357.400844 -215.719696)
			(xy 357.355213 -215.74253) (xy 357.306609 -215.758062) (xy 357.256193 -215.76592) (xy 357.23068 -215.766396)
			(xy 357.204774 -215.765878) (xy 357.1536 -215.75777) (xy 357.104325 -215.741757) (xy 357.058161 -215.718233)
			(xy 357.016246 -215.687777) (xy 356.97961 -215.651139) (xy 356.949157 -215.609222) (xy 356.925635 -215.563056)
			(xy 356.909625 -215.51378) (xy 356.90152 -215.462606) (xy 356.620064 -215.462606) (xy 356.620064 -215.462611)
			(xy 356.611958 -215.513788) (xy 356.595946 -215.563067) (xy 356.572423 -215.609234) (xy 356.541967 -215.651153)
			(xy 356.505329 -215.687791) (xy 356.46341 -215.718247) (xy 356.417243 -215.74177) (xy 356.367964 -215.757782)
			(xy 356.316787 -215.765888) (xy 356.264973 -215.765888) (xy 356.213796 -215.757782) (xy 356.164517 -215.74177)
			(xy 356.11835 -215.718247) (xy 356.076431 -215.687791) (xy 356.039793 -215.651153) (xy 356.009337 -215.609234)
			(xy 355.985814 -215.563067) (xy 355.969802 -215.513788) (xy 355.961696 -215.462611) (xy 355.961188 -215.436704)
			(xy 354.740972 -215.436704) (xy 354.740464 -215.462611) (xy 354.732358 -215.513788) (xy 354.716346 -215.563067)
			(xy 354.692823 -215.609234) (xy 354.662367 -215.651153) (xy 354.625729 -215.687791) (xy 354.58381 -215.718247)
			(xy 354.537643 -215.74177) (xy 354.488364 -215.757782) (xy 354.437187 -215.765888) (xy 354.385373 -215.765888)
			(xy 354.334196 -215.757782) (xy 354.284917 -215.74177) (xy 354.23875 -215.718247) (xy 354.196831 -215.687791)
			(xy 354.160193 -215.651153) (xy 354.129737 -215.609234) (xy 354.106214 -215.563067) (xy 354.090202 -215.513788)
			(xy 354.082096 -215.462611) (xy 354.081588 -215.436704) (xy 352.861372 -215.436704) (xy 352.860864 -215.462611)
			(xy 352.852758 -215.513788) (xy 352.836746 -215.563067) (xy 352.813223 -215.609234) (xy 352.782767 -215.651153)
			(xy 352.746129 -215.687791) (xy 352.70421 -215.718247) (xy 352.658043 -215.74177) (xy 352.608764 -215.757782)
			(xy 352.557587 -215.765888) (xy 352.505773 -215.765888) (xy 352.454596 -215.757782) (xy 352.405317 -215.74177)
			(xy 352.35915 -215.718247) (xy 352.317231 -215.687791) (xy 352.280593 -215.651153) (xy 352.250137 -215.609234)
			(xy 352.226614 -215.563067) (xy 352.210602 -215.513788) (xy 352.202496 -215.462611) (xy 352.201988 -215.436704)
			(xy 350.981772 -215.436704) (xy 350.981264 -215.462611) (xy 350.973158 -215.513788) (xy 350.957146 -215.563067)
			(xy 350.933623 -215.609234) (xy 350.903167 -215.651153) (xy 350.866529 -215.687791) (xy 350.82461 -215.718247)
			(xy 350.778443 -215.74177) (xy 350.729164 -215.757782) (xy 350.677987 -215.765888) (xy 350.626173 -215.765888)
			(xy 350.574996 -215.757782) (xy 350.525717 -215.74177) (xy 350.47955 -215.718247) (xy 350.437631 -215.687791)
			(xy 350.400993 -215.651153) (xy 350.370537 -215.609234) (xy 350.347014 -215.563067) (xy 350.331002 -215.513788)
			(xy 350.322896 -215.462611) (xy 350.322388 -215.436704) (xy 349.102172 -215.436704) (xy 349.101664 -215.462611)
			(xy 349.093558 -215.513788) (xy 349.077546 -215.563067) (xy 349.054023 -215.609234) (xy 349.023567 -215.651153)
			(xy 348.986929 -215.687791) (xy 348.94501 -215.718247) (xy 348.898843 -215.74177) (xy 348.849564 -215.757782)
			(xy 348.798387 -215.765888) (xy 348.746573 -215.765888) (xy 348.695396 -215.757782) (xy 348.646117 -215.74177)
			(xy 348.59995 -215.718247) (xy 348.558031 -215.687791) (xy 348.521393 -215.651153) (xy 348.490937 -215.609234)
			(xy 348.467414 -215.563067) (xy 348.451402 -215.513788) (xy 348.443296 -215.462611) (xy 348.442788 -215.436704)
			(xy 347.222572 -215.436704) (xy 347.222064 -215.462611) (xy 347.213958 -215.513788) (xy 347.197946 -215.563067)
			(xy 347.174423 -215.609234) (xy 347.143967 -215.651153) (xy 347.107329 -215.687791) (xy 347.06541 -215.718247)
			(xy 347.019243 -215.74177) (xy 346.969964 -215.757782) (xy 346.918787 -215.765888) (xy 346.866973 -215.765888)
			(xy 346.815796 -215.757782) (xy 346.766517 -215.74177) (xy 346.72035 -215.718247) (xy 346.678431 -215.687791)
			(xy 346.641793 -215.651153) (xy 346.611337 -215.609234) (xy 346.587814 -215.563067) (xy 346.571802 -215.513788)
			(xy 346.563696 -215.462611) (xy 346.563188 -215.436704) (xy 345.342972 -215.436704) (xy 345.342464 -215.462611)
			(xy 345.334358 -215.513788) (xy 345.318346 -215.563067) (xy 345.294823 -215.609234) (xy 345.264367 -215.651153)
			(xy 345.227729 -215.687791) (xy 345.18581 -215.718247) (xy 345.139643 -215.74177) (xy 345.090364 -215.757782)
			(xy 345.039187 -215.765888) (xy 344.987373 -215.765888) (xy 344.936196 -215.757782) (xy 344.886917 -215.74177)
			(xy 344.84075 -215.718247) (xy 344.798831 -215.687791) (xy 344.762193 -215.651153) (xy 344.731737 -215.609234)
			(xy 344.708214 -215.563067) (xy 344.692202 -215.513788) (xy 344.684096 -215.462611) (xy 344.683588 -215.436704)
			(xy 343.463372 -215.436704) (xy 343.462864 -215.462611) (xy 343.454758 -215.513788) (xy 343.438746 -215.563067)
			(xy 343.415223 -215.609234) (xy 343.384767 -215.651153) (xy 343.348129 -215.687791) (xy 343.30621 -215.718247)
			(xy 343.260043 -215.74177) (xy 343.210764 -215.757782) (xy 343.159587 -215.765888) (xy 343.107773 -215.765888)
			(xy 343.056596 -215.757782) (xy 343.007317 -215.74177) (xy 342.96115 -215.718247) (xy 342.919231 -215.687791)
			(xy 342.882593 -215.651153) (xy 342.852137 -215.609234) (xy 342.828614 -215.563067) (xy 342.812602 -215.513788)
			(xy 342.804496 -215.462611) (xy 342.803988 -215.436704) (xy 341.583772 -215.436704) (xy 341.583264 -215.462611)
			(xy 341.575158 -215.513788) (xy 341.559146 -215.563067) (xy 341.535623 -215.609234) (xy 341.505167 -215.651153)
			(xy 341.468529 -215.687791) (xy 341.42661 -215.718247) (xy 341.380443 -215.74177) (xy 341.331164 -215.757782)
			(xy 341.279987 -215.765888) (xy 341.228173 -215.765888) (xy 341.176996 -215.757782) (xy 341.127717 -215.74177)
			(xy 341.08155 -215.718247) (xy 341.039631 -215.687791) (xy 341.002993 -215.651153) (xy 340.972537 -215.609234)
			(xy 340.949014 -215.563067) (xy 340.933002 -215.513788) (xy 340.924896 -215.462611) (xy 340.924388 -215.436704)
			(xy 339.704172 -215.436704) (xy 339.703664 -215.462611) (xy 339.695558 -215.513788) (xy 339.679546 -215.563067)
			(xy 339.656023 -215.609234) (xy 339.625567 -215.651153) (xy 339.588929 -215.687791) (xy 339.54701 -215.718247)
			(xy 339.500843 -215.74177) (xy 339.451564 -215.757782) (xy 339.400387 -215.765888) (xy 339.348573 -215.765888)
			(xy 339.297396 -215.757782) (xy 339.248117 -215.74177) (xy 339.20195 -215.718247) (xy 339.160031 -215.687791)
			(xy 339.123393 -215.651153) (xy 339.092937 -215.609234) (xy 339.069414 -215.563067) (xy 339.053402 -215.513788)
			(xy 339.045296 -215.462611) (xy 339.044788 -215.436704) (xy 337.824572 -215.436704) (xy 337.824064 -215.462611)
			(xy 337.815958 -215.513788) (xy 337.799946 -215.563067) (xy 337.776423 -215.609234) (xy 337.745967 -215.651153)
			(xy 337.709329 -215.687791) (xy 337.66741 -215.718247) (xy 337.621243 -215.74177) (xy 337.571964 -215.757782)
			(xy 337.520787 -215.765888) (xy 337.468973 -215.765888) (xy 337.417796 -215.757782) (xy 337.368517 -215.74177)
			(xy 337.32235 -215.718247) (xy 337.280431 -215.687791) (xy 337.243793 -215.651153) (xy 337.213337 -215.609234)
			(xy 337.189814 -215.563067) (xy 337.173802 -215.513788) (xy 337.165696 -215.462611) (xy 337.165188 -215.436704)
			(xy 336.884772 -215.436704) (xy 336.884181 -215.464421) (xy 336.874856 -215.519068) (xy 336.86623 -215.545416)
			(xy 336.858356 -215.567514) (xy 337.063334 -215.922352) (xy 337.086194 -215.92667) (xy 337.110997 -215.931858)
			(xy 337.158737 -215.948846) (xy 337.203315 -215.972939) (xy 337.243681 -216.00357) (xy 337.278884 -216.040017)
			(xy 337.308096 -216.081421) (xy 337.330629 -216.126808) (xy 337.345951 -216.175108) (xy 337.353702 -216.225184)
			(xy 337.354164 -216.25052) (xy 337.353656 -216.276407) (xy 337.345557 -216.327545) (xy 337.329558 -216.376785)
			(xy 337.306052 -216.422917) (xy 337.27562 -216.464804) (xy 337.23901 -216.501414) (xy 337.197123 -216.531846)
			(xy 337.150991 -216.555352) (xy 337.101751 -216.571351) (xy 337.050613 -216.57945) (xy 336.998839 -216.57945)
			(xy 336.947701 -216.571351) (xy 336.898461 -216.555352) (xy 336.852329 -216.531846) (xy 336.810442 -216.501414)
			(xy 336.773832 -216.464804) (xy 336.7434 -216.422917) (xy 336.719894 -216.376785) (xy 336.703895 -216.327545)
			(xy 336.695796 -216.276407) (xy 336.695288 -216.25052) (xy 336.695823 -216.222812) (xy 336.705015 -216.168165)
			(xy 336.713576 -216.141808) (xy 336.72145 -216.11971) (xy 336.516472 -215.764872) (xy 336.493612 -215.760554)
			(xy 336.46879 -215.755389) (xy 336.421007 -215.73844) (xy 336.376384 -215.714372) (xy 336.335974 -215.683753)
			(xy 336.300731 -215.647305) (xy 336.271487 -215.60589) (xy 336.248932 -215.560483) (xy 336.233597 -215.512158)
			(xy 336.225846 -215.462054) (xy 336.225388 -215.436704) (xy 135.934704 -215.436704) (xy 135.934196 -215.462611)
			(xy 135.92609 -215.513788) (xy 135.910078 -215.563067) (xy 135.886555 -215.609234) (xy 135.856099 -215.651153)
			(xy 135.819461 -215.687791) (xy 135.777542 -215.718247) (xy 135.731375 -215.74177) (xy 135.682096 -215.757782)
			(xy 135.630919 -215.765888) (xy 135.579105 -215.765888) (xy 135.527928 -215.757782) (xy 135.478649 -215.74177)
			(xy 135.432482 -215.718247) (xy 135.390563 -215.687791) (xy 135.353925 -215.651153) (xy 135.323469 -215.609234)
			(xy 135.299946 -215.563067) (xy 135.283934 -215.513788) (xy 135.275828 -215.462611) (xy 135.27532 -215.436704)
			(xy 135.27603 -215.405863) (xy 135.287538 -215.345263) (xy 135.29818 -215.316308) (xy 135.306816 -215.294464)
			(xy 135.084058 -214.872824) (xy 135.061452 -214.867744) (xy 135.037516 -214.861817) (xy 134.991624 -214.843773)
			(xy 134.948934 -214.819093) (xy 134.910397 -214.788329) (xy 134.876873 -214.752166) (xy 134.849112 -214.711412)
			(xy 134.827733 -214.666976) (xy 134.813212 -214.619852) (xy 134.805875 -214.57109) (xy 134.80542 -214.546434)
			(xy 133.57622 -214.546434) (xy 133.584188 -214.596747) (xy 133.584696 -214.622634) (xy 133.584247 -214.64797)
			(xy 133.57649 -214.698044) (xy 133.561163 -214.746341) (xy 133.538627 -214.791726) (xy 133.509412 -214.833128)
			(xy 133.474208 -214.869572) (xy 133.433842 -214.900202) (xy 133.389265 -214.924296) (xy 133.341527 -214.941286)
			(xy 133.316726 -214.946484) (xy 133.293866 -214.950802) (xy 133.088888 -215.305894) (xy 133.096762 -215.327738)
			(xy 133.10541 -215.354146) (xy 133.114729 -215.408922) (xy 133.115304 -215.436704) (xy 133.114796 -215.46261)
			(xy 133.396194 -215.46261) (xy 133.396194 -215.41079) (xy 133.4043 -215.359609) (xy 133.420313 -215.310326)
			(xy 133.44384 -215.264155) (xy 133.474299 -215.222232) (xy 133.510941 -215.185591) (xy 133.552865 -215.155133)
			(xy 133.599037 -215.131609) (xy 133.648321 -215.115597) (xy 133.699502 -215.107493) (xy 133.725412 -215.107012)
			(xy 133.750924 -215.107479) (xy 133.80134 -215.115342) (xy 133.849942 -215.130878) (xy 133.89557 -215.153716)
			(xy 133.937135 -215.183311) (xy 133.973645 -215.218956) (xy 133.989318 -215.239092) (xy 134.401306 -215.239092)
			(xy 134.416974 -215.218952) (xy 134.453485 -215.183309) (xy 134.495052 -215.153716) (xy 134.540681 -215.130881)
			(xy 134.589284 -215.115348) (xy 134.6397 -215.107489) (xy 134.665212 -215.107012) (xy 134.691119 -215.107513)
			(xy 134.742295 -215.11562) (xy 134.791573 -215.131633) (xy 134.837739 -215.155158) (xy 134.879656 -215.185614)
			(xy 134.916294 -215.222253) (xy 134.946749 -215.264172) (xy 134.970271 -215.310339) (xy 134.986282 -215.359617)
			(xy 134.994388 -215.410793) (xy 134.994388 -215.462607) (xy 134.986282 -215.513783) (xy 134.970271 -215.563061)
			(xy 134.946749 -215.609228) (xy 134.916294 -215.651147) (xy 134.879656 -215.687786) (xy 134.837739 -215.718242)
			(xy 134.791573 -215.741767) (xy 134.742295 -215.75778) (xy 134.691119 -215.765887) (xy 134.665212 -215.766396)
			(xy 134.6397 -215.765908) (xy 134.589286 -215.758049) (xy 134.540685 -215.742517) (xy 134.495056 -215.719683)
			(xy 134.453491 -215.690092) (xy 134.41698 -215.65445) (xy 134.401306 -215.634316) (xy 133.989318 -215.634316)
			(xy 133.973638 -215.654446) (xy 133.937129 -215.69009) (xy 133.895565 -215.719683) (xy 133.849938 -215.74252)
			(xy 133.801337 -215.758055) (xy 133.750924 -215.765918) (xy 133.725412 -215.766396) (xy 133.699502 -215.765907)
			(xy 133.648321 -215.757803) (xy 133.599037 -215.741791) (xy 133.552865 -215.718267) (xy 133.510941 -215.687809)
			(xy 133.474299 -215.651168) (xy 133.44384 -215.609245) (xy 133.420313 -215.563074) (xy 133.4043 -215.513791)
			(xy 133.396194 -215.46261) (xy 133.114796 -215.46261) (xy 133.114796 -215.462611) (xy 133.10669 -215.513788)
			(xy 133.090678 -215.563067) (xy 133.067155 -215.609234) (xy 133.036699 -215.651153) (xy 133.000061 -215.687791)
			(xy 132.958142 -215.718247) (xy 132.911975 -215.74177) (xy 132.862696 -215.757782) (xy 132.811519 -215.765888)
			(xy 132.759705 -215.765888) (xy 132.708528 -215.757782) (xy 132.659249 -215.74177) (xy 132.613082 -215.718247)
			(xy 132.571163 -215.687791) (xy 132.534525 -215.651153) (xy 132.504069 -215.609234) (xy 132.480546 -215.563067)
			(xy 132.464534 -215.513788) (xy 132.456428 -215.462611) (xy 132.45592 -215.436704) (xy 131.235704 -215.436704)
			(xy 131.235196 -215.462611) (xy 131.22709 -215.513788) (xy 131.211078 -215.563067) (xy 131.187555 -215.609234)
			(xy 131.157099 -215.651153) (xy 131.120461 -215.687791) (xy 131.078542 -215.718247) (xy 131.032375 -215.74177)
			(xy 130.983096 -215.757782) (xy 130.931919 -215.765888) (xy 130.880105 -215.765888) (xy 130.828928 -215.757782)
			(xy 130.779649 -215.74177) (xy 130.733482 -215.718247) (xy 130.691563 -215.687791) (xy 130.654925 -215.651153)
			(xy 130.624469 -215.609234) (xy 130.600946 -215.563067) (xy 130.584934 -215.513788) (xy 130.576828 -215.462611)
			(xy 130.57632 -215.436704) (xy 129.356104 -215.436704) (xy 129.355596 -215.462611) (xy 129.34749 -215.513788)
			(xy 129.331478 -215.563067) (xy 129.307955 -215.609234) (xy 129.277499 -215.651153) (xy 129.240861 -215.687791)
			(xy 129.198942 -215.718247) (xy 129.152775 -215.74177) (xy 129.103496 -215.757782) (xy 129.052319 -215.765888)
			(xy 129.000505 -215.765888) (xy 128.949328 -215.757782) (xy 128.900049 -215.74177) (xy 128.853882 -215.718247)
			(xy 128.811963 -215.687791) (xy 128.775325 -215.651153) (xy 128.744869 -215.609234) (xy 128.721346 -215.563067)
			(xy 128.705334 -215.513788) (xy 128.697228 -215.462611) (xy 128.69672 -215.436704) (xy 127.476504 -215.436704)
			(xy 127.475996 -215.462611) (xy 127.46789 -215.513788) (xy 127.451878 -215.563067) (xy 127.428355 -215.609234)
			(xy 127.397899 -215.651153) (xy 127.361261 -215.687791) (xy 127.319342 -215.718247) (xy 127.273175 -215.74177)
			(xy 127.223896 -215.757782) (xy 127.172719 -215.765888) (xy 127.120905 -215.765888) (xy 127.069728 -215.757782)
			(xy 127.020449 -215.74177) (xy 126.974282 -215.718247) (xy 126.932363 -215.687791) (xy 126.895725 -215.651153)
			(xy 126.865269 -215.609234) (xy 126.841746 -215.563067) (xy 126.825734 -215.513788) (xy 126.817628 -215.462611)
			(xy 126.81712 -215.436704) (xy 125.596904 -215.436704) (xy 125.596396 -215.462611) (xy 125.58829 -215.513788)
			(xy 125.572278 -215.563067) (xy 125.548755 -215.609234) (xy 125.518299 -215.651153) (xy 125.481661 -215.687791)
			(xy 125.439742 -215.718247) (xy 125.393575 -215.74177) (xy 125.344296 -215.757782) (xy 125.293119 -215.765888)
			(xy 125.241305 -215.765888) (xy 125.190128 -215.757782) (xy 125.140849 -215.74177) (xy 125.094682 -215.718247)
			(xy 125.052763 -215.687791) (xy 125.016125 -215.651153) (xy 124.985669 -215.609234) (xy 124.962146 -215.563067)
			(xy 124.946134 -215.513788) (xy 124.938028 -215.462611) (xy 124.93752 -215.436704) (xy 123.717304 -215.436704)
			(xy 123.716796 -215.462611) (xy 123.70869 -215.513788) (xy 123.692678 -215.563067) (xy 123.669155 -215.609234)
			(xy 123.638699 -215.651153) (xy 123.602061 -215.687791) (xy 123.560142 -215.718247) (xy 123.513975 -215.74177)
			(xy 123.464696 -215.757782) (xy 123.413519 -215.765888) (xy 123.361705 -215.765888) (xy 123.310528 -215.757782)
			(xy 123.261249 -215.74177) (xy 123.215082 -215.718247) (xy 123.173163 -215.687791) (xy 123.136525 -215.651153)
			(xy 123.106069 -215.609234) (xy 123.082546 -215.563067) (xy 123.066534 -215.513788) (xy 123.058428 -215.462611)
			(xy 123.05792 -215.436704) (xy 121.837704 -215.436704) (xy 121.837196 -215.462611) (xy 121.82909 -215.513788)
			(xy 121.813078 -215.563067) (xy 121.789555 -215.609234) (xy 121.759099 -215.651153) (xy 121.722461 -215.687791)
			(xy 121.680542 -215.718247) (xy 121.634375 -215.74177) (xy 121.585096 -215.757782) (xy 121.533919 -215.765888)
			(xy 121.482105 -215.765888) (xy 121.430928 -215.757782) (xy 121.381649 -215.74177) (xy 121.335482 -215.718247)
			(xy 121.293563 -215.687791) (xy 121.256925 -215.651153) (xy 121.226469 -215.609234) (xy 121.202946 -215.563067)
			(xy 121.186934 -215.513788) (xy 121.178828 -215.462611) (xy 121.17832 -215.436704) (xy 119.958104 -215.436704)
			(xy 119.957596 -215.462611) (xy 119.94949 -215.513788) (xy 119.933478 -215.563067) (xy 119.909955 -215.609234)
			(xy 119.879499 -215.651153) (xy 119.842861 -215.687791) (xy 119.800942 -215.718247) (xy 119.754775 -215.74177)
			(xy 119.705496 -215.757782) (xy 119.654319 -215.765888) (xy 119.602505 -215.765888) (xy 119.551328 -215.757782)
			(xy 119.502049 -215.74177) (xy 119.455882 -215.718247) (xy 119.413963 -215.687791) (xy 119.377325 -215.651153)
			(xy 119.346869 -215.609234) (xy 119.323346 -215.563067) (xy 119.307334 -215.513788) (xy 119.299228 -215.462611)
			(xy 119.29872 -215.436704) (xy 118.078504 -215.436704) (xy 118.077996 -215.462611) (xy 118.06989 -215.513788)
			(xy 118.053878 -215.563067) (xy 118.030355 -215.609234) (xy 117.999899 -215.651153) (xy 117.963261 -215.687791)
			(xy 117.921342 -215.718247) (xy 117.875175 -215.74177) (xy 117.825896 -215.757782) (xy 117.774719 -215.765888)
			(xy 117.722905 -215.765888) (xy 117.671728 -215.757782) (xy 117.622449 -215.74177) (xy 117.576282 -215.718247)
			(xy 117.534363 -215.687791) (xy 117.497725 -215.651153) (xy 117.467269 -215.609234) (xy 117.443746 -215.563067)
			(xy 117.427734 -215.513788) (xy 117.419628 -215.462611) (xy 117.41912 -215.436704) (xy 116.198904 -215.436704)
			(xy 116.198396 -215.462611) (xy 116.19029 -215.513788) (xy 116.174278 -215.563067) (xy 116.150755 -215.609234)
			(xy 116.120299 -215.651153) (xy 116.083661 -215.687791) (xy 116.041742 -215.718247) (xy 115.995575 -215.74177)
			(xy 115.946296 -215.757782) (xy 115.895119 -215.765888) (xy 115.843305 -215.765888) (xy 115.792128 -215.757782)
			(xy 115.742849 -215.74177) (xy 115.696682 -215.718247) (xy 115.654763 -215.687791) (xy 115.618125 -215.651153)
			(xy 115.587669 -215.609234) (xy 115.564146 -215.563067) (xy 115.548134 -215.513788) (xy 115.540028 -215.462611)
			(xy 115.53952 -215.436704) (xy 114.319304 -215.436704) (xy 114.318796 -215.462611) (xy 114.31069 -215.513788)
			(xy 114.294678 -215.563067) (xy 114.271155 -215.609234) (xy 114.240699 -215.651153) (xy 114.204061 -215.687791)
			(xy 114.162142 -215.718247) (xy 114.115975 -215.74177) (xy 114.066696 -215.757782) (xy 114.015519 -215.765888)
			(xy 113.963705 -215.765888) (xy 113.912528 -215.757782) (xy 113.863249 -215.74177) (xy 113.817082 -215.718247)
			(xy 113.775163 -215.687791) (xy 113.738525 -215.651153) (xy 113.708069 -215.609234) (xy 113.684546 -215.563067)
			(xy 113.668534 -215.513788) (xy 113.660428 -215.462611) (xy 113.65992 -215.436704) (xy 111.499904 -215.436704)
			(xy 111.499396 -215.462611) (xy 111.49129 -215.513788) (xy 111.475278 -215.563067) (xy 111.451755 -215.609234)
			(xy 111.421299 -215.651153) (xy 111.384661 -215.687791) (xy 111.342742 -215.718247) (xy 111.296575 -215.74177)
			(xy 111.247296 -215.757782) (xy 111.196119 -215.765888) (xy 111.144305 -215.765888) (xy 111.093128 -215.757782)
			(xy 111.043849 -215.74177) (xy 110.997682 -215.718247) (xy 110.955763 -215.687791) (xy 110.919125 -215.651153)
			(xy 110.888669 -215.609234) (xy 110.865146 -215.563067) (xy 110.849134 -215.513788) (xy 110.841028 -215.462611)
			(xy 110.84052 -215.436704) (xy 110.840955 -215.413764) (xy 110.847378 -215.368334) (xy 110.860018 -215.324227)
			(xy 110.868968 -215.3031) (xy 110.878874 -215.280494) (xy 110.665006 -214.87511) (xy 110.640876 -214.870538)
			(xy 110.615954 -214.86544) (xy 110.567941 -214.848641) (xy 110.523081 -214.824663) (xy 110.482438 -214.794075)
			(xy 110.44698 -214.757604) (xy 110.417549 -214.716116) (xy 110.394843 -214.670598) (xy 110.379403 -214.622131)
			(xy 110.371595 -214.571867) (xy 110.371128 -214.546434) (xy 109.14142 -214.546434) (xy 109.149388 -214.596747)
			(xy 109.149896 -214.622634) (xy 109.149447 -214.64797) (xy 109.14169 -214.698044) (xy 109.126363 -214.746341)
			(xy 109.103827 -214.791726) (xy 109.074612 -214.833128) (xy 109.039408 -214.869572) (xy 108.999042 -214.900202)
			(xy 108.954465 -214.924296) (xy 108.906727 -214.941286) (xy 108.881926 -214.946484) (xy 108.859066 -214.950802)
			(xy 108.654088 -215.305894) (xy 108.661962 -215.327738) (xy 108.67061 -215.354146) (xy 108.679929 -215.408922)
			(xy 108.680504 -215.436704) (xy 108.679996 -215.46261) (xy 108.961394 -215.46261) (xy 108.961394 -215.41079)
			(xy 108.9695 -215.359609) (xy 108.985513 -215.310326) (xy 109.00904 -215.264155) (xy 109.039499 -215.222232)
			(xy 109.076141 -215.185591) (xy 109.118065 -215.155133) (xy 109.164237 -215.131609) (xy 109.213521 -215.115597)
			(xy 109.264702 -215.107493) (xy 109.290612 -215.107012) (xy 109.316124 -215.107479) (xy 109.36654 -215.115342)
			(xy 109.415142 -215.130878) (xy 109.46077 -215.153716) (xy 109.502335 -215.183311) (xy 109.538845 -215.218956)
			(xy 109.554518 -215.239092) (xy 109.966506 -215.239092) (xy 109.982174 -215.218952) (xy 110.018685 -215.183309)
			(xy 110.060252 -215.153716) (xy 110.105881 -215.130881) (xy 110.154484 -215.115348) (xy 110.2049 -215.107489)
			(xy 110.230412 -215.107012) (xy 110.256319 -215.107513) (xy 110.307495 -215.11562) (xy 110.356773 -215.131633)
			(xy 110.402939 -215.155158) (xy 110.444856 -215.185614) (xy 110.481494 -215.222253) (xy 110.511949 -215.264172)
			(xy 110.535471 -215.310339) (xy 110.551482 -215.359617) (xy 110.559588 -215.410793) (xy 110.559588 -215.462607)
			(xy 110.551482 -215.513783) (xy 110.535471 -215.563061) (xy 110.511949 -215.609228) (xy 110.481494 -215.651147)
			(xy 110.444856 -215.687786) (xy 110.402939 -215.718242) (xy 110.356773 -215.741767) (xy 110.307495 -215.75778)
			(xy 110.256319 -215.765887) (xy 110.230412 -215.766396) (xy 110.2049 -215.765908) (xy 110.154486 -215.758049)
			(xy 110.105885 -215.742517) (xy 110.060256 -215.719683) (xy 110.018691 -215.690092) (xy 109.98218 -215.65445)
			(xy 109.966506 -215.634316) (xy 109.554518 -215.634316) (xy 109.538838 -215.654446) (xy 109.502329 -215.69009)
			(xy 109.460765 -215.719683) (xy 109.415138 -215.74252) (xy 109.366537 -215.758055) (xy 109.316124 -215.765918)
			(xy 109.290612 -215.766396) (xy 109.264702 -215.765907) (xy 109.213521 -215.757803) (xy 109.164237 -215.741791)
			(xy 109.118065 -215.718267) (xy 109.076141 -215.687809) (xy 109.039499 -215.651168) (xy 109.00904 -215.609245)
			(xy 108.985513 -215.563074) (xy 108.9695 -215.513791) (xy 108.961394 -215.46261) (xy 108.679996 -215.46261)
			(xy 108.679996 -215.462611) (xy 108.67189 -215.513788) (xy 108.655878 -215.563067) (xy 108.632355 -215.609234)
			(xy 108.601899 -215.651153) (xy 108.565261 -215.687791) (xy 108.523342 -215.718247) (xy 108.477175 -215.74177)
			(xy 108.427896 -215.757782) (xy 108.376719 -215.765888) (xy 108.324905 -215.765888) (xy 108.273728 -215.757782)
			(xy 108.224449 -215.74177) (xy 108.178282 -215.718247) (xy 108.136363 -215.687791) (xy 108.099725 -215.651153)
			(xy 108.069269 -215.609234) (xy 108.045746 -215.563067) (xy 108.029734 -215.513788) (xy 108.021628 -215.462611)
			(xy 108.02112 -215.436704) (xy 106.800904 -215.436704) (xy 106.800396 -215.462611) (xy 106.79229 -215.513788)
			(xy 106.776278 -215.563067) (xy 106.752755 -215.609234) (xy 106.722299 -215.651153) (xy 106.685661 -215.687791)
			(xy 106.643742 -215.718247) (xy 106.597575 -215.74177) (xy 106.548296 -215.757782) (xy 106.497119 -215.765888)
			(xy 106.445305 -215.765888) (xy 106.394128 -215.757782) (xy 106.344849 -215.74177) (xy 106.298682 -215.718247)
			(xy 106.256763 -215.687791) (xy 106.220125 -215.651153) (xy 106.189669 -215.609234) (xy 106.166146 -215.563067)
			(xy 106.150134 -215.513788) (xy 106.142028 -215.462611) (xy 106.14152 -215.436704) (xy 104.921304 -215.436704)
			(xy 104.920796 -215.462611) (xy 104.91269 -215.513788) (xy 104.896678 -215.563067) (xy 104.873155 -215.609234)
			(xy 104.842699 -215.651153) (xy 104.806061 -215.687791) (xy 104.764142 -215.718247) (xy 104.717975 -215.74177)
			(xy 104.668696 -215.757782) (xy 104.617519 -215.765888) (xy 104.565705 -215.765888) (xy 104.514528 -215.757782)
			(xy 104.465249 -215.74177) (xy 104.419082 -215.718247) (xy 104.377163 -215.687791) (xy 104.340525 -215.651153)
			(xy 104.310069 -215.609234) (xy 104.286546 -215.563067) (xy 104.270534 -215.513788) (xy 104.262428 -215.462611)
			(xy 104.26192 -215.436704) (xy 103.041704 -215.436704) (xy 103.041196 -215.462611) (xy 103.03309 -215.513788)
			(xy 103.017078 -215.563067) (xy 102.993555 -215.609234) (xy 102.963099 -215.651153) (xy 102.926461 -215.687791)
			(xy 102.884542 -215.718247) (xy 102.838375 -215.74177) (xy 102.789096 -215.757782) (xy 102.737919 -215.765888)
			(xy 102.686105 -215.765888) (xy 102.634928 -215.757782) (xy 102.585649 -215.74177) (xy 102.539482 -215.718247)
			(xy 102.497563 -215.687791) (xy 102.460925 -215.651153) (xy 102.430469 -215.609234) (xy 102.406946 -215.563067)
			(xy 102.390934 -215.513788) (xy 102.382828 -215.462611) (xy 102.38232 -215.436704) (xy 101.162104 -215.436704)
			(xy 101.161596 -215.462611) (xy 101.15349 -215.513788) (xy 101.137478 -215.563067) (xy 101.113955 -215.609234)
			(xy 101.083499 -215.651153) (xy 101.046861 -215.687791) (xy 101.004942 -215.718247) (xy 100.958775 -215.74177)
			(xy 100.909496 -215.757782) (xy 100.858319 -215.765888) (xy 100.806505 -215.765888) (xy 100.755328 -215.757782)
			(xy 100.706049 -215.74177) (xy 100.659882 -215.718247) (xy 100.617963 -215.687791) (xy 100.581325 -215.651153)
			(xy 100.550869 -215.609234) (xy 100.527346 -215.563067) (xy 100.511334 -215.513788) (xy 100.503228 -215.462611)
			(xy 100.50272 -215.436704) (xy 99.282504 -215.436704) (xy 99.281996 -215.462611) (xy 99.27389 -215.513788)
			(xy 99.257878 -215.563067) (xy 99.234355 -215.609234) (xy 99.203899 -215.651153) (xy 99.167261 -215.687791)
			(xy 99.125342 -215.718247) (xy 99.079175 -215.74177) (xy 99.029896 -215.757782) (xy 98.978719 -215.765888)
			(xy 98.926905 -215.765888) (xy 98.875728 -215.757782) (xy 98.826449 -215.74177) (xy 98.780282 -215.718247)
			(xy 98.738363 -215.687791) (xy 98.701725 -215.651153) (xy 98.671269 -215.609234) (xy 98.647746 -215.563067)
			(xy 98.631734 -215.513788) (xy 98.623628 -215.462611) (xy 98.62312 -215.436704) (xy 97.402904 -215.436704)
			(xy 97.402396 -215.462611) (xy 97.39429 -215.513788) (xy 97.378278 -215.563067) (xy 97.354755 -215.609234)
			(xy 97.324299 -215.651153) (xy 97.287661 -215.687791) (xy 97.245742 -215.718247) (xy 97.199575 -215.74177)
			(xy 97.150296 -215.757782) (xy 97.099119 -215.765888) (xy 97.047305 -215.765888) (xy 96.996128 -215.757782)
			(xy 96.946849 -215.74177) (xy 96.900682 -215.718247) (xy 96.858763 -215.687791) (xy 96.822125 -215.651153)
			(xy 96.791669 -215.609234) (xy 96.768146 -215.563067) (xy 96.752134 -215.513788) (xy 96.744028 -215.462611)
			(xy 96.74352 -215.436704) (xy 95.523304 -215.436704) (xy 95.522796 -215.462611) (xy 95.51469 -215.513788)
			(xy 95.498678 -215.563067) (xy 95.475155 -215.609234) (xy 95.444699 -215.651153) (xy 95.408061 -215.687791)
			(xy 95.366142 -215.718247) (xy 95.319975 -215.74177) (xy 95.270696 -215.757782) (xy 95.219519 -215.765888)
			(xy 95.167705 -215.765888) (xy 95.116528 -215.757782) (xy 95.067249 -215.74177) (xy 95.021082 -215.718247)
			(xy 94.979163 -215.687791) (xy 94.942525 -215.651153) (xy 94.912069 -215.609234) (xy 94.888546 -215.563067)
			(xy 94.872534 -215.513788) (xy 94.864428 -215.462611) (xy 94.86392 -215.436704) (xy 93.643704 -215.436704)
			(xy 93.643196 -215.462611) (xy 93.63509 -215.513788) (xy 93.619078 -215.563067) (xy 93.595555 -215.609234)
			(xy 93.565099 -215.651153) (xy 93.528461 -215.687791) (xy 93.486542 -215.718247) (xy 93.440375 -215.74177)
			(xy 93.391096 -215.757782) (xy 93.339919 -215.765888) (xy 93.288105 -215.765888) (xy 93.236928 -215.757782)
			(xy 93.187649 -215.74177) (xy 93.141482 -215.718247) (xy 93.099563 -215.687791) (xy 93.062925 -215.651153)
			(xy 93.032469 -215.609234) (xy 93.008946 -215.563067) (xy 92.992934 -215.513788) (xy 92.984828 -215.462611)
			(xy 92.98432 -215.436704) (xy 91.764104 -215.436704) (xy 91.763596 -215.462611) (xy 91.75549 -215.513788)
			(xy 91.739478 -215.563067) (xy 91.715955 -215.609234) (xy 91.685499 -215.651153) (xy 91.648861 -215.687791)
			(xy 91.606942 -215.718247) (xy 91.560775 -215.74177) (xy 91.511496 -215.757782) (xy 91.460319 -215.765888)
			(xy 91.408505 -215.765888) (xy 91.357328 -215.757782) (xy 91.308049 -215.74177) (xy 91.261882 -215.718247)
			(xy 91.219963 -215.687791) (xy 91.183325 -215.651153) (xy 91.152869 -215.609234) (xy 91.129346 -215.563067)
			(xy 91.113334 -215.513788) (xy 91.105228 -215.462611) (xy 91.10472 -215.436704) (xy 89.884504 -215.436704)
			(xy 89.883996 -215.462611) (xy 89.87589 -215.513788) (xy 89.859878 -215.563067) (xy 89.836355 -215.609234)
			(xy 89.805899 -215.651153) (xy 89.769261 -215.687791) (xy 89.727342 -215.718247) (xy 89.681175 -215.74177)
			(xy 89.631896 -215.757782) (xy 89.580719 -215.765888) (xy 89.528905 -215.765888) (xy 89.477728 -215.757782)
			(xy 89.428449 -215.74177) (xy 89.382282 -215.718247) (xy 89.340363 -215.687791) (xy 89.303725 -215.651153)
			(xy 89.273269 -215.609234) (xy 89.249746 -215.563067) (xy 89.233734 -215.513788) (xy 89.225628 -215.462611)
			(xy 89.22512 -215.436704) (xy 88.944704 -215.436704) (xy 88.944111 -215.464421) (xy 88.934787 -215.519068)
			(xy 88.926162 -215.545416) (xy 88.918288 -215.567514) (xy 89.123266 -215.922352) (xy 89.146126 -215.92667)
			(xy 89.170934 -215.931835) (xy 89.218674 -215.948828) (xy 89.263251 -215.972925) (xy 89.303616 -216.003559)
			(xy 89.338819 -216.040009) (xy 89.36803 -216.081415) (xy 89.390562 -216.126804) (xy 89.405883 -216.175106)
			(xy 89.413634 -216.225183) (xy 89.414096 -216.25052) (xy 89.413588 -216.276407) (xy 89.405489 -216.327545)
			(xy 89.38949 -216.376785) (xy 89.365984 -216.422917) (xy 89.335552 -216.464804) (xy 89.298942 -216.501414)
			(xy 89.257055 -216.531846) (xy 89.210923 -216.555352) (xy 89.161683 -216.571351) (xy 89.110545 -216.57945)
			(xy 89.058771 -216.57945) (xy 89.007633 -216.571351) (xy 88.958393 -216.555352) (xy 88.912261 -216.531846)
			(xy 88.870374 -216.501414) (xy 88.833764 -216.464804) (xy 88.803332 -216.422917) (xy 88.779826 -216.376785)
			(xy 88.763827 -216.327545) (xy 88.755728 -216.276407) (xy 88.75522 -216.25052) (xy 88.755754 -216.222812)
			(xy 88.764946 -216.168165) (xy 88.773508 -216.141808) (xy 88.781382 -216.11971) (xy 88.576404 -215.764872)
			(xy 88.553544 -215.760554) (xy 88.528711 -215.755439) (xy 88.480928 -215.73848) (xy 88.436306 -215.714403)
			(xy 88.395898 -215.683776) (xy 88.360658 -215.647323) (xy 88.331415 -215.605902) (xy 88.308862 -215.560492)
			(xy 88.293529 -215.512163) (xy 88.285778 -215.462056) (xy 88.28532 -215.436704) (xy 2.509012 -215.436704)
			(xy 2.509012 -217.878406) (xy 88.755728 -217.878406) (xy 88.756236 -217.852519) (xy 88.764335 -217.801381)
			(xy 88.780334 -217.752141) (xy 88.80384 -217.706009) (xy 88.834272 -217.664122) (xy 88.870882 -217.627512)
			(xy 88.912769 -217.59708) (xy 88.958901 -217.573574) (xy 89.008141 -217.557575) (xy 89.059279 -217.549476)
			(xy 89.111053 -217.549476) (xy 89.162191 -217.557575) (xy 89.211431 -217.573574) (xy 89.257563 -217.59708)
			(xy 89.29945 -217.627512) (xy 89.33606 -217.664122) (xy 89.366492 -217.706009) (xy 89.389998 -217.752141)
			(xy 89.405997 -217.801381) (xy 89.414096 -217.852519) (xy 89.414604 -217.878406) (xy 89.695528 -217.878406)
			(xy 89.695994 -217.853071) (xy 89.703746 -217.802996) (xy 89.719069 -217.754698) (xy 89.741602 -217.709313)
			(xy 89.770814 -217.66791) (xy 89.806017 -217.631464) (xy 89.846382 -217.600835) (xy 89.890959 -217.576742)
			(xy 89.938697 -217.559754) (xy 89.963498 -217.554556) (xy 89.986358 -217.550238) (xy 90.191336 -217.195146)
			(xy 90.183462 -217.173302) (xy 90.174824 -217.146891) (xy 90.165499 -217.092117) (xy 90.16492 -217.064336)
			(xy 90.165428 -217.038429) (xy 90.173534 -216.987252) (xy 90.189546 -216.937973) (xy 90.213069 -216.891806)
			(xy 90.243525 -216.849887) (xy 90.280163 -216.813249) (xy 90.322082 -216.782793) (xy 90.368249 -216.75927)
			(xy 90.417528 -216.743258) (xy 90.468705 -216.735152) (xy 90.520519 -216.735152) (xy 90.571696 -216.743258)
			(xy 90.620975 -216.75927) (xy 90.667142 -216.782793) (xy 90.709061 -216.813249) (xy 90.745699 -216.849887)
			(xy 90.776155 -216.891806) (xy 90.799678 -216.937973) (xy 90.81569 -216.987252) (xy 90.823796 -217.038429)
			(xy 90.824304 -217.064336) (xy 90.823812 -217.08968) (xy 90.816035 -217.13977) (xy 90.800686 -217.188079)
			(xy 90.778125 -217.233471) (xy 90.748884 -217.274876) (xy 90.713652 -217.311319) (xy 90.673259 -217.341943)
			(xy 90.628655 -217.366024) (xy 90.580892 -217.382998) (xy 90.55608 -217.388186) (xy 90.53322 -217.392504)
			(xy 90.328242 -217.747596) (xy 90.336116 -217.76944) (xy 90.344706 -217.795856) (xy 90.353895 -217.850633)
			(xy 90.354404 -217.878406) (xy 90.635328 -217.878406) (xy 90.635836 -217.852519) (xy 90.643935 -217.801381)
			(xy 90.659934 -217.752141) (xy 90.68344 -217.706009) (xy 90.713872 -217.664122) (xy 90.750482 -217.627512)
			(xy 90.792369 -217.59708) (xy 90.838501 -217.573574) (xy 90.887741 -217.557575) (xy 90.938879 -217.549476)
			(xy 90.990653 -217.549476) (xy 91.041791 -217.557575) (xy 91.091031 -217.573574) (xy 91.137163 -217.59708)
			(xy 91.17905 -217.627512) (xy 91.21566 -217.664122) (xy 91.246092 -217.706009) (xy 91.269598 -217.752141)
			(xy 91.285597 -217.801381) (xy 91.293696 -217.852519) (xy 91.294204 -217.878406) (xy 91.575128 -217.878406)
			(xy 91.575594 -217.853071) (xy 91.583346 -217.802996) (xy 91.598669 -217.754698) (xy 91.621202 -217.709313)
			(xy 91.650414 -217.66791) (xy 91.685617 -217.631464) (xy 91.725982 -217.600835) (xy 91.770559 -217.576742)
			(xy 91.818297 -217.559754) (xy 91.843098 -217.554556) (xy 91.865958 -217.550238) (xy 92.070936 -217.195146)
			(xy 92.063062 -217.173302) (xy 92.054424 -217.146891) (xy 92.045099 -217.092117) (xy 92.04452 -217.064336)
			(xy 92.045028 -217.038429) (xy 92.053134 -216.987252) (xy 92.069146 -216.937973) (xy 92.092669 -216.891806)
			(xy 92.123125 -216.849887) (xy 92.159763 -216.813249) (xy 92.201682 -216.782793) (xy 92.247849 -216.75927)
			(xy 92.297128 -216.743258) (xy 92.348305 -216.735152) (xy 92.400119 -216.735152) (xy 92.451296 -216.743258)
			(xy 92.500575 -216.75927) (xy 92.546742 -216.782793) (xy 92.588661 -216.813249) (xy 92.625299 -216.849887)
			(xy 92.655755 -216.891806) (xy 92.679278 -216.937973) (xy 92.69529 -216.987252) (xy 92.703396 -217.038429)
			(xy 92.703904 -217.064336) (xy 92.703412 -217.08968) (xy 92.695635 -217.13977) (xy 92.680286 -217.188079)
			(xy 92.657725 -217.233471) (xy 92.628484 -217.274876) (xy 92.593252 -217.311319) (xy 92.552859 -217.341943)
			(xy 92.508255 -217.366024) (xy 92.460492 -217.382998) (xy 92.43568 -217.388186) (xy 92.41282 -217.392504)
			(xy 92.207842 -217.747596) (xy 92.215716 -217.76944) (xy 92.224306 -217.795856) (xy 92.233495 -217.850633)
			(xy 92.234004 -217.878406) (xy 92.514928 -217.878406) (xy 92.515436 -217.852519) (xy 92.523535 -217.801381)
			(xy 92.539534 -217.752141) (xy 92.56304 -217.706009) (xy 92.593472 -217.664122) (xy 92.630082 -217.627512)
			(xy 92.671969 -217.59708) (xy 92.718101 -217.573574) (xy 92.767341 -217.557575) (xy 92.818479 -217.549476)
			(xy 92.870253 -217.549476) (xy 92.921391 -217.557575) (xy 92.970631 -217.573574) (xy 93.016763 -217.59708)
			(xy 93.05865 -217.627512) (xy 93.09526 -217.664122) (xy 93.125692 -217.706009) (xy 93.149198 -217.752141)
			(xy 93.165197 -217.801381) (xy 93.173296 -217.852519) (xy 93.173804 -217.878406) (xy 93.454728 -217.878406)
			(xy 93.455194 -217.853071) (xy 93.462946 -217.802996) (xy 93.478269 -217.754698) (xy 93.500802 -217.709313)
			(xy 93.530014 -217.66791) (xy 93.565217 -217.631464) (xy 93.605582 -217.600835) (xy 93.650159 -217.576742)
			(xy 93.697897 -217.559754) (xy 93.722698 -217.554556) (xy 93.745558 -217.550238) (xy 93.950536 -217.195146)
			(xy 93.942662 -217.173302) (xy 93.934024 -217.146891) (xy 93.924699 -217.092117) (xy 93.92412 -217.064336)
			(xy 93.924628 -217.038429) (xy 93.932734 -216.987252) (xy 93.948746 -216.937973) (xy 93.972269 -216.891806)
			(xy 94.002725 -216.849887) (xy 94.039363 -216.813249) (xy 94.081282 -216.782793) (xy 94.127449 -216.75927)
			(xy 94.176728 -216.743258) (xy 94.227905 -216.735152) (xy 94.279719 -216.735152) (xy 94.330896 -216.743258)
			(xy 94.380175 -216.75927) (xy 94.426342 -216.782793) (xy 94.468261 -216.813249) (xy 94.504899 -216.849887)
			(xy 94.535355 -216.891806) (xy 94.558878 -216.937973) (xy 94.57489 -216.987252) (xy 94.582996 -217.038429)
			(xy 94.583504 -217.064336) (xy 94.583012 -217.08968) (xy 94.575235 -217.13977) (xy 94.559886 -217.188079)
			(xy 94.537325 -217.233471) (xy 94.508084 -217.274876) (xy 94.472852 -217.311319) (xy 94.432459 -217.341943)
			(xy 94.387855 -217.366024) (xy 94.340092 -217.382998) (xy 94.31528 -217.388186) (xy 94.29242 -217.392504)
			(xy 94.087442 -217.747596) (xy 94.095316 -217.76944) (xy 94.103906 -217.795856) (xy 94.113095 -217.850633)
			(xy 94.113604 -217.878406) (xy 94.394528 -217.878406) (xy 94.395036 -217.852519) (xy 94.403135 -217.801381)
			(xy 94.419134 -217.752141) (xy 94.44264 -217.706009) (xy 94.473072 -217.664122) (xy 94.509682 -217.627512)
			(xy 94.551569 -217.59708) (xy 94.597701 -217.573574) (xy 94.646941 -217.557575) (xy 94.698079 -217.549476)
			(xy 94.749853 -217.549476) (xy 94.800991 -217.557575) (xy 94.850231 -217.573574) (xy 94.896363 -217.59708)
			(xy 94.93825 -217.627512) (xy 94.97486 -217.664122) (xy 95.005292 -217.706009) (xy 95.028798 -217.752141)
			(xy 95.044797 -217.801381) (xy 95.052896 -217.852519) (xy 95.053404 -217.878406) (xy 95.334328 -217.878406)
			(xy 95.334794 -217.853071) (xy 95.342546 -217.802996) (xy 95.357869 -217.754698) (xy 95.380402 -217.709313)
			(xy 95.409614 -217.66791) (xy 95.444817 -217.631464) (xy 95.485182 -217.600835) (xy 95.529759 -217.576742)
			(xy 95.577497 -217.559754) (xy 95.602298 -217.554556) (xy 95.625158 -217.550238) (xy 95.830136 -217.195146)
			(xy 95.822262 -217.173302) (xy 95.813624 -217.146891) (xy 95.804299 -217.092117) (xy 95.80372 -217.064336)
			(xy 95.804228 -217.038429) (xy 95.812334 -216.987252) (xy 95.828346 -216.937973) (xy 95.851869 -216.891806)
			(xy 95.882325 -216.849887) (xy 95.918963 -216.813249) (xy 95.960882 -216.782793) (xy 96.007049 -216.75927)
			(xy 96.056328 -216.743258) (xy 96.107505 -216.735152) (xy 96.159319 -216.735152) (xy 96.210496 -216.743258)
			(xy 96.259775 -216.75927) (xy 96.305942 -216.782793) (xy 96.347861 -216.813249) (xy 96.384499 -216.849887)
			(xy 96.414955 -216.891806) (xy 96.438478 -216.937973) (xy 96.45449 -216.987252) (xy 96.462596 -217.038429)
			(xy 96.463104 -217.064336) (xy 96.462612 -217.08968) (xy 96.454835 -217.13977) (xy 96.439486 -217.188079)
			(xy 96.416925 -217.233471) (xy 96.387684 -217.274876) (xy 96.352452 -217.311319) (xy 96.312059 -217.341943)
			(xy 96.267455 -217.366024) (xy 96.219692 -217.382998) (xy 96.19488 -217.388186) (xy 96.17202 -217.392504)
			(xy 95.967042 -217.747596) (xy 95.974916 -217.76944) (xy 95.983506 -217.795856) (xy 95.992695 -217.850633)
			(xy 95.993204 -217.878406) (xy 96.274128 -217.878406) (xy 96.274636 -217.852519) (xy 96.282735 -217.801381)
			(xy 96.298734 -217.752141) (xy 96.32224 -217.706009) (xy 96.352672 -217.664122) (xy 96.389282 -217.627512)
			(xy 96.431169 -217.59708) (xy 96.477301 -217.573574) (xy 96.526541 -217.557575) (xy 96.577679 -217.549476)
			(xy 96.629453 -217.549476) (xy 96.680591 -217.557575) (xy 96.729831 -217.573574) (xy 96.775963 -217.59708)
			(xy 96.81785 -217.627512) (xy 96.85446 -217.664122) (xy 96.884892 -217.706009) (xy 96.908398 -217.752141)
			(xy 96.924397 -217.801381) (xy 96.932496 -217.852519) (xy 96.933004 -217.878406) (xy 97.213928 -217.878406)
			(xy 97.214394 -217.853071) (xy 97.222146 -217.802996) (xy 97.237469 -217.754698) (xy 97.260002 -217.709313)
			(xy 97.289214 -217.66791) (xy 97.324417 -217.631464) (xy 97.364782 -217.600835) (xy 97.409359 -217.576742)
			(xy 97.457097 -217.559754) (xy 97.481898 -217.554556) (xy 97.504758 -217.550238) (xy 97.709736 -217.195146)
			(xy 97.701862 -217.173302) (xy 97.693224 -217.146891) (xy 97.683899 -217.092117) (xy 97.68332 -217.064336)
			(xy 97.683828 -217.038429) (xy 97.691934 -216.987252) (xy 97.707946 -216.937973) (xy 97.731469 -216.891806)
			(xy 97.761925 -216.849887) (xy 97.798563 -216.813249) (xy 97.840482 -216.782793) (xy 97.886649 -216.75927)
			(xy 97.935928 -216.743258) (xy 97.987105 -216.735152) (xy 98.038919 -216.735152) (xy 98.090096 -216.743258)
			(xy 98.139375 -216.75927) (xy 98.185542 -216.782793) (xy 98.227461 -216.813249) (xy 98.264099 -216.849887)
			(xy 98.294555 -216.891806) (xy 98.318078 -216.937973) (xy 98.33409 -216.987252) (xy 98.342196 -217.038429)
			(xy 98.342704 -217.064336) (xy 98.342212 -217.08968) (xy 98.334435 -217.13977) (xy 98.319086 -217.188079)
			(xy 98.296525 -217.233471) (xy 98.267284 -217.274876) (xy 98.232052 -217.311319) (xy 98.191659 -217.341943)
			(xy 98.147055 -217.366024) (xy 98.099292 -217.382998) (xy 98.07448 -217.388186) (xy 98.05162 -217.392504)
			(xy 97.846642 -217.747596) (xy 97.854516 -217.76944) (xy 97.863106 -217.795856) (xy 97.872295 -217.850633)
			(xy 97.872804 -217.878406) (xy 98.153728 -217.878406) (xy 98.154236 -217.852519) (xy 98.162335 -217.801381)
			(xy 98.178334 -217.752141) (xy 98.20184 -217.706009) (xy 98.232272 -217.664122) (xy 98.268882 -217.627512)
			(xy 98.310769 -217.59708) (xy 98.356901 -217.573574) (xy 98.406141 -217.557575) (xy 98.457279 -217.549476)
			(xy 98.509053 -217.549476) (xy 98.560191 -217.557575) (xy 98.609431 -217.573574) (xy 98.655563 -217.59708)
			(xy 98.69745 -217.627512) (xy 98.73406 -217.664122) (xy 98.764492 -217.706009) (xy 98.787998 -217.752141)
			(xy 98.803997 -217.801381) (xy 98.812096 -217.852519) (xy 98.812604 -217.878406) (xy 99.093528 -217.878406)
			(xy 99.093994 -217.853071) (xy 99.101746 -217.802996) (xy 99.117069 -217.754698) (xy 99.139602 -217.709313)
			(xy 99.168814 -217.66791) (xy 99.204017 -217.631464) (xy 99.244382 -217.600835) (xy 99.288959 -217.576742)
			(xy 99.336697 -217.559754) (xy 99.361498 -217.554556) (xy 99.384358 -217.550238) (xy 99.589336 -217.195146)
			(xy 99.581462 -217.173302) (xy 99.572824 -217.146891) (xy 99.563499 -217.092117) (xy 99.56292 -217.064336)
			(xy 99.563428 -217.038429) (xy 99.571534 -216.987252) (xy 99.587546 -216.937973) (xy 99.611069 -216.891806)
			(xy 99.641525 -216.849887) (xy 99.678163 -216.813249) (xy 99.720082 -216.782793) (xy 99.766249 -216.75927)
			(xy 99.815528 -216.743258) (xy 99.866705 -216.735152) (xy 99.918519 -216.735152) (xy 99.969696 -216.743258)
			(xy 100.018975 -216.75927) (xy 100.065142 -216.782793) (xy 100.107061 -216.813249) (xy 100.143699 -216.849887)
			(xy 100.174155 -216.891806) (xy 100.197678 -216.937973) (xy 100.21369 -216.987252) (xy 100.221796 -217.038429)
			(xy 100.222304 -217.064336) (xy 100.221812 -217.08968) (xy 100.214035 -217.13977) (xy 100.198686 -217.188079)
			(xy 100.176125 -217.233471) (xy 100.146884 -217.274876) (xy 100.111652 -217.311319) (xy 100.071259 -217.341943)
			(xy 100.026655 -217.366024) (xy 99.978892 -217.382998) (xy 99.95408 -217.388186) (xy 99.93122 -217.392504)
			(xy 99.726242 -217.747596) (xy 99.734116 -217.76944) (xy 99.742706 -217.795856) (xy 99.751895 -217.850633)
			(xy 99.752404 -217.878406) (xy 100.033328 -217.878406) (xy 100.033836 -217.852519) (xy 100.041935 -217.801381)
			(xy 100.057934 -217.752141) (xy 100.08144 -217.706009) (xy 100.111872 -217.664122) (xy 100.148482 -217.627512)
			(xy 100.190369 -217.59708) (xy 100.236501 -217.573574) (xy 100.285741 -217.557575) (xy 100.336879 -217.549476)
			(xy 100.388653 -217.549476) (xy 100.439791 -217.557575) (xy 100.489031 -217.573574) (xy 100.535163 -217.59708)
			(xy 100.57705 -217.627512) (xy 100.61366 -217.664122) (xy 100.644092 -217.706009) (xy 100.667598 -217.752141)
			(xy 100.683597 -217.801381) (xy 100.691696 -217.852519) (xy 100.692204 -217.878406) (xy 100.973128 -217.878406)
			(xy 100.973594 -217.853071) (xy 100.981346 -217.802996) (xy 100.996669 -217.754698) (xy 101.019202 -217.709313)
			(xy 101.048414 -217.66791) (xy 101.083617 -217.631464) (xy 101.123982 -217.600835) (xy 101.168559 -217.576742)
			(xy 101.216297 -217.559754) (xy 101.241098 -217.554556) (xy 101.263958 -217.550238) (xy 101.468936 -217.195146)
			(xy 101.461062 -217.173302) (xy 101.452424 -217.146891) (xy 101.443099 -217.092117) (xy 101.44252 -217.064336)
			(xy 101.443028 -217.038429) (xy 101.451134 -216.987252) (xy 101.467146 -216.937973) (xy 101.490669 -216.891806)
			(xy 101.521125 -216.849887) (xy 101.557763 -216.813249) (xy 101.599682 -216.782793) (xy 101.645849 -216.75927)
			(xy 101.695128 -216.743258) (xy 101.746305 -216.735152) (xy 101.798119 -216.735152) (xy 101.849296 -216.743258)
			(xy 101.898575 -216.75927) (xy 101.944742 -216.782793) (xy 101.986661 -216.813249) (xy 102.023299 -216.849887)
			(xy 102.053755 -216.891806) (xy 102.077278 -216.937973) (xy 102.09329 -216.987252) (xy 102.101396 -217.038429)
			(xy 102.101904 -217.064336) (xy 102.101412 -217.08968) (xy 102.093635 -217.13977) (xy 102.078286 -217.188079)
			(xy 102.055725 -217.233471) (xy 102.026484 -217.274876) (xy 101.991252 -217.311319) (xy 101.950859 -217.341943)
			(xy 101.906255 -217.366024) (xy 101.858492 -217.382998) (xy 101.83368 -217.388186) (xy 101.81082 -217.392504)
			(xy 101.605842 -217.747596) (xy 101.613716 -217.76944) (xy 101.622306 -217.795856) (xy 101.631495 -217.850633)
			(xy 101.632004 -217.878406) (xy 101.912928 -217.878406) (xy 101.913436 -217.852519) (xy 101.921535 -217.801381)
			(xy 101.937534 -217.752141) (xy 101.96104 -217.706009) (xy 101.991472 -217.664122) (xy 102.028082 -217.627512)
			(xy 102.069969 -217.59708) (xy 102.116101 -217.573574) (xy 102.165341 -217.557575) (xy 102.216479 -217.549476)
			(xy 102.268253 -217.549476) (xy 102.319391 -217.557575) (xy 102.368631 -217.573574) (xy 102.414763 -217.59708)
			(xy 102.45665 -217.627512) (xy 102.49326 -217.664122) (xy 102.523692 -217.706009) (xy 102.547198 -217.752141)
			(xy 102.563197 -217.801381) (xy 102.571296 -217.852519) (xy 102.571804 -217.878406) (xy 102.852728 -217.878406)
			(xy 102.853194 -217.853071) (xy 102.860946 -217.802996) (xy 102.876269 -217.754698) (xy 102.898802 -217.709313)
			(xy 102.928014 -217.66791) (xy 102.963217 -217.631464) (xy 103.003582 -217.600835) (xy 103.048159 -217.576742)
			(xy 103.095897 -217.559754) (xy 103.120698 -217.554556) (xy 103.143558 -217.550238) (xy 103.348536 -217.195146)
			(xy 103.340662 -217.173302) (xy 103.332024 -217.146891) (xy 103.322699 -217.092117) (xy 103.32212 -217.064336)
			(xy 103.322628 -217.038429) (xy 103.330734 -216.987252) (xy 103.346746 -216.937973) (xy 103.370269 -216.891806)
			(xy 103.400725 -216.849887) (xy 103.437363 -216.813249) (xy 103.479282 -216.782793) (xy 103.525449 -216.75927)
			(xy 103.574728 -216.743258) (xy 103.625905 -216.735152) (xy 103.677719 -216.735152) (xy 103.728896 -216.743258)
			(xy 103.778175 -216.75927) (xy 103.824342 -216.782793) (xy 103.866261 -216.813249) (xy 103.902899 -216.849887)
			(xy 103.933355 -216.891806) (xy 103.956878 -216.937973) (xy 103.97289 -216.987252) (xy 103.980996 -217.038429)
			(xy 103.981504 -217.064336) (xy 103.981012 -217.08968) (xy 103.973235 -217.13977) (xy 103.957886 -217.188079)
			(xy 103.935325 -217.233471) (xy 103.906084 -217.274876) (xy 103.870852 -217.311319) (xy 103.830459 -217.341943)
			(xy 103.785855 -217.366024) (xy 103.738092 -217.382998) (xy 103.71328 -217.388186) (xy 103.69042 -217.392504)
			(xy 103.485442 -217.747596) (xy 103.493316 -217.76944) (xy 103.501906 -217.795856) (xy 103.511095 -217.850633)
			(xy 103.511604 -217.878406) (xy 103.792528 -217.878406) (xy 103.793036 -217.852519) (xy 103.801135 -217.801381)
			(xy 103.817134 -217.752141) (xy 103.84064 -217.706009) (xy 103.871072 -217.664122) (xy 103.907682 -217.627512)
			(xy 103.949569 -217.59708) (xy 103.995701 -217.573574) (xy 104.044941 -217.557575) (xy 104.096079 -217.549476)
			(xy 104.147853 -217.549476) (xy 104.198991 -217.557575) (xy 104.248231 -217.573574) (xy 104.294363 -217.59708)
			(xy 104.33625 -217.627512) (xy 104.37286 -217.664122) (xy 104.403292 -217.706009) (xy 104.426798 -217.752141)
			(xy 104.442797 -217.801381) (xy 104.450896 -217.852519) (xy 104.451404 -217.878406) (xy 104.732328 -217.878406)
			(xy 104.732794 -217.853071) (xy 104.740546 -217.802996) (xy 104.755869 -217.754698) (xy 104.778402 -217.709313)
			(xy 104.807614 -217.66791) (xy 104.842817 -217.631464) (xy 104.883182 -217.600835) (xy 104.927759 -217.576742)
			(xy 104.975497 -217.559754) (xy 105.000298 -217.554556) (xy 105.023158 -217.550238) (xy 105.228136 -217.195146)
			(xy 105.220262 -217.173302) (xy 105.211624 -217.146891) (xy 105.202299 -217.092117) (xy 105.20172 -217.064336)
			(xy 105.202228 -217.038429) (xy 105.210334 -216.987252) (xy 105.226346 -216.937973) (xy 105.249869 -216.891806)
			(xy 105.280325 -216.849887) (xy 105.316963 -216.813249) (xy 105.358882 -216.782793) (xy 105.405049 -216.75927)
			(xy 105.454328 -216.743258) (xy 105.505505 -216.735152) (xy 105.557319 -216.735152) (xy 105.608496 -216.743258)
			(xy 105.657775 -216.75927) (xy 105.703942 -216.782793) (xy 105.745861 -216.813249) (xy 105.782499 -216.849887)
			(xy 105.812955 -216.891806) (xy 105.836478 -216.937973) (xy 105.85249 -216.987252) (xy 105.860596 -217.038429)
			(xy 105.861104 -217.064336) (xy 105.860612 -217.08968) (xy 105.852835 -217.13977) (xy 105.837486 -217.188079)
			(xy 105.814925 -217.233471) (xy 105.785684 -217.274876) (xy 105.750452 -217.311319) (xy 105.710059 -217.341943)
			(xy 105.665455 -217.366024) (xy 105.617692 -217.382998) (xy 105.59288 -217.388186) (xy 105.57002 -217.392504)
			(xy 105.365042 -217.747596) (xy 105.372916 -217.76944) (xy 105.381506 -217.795856) (xy 105.390695 -217.850633)
			(xy 105.391204 -217.878406) (xy 105.672128 -217.878406) (xy 105.672636 -217.852519) (xy 105.680735 -217.801381)
			(xy 105.696734 -217.752141) (xy 105.72024 -217.706009) (xy 105.750672 -217.664122) (xy 105.787282 -217.627512)
			(xy 105.829169 -217.59708) (xy 105.875301 -217.573574) (xy 105.924541 -217.557575) (xy 105.975679 -217.549476)
			(xy 106.027453 -217.549476) (xy 106.078591 -217.557575) (xy 106.127831 -217.573574) (xy 106.173963 -217.59708)
			(xy 106.21585 -217.627512) (xy 106.25246 -217.664122) (xy 106.282892 -217.706009) (xy 106.306398 -217.752141)
			(xy 106.322397 -217.801381) (xy 106.330496 -217.852519) (xy 106.331004 -217.878406) (xy 106.611928 -217.878406)
			(xy 106.612394 -217.853071) (xy 106.620146 -217.802996) (xy 106.635469 -217.754698) (xy 106.658002 -217.709313)
			(xy 106.687214 -217.66791) (xy 106.722417 -217.631464) (xy 106.762782 -217.600835) (xy 106.807359 -217.576742)
			(xy 106.855097 -217.559754) (xy 106.879898 -217.554556) (xy 106.902758 -217.550238) (xy 107.107736 -217.195146)
			(xy 107.099862 -217.173302) (xy 107.091224 -217.146891) (xy 107.081899 -217.092117) (xy 107.08132 -217.064336)
			(xy 107.081828 -217.038429) (xy 107.089934 -216.987252) (xy 107.105946 -216.937973) (xy 107.129469 -216.891806)
			(xy 107.159925 -216.849887) (xy 107.196563 -216.813249) (xy 107.238482 -216.782793) (xy 107.284649 -216.75927)
			(xy 107.333928 -216.743258) (xy 107.385105 -216.735152) (xy 107.436919 -216.735152) (xy 107.488096 -216.743258)
			(xy 107.537375 -216.75927) (xy 107.583542 -216.782793) (xy 107.625461 -216.813249) (xy 107.662099 -216.849887)
			(xy 107.692555 -216.891806) (xy 107.716078 -216.937973) (xy 107.73209 -216.987252) (xy 107.740196 -217.038429)
			(xy 107.740704 -217.064336) (xy 107.740212 -217.08968) (xy 107.732435 -217.13977) (xy 107.717086 -217.188079)
			(xy 107.694525 -217.233471) (xy 107.665284 -217.274876) (xy 107.630052 -217.311319) (xy 107.589659 -217.341943)
			(xy 107.545055 -217.366024) (xy 107.497292 -217.382998) (xy 107.47248 -217.388186) (xy 107.44962 -217.392504)
			(xy 107.244642 -217.747596) (xy 107.252516 -217.76944) (xy 107.261106 -217.795856) (xy 107.270295 -217.850633)
			(xy 107.270804 -217.878406) (xy 107.551728 -217.878406) (xy 107.552236 -217.852519) (xy 107.560335 -217.801381)
			(xy 107.576334 -217.752141) (xy 107.59984 -217.706009) (xy 107.630272 -217.664122) (xy 107.666882 -217.627512)
			(xy 107.708769 -217.59708) (xy 107.754901 -217.573574) (xy 107.804141 -217.557575) (xy 107.855279 -217.549476)
			(xy 107.907053 -217.549476) (xy 107.958191 -217.557575) (xy 108.007431 -217.573574) (xy 108.053563 -217.59708)
			(xy 108.09545 -217.627512) (xy 108.13206 -217.664122) (xy 108.162492 -217.706009) (xy 108.185998 -217.752141)
			(xy 108.201997 -217.801381) (xy 108.210096 -217.852519) (xy 108.210604 -217.878406) (xy 108.491528 -217.878406)
			(xy 108.491994 -217.853071) (xy 108.499746 -217.802996) (xy 108.515069 -217.754698) (xy 108.537602 -217.709313)
			(xy 108.566814 -217.66791) (xy 108.602017 -217.631464) (xy 108.642382 -217.600835) (xy 108.686959 -217.576742)
			(xy 108.734697 -217.559754) (xy 108.759498 -217.554556) (xy 108.782358 -217.550238) (xy 108.987336 -217.195146)
			(xy 108.979462 -217.173302) (xy 108.970824 -217.146891) (xy 108.961499 -217.092117) (xy 108.96092 -217.064336)
			(xy 108.961428 -217.038429) (xy 108.969534 -216.987252) (xy 108.985546 -216.937973) (xy 109.009069 -216.891806)
			(xy 109.039525 -216.849887) (xy 109.076163 -216.813249) (xy 109.118082 -216.782793) (xy 109.164249 -216.75927)
			(xy 109.213528 -216.743258) (xy 109.264705 -216.735152) (xy 109.316519 -216.735152) (xy 109.367696 -216.743258)
			(xy 109.416975 -216.75927) (xy 109.463142 -216.782793) (xy 109.505061 -216.813249) (xy 109.541699 -216.849887)
			(xy 109.572155 -216.891806) (xy 109.595678 -216.937973) (xy 109.61169 -216.987252) (xy 109.619796 -217.038429)
			(xy 109.620304 -217.064336) (xy 109.619812 -217.08968) (xy 109.612035 -217.13977) (xy 109.596686 -217.188079)
			(xy 109.574125 -217.233471) (xy 109.544884 -217.274876) (xy 109.509652 -217.311319) (xy 109.469259 -217.341943)
			(xy 109.424655 -217.366024) (xy 109.376892 -217.382998) (xy 109.35208 -217.388186) (xy 109.32922 -217.392504)
			(xy 109.124242 -217.747596) (xy 109.132116 -217.76944) (xy 109.140706 -217.795856) (xy 109.149895 -217.850633)
			(xy 109.150404 -217.878406) (xy 109.431328 -217.878406) (xy 109.431836 -217.852519) (xy 109.439935 -217.801381)
			(xy 109.455934 -217.752141) (xy 109.47944 -217.706009) (xy 109.509872 -217.664122) (xy 109.546482 -217.627512)
			(xy 109.588369 -217.59708) (xy 109.634501 -217.573574) (xy 109.683741 -217.557575) (xy 109.734879 -217.549476)
			(xy 109.786653 -217.549476) (xy 109.837791 -217.557575) (xy 109.887031 -217.573574) (xy 109.933163 -217.59708)
			(xy 109.97505 -217.627512) (xy 110.01166 -217.664122) (xy 110.042092 -217.706009) (xy 110.065598 -217.752141)
			(xy 110.081597 -217.801381) (xy 110.089696 -217.852519) (xy 110.090204 -217.878406) (xy 110.371128 -217.878406)
			(xy 110.371594 -217.853071) (xy 110.379346 -217.802996) (xy 110.394669 -217.754698) (xy 110.417202 -217.709313)
			(xy 110.446414 -217.66791) (xy 110.481617 -217.631464) (xy 110.521982 -217.600835) (xy 110.566559 -217.576742)
			(xy 110.614297 -217.559754) (xy 110.639098 -217.554556) (xy 110.661958 -217.550238) (xy 110.866936 -217.194892)
			(xy 110.859316 -217.173048) (xy 110.850741 -217.146694) (xy 110.841552 -217.092045) (xy 110.841028 -217.064336)
			(xy 110.841536 -217.038449) (xy 110.849635 -216.987311) (xy 110.865634 -216.938071) (xy 110.88914 -216.891939)
			(xy 110.919572 -216.850052) (xy 110.956182 -216.813442) (xy 110.998069 -216.78301) (xy 111.044201 -216.759504)
			(xy 111.093441 -216.743505) (xy 111.144579 -216.735406) (xy 111.196353 -216.735406) (xy 111.247491 -216.743505)
			(xy 111.296731 -216.759504) (xy 111.342863 -216.78301) (xy 111.38475 -216.813442) (xy 111.42136 -216.850052)
			(xy 111.451792 -216.891939) (xy 111.475298 -216.938071) (xy 111.491297 -216.987311) (xy 111.499396 -217.038449)
			(xy 111.499904 -217.064336) (xy 112.72012 -217.064336) (xy 112.720628 -217.038429) (xy 112.728734 -216.987252)
			(xy 112.744746 -216.937973) (xy 112.768269 -216.891806) (xy 112.798725 -216.849887) (xy 112.835363 -216.813249)
			(xy 112.877282 -216.782793) (xy 112.923449 -216.75927) (xy 112.972728 -216.743258) (xy 113.023905 -216.735152)
			(xy 113.075719 -216.735152) (xy 113.126896 -216.743258) (xy 113.176175 -216.75927) (xy 113.222342 -216.782793)
			(xy 113.264261 -216.813249) (xy 113.300899 -216.849887) (xy 113.331355 -216.891806) (xy 113.354878 -216.937973)
			(xy 113.37089 -216.987252) (xy 113.378996 -217.038429) (xy 113.379504 -217.064336) (xy 114.59972 -217.064336)
			(xy 114.600228 -217.038429) (xy 114.608334 -216.987252) (xy 114.624346 -216.937973) (xy 114.647869 -216.891806)
			(xy 114.678325 -216.849887) (xy 114.714963 -216.813249) (xy 114.756882 -216.782793) (xy 114.803049 -216.75927)
			(xy 114.852328 -216.743258) (xy 114.903505 -216.735152) (xy 114.955319 -216.735152) (xy 115.006496 -216.743258)
			(xy 115.055775 -216.75927) (xy 115.101942 -216.782793) (xy 115.143861 -216.813249) (xy 115.180499 -216.849887)
			(xy 115.210955 -216.891806) (xy 115.234478 -216.937973) (xy 115.25049 -216.987252) (xy 115.258596 -217.038429)
			(xy 115.259104 -217.064336) (xy 116.47932 -217.064336) (xy 116.479828 -217.038429) (xy 116.487934 -216.987252)
			(xy 116.503946 -216.937973) (xy 116.527469 -216.891806) (xy 116.557925 -216.849887) (xy 116.594563 -216.813249)
			(xy 116.636482 -216.782793) (xy 116.682649 -216.75927) (xy 116.731928 -216.743258) (xy 116.783105 -216.735152)
			(xy 116.834919 -216.735152) (xy 116.886096 -216.743258) (xy 116.935375 -216.75927) (xy 116.981542 -216.782793)
			(xy 117.023461 -216.813249) (xy 117.060099 -216.849887) (xy 117.090555 -216.891806) (xy 117.114078 -216.937973)
			(xy 117.13009 -216.987252) (xy 117.138196 -217.038429) (xy 117.138704 -217.064336) (xy 118.35892 -217.064336)
			(xy 118.359428 -217.038429) (xy 118.367534 -216.987252) (xy 118.383546 -216.937973) (xy 118.407069 -216.891806)
			(xy 118.437525 -216.849887) (xy 118.474163 -216.813249) (xy 118.516082 -216.782793) (xy 118.562249 -216.75927)
			(xy 118.611528 -216.743258) (xy 118.662705 -216.735152) (xy 118.714519 -216.735152) (xy 118.765696 -216.743258)
			(xy 118.814975 -216.75927) (xy 118.861142 -216.782793) (xy 118.903061 -216.813249) (xy 118.939699 -216.849887)
			(xy 118.970155 -216.891806) (xy 118.993678 -216.937973) (xy 119.00969 -216.987252) (xy 119.017796 -217.038429)
			(xy 119.018304 -217.064336) (xy 120.23852 -217.064336) (xy 120.239028 -217.038429) (xy 120.247134 -216.987252)
			(xy 120.263146 -216.937973) (xy 120.286669 -216.891806) (xy 120.317125 -216.849887) (xy 120.353763 -216.813249)
			(xy 120.395682 -216.782793) (xy 120.441849 -216.75927) (xy 120.491128 -216.743258) (xy 120.542305 -216.735152)
			(xy 120.594119 -216.735152) (xy 120.645296 -216.743258) (xy 120.694575 -216.75927) (xy 120.740742 -216.782793)
			(xy 120.782661 -216.813249) (xy 120.819299 -216.849887) (xy 120.849755 -216.891806) (xy 120.873278 -216.937973)
			(xy 120.88929 -216.987252) (xy 120.897396 -217.038429) (xy 120.897904 -217.064336) (xy 122.11812 -217.064336)
			(xy 122.118628 -217.038429) (xy 122.126734 -216.987252) (xy 122.142746 -216.937973) (xy 122.166269 -216.891806)
			(xy 122.196725 -216.849887) (xy 122.233363 -216.813249) (xy 122.275282 -216.782793) (xy 122.321449 -216.75927)
			(xy 122.370728 -216.743258) (xy 122.421905 -216.735152) (xy 122.473719 -216.735152) (xy 122.524896 -216.743258)
			(xy 122.574175 -216.75927) (xy 122.620342 -216.782793) (xy 122.662261 -216.813249) (xy 122.698899 -216.849887)
			(xy 122.729355 -216.891806) (xy 122.752878 -216.937973) (xy 122.76889 -216.987252) (xy 122.776996 -217.038429)
			(xy 122.777504 -217.064336) (xy 123.99772 -217.064336) (xy 123.998228 -217.038429) (xy 124.006334 -216.987252)
			(xy 124.022346 -216.937973) (xy 124.045869 -216.891806) (xy 124.076325 -216.849887) (xy 124.112963 -216.813249)
			(xy 124.154882 -216.782793) (xy 124.201049 -216.75927) (xy 124.250328 -216.743258) (xy 124.301505 -216.735152)
			(xy 124.353319 -216.735152) (xy 124.404496 -216.743258) (xy 124.453775 -216.75927) (xy 124.499942 -216.782793)
			(xy 124.541861 -216.813249) (xy 124.578499 -216.849887) (xy 124.608955 -216.891806) (xy 124.632478 -216.937973)
			(xy 124.64849 -216.987252) (xy 124.656596 -217.038429) (xy 124.657104 -217.064336) (xy 125.87732 -217.064336)
			(xy 125.877828 -217.038429) (xy 125.885934 -216.987252) (xy 125.901946 -216.937973) (xy 125.925469 -216.891806)
			(xy 125.955925 -216.849887) (xy 125.992563 -216.813249) (xy 126.034482 -216.782793) (xy 126.080649 -216.75927)
			(xy 126.129928 -216.743258) (xy 126.181105 -216.735152) (xy 126.232919 -216.735152) (xy 126.284096 -216.743258)
			(xy 126.333375 -216.75927) (xy 126.379542 -216.782793) (xy 126.421461 -216.813249) (xy 126.458099 -216.849887)
			(xy 126.488555 -216.891806) (xy 126.512078 -216.937973) (xy 126.52809 -216.987252) (xy 126.536196 -217.038429)
			(xy 126.536704 -217.064336) (xy 127.75692 -217.064336) (xy 127.757428 -217.038429) (xy 127.765534 -216.987252)
			(xy 127.781546 -216.937973) (xy 127.805069 -216.891806) (xy 127.835525 -216.849887) (xy 127.872163 -216.813249)
			(xy 127.914082 -216.782793) (xy 127.960249 -216.75927) (xy 128.009528 -216.743258) (xy 128.060705 -216.735152)
			(xy 128.112519 -216.735152) (xy 128.163696 -216.743258) (xy 128.212975 -216.75927) (xy 128.259142 -216.782793)
			(xy 128.301061 -216.813249) (xy 128.337699 -216.849887) (xy 128.368155 -216.891806) (xy 128.391678 -216.937973)
			(xy 128.40769 -216.987252) (xy 128.415796 -217.038429) (xy 128.416304 -217.064336) (xy 129.63652 -217.064336)
			(xy 129.637028 -217.038429) (xy 129.645134 -216.987252) (xy 129.661146 -216.937973) (xy 129.684669 -216.891806)
			(xy 129.715125 -216.849887) (xy 129.751763 -216.813249) (xy 129.793682 -216.782793) (xy 129.839849 -216.75927)
			(xy 129.889128 -216.743258) (xy 129.940305 -216.735152) (xy 129.992119 -216.735152) (xy 130.043296 -216.743258)
			(xy 130.092575 -216.75927) (xy 130.138742 -216.782793) (xy 130.180661 -216.813249) (xy 130.217299 -216.849887)
			(xy 130.247755 -216.891806) (xy 130.271278 -216.937973) (xy 130.28729 -216.987252) (xy 130.295396 -217.038429)
			(xy 130.295904 -217.064336) (xy 131.51612 -217.064336) (xy 131.516628 -217.038429) (xy 131.524734 -216.987252)
			(xy 131.540746 -216.937973) (xy 131.564269 -216.891806) (xy 131.594725 -216.849887) (xy 131.631363 -216.813249)
			(xy 131.673282 -216.782793) (xy 131.719449 -216.75927) (xy 131.768728 -216.743258) (xy 131.819905 -216.735152)
			(xy 131.871719 -216.735152) (xy 131.922896 -216.743258) (xy 131.972175 -216.75927) (xy 132.018342 -216.782793)
			(xy 132.060261 -216.813249) (xy 132.096899 -216.849887) (xy 132.127355 -216.891806) (xy 132.150878 -216.937973)
			(xy 132.16689 -216.987252) (xy 132.174996 -217.038429) (xy 132.175504 -217.064336) (xy 133.39572 -217.064336)
			(xy 133.396228 -217.038429) (xy 133.404334 -216.987252) (xy 133.420346 -216.937973) (xy 133.443869 -216.891806)
			(xy 133.474325 -216.849887) (xy 133.510963 -216.813249) (xy 133.552882 -216.782793) (xy 133.599049 -216.75927)
			(xy 133.648328 -216.743258) (xy 133.699505 -216.735152) (xy 133.751319 -216.735152) (xy 133.802496 -216.743258)
			(xy 133.851775 -216.75927) (xy 133.897942 -216.782793) (xy 133.939861 -216.813249) (xy 133.976499 -216.849887)
			(xy 134.006955 -216.891806) (xy 134.030478 -216.937973) (xy 134.04649 -216.987252) (xy 134.054596 -217.038429)
			(xy 134.055104 -217.064336) (xy 134.054489 -217.091989) (xy 134.045169 -217.146507) (xy 134.036562 -217.172794)
			(xy 134.028942 -217.194892) (xy 134.234174 -217.550238) (xy 134.257034 -217.554556) (xy 134.281841 -217.559728)
			(xy 134.329579 -217.576721) (xy 134.374156 -217.600818) (xy 134.41452 -217.631451) (xy 134.449723 -217.6679)
			(xy 134.478934 -217.709305) (xy 134.501466 -217.754693) (xy 134.516789 -217.802993) (xy 134.524541 -217.85307)
			(xy 134.525004 -217.878406) (xy 336.695796 -217.878406) (xy 336.696304 -217.852519) (xy 336.704403 -217.801381)
			(xy 336.720402 -217.752141) (xy 336.743908 -217.706009) (xy 336.77434 -217.664122) (xy 336.81095 -217.627512)
			(xy 336.852837 -217.59708) (xy 336.898969 -217.573574) (xy 336.948209 -217.557575) (xy 336.999347 -217.549476)
			(xy 337.051121 -217.549476) (xy 337.102259 -217.557575) (xy 337.151499 -217.573574) (xy 337.197631 -217.59708)
			(xy 337.239518 -217.627512) (xy 337.276128 -217.664122) (xy 337.30656 -217.706009) (xy 337.330066 -217.752141)
			(xy 337.346065 -217.801381) (xy 337.354164 -217.852519) (xy 337.354672 -217.878406) (xy 337.635596 -217.878406)
			(xy 337.636088 -217.853072) (xy 337.643839 -217.803) (xy 337.65916 -217.754704) (xy 337.681691 -217.70932)
			(xy 337.710899 -217.667918) (xy 337.746099 -217.631473) (xy 337.78646 -217.600842) (xy 337.831033 -217.576747)
			(xy 337.878767 -217.559756) (xy 337.903566 -217.554556) (xy 337.926426 -217.550238) (xy 338.131404 -217.195146)
			(xy 338.12353 -217.173302) (xy 338.114891 -217.146892) (xy 338.105567 -217.092117) (xy 338.104988 -217.064336)
			(xy 338.105496 -217.038429) (xy 338.113602 -216.987252) (xy 338.129614 -216.937973) (xy 338.153137 -216.891806)
			(xy 338.183593 -216.849887) (xy 338.220231 -216.813249) (xy 338.26215 -216.782793) (xy 338.308317 -216.75927)
			(xy 338.357596 -216.743258) (xy 338.408773 -216.735152) (xy 338.460587 -216.735152) (xy 338.511764 -216.743258)
			(xy 338.561043 -216.75927) (xy 338.60721 -216.782793) (xy 338.649129 -216.813249) (xy 338.685767 -216.849887)
			(xy 338.716223 -216.891806) (xy 338.739746 -216.937973) (xy 338.755758 -216.987252) (xy 338.763864 -217.038429)
			(xy 338.764372 -217.064336) (xy 338.763906 -217.089682) (xy 338.756128 -217.139773) (xy 338.740777 -217.188085)
			(xy 338.718213 -217.233478) (xy 338.688969 -217.274884) (xy 338.653734 -217.311328) (xy 338.613336 -217.34195)
			(xy 338.568729 -217.36603) (xy 338.520962 -217.383) (xy 338.496148 -217.388186) (xy 338.473288 -217.392504)
			(xy 338.26831 -217.747596) (xy 338.276184 -217.76944) (xy 338.284773 -217.795856) (xy 338.293963 -217.850633)
			(xy 338.294472 -217.878406) (xy 338.575396 -217.878406) (xy 338.575904 -217.852519) (xy 338.584003 -217.801381)
			(xy 338.600002 -217.752141) (xy 338.623508 -217.706009) (xy 338.65394 -217.664122) (xy 338.69055 -217.627512)
			(xy 338.732437 -217.59708) (xy 338.778569 -217.573574) (xy 338.827809 -217.557575) (xy 338.878947 -217.549476)
			(xy 338.930721 -217.549476) (xy 338.981859 -217.557575) (xy 339.031099 -217.573574) (xy 339.077231 -217.59708)
			(xy 339.119118 -217.627512) (xy 339.155728 -217.664122) (xy 339.18616 -217.706009) (xy 339.209666 -217.752141)
			(xy 339.225665 -217.801381) (xy 339.233764 -217.852519) (xy 339.234272 -217.878406) (xy 339.515196 -217.878406)
			(xy 339.515688 -217.853072) (xy 339.523439 -217.803) (xy 339.53876 -217.754704) (xy 339.561291 -217.70932)
			(xy 339.590499 -217.667918) (xy 339.625699 -217.631473) (xy 339.66606 -217.600842) (xy 339.710633 -217.576747)
			(xy 339.758367 -217.559756) (xy 339.783166 -217.554556) (xy 339.806026 -217.550238) (xy 340.011004 -217.195146)
			(xy 340.00313 -217.173302) (xy 339.994491 -217.146892) (xy 339.985167 -217.092117) (xy 339.984588 -217.064336)
			(xy 339.985096 -217.038429) (xy 339.993202 -216.987252) (xy 340.009214 -216.937973) (xy 340.032737 -216.891806)
			(xy 340.063193 -216.849887) (xy 340.099831 -216.813249) (xy 340.14175 -216.782793) (xy 340.187917 -216.75927)
			(xy 340.237196 -216.743258) (xy 340.288373 -216.735152) (xy 340.340187 -216.735152) (xy 340.391364 -216.743258)
			(xy 340.440643 -216.75927) (xy 340.48681 -216.782793) (xy 340.528729 -216.813249) (xy 340.565367 -216.849887)
			(xy 340.595823 -216.891806) (xy 340.619346 -216.937973) (xy 340.635358 -216.987252) (xy 340.643464 -217.038429)
			(xy 340.643972 -217.064336) (xy 340.643506 -217.089682) (xy 340.635728 -217.139773) (xy 340.620377 -217.188085)
			(xy 340.597813 -217.233478) (xy 340.568569 -217.274884) (xy 340.533334 -217.311328) (xy 340.492936 -217.34195)
			(xy 340.448329 -217.36603) (xy 340.400562 -217.383) (xy 340.375748 -217.388186) (xy 340.352888 -217.392504)
			(xy 340.14791 -217.747596) (xy 340.155784 -217.76944) (xy 340.164373 -217.795856) (xy 340.173563 -217.850633)
			(xy 340.174072 -217.878406) (xy 340.454996 -217.878406) (xy 340.455504 -217.852519) (xy 340.463603 -217.801381)
			(xy 340.479602 -217.752141) (xy 340.503108 -217.706009) (xy 340.53354 -217.664122) (xy 340.57015 -217.627512)
			(xy 340.612037 -217.59708) (xy 340.658169 -217.573574) (xy 340.707409 -217.557575) (xy 340.758547 -217.549476)
			(xy 340.810321 -217.549476) (xy 340.861459 -217.557575) (xy 340.910699 -217.573574) (xy 340.956831 -217.59708)
			(xy 340.998718 -217.627512) (xy 341.035328 -217.664122) (xy 341.06576 -217.706009) (xy 341.089266 -217.752141)
			(xy 341.105265 -217.801381) (xy 341.113364 -217.852519) (xy 341.113872 -217.878406) (xy 341.394796 -217.878406)
			(xy 341.395288 -217.853072) (xy 341.403039 -217.803) (xy 341.41836 -217.754704) (xy 341.440891 -217.70932)
			(xy 341.470099 -217.667918) (xy 341.505299 -217.631473) (xy 341.54566 -217.600842) (xy 341.590233 -217.576747)
			(xy 341.637967 -217.559756) (xy 341.662766 -217.554556) (xy 341.685626 -217.550238) (xy 341.890604 -217.195146)
			(xy 341.88273 -217.173302) (xy 341.874091 -217.146892) (xy 341.864767 -217.092117) (xy 341.864188 -217.064336)
			(xy 341.864696 -217.038429) (xy 341.872802 -216.987252) (xy 341.888814 -216.937973) (xy 341.912337 -216.891806)
			(xy 341.942793 -216.849887) (xy 341.979431 -216.813249) (xy 342.02135 -216.782793) (xy 342.067517 -216.75927)
			(xy 342.116796 -216.743258) (xy 342.167973 -216.735152) (xy 342.219787 -216.735152) (xy 342.270964 -216.743258)
			(xy 342.320243 -216.75927) (xy 342.36641 -216.782793) (xy 342.408329 -216.813249) (xy 342.444967 -216.849887)
			(xy 342.475423 -216.891806) (xy 342.498946 -216.937973) (xy 342.514958 -216.987252) (xy 342.523064 -217.038429)
			(xy 342.523572 -217.064336) (xy 342.523106 -217.089682) (xy 342.515328 -217.139773) (xy 342.499977 -217.188085)
			(xy 342.477413 -217.233478) (xy 342.448169 -217.274884) (xy 342.412934 -217.311328) (xy 342.372536 -217.34195)
			(xy 342.327929 -217.36603) (xy 342.280162 -217.383) (xy 342.255348 -217.388186) (xy 342.232488 -217.392504)
			(xy 342.02751 -217.747596) (xy 342.035384 -217.76944) (xy 342.043973 -217.795856) (xy 342.053163 -217.850633)
			(xy 342.053672 -217.878406) (xy 342.334596 -217.878406) (xy 342.335104 -217.852519) (xy 342.343203 -217.801381)
			(xy 342.359202 -217.752141) (xy 342.382708 -217.706009) (xy 342.41314 -217.664122) (xy 342.44975 -217.627512)
			(xy 342.491637 -217.59708) (xy 342.537769 -217.573574) (xy 342.587009 -217.557575) (xy 342.638147 -217.549476)
			(xy 342.689921 -217.549476) (xy 342.741059 -217.557575) (xy 342.790299 -217.573574) (xy 342.836431 -217.59708)
			(xy 342.878318 -217.627512) (xy 342.914928 -217.664122) (xy 342.94536 -217.706009) (xy 342.968866 -217.752141)
			(xy 342.984865 -217.801381) (xy 342.992964 -217.852519) (xy 342.993472 -217.878406) (xy 343.274396 -217.878406)
			(xy 343.274888 -217.853072) (xy 343.282639 -217.803) (xy 343.29796 -217.754704) (xy 343.320491 -217.70932)
			(xy 343.349699 -217.667918) (xy 343.384899 -217.631473) (xy 343.42526 -217.600842) (xy 343.469833 -217.576747)
			(xy 343.517567 -217.559756) (xy 343.542366 -217.554556) (xy 343.565226 -217.550238) (xy 343.770204 -217.195146)
			(xy 343.76233 -217.173302) (xy 343.753691 -217.146892) (xy 343.744367 -217.092117) (xy 343.743788 -217.064336)
			(xy 343.744296 -217.038429) (xy 343.752402 -216.987252) (xy 343.768414 -216.937973) (xy 343.791937 -216.891806)
			(xy 343.822393 -216.849887) (xy 343.859031 -216.813249) (xy 343.90095 -216.782793) (xy 343.947117 -216.75927)
			(xy 343.996396 -216.743258) (xy 344.047573 -216.735152) (xy 344.099387 -216.735152) (xy 344.150564 -216.743258)
			(xy 344.199843 -216.75927) (xy 344.24601 -216.782793) (xy 344.287929 -216.813249) (xy 344.324567 -216.849887)
			(xy 344.355023 -216.891806) (xy 344.378546 -216.937973) (xy 344.394558 -216.987252) (xy 344.402664 -217.038429)
			(xy 344.403172 -217.064336) (xy 344.402706 -217.089682) (xy 344.394928 -217.139773) (xy 344.379577 -217.188085)
			(xy 344.357013 -217.233478) (xy 344.327769 -217.274884) (xy 344.292534 -217.311328) (xy 344.252136 -217.34195)
			(xy 344.207529 -217.36603) (xy 344.159762 -217.383) (xy 344.134948 -217.388186) (xy 344.112088 -217.392504)
			(xy 343.90711 -217.747596) (xy 343.914984 -217.76944) (xy 343.923573 -217.795856) (xy 343.932763 -217.850633)
			(xy 343.933272 -217.878406) (xy 344.214196 -217.878406) (xy 344.214704 -217.852519) (xy 344.222803 -217.801381)
			(xy 344.238802 -217.752141) (xy 344.262308 -217.706009) (xy 344.29274 -217.664122) (xy 344.32935 -217.627512)
			(xy 344.371237 -217.59708) (xy 344.417369 -217.573574) (xy 344.466609 -217.557575) (xy 344.517747 -217.549476)
			(xy 344.569521 -217.549476) (xy 344.620659 -217.557575) (xy 344.669899 -217.573574) (xy 344.716031 -217.59708)
			(xy 344.757918 -217.627512) (xy 344.794528 -217.664122) (xy 344.82496 -217.706009) (xy 344.848466 -217.752141)
			(xy 344.864465 -217.801381) (xy 344.872564 -217.852519) (xy 344.873072 -217.878406) (xy 345.153996 -217.878406)
			(xy 345.154488 -217.853072) (xy 345.162239 -217.803) (xy 345.17756 -217.754704) (xy 345.200091 -217.70932)
			(xy 345.229299 -217.667918) (xy 345.264499 -217.631473) (xy 345.30486 -217.600842) (xy 345.349433 -217.576747)
			(xy 345.397167 -217.559756) (xy 345.421966 -217.554556) (xy 345.444826 -217.550238) (xy 345.649804 -217.195146)
			(xy 345.64193 -217.173302) (xy 345.633291 -217.146892) (xy 345.623967 -217.092117) (xy 345.623388 -217.064336)
			(xy 345.623896 -217.038429) (xy 345.632002 -216.987252) (xy 345.648014 -216.937973) (xy 345.671537 -216.891806)
			(xy 345.701993 -216.849887) (xy 345.738631 -216.813249) (xy 345.78055 -216.782793) (xy 345.826717 -216.75927)
			(xy 345.875996 -216.743258) (xy 345.927173 -216.735152) (xy 345.978987 -216.735152) (xy 346.030164 -216.743258)
			(xy 346.079443 -216.75927) (xy 346.12561 -216.782793) (xy 346.167529 -216.813249) (xy 346.204167 -216.849887)
			(xy 346.234623 -216.891806) (xy 346.258146 -216.937973) (xy 346.274158 -216.987252) (xy 346.282264 -217.038429)
			(xy 346.282772 -217.064336) (xy 346.282306 -217.089682) (xy 346.274528 -217.139773) (xy 346.259177 -217.188085)
			(xy 346.236613 -217.233478) (xy 346.207369 -217.274884) (xy 346.172134 -217.311328) (xy 346.131736 -217.34195)
			(xy 346.087129 -217.36603) (xy 346.039362 -217.383) (xy 346.014548 -217.388186) (xy 345.991688 -217.392504)
			(xy 345.78671 -217.747596) (xy 345.794584 -217.76944) (xy 345.803173 -217.795856) (xy 345.812363 -217.850633)
			(xy 345.812872 -217.878406) (xy 346.093796 -217.878406) (xy 346.094304 -217.852519) (xy 346.102403 -217.801381)
			(xy 346.118402 -217.752141) (xy 346.141908 -217.706009) (xy 346.17234 -217.664122) (xy 346.20895 -217.627512)
			(xy 346.250837 -217.59708) (xy 346.296969 -217.573574) (xy 346.346209 -217.557575) (xy 346.397347 -217.549476)
			(xy 346.449121 -217.549476) (xy 346.500259 -217.557575) (xy 346.549499 -217.573574) (xy 346.595631 -217.59708)
			(xy 346.637518 -217.627512) (xy 346.674128 -217.664122) (xy 346.70456 -217.706009) (xy 346.728066 -217.752141)
			(xy 346.744065 -217.801381) (xy 346.752164 -217.852519) (xy 346.752672 -217.878406) (xy 347.033596 -217.878406)
			(xy 347.034088 -217.853072) (xy 347.041839 -217.803) (xy 347.05716 -217.754704) (xy 347.079691 -217.70932)
			(xy 347.108899 -217.667918) (xy 347.144099 -217.631473) (xy 347.18446 -217.600842) (xy 347.229033 -217.576747)
			(xy 347.276767 -217.559756) (xy 347.301566 -217.554556) (xy 347.324426 -217.550238) (xy 347.529404 -217.195146)
			(xy 347.52153 -217.173302) (xy 347.512891 -217.146892) (xy 347.503567 -217.092117) (xy 347.502988 -217.064336)
			(xy 347.503496 -217.038429) (xy 347.511602 -216.987252) (xy 347.527614 -216.937973) (xy 347.551137 -216.891806)
			(xy 347.581593 -216.849887) (xy 347.618231 -216.813249) (xy 347.66015 -216.782793) (xy 347.706317 -216.75927)
			(xy 347.755596 -216.743258) (xy 347.806773 -216.735152) (xy 347.858587 -216.735152) (xy 347.909764 -216.743258)
			(xy 347.959043 -216.75927) (xy 348.00521 -216.782793) (xy 348.047129 -216.813249) (xy 348.083767 -216.849887)
			(xy 348.114223 -216.891806) (xy 348.137746 -216.937973) (xy 348.153758 -216.987252) (xy 348.161864 -217.038429)
			(xy 348.162372 -217.064336) (xy 348.161906 -217.089682) (xy 348.154128 -217.139773) (xy 348.138777 -217.188085)
			(xy 348.116213 -217.233478) (xy 348.086969 -217.274884) (xy 348.051734 -217.311328) (xy 348.011336 -217.34195)
			(xy 347.966729 -217.36603) (xy 347.918962 -217.383) (xy 347.894148 -217.388186) (xy 347.871288 -217.392504)
			(xy 347.66631 -217.747596) (xy 347.674184 -217.76944) (xy 347.682773 -217.795856) (xy 347.691963 -217.850633)
			(xy 347.692472 -217.878406) (xy 347.973396 -217.878406) (xy 347.973904 -217.852519) (xy 347.982003 -217.801381)
			(xy 347.998002 -217.752141) (xy 348.021508 -217.706009) (xy 348.05194 -217.664122) (xy 348.08855 -217.627512)
			(xy 348.130437 -217.59708) (xy 348.176569 -217.573574) (xy 348.225809 -217.557575) (xy 348.276947 -217.549476)
			(xy 348.328721 -217.549476) (xy 348.379859 -217.557575) (xy 348.429099 -217.573574) (xy 348.475231 -217.59708)
			(xy 348.517118 -217.627512) (xy 348.553728 -217.664122) (xy 348.58416 -217.706009) (xy 348.607666 -217.752141)
			(xy 348.623665 -217.801381) (xy 348.631764 -217.852519) (xy 348.632272 -217.878406) (xy 348.913196 -217.878406)
			(xy 348.913688 -217.853072) (xy 348.921439 -217.803) (xy 348.93676 -217.754704) (xy 348.959291 -217.70932)
			(xy 348.988499 -217.667918) (xy 349.023699 -217.631473) (xy 349.06406 -217.600842) (xy 349.108633 -217.576747)
			(xy 349.156367 -217.559756) (xy 349.181166 -217.554556) (xy 349.204026 -217.550238) (xy 349.409004 -217.195146)
			(xy 349.40113 -217.173302) (xy 349.392491 -217.146892) (xy 349.383167 -217.092117) (xy 349.382588 -217.064336)
			(xy 349.383096 -217.038429) (xy 349.391202 -216.987252) (xy 349.407214 -216.937973) (xy 349.430737 -216.891806)
			(xy 349.461193 -216.849887) (xy 349.497831 -216.813249) (xy 349.53975 -216.782793) (xy 349.585917 -216.75927)
			(xy 349.635196 -216.743258) (xy 349.686373 -216.735152) (xy 349.738187 -216.735152) (xy 349.789364 -216.743258)
			(xy 349.838643 -216.75927) (xy 349.88481 -216.782793) (xy 349.926729 -216.813249) (xy 349.963367 -216.849887)
			(xy 349.993823 -216.891806) (xy 350.017346 -216.937973) (xy 350.033358 -216.987252) (xy 350.041464 -217.038429)
			(xy 350.041972 -217.064336) (xy 350.041506 -217.089682) (xy 350.033728 -217.139773) (xy 350.018377 -217.188085)
			(xy 349.995813 -217.233478) (xy 349.966569 -217.274884) (xy 349.931334 -217.311328) (xy 349.890936 -217.34195)
			(xy 349.846329 -217.36603) (xy 349.798562 -217.383) (xy 349.773748 -217.388186) (xy 349.750888 -217.392504)
			(xy 349.54591 -217.747596) (xy 349.553784 -217.76944) (xy 349.562373 -217.795856) (xy 349.571563 -217.850633)
			(xy 349.572072 -217.878406) (xy 349.852996 -217.878406) (xy 349.853504 -217.852519) (xy 349.861603 -217.801381)
			(xy 349.877602 -217.752141) (xy 349.901108 -217.706009) (xy 349.93154 -217.664122) (xy 349.96815 -217.627512)
			(xy 350.010037 -217.59708) (xy 350.056169 -217.573574) (xy 350.105409 -217.557575) (xy 350.156547 -217.549476)
			(xy 350.208321 -217.549476) (xy 350.259459 -217.557575) (xy 350.308699 -217.573574) (xy 350.354831 -217.59708)
			(xy 350.396718 -217.627512) (xy 350.433328 -217.664122) (xy 350.46376 -217.706009) (xy 350.487266 -217.752141)
			(xy 350.503265 -217.801381) (xy 350.511364 -217.852519) (xy 350.511872 -217.878406) (xy 350.792796 -217.878406)
			(xy 350.793288 -217.853072) (xy 350.801039 -217.803) (xy 350.81636 -217.754704) (xy 350.838891 -217.70932)
			(xy 350.868099 -217.667918) (xy 350.903299 -217.631473) (xy 350.94366 -217.600842) (xy 350.988233 -217.576747)
			(xy 351.035967 -217.559756) (xy 351.060766 -217.554556) (xy 351.083626 -217.550238) (xy 351.288604 -217.195146)
			(xy 351.28073 -217.173302) (xy 351.272091 -217.146892) (xy 351.262767 -217.092117) (xy 351.262188 -217.064336)
			(xy 351.262696 -217.038429) (xy 351.270802 -216.987252) (xy 351.286814 -216.937973) (xy 351.310337 -216.891806)
			(xy 351.340793 -216.849887) (xy 351.377431 -216.813249) (xy 351.41935 -216.782793) (xy 351.465517 -216.75927)
			(xy 351.514796 -216.743258) (xy 351.565973 -216.735152) (xy 351.617787 -216.735152) (xy 351.668964 -216.743258)
			(xy 351.718243 -216.75927) (xy 351.76441 -216.782793) (xy 351.806329 -216.813249) (xy 351.842967 -216.849887)
			(xy 351.873423 -216.891806) (xy 351.896946 -216.937973) (xy 351.912958 -216.987252) (xy 351.921064 -217.038429)
			(xy 351.921572 -217.064336) (xy 351.921106 -217.089682) (xy 351.913328 -217.139773) (xy 351.897977 -217.188085)
			(xy 351.875413 -217.233478) (xy 351.846169 -217.274884) (xy 351.810934 -217.311328) (xy 351.770536 -217.34195)
			(xy 351.725929 -217.36603) (xy 351.678162 -217.383) (xy 351.653348 -217.388186) (xy 351.630488 -217.392504)
			(xy 351.42551 -217.747596) (xy 351.433384 -217.76944) (xy 351.441973 -217.795856) (xy 351.451163 -217.850633)
			(xy 351.451672 -217.878406) (xy 351.732596 -217.878406) (xy 351.733104 -217.852519) (xy 351.741203 -217.801381)
			(xy 351.757202 -217.752141) (xy 351.780708 -217.706009) (xy 351.81114 -217.664122) (xy 351.84775 -217.627512)
			(xy 351.889637 -217.59708) (xy 351.935769 -217.573574) (xy 351.985009 -217.557575) (xy 352.036147 -217.549476)
			(xy 352.087921 -217.549476) (xy 352.139059 -217.557575) (xy 352.188299 -217.573574) (xy 352.234431 -217.59708)
			(xy 352.276318 -217.627512) (xy 352.312928 -217.664122) (xy 352.34336 -217.706009) (xy 352.366866 -217.752141)
			(xy 352.382865 -217.801381) (xy 352.390964 -217.852519) (xy 352.391472 -217.878406) (xy 352.672396 -217.878406)
			(xy 352.672888 -217.853072) (xy 352.680639 -217.803) (xy 352.69596 -217.754704) (xy 352.718491 -217.70932)
			(xy 352.747699 -217.667918) (xy 352.782899 -217.631473) (xy 352.82326 -217.600842) (xy 352.867833 -217.576747)
			(xy 352.915567 -217.559756) (xy 352.940366 -217.554556) (xy 352.963226 -217.550238) (xy 353.168204 -217.195146)
			(xy 353.16033 -217.173302) (xy 353.151691 -217.146892) (xy 353.142367 -217.092117) (xy 353.141788 -217.064336)
			(xy 353.142296 -217.038429) (xy 353.150402 -216.987252) (xy 353.166414 -216.937973) (xy 353.189937 -216.891806)
			(xy 353.220393 -216.849887) (xy 353.257031 -216.813249) (xy 353.29895 -216.782793) (xy 353.345117 -216.75927)
			(xy 353.394396 -216.743258) (xy 353.445573 -216.735152) (xy 353.497387 -216.735152) (xy 353.548564 -216.743258)
			(xy 353.597843 -216.75927) (xy 353.64401 -216.782793) (xy 353.685929 -216.813249) (xy 353.722567 -216.849887)
			(xy 353.753023 -216.891806) (xy 353.776546 -216.937973) (xy 353.792558 -216.987252) (xy 353.800664 -217.038429)
			(xy 353.801172 -217.064336) (xy 353.800706 -217.089682) (xy 353.792928 -217.139773) (xy 353.777577 -217.188085)
			(xy 353.755013 -217.233478) (xy 353.725769 -217.274884) (xy 353.690534 -217.311328) (xy 353.650136 -217.34195)
			(xy 353.605529 -217.36603) (xy 353.557762 -217.383) (xy 353.532948 -217.388186) (xy 353.510088 -217.392504)
			(xy 353.30511 -217.747596) (xy 353.312984 -217.76944) (xy 353.321573 -217.795856) (xy 353.330763 -217.850633)
			(xy 353.331272 -217.878406) (xy 353.612196 -217.878406) (xy 353.612704 -217.852519) (xy 353.620803 -217.801381)
			(xy 353.636802 -217.752141) (xy 353.660308 -217.706009) (xy 353.69074 -217.664122) (xy 353.72735 -217.627512)
			(xy 353.769237 -217.59708) (xy 353.815369 -217.573574) (xy 353.864609 -217.557575) (xy 353.915747 -217.549476)
			(xy 353.967521 -217.549476) (xy 354.018659 -217.557575) (xy 354.067899 -217.573574) (xy 354.114031 -217.59708)
			(xy 354.155918 -217.627512) (xy 354.192528 -217.664122) (xy 354.22296 -217.706009) (xy 354.246466 -217.752141)
			(xy 354.262465 -217.801381) (xy 354.270564 -217.852519) (xy 354.271072 -217.878406) (xy 354.551996 -217.878406)
			(xy 354.552488 -217.853072) (xy 354.560239 -217.803) (xy 354.57556 -217.754704) (xy 354.598091 -217.70932)
			(xy 354.627299 -217.667918) (xy 354.662499 -217.631473) (xy 354.70286 -217.600842) (xy 354.747433 -217.576747)
			(xy 354.795167 -217.559756) (xy 354.819966 -217.554556) (xy 354.842826 -217.550238) (xy 355.047804 -217.195146)
			(xy 355.03993 -217.173302) (xy 355.031291 -217.146892) (xy 355.021967 -217.092117) (xy 355.021388 -217.064336)
			(xy 355.021896 -217.038429) (xy 355.030002 -216.987252) (xy 355.046014 -216.937973) (xy 355.069537 -216.891806)
			(xy 355.099993 -216.849887) (xy 355.136631 -216.813249) (xy 355.17855 -216.782793) (xy 355.224717 -216.75927)
			(xy 355.273996 -216.743258) (xy 355.325173 -216.735152) (xy 355.376987 -216.735152) (xy 355.428164 -216.743258)
			(xy 355.477443 -216.75927) (xy 355.52361 -216.782793) (xy 355.565529 -216.813249) (xy 355.602167 -216.849887)
			(xy 355.632623 -216.891806) (xy 355.656146 -216.937973) (xy 355.672158 -216.987252) (xy 355.680264 -217.038429)
			(xy 355.680772 -217.064336) (xy 355.680306 -217.089682) (xy 355.672528 -217.139773) (xy 355.657177 -217.188085)
			(xy 355.634613 -217.233478) (xy 355.605369 -217.274884) (xy 355.570134 -217.311328) (xy 355.529736 -217.34195)
			(xy 355.485129 -217.36603) (xy 355.437362 -217.383) (xy 355.412548 -217.388186) (xy 355.389688 -217.392504)
			(xy 355.18471 -217.747596) (xy 355.192584 -217.76944) (xy 355.201173 -217.795856) (xy 355.210363 -217.850633)
			(xy 355.210872 -217.878406) (xy 355.491796 -217.878406) (xy 355.492304 -217.852519) (xy 355.500403 -217.801381)
			(xy 355.516402 -217.752141) (xy 355.539908 -217.706009) (xy 355.57034 -217.664122) (xy 355.60695 -217.627512)
			(xy 355.648837 -217.59708) (xy 355.694969 -217.573574) (xy 355.744209 -217.557575) (xy 355.795347 -217.549476)
			(xy 355.847121 -217.549476) (xy 355.898259 -217.557575) (xy 355.947499 -217.573574) (xy 355.993631 -217.59708)
			(xy 356.035518 -217.627512) (xy 356.072128 -217.664122) (xy 356.10256 -217.706009) (xy 356.126066 -217.752141)
			(xy 356.142065 -217.801381) (xy 356.150164 -217.852519) (xy 356.150672 -217.878406) (xy 356.431596 -217.878406)
			(xy 356.432088 -217.853072) (xy 356.439839 -217.803) (xy 356.45516 -217.754704) (xy 356.477691 -217.70932)
			(xy 356.506899 -217.667918) (xy 356.542099 -217.631473) (xy 356.58246 -217.600842) (xy 356.627033 -217.576747)
			(xy 356.674767 -217.559756) (xy 356.699566 -217.554556) (xy 356.722426 -217.550238) (xy 356.927404 -217.195146)
			(xy 356.91953 -217.173302) (xy 356.910891 -217.146892) (xy 356.901567 -217.092117) (xy 356.900988 -217.064336)
			(xy 356.901496 -217.038429) (xy 356.909602 -216.987252) (xy 356.925614 -216.937973) (xy 356.949137 -216.891806)
			(xy 356.979593 -216.849887) (xy 357.016231 -216.813249) (xy 357.05815 -216.782793) (xy 357.104317 -216.75927)
			(xy 357.153596 -216.743258) (xy 357.204773 -216.735152) (xy 357.256587 -216.735152) (xy 357.307764 -216.743258)
			(xy 357.357043 -216.75927) (xy 357.40321 -216.782793) (xy 357.445129 -216.813249) (xy 357.481767 -216.849887)
			(xy 357.512223 -216.891806) (xy 357.535746 -216.937973) (xy 357.551758 -216.987252) (xy 357.559864 -217.038429)
			(xy 357.560372 -217.064336) (xy 357.559906 -217.089682) (xy 357.552128 -217.139773) (xy 357.536777 -217.188085)
			(xy 357.514213 -217.233478) (xy 357.484969 -217.274884) (xy 357.449734 -217.311328) (xy 357.409336 -217.34195)
			(xy 357.364729 -217.36603) (xy 357.316962 -217.383) (xy 357.292148 -217.388186) (xy 357.269288 -217.392504)
			(xy 357.06431 -217.747596) (xy 357.072184 -217.76944) (xy 357.080773 -217.795856) (xy 357.089963 -217.850633)
			(xy 357.090472 -217.878406) (xy 357.371396 -217.878406) (xy 357.371904 -217.852519) (xy 357.380003 -217.801381)
			(xy 357.396002 -217.752141) (xy 357.419508 -217.706009) (xy 357.44994 -217.664122) (xy 357.48655 -217.627512)
			(xy 357.528437 -217.59708) (xy 357.574569 -217.573574) (xy 357.623809 -217.557575) (xy 357.674947 -217.549476)
			(xy 357.726721 -217.549476) (xy 357.777859 -217.557575) (xy 357.827099 -217.573574) (xy 357.873231 -217.59708)
			(xy 357.915118 -217.627512) (xy 357.951728 -217.664122) (xy 357.98216 -217.706009) (xy 358.005666 -217.752141)
			(xy 358.021665 -217.801381) (xy 358.029764 -217.852519) (xy 358.030272 -217.878406) (xy 358.311196 -217.878406)
			(xy 358.311688 -217.853072) (xy 358.319439 -217.803) (xy 358.33476 -217.754704) (xy 358.357291 -217.70932)
			(xy 358.386499 -217.667918) (xy 358.421699 -217.631473) (xy 358.46206 -217.600842) (xy 358.506633 -217.576747)
			(xy 358.554367 -217.559756) (xy 358.579166 -217.554556) (xy 358.602026 -217.550238) (xy 358.807004 -217.194892)
			(xy 358.799384 -217.173048) (xy 358.790811 -217.146694) (xy 358.78162 -217.092045) (xy 358.781096 -217.064336)
			(xy 358.781604 -217.038449) (xy 358.789703 -216.987311) (xy 358.805702 -216.938071) (xy 358.829208 -216.891939)
			(xy 358.85964 -216.850052) (xy 358.89625 -216.813442) (xy 358.938137 -216.78301) (xy 358.984269 -216.759504)
			(xy 359.033509 -216.743505) (xy 359.084647 -216.735406) (xy 359.136421 -216.735406) (xy 359.187559 -216.743505)
			(xy 359.236799 -216.759504) (xy 359.282931 -216.78301) (xy 359.324818 -216.813442) (xy 359.361428 -216.850052)
			(xy 359.39186 -216.891939) (xy 359.415366 -216.938071) (xy 359.431365 -216.987311) (xy 359.439464 -217.038449)
			(xy 359.439972 -217.064336) (xy 360.660188 -217.064336) (xy 360.660696 -217.038429) (xy 360.668802 -216.987252)
			(xy 360.684814 -216.937973) (xy 360.708337 -216.891806) (xy 360.738793 -216.849887) (xy 360.775431 -216.813249)
			(xy 360.81735 -216.782793) (xy 360.863517 -216.75927) (xy 360.912796 -216.743258) (xy 360.963973 -216.735152)
			(xy 361.015787 -216.735152) (xy 361.066964 -216.743258) (xy 361.116243 -216.75927) (xy 361.16241 -216.782793)
			(xy 361.204329 -216.813249) (xy 361.240967 -216.849887) (xy 361.271423 -216.891806) (xy 361.294946 -216.937973)
			(xy 361.310958 -216.987252) (xy 361.319064 -217.038429) (xy 361.319572 -217.064336) (xy 362.539788 -217.064336)
			(xy 362.540296 -217.038429) (xy 362.548402 -216.987252) (xy 362.564414 -216.937973) (xy 362.587937 -216.891806)
			(xy 362.618393 -216.849887) (xy 362.655031 -216.813249) (xy 362.69695 -216.782793) (xy 362.743117 -216.75927)
			(xy 362.792396 -216.743258) (xy 362.843573 -216.735152) (xy 362.895387 -216.735152) (xy 362.946564 -216.743258)
			(xy 362.995843 -216.75927) (xy 363.04201 -216.782793) (xy 363.083929 -216.813249) (xy 363.120567 -216.849887)
			(xy 363.151023 -216.891806) (xy 363.174546 -216.937973) (xy 363.190558 -216.987252) (xy 363.198664 -217.038429)
			(xy 363.199172 -217.064336) (xy 364.419388 -217.064336) (xy 364.419896 -217.038429) (xy 364.428002 -216.987252)
			(xy 364.444014 -216.937973) (xy 364.467537 -216.891806) (xy 364.497993 -216.849887) (xy 364.534631 -216.813249)
			(xy 364.57655 -216.782793) (xy 364.622717 -216.75927) (xy 364.671996 -216.743258) (xy 364.723173 -216.735152)
			(xy 364.774987 -216.735152) (xy 364.826164 -216.743258) (xy 364.875443 -216.75927) (xy 364.92161 -216.782793)
			(xy 364.963529 -216.813249) (xy 365.000167 -216.849887) (xy 365.030623 -216.891806) (xy 365.054146 -216.937973)
			(xy 365.070158 -216.987252) (xy 365.078264 -217.038429) (xy 365.078772 -217.064336) (xy 366.298988 -217.064336)
			(xy 366.299496 -217.038429) (xy 366.307602 -216.987252) (xy 366.323614 -216.937973) (xy 366.347137 -216.891806)
			(xy 366.377593 -216.849887) (xy 366.414231 -216.813249) (xy 366.45615 -216.782793) (xy 366.502317 -216.75927)
			(xy 366.551596 -216.743258) (xy 366.602773 -216.735152) (xy 366.654587 -216.735152) (xy 366.705764 -216.743258)
			(xy 366.755043 -216.75927) (xy 366.80121 -216.782793) (xy 366.843129 -216.813249) (xy 366.879767 -216.849887)
			(xy 366.910223 -216.891806) (xy 366.933746 -216.937973) (xy 366.949758 -216.987252) (xy 366.957864 -217.038429)
			(xy 366.958372 -217.064336) (xy 368.178588 -217.064336) (xy 368.179096 -217.038429) (xy 368.187202 -216.987252)
			(xy 368.203214 -216.937973) (xy 368.226737 -216.891806) (xy 368.257193 -216.849887) (xy 368.293831 -216.813249)
			(xy 368.33575 -216.782793) (xy 368.381917 -216.75927) (xy 368.431196 -216.743258) (xy 368.482373 -216.735152)
			(xy 368.534187 -216.735152) (xy 368.585364 -216.743258) (xy 368.634643 -216.75927) (xy 368.68081 -216.782793)
			(xy 368.722729 -216.813249) (xy 368.759367 -216.849887) (xy 368.789823 -216.891806) (xy 368.813346 -216.937973)
			(xy 368.829358 -216.987252) (xy 368.837464 -217.038429) (xy 368.837972 -217.064336) (xy 370.058188 -217.064336)
			(xy 370.058696 -217.038429) (xy 370.066802 -216.987252) (xy 370.082814 -216.937973) (xy 370.106337 -216.891806)
			(xy 370.136793 -216.849887) (xy 370.173431 -216.813249) (xy 370.21535 -216.782793) (xy 370.261517 -216.75927)
			(xy 370.310796 -216.743258) (xy 370.361973 -216.735152) (xy 370.413787 -216.735152) (xy 370.464964 -216.743258)
			(xy 370.514243 -216.75927) (xy 370.56041 -216.782793) (xy 370.602329 -216.813249) (xy 370.638967 -216.849887)
			(xy 370.669423 -216.891806) (xy 370.692946 -216.937973) (xy 370.708958 -216.987252) (xy 370.717064 -217.038429)
			(xy 370.717572 -217.064336) (xy 371.937788 -217.064336) (xy 371.938296 -217.038429) (xy 371.946402 -216.987252)
			(xy 371.962414 -216.937973) (xy 371.985937 -216.891806) (xy 372.016393 -216.849887) (xy 372.053031 -216.813249)
			(xy 372.09495 -216.782793) (xy 372.141117 -216.75927) (xy 372.190396 -216.743258) (xy 372.241573 -216.735152)
			(xy 372.293387 -216.735152) (xy 372.344564 -216.743258) (xy 372.393843 -216.75927) (xy 372.44001 -216.782793)
			(xy 372.481929 -216.813249) (xy 372.518567 -216.849887) (xy 372.549023 -216.891806) (xy 372.572546 -216.937973)
			(xy 372.588558 -216.987252) (xy 372.596664 -217.038429) (xy 372.597172 -217.064336) (xy 373.817388 -217.064336)
			(xy 373.817896 -217.038429) (xy 373.826002 -216.987252) (xy 373.842014 -216.937973) (xy 373.865537 -216.891806)
			(xy 373.895993 -216.849887) (xy 373.932631 -216.813249) (xy 373.97455 -216.782793) (xy 374.020717 -216.75927)
			(xy 374.069996 -216.743258) (xy 374.121173 -216.735152) (xy 374.172987 -216.735152) (xy 374.224164 -216.743258)
			(xy 374.273443 -216.75927) (xy 374.31961 -216.782793) (xy 374.361529 -216.813249) (xy 374.398167 -216.849887)
			(xy 374.428623 -216.891806) (xy 374.452146 -216.937973) (xy 374.468158 -216.987252) (xy 374.476264 -217.038429)
			(xy 374.476772 -217.064336) (xy 375.696988 -217.064336) (xy 375.697496 -217.038429) (xy 375.705602 -216.987252)
			(xy 375.721614 -216.937973) (xy 375.745137 -216.891806) (xy 375.775593 -216.849887) (xy 375.812231 -216.813249)
			(xy 375.85415 -216.782793) (xy 375.900317 -216.75927) (xy 375.949596 -216.743258) (xy 376.000773 -216.735152)
			(xy 376.052587 -216.735152) (xy 376.103764 -216.743258) (xy 376.153043 -216.75927) (xy 376.19921 -216.782793)
			(xy 376.241129 -216.813249) (xy 376.277767 -216.849887) (xy 376.308223 -216.891806) (xy 376.331746 -216.937973)
			(xy 376.347758 -216.987252) (xy 376.355864 -217.038429) (xy 376.356372 -217.064336) (xy 377.576588 -217.064336)
			(xy 377.577096 -217.038429) (xy 377.585202 -216.987252) (xy 377.601214 -216.937973) (xy 377.624737 -216.891806)
			(xy 377.655193 -216.849887) (xy 377.691831 -216.813249) (xy 377.73375 -216.782793) (xy 377.779917 -216.75927)
			(xy 377.829196 -216.743258) (xy 377.880373 -216.735152) (xy 377.932187 -216.735152) (xy 377.983364 -216.743258)
			(xy 378.032643 -216.75927) (xy 378.07881 -216.782793) (xy 378.120729 -216.813249) (xy 378.157367 -216.849887)
			(xy 378.187823 -216.891806) (xy 378.211346 -216.937973) (xy 378.227358 -216.987252) (xy 378.235464 -217.038429)
			(xy 378.235972 -217.064336) (xy 379.456188 -217.064336) (xy 379.456696 -217.038429) (xy 379.464802 -216.987252)
			(xy 379.480814 -216.937973) (xy 379.504337 -216.891806) (xy 379.534793 -216.849887) (xy 379.571431 -216.813249)
			(xy 379.61335 -216.782793) (xy 379.659517 -216.75927) (xy 379.708796 -216.743258) (xy 379.759973 -216.735152)
			(xy 379.811787 -216.735152) (xy 379.862964 -216.743258) (xy 379.912243 -216.75927) (xy 379.95841 -216.782793)
			(xy 380.000329 -216.813249) (xy 380.036967 -216.849887) (xy 380.067423 -216.891806) (xy 380.090946 -216.937973)
			(xy 380.106958 -216.987252) (xy 380.115064 -217.038429) (xy 380.115572 -217.064336) (xy 381.335788 -217.064336)
			(xy 381.336296 -217.038429) (xy 381.344402 -216.987252) (xy 381.360414 -216.937973) (xy 381.383937 -216.891806)
			(xy 381.414393 -216.849887) (xy 381.451031 -216.813249) (xy 381.49295 -216.782793) (xy 381.539117 -216.75927)
			(xy 381.588396 -216.743258) (xy 381.639573 -216.735152) (xy 381.691387 -216.735152) (xy 381.742564 -216.743258)
			(xy 381.791843 -216.75927) (xy 381.83801 -216.782793) (xy 381.879929 -216.813249) (xy 381.916567 -216.849887)
			(xy 381.947023 -216.891806) (xy 381.970546 -216.937973) (xy 381.986558 -216.987252) (xy 381.994664 -217.038429)
			(xy 381.995172 -217.064336) (xy 381.994559 -217.091989) (xy 381.985238 -217.146507) (xy 381.97663 -217.172794)
			(xy 381.96901 -217.194892) (xy 382.174242 -217.550238) (xy 382.197102 -217.554556) (xy 382.221903 -217.559751)
			(xy 382.269642 -217.57674) (xy 382.314219 -217.600833) (xy 382.354584 -217.631463) (xy 382.389788 -217.667908)
			(xy 382.419 -217.709312) (xy 382.441533 -217.754697) (xy 382.456856 -217.802996) (xy 382.464608 -217.85307)
			(xy 382.465072 -217.878406) (xy 382.464564 -217.904293) (xy 382.456465 -217.955431) (xy 382.440466 -218.004671)
			(xy 382.41696 -218.050803) (xy 382.386528 -218.09269) (xy 382.349918 -218.1293) (xy 382.308031 -218.159732)
			(xy 382.261899 -218.183238) (xy 382.212659 -218.199237) (xy 382.161521 -218.207336) (xy 382.109747 -218.207336)
			(xy 382.058609 -218.199237) (xy 382.009369 -218.183238) (xy 381.963237 -218.159732) (xy 381.92135 -218.1293)
			(xy 381.88474 -218.09269) (xy 381.854308 -218.050803) (xy 381.830802 -218.004671) (xy 381.814803 -217.955431)
			(xy 381.806704 -217.904293) (xy 381.806196 -217.878406) (xy 381.806727 -217.850698) (xy 381.815921 -217.796051)
			(xy 381.824484 -217.769694) (xy 381.832358 -217.747596) (xy 381.62738 -217.392504) (xy 381.60452 -217.388186)
			(xy 381.579675 -217.38302) (xy 381.531826 -217.366126) (xy 381.487133 -217.342096) (xy 381.446653 -217.311499)
			(xy 381.411341 -217.275058) (xy 381.382033 -217.233634) (xy 381.359422 -217.188207) (xy 381.344043 -217.13985)
			(xy 381.336258 -217.089708) (xy 381.335788 -217.064336) (xy 380.115572 -217.064336) (xy 380.114959 -217.091989)
			(xy 380.105638 -217.146507) (xy 380.09703 -217.172794) (xy 380.08941 -217.194892) (xy 380.294642 -217.550238)
			(xy 380.317502 -217.554556) (xy 380.342303 -217.559751) (xy 380.390042 -217.57674) (xy 380.434619 -217.600833)
			(xy 380.474984 -217.631463) (xy 380.510188 -217.667908) (xy 380.5394 -217.709312) (xy 380.561933 -217.754697)
			(xy 380.577256 -217.802996) (xy 380.585008 -217.85307) (xy 380.585472 -217.878406) (xy 380.584964 -217.904293)
			(xy 380.576865 -217.955431) (xy 380.560866 -218.004671) (xy 380.53736 -218.050803) (xy 380.506928 -218.09269)
			(xy 380.470318 -218.1293) (xy 380.428431 -218.159732) (xy 380.382299 -218.183238) (xy 380.333059 -218.199237)
			(xy 380.281921 -218.207336) (xy 380.230147 -218.207336) (xy 380.179009 -218.199237) (xy 380.129769 -218.183238)
			(xy 380.083637 -218.159732) (xy 380.04175 -218.1293) (xy 380.00514 -218.09269) (xy 379.974708 -218.050803)
			(xy 379.951202 -218.004671) (xy 379.935203 -217.955431) (xy 379.927104 -217.904293) (xy 379.926596 -217.878406)
			(xy 379.927127 -217.850698) (xy 379.936321 -217.796051) (xy 379.944884 -217.769694) (xy 379.952758 -217.747596)
			(xy 379.74778 -217.392504) (xy 379.72492 -217.388186) (xy 379.700075 -217.38302) (xy 379.652226 -217.366126)
			(xy 379.607533 -217.342096) (xy 379.567053 -217.311499) (xy 379.531741 -217.275058) (xy 379.502433 -217.233634)
			(xy 379.479822 -217.188207) (xy 379.464443 -217.13985) (xy 379.456658 -217.089708) (xy 379.456188 -217.064336)
			(xy 378.235972 -217.064336) (xy 378.235359 -217.091989) (xy 378.226038 -217.146507) (xy 378.21743 -217.172794)
			(xy 378.20981 -217.194892) (xy 378.415042 -217.550238) (xy 378.437902 -217.554556) (xy 378.462703 -217.559751)
			(xy 378.510442 -217.57674) (xy 378.555019 -217.600833) (xy 378.595384 -217.631463) (xy 378.630588 -217.667908)
			(xy 378.6598 -217.709312) (xy 378.682333 -217.754697) (xy 378.697656 -217.802996) (xy 378.705408 -217.85307)
			(xy 378.705872 -217.878406) (xy 378.705364 -217.904293) (xy 378.697265 -217.955431) (xy 378.681266 -218.004671)
			(xy 378.65776 -218.050803) (xy 378.627328 -218.09269) (xy 378.590718 -218.1293) (xy 378.548831 -218.159732)
			(xy 378.502699 -218.183238) (xy 378.453459 -218.199237) (xy 378.402321 -218.207336) (xy 378.350547 -218.207336)
			(xy 378.299409 -218.199237) (xy 378.250169 -218.183238) (xy 378.204037 -218.159732) (xy 378.16215 -218.1293)
			(xy 378.12554 -218.09269) (xy 378.095108 -218.050803) (xy 378.071602 -218.004671) (xy 378.055603 -217.955431)
			(xy 378.047504 -217.904293) (xy 378.046996 -217.878406) (xy 378.047527 -217.850698) (xy 378.056721 -217.796051)
			(xy 378.065284 -217.769694) (xy 378.073158 -217.747596) (xy 377.86818 -217.392504) (xy 377.84532 -217.388186)
			(xy 377.820475 -217.38302) (xy 377.772626 -217.366126) (xy 377.727933 -217.342096) (xy 377.687453 -217.311499)
			(xy 377.652141 -217.275058) (xy 377.622833 -217.233634) (xy 377.600222 -217.188207) (xy 377.584843 -217.13985)
			(xy 377.577058 -217.089708) (xy 377.576588 -217.064336) (xy 376.356372 -217.064336) (xy 376.355759 -217.091989)
			(xy 376.346438 -217.146507) (xy 376.33783 -217.172794) (xy 376.33021 -217.194892) (xy 376.535442 -217.550238)
			(xy 376.558302 -217.554556) (xy 376.583103 -217.559751) (xy 376.630842 -217.57674) (xy 376.675419 -217.600833)
			(xy 376.715784 -217.631463) (xy 376.750988 -217.667908) (xy 376.7802 -217.709312) (xy 376.802733 -217.754697)
			(xy 376.818056 -217.802996) (xy 376.825808 -217.85307) (xy 376.826272 -217.878406) (xy 376.825764 -217.904293)
			(xy 376.817665 -217.955431) (xy 376.801666 -218.004671) (xy 376.77816 -218.050803) (xy 376.747728 -218.09269)
			(xy 376.711118 -218.1293) (xy 376.669231 -218.159732) (xy 376.623099 -218.183238) (xy 376.573859 -218.199237)
			(xy 376.522721 -218.207336) (xy 376.470947 -218.207336) (xy 376.419809 -218.199237) (xy 376.370569 -218.183238)
			(xy 376.324437 -218.159732) (xy 376.28255 -218.1293) (xy 376.24594 -218.09269) (xy 376.215508 -218.050803)
			(xy 376.192002 -218.004671) (xy 376.176003 -217.955431) (xy 376.167904 -217.904293) (xy 376.167396 -217.878406)
			(xy 376.167927 -217.850698) (xy 376.177121 -217.796051) (xy 376.185684 -217.769694) (xy 376.193558 -217.747596)
			(xy 375.98858 -217.392504) (xy 375.96572 -217.388186) (xy 375.940875 -217.38302) (xy 375.893026 -217.366126)
			(xy 375.848333 -217.342096) (xy 375.807853 -217.311499) (xy 375.772541 -217.275058) (xy 375.743233 -217.233634)
			(xy 375.720622 -217.188207) (xy 375.705243 -217.13985) (xy 375.697458 -217.089708) (xy 375.696988 -217.064336)
			(xy 374.476772 -217.064336) (xy 374.476159 -217.091989) (xy 374.466838 -217.146507) (xy 374.45823 -217.172794)
			(xy 374.45061 -217.194892) (xy 374.655842 -217.550238) (xy 374.678702 -217.554556) (xy 374.703503 -217.559751)
			(xy 374.751242 -217.57674) (xy 374.795819 -217.600833) (xy 374.836184 -217.631463) (xy 374.871388 -217.667908)
			(xy 374.9006 -217.709312) (xy 374.923133 -217.754697) (xy 374.938456 -217.802996) (xy 374.946208 -217.85307)
			(xy 374.946672 -217.878406) (xy 374.946164 -217.904293) (xy 374.938065 -217.955431) (xy 374.922066 -218.004671)
			(xy 374.89856 -218.050803) (xy 374.868128 -218.09269) (xy 374.831518 -218.1293) (xy 374.789631 -218.159732)
			(xy 374.743499 -218.183238) (xy 374.694259 -218.199237) (xy 374.643121 -218.207336) (xy 374.591347 -218.207336)
			(xy 374.540209 -218.199237) (xy 374.490969 -218.183238) (xy 374.444837 -218.159732) (xy 374.40295 -218.1293)
			(xy 374.36634 -218.09269) (xy 374.335908 -218.050803) (xy 374.312402 -218.004671) (xy 374.296403 -217.955431)
			(xy 374.288304 -217.904293) (xy 374.287796 -217.878406) (xy 374.288327 -217.850698) (xy 374.297521 -217.796051)
			(xy 374.306084 -217.769694) (xy 374.313958 -217.747596) (xy 374.10898 -217.392504) (xy 374.08612 -217.388186)
			(xy 374.061275 -217.38302) (xy 374.013426 -217.366126) (xy 373.968733 -217.342096) (xy 373.928253 -217.311499)
			(xy 373.892941 -217.275058) (xy 373.863633 -217.233634) (xy 373.841022 -217.188207) (xy 373.825643 -217.13985)
			(xy 373.817858 -217.089708) (xy 373.817388 -217.064336) (xy 372.597172 -217.064336) (xy 372.596559 -217.091989)
			(xy 372.587238 -217.146507) (xy 372.57863 -217.172794) (xy 372.57101 -217.194892) (xy 372.776242 -217.550238)
			(xy 372.799102 -217.554556) (xy 372.823903 -217.559751) (xy 372.871642 -217.57674) (xy 372.916219 -217.600833)
			(xy 372.956584 -217.631463) (xy 372.991788 -217.667908) (xy 373.021 -217.709312) (xy 373.043533 -217.754697)
			(xy 373.058856 -217.802996) (xy 373.066608 -217.85307) (xy 373.067072 -217.878406) (xy 373.066564 -217.904293)
			(xy 373.058465 -217.955431) (xy 373.042466 -218.004671) (xy 373.01896 -218.050803) (xy 372.988528 -218.09269)
			(xy 372.951918 -218.1293) (xy 372.910031 -218.159732) (xy 372.863899 -218.183238) (xy 372.814659 -218.199237)
			(xy 372.763521 -218.207336) (xy 372.711747 -218.207336) (xy 372.660609 -218.199237) (xy 372.611369 -218.183238)
			(xy 372.565237 -218.159732) (xy 372.52335 -218.1293) (xy 372.48674 -218.09269) (xy 372.456308 -218.050803)
			(xy 372.432802 -218.004671) (xy 372.416803 -217.955431) (xy 372.408704 -217.904293) (xy 372.408196 -217.878406)
			(xy 372.408727 -217.850698) (xy 372.417921 -217.796051) (xy 372.426484 -217.769694) (xy 372.434358 -217.747596)
			(xy 372.22938 -217.392504) (xy 372.20652 -217.388186) (xy 372.181675 -217.38302) (xy 372.133826 -217.366126)
			(xy 372.089133 -217.342096) (xy 372.048653 -217.311499) (xy 372.013341 -217.275058) (xy 371.984033 -217.233634)
			(xy 371.961422 -217.188207) (xy 371.946043 -217.13985) (xy 371.938258 -217.089708) (xy 371.937788 -217.064336)
			(xy 370.717572 -217.064336) (xy 370.716959 -217.091989) (xy 370.707638 -217.146507) (xy 370.69903 -217.172794)
			(xy 370.69141 -217.194892) (xy 370.896642 -217.550238) (xy 370.919502 -217.554556) (xy 370.944303 -217.559751)
			(xy 370.992042 -217.57674) (xy 371.036619 -217.600833) (xy 371.076984 -217.631463) (xy 371.112188 -217.667908)
			(xy 371.1414 -217.709312) (xy 371.163933 -217.754697) (xy 371.179256 -217.802996) (xy 371.187008 -217.85307)
			(xy 371.187472 -217.878406) (xy 371.186964 -217.904293) (xy 371.178865 -217.955431) (xy 371.162866 -218.004671)
			(xy 371.13936 -218.050803) (xy 371.108928 -218.09269) (xy 371.072318 -218.1293) (xy 371.030431 -218.159732)
			(xy 370.984299 -218.183238) (xy 370.935059 -218.199237) (xy 370.883921 -218.207336) (xy 370.832147 -218.207336)
			(xy 370.781009 -218.199237) (xy 370.731769 -218.183238) (xy 370.685637 -218.159732) (xy 370.64375 -218.1293)
			(xy 370.60714 -218.09269) (xy 370.576708 -218.050803) (xy 370.553202 -218.004671) (xy 370.537203 -217.955431)
			(xy 370.529104 -217.904293) (xy 370.528596 -217.878406) (xy 370.529127 -217.850698) (xy 370.538321 -217.796051)
			(xy 370.546884 -217.769694) (xy 370.554758 -217.747596) (xy 370.34978 -217.392504) (xy 370.32692 -217.388186)
			(xy 370.302075 -217.38302) (xy 370.254226 -217.366126) (xy 370.209533 -217.342096) (xy 370.169053 -217.311499)
			(xy 370.133741 -217.275058) (xy 370.104433 -217.233634) (xy 370.081822 -217.188207) (xy 370.066443 -217.13985)
			(xy 370.058658 -217.089708) (xy 370.058188 -217.064336) (xy 368.837972 -217.064336) (xy 368.837359 -217.091989)
			(xy 368.828038 -217.146507) (xy 368.81943 -217.172794) (xy 368.81181 -217.194892) (xy 369.017042 -217.550238)
			(xy 369.039902 -217.554556) (xy 369.064703 -217.559751) (xy 369.112442 -217.57674) (xy 369.157019 -217.600833)
			(xy 369.197384 -217.631463) (xy 369.232588 -217.667908) (xy 369.2618 -217.709312) (xy 369.284333 -217.754697)
			(xy 369.299656 -217.802996) (xy 369.307408 -217.85307) (xy 369.307872 -217.878406) (xy 369.307364 -217.904293)
			(xy 369.299265 -217.955431) (xy 369.283266 -218.004671) (xy 369.25976 -218.050803) (xy 369.229328 -218.09269)
			(xy 369.192718 -218.1293) (xy 369.150831 -218.159732) (xy 369.104699 -218.183238) (xy 369.055459 -218.199237)
			(xy 369.004321 -218.207336) (xy 368.952547 -218.207336) (xy 368.901409 -218.199237) (xy 368.852169 -218.183238)
			(xy 368.806037 -218.159732) (xy 368.76415 -218.1293) (xy 368.72754 -218.09269) (xy 368.697108 -218.050803)
			(xy 368.673602 -218.004671) (xy 368.657603 -217.955431) (xy 368.649504 -217.904293) (xy 368.648996 -217.878406)
			(xy 368.649527 -217.850698) (xy 368.658721 -217.796051) (xy 368.667284 -217.769694) (xy 368.675158 -217.747596)
			(xy 368.47018 -217.392504) (xy 368.44732 -217.388186) (xy 368.422475 -217.38302) (xy 368.374626 -217.366126)
			(xy 368.329933 -217.342096) (xy 368.289453 -217.311499) (xy 368.254141 -217.275058) (xy 368.224833 -217.233634)
			(xy 368.202222 -217.188207) (xy 368.186843 -217.13985) (xy 368.179058 -217.089708) (xy 368.178588 -217.064336)
			(xy 366.958372 -217.064336) (xy 366.957759 -217.091989) (xy 366.948438 -217.146507) (xy 366.93983 -217.172794)
			(xy 366.93221 -217.194892) (xy 367.137442 -217.550238) (xy 367.160302 -217.554556) (xy 367.185103 -217.559751)
			(xy 367.232842 -217.57674) (xy 367.277419 -217.600833) (xy 367.317784 -217.631463) (xy 367.352988 -217.667908)
			(xy 367.3822 -217.709312) (xy 367.404733 -217.754697) (xy 367.420056 -217.802996) (xy 367.427808 -217.85307)
			(xy 367.428272 -217.878406) (xy 367.427764 -217.904293) (xy 367.419665 -217.955431) (xy 367.403666 -218.004671)
			(xy 367.38016 -218.050803) (xy 367.349728 -218.09269) (xy 367.313118 -218.1293) (xy 367.271231 -218.159732)
			(xy 367.225099 -218.183238) (xy 367.175859 -218.199237) (xy 367.124721 -218.207336) (xy 367.072947 -218.207336)
			(xy 367.021809 -218.199237) (xy 366.972569 -218.183238) (xy 366.926437 -218.159732) (xy 366.88455 -218.1293)
			(xy 366.84794 -218.09269) (xy 366.817508 -218.050803) (xy 366.794002 -218.004671) (xy 366.778003 -217.955431)
			(xy 366.769904 -217.904293) (xy 366.769396 -217.878406) (xy 366.769927 -217.850698) (xy 366.779121 -217.796051)
			(xy 366.787684 -217.769694) (xy 366.795558 -217.747596) (xy 366.59058 -217.392504) (xy 366.56772 -217.388186)
			(xy 366.542875 -217.38302) (xy 366.495026 -217.366126) (xy 366.450333 -217.342096) (xy 366.409853 -217.311499)
			(xy 366.374541 -217.275058) (xy 366.345233 -217.233634) (xy 366.322622 -217.188207) (xy 366.307243 -217.13985)
			(xy 366.299458 -217.089708) (xy 366.298988 -217.064336) (xy 365.078772 -217.064336) (xy 365.078159 -217.091989)
			(xy 365.068838 -217.146507) (xy 365.06023 -217.172794) (xy 365.05261 -217.194892) (xy 365.257842 -217.550238)
			(xy 365.280702 -217.554556) (xy 365.305503 -217.559751) (xy 365.353242 -217.57674) (xy 365.397819 -217.600833)
			(xy 365.438184 -217.631463) (xy 365.473388 -217.667908) (xy 365.5026 -217.709312) (xy 365.525133 -217.754697)
			(xy 365.540456 -217.802996) (xy 365.548208 -217.85307) (xy 365.548672 -217.878406) (xy 365.548164 -217.904293)
			(xy 365.540065 -217.955431) (xy 365.524066 -218.004671) (xy 365.50056 -218.050803) (xy 365.470128 -218.09269)
			(xy 365.433518 -218.1293) (xy 365.391631 -218.159732) (xy 365.345499 -218.183238) (xy 365.296259 -218.199237)
			(xy 365.245121 -218.207336) (xy 365.193347 -218.207336) (xy 365.142209 -218.199237) (xy 365.092969 -218.183238)
			(xy 365.046837 -218.159732) (xy 365.00495 -218.1293) (xy 364.96834 -218.09269) (xy 364.937908 -218.050803)
			(xy 364.914402 -218.004671) (xy 364.898403 -217.955431) (xy 364.890304 -217.904293) (xy 364.889796 -217.878406)
			(xy 364.890327 -217.850698) (xy 364.899521 -217.796051) (xy 364.908084 -217.769694) (xy 364.915958 -217.747596)
			(xy 364.71098 -217.392504) (xy 364.68812 -217.388186) (xy 364.663275 -217.38302) (xy 364.615426 -217.366126)
			(xy 364.570733 -217.342096) (xy 364.530253 -217.311499) (xy 364.494941 -217.275058) (xy 364.465633 -217.233634)
			(xy 364.443022 -217.188207) (xy 364.427643 -217.13985) (xy 364.419858 -217.089708) (xy 364.419388 -217.064336)
			(xy 363.199172 -217.064336) (xy 363.198559 -217.091989) (xy 363.189238 -217.146507) (xy 363.18063 -217.172794)
			(xy 363.17301 -217.194892) (xy 363.378242 -217.550238) (xy 363.401102 -217.554556) (xy 363.425903 -217.559751)
			(xy 363.473642 -217.57674) (xy 363.518219 -217.600833) (xy 363.558584 -217.631463) (xy 363.593788 -217.667908)
			(xy 363.623 -217.709312) (xy 363.645533 -217.754697) (xy 363.660856 -217.802996) (xy 363.668608 -217.85307)
			(xy 363.669072 -217.878406) (xy 363.668564 -217.904293) (xy 363.660465 -217.955431) (xy 363.644466 -218.004671)
			(xy 363.62096 -218.050803) (xy 363.590528 -218.09269) (xy 363.553918 -218.1293) (xy 363.512031 -218.159732)
			(xy 363.465899 -218.183238) (xy 363.416659 -218.199237) (xy 363.365521 -218.207336) (xy 363.313747 -218.207336)
			(xy 363.262609 -218.199237) (xy 363.213369 -218.183238) (xy 363.167237 -218.159732) (xy 363.12535 -218.1293)
			(xy 363.08874 -218.09269) (xy 363.058308 -218.050803) (xy 363.034802 -218.004671) (xy 363.018803 -217.955431)
			(xy 363.010704 -217.904293) (xy 363.010196 -217.878406) (xy 363.010727 -217.850698) (xy 363.019921 -217.796051)
			(xy 363.028484 -217.769694) (xy 363.036358 -217.747596) (xy 362.83138 -217.392504) (xy 362.80852 -217.388186)
			(xy 362.783675 -217.38302) (xy 362.735826 -217.366126) (xy 362.691133 -217.342096) (xy 362.650653 -217.311499)
			(xy 362.615341 -217.275058) (xy 362.586033 -217.233634) (xy 362.563422 -217.188207) (xy 362.548043 -217.13985)
			(xy 362.540258 -217.089708) (xy 362.539788 -217.064336) (xy 361.319572 -217.064336) (xy 361.318959 -217.091989)
			(xy 361.309638 -217.146507) (xy 361.30103 -217.172794) (xy 361.29341 -217.194892) (xy 361.498642 -217.550238)
			(xy 361.521502 -217.554556) (xy 361.546303 -217.559751) (xy 361.594042 -217.57674) (xy 361.638619 -217.600833)
			(xy 361.678984 -217.631463) (xy 361.714188 -217.667908) (xy 361.7434 -217.709312) (xy 361.765933 -217.754697)
			(xy 361.781256 -217.802996) (xy 361.789008 -217.85307) (xy 361.789472 -217.878406) (xy 361.788964 -217.904293)
			(xy 361.780865 -217.955431) (xy 361.764866 -218.004671) (xy 361.74136 -218.050803) (xy 361.710928 -218.09269)
			(xy 361.674318 -218.1293) (xy 361.632431 -218.159732) (xy 361.586299 -218.183238) (xy 361.537059 -218.199237)
			(xy 361.485921 -218.207336) (xy 361.434147 -218.207336) (xy 361.383009 -218.199237) (xy 361.333769 -218.183238)
			(xy 361.287637 -218.159732) (xy 361.24575 -218.1293) (xy 361.20914 -218.09269) (xy 361.178708 -218.050803)
			(xy 361.155202 -218.004671) (xy 361.139203 -217.955431) (xy 361.131104 -217.904293) (xy 361.130596 -217.878406)
			(xy 361.131127 -217.850698) (xy 361.140321 -217.796051) (xy 361.148884 -217.769694) (xy 361.156758 -217.747596)
			(xy 360.95178 -217.392504) (xy 360.92892 -217.388186) (xy 360.904075 -217.38302) (xy 360.856226 -217.366126)
			(xy 360.811533 -217.342096) (xy 360.771053 -217.311499) (xy 360.735741 -217.275058) (xy 360.706433 -217.233634)
			(xy 360.683822 -217.188207) (xy 360.668443 -217.13985) (xy 360.660658 -217.089708) (xy 360.660188 -217.064336)
			(xy 359.439972 -217.064336) (xy 359.439506 -217.089682) (xy 359.431728 -217.139773) (xy 359.416377 -217.188085)
			(xy 359.393813 -217.233478) (xy 359.364569 -217.274884) (xy 359.329334 -217.311328) (xy 359.288936 -217.34195)
			(xy 359.244329 -217.36603) (xy 359.196562 -217.383) (xy 359.171748 -217.388186) (xy 359.148888 -217.392504)
			(xy 358.94391 -217.747596) (xy 358.951784 -217.76944) (xy 358.960373 -217.795856) (xy 358.969563 -217.850633)
			(xy 358.970072 -217.878406) (xy 358.969564 -217.904293) (xy 358.961465 -217.955431) (xy 358.945466 -218.004671)
			(xy 358.92196 -218.050803) (xy 358.891528 -218.09269) (xy 358.854918 -218.1293) (xy 358.813031 -218.159732)
			(xy 358.766899 -218.183238) (xy 358.717659 -218.199237) (xy 358.666521 -218.207336) (xy 358.614747 -218.207336)
			(xy 358.563609 -218.199237) (xy 358.514369 -218.183238) (xy 358.468237 -218.159732) (xy 358.42635 -218.1293)
			(xy 358.38974 -218.09269) (xy 358.359308 -218.050803) (xy 358.335802 -218.004671) (xy 358.319803 -217.955431)
			(xy 358.311704 -217.904293) (xy 358.311196 -217.878406) (xy 358.030272 -217.878406) (xy 358.029741 -217.906114)
			(xy 358.020546 -217.960761) (xy 358.011984 -217.987118) (xy 358.004364 -218.008962) (xy 358.209342 -218.364054)
			(xy 358.232202 -218.368372) (xy 358.257007 -218.373552) (xy 358.304747 -218.390542) (xy 358.349324 -218.414636)
			(xy 358.38969 -218.445268) (xy 358.424894 -218.481716) (xy 358.454106 -218.523121) (xy 358.476638 -218.568508)
			(xy 358.491959 -218.616809) (xy 358.49971 -218.666886) (xy 358.500172 -218.692222) (xy 359.720388 -218.692222)
			(xy 359.720939 -218.66688) (xy 359.728707 -218.616793) (xy 359.744048 -218.568485) (xy 359.766601 -218.523094)
			(xy 359.795834 -218.481689) (xy 359.831059 -218.445245) (xy 359.871446 -218.41462) (xy 359.916044 -218.390537)
			(xy 359.963802 -218.373561) (xy 359.988612 -218.368372) (xy 360.011472 -218.364054) (xy 360.216704 -218.008708)
			(xy 360.20883 -217.98661) (xy 360.200361 -217.960367) (xy 360.191292 -217.905977) (xy 360.190796 -217.878406)
			(xy 360.191304 -217.852519) (xy 360.199403 -217.801381) (xy 360.215402 -217.752141) (xy 360.238908 -217.706009)
			(xy 360.26934 -217.664122) (xy 360.30595 -217.627512) (xy 360.347837 -217.59708) (xy 360.393969 -217.573574)
			(xy 360.443209 -217.557575) (xy 360.494347 -217.549476) (xy 360.546121 -217.549476) (xy 360.597259 -217.557575)
			(xy 360.646499 -217.573574) (xy 360.692631 -217.59708) (xy 360.734518 -217.627512) (xy 360.771128 -217.664122)
			(xy 360.80156 -217.706009) (xy 360.825066 -217.752141) (xy 360.841065 -217.801381) (xy 360.849164 -217.852519)
			(xy 360.849672 -217.878406) (xy 360.849225 -217.903782) (xy 360.841455 -217.953934) (xy 360.826085 -218.002302)
			(xy 360.803477 -218.047739) (xy 360.774167 -218.089171) (xy 360.73885 -218.125617) (xy 360.69836 -218.156215)
			(xy 360.653656 -218.18024) (xy 360.605796 -218.197124) (xy 360.58094 -218.202256) (xy 360.55808 -218.206574)
			(xy 360.353356 -218.561412) (xy 360.36123 -218.583256) (xy 360.369881 -218.609663) (xy 360.379198 -218.66444)
			(xy 360.379772 -218.692222) (xy 361.600496 -218.692222) (xy 361.601002 -218.666888) (xy 361.608751 -218.616817)
			(xy 361.62407 -218.568521) (xy 361.646599 -218.523138) (xy 361.675805 -218.481736) (xy 361.711003 -218.44529)
			(xy 361.751363 -218.414659) (xy 361.795934 -218.390564) (xy 361.843667 -218.373572) (xy 361.868466 -218.368372)
			(xy 361.891326 -218.364054) (xy 362.096304 -218.008962) (xy 362.088684 -217.986864) (xy 362.080159 -217.960694)
			(xy 362.070969 -217.906431) (xy 362.070396 -217.878914) (xy 362.070396 -217.878406) (xy 362.070904 -217.852519)
			(xy 362.079003 -217.801381) (xy 362.095002 -217.752141) (xy 362.118508 -217.706009) (xy 362.14894 -217.664122)
			(xy 362.18555 -217.627512) (xy 362.227437 -217.59708) (xy 362.273569 -217.573574) (xy 362.322809 -217.557575)
			(xy 362.373947 -217.549476) (xy 362.425721 -217.549476) (xy 362.476859 -217.557575) (xy 362.526099 -217.573574)
			(xy 362.572231 -217.59708) (xy 362.614118 -217.627512) (xy 362.650728 -217.664122) (xy 362.68116 -217.706009)
			(xy 362.704666 -217.752141) (xy 362.720665 -217.801381) (xy 362.728764 -217.852519) (xy 362.729272 -217.878406)
			(xy 362.728863 -217.903772) (xy 362.721112 -217.953909) (xy 362.705764 -218.002264) (xy 362.683182 -218.047694)
			(xy 362.6539 -218.089122) (xy 362.61861 -218.12557) (xy 362.578149 -218.156175) (xy 362.533472 -218.180212)
			(xy 362.485638 -218.197113) (xy 362.460794 -218.202256) (xy 362.437934 -218.206574) (xy 362.23321 -218.561412)
			(xy 362.241084 -218.583256) (xy 362.249677 -218.609671) (xy 362.258865 -218.664449) (xy 362.259372 -218.692222)
			(xy 363.479588 -218.692222) (xy 363.480139 -218.66688) (xy 363.487907 -218.616793) (xy 363.503248 -218.568485)
			(xy 363.525801 -218.523094) (xy 363.555034 -218.481689) (xy 363.590259 -218.445245) (xy 363.630646 -218.41462)
			(xy 363.675244 -218.390537) (xy 363.723002 -218.373561) (xy 363.747812 -218.368372) (xy 363.770672 -218.364054)
			(xy 363.975904 -218.008708) (xy 363.96803 -217.98661) (xy 363.959561 -217.960367) (xy 363.950492 -217.905977)
			(xy 363.949996 -217.878406) (xy 363.950504 -217.852519) (xy 363.958603 -217.801381) (xy 363.974602 -217.752141)
			(xy 363.998108 -217.706009) (xy 364.02854 -217.664122) (xy 364.06515 -217.627512) (xy 364.107037 -217.59708)
			(xy 364.153169 -217.573574) (xy 364.202409 -217.557575) (xy 364.253547 -217.549476) (xy 364.305321 -217.549476)
			(xy 364.356459 -217.557575) (xy 364.405699 -217.573574) (xy 364.451831 -217.59708) (xy 364.493718 -217.627512)
			(xy 364.530328 -217.664122) (xy 364.56076 -217.706009) (xy 364.584266 -217.752141) (xy 364.600265 -217.801381)
			(xy 364.608364 -217.852519) (xy 364.608872 -217.878406) (xy 364.608425 -217.903782) (xy 364.600655 -217.953934)
			(xy 364.585285 -218.002302) (xy 364.562677 -218.047739) (xy 364.533367 -218.089171) (xy 364.49805 -218.125617)
			(xy 364.45756 -218.156215) (xy 364.412856 -218.18024) (xy 364.364996 -218.197124) (xy 364.34014 -218.202256)
			(xy 364.31728 -218.206574) (xy 364.112556 -218.561412) (xy 364.12043 -218.583256) (xy 364.129081 -218.609663)
			(xy 364.138398 -218.66444) (xy 364.138972 -218.692222) (xy 365.359188 -218.692222) (xy 365.359739 -218.66688)
			(xy 365.367507 -218.616793) (xy 365.382848 -218.568485) (xy 365.405401 -218.523094) (xy 365.434634 -218.481689)
			(xy 365.469859 -218.445245) (xy 365.510246 -218.41462) (xy 365.554844 -218.390537) (xy 365.602602 -218.373561)
			(xy 365.627412 -218.368372) (xy 365.650272 -218.364054) (xy 365.855504 -218.008708) (xy 365.84763 -217.98661)
			(xy 365.839161 -217.960367) (xy 365.830092 -217.905977) (xy 365.829596 -217.878406) (xy 365.830104 -217.852519)
			(xy 365.838203 -217.801381) (xy 365.854202 -217.752141) (xy 365.877708 -217.706009) (xy 365.90814 -217.664122)
			(xy 365.94475 -217.627512) (xy 365.986637 -217.59708) (xy 366.032769 -217.573574) (xy 366.082009 -217.557575)
			(xy 366.133147 -217.549476) (xy 366.184921 -217.549476) (xy 366.236059 -217.557575) (xy 366.285299 -217.573574)
			(xy 366.331431 -217.59708) (xy 366.373318 -217.627512) (xy 366.409928 -217.664122) (xy 366.44036 -217.706009)
			(xy 366.463866 -217.752141) (xy 366.479865 -217.801381) (xy 366.487964 -217.852519) (xy 366.488472 -217.878406)
			(xy 366.488025 -217.903782) (xy 366.480255 -217.953934) (xy 366.464885 -218.002302) (xy 366.442277 -218.047739)
			(xy 366.412967 -218.089171) (xy 366.37765 -218.125617) (xy 366.33716 -218.156215) (xy 366.292456 -218.18024)
			(xy 366.244596 -218.197124) (xy 366.21974 -218.202256) (xy 366.19688 -218.206574) (xy 365.992156 -218.561412)
			(xy 366.00003 -218.583256) (xy 366.008681 -218.609663) (xy 366.017998 -218.66444) (xy 366.018572 -218.692222)
			(xy 367.238788 -218.692222) (xy 367.239339 -218.66688) (xy 367.247107 -218.616793) (xy 367.262448 -218.568485)
			(xy 367.285001 -218.523094) (xy 367.314234 -218.481689) (xy 367.349459 -218.445245) (xy 367.389846 -218.41462)
			(xy 367.434444 -218.390537) (xy 367.482202 -218.373561) (xy 367.507012 -218.368372) (xy 367.529872 -218.364054)
			(xy 367.735104 -218.008708) (xy 367.72723 -217.98661) (xy 367.718761 -217.960367) (xy 367.709692 -217.905977)
			(xy 367.709196 -217.878406) (xy 367.709704 -217.852519) (xy 367.717803 -217.801381) (xy 367.733802 -217.752141)
			(xy 367.757308 -217.706009) (xy 367.78774 -217.664122) (xy 367.82435 -217.627512) (xy 367.866237 -217.59708)
			(xy 367.912369 -217.573574) (xy 367.961609 -217.557575) (xy 368.012747 -217.549476) (xy 368.064521 -217.549476)
			(xy 368.115659 -217.557575) (xy 368.164899 -217.573574) (xy 368.211031 -217.59708) (xy 368.252918 -217.627512)
			(xy 368.289528 -217.664122) (xy 368.31996 -217.706009) (xy 368.343466 -217.752141) (xy 368.359465 -217.801381)
			(xy 368.367564 -217.852519) (xy 368.368072 -217.878406) (xy 368.367625 -217.903782) (xy 368.359855 -217.953934)
			(xy 368.344485 -218.002302) (xy 368.321877 -218.047739) (xy 368.292567 -218.089171) (xy 368.25725 -218.125617)
			(xy 368.21676 -218.156215) (xy 368.172056 -218.18024) (xy 368.124196 -218.197124) (xy 368.09934 -218.202256)
			(xy 368.07648 -218.206574) (xy 367.871756 -218.561412) (xy 367.87963 -218.583256) (xy 367.888281 -218.609663)
			(xy 367.897598 -218.66444) (xy 367.898172 -218.692222) (xy 369.118388 -218.692222) (xy 369.118939 -218.66688)
			(xy 369.126707 -218.616793) (xy 369.142048 -218.568485) (xy 369.164601 -218.523094) (xy 369.193834 -218.481689)
			(xy 369.229059 -218.445245) (xy 369.269446 -218.41462) (xy 369.314044 -218.390537) (xy 369.361802 -218.373561)
			(xy 369.386612 -218.368372) (xy 369.409472 -218.364054) (xy 369.614704 -218.008708) (xy 369.60683 -217.98661)
			(xy 369.598361 -217.960367) (xy 369.589292 -217.905977) (xy 369.588796 -217.878406) (xy 369.589304 -217.852519)
			(xy 369.597403 -217.801381) (xy 369.613402 -217.752141) (xy 369.636908 -217.706009) (xy 369.66734 -217.664122)
			(xy 369.70395 -217.627512) (xy 369.745837 -217.59708) (xy 369.791969 -217.573574) (xy 369.841209 -217.557575)
			(xy 369.892347 -217.549476) (xy 369.944121 -217.549476) (xy 369.995259 -217.557575) (xy 370.044499 -217.573574)
			(xy 370.090631 -217.59708) (xy 370.132518 -217.627512) (xy 370.169128 -217.664122) (xy 370.19956 -217.706009)
			(xy 370.223066 -217.752141) (xy 370.239065 -217.801381) (xy 370.247164 -217.852519) (xy 370.247672 -217.878406)
			(xy 370.247225 -217.903782) (xy 370.239455 -217.953934) (xy 370.224085 -218.002302) (xy 370.201477 -218.047739)
			(xy 370.172167 -218.089171) (xy 370.13685 -218.125617) (xy 370.09636 -218.156215) (xy 370.051656 -218.18024)
			(xy 370.003796 -218.197124) (xy 369.97894 -218.202256) (xy 369.95608 -218.206574) (xy 369.751356 -218.561412)
			(xy 369.75923 -218.583256) (xy 369.767881 -218.609663) (xy 369.777198 -218.66444) (xy 369.777772 -218.692222)
			(xy 370.997988 -218.692222) (xy 370.998539 -218.66688) (xy 371.006307 -218.616793) (xy 371.021648 -218.568485)
			(xy 371.044201 -218.523094) (xy 371.073434 -218.481689) (xy 371.108659 -218.445245) (xy 371.149046 -218.41462)
			(xy 371.193644 -218.390537) (xy 371.241402 -218.373561) (xy 371.266212 -218.368372) (xy 371.289072 -218.364054)
			(xy 371.494304 -218.008708) (xy 371.48643 -217.98661) (xy 371.477961 -217.960367) (xy 371.468892 -217.905977)
			(xy 371.468396 -217.878406) (xy 371.468904 -217.852519) (xy 371.477003 -217.801381) (xy 371.493002 -217.752141)
			(xy 371.516508 -217.706009) (xy 371.54694 -217.664122) (xy 371.58355 -217.627512) (xy 371.625437 -217.59708)
			(xy 371.671569 -217.573574) (xy 371.720809 -217.557575) (xy 371.771947 -217.549476) (xy 371.823721 -217.549476)
			(xy 371.874859 -217.557575) (xy 371.924099 -217.573574) (xy 371.970231 -217.59708) (xy 372.012118 -217.627512)
			(xy 372.048728 -217.664122) (xy 372.07916 -217.706009) (xy 372.102666 -217.752141) (xy 372.118665 -217.801381)
			(xy 372.126764 -217.852519) (xy 372.127272 -217.878406) (xy 372.126825 -217.903782) (xy 372.119055 -217.953934)
			(xy 372.103685 -218.002302) (xy 372.081077 -218.047739) (xy 372.051767 -218.089171) (xy 372.01645 -218.125617)
			(xy 371.97596 -218.156215) (xy 371.931256 -218.18024) (xy 371.883396 -218.197124) (xy 371.85854 -218.202256)
			(xy 371.83568 -218.206574) (xy 371.630956 -218.561412) (xy 371.63883 -218.583256) (xy 371.647481 -218.609663)
			(xy 371.656798 -218.66444) (xy 371.657372 -218.692222) (xy 372.877588 -218.692222) (xy 372.878139 -218.66688)
			(xy 372.885907 -218.616793) (xy 372.901248 -218.568485) (xy 372.923801 -218.523094) (xy 372.953034 -218.481689)
			(xy 372.988259 -218.445245) (xy 373.028646 -218.41462) (xy 373.073244 -218.390537) (xy 373.121002 -218.373561)
			(xy 373.145812 -218.368372) (xy 373.168672 -218.364054) (xy 373.373904 -218.008708) (xy 373.36603 -217.98661)
			(xy 373.357561 -217.960367) (xy 373.348492 -217.905977) (xy 373.347996 -217.878406) (xy 373.348504 -217.852519)
			(xy 373.356603 -217.801381) (xy 373.372602 -217.752141) (xy 373.396108 -217.706009) (xy 373.42654 -217.664122)
			(xy 373.46315 -217.627512) (xy 373.505037 -217.59708) (xy 373.551169 -217.573574) (xy 373.600409 -217.557575)
			(xy 373.651547 -217.549476) (xy 373.703321 -217.549476) (xy 373.754459 -217.557575) (xy 373.803699 -217.573574)
			(xy 373.849831 -217.59708) (xy 373.891718 -217.627512) (xy 373.928328 -217.664122) (xy 373.95876 -217.706009)
			(xy 373.982266 -217.752141) (xy 373.998265 -217.801381) (xy 374.006364 -217.852519) (xy 374.006872 -217.878406)
			(xy 374.006425 -217.903782) (xy 373.998655 -217.953934) (xy 373.983285 -218.002302) (xy 373.960677 -218.047739)
			(xy 373.931367 -218.089171) (xy 373.89605 -218.125617) (xy 373.85556 -218.156215) (xy 373.810856 -218.18024)
			(xy 373.762996 -218.197124) (xy 373.73814 -218.202256) (xy 373.71528 -218.206574) (xy 373.510556 -218.561412)
			(xy 373.51843 -218.583256) (xy 373.527081 -218.609663) (xy 373.536398 -218.66444) (xy 373.536972 -218.692222)
			(xy 374.757188 -218.692222) (xy 374.757739 -218.66688) (xy 374.765507 -218.616793) (xy 374.780848 -218.568485)
			(xy 374.803401 -218.523094) (xy 374.832634 -218.481689) (xy 374.867859 -218.445245) (xy 374.908246 -218.41462)
			(xy 374.952844 -218.390537) (xy 375.000602 -218.373561) (xy 375.025412 -218.368372) (xy 375.048272 -218.364054)
			(xy 375.253504 -218.008708) (xy 375.24563 -217.98661) (xy 375.237161 -217.960367) (xy 375.228092 -217.905977)
			(xy 375.227596 -217.878406) (xy 375.228104 -217.852519) (xy 375.236203 -217.801381) (xy 375.252202 -217.752141)
			(xy 375.275708 -217.706009) (xy 375.30614 -217.664122) (xy 375.34275 -217.627512) (xy 375.384637 -217.59708)
			(xy 375.430769 -217.573574) (xy 375.480009 -217.557575) (xy 375.531147 -217.549476) (xy 375.582921 -217.549476)
			(xy 375.634059 -217.557575) (xy 375.683299 -217.573574) (xy 375.729431 -217.59708) (xy 375.771318 -217.627512)
			(xy 375.807928 -217.664122) (xy 375.83836 -217.706009) (xy 375.861866 -217.752141) (xy 375.877865 -217.801381)
			(xy 375.885964 -217.852519) (xy 375.886472 -217.878406) (xy 375.886025 -217.903782) (xy 375.878255 -217.953934)
			(xy 375.862885 -218.002302) (xy 375.840277 -218.047739) (xy 375.810967 -218.089171) (xy 375.77565 -218.125617)
			(xy 375.73516 -218.156215) (xy 375.690456 -218.18024) (xy 375.642596 -218.197124) (xy 375.61774 -218.202256)
			(xy 375.59488 -218.206574) (xy 375.390156 -218.561412) (xy 375.39803 -218.583256) (xy 375.406681 -218.609663)
			(xy 375.415998 -218.66444) (xy 375.416572 -218.692222) (xy 376.636788 -218.692222) (xy 376.637339 -218.66688)
			(xy 376.645107 -218.616793) (xy 376.660448 -218.568485) (xy 376.683001 -218.523094) (xy 376.712234 -218.481689)
			(xy 376.747459 -218.445245) (xy 376.787846 -218.41462) (xy 376.832444 -218.390537) (xy 376.880202 -218.373561)
			(xy 376.905012 -218.368372) (xy 376.927872 -218.364054) (xy 377.133104 -218.008708) (xy 377.12523 -217.98661)
			(xy 377.116761 -217.960367) (xy 377.107692 -217.905977) (xy 377.107196 -217.878406) (xy 377.107704 -217.852519)
			(xy 377.115803 -217.801381) (xy 377.131802 -217.752141) (xy 377.155308 -217.706009) (xy 377.18574 -217.664122)
			(xy 377.22235 -217.627512) (xy 377.264237 -217.59708) (xy 377.310369 -217.573574) (xy 377.359609 -217.557575)
			(xy 377.410747 -217.549476) (xy 377.462521 -217.549476) (xy 377.513659 -217.557575) (xy 377.562899 -217.573574)
			(xy 377.609031 -217.59708) (xy 377.650918 -217.627512) (xy 377.687528 -217.664122) (xy 377.71796 -217.706009)
			(xy 377.741466 -217.752141) (xy 377.757465 -217.801381) (xy 377.765564 -217.852519) (xy 377.766072 -217.878406)
			(xy 377.765625 -217.903782) (xy 377.757855 -217.953934) (xy 377.742485 -218.002302) (xy 377.719877 -218.047739)
			(xy 377.690567 -218.089171) (xy 377.65525 -218.125617) (xy 377.61476 -218.156215) (xy 377.570056 -218.18024)
			(xy 377.522196 -218.197124) (xy 377.49734 -218.202256) (xy 377.47448 -218.206574) (xy 377.269756 -218.561412)
			(xy 377.27763 -218.583256) (xy 377.286281 -218.609663) (xy 377.295598 -218.66444) (xy 377.296172 -218.692222)
			(xy 378.516388 -218.692222) (xy 378.516939 -218.66688) (xy 378.524707 -218.616793) (xy 378.540048 -218.568485)
			(xy 378.562601 -218.523094) (xy 378.591834 -218.481689) (xy 378.627059 -218.445245) (xy 378.667446 -218.41462)
			(xy 378.712044 -218.390537) (xy 378.759802 -218.373561) (xy 378.784612 -218.368372) (xy 378.807472 -218.364054)
			(xy 379.012704 -218.008708) (xy 379.00483 -217.98661) (xy 378.996361 -217.960367) (xy 378.987292 -217.905977)
			(xy 378.986796 -217.878406) (xy 378.987304 -217.852519) (xy 378.995403 -217.801381) (xy 379.011402 -217.752141)
			(xy 379.034908 -217.706009) (xy 379.06534 -217.664122) (xy 379.10195 -217.627512) (xy 379.143837 -217.59708)
			(xy 379.189969 -217.573574) (xy 379.239209 -217.557575) (xy 379.290347 -217.549476) (xy 379.342121 -217.549476)
			(xy 379.393259 -217.557575) (xy 379.442499 -217.573574) (xy 379.488631 -217.59708) (xy 379.530518 -217.627512)
			(xy 379.567128 -217.664122) (xy 379.59756 -217.706009) (xy 379.621066 -217.752141) (xy 379.637065 -217.801381)
			(xy 379.645164 -217.852519) (xy 379.645672 -217.878406) (xy 379.645225 -217.903782) (xy 379.637455 -217.953934)
			(xy 379.622085 -218.002302) (xy 379.599477 -218.047739) (xy 379.570167 -218.089171) (xy 379.53485 -218.125617)
			(xy 379.49436 -218.156215) (xy 379.449656 -218.18024) (xy 379.401796 -218.197124) (xy 379.37694 -218.202256)
			(xy 379.35408 -218.206574) (xy 379.149356 -218.561412) (xy 379.15723 -218.583256) (xy 379.165881 -218.609663)
			(xy 379.175198 -218.66444) (xy 379.175772 -218.692222) (xy 380.395988 -218.692222) (xy 380.396539 -218.66688)
			(xy 380.404307 -218.616793) (xy 380.419648 -218.568485) (xy 380.442201 -218.523094) (xy 380.471434 -218.481689)
			(xy 380.506659 -218.445245) (xy 380.547046 -218.41462) (xy 380.591644 -218.390537) (xy 380.639402 -218.373561)
			(xy 380.664212 -218.368372) (xy 380.687072 -218.364054) (xy 380.892304 -218.008708) (xy 380.88443 -217.98661)
			(xy 380.875961 -217.960367) (xy 380.866892 -217.905977) (xy 380.866396 -217.878406) (xy 380.866904 -217.852519)
			(xy 380.875003 -217.801381) (xy 380.891002 -217.752141) (xy 380.914508 -217.706009) (xy 380.94494 -217.664122)
			(xy 380.98155 -217.627512) (xy 381.023437 -217.59708) (xy 381.069569 -217.573574) (xy 381.118809 -217.557575)
			(xy 381.169947 -217.549476) (xy 381.221721 -217.549476) (xy 381.272859 -217.557575) (xy 381.322099 -217.573574)
			(xy 381.368231 -217.59708) (xy 381.410118 -217.627512) (xy 381.446728 -217.664122) (xy 381.47716 -217.706009)
			(xy 381.500666 -217.752141) (xy 381.516665 -217.801381) (xy 381.524764 -217.852519) (xy 381.525272 -217.878406)
			(xy 381.524825 -217.903782) (xy 381.517055 -217.953934) (xy 381.501685 -218.002302) (xy 381.479077 -218.047739)
			(xy 381.449767 -218.089171) (xy 381.41445 -218.125617) (xy 381.37396 -218.156215) (xy 381.329256 -218.18024)
			(xy 381.281396 -218.197124) (xy 381.25654 -218.202256) (xy 381.23368 -218.206574) (xy 381.028956 -218.561412)
			(xy 381.03683 -218.583256) (xy 381.045481 -218.609663) (xy 381.054798 -218.66444) (xy 381.055372 -218.692222)
			(xy 381.054864 -218.718129) (xy 381.046758 -218.769306) (xy 381.030746 -218.818585) (xy 381.007223 -218.864752)
			(xy 380.976767 -218.906671) (xy 380.940129 -218.943309) (xy 380.89821 -218.973765) (xy 380.852043 -218.997288)
			(xy 380.802764 -219.0133) (xy 380.751587 -219.021406) (xy 380.699773 -219.021406) (xy 380.648596 -219.0133)
			(xy 380.599317 -218.997288) (xy 380.55315 -218.973765) (xy 380.511231 -218.943309) (xy 380.474593 -218.906671)
			(xy 380.444137 -218.864752) (xy 380.420614 -218.818585) (xy 380.404602 -218.769306) (xy 380.396496 -218.718129)
			(xy 380.395988 -218.692222) (xy 379.175772 -218.692222) (xy 379.175264 -218.718129) (xy 379.167158 -218.769306)
			(xy 379.151146 -218.818585) (xy 379.127623 -218.864752) (xy 379.097167 -218.906671) (xy 379.060529 -218.943309)
			(xy 379.01861 -218.973765) (xy 378.972443 -218.997288) (xy 378.923164 -219.0133) (xy 378.871987 -219.021406)
			(xy 378.820173 -219.021406) (xy 378.768996 -219.0133) (xy 378.719717 -218.997288) (xy 378.67355 -218.973765)
			(xy 378.631631 -218.943309) (xy 378.594993 -218.906671) (xy 378.564537 -218.864752) (xy 378.541014 -218.818585)
			(xy 378.525002 -218.769306) (xy 378.516896 -218.718129) (xy 378.516388 -218.692222) (xy 377.296172 -218.692222)
			(xy 377.295664 -218.718129) (xy 377.287558 -218.769306) (xy 377.271546 -218.818585) (xy 377.248023 -218.864752)
			(xy 377.217567 -218.906671) (xy 377.180929 -218.943309) (xy 377.13901 -218.973765) (xy 377.092843 -218.997288)
			(xy 377.043564 -219.0133) (xy 376.992387 -219.021406) (xy 376.940573 -219.021406) (xy 376.889396 -219.0133)
			(xy 376.840117 -218.997288) (xy 376.79395 -218.973765) (xy 376.752031 -218.943309) (xy 376.715393 -218.906671)
			(xy 376.684937 -218.864752) (xy 376.661414 -218.818585) (xy 376.645402 -218.769306) (xy 376.637296 -218.718129)
			(xy 376.636788 -218.692222) (xy 375.416572 -218.692222) (xy 375.416064 -218.718129) (xy 375.407958 -218.769306)
			(xy 375.391946 -218.818585) (xy 375.368423 -218.864752) (xy 375.337967 -218.906671) (xy 375.301329 -218.943309)
			(xy 375.25941 -218.973765) (xy 375.213243 -218.997288) (xy 375.163964 -219.0133) (xy 375.112787 -219.021406)
			(xy 375.060973 -219.021406) (xy 375.009796 -219.0133) (xy 374.960517 -218.997288) (xy 374.91435 -218.973765)
			(xy 374.872431 -218.943309) (xy 374.835793 -218.906671) (xy 374.805337 -218.864752) (xy 374.781814 -218.818585)
			(xy 374.765802 -218.769306) (xy 374.757696 -218.718129) (xy 374.757188 -218.692222) (xy 373.536972 -218.692222)
			(xy 373.536464 -218.718129) (xy 373.528358 -218.769306) (xy 373.512346 -218.818585) (xy 373.488823 -218.864752)
			(xy 373.458367 -218.906671) (xy 373.421729 -218.943309) (xy 373.37981 -218.973765) (xy 373.333643 -218.997288)
			(xy 373.284364 -219.0133) (xy 373.233187 -219.021406) (xy 373.181373 -219.021406) (xy 373.130196 -219.0133)
			(xy 373.080917 -218.997288) (xy 373.03475 -218.973765) (xy 372.992831 -218.943309) (xy 372.956193 -218.906671)
			(xy 372.925737 -218.864752) (xy 372.902214 -218.818585) (xy 372.886202 -218.769306) (xy 372.878096 -218.718129)
			(xy 372.877588 -218.692222) (xy 371.657372 -218.692222) (xy 371.656864 -218.718129) (xy 371.648758 -218.769306)
			(xy 371.632746 -218.818585) (xy 371.609223 -218.864752) (xy 371.578767 -218.906671) (xy 371.542129 -218.943309)
			(xy 371.50021 -218.973765) (xy 371.454043 -218.997288) (xy 371.404764 -219.0133) (xy 371.353587 -219.021406)
			(xy 371.301773 -219.021406) (xy 371.250596 -219.0133) (xy 371.201317 -218.997288) (xy 371.15515 -218.973765)
			(xy 371.113231 -218.943309) (xy 371.076593 -218.906671) (xy 371.046137 -218.864752) (xy 371.022614 -218.818585)
			(xy 371.006602 -218.769306) (xy 370.998496 -218.718129) (xy 370.997988 -218.692222) (xy 369.777772 -218.692222)
			(xy 369.777264 -218.718129) (xy 369.769158 -218.769306) (xy 369.753146 -218.818585) (xy 369.729623 -218.864752)
			(xy 369.699167 -218.906671) (xy 369.662529 -218.943309) (xy 369.62061 -218.973765) (xy 369.574443 -218.997288)
			(xy 369.525164 -219.0133) (xy 369.473987 -219.021406) (xy 369.422173 -219.021406) (xy 369.370996 -219.0133)
			(xy 369.321717 -218.997288) (xy 369.27555 -218.973765) (xy 369.233631 -218.943309) (xy 369.196993 -218.906671)
			(xy 369.166537 -218.864752) (xy 369.143014 -218.818585) (xy 369.127002 -218.769306) (xy 369.118896 -218.718129)
			(xy 369.118388 -218.692222) (xy 367.898172 -218.692222) (xy 367.897664 -218.718129) (xy 367.889558 -218.769306)
			(xy 367.873546 -218.818585) (xy 367.850023 -218.864752) (xy 367.819567 -218.906671) (xy 367.782929 -218.943309)
			(xy 367.74101 -218.973765) (xy 367.694843 -218.997288) (xy 367.645564 -219.0133) (xy 367.594387 -219.021406)
			(xy 367.542573 -219.021406) (xy 367.491396 -219.0133) (xy 367.442117 -218.997288) (xy 367.39595 -218.973765)
			(xy 367.354031 -218.943309) (xy 367.317393 -218.906671) (xy 367.286937 -218.864752) (xy 367.263414 -218.818585)
			(xy 367.247402 -218.769306) (xy 367.239296 -218.718129) (xy 367.238788 -218.692222) (xy 366.018572 -218.692222)
			(xy 366.018064 -218.718129) (xy 366.009958 -218.769306) (xy 365.993946 -218.818585) (xy 365.970423 -218.864752)
			(xy 365.939967 -218.906671) (xy 365.903329 -218.943309) (xy 365.86141 -218.973765) (xy 365.815243 -218.997288)
			(xy 365.765964 -219.0133) (xy 365.714787 -219.021406) (xy 365.662973 -219.021406) (xy 365.611796 -219.0133)
			(xy 365.562517 -218.997288) (xy 365.51635 -218.973765) (xy 365.474431 -218.943309) (xy 365.437793 -218.906671)
			(xy 365.407337 -218.864752) (xy 365.383814 -218.818585) (xy 365.367802 -218.769306) (xy 365.359696 -218.718129)
			(xy 365.359188 -218.692222) (xy 364.138972 -218.692222) (xy 364.138464 -218.718129) (xy 364.130358 -218.769306)
			(xy 364.114346 -218.818585) (xy 364.090823 -218.864752) (xy 364.060367 -218.906671) (xy 364.023729 -218.943309)
			(xy 363.98181 -218.973765) (xy 363.935643 -218.997288) (xy 363.886364 -219.0133) (xy 363.835187 -219.021406)
			(xy 363.783373 -219.021406) (xy 363.732196 -219.0133) (xy 363.682917 -218.997288) (xy 363.63675 -218.973765)
			(xy 363.594831 -218.943309) (xy 363.558193 -218.906671) (xy 363.527737 -218.864752) (xy 363.504214 -218.818585)
			(xy 363.488202 -218.769306) (xy 363.480096 -218.718129) (xy 363.479588 -218.692222) (xy 362.259372 -218.692222)
			(xy 362.258864 -218.718109) (xy 362.250765 -218.769247) (xy 362.234766 -218.818487) (xy 362.21126 -218.864619)
			(xy 362.180828 -218.906506) (xy 362.144218 -218.943116) (xy 362.102331 -218.973548) (xy 362.056199 -218.997054)
			(xy 362.006959 -219.013053) (xy 361.955821 -219.021152) (xy 361.904047 -219.021152) (xy 361.852909 -219.013053)
			(xy 361.803669 -218.997054) (xy 361.757537 -218.973548) (xy 361.71565 -218.943116) (xy 361.67904 -218.906506)
			(xy 361.648608 -218.864619) (xy 361.625102 -218.818487) (xy 361.609103 -218.769247) (xy 361.601004 -218.718109)
			(xy 361.600496 -218.692222) (xy 360.379772 -218.692222) (xy 360.379264 -218.718129) (xy 360.371158 -218.769306)
			(xy 360.355146 -218.818585) (xy 360.331623 -218.864752) (xy 360.301167 -218.906671) (xy 360.264529 -218.943309)
			(xy 360.22261 -218.973765) (xy 360.176443 -218.997288) (xy 360.127164 -219.0133) (xy 360.075987 -219.021406)
			(xy 360.024173 -219.021406) (xy 359.972996 -219.0133) (xy 359.923717 -218.997288) (xy 359.87755 -218.973765)
			(xy 359.835631 -218.943309) (xy 359.798993 -218.906671) (xy 359.768537 -218.864752) (xy 359.745014 -218.818585)
			(xy 359.729002 -218.769306) (xy 359.720896 -218.718129) (xy 359.720388 -218.692222) (xy 358.500172 -218.692222)
			(xy 358.499664 -218.718109) (xy 358.491565 -218.769247) (xy 358.475566 -218.818487) (xy 358.45206 -218.864619)
			(xy 358.421628 -218.906506) (xy 358.385018 -218.943116) (xy 358.343131 -218.973548) (xy 358.296999 -218.997054)
			(xy 358.247759 -219.013053) (xy 358.196621 -219.021152) (xy 358.144847 -219.021152) (xy 358.093709 -219.013053)
			(xy 358.044469 -218.997054) (xy 357.998337 -218.973548) (xy 357.95645 -218.943116) (xy 357.91984 -218.906506)
			(xy 357.889408 -218.864619) (xy 357.865902 -218.818487) (xy 357.849903 -218.769247) (xy 357.841804 -218.718109)
			(xy 357.841296 -218.692222) (xy 357.841831 -218.664514) (xy 357.851023 -218.609867) (xy 357.859584 -218.58351)
			(xy 357.867458 -218.561412) (xy 357.66248 -218.206574) (xy 357.63962 -218.202256) (xy 357.614783 -218.197156)
			(xy 357.567001 -218.180194) (xy 357.52238 -218.156114) (xy 357.481972 -218.125486) (xy 357.446732 -218.08903)
			(xy 357.417491 -218.047608) (xy 357.394937 -218.002196) (xy 357.379605 -217.953866) (xy 357.371854 -217.903758)
			(xy 357.371396 -217.878406) (xy 357.090472 -217.878406) (xy 357.089964 -217.904293) (xy 357.081865 -217.955431)
			(xy 357.065866 -218.004671) (xy 357.04236 -218.050803) (xy 357.011928 -218.09269) (xy 356.975318 -218.1293)
			(xy 356.933431 -218.159732) (xy 356.887299 -218.183238) (xy 356.838059 -218.199237) (xy 356.786921 -218.207336)
			(xy 356.735147 -218.207336) (xy 356.684009 -218.199237) (xy 356.634769 -218.183238) (xy 356.588637 -218.159732)
			(xy 356.54675 -218.1293) (xy 356.51014 -218.09269) (xy 356.479708 -218.050803) (xy 356.456202 -218.004671)
			(xy 356.440203 -217.955431) (xy 356.432104 -217.904293) (xy 356.431596 -217.878406) (xy 356.150672 -217.878406)
			(xy 356.150141 -217.906114) (xy 356.140946 -217.960761) (xy 356.132384 -217.987118) (xy 356.12451 -218.009216)
			(xy 356.329488 -218.364054) (xy 356.352348 -218.368372) (xy 356.377163 -218.373563) (xy 356.424941 -218.390515)
			(xy 356.469559 -218.414584) (xy 356.509965 -218.445202) (xy 356.545206 -218.481645) (xy 356.57445 -218.523056)
			(xy 356.597009 -218.568456) (xy 356.612349 -218.616776) (xy 356.620108 -218.666874) (xy 356.620572 -218.692222)
			(xy 356.620064 -218.718129) (xy 356.611958 -218.769306) (xy 356.595946 -218.818585) (xy 356.572423 -218.864752)
			(xy 356.541967 -218.906671) (xy 356.505329 -218.943309) (xy 356.46341 -218.973765) (xy 356.417243 -218.997288)
			(xy 356.367964 -219.0133) (xy 356.316787 -219.021406) (xy 356.264973 -219.021406) (xy 356.213796 -219.0133)
			(xy 356.164517 -218.997288) (xy 356.11835 -218.973765) (xy 356.076431 -218.943309) (xy 356.039793 -218.906671)
			(xy 356.009337 -218.864752) (xy 355.985814 -218.818585) (xy 355.969802 -218.769306) (xy 355.961696 -218.718129)
			(xy 355.961188 -218.692222) (xy 355.961788 -218.664505) (xy 355.971107 -218.609859) (xy 355.97973 -218.58351)
			(xy 355.987604 -218.561412) (xy 355.782626 -218.206574) (xy 355.759766 -218.202256) (xy 355.734962 -218.197073)
			(xy 355.687224 -218.180081) (xy 355.642649 -218.155985) (xy 355.602284 -218.125353) (xy 355.567082 -218.088906)
			(xy 355.53787 -218.047502) (xy 355.515337 -218.002116) (xy 355.500013 -217.953817) (xy 355.49226 -217.903742)
			(xy 355.491796 -217.878406) (xy 355.210872 -217.878406) (xy 355.210364 -217.904293) (xy 355.202265 -217.955431)
			(xy 355.186266 -218.004671) (xy 355.16276 -218.050803) (xy 355.132328 -218.09269) (xy 355.095718 -218.1293)
			(xy 355.053831 -218.159732) (xy 355.007699 -218.183238) (xy 354.958459 -218.199237) (xy 354.907321 -218.207336)
			(xy 354.855547 -218.207336) (xy 354.804409 -218.199237) (xy 354.755169 -218.183238) (xy 354.709037 -218.159732)
			(xy 354.66715 -218.1293) (xy 354.63054 -218.09269) (xy 354.600108 -218.050803) (xy 354.576602 -218.004671)
			(xy 354.560603 -217.955431) (xy 354.552504 -217.904293) (xy 354.551996 -217.878406) (xy 354.271072 -217.878406)
			(xy 354.270541 -217.906114) (xy 354.261346 -217.960761) (xy 354.252784 -217.987118) (xy 354.24491 -218.009216)
			(xy 354.449888 -218.364054) (xy 354.472748 -218.368372) (xy 354.497563 -218.373563) (xy 354.545341 -218.390515)
			(xy 354.589959 -218.414584) (xy 354.630365 -218.445202) (xy 354.665606 -218.481645) (xy 354.69485 -218.523056)
			(xy 354.717409 -218.568456) (xy 354.732749 -218.616776) (xy 354.740508 -218.666874) (xy 354.740972 -218.692222)
			(xy 354.740464 -218.718129) (xy 354.732358 -218.769306) (xy 354.716346 -218.818585) (xy 354.692823 -218.864752)
			(xy 354.662367 -218.906671) (xy 354.625729 -218.943309) (xy 354.58381 -218.973765) (xy 354.537643 -218.997288)
			(xy 354.488364 -219.0133) (xy 354.437187 -219.021406) (xy 354.385373 -219.021406) (xy 354.334196 -219.0133)
			(xy 354.284917 -218.997288) (xy 354.23875 -218.973765) (xy 354.196831 -218.943309) (xy 354.160193 -218.906671)
			(xy 354.129737 -218.864752) (xy 354.106214 -218.818585) (xy 354.090202 -218.769306) (xy 354.082096 -218.718129)
			(xy 354.081588 -218.692222) (xy 354.082188 -218.664505) (xy 354.091507 -218.609859) (xy 354.10013 -218.58351)
			(xy 354.108004 -218.561412) (xy 353.903026 -218.206574) (xy 353.880166 -218.202256) (xy 353.855362 -218.197073)
			(xy 353.807624 -218.180081) (xy 353.763049 -218.155985) (xy 353.722684 -218.125353) (xy 353.687482 -218.088906)
			(xy 353.65827 -218.047502) (xy 353.635737 -218.002116) (xy 353.620413 -217.953817) (xy 353.61266 -217.903742)
			(xy 353.612196 -217.878406) (xy 353.331272 -217.878406) (xy 353.330764 -217.904293) (xy 353.322665 -217.955431)
			(xy 353.306666 -218.004671) (xy 353.28316 -218.050803) (xy 353.252728 -218.09269) (xy 353.216118 -218.1293)
			(xy 353.174231 -218.159732) (xy 353.128099 -218.183238) (xy 353.078859 -218.199237) (xy 353.027721 -218.207336)
			(xy 352.975947 -218.207336) (xy 352.924809 -218.199237) (xy 352.875569 -218.183238) (xy 352.829437 -218.159732)
			(xy 352.78755 -218.1293) (xy 352.75094 -218.09269) (xy 352.720508 -218.050803) (xy 352.697002 -218.004671)
			(xy 352.681003 -217.955431) (xy 352.672904 -217.904293) (xy 352.672396 -217.878406) (xy 352.391472 -217.878406)
			(xy 352.390941 -217.906114) (xy 352.381746 -217.960761) (xy 352.373184 -217.987118) (xy 352.36531 -218.009216)
			(xy 352.570288 -218.364054) (xy 352.593148 -218.368372) (xy 352.617963 -218.373563) (xy 352.665741 -218.390515)
			(xy 352.710359 -218.414584) (xy 352.750765 -218.445202) (xy 352.786006 -218.481645) (xy 352.81525 -218.523056)
			(xy 352.837809 -218.568456) (xy 352.853149 -218.616776) (xy 352.860908 -218.666874) (xy 352.861372 -218.692222)
			(xy 352.860864 -218.718129) (xy 352.852758 -218.769306) (xy 352.836746 -218.818585) (xy 352.813223 -218.864752)
			(xy 352.782767 -218.906671) (xy 352.746129 -218.943309) (xy 352.70421 -218.973765) (xy 352.658043 -218.997288)
			(xy 352.608764 -219.0133) (xy 352.557587 -219.021406) (xy 352.505773 -219.021406) (xy 352.454596 -219.0133)
			(xy 352.405317 -218.997288) (xy 352.35915 -218.973765) (xy 352.317231 -218.943309) (xy 352.280593 -218.906671)
			(xy 352.250137 -218.864752) (xy 352.226614 -218.818585) (xy 352.210602 -218.769306) (xy 352.202496 -218.718129)
			(xy 352.201988 -218.692222) (xy 352.202588 -218.664505) (xy 352.211907 -218.609859) (xy 352.22053 -218.58351)
			(xy 352.228404 -218.561412) (xy 352.023426 -218.206574) (xy 352.000566 -218.202256) (xy 351.975762 -218.197073)
			(xy 351.928024 -218.180081) (xy 351.883449 -218.155985) (xy 351.843084 -218.125353) (xy 351.807882 -218.088906)
			(xy 351.77867 -218.047502) (xy 351.756137 -218.002116) (xy 351.740813 -217.953817) (xy 351.73306 -217.903742)
			(xy 351.732596 -217.878406) (xy 351.451672 -217.878406) (xy 351.451164 -217.904293) (xy 351.443065 -217.955431)
			(xy 351.427066 -218.004671) (xy 351.40356 -218.050803) (xy 351.373128 -218.09269) (xy 351.336518 -218.1293)
			(xy 351.294631 -218.159732) (xy 351.248499 -218.183238) (xy 351.199259 -218.199237) (xy 351.148121 -218.207336)
			(xy 351.096347 -218.207336) (xy 351.045209 -218.199237) (xy 350.995969 -218.183238) (xy 350.949837 -218.159732)
			(xy 350.90795 -218.1293) (xy 350.87134 -218.09269) (xy 350.840908 -218.050803) (xy 350.817402 -218.004671)
			(xy 350.801403 -217.955431) (xy 350.793304 -217.904293) (xy 350.792796 -217.878406) (xy 350.511872 -217.878406)
			(xy 350.511341 -217.906114) (xy 350.502146 -217.960761) (xy 350.493584 -217.987118) (xy 350.48571 -218.009216)
			(xy 350.690688 -218.364054) (xy 350.713548 -218.368372) (xy 350.738363 -218.373563) (xy 350.786141 -218.390515)
			(xy 350.830759 -218.414584) (xy 350.871165 -218.445202) (xy 350.906406 -218.481645) (xy 350.93565 -218.523056)
			(xy 350.958209 -218.568456) (xy 350.973549 -218.616776) (xy 350.981308 -218.666874) (xy 350.981772 -218.692222)
			(xy 350.981264 -218.718129) (xy 350.973158 -218.769306) (xy 350.957146 -218.818585) (xy 350.933623 -218.864752)
			(xy 350.903167 -218.906671) (xy 350.866529 -218.943309) (xy 350.82461 -218.973765) (xy 350.778443 -218.997288)
			(xy 350.729164 -219.0133) (xy 350.677987 -219.021406) (xy 350.626173 -219.021406) (xy 350.574996 -219.0133)
			(xy 350.525717 -218.997288) (xy 350.47955 -218.973765) (xy 350.437631 -218.943309) (xy 350.400993 -218.906671)
			(xy 350.370537 -218.864752) (xy 350.347014 -218.818585) (xy 350.331002 -218.769306) (xy 350.322896 -218.718129)
			(xy 350.322388 -218.692222) (xy 350.322988 -218.664505) (xy 350.332307 -218.609859) (xy 350.34093 -218.58351)
			(xy 350.348804 -218.561412) (xy 350.143826 -218.206574) (xy 350.120966 -218.202256) (xy 350.096162 -218.197073)
			(xy 350.048424 -218.180081) (xy 350.003849 -218.155985) (xy 349.963484 -218.125353) (xy 349.928282 -218.088906)
			(xy 349.89907 -218.047502) (xy 349.876537 -218.002116) (xy 349.861213 -217.953817) (xy 349.85346 -217.903742)
			(xy 349.852996 -217.878406) (xy 349.572072 -217.878406) (xy 349.571564 -217.904293) (xy 349.563465 -217.955431)
			(xy 349.547466 -218.004671) (xy 349.52396 -218.050803) (xy 349.493528 -218.09269) (xy 349.456918 -218.1293)
			(xy 349.415031 -218.159732) (xy 349.368899 -218.183238) (xy 349.319659 -218.199237) (xy 349.268521 -218.207336)
			(xy 349.216747 -218.207336) (xy 349.165609 -218.199237) (xy 349.116369 -218.183238) (xy 349.070237 -218.159732)
			(xy 349.02835 -218.1293) (xy 348.99174 -218.09269) (xy 348.961308 -218.050803) (xy 348.937802 -218.004671)
			(xy 348.921803 -217.955431) (xy 348.913704 -217.904293) (xy 348.913196 -217.878406) (xy 348.632272 -217.878406)
			(xy 348.631741 -217.906114) (xy 348.622546 -217.960761) (xy 348.613984 -217.987118) (xy 348.60611 -218.009216)
			(xy 348.811088 -218.364054) (xy 348.833948 -218.368372) (xy 348.858763 -218.373563) (xy 348.906541 -218.390515)
			(xy 348.951159 -218.414584) (xy 348.991565 -218.445202) (xy 349.026806 -218.481645) (xy 349.05605 -218.523056)
			(xy 349.078609 -218.568456) (xy 349.093949 -218.616776) (xy 349.101708 -218.666874) (xy 349.102172 -218.692222)
			(xy 349.101664 -218.718129) (xy 349.093558 -218.769306) (xy 349.077546 -218.818585) (xy 349.054023 -218.864752)
			(xy 349.023567 -218.906671) (xy 348.986929 -218.943309) (xy 348.94501 -218.973765) (xy 348.898843 -218.997288)
			(xy 348.849564 -219.0133) (xy 348.798387 -219.021406) (xy 348.746573 -219.021406) (xy 348.695396 -219.0133)
			(xy 348.646117 -218.997288) (xy 348.59995 -218.973765) (xy 348.558031 -218.943309) (xy 348.521393 -218.906671)
			(xy 348.490937 -218.864752) (xy 348.467414 -218.818585) (xy 348.451402 -218.769306) (xy 348.443296 -218.718129)
			(xy 348.442788 -218.692222) (xy 348.443388 -218.664505) (xy 348.452707 -218.609859) (xy 348.46133 -218.58351)
			(xy 348.469204 -218.561412) (xy 348.264226 -218.206574) (xy 348.241366 -218.202256) (xy 348.216562 -218.197073)
			(xy 348.168824 -218.180081) (xy 348.124249 -218.155985) (xy 348.083884 -218.125353) (xy 348.048682 -218.088906)
			(xy 348.01947 -218.047502) (xy 347.996937 -218.002116) (xy 347.981613 -217.953817) (xy 347.97386 -217.903742)
			(xy 347.973396 -217.878406) (xy 347.692472 -217.878406) (xy 347.691964 -217.904293) (xy 347.683865 -217.955431)
			(xy 347.667866 -218.004671) (xy 347.64436 -218.050803) (xy 347.613928 -218.09269) (xy 347.577318 -218.1293)
			(xy 347.535431 -218.159732) (xy 347.489299 -218.183238) (xy 347.440059 -218.199237) (xy 347.388921 -218.207336)
			(xy 347.337147 -218.207336) (xy 347.286009 -218.199237) (xy 347.236769 -218.183238) (xy 347.190637 -218.159732)
			(xy 347.14875 -218.1293) (xy 347.11214 -218.09269) (xy 347.081708 -218.050803) (xy 347.058202 -218.004671)
			(xy 347.042203 -217.955431) (xy 347.034104 -217.904293) (xy 347.033596 -217.878406) (xy 346.752672 -217.878406)
			(xy 346.752141 -217.906114) (xy 346.742946 -217.960761) (xy 346.734384 -217.987118) (xy 346.72651 -218.009216)
			(xy 346.931488 -218.364054) (xy 346.954348 -218.368372) (xy 346.979163 -218.373563) (xy 347.026941 -218.390515)
			(xy 347.071559 -218.414584) (xy 347.111965 -218.445202) (xy 347.147206 -218.481645) (xy 347.17645 -218.523056)
			(xy 347.199009 -218.568456) (xy 347.214349 -218.616776) (xy 347.222108 -218.666874) (xy 347.222572 -218.692222)
			(xy 347.222064 -218.718129) (xy 347.213958 -218.769306) (xy 347.197946 -218.818585) (xy 347.174423 -218.864752)
			(xy 347.143967 -218.906671) (xy 347.107329 -218.943309) (xy 347.06541 -218.973765) (xy 347.019243 -218.997288)
			(xy 346.969964 -219.0133) (xy 346.918787 -219.021406) (xy 346.866973 -219.021406) (xy 346.815796 -219.0133)
			(xy 346.766517 -218.997288) (xy 346.72035 -218.973765) (xy 346.678431 -218.943309) (xy 346.641793 -218.906671)
			(xy 346.611337 -218.864752) (xy 346.587814 -218.818585) (xy 346.571802 -218.769306) (xy 346.563696 -218.718129)
			(xy 346.563188 -218.692222) (xy 346.563788 -218.664505) (xy 346.573107 -218.609859) (xy 346.58173 -218.58351)
			(xy 346.589604 -218.561412) (xy 346.384626 -218.206574) (xy 346.361766 -218.202256) (xy 346.336962 -218.197073)
			(xy 346.289224 -218.180081) (xy 346.244649 -218.155985) (xy 346.204284 -218.125353) (xy 346.169082 -218.088906)
			(xy 346.13987 -218.047502) (xy 346.117337 -218.002116) (xy 346.102013 -217.953817) (xy 346.09426 -217.903742)
			(xy 346.093796 -217.878406) (xy 345.812872 -217.878406) (xy 345.812364 -217.904293) (xy 345.804265 -217.955431)
			(xy 345.788266 -218.004671) (xy 345.76476 -218.050803) (xy 345.734328 -218.09269) (xy 345.697718 -218.1293)
			(xy 345.655831 -218.159732) (xy 345.609699 -218.183238) (xy 345.560459 -218.199237) (xy 345.509321 -218.207336)
			(xy 345.457547 -218.207336) (xy 345.406409 -218.199237) (xy 345.357169 -218.183238) (xy 345.311037 -218.159732)
			(xy 345.26915 -218.1293) (xy 345.23254 -218.09269) (xy 345.202108 -218.050803) (xy 345.178602 -218.004671)
			(xy 345.162603 -217.955431) (xy 345.154504 -217.904293) (xy 345.153996 -217.878406) (xy 344.873072 -217.878406)
			(xy 344.872541 -217.906114) (xy 344.863346 -217.960761) (xy 344.854784 -217.987118) (xy 344.84691 -218.009216)
			(xy 345.051888 -218.364054) (xy 345.074748 -218.368372) (xy 345.099563 -218.373563) (xy 345.147341 -218.390515)
			(xy 345.191959 -218.414584) (xy 345.232365 -218.445202) (xy 345.267606 -218.481645) (xy 345.29685 -218.523056)
			(xy 345.319409 -218.568456) (xy 345.334749 -218.616776) (xy 345.342508 -218.666874) (xy 345.342972 -218.692222)
			(xy 345.342464 -218.718129) (xy 345.334358 -218.769306) (xy 345.318346 -218.818585) (xy 345.294823 -218.864752)
			(xy 345.264367 -218.906671) (xy 345.227729 -218.943309) (xy 345.18581 -218.973765) (xy 345.139643 -218.997288)
			(xy 345.090364 -219.0133) (xy 345.039187 -219.021406) (xy 344.987373 -219.021406) (xy 344.936196 -219.0133)
			(xy 344.886917 -218.997288) (xy 344.84075 -218.973765) (xy 344.798831 -218.943309) (xy 344.762193 -218.906671)
			(xy 344.731737 -218.864752) (xy 344.708214 -218.818585) (xy 344.692202 -218.769306) (xy 344.684096 -218.718129)
			(xy 344.683588 -218.692222) (xy 344.684188 -218.664505) (xy 344.693507 -218.609859) (xy 344.70213 -218.58351)
			(xy 344.710004 -218.561412) (xy 344.505026 -218.206574) (xy 344.482166 -218.202256) (xy 344.457362 -218.197073)
			(xy 344.409624 -218.180081) (xy 344.365049 -218.155985) (xy 344.324684 -218.125353) (xy 344.289482 -218.088906)
			(xy 344.26027 -218.047502) (xy 344.237737 -218.002116) (xy 344.222413 -217.953817) (xy 344.21466 -217.903742)
			(xy 344.214196 -217.878406) (xy 343.933272 -217.878406) (xy 343.932764 -217.904293) (xy 343.924665 -217.955431)
			(xy 343.908666 -218.004671) (xy 343.88516 -218.050803) (xy 343.854728 -218.09269) (xy 343.818118 -218.1293)
			(xy 343.776231 -218.159732) (xy 343.730099 -218.183238) (xy 343.680859 -218.199237) (xy 343.629721 -218.207336)
			(xy 343.577947 -218.207336) (xy 343.526809 -218.199237) (xy 343.477569 -218.183238) (xy 343.431437 -218.159732)
			(xy 343.38955 -218.1293) (xy 343.35294 -218.09269) (xy 343.322508 -218.050803) (xy 343.299002 -218.004671)
			(xy 343.283003 -217.955431) (xy 343.274904 -217.904293) (xy 343.274396 -217.878406) (xy 342.993472 -217.878406)
			(xy 342.992941 -217.906114) (xy 342.983746 -217.960761) (xy 342.975184 -217.987118) (xy 342.96731 -218.009216)
			(xy 343.172288 -218.364054) (xy 343.195148 -218.368372) (xy 343.219963 -218.373563) (xy 343.267741 -218.390515)
			(xy 343.312359 -218.414584) (xy 343.352765 -218.445202) (xy 343.388006 -218.481645) (xy 343.41725 -218.523056)
			(xy 343.439809 -218.568456) (xy 343.455149 -218.616776) (xy 343.462908 -218.666874) (xy 343.463372 -218.692222)
			(xy 343.462864 -218.718129) (xy 343.454758 -218.769306) (xy 343.438746 -218.818585) (xy 343.415223 -218.864752)
			(xy 343.384767 -218.906671) (xy 343.348129 -218.943309) (xy 343.30621 -218.973765) (xy 343.260043 -218.997288)
			(xy 343.210764 -219.0133) (xy 343.159587 -219.021406) (xy 343.107773 -219.021406) (xy 343.056596 -219.0133)
			(xy 343.007317 -218.997288) (xy 342.96115 -218.973765) (xy 342.919231 -218.943309) (xy 342.882593 -218.906671)
			(xy 342.852137 -218.864752) (xy 342.828614 -218.818585) (xy 342.812602 -218.769306) (xy 342.804496 -218.718129)
			(xy 342.803988 -218.692222) (xy 342.804588 -218.664505) (xy 342.813907 -218.609859) (xy 342.82253 -218.58351)
			(xy 342.830404 -218.561412) (xy 342.625426 -218.206574) (xy 342.602566 -218.202256) (xy 342.577762 -218.197073)
			(xy 342.530024 -218.180081) (xy 342.485449 -218.155985) (xy 342.445084 -218.125353) (xy 342.409882 -218.088906)
			(xy 342.38067 -218.047502) (xy 342.358137 -218.002116) (xy 342.342813 -217.953817) (xy 342.33506 -217.903742)
			(xy 342.334596 -217.878406) (xy 342.053672 -217.878406) (xy 342.053164 -217.904293) (xy 342.045065 -217.955431)
			(xy 342.029066 -218.004671) (xy 342.00556 -218.050803) (xy 341.975128 -218.09269) (xy 341.938518 -218.1293)
			(xy 341.896631 -218.159732) (xy 341.850499 -218.183238) (xy 341.801259 -218.199237) (xy 341.750121 -218.207336)
			(xy 341.698347 -218.207336) (xy 341.647209 -218.199237) (xy 341.597969 -218.183238) (xy 341.551837 -218.159732)
			(xy 341.50995 -218.1293) (xy 341.47334 -218.09269) (xy 341.442908 -218.050803) (xy 341.419402 -218.004671)
			(xy 341.403403 -217.955431) (xy 341.395304 -217.904293) (xy 341.394796 -217.878406) (xy 341.113872 -217.878406)
			(xy 341.113341 -217.906114) (xy 341.104146 -217.960761) (xy 341.095584 -217.987118) (xy 341.08771 -218.009216)
			(xy 341.292688 -218.364054) (xy 341.315548 -218.368372) (xy 341.340363 -218.373563) (xy 341.388141 -218.390515)
			(xy 341.432759 -218.414584) (xy 341.473165 -218.445202) (xy 341.508406 -218.481645) (xy 341.53765 -218.523056)
			(xy 341.560209 -218.568456) (xy 341.575549 -218.616776) (xy 341.583308 -218.666874) (xy 341.583772 -218.692222)
			(xy 341.583264 -218.718129) (xy 341.575158 -218.769306) (xy 341.559146 -218.818585) (xy 341.535623 -218.864752)
			(xy 341.505167 -218.906671) (xy 341.468529 -218.943309) (xy 341.42661 -218.973765) (xy 341.380443 -218.997288)
			(xy 341.331164 -219.0133) (xy 341.279987 -219.021406) (xy 341.228173 -219.021406) (xy 341.176996 -219.0133)
			(xy 341.127717 -218.997288) (xy 341.08155 -218.973765) (xy 341.039631 -218.943309) (xy 341.002993 -218.906671)
			(xy 340.972537 -218.864752) (xy 340.949014 -218.818585) (xy 340.933002 -218.769306) (xy 340.924896 -218.718129)
			(xy 340.924388 -218.692222) (xy 340.924988 -218.664505) (xy 340.934307 -218.609859) (xy 340.94293 -218.58351)
			(xy 340.950804 -218.561412) (xy 340.745826 -218.206574) (xy 340.722966 -218.202256) (xy 340.698162 -218.197073)
			(xy 340.650424 -218.180081) (xy 340.605849 -218.155985) (xy 340.565484 -218.125353) (xy 340.530282 -218.088906)
			(xy 340.50107 -218.047502) (xy 340.478537 -218.002116) (xy 340.463213 -217.953817) (xy 340.45546 -217.903742)
			(xy 340.454996 -217.878406) (xy 340.174072 -217.878406) (xy 340.173564 -217.904293) (xy 340.165465 -217.955431)
			(xy 340.149466 -218.004671) (xy 340.12596 -218.050803) (xy 340.095528 -218.09269) (xy 340.058918 -218.1293)
			(xy 340.017031 -218.159732) (xy 339.970899 -218.183238) (xy 339.921659 -218.199237) (xy 339.870521 -218.207336)
			(xy 339.818747 -218.207336) (xy 339.767609 -218.199237) (xy 339.718369 -218.183238) (xy 339.672237 -218.159732)
			(xy 339.63035 -218.1293) (xy 339.59374 -218.09269) (xy 339.563308 -218.050803) (xy 339.539802 -218.004671)
			(xy 339.523803 -217.955431) (xy 339.515704 -217.904293) (xy 339.515196 -217.878406) (xy 339.234272 -217.878406)
			(xy 339.233741 -217.906114) (xy 339.224546 -217.960761) (xy 339.215984 -217.987118) (xy 339.20811 -218.009216)
			(xy 339.413088 -218.364054) (xy 339.435948 -218.368372) (xy 339.460763 -218.373563) (xy 339.508541 -218.390515)
			(xy 339.553159 -218.414584) (xy 339.593565 -218.445202) (xy 339.628806 -218.481645) (xy 339.65805 -218.523056)
			(xy 339.680609 -218.568456) (xy 339.695949 -218.616776) (xy 339.703708 -218.666874) (xy 339.704172 -218.692222)
			(xy 339.703664 -218.718129) (xy 339.695558 -218.769306) (xy 339.679546 -218.818585) (xy 339.656023 -218.864752)
			(xy 339.625567 -218.906671) (xy 339.588929 -218.943309) (xy 339.54701 -218.973765) (xy 339.500843 -218.997288)
			(xy 339.451564 -219.0133) (xy 339.400387 -219.021406) (xy 339.348573 -219.021406) (xy 339.297396 -219.0133)
			(xy 339.248117 -218.997288) (xy 339.20195 -218.973765) (xy 339.160031 -218.943309) (xy 339.123393 -218.906671)
			(xy 339.092937 -218.864752) (xy 339.069414 -218.818585) (xy 339.053402 -218.769306) (xy 339.045296 -218.718129)
			(xy 339.044788 -218.692222) (xy 339.045388 -218.664505) (xy 339.054707 -218.609859) (xy 339.06333 -218.58351)
			(xy 339.071204 -218.561412) (xy 338.866226 -218.206574) (xy 338.843366 -218.202256) (xy 338.818562 -218.197073)
			(xy 338.770824 -218.180081) (xy 338.726249 -218.155985) (xy 338.685884 -218.125353) (xy 338.650682 -218.088906)
			(xy 338.62147 -218.047502) (xy 338.598937 -218.002116) (xy 338.583613 -217.953817) (xy 338.57586 -217.903742)
			(xy 338.575396 -217.878406) (xy 338.294472 -217.878406) (xy 338.293964 -217.904293) (xy 338.285865 -217.955431)
			(xy 338.269866 -218.004671) (xy 338.24636 -218.050803) (xy 338.215928 -218.09269) (xy 338.179318 -218.1293)
			(xy 338.137431 -218.159732) (xy 338.091299 -218.183238) (xy 338.042059 -218.199237) (xy 337.990921 -218.207336)
			(xy 337.939147 -218.207336) (xy 337.888009 -218.199237) (xy 337.838769 -218.183238) (xy 337.792637 -218.159732)
			(xy 337.75075 -218.1293) (xy 337.71414 -218.09269) (xy 337.683708 -218.050803) (xy 337.660202 -218.004671)
			(xy 337.644203 -217.955431) (xy 337.636104 -217.904293) (xy 337.635596 -217.878406) (xy 337.354672 -217.878406)
			(xy 337.354141 -217.906114) (xy 337.344946 -217.960761) (xy 337.336384 -217.987118) (xy 337.32851 -218.009216)
			(xy 337.533488 -218.364054) (xy 337.556348 -218.368372) (xy 337.581163 -218.373563) (xy 337.628941 -218.390515)
			(xy 337.673559 -218.414584) (xy 337.713965 -218.445202) (xy 337.749206 -218.481645) (xy 337.77845 -218.523056)
			(xy 337.801009 -218.568456) (xy 337.816349 -218.616776) (xy 337.824108 -218.666874) (xy 337.824572 -218.692222)
			(xy 337.824064 -218.718129) (xy 337.815958 -218.769306) (xy 337.799946 -218.818585) (xy 337.776423 -218.864752)
			(xy 337.745967 -218.906671) (xy 337.709329 -218.943309) (xy 337.66741 -218.973765) (xy 337.621243 -218.997288)
			(xy 337.571964 -219.0133) (xy 337.520787 -219.021406) (xy 337.468973 -219.021406) (xy 337.417796 -219.0133)
			(xy 337.368517 -218.997288) (xy 337.32235 -218.973765) (xy 337.280431 -218.943309) (xy 337.243793 -218.906671)
			(xy 337.213337 -218.864752) (xy 337.189814 -218.818585) (xy 337.173802 -218.769306) (xy 337.165696 -218.718129)
			(xy 337.165188 -218.692222) (xy 337.165788 -218.664505) (xy 337.175107 -218.609859) (xy 337.18373 -218.58351)
			(xy 337.191604 -218.561412) (xy 336.986626 -218.206574) (xy 336.963766 -218.202256) (xy 336.938962 -218.197073)
			(xy 336.891224 -218.180081) (xy 336.846649 -218.155985) (xy 336.806284 -218.125353) (xy 336.771082 -218.088906)
			(xy 336.74187 -218.047502) (xy 336.719337 -218.002116) (xy 336.704013 -217.953817) (xy 336.69626 -217.903742)
			(xy 336.695796 -217.878406) (xy 134.525004 -217.878406) (xy 134.524496 -217.904293) (xy 134.516397 -217.955431)
			(xy 134.500398 -218.004671) (xy 134.476892 -218.050803) (xy 134.44646 -218.09269) (xy 134.40985 -218.1293)
			(xy 134.367963 -218.159732) (xy 134.321831 -218.183238) (xy 134.272591 -218.199237) (xy 134.221453 -218.207336)
			(xy 134.169679 -218.207336) (xy 134.118541 -218.199237) (xy 134.069301 -218.183238) (xy 134.023169 -218.159732)
			(xy 133.981282 -218.1293) (xy 133.944672 -218.09269) (xy 133.91424 -218.050803) (xy 133.890734 -218.004671)
			(xy 133.874735 -217.955431) (xy 133.866636 -217.904293) (xy 133.866128 -217.878406) (xy 133.866662 -217.850698)
			(xy 133.875855 -217.796051) (xy 133.884416 -217.769694) (xy 133.89229 -217.747596) (xy 133.687312 -217.392504)
			(xy 133.664452 -217.388186) (xy 133.639596 -217.383069) (xy 133.591748 -217.366166) (xy 133.547056 -217.342128)
			(xy 133.506577 -217.311523) (xy 133.471267 -217.275076) (xy 133.441961 -217.233647) (xy 133.419352 -217.188215)
			(xy 133.403974 -217.139855) (xy 133.39619 -217.089709) (xy 133.39572 -217.064336) (xy 132.175504 -217.064336)
			(xy 132.174889 -217.091989) (xy 132.165569 -217.146507) (xy 132.156962 -217.172794) (xy 132.149342 -217.194892)
			(xy 132.354574 -217.550238) (xy 132.377434 -217.554556) (xy 132.402241 -217.559728) (xy 132.449979 -217.576721)
			(xy 132.494556 -217.600818) (xy 132.53492 -217.631451) (xy 132.570123 -217.6679) (xy 132.599334 -217.709305)
			(xy 132.621866 -217.754693) (xy 132.637189 -217.802993) (xy 132.644941 -217.85307) (xy 132.645404 -217.878406)
			(xy 132.644896 -217.904293) (xy 132.636797 -217.955431) (xy 132.620798 -218.004671) (xy 132.597292 -218.050803)
			(xy 132.56686 -218.09269) (xy 132.53025 -218.1293) (xy 132.488363 -218.159732) (xy 132.442231 -218.183238)
			(xy 132.392991 -218.199237) (xy 132.341853 -218.207336) (xy 132.290079 -218.207336) (xy 132.238941 -218.199237)
			(xy 132.189701 -218.183238) (xy 132.143569 -218.159732) (xy 132.101682 -218.1293) (xy 132.065072 -218.09269)
			(xy 132.03464 -218.050803) (xy 132.011134 -218.004671) (xy 131.995135 -217.955431) (xy 131.987036 -217.904293)
			(xy 131.986528 -217.878406) (xy 131.987062 -217.850698) (xy 131.996255 -217.796051) (xy 132.004816 -217.769694)
			(xy 132.01269 -217.747596) (xy 131.807712 -217.392504) (xy 131.784852 -217.388186) (xy 131.759996 -217.383069)
			(xy 131.712148 -217.366166) (xy 131.667456 -217.342128) (xy 131.626977 -217.311523) (xy 131.591667 -217.275076)
			(xy 131.562361 -217.233647) (xy 131.539752 -217.188215) (xy 131.524374 -217.139855) (xy 131.51659 -217.089709)
			(xy 131.51612 -217.064336) (xy 130.295904 -217.064336) (xy 130.295289 -217.091989) (xy 130.285969 -217.146507)
			(xy 130.277362 -217.172794) (xy 130.269742 -217.194892) (xy 130.474974 -217.550238) (xy 130.497834 -217.554556)
			(xy 130.522641 -217.559728) (xy 130.570379 -217.576721) (xy 130.614956 -217.600818) (xy 130.65532 -217.631451)
			(xy 130.690523 -217.6679) (xy 130.719734 -217.709305) (xy 130.742266 -217.754693) (xy 130.757589 -217.802993)
			(xy 130.765341 -217.85307) (xy 130.765804 -217.878406) (xy 130.765296 -217.904293) (xy 130.757197 -217.955431)
			(xy 130.741198 -218.004671) (xy 130.717692 -218.050803) (xy 130.68726 -218.09269) (xy 130.65065 -218.1293)
			(xy 130.608763 -218.159732) (xy 130.562631 -218.183238) (xy 130.513391 -218.199237) (xy 130.462253 -218.207336)
			(xy 130.410479 -218.207336) (xy 130.359341 -218.199237) (xy 130.310101 -218.183238) (xy 130.263969 -218.159732)
			(xy 130.222082 -218.1293) (xy 130.185472 -218.09269) (xy 130.15504 -218.050803) (xy 130.131534 -218.004671)
			(xy 130.115535 -217.955431) (xy 130.107436 -217.904293) (xy 130.106928 -217.878406) (xy 130.107462 -217.850698)
			(xy 130.116655 -217.796051) (xy 130.125216 -217.769694) (xy 130.13309 -217.747596) (xy 129.928112 -217.392504)
			(xy 129.905252 -217.388186) (xy 129.880396 -217.383069) (xy 129.832548 -217.366166) (xy 129.787856 -217.342128)
			(xy 129.747377 -217.311523) (xy 129.712067 -217.275076) (xy 129.682761 -217.233647) (xy 129.660152 -217.188215)
			(xy 129.644774 -217.139855) (xy 129.63699 -217.089709) (xy 129.63652 -217.064336) (xy 128.416304 -217.064336)
			(xy 128.415689 -217.091989) (xy 128.406369 -217.146507) (xy 128.397762 -217.172794) (xy 128.390142 -217.194892)
			(xy 128.595374 -217.550238) (xy 128.618234 -217.554556) (xy 128.643041 -217.559728) (xy 128.690779 -217.576721)
			(xy 128.735356 -217.600818) (xy 128.77572 -217.631451) (xy 128.810923 -217.6679) (xy 128.840134 -217.709305)
			(xy 128.862666 -217.754693) (xy 128.877989 -217.802993) (xy 128.885741 -217.85307) (xy 128.886204 -217.878406)
			(xy 128.885696 -217.904293) (xy 128.877597 -217.955431) (xy 128.861598 -218.004671) (xy 128.838092 -218.050803)
			(xy 128.80766 -218.09269) (xy 128.77105 -218.1293) (xy 128.729163 -218.159732) (xy 128.683031 -218.183238)
			(xy 128.633791 -218.199237) (xy 128.582653 -218.207336) (xy 128.530879 -218.207336) (xy 128.479741 -218.199237)
			(xy 128.430501 -218.183238) (xy 128.384369 -218.159732) (xy 128.342482 -218.1293) (xy 128.305872 -218.09269)
			(xy 128.27544 -218.050803) (xy 128.251934 -218.004671) (xy 128.235935 -217.955431) (xy 128.227836 -217.904293)
			(xy 128.227328 -217.878406) (xy 128.227862 -217.850698) (xy 128.237055 -217.796051) (xy 128.245616 -217.769694)
			(xy 128.25349 -217.747596) (xy 128.048512 -217.392504) (xy 128.025652 -217.388186) (xy 128.000796 -217.383069)
			(xy 127.952948 -217.366166) (xy 127.908256 -217.342128) (xy 127.867777 -217.311523) (xy 127.832467 -217.275076)
			(xy 127.803161 -217.233647) (xy 127.780552 -217.188215) (xy 127.765174 -217.139855) (xy 127.75739 -217.089709)
			(xy 127.75692 -217.064336) (xy 126.536704 -217.064336) (xy 126.536089 -217.091989) (xy 126.526769 -217.146507)
			(xy 126.518162 -217.172794) (xy 126.510542 -217.194892) (xy 126.715774 -217.550238) (xy 126.738634 -217.554556)
			(xy 126.763441 -217.559728) (xy 126.811179 -217.576721) (xy 126.855756 -217.600818) (xy 126.89612 -217.631451)
			(xy 126.931323 -217.6679) (xy 126.960534 -217.709305) (xy 126.983066 -217.754693) (xy 126.998389 -217.802993)
			(xy 127.006141 -217.85307) (xy 127.006604 -217.878406) (xy 127.006096 -217.904293) (xy 126.997997 -217.955431)
			(xy 126.981998 -218.004671) (xy 126.958492 -218.050803) (xy 126.92806 -218.09269) (xy 126.89145 -218.1293)
			(xy 126.849563 -218.159732) (xy 126.803431 -218.183238) (xy 126.754191 -218.199237) (xy 126.703053 -218.207336)
			(xy 126.651279 -218.207336) (xy 126.600141 -218.199237) (xy 126.550901 -218.183238) (xy 126.504769 -218.159732)
			(xy 126.462882 -218.1293) (xy 126.426272 -218.09269) (xy 126.39584 -218.050803) (xy 126.372334 -218.004671)
			(xy 126.356335 -217.955431) (xy 126.348236 -217.904293) (xy 126.347728 -217.878406) (xy 126.348262 -217.850698)
			(xy 126.357455 -217.796051) (xy 126.366016 -217.769694) (xy 126.37389 -217.747596) (xy 126.168912 -217.392504)
			(xy 126.146052 -217.388186) (xy 126.121196 -217.383069) (xy 126.073348 -217.366166) (xy 126.028656 -217.342128)
			(xy 125.988177 -217.311523) (xy 125.952867 -217.275076) (xy 125.923561 -217.233647) (xy 125.900952 -217.188215)
			(xy 125.885574 -217.139855) (xy 125.87779 -217.089709) (xy 125.87732 -217.064336) (xy 124.657104 -217.064336)
			(xy 124.656489 -217.091989) (xy 124.647169 -217.146507) (xy 124.638562 -217.172794) (xy 124.630942 -217.194892)
			(xy 124.836174 -217.550238) (xy 124.859034 -217.554556) (xy 124.883841 -217.559728) (xy 124.931579 -217.576721)
			(xy 124.976156 -217.600818) (xy 125.01652 -217.631451) (xy 125.051723 -217.6679) (xy 125.080934 -217.709305)
			(xy 125.103466 -217.754693) (xy 125.118789 -217.802993) (xy 125.126541 -217.85307) (xy 125.127004 -217.878406)
			(xy 125.126496 -217.904293) (xy 125.118397 -217.955431) (xy 125.102398 -218.004671) (xy 125.078892 -218.050803)
			(xy 125.04846 -218.09269) (xy 125.01185 -218.1293) (xy 124.969963 -218.159732) (xy 124.923831 -218.183238)
			(xy 124.874591 -218.199237) (xy 124.823453 -218.207336) (xy 124.771679 -218.207336) (xy 124.720541 -218.199237)
			(xy 124.671301 -218.183238) (xy 124.625169 -218.159732) (xy 124.583282 -218.1293) (xy 124.546672 -218.09269)
			(xy 124.51624 -218.050803) (xy 124.492734 -218.004671) (xy 124.476735 -217.955431) (xy 124.468636 -217.904293)
			(xy 124.468128 -217.878406) (xy 124.468662 -217.850698) (xy 124.477855 -217.796051) (xy 124.486416 -217.769694)
			(xy 124.49429 -217.747596) (xy 124.289312 -217.392504) (xy 124.266452 -217.388186) (xy 124.241596 -217.383069)
			(xy 124.193748 -217.366166) (xy 124.149056 -217.342128) (xy 124.108577 -217.311523) (xy 124.073267 -217.275076)
			(xy 124.043961 -217.233647) (xy 124.021352 -217.188215) (xy 124.005974 -217.139855) (xy 123.99819 -217.089709)
			(xy 123.99772 -217.064336) (xy 122.777504 -217.064336) (xy 122.776889 -217.091989) (xy 122.767569 -217.146507)
			(xy 122.758962 -217.172794) (xy 122.751342 -217.194892) (xy 122.956574 -217.550238) (xy 122.979434 -217.554556)
			(xy 123.004241 -217.559728) (xy 123.051979 -217.576721) (xy 123.096556 -217.600818) (xy 123.13692 -217.631451)
			(xy 123.172123 -217.6679) (xy 123.201334 -217.709305) (xy 123.223866 -217.754693) (xy 123.239189 -217.802993)
			(xy 123.246941 -217.85307) (xy 123.247404 -217.878406) (xy 123.246896 -217.904293) (xy 123.238797 -217.955431)
			(xy 123.222798 -218.004671) (xy 123.199292 -218.050803) (xy 123.16886 -218.09269) (xy 123.13225 -218.1293)
			(xy 123.090363 -218.159732) (xy 123.044231 -218.183238) (xy 122.994991 -218.199237) (xy 122.943853 -218.207336)
			(xy 122.892079 -218.207336) (xy 122.840941 -218.199237) (xy 122.791701 -218.183238) (xy 122.745569 -218.159732)
			(xy 122.703682 -218.1293) (xy 122.667072 -218.09269) (xy 122.63664 -218.050803) (xy 122.613134 -218.004671)
			(xy 122.597135 -217.955431) (xy 122.589036 -217.904293) (xy 122.588528 -217.878406) (xy 122.589062 -217.850698)
			(xy 122.598255 -217.796051) (xy 122.606816 -217.769694) (xy 122.61469 -217.747596) (xy 122.409712 -217.392504)
			(xy 122.386852 -217.388186) (xy 122.361996 -217.383069) (xy 122.314148 -217.366166) (xy 122.269456 -217.342128)
			(xy 122.228977 -217.311523) (xy 122.193667 -217.275076) (xy 122.164361 -217.233647) (xy 122.141752 -217.188215)
			(xy 122.126374 -217.139855) (xy 122.11859 -217.089709) (xy 122.11812 -217.064336) (xy 120.897904 -217.064336)
			(xy 120.897289 -217.091989) (xy 120.887969 -217.146507) (xy 120.879362 -217.172794) (xy 120.871742 -217.194892)
			(xy 121.076974 -217.550238) (xy 121.099834 -217.554556) (xy 121.124641 -217.559728) (xy 121.172379 -217.576721)
			(xy 121.216956 -217.600818) (xy 121.25732 -217.631451) (xy 121.292523 -217.6679) (xy 121.321734 -217.709305)
			(xy 121.344266 -217.754693) (xy 121.359589 -217.802993) (xy 121.367341 -217.85307) (xy 121.367804 -217.878406)
			(xy 121.367296 -217.904293) (xy 121.359197 -217.955431) (xy 121.343198 -218.004671) (xy 121.319692 -218.050803)
			(xy 121.28926 -218.09269) (xy 121.25265 -218.1293) (xy 121.210763 -218.159732) (xy 121.164631 -218.183238)
			(xy 121.115391 -218.199237) (xy 121.064253 -218.207336) (xy 121.012479 -218.207336) (xy 120.961341 -218.199237)
			(xy 120.912101 -218.183238) (xy 120.865969 -218.159732) (xy 120.824082 -218.1293) (xy 120.787472 -218.09269)
			(xy 120.75704 -218.050803) (xy 120.733534 -218.004671) (xy 120.717535 -217.955431) (xy 120.709436 -217.904293)
			(xy 120.708928 -217.878406) (xy 120.709462 -217.850698) (xy 120.718655 -217.796051) (xy 120.727216 -217.769694)
			(xy 120.73509 -217.747596) (xy 120.530112 -217.392504) (xy 120.507252 -217.388186) (xy 120.482396 -217.383069)
			(xy 120.434548 -217.366166) (xy 120.389856 -217.342128) (xy 120.349377 -217.311523) (xy 120.314067 -217.275076)
			(xy 120.284761 -217.233647) (xy 120.262152 -217.188215) (xy 120.246774 -217.139855) (xy 120.23899 -217.089709)
			(xy 120.23852 -217.064336) (xy 119.018304 -217.064336) (xy 119.017689 -217.091989) (xy 119.008369 -217.146507)
			(xy 118.999762 -217.172794) (xy 118.992142 -217.194892) (xy 119.197374 -217.550238) (xy 119.220234 -217.554556)
			(xy 119.245041 -217.559728) (xy 119.292779 -217.576721) (xy 119.337356 -217.600818) (xy 119.37772 -217.631451)
			(xy 119.412923 -217.6679) (xy 119.442134 -217.709305) (xy 119.464666 -217.754693) (xy 119.479989 -217.802993)
			(xy 119.487741 -217.85307) (xy 119.488204 -217.878406) (xy 119.487696 -217.904293) (xy 119.479597 -217.955431)
			(xy 119.463598 -218.004671) (xy 119.440092 -218.050803) (xy 119.40966 -218.09269) (xy 119.37305 -218.1293)
			(xy 119.331163 -218.159732) (xy 119.285031 -218.183238) (xy 119.235791 -218.199237) (xy 119.184653 -218.207336)
			(xy 119.132879 -218.207336) (xy 119.081741 -218.199237) (xy 119.032501 -218.183238) (xy 118.986369 -218.159732)
			(xy 118.944482 -218.1293) (xy 118.907872 -218.09269) (xy 118.87744 -218.050803) (xy 118.853934 -218.004671)
			(xy 118.837935 -217.955431) (xy 118.829836 -217.904293) (xy 118.829328 -217.878406) (xy 118.829862 -217.850698)
			(xy 118.839055 -217.796051) (xy 118.847616 -217.769694) (xy 118.85549 -217.747596) (xy 118.650512 -217.392504)
			(xy 118.627652 -217.388186) (xy 118.602796 -217.383069) (xy 118.554948 -217.366166) (xy 118.510256 -217.342128)
			(xy 118.469777 -217.311523) (xy 118.434467 -217.275076) (xy 118.405161 -217.233647) (xy 118.382552 -217.188215)
			(xy 118.367174 -217.139855) (xy 118.35939 -217.089709) (xy 118.35892 -217.064336) (xy 117.138704 -217.064336)
			(xy 117.138089 -217.091989) (xy 117.128769 -217.146507) (xy 117.120162 -217.172794) (xy 117.112542 -217.194892)
			(xy 117.317774 -217.550238) (xy 117.340634 -217.554556) (xy 117.365441 -217.559728) (xy 117.413179 -217.576721)
			(xy 117.457756 -217.600818) (xy 117.49812 -217.631451) (xy 117.533323 -217.6679) (xy 117.562534 -217.709305)
			(xy 117.585066 -217.754693) (xy 117.600389 -217.802993) (xy 117.608141 -217.85307) (xy 117.608604 -217.878406)
			(xy 117.608096 -217.904293) (xy 117.599997 -217.955431) (xy 117.583998 -218.004671) (xy 117.560492 -218.050803)
			(xy 117.53006 -218.09269) (xy 117.49345 -218.1293) (xy 117.451563 -218.159732) (xy 117.405431 -218.183238)
			(xy 117.356191 -218.199237) (xy 117.305053 -218.207336) (xy 117.253279 -218.207336) (xy 117.202141 -218.199237)
			(xy 117.152901 -218.183238) (xy 117.106769 -218.159732) (xy 117.064882 -218.1293) (xy 117.028272 -218.09269)
			(xy 116.99784 -218.050803) (xy 116.974334 -218.004671) (xy 116.958335 -217.955431) (xy 116.950236 -217.904293)
			(xy 116.949728 -217.878406) (xy 116.950262 -217.850698) (xy 116.959455 -217.796051) (xy 116.968016 -217.769694)
			(xy 116.97589 -217.747596) (xy 116.770912 -217.392504) (xy 116.748052 -217.388186) (xy 116.723196 -217.383069)
			(xy 116.675348 -217.366166) (xy 116.630656 -217.342128) (xy 116.590177 -217.311523) (xy 116.554867 -217.275076)
			(xy 116.525561 -217.233647) (xy 116.502952 -217.188215) (xy 116.487574 -217.139855) (xy 116.47979 -217.089709)
			(xy 116.47932 -217.064336) (xy 115.259104 -217.064336) (xy 115.258489 -217.091989) (xy 115.249169 -217.146507)
			(xy 115.240562 -217.172794) (xy 115.232942 -217.194892) (xy 115.438174 -217.550238) (xy 115.461034 -217.554556)
			(xy 115.485841 -217.559728) (xy 115.533579 -217.576721) (xy 115.578156 -217.600818) (xy 115.61852 -217.631451)
			(xy 115.653723 -217.6679) (xy 115.682934 -217.709305) (xy 115.705466 -217.754693) (xy 115.720789 -217.802993)
			(xy 115.728541 -217.85307) (xy 115.729004 -217.878406) (xy 115.728496 -217.904293) (xy 115.720397 -217.955431)
			(xy 115.704398 -218.004671) (xy 115.680892 -218.050803) (xy 115.65046 -218.09269) (xy 115.61385 -218.1293)
			(xy 115.571963 -218.159732) (xy 115.525831 -218.183238) (xy 115.476591 -218.199237) (xy 115.425453 -218.207336)
			(xy 115.373679 -218.207336) (xy 115.322541 -218.199237) (xy 115.273301 -218.183238) (xy 115.227169 -218.159732)
			(xy 115.185282 -218.1293) (xy 115.148672 -218.09269) (xy 115.11824 -218.050803) (xy 115.094734 -218.004671)
			(xy 115.078735 -217.955431) (xy 115.070636 -217.904293) (xy 115.070128 -217.878406) (xy 115.070662 -217.850698)
			(xy 115.079855 -217.796051) (xy 115.088416 -217.769694) (xy 115.09629 -217.747596) (xy 114.891312 -217.392504)
			(xy 114.868452 -217.388186) (xy 114.843596 -217.383069) (xy 114.795748 -217.366166) (xy 114.751056 -217.342128)
			(xy 114.710577 -217.311523) (xy 114.675267 -217.275076) (xy 114.645961 -217.233647) (xy 114.623352 -217.188215)
			(xy 114.607974 -217.139855) (xy 114.60019 -217.089709) (xy 114.59972 -217.064336) (xy 113.379504 -217.064336)
			(xy 113.378889 -217.091989) (xy 113.369569 -217.146507) (xy 113.360962 -217.172794) (xy 113.353342 -217.194892)
			(xy 113.558574 -217.550238) (xy 113.581434 -217.554556) (xy 113.606241 -217.559728) (xy 113.653979 -217.576721)
			(xy 113.698556 -217.600818) (xy 113.73892 -217.631451) (xy 113.774123 -217.6679) (xy 113.803334 -217.709305)
			(xy 113.825866 -217.754693) (xy 113.841189 -217.802993) (xy 113.848941 -217.85307) (xy 113.849404 -217.878406)
			(xy 113.848896 -217.904293) (xy 113.840797 -217.955431) (xy 113.824798 -218.004671) (xy 113.801292 -218.050803)
			(xy 113.77086 -218.09269) (xy 113.73425 -218.1293) (xy 113.692363 -218.159732) (xy 113.646231 -218.183238)
			(xy 113.596991 -218.199237) (xy 113.545853 -218.207336) (xy 113.494079 -218.207336) (xy 113.442941 -218.199237)
			(xy 113.393701 -218.183238) (xy 113.347569 -218.159732) (xy 113.305682 -218.1293) (xy 113.269072 -218.09269)
			(xy 113.23864 -218.050803) (xy 113.215134 -218.004671) (xy 113.199135 -217.955431) (xy 113.191036 -217.904293)
			(xy 113.190528 -217.878406) (xy 113.191062 -217.850698) (xy 113.200255 -217.796051) (xy 113.208816 -217.769694)
			(xy 113.21669 -217.747596) (xy 113.011712 -217.392504) (xy 112.988852 -217.388186) (xy 112.963996 -217.383069)
			(xy 112.916148 -217.366166) (xy 112.871456 -217.342128) (xy 112.830977 -217.311523) (xy 112.795667 -217.275076)
			(xy 112.766361 -217.233647) (xy 112.743752 -217.188215) (xy 112.728374 -217.139855) (xy 112.72059 -217.089709)
			(xy 112.72012 -217.064336) (xy 111.499904 -217.064336) (xy 111.499412 -217.08968) (xy 111.491635 -217.13977)
			(xy 111.476286 -217.188079) (xy 111.453725 -217.233471) (xy 111.424484 -217.274876) (xy 111.389252 -217.311319)
			(xy 111.348859 -217.341943) (xy 111.304255 -217.366024) (xy 111.256492 -217.382998) (xy 111.23168 -217.388186)
			(xy 111.20882 -217.392504) (xy 111.003842 -217.747596) (xy 111.011716 -217.76944) (xy 111.020306 -217.795856)
			(xy 111.029495 -217.850633) (xy 111.030004 -217.878406) (xy 111.029496 -217.904293) (xy 111.021397 -217.955431)
			(xy 111.005398 -218.004671) (xy 110.981892 -218.050803) (xy 110.95146 -218.09269) (xy 110.91485 -218.1293)
			(xy 110.872963 -218.159732) (xy 110.826831 -218.183238) (xy 110.777591 -218.199237) (xy 110.726453 -218.207336)
			(xy 110.674679 -218.207336) (xy 110.623541 -218.199237) (xy 110.574301 -218.183238) (xy 110.528169 -218.159732)
			(xy 110.486282 -218.1293) (xy 110.449672 -218.09269) (xy 110.41924 -218.050803) (xy 110.395734 -218.004671)
			(xy 110.379735 -217.955431) (xy 110.371636 -217.904293) (xy 110.371128 -217.878406) (xy 110.090204 -217.878406)
			(xy 110.089676 -217.906114) (xy 110.08048 -217.960761) (xy 110.071916 -217.987118) (xy 110.064296 -218.008962)
			(xy 110.269274 -218.364054) (xy 110.292134 -218.368372) (xy 110.316944 -218.373529) (xy 110.364684 -218.390523)
			(xy 110.409261 -218.414621) (xy 110.449626 -218.445257) (xy 110.484829 -218.481707) (xy 110.51404 -218.523115)
			(xy 110.536571 -218.568504) (xy 110.551892 -218.616807) (xy 110.559642 -218.666885) (xy 110.560104 -218.692222)
			(xy 111.78032 -218.692222) (xy 111.780845 -218.666878) (xy 111.788614 -218.616789) (xy 111.803957 -218.56848)
			(xy 111.826512 -218.523087) (xy 111.855749 -218.481681) (xy 111.890978 -218.445236) (xy 111.931369 -218.414613)
			(xy 111.97597 -218.390531) (xy 112.023732 -218.373559) (xy 112.048544 -218.368372) (xy 112.071404 -218.364054)
			(xy 112.276636 -218.008708) (xy 112.268762 -217.98661) (xy 112.260294 -217.960366) (xy 112.251224 -217.905977)
			(xy 112.250728 -217.878406) (xy 112.251236 -217.852519) (xy 112.259335 -217.801381) (xy 112.275334 -217.752141)
			(xy 112.29884 -217.706009) (xy 112.329272 -217.664122) (xy 112.365882 -217.627512) (xy 112.407769 -217.59708)
			(xy 112.453901 -217.573574) (xy 112.503141 -217.557575) (xy 112.554279 -217.549476) (xy 112.606053 -217.549476)
			(xy 112.657191 -217.557575) (xy 112.706431 -217.573574) (xy 112.752563 -217.59708) (xy 112.79445 -217.627512)
			(xy 112.83106 -217.664122) (xy 112.861492 -217.706009) (xy 112.884998 -217.752141) (xy 112.900997 -217.801381)
			(xy 112.909096 -217.852519) (xy 112.909604 -217.878406) (xy 112.909131 -217.90378) (xy 112.901362 -217.953931)
			(xy 112.885993 -218.002296) (xy 112.863388 -218.047732) (xy 112.834082 -218.089163) (xy 112.798768 -218.125609)
			(xy 112.758282 -218.156208) (xy 112.713582 -218.180235) (xy 112.665726 -218.197122) (xy 112.640872 -218.202256)
			(xy 112.618012 -218.206574) (xy 112.413288 -218.561412) (xy 112.421162 -218.583256) (xy 112.429814 -218.609662)
			(xy 112.43913 -218.66444) (xy 112.439704 -218.692222) (xy 113.660428 -218.692222) (xy 113.660908 -218.666887)
			(xy 113.668658 -218.616813) (xy 113.683979 -218.568515) (xy 113.70651 -218.52313) (xy 113.73572 -218.481727)
			(xy 113.770922 -218.445282) (xy 113.811285 -218.414651) (xy 113.855861 -218.390558) (xy 113.903598 -218.37357)
			(xy 113.928398 -218.368372) (xy 113.951258 -218.364054) (xy 114.156236 -218.008962) (xy 114.148616 -217.986864)
			(xy 114.140092 -217.960694) (xy 114.130901 -217.906431) (xy 114.130328 -217.878914) (xy 114.130328 -217.878406)
			(xy 114.130836 -217.852519) (xy 114.138935 -217.801381) (xy 114.154934 -217.752141) (xy 114.17844 -217.706009)
			(xy 114.208872 -217.664122) (xy 114.245482 -217.627512) (xy 114.287369 -217.59708) (xy 114.333501 -217.573574)
			(xy 114.382741 -217.557575) (xy 114.433879 -217.549476) (xy 114.485653 -217.549476) (xy 114.536791 -217.557575)
			(xy 114.586031 -217.573574) (xy 114.632163 -217.59708) (xy 114.67405 -217.627512) (xy 114.71066 -217.664122)
			(xy 114.741092 -217.706009) (xy 114.764598 -217.752141) (xy 114.780597 -217.801381) (xy 114.788696 -217.852519)
			(xy 114.789204 -217.878406) (xy 114.788769 -217.903771) (xy 114.781019 -217.953906) (xy 114.765673 -218.002259)
			(xy 114.743093 -218.047686) (xy 114.713814 -218.089114) (xy 114.678529 -218.125562) (xy 114.638071 -218.156167)
			(xy 114.593399 -218.180207) (xy 114.545568 -218.197111) (xy 114.520726 -218.202256) (xy 114.497866 -218.206574)
			(xy 114.293142 -218.561412) (xy 114.301016 -218.583256) (xy 114.309609 -218.609671) (xy 114.318797 -218.664449)
			(xy 114.319304 -218.692222) (xy 115.53952 -218.692222) (xy 115.540045 -218.666878) (xy 115.547814 -218.616789)
			(xy 115.563157 -218.56848) (xy 115.585712 -218.523087) (xy 115.614949 -218.481681) (xy 115.650178 -218.445236)
			(xy 115.690569 -218.414613) (xy 115.73517 -218.390531) (xy 115.782932 -218.373559) (xy 115.807744 -218.368372)
			(xy 115.830604 -218.364054) (xy 116.035836 -218.008708) (xy 116.027962 -217.98661) (xy 116.019494 -217.960366)
			(xy 116.010424 -217.905977) (xy 116.009928 -217.878406) (xy 116.010436 -217.852519) (xy 116.018535 -217.801381)
			(xy 116.034534 -217.752141) (xy 116.05804 -217.706009) (xy 116.088472 -217.664122) (xy 116.125082 -217.627512)
			(xy 116.166969 -217.59708) (xy 116.213101 -217.573574) (xy 116.262341 -217.557575) (xy 116.313479 -217.549476)
			(xy 116.365253 -217.549476) (xy 116.416391 -217.557575) (xy 116.465631 -217.573574) (xy 116.511763 -217.59708)
			(xy 116.55365 -217.627512) (xy 116.59026 -217.664122) (xy 116.620692 -217.706009) (xy 116.644198 -217.752141)
			(xy 116.660197 -217.801381) (xy 116.668296 -217.852519) (xy 116.668804 -217.878406) (xy 116.668331 -217.90378)
			(xy 116.660562 -217.953931) (xy 116.645193 -218.002296) (xy 116.622588 -218.047732) (xy 116.593282 -218.089163)
			(xy 116.557968 -218.125609) (xy 116.517482 -218.156208) (xy 116.472782 -218.180235) (xy 116.424926 -218.197122)
			(xy 116.400072 -218.202256) (xy 116.377212 -218.206574) (xy 116.172488 -218.561412) (xy 116.180362 -218.583256)
			(xy 116.189014 -218.609662) (xy 116.19833 -218.66444) (xy 116.198904 -218.692222) (xy 117.41912 -218.692222)
			(xy 117.419645 -218.666878) (xy 117.427414 -218.616789) (xy 117.442757 -218.56848) (xy 117.465312 -218.523087)
			(xy 117.494549 -218.481681) (xy 117.529778 -218.445236) (xy 117.570169 -218.414613) (xy 117.61477 -218.390531)
			(xy 117.662532 -218.373559) (xy 117.687344 -218.368372) (xy 117.710204 -218.364054) (xy 117.915436 -218.008708)
			(xy 117.907562 -217.98661) (xy 117.899094 -217.960366) (xy 117.890024 -217.905977) (xy 117.889528 -217.878406)
			(xy 117.890036 -217.852519) (xy 117.898135 -217.801381) (xy 117.914134 -217.752141) (xy 117.93764 -217.706009)
			(xy 117.968072 -217.664122) (xy 118.004682 -217.627512) (xy 118.046569 -217.59708) (xy 118.092701 -217.573574)
			(xy 118.141941 -217.557575) (xy 118.193079 -217.549476) (xy 118.244853 -217.549476) (xy 118.295991 -217.557575)
			(xy 118.345231 -217.573574) (xy 118.391363 -217.59708) (xy 118.43325 -217.627512) (xy 118.46986 -217.664122)
			(xy 118.500292 -217.706009) (xy 118.523798 -217.752141) (xy 118.539797 -217.801381) (xy 118.547896 -217.852519)
			(xy 118.548404 -217.878406) (xy 118.547931 -217.90378) (xy 118.540162 -217.953931) (xy 118.524793 -218.002296)
			(xy 118.502188 -218.047732) (xy 118.472882 -218.089163) (xy 118.437568 -218.125609) (xy 118.397082 -218.156208)
			(xy 118.352382 -218.180235) (xy 118.304526 -218.197122) (xy 118.279672 -218.202256) (xy 118.256812 -218.206574)
			(xy 118.052088 -218.561412) (xy 118.059962 -218.583256) (xy 118.068614 -218.609662) (xy 118.07793 -218.66444)
			(xy 118.078504 -218.692222) (xy 119.29872 -218.692222) (xy 119.299245 -218.666878) (xy 119.307014 -218.616789)
			(xy 119.322357 -218.56848) (xy 119.344912 -218.523087) (xy 119.374149 -218.481681) (xy 119.409378 -218.445236)
			(xy 119.449769 -218.414613) (xy 119.49437 -218.390531) (xy 119.542132 -218.373559) (xy 119.566944 -218.368372)
			(xy 119.589804 -218.364054) (xy 119.795036 -218.008708) (xy 119.787162 -217.98661) (xy 119.778694 -217.960366)
			(xy 119.769624 -217.905977) (xy 119.769128 -217.878406) (xy 119.769636 -217.852519) (xy 119.777735 -217.801381)
			(xy 119.793734 -217.752141) (xy 119.81724 -217.706009) (xy 119.847672 -217.664122) (xy 119.884282 -217.627512)
			(xy 119.926169 -217.59708) (xy 119.972301 -217.573574) (xy 120.021541 -217.557575) (xy 120.072679 -217.549476)
			(xy 120.124453 -217.549476) (xy 120.175591 -217.557575) (xy 120.224831 -217.573574) (xy 120.270963 -217.59708)
			(xy 120.31285 -217.627512) (xy 120.34946 -217.664122) (xy 120.379892 -217.706009) (xy 120.403398 -217.752141)
			(xy 120.419397 -217.801381) (xy 120.427496 -217.852519) (xy 120.428004 -217.878406) (xy 120.427531 -217.90378)
			(xy 120.419762 -217.953931) (xy 120.404393 -218.002296) (xy 120.381788 -218.047732) (xy 120.352482 -218.089163)
			(xy 120.317168 -218.125609) (xy 120.276682 -218.156208) (xy 120.231982 -218.180235) (xy 120.184126 -218.197122)
			(xy 120.159272 -218.202256) (xy 120.136412 -218.206574) (xy 119.931688 -218.561412) (xy 119.939562 -218.583256)
			(xy 119.948214 -218.609662) (xy 119.95753 -218.66444) (xy 119.958104 -218.692222) (xy 121.17832 -218.692222)
			(xy 121.178845 -218.666878) (xy 121.186614 -218.616789) (xy 121.201957 -218.56848) (xy 121.224512 -218.523087)
			(xy 121.253749 -218.481681) (xy 121.288978 -218.445236) (xy 121.329369 -218.414613) (xy 121.37397 -218.390531)
			(xy 121.421732 -218.373559) (xy 121.446544 -218.368372) (xy 121.469404 -218.364054) (xy 121.674636 -218.008708)
			(xy 121.666762 -217.98661) (xy 121.658294 -217.960366) (xy 121.649224 -217.905977) (xy 121.648728 -217.878406)
			(xy 121.649236 -217.852519) (xy 121.657335 -217.801381) (xy 121.673334 -217.752141) (xy 121.69684 -217.706009)
			(xy 121.727272 -217.664122) (xy 121.763882 -217.627512) (xy 121.805769 -217.59708) (xy 121.851901 -217.573574)
			(xy 121.901141 -217.557575) (xy 121.952279 -217.549476) (xy 122.004053 -217.549476) (xy 122.055191 -217.557575)
			(xy 122.104431 -217.573574) (xy 122.150563 -217.59708) (xy 122.19245 -217.627512) (xy 122.22906 -217.664122)
			(xy 122.259492 -217.706009) (xy 122.282998 -217.752141) (xy 122.298997 -217.801381) (xy 122.307096 -217.852519)
			(xy 122.307604 -217.878406) (xy 122.307131 -217.90378) (xy 122.299362 -217.953931) (xy 122.283993 -218.002296)
			(xy 122.261388 -218.047732) (xy 122.232082 -218.089163) (xy 122.196768 -218.125609) (xy 122.156282 -218.156208)
			(xy 122.111582 -218.180235) (xy 122.063726 -218.197122) (xy 122.038872 -218.202256) (xy 122.016012 -218.206574)
			(xy 121.811288 -218.561412) (xy 121.819162 -218.583256) (xy 121.827814 -218.609662) (xy 121.83713 -218.66444)
			(xy 121.837704 -218.692222) (xy 123.05792 -218.692222) (xy 123.058445 -218.666878) (xy 123.066214 -218.616789)
			(xy 123.081557 -218.56848) (xy 123.104112 -218.523087) (xy 123.133349 -218.481681) (xy 123.168578 -218.445236)
			(xy 123.208969 -218.414613) (xy 123.25357 -218.390531) (xy 123.301332 -218.373559) (xy 123.326144 -218.368372)
			(xy 123.349004 -218.364054) (xy 123.554236 -218.008708) (xy 123.546362 -217.98661) (xy 123.537894 -217.960366)
			(xy 123.528824 -217.905977) (xy 123.528328 -217.878406) (xy 123.528836 -217.852519) (xy 123.536935 -217.801381)
			(xy 123.552934 -217.752141) (xy 123.57644 -217.706009) (xy 123.606872 -217.664122) (xy 123.643482 -217.627512)
			(xy 123.685369 -217.59708) (xy 123.731501 -217.573574) (xy 123.780741 -217.557575) (xy 123.831879 -217.549476)
			(xy 123.883653 -217.549476) (xy 123.934791 -217.557575) (xy 123.984031 -217.573574) (xy 124.030163 -217.59708)
			(xy 124.07205 -217.627512) (xy 124.10866 -217.664122) (xy 124.139092 -217.706009) (xy 124.162598 -217.752141)
			(xy 124.178597 -217.801381) (xy 124.186696 -217.852519) (xy 124.187204 -217.878406) (xy 124.186731 -217.90378)
			(xy 124.178962 -217.953931) (xy 124.163593 -218.002296) (xy 124.140988 -218.047732) (xy 124.111682 -218.089163)
			(xy 124.076368 -218.125609) (xy 124.035882 -218.156208) (xy 123.991182 -218.180235) (xy 123.943326 -218.197122)
			(xy 123.918472 -218.202256) (xy 123.895612 -218.206574) (xy 123.690888 -218.561412) (xy 123.698762 -218.583256)
			(xy 123.707414 -218.609662) (xy 123.71673 -218.66444) (xy 123.717304 -218.692222) (xy 124.93752 -218.692222)
			(xy 124.938045 -218.666878) (xy 124.945814 -218.616789) (xy 124.961157 -218.56848) (xy 124.983712 -218.523087)
			(xy 125.012949 -218.481681) (xy 125.048178 -218.445236) (xy 125.088569 -218.414613) (xy 125.13317 -218.390531)
			(xy 125.180932 -218.373559) (xy 125.205744 -218.368372) (xy 125.228604 -218.364054) (xy 125.433836 -218.008708)
			(xy 125.425962 -217.98661) (xy 125.417494 -217.960366) (xy 125.408424 -217.905977) (xy 125.407928 -217.878406)
			(xy 125.408436 -217.852519) (xy 125.416535 -217.801381) (xy 125.432534 -217.752141) (xy 125.45604 -217.706009)
			(xy 125.486472 -217.664122) (xy 125.523082 -217.627512) (xy 125.564969 -217.59708) (xy 125.611101 -217.573574)
			(xy 125.660341 -217.557575) (xy 125.711479 -217.549476) (xy 125.763253 -217.549476) (xy 125.814391 -217.557575)
			(xy 125.863631 -217.573574) (xy 125.909763 -217.59708) (xy 125.95165 -217.627512) (xy 125.98826 -217.664122)
			(xy 126.018692 -217.706009) (xy 126.042198 -217.752141) (xy 126.058197 -217.801381) (xy 126.066296 -217.852519)
			(xy 126.066804 -217.878406) (xy 126.066331 -217.90378) (xy 126.058562 -217.953931) (xy 126.043193 -218.002296)
			(xy 126.020588 -218.047732) (xy 125.991282 -218.089163) (xy 125.955968 -218.125609) (xy 125.915482 -218.156208)
			(xy 125.870782 -218.180235) (xy 125.822926 -218.197122) (xy 125.798072 -218.202256) (xy 125.775212 -218.206574)
			(xy 125.570488 -218.561412) (xy 125.578362 -218.583256) (xy 125.587014 -218.609662) (xy 125.59633 -218.66444)
			(xy 125.596904 -218.692222) (xy 126.81712 -218.692222) (xy 126.817645 -218.666878) (xy 126.825414 -218.616789)
			(xy 126.840757 -218.56848) (xy 126.863312 -218.523087) (xy 126.892549 -218.481681) (xy 126.927778 -218.445236)
			(xy 126.968169 -218.414613) (xy 127.01277 -218.390531) (xy 127.060532 -218.373559) (xy 127.085344 -218.368372)
			(xy 127.108204 -218.364054) (xy 127.313436 -218.008708) (xy 127.305562 -217.98661) (xy 127.297094 -217.960366)
			(xy 127.288024 -217.905977) (xy 127.287528 -217.878406) (xy 127.288036 -217.852519) (xy 127.296135 -217.801381)
			(xy 127.312134 -217.752141) (xy 127.33564 -217.706009) (xy 127.366072 -217.664122) (xy 127.402682 -217.627512)
			(xy 127.444569 -217.59708) (xy 127.490701 -217.573574) (xy 127.539941 -217.557575) (xy 127.591079 -217.549476)
			(xy 127.642853 -217.549476) (xy 127.693991 -217.557575) (xy 127.743231 -217.573574) (xy 127.789363 -217.59708)
			(xy 127.83125 -217.627512) (xy 127.86786 -217.664122) (xy 127.898292 -217.706009) (xy 127.921798 -217.752141)
			(xy 127.937797 -217.801381) (xy 127.945896 -217.852519) (xy 127.946404 -217.878406) (xy 127.945931 -217.90378)
			(xy 127.938162 -217.953931) (xy 127.922793 -218.002296) (xy 127.900188 -218.047732) (xy 127.870882 -218.089163)
			(xy 127.835568 -218.125609) (xy 127.795082 -218.156208) (xy 127.750382 -218.180235) (xy 127.702526 -218.197122)
			(xy 127.677672 -218.202256) (xy 127.654812 -218.206574) (xy 127.450088 -218.561412) (xy 127.457962 -218.583256)
			(xy 127.466614 -218.609662) (xy 127.47593 -218.66444) (xy 127.476504 -218.692222) (xy 128.69672 -218.692222)
			(xy 128.697245 -218.666878) (xy 128.705014 -218.616789) (xy 128.720357 -218.56848) (xy 128.742912 -218.523087)
			(xy 128.772149 -218.481681) (xy 128.807378 -218.445236) (xy 128.847769 -218.414613) (xy 128.89237 -218.390531)
			(xy 128.940132 -218.373559) (xy 128.964944 -218.368372) (xy 128.987804 -218.364054) (xy 129.193036 -218.008708)
			(xy 129.185162 -217.98661) (xy 129.176694 -217.960366) (xy 129.167624 -217.905977) (xy 129.167128 -217.878406)
			(xy 129.167636 -217.852519) (xy 129.175735 -217.801381) (xy 129.191734 -217.752141) (xy 129.21524 -217.706009)
			(xy 129.245672 -217.664122) (xy 129.282282 -217.627512) (xy 129.324169 -217.59708) (xy 129.370301 -217.573574)
			(xy 129.419541 -217.557575) (xy 129.470679 -217.549476) (xy 129.522453 -217.549476) (xy 129.573591 -217.557575)
			(xy 129.622831 -217.573574) (xy 129.668963 -217.59708) (xy 129.71085 -217.627512) (xy 129.74746 -217.664122)
			(xy 129.777892 -217.706009) (xy 129.801398 -217.752141) (xy 129.817397 -217.801381) (xy 129.825496 -217.852519)
			(xy 129.826004 -217.878406) (xy 129.825531 -217.90378) (xy 129.817762 -217.953931) (xy 129.802393 -218.002296)
			(xy 129.779788 -218.047732) (xy 129.750482 -218.089163) (xy 129.715168 -218.125609) (xy 129.674682 -218.156208)
			(xy 129.629982 -218.180235) (xy 129.582126 -218.197122) (xy 129.557272 -218.202256) (xy 129.534412 -218.206574)
			(xy 129.329688 -218.561412) (xy 129.337562 -218.583256) (xy 129.346214 -218.609662) (xy 129.35553 -218.66444)
			(xy 129.356104 -218.692222) (xy 130.57632 -218.692222) (xy 130.576845 -218.666878) (xy 130.584614 -218.616789)
			(xy 130.599957 -218.56848) (xy 130.622512 -218.523087) (xy 130.651749 -218.481681) (xy 130.686978 -218.445236)
			(xy 130.727369 -218.414613) (xy 130.77197 -218.390531) (xy 130.819732 -218.373559) (xy 130.844544 -218.368372)
			(xy 130.867404 -218.364054) (xy 131.072636 -218.008708) (xy 131.064762 -217.98661) (xy 131.056294 -217.960366)
			(xy 131.047224 -217.905977) (xy 131.046728 -217.878406) (xy 131.047236 -217.852519) (xy 131.055335 -217.801381)
			(xy 131.071334 -217.752141) (xy 131.09484 -217.706009) (xy 131.125272 -217.664122) (xy 131.161882 -217.627512)
			(xy 131.203769 -217.59708) (xy 131.249901 -217.573574) (xy 131.299141 -217.557575) (xy 131.350279 -217.549476)
			(xy 131.402053 -217.549476) (xy 131.453191 -217.557575) (xy 131.502431 -217.573574) (xy 131.548563 -217.59708)
			(xy 131.59045 -217.627512) (xy 131.62706 -217.664122) (xy 131.657492 -217.706009) (xy 131.680998 -217.752141)
			(xy 131.696997 -217.801381) (xy 131.705096 -217.852519) (xy 131.705604 -217.878406) (xy 131.705131 -217.90378)
			(xy 131.697362 -217.953931) (xy 131.681993 -218.002296) (xy 131.659388 -218.047732) (xy 131.630082 -218.089163)
			(xy 131.594768 -218.125609) (xy 131.554282 -218.156208) (xy 131.509582 -218.180235) (xy 131.461726 -218.197122)
			(xy 131.436872 -218.202256) (xy 131.414012 -218.206574) (xy 131.209288 -218.561412) (xy 131.217162 -218.583256)
			(xy 131.225814 -218.609662) (xy 131.23513 -218.66444) (xy 131.235704 -218.692222) (xy 132.45592 -218.692222)
			(xy 132.456445 -218.666878) (xy 132.464214 -218.616789) (xy 132.479557 -218.56848) (xy 132.502112 -218.523087)
			(xy 132.531349 -218.481681) (xy 132.566578 -218.445236) (xy 132.606969 -218.414613) (xy 132.65157 -218.390531)
			(xy 132.699332 -218.373559) (xy 132.724144 -218.368372) (xy 132.747004 -218.364054) (xy 132.952236 -218.008708)
			(xy 132.944362 -217.98661) (xy 132.935894 -217.960366) (xy 132.926824 -217.905977) (xy 132.926328 -217.878406)
			(xy 132.926836 -217.852519) (xy 132.934935 -217.801381) (xy 132.950934 -217.752141) (xy 132.97444 -217.706009)
			(xy 133.004872 -217.664122) (xy 133.041482 -217.627512) (xy 133.083369 -217.59708) (xy 133.129501 -217.573574)
			(xy 133.178741 -217.557575) (xy 133.229879 -217.549476) (xy 133.281653 -217.549476) (xy 133.332791 -217.557575)
			(xy 133.382031 -217.573574) (xy 133.428163 -217.59708) (xy 133.47005 -217.627512) (xy 133.50666 -217.664122)
			(xy 133.537092 -217.706009) (xy 133.560598 -217.752141) (xy 133.576597 -217.801381) (xy 133.584696 -217.852519)
			(xy 133.585204 -217.878406) (xy 133.584731 -217.90378) (xy 133.576962 -217.953931) (xy 133.561593 -218.002296)
			(xy 133.538988 -218.047732) (xy 133.509682 -218.089163) (xy 133.474368 -218.125609) (xy 133.433882 -218.156208)
			(xy 133.389182 -218.180235) (xy 133.341326 -218.197122) (xy 133.316472 -218.202256) (xy 133.293612 -218.206574)
			(xy 133.088888 -218.561412) (xy 133.096762 -218.583256) (xy 133.105414 -218.609662) (xy 133.11473 -218.66444)
			(xy 133.115304 -218.692222) (xy 133.114796 -218.718129) (xy 133.10669 -218.769306) (xy 133.090678 -218.818585)
			(xy 133.067155 -218.864752) (xy 133.036699 -218.906671) (xy 133.000061 -218.943309) (xy 132.958142 -218.973765)
			(xy 132.911975 -218.997288) (xy 132.862696 -219.0133) (xy 132.811519 -219.021406) (xy 132.759705 -219.021406)
			(xy 132.708528 -219.0133) (xy 132.659249 -218.997288) (xy 132.613082 -218.973765) (xy 132.571163 -218.943309)
			(xy 132.534525 -218.906671) (xy 132.504069 -218.864752) (xy 132.480546 -218.818585) (xy 132.464534 -218.769306)
			(xy 132.456428 -218.718129) (xy 132.45592 -218.692222) (xy 131.235704 -218.692222) (xy 131.235196 -218.718129)
			(xy 131.22709 -218.769306) (xy 131.211078 -218.818585) (xy 131.187555 -218.864752) (xy 131.157099 -218.906671)
			(xy 131.120461 -218.943309) (xy 131.078542 -218.973765) (xy 131.032375 -218.997288) (xy 130.983096 -219.0133)
			(xy 130.931919 -219.021406) (xy 130.880105 -219.021406) (xy 130.828928 -219.0133) (xy 130.779649 -218.997288)
			(xy 130.733482 -218.973765) (xy 130.691563 -218.943309) (xy 130.654925 -218.906671) (xy 130.624469 -218.864752)
			(xy 130.600946 -218.818585) (xy 130.584934 -218.769306) (xy 130.576828 -218.718129) (xy 130.57632 -218.692222)
			(xy 129.356104 -218.692222) (xy 129.355596 -218.718129) (xy 129.34749 -218.769306) (xy 129.331478 -218.818585)
			(xy 129.307955 -218.864752) (xy 129.277499 -218.906671) (xy 129.240861 -218.943309) (xy 129.198942 -218.973765)
			(xy 129.152775 -218.997288) (xy 129.103496 -219.0133) (xy 129.052319 -219.021406) (xy 129.000505 -219.021406)
			(xy 128.949328 -219.0133) (xy 128.900049 -218.997288) (xy 128.853882 -218.973765) (xy 128.811963 -218.943309)
			(xy 128.775325 -218.906671) (xy 128.744869 -218.864752) (xy 128.721346 -218.818585) (xy 128.705334 -218.769306)
			(xy 128.697228 -218.718129) (xy 128.69672 -218.692222) (xy 127.476504 -218.692222) (xy 127.475996 -218.718129)
			(xy 127.46789 -218.769306) (xy 127.451878 -218.818585) (xy 127.428355 -218.864752) (xy 127.397899 -218.906671)
			(xy 127.361261 -218.943309) (xy 127.319342 -218.973765) (xy 127.273175 -218.997288) (xy 127.223896 -219.0133)
			(xy 127.172719 -219.021406) (xy 127.120905 -219.021406) (xy 127.069728 -219.0133) (xy 127.020449 -218.997288)
			(xy 126.974282 -218.973765) (xy 126.932363 -218.943309) (xy 126.895725 -218.906671) (xy 126.865269 -218.864752)
			(xy 126.841746 -218.818585) (xy 126.825734 -218.769306) (xy 126.817628 -218.718129) (xy 126.81712 -218.692222)
			(xy 125.596904 -218.692222) (xy 125.596396 -218.718129) (xy 125.58829 -218.769306) (xy 125.572278 -218.818585)
			(xy 125.548755 -218.864752) (xy 125.518299 -218.906671) (xy 125.481661 -218.943309) (xy 125.439742 -218.973765)
			(xy 125.393575 -218.997288) (xy 125.344296 -219.0133) (xy 125.293119 -219.021406) (xy 125.241305 -219.021406)
			(xy 125.190128 -219.0133) (xy 125.140849 -218.997288) (xy 125.094682 -218.973765) (xy 125.052763 -218.943309)
			(xy 125.016125 -218.906671) (xy 124.985669 -218.864752) (xy 124.962146 -218.818585) (xy 124.946134 -218.769306)
			(xy 124.938028 -218.718129) (xy 124.93752 -218.692222) (xy 123.717304 -218.692222) (xy 123.716796 -218.718129)
			(xy 123.70869 -218.769306) (xy 123.692678 -218.818585) (xy 123.669155 -218.864752) (xy 123.638699 -218.906671)
			(xy 123.602061 -218.943309) (xy 123.560142 -218.973765) (xy 123.513975 -218.997288) (xy 123.464696 -219.0133)
			(xy 123.413519 -219.021406) (xy 123.361705 -219.021406) (xy 123.310528 -219.0133) (xy 123.261249 -218.997288)
			(xy 123.215082 -218.973765) (xy 123.173163 -218.943309) (xy 123.136525 -218.906671) (xy 123.106069 -218.864752)
			(xy 123.082546 -218.818585) (xy 123.066534 -218.769306) (xy 123.058428 -218.718129) (xy 123.05792 -218.692222)
			(xy 121.837704 -218.692222) (xy 121.837196 -218.718129) (xy 121.82909 -218.769306) (xy 121.813078 -218.818585)
			(xy 121.789555 -218.864752) (xy 121.759099 -218.906671) (xy 121.722461 -218.943309) (xy 121.680542 -218.973765)
			(xy 121.634375 -218.997288) (xy 121.585096 -219.0133) (xy 121.533919 -219.021406) (xy 121.482105 -219.021406)
			(xy 121.430928 -219.0133) (xy 121.381649 -218.997288) (xy 121.335482 -218.973765) (xy 121.293563 -218.943309)
			(xy 121.256925 -218.906671) (xy 121.226469 -218.864752) (xy 121.202946 -218.818585) (xy 121.186934 -218.769306)
			(xy 121.178828 -218.718129) (xy 121.17832 -218.692222) (xy 119.958104 -218.692222) (xy 119.957596 -218.718129)
			(xy 119.94949 -218.769306) (xy 119.933478 -218.818585) (xy 119.909955 -218.864752) (xy 119.879499 -218.906671)
			(xy 119.842861 -218.943309) (xy 119.800942 -218.973765) (xy 119.754775 -218.997288) (xy 119.705496 -219.0133)
			(xy 119.654319 -219.021406) (xy 119.602505 -219.021406) (xy 119.551328 -219.0133) (xy 119.502049 -218.997288)
			(xy 119.455882 -218.973765) (xy 119.413963 -218.943309) (xy 119.377325 -218.906671) (xy 119.346869 -218.864752)
			(xy 119.323346 -218.818585) (xy 119.307334 -218.769306) (xy 119.299228 -218.718129) (xy 119.29872 -218.692222)
			(xy 118.078504 -218.692222) (xy 118.077996 -218.718129) (xy 118.06989 -218.769306) (xy 118.053878 -218.818585)
			(xy 118.030355 -218.864752) (xy 117.999899 -218.906671) (xy 117.963261 -218.943309) (xy 117.921342 -218.973765)
			(xy 117.875175 -218.997288) (xy 117.825896 -219.0133) (xy 117.774719 -219.021406) (xy 117.722905 -219.021406)
			(xy 117.671728 -219.0133) (xy 117.622449 -218.997288) (xy 117.576282 -218.973765) (xy 117.534363 -218.943309)
			(xy 117.497725 -218.906671) (xy 117.467269 -218.864752) (xy 117.443746 -218.818585) (xy 117.427734 -218.769306)
			(xy 117.419628 -218.718129) (xy 117.41912 -218.692222) (xy 116.198904 -218.692222) (xy 116.198396 -218.718129)
			(xy 116.19029 -218.769306) (xy 116.174278 -218.818585) (xy 116.150755 -218.864752) (xy 116.120299 -218.906671)
			(xy 116.083661 -218.943309) (xy 116.041742 -218.973765) (xy 115.995575 -218.997288) (xy 115.946296 -219.0133)
			(xy 115.895119 -219.021406) (xy 115.843305 -219.021406) (xy 115.792128 -219.0133) (xy 115.742849 -218.997288)
			(xy 115.696682 -218.973765) (xy 115.654763 -218.943309) (xy 115.618125 -218.906671) (xy 115.587669 -218.864752)
			(xy 115.564146 -218.818585) (xy 115.548134 -218.769306) (xy 115.540028 -218.718129) (xy 115.53952 -218.692222)
			(xy 114.319304 -218.692222) (xy 114.318796 -218.718109) (xy 114.310697 -218.769247) (xy 114.294698 -218.818487)
			(xy 114.271192 -218.864619) (xy 114.24076 -218.906506) (xy 114.20415 -218.943116) (xy 114.162263 -218.973548)
			(xy 114.116131 -218.997054) (xy 114.066891 -219.013053) (xy 114.015753 -219.021152) (xy 113.963979 -219.021152)
			(xy 113.912841 -219.013053) (xy 113.863601 -218.997054) (xy 113.817469 -218.973548) (xy 113.775582 -218.943116)
			(xy 113.738972 -218.906506) (xy 113.70854 -218.864619) (xy 113.685034 -218.818487) (xy 113.669035 -218.769247)
			(xy 113.660936 -218.718109) (xy 113.660428 -218.692222) (xy 112.439704 -218.692222) (xy 112.439196 -218.718129)
			(xy 112.43109 -218.769306) (xy 112.415078 -218.818585) (xy 112.391555 -218.864752) (xy 112.361099 -218.906671)
			(xy 112.324461 -218.943309) (xy 112.282542 -218.973765) (xy 112.236375 -218.997288) (xy 112.187096 -219.0133)
			(xy 112.135919 -219.021406) (xy 112.084105 -219.021406) (xy 112.032928 -219.0133) (xy 111.983649 -218.997288)
			(xy 111.937482 -218.973765) (xy 111.895563 -218.943309) (xy 111.858925 -218.906671) (xy 111.828469 -218.864752)
			(xy 111.804946 -218.818585) (xy 111.788934 -218.769306) (xy 111.780828 -218.718129) (xy 111.78032 -218.692222)
			(xy 110.560104 -218.692222) (xy 110.559596 -218.718109) (xy 110.551497 -218.769247) (xy 110.535498 -218.818487)
			(xy 110.511992 -218.864619) (xy 110.48156 -218.906506) (xy 110.44495 -218.943116) (xy 110.403063 -218.973548)
			(xy 110.356931 -218.997054) (xy 110.307691 -219.013053) (xy 110.256553 -219.021152) (xy 110.204779 -219.021152)
			(xy 110.153641 -219.013053) (xy 110.104401 -218.997054) (xy 110.058269 -218.973548) (xy 110.016382 -218.943116)
			(xy 109.979772 -218.906506) (xy 109.94934 -218.864619) (xy 109.925834 -218.818487) (xy 109.909835 -218.769247)
			(xy 109.901736 -218.718109) (xy 109.901228 -218.692222) (xy 109.901766 -218.664514) (xy 109.910956 -218.609868)
			(xy 109.919516 -218.58351) (xy 109.92739 -218.561412) (xy 109.722412 -218.206574) (xy 109.699552 -218.202256)
			(xy 109.67472 -218.197133) (xy 109.626938 -218.180175) (xy 109.582316 -218.1561) (xy 109.541908 -218.125474)
			(xy 109.506667 -218.089022) (xy 109.477424 -218.047602) (xy 109.45487 -218.002192) (xy 109.439537 -217.953864)
			(xy 109.431786 -217.903757) (xy 109.431328 -217.878406) (xy 109.150404 -217.878406) (xy 109.149896 -217.904293)
			(xy 109.141797 -217.955431) (xy 109.125798 -218.004671) (xy 109.102292 -218.050803) (xy 109.07186 -218.09269)
			(xy 109.03525 -218.1293) (xy 108.993363 -218.159732) (xy 108.947231 -218.183238) (xy 108.897991 -218.199237)
			(xy 108.846853 -218.207336) (xy 108.795079 -218.207336) (xy 108.743941 -218.199237) (xy 108.694701 -218.183238)
			(xy 108.648569 -218.159732) (xy 108.606682 -218.1293) (xy 108.570072 -218.09269) (xy 108.53964 -218.050803)
			(xy 108.516134 -218.004671) (xy 108.500135 -217.955431) (xy 108.492036 -217.904293) (xy 108.491528 -217.878406)
			(xy 108.210604 -217.878406) (xy 108.210076 -217.906114) (xy 108.20088 -217.960761) (xy 108.192316 -217.987118)
			(xy 108.184442 -218.009216) (xy 108.38942 -218.364054) (xy 108.41228 -218.368372) (xy 108.4371 -218.37354)
			(xy 108.484878 -218.390497) (xy 108.529495 -218.41457) (xy 108.5699 -218.44519) (xy 108.60514 -218.481637)
			(xy 108.634384 -218.52305) (xy 108.656942 -218.568452) (xy 108.672281 -218.616773) (xy 108.680041 -218.666873)
			(xy 108.680504 -218.692222) (xy 108.679996 -218.718129) (xy 108.67189 -218.769306) (xy 108.655878 -218.818585)
			(xy 108.632355 -218.864752) (xy 108.601899 -218.906671) (xy 108.565261 -218.943309) (xy 108.523342 -218.973765)
			(xy 108.477175 -218.997288) (xy 108.427896 -219.0133) (xy 108.376719 -219.021406) (xy 108.324905 -219.021406)
			(xy 108.273728 -219.0133) (xy 108.224449 -218.997288) (xy 108.178282 -218.973765) (xy 108.136363 -218.943309)
			(xy 108.099725 -218.906671) (xy 108.069269 -218.864752) (xy 108.045746 -218.818585) (xy 108.029734 -218.769306)
			(xy 108.021628 -218.718129) (xy 108.02112 -218.692222) (xy 108.021718 -218.664505) (xy 108.031039 -218.609858)
			(xy 108.039662 -218.58351) (xy 108.047536 -218.561412) (xy 107.842558 -218.206574) (xy 107.819698 -218.202256)
			(xy 107.794899 -218.197049) (xy 107.747162 -218.180062) (xy 107.702585 -218.15597) (xy 107.66222 -218.125341)
			(xy 107.627017 -218.088897) (xy 107.597804 -218.047495) (xy 107.575271 -218.002112) (xy 107.559946 -217.953814)
			(xy 107.552192 -217.903741) (xy 107.551728 -217.878406) (xy 107.270804 -217.878406) (xy 107.270296 -217.904293)
			(xy 107.262197 -217.955431) (xy 107.246198 -218.004671) (xy 107.222692 -218.050803) (xy 107.19226 -218.09269)
			(xy 107.15565 -218.1293) (xy 107.113763 -218.159732) (xy 107.067631 -218.183238) (xy 107.018391 -218.199237)
			(xy 106.967253 -218.207336) (xy 106.915479 -218.207336) (xy 106.864341 -218.199237) (xy 106.815101 -218.183238)
			(xy 106.768969 -218.159732) (xy 106.727082 -218.1293) (xy 106.690472 -218.09269) (xy 106.66004 -218.050803)
			(xy 106.636534 -218.004671) (xy 106.620535 -217.955431) (xy 106.612436 -217.904293) (xy 106.611928 -217.878406)
			(xy 106.331004 -217.878406) (xy 106.330476 -217.906114) (xy 106.32128 -217.960761) (xy 106.312716 -217.987118)
			(xy 106.304842 -218.009216) (xy 106.50982 -218.364054) (xy 106.53268 -218.368372) (xy 106.5575 -218.37354)
			(xy 106.605278 -218.390497) (xy 106.649895 -218.41457) (xy 106.6903 -218.44519) (xy 106.72554 -218.481637)
			(xy 106.754784 -218.52305) (xy 106.777342 -218.568452) (xy 106.792681 -218.616773) (xy 106.800441 -218.666873)
			(xy 106.800904 -218.692222) (xy 106.800396 -218.718129) (xy 106.79229 -218.769306) (xy 106.776278 -218.818585)
			(xy 106.752755 -218.864752) (xy 106.722299 -218.906671) (xy 106.685661 -218.943309) (xy 106.643742 -218.973765)
			(xy 106.597575 -218.997288) (xy 106.548296 -219.0133) (xy 106.497119 -219.021406) (xy 106.445305 -219.021406)
			(xy 106.394128 -219.0133) (xy 106.344849 -218.997288) (xy 106.298682 -218.973765) (xy 106.256763 -218.943309)
			(xy 106.220125 -218.906671) (xy 106.189669 -218.864752) (xy 106.166146 -218.818585) (xy 106.150134 -218.769306)
			(xy 106.142028 -218.718129) (xy 106.14152 -218.692222) (xy 106.142118 -218.664505) (xy 106.151439 -218.609858)
			(xy 106.160062 -218.58351) (xy 106.167936 -218.561412) (xy 105.962958 -218.206574) (xy 105.940098 -218.202256)
			(xy 105.915299 -218.197049) (xy 105.867562 -218.180062) (xy 105.822985 -218.15597) (xy 105.78262 -218.125341)
			(xy 105.747417 -218.088897) (xy 105.718204 -218.047495) (xy 105.695671 -218.002112) (xy 105.680346 -217.953814)
			(xy 105.672592 -217.903741) (xy 105.672128 -217.878406) (xy 105.391204 -217.878406) (xy 105.390696 -217.904293)
			(xy 105.382597 -217.955431) (xy 105.366598 -218.004671) (xy 105.343092 -218.050803) (xy 105.31266 -218.09269)
			(xy 105.27605 -218.1293) (xy 105.234163 -218.159732) (xy 105.188031 -218.183238) (xy 105.138791 -218.199237)
			(xy 105.087653 -218.207336) (xy 105.035879 -218.207336) (xy 104.984741 -218.199237) (xy 104.935501 -218.183238)
			(xy 104.889369 -218.159732) (xy 104.847482 -218.1293) (xy 104.810872 -218.09269) (xy 104.78044 -218.050803)
			(xy 104.756934 -218.004671) (xy 104.740935 -217.955431) (xy 104.732836 -217.904293) (xy 104.732328 -217.878406)
			(xy 104.451404 -217.878406) (xy 104.450876 -217.906114) (xy 104.44168 -217.960761) (xy 104.433116 -217.987118)
			(xy 104.425242 -218.009216) (xy 104.63022 -218.364054) (xy 104.65308 -218.368372) (xy 104.6779 -218.37354)
			(xy 104.725678 -218.390497) (xy 104.770295 -218.41457) (xy 104.8107 -218.44519) (xy 104.84594 -218.481637)
			(xy 104.875184 -218.52305) (xy 104.897742 -218.568452) (xy 104.913081 -218.616773) (xy 104.920841 -218.666873)
			(xy 104.921304 -218.692222) (xy 104.920796 -218.718129) (xy 104.91269 -218.769306) (xy 104.896678 -218.818585)
			(xy 104.873155 -218.864752) (xy 104.842699 -218.906671) (xy 104.806061 -218.943309) (xy 104.764142 -218.973765)
			(xy 104.717975 -218.997288) (xy 104.668696 -219.0133) (xy 104.617519 -219.021406) (xy 104.565705 -219.021406)
			(xy 104.514528 -219.0133) (xy 104.465249 -218.997288) (xy 104.419082 -218.973765) (xy 104.377163 -218.943309)
			(xy 104.340525 -218.906671) (xy 104.310069 -218.864752) (xy 104.286546 -218.818585) (xy 104.270534 -218.769306)
			(xy 104.262428 -218.718129) (xy 104.26192 -218.692222) (xy 104.262518 -218.664505) (xy 104.271839 -218.609858)
			(xy 104.280462 -218.58351) (xy 104.288336 -218.561412) (xy 104.083358 -218.206574) (xy 104.060498 -218.202256)
			(xy 104.035699 -218.197049) (xy 103.987962 -218.180062) (xy 103.943385 -218.15597) (xy 103.90302 -218.125341)
			(xy 103.867817 -218.088897) (xy 103.838604 -218.047495) (xy 103.816071 -218.002112) (xy 103.800746 -217.953814)
			(xy 103.792992 -217.903741) (xy 103.792528 -217.878406) (xy 103.511604 -217.878406) (xy 103.511096 -217.904293)
			(xy 103.502997 -217.955431) (xy 103.486998 -218.004671) (xy 103.463492 -218.050803) (xy 103.43306 -218.09269)
			(xy 103.39645 -218.1293) (xy 103.354563 -218.159732) (xy 103.308431 -218.183238) (xy 103.259191 -218.199237)
			(xy 103.208053 -218.207336) (xy 103.156279 -218.207336) (xy 103.105141 -218.199237) (xy 103.055901 -218.183238)
			(xy 103.009769 -218.159732) (xy 102.967882 -218.1293) (xy 102.931272 -218.09269) (xy 102.90084 -218.050803)
			(xy 102.877334 -218.004671) (xy 102.861335 -217.955431) (xy 102.853236 -217.904293) (xy 102.852728 -217.878406)
			(xy 102.571804 -217.878406) (xy 102.571276 -217.906114) (xy 102.56208 -217.960761) (xy 102.553516 -217.987118)
			(xy 102.545642 -218.009216) (xy 102.75062 -218.364054) (xy 102.77348 -218.368372) (xy 102.7983 -218.37354)
			(xy 102.846078 -218.390497) (xy 102.890695 -218.41457) (xy 102.9311 -218.44519) (xy 102.96634 -218.481637)
			(xy 102.995584 -218.52305) (xy 103.018142 -218.568452) (xy 103.033481 -218.616773) (xy 103.041241 -218.666873)
			(xy 103.041704 -218.692222) (xy 103.041196 -218.718129) (xy 103.03309 -218.769306) (xy 103.017078 -218.818585)
			(xy 102.993555 -218.864752) (xy 102.963099 -218.906671) (xy 102.926461 -218.943309) (xy 102.884542 -218.973765)
			(xy 102.838375 -218.997288) (xy 102.789096 -219.0133) (xy 102.737919 -219.021406) (xy 102.686105 -219.021406)
			(xy 102.634928 -219.0133) (xy 102.585649 -218.997288) (xy 102.539482 -218.973765) (xy 102.497563 -218.943309)
			(xy 102.460925 -218.906671) (xy 102.430469 -218.864752) (xy 102.406946 -218.818585) (xy 102.390934 -218.769306)
			(xy 102.382828 -218.718129) (xy 102.38232 -218.692222) (xy 102.382918 -218.664505) (xy 102.392239 -218.609858)
			(xy 102.400862 -218.58351) (xy 102.408736 -218.561412) (xy 102.203758 -218.206574) (xy 102.180898 -218.202256)
			(xy 102.156099 -218.197049) (xy 102.108362 -218.180062) (xy 102.063785 -218.15597) (xy 102.02342 -218.125341)
			(xy 101.988217 -218.088897) (xy 101.959004 -218.047495) (xy 101.936471 -218.002112) (xy 101.921146 -217.953814)
			(xy 101.913392 -217.903741) (xy 101.912928 -217.878406) (xy 101.632004 -217.878406) (xy 101.631496 -217.904293)
			(xy 101.623397 -217.955431) (xy 101.607398 -218.004671) (xy 101.583892 -218.050803) (xy 101.55346 -218.09269)
			(xy 101.51685 -218.1293) (xy 101.474963 -218.159732) (xy 101.428831 -218.183238) (xy 101.379591 -218.199237)
			(xy 101.328453 -218.207336) (xy 101.276679 -218.207336) (xy 101.225541 -218.199237) (xy 101.176301 -218.183238)
			(xy 101.130169 -218.159732) (xy 101.088282 -218.1293) (xy 101.051672 -218.09269) (xy 101.02124 -218.050803)
			(xy 100.997734 -218.004671) (xy 100.981735 -217.955431) (xy 100.973636 -217.904293) (xy 100.973128 -217.878406)
			(xy 100.692204 -217.878406) (xy 100.691676 -217.906114) (xy 100.68248 -217.960761) (xy 100.673916 -217.987118)
			(xy 100.666042 -218.009216) (xy 100.87102 -218.364054) (xy 100.89388 -218.368372) (xy 100.9187 -218.37354)
			(xy 100.966478 -218.390497) (xy 101.011095 -218.41457) (xy 101.0515 -218.44519) (xy 101.08674 -218.481637)
			(xy 101.115984 -218.52305) (xy 101.138542 -218.568452) (xy 101.153881 -218.616773) (xy 101.161641 -218.666873)
			(xy 101.162104 -218.692222) (xy 101.161596 -218.718129) (xy 101.15349 -218.769306) (xy 101.137478 -218.818585)
			(xy 101.113955 -218.864752) (xy 101.083499 -218.906671) (xy 101.046861 -218.943309) (xy 101.004942 -218.973765)
			(xy 100.958775 -218.997288) (xy 100.909496 -219.0133) (xy 100.858319 -219.021406) (xy 100.806505 -219.021406)
			(xy 100.755328 -219.0133) (xy 100.706049 -218.997288) (xy 100.659882 -218.973765) (xy 100.617963 -218.943309)
			(xy 100.581325 -218.906671) (xy 100.550869 -218.864752) (xy 100.527346 -218.818585) (xy 100.511334 -218.769306)
			(xy 100.503228 -218.718129) (xy 100.50272 -218.692222) (xy 100.503318 -218.664505) (xy 100.512639 -218.609858)
			(xy 100.521262 -218.58351) (xy 100.529136 -218.561412) (xy 100.324158 -218.206574) (xy 100.301298 -218.202256)
			(xy 100.276499 -218.197049) (xy 100.228762 -218.180062) (xy 100.184185 -218.15597) (xy 100.14382 -218.125341)
			(xy 100.108617 -218.088897) (xy 100.079404 -218.047495) (xy 100.056871 -218.002112) (xy 100.041546 -217.953814)
			(xy 100.033792 -217.903741) (xy 100.033328 -217.878406) (xy 99.752404 -217.878406) (xy 99.751896 -217.904293)
			(xy 99.743797 -217.955431) (xy 99.727798 -218.004671) (xy 99.704292 -218.050803) (xy 99.67386 -218.09269)
			(xy 99.63725 -218.1293) (xy 99.595363 -218.159732) (xy 99.549231 -218.183238) (xy 99.499991 -218.199237)
			(xy 99.448853 -218.207336) (xy 99.397079 -218.207336) (xy 99.345941 -218.199237) (xy 99.296701 -218.183238)
			(xy 99.250569 -218.159732) (xy 99.208682 -218.1293) (xy 99.172072 -218.09269) (xy 99.14164 -218.050803)
			(xy 99.118134 -218.004671) (xy 99.102135 -217.955431) (xy 99.094036 -217.904293) (xy 99.093528 -217.878406)
			(xy 98.812604 -217.878406) (xy 98.812076 -217.906114) (xy 98.80288 -217.960761) (xy 98.794316 -217.987118)
			(xy 98.786442 -218.009216) (xy 98.99142 -218.364054) (xy 99.01428 -218.368372) (xy 99.0391 -218.37354)
			(xy 99.086878 -218.390497) (xy 99.131495 -218.41457) (xy 99.1719 -218.44519) (xy 99.20714 -218.481637)
			(xy 99.236384 -218.52305) (xy 99.258942 -218.568452) (xy 99.274281 -218.616773) (xy 99.282041 -218.666873)
			(xy 99.282504 -218.692222) (xy 99.281996 -218.718129) (xy 99.27389 -218.769306) (xy 99.257878 -218.818585)
			(xy 99.234355 -218.864752) (xy 99.203899 -218.906671) (xy 99.167261 -218.943309) (xy 99.125342 -218.973765)
			(xy 99.079175 -218.997288) (xy 99.029896 -219.0133) (xy 98.978719 -219.021406) (xy 98.926905 -219.021406)
			(xy 98.875728 -219.0133) (xy 98.826449 -218.997288) (xy 98.780282 -218.973765) (xy 98.738363 -218.943309)
			(xy 98.701725 -218.906671) (xy 98.671269 -218.864752) (xy 98.647746 -218.818585) (xy 98.631734 -218.769306)
			(xy 98.623628 -218.718129) (xy 98.62312 -218.692222) (xy 98.623718 -218.664505) (xy 98.633039 -218.609858)
			(xy 98.641662 -218.58351) (xy 98.649536 -218.561412) (xy 98.444558 -218.206574) (xy 98.421698 -218.202256)
			(xy 98.396899 -218.197049) (xy 98.349162 -218.180062) (xy 98.304585 -218.15597) (xy 98.26422 -218.125341)
			(xy 98.229017 -218.088897) (xy 98.199804 -218.047495) (xy 98.177271 -218.002112) (xy 98.161946 -217.953814)
			(xy 98.154192 -217.903741) (xy 98.153728 -217.878406) (xy 97.872804 -217.878406) (xy 97.872296 -217.904293)
			(xy 97.864197 -217.955431) (xy 97.848198 -218.004671) (xy 97.824692 -218.050803) (xy 97.79426 -218.09269)
			(xy 97.75765 -218.1293) (xy 97.715763 -218.159732) (xy 97.669631 -218.183238) (xy 97.620391 -218.199237)
			(xy 97.569253 -218.207336) (xy 97.517479 -218.207336) (xy 97.466341 -218.199237) (xy 97.417101 -218.183238)
			(xy 97.370969 -218.159732) (xy 97.329082 -218.1293) (xy 97.292472 -218.09269) (xy 97.26204 -218.050803)
			(xy 97.238534 -218.004671) (xy 97.222535 -217.955431) (xy 97.214436 -217.904293) (xy 97.213928 -217.878406)
			(xy 96.933004 -217.878406) (xy 96.932476 -217.906114) (xy 96.92328 -217.960761) (xy 96.914716 -217.987118)
			(xy 96.906842 -218.009216) (xy 97.11182 -218.364054) (xy 97.13468 -218.368372) (xy 97.1595 -218.37354)
			(xy 97.207278 -218.390497) (xy 97.251895 -218.41457) (xy 97.2923 -218.44519) (xy 97.32754 -218.481637)
			(xy 97.356784 -218.52305) (xy 97.379342 -218.568452) (xy 97.394681 -218.616773) (xy 97.402441 -218.666873)
			(xy 97.402904 -218.692222) (xy 97.402396 -218.718129) (xy 97.39429 -218.769306) (xy 97.378278 -218.818585)
			(xy 97.354755 -218.864752) (xy 97.324299 -218.906671) (xy 97.287661 -218.943309) (xy 97.245742 -218.973765)
			(xy 97.199575 -218.997288) (xy 97.150296 -219.0133) (xy 97.099119 -219.021406) (xy 97.047305 -219.021406)
			(xy 96.996128 -219.0133) (xy 96.946849 -218.997288) (xy 96.900682 -218.973765) (xy 96.858763 -218.943309)
			(xy 96.822125 -218.906671) (xy 96.791669 -218.864752) (xy 96.768146 -218.818585) (xy 96.752134 -218.769306)
			(xy 96.744028 -218.718129) (xy 96.74352 -218.692222) (xy 96.744118 -218.664505) (xy 96.753439 -218.609858)
			(xy 96.762062 -218.58351) (xy 96.769936 -218.561412) (xy 96.564958 -218.206574) (xy 96.542098 -218.202256)
			(xy 96.517299 -218.197049) (xy 96.469562 -218.180062) (xy 96.424985 -218.15597) (xy 96.38462 -218.125341)
			(xy 96.349417 -218.088897) (xy 96.320204 -218.047495) (xy 96.297671 -218.002112) (xy 96.282346 -217.953814)
			(xy 96.274592 -217.903741) (xy 96.274128 -217.878406) (xy 95.993204 -217.878406) (xy 95.992696 -217.904293)
			(xy 95.984597 -217.955431) (xy 95.968598 -218.004671) (xy 95.945092 -218.050803) (xy 95.91466 -218.09269)
			(xy 95.87805 -218.1293) (xy 95.836163 -218.159732) (xy 95.790031 -218.183238) (xy 95.740791 -218.199237)
			(xy 95.689653 -218.207336) (xy 95.637879 -218.207336) (xy 95.586741 -218.199237) (xy 95.537501 -218.183238)
			(xy 95.491369 -218.159732) (xy 95.449482 -218.1293) (xy 95.412872 -218.09269) (xy 95.38244 -218.050803)
			(xy 95.358934 -218.004671) (xy 95.342935 -217.955431) (xy 95.334836 -217.904293) (xy 95.334328 -217.878406)
			(xy 95.053404 -217.878406) (xy 95.052876 -217.906114) (xy 95.04368 -217.960761) (xy 95.035116 -217.987118)
			(xy 95.027242 -218.009216) (xy 95.23222 -218.364054) (xy 95.25508 -218.368372) (xy 95.2799 -218.37354)
			(xy 95.327678 -218.390497) (xy 95.372295 -218.41457) (xy 95.4127 -218.44519) (xy 95.44794 -218.481637)
			(xy 95.477184 -218.52305) (xy 95.499742 -218.568452) (xy 95.515081 -218.616773) (xy 95.522841 -218.666873)
			(xy 95.523304 -218.692222) (xy 95.522796 -218.718129) (xy 95.51469 -218.769306) (xy 95.498678 -218.818585)
			(xy 95.475155 -218.864752) (xy 95.444699 -218.906671) (xy 95.408061 -218.943309) (xy 95.366142 -218.973765)
			(xy 95.319975 -218.997288) (xy 95.270696 -219.0133) (xy 95.219519 -219.021406) (xy 95.167705 -219.021406)
			(xy 95.116528 -219.0133) (xy 95.067249 -218.997288) (xy 95.021082 -218.973765) (xy 94.979163 -218.943309)
			(xy 94.942525 -218.906671) (xy 94.912069 -218.864752) (xy 94.888546 -218.818585) (xy 94.872534 -218.769306)
			(xy 94.864428 -218.718129) (xy 94.86392 -218.692222) (xy 94.864518 -218.664505) (xy 94.873839 -218.609858)
			(xy 94.882462 -218.58351) (xy 94.890336 -218.561412) (xy 94.685358 -218.206574) (xy 94.662498 -218.202256)
			(xy 94.637699 -218.197049) (xy 94.589962 -218.180062) (xy 94.545385 -218.15597) (xy 94.50502 -218.125341)
			(xy 94.469817 -218.088897) (xy 94.440604 -218.047495) (xy 94.418071 -218.002112) (xy 94.402746 -217.953814)
			(xy 94.394992 -217.903741) (xy 94.394528 -217.878406) (xy 94.113604 -217.878406) (xy 94.113096 -217.904293)
			(xy 94.104997 -217.955431) (xy 94.088998 -218.004671) (xy 94.065492 -218.050803) (xy 94.03506 -218.09269)
			(xy 93.99845 -218.1293) (xy 93.956563 -218.159732) (xy 93.910431 -218.183238) (xy 93.861191 -218.199237)
			(xy 93.810053 -218.207336) (xy 93.758279 -218.207336) (xy 93.707141 -218.199237) (xy 93.657901 -218.183238)
			(xy 93.611769 -218.159732) (xy 93.569882 -218.1293) (xy 93.533272 -218.09269) (xy 93.50284 -218.050803)
			(xy 93.479334 -218.004671) (xy 93.463335 -217.955431) (xy 93.455236 -217.904293) (xy 93.454728 -217.878406)
			(xy 93.173804 -217.878406) (xy 93.173276 -217.906114) (xy 93.16408 -217.960761) (xy 93.155516 -217.987118)
			(xy 93.147642 -218.009216) (xy 93.35262 -218.364054) (xy 93.37548 -218.368372) (xy 93.4003 -218.37354)
			(xy 93.448078 -218.390497) (xy 93.492695 -218.41457) (xy 93.5331 -218.44519) (xy 93.56834 -218.481637)
			(xy 93.597584 -218.52305) (xy 93.620142 -218.568452) (xy 93.635481 -218.616773) (xy 93.643241 -218.666873)
			(xy 93.643704 -218.692222) (xy 93.643196 -218.718129) (xy 93.63509 -218.769306) (xy 93.619078 -218.818585)
			(xy 93.595555 -218.864752) (xy 93.565099 -218.906671) (xy 93.528461 -218.943309) (xy 93.486542 -218.973765)
			(xy 93.440375 -218.997288) (xy 93.391096 -219.0133) (xy 93.339919 -219.021406) (xy 93.288105 -219.021406)
			(xy 93.236928 -219.0133) (xy 93.187649 -218.997288) (xy 93.141482 -218.973765) (xy 93.099563 -218.943309)
			(xy 93.062925 -218.906671) (xy 93.032469 -218.864752) (xy 93.008946 -218.818585) (xy 92.992934 -218.769306)
			(xy 92.984828 -218.718129) (xy 92.98432 -218.692222) (xy 92.984918 -218.664505) (xy 92.994239 -218.609858)
			(xy 93.002862 -218.58351) (xy 93.010736 -218.561412) (xy 92.805758 -218.206574) (xy 92.782898 -218.202256)
			(xy 92.758099 -218.197049) (xy 92.710362 -218.180062) (xy 92.665785 -218.15597) (xy 92.62542 -218.125341)
			(xy 92.590217 -218.088897) (xy 92.561004 -218.047495) (xy 92.538471 -218.002112) (xy 92.523146 -217.953814)
			(xy 92.515392 -217.903741) (xy 92.514928 -217.878406) (xy 92.234004 -217.878406) (xy 92.233496 -217.904293)
			(xy 92.225397 -217.955431) (xy 92.209398 -218.004671) (xy 92.185892 -218.050803) (xy 92.15546 -218.09269)
			(xy 92.11885 -218.1293) (xy 92.076963 -218.159732) (xy 92.030831 -218.183238) (xy 91.981591 -218.199237)
			(xy 91.930453 -218.207336) (xy 91.878679 -218.207336) (xy 91.827541 -218.199237) (xy 91.778301 -218.183238)
			(xy 91.732169 -218.159732) (xy 91.690282 -218.1293) (xy 91.653672 -218.09269) (xy 91.62324 -218.050803)
			(xy 91.599734 -218.004671) (xy 91.583735 -217.955431) (xy 91.575636 -217.904293) (xy 91.575128 -217.878406)
			(xy 91.294204 -217.878406) (xy 91.293676 -217.906114) (xy 91.28448 -217.960761) (xy 91.275916 -217.987118)
			(xy 91.268042 -218.009216) (xy 91.47302 -218.364054) (xy 91.49588 -218.368372) (xy 91.5207 -218.37354)
			(xy 91.568478 -218.390497) (xy 91.613095 -218.41457) (xy 91.6535 -218.44519) (xy 91.68874 -218.481637)
			(xy 91.717984 -218.52305) (xy 91.740542 -218.568452) (xy 91.755881 -218.616773) (xy 91.763641 -218.666873)
			(xy 91.764104 -218.692222) (xy 91.763596 -218.718129) (xy 91.75549 -218.769306) (xy 91.739478 -218.818585)
			(xy 91.715955 -218.864752) (xy 91.685499 -218.906671) (xy 91.648861 -218.943309) (xy 91.606942 -218.973765)
			(xy 91.560775 -218.997288) (xy 91.511496 -219.0133) (xy 91.460319 -219.021406) (xy 91.408505 -219.021406)
			(xy 91.357328 -219.0133) (xy 91.308049 -218.997288) (xy 91.261882 -218.973765) (xy 91.219963 -218.943309)
			(xy 91.183325 -218.906671) (xy 91.152869 -218.864752) (xy 91.129346 -218.818585) (xy 91.113334 -218.769306)
			(xy 91.105228 -218.718129) (xy 91.10472 -218.692222) (xy 91.105318 -218.664505) (xy 91.114639 -218.609858)
			(xy 91.123262 -218.58351) (xy 91.131136 -218.561412) (xy 90.926158 -218.206574) (xy 90.903298 -218.202256)
			(xy 90.878499 -218.197049) (xy 90.830762 -218.180062) (xy 90.786185 -218.15597) (xy 90.74582 -218.125341)
			(xy 90.710617 -218.088897) (xy 90.681404 -218.047495) (xy 90.658871 -218.002112) (xy 90.643546 -217.953814)
			(xy 90.635792 -217.903741) (xy 90.635328 -217.878406) (xy 90.354404 -217.878406) (xy 90.353896 -217.904293)
			(xy 90.345797 -217.955431) (xy 90.329798 -218.004671) (xy 90.306292 -218.050803) (xy 90.27586 -218.09269)
			(xy 90.23925 -218.1293) (xy 90.197363 -218.159732) (xy 90.151231 -218.183238) (xy 90.101991 -218.199237)
			(xy 90.050853 -218.207336) (xy 89.999079 -218.207336) (xy 89.947941 -218.199237) (xy 89.898701 -218.183238)
			(xy 89.852569 -218.159732) (xy 89.810682 -218.1293) (xy 89.774072 -218.09269) (xy 89.74364 -218.050803)
			(xy 89.720134 -218.004671) (xy 89.704135 -217.955431) (xy 89.696036 -217.904293) (xy 89.695528 -217.878406)
			(xy 89.414604 -217.878406) (xy 89.414076 -217.906114) (xy 89.40488 -217.960761) (xy 89.396316 -217.987118)
			(xy 89.388442 -218.009216) (xy 89.59342 -218.364054) (xy 89.61628 -218.368372) (xy 89.6411 -218.37354)
			(xy 89.688878 -218.390497) (xy 89.733495 -218.41457) (xy 89.7739 -218.44519) (xy 89.80914 -218.481637)
			(xy 89.838384 -218.52305) (xy 89.860942 -218.568452) (xy 89.876281 -218.616773) (xy 89.884041 -218.666873)
			(xy 89.884504 -218.692222) (xy 89.883996 -218.718129) (xy 89.87589 -218.769306) (xy 89.859878 -218.818585)
			(xy 89.836355 -218.864752) (xy 89.805899 -218.906671) (xy 89.769261 -218.943309) (xy 89.727342 -218.973765)
			(xy 89.681175 -218.997288) (xy 89.631896 -219.0133) (xy 89.580719 -219.021406) (xy 89.528905 -219.021406)
			(xy 89.477728 -219.0133) (xy 89.428449 -218.997288) (xy 89.382282 -218.973765) (xy 89.340363 -218.943309)
			(xy 89.303725 -218.906671) (xy 89.273269 -218.864752) (xy 89.249746 -218.818585) (xy 89.233734 -218.769306)
			(xy 89.225628 -218.718129) (xy 89.22512 -218.692222) (xy 89.225718 -218.664505) (xy 89.235039 -218.609858)
			(xy 89.243662 -218.58351) (xy 89.251536 -218.561412) (xy 89.046558 -218.206574) (xy 89.023698 -218.202256)
			(xy 88.998899 -218.197049) (xy 88.951162 -218.180062) (xy 88.906585 -218.15597) (xy 88.86622 -218.125341)
			(xy 88.831017 -218.088897) (xy 88.801804 -218.047495) (xy 88.779271 -218.002112) (xy 88.763946 -217.953814)
			(xy 88.756192 -217.903741) (xy 88.755728 -217.878406) (xy 2.509012 -217.878406) (xy 2.509012 -221.133924)
			(xy 88.755728 -221.133924) (xy 88.756236 -221.108037) (xy 88.764335 -221.056899) (xy 88.780334 -221.007659)
			(xy 88.80384 -220.961527) (xy 88.834272 -220.91964) (xy 88.870882 -220.88303) (xy 88.912769 -220.852598)
			(xy 88.958901 -220.829092) (xy 89.008141 -220.813093) (xy 89.059279 -220.804994) (xy 89.111053 -220.804994)
			(xy 89.162191 -220.813093) (xy 89.211431 -220.829092) (xy 89.257563 -220.852598) (xy 89.29945 -220.88303)
			(xy 89.33606 -220.91964) (xy 89.366492 -220.961527) (xy 89.389998 -221.007659) (xy 89.405997 -221.056899)
			(xy 89.414096 -221.108037) (xy 89.414604 -221.133924) (xy 89.695528 -221.133924) (xy 89.69601 -221.108589)
			(xy 89.70376 -221.058515) (xy 89.71908 -221.010217) (xy 89.741611 -220.964832) (xy 89.770821 -220.923429)
			(xy 89.806022 -220.886984) (xy 89.846386 -220.856354) (xy 89.890961 -220.83226) (xy 89.938698 -220.815272)
			(xy 89.963498 -220.810074) (xy 89.986358 -220.805756) (xy 90.191336 -220.450664) (xy 90.183462 -220.42882)
			(xy 90.174829 -220.402408) (xy 90.1655 -220.347635) (xy 90.16492 -220.319854) (xy 90.165428 -220.293947)
			(xy 90.173534 -220.24277) (xy 90.189546 -220.193491) (xy 90.213069 -220.147324) (xy 90.243525 -220.105405)
			(xy 90.280163 -220.068767) (xy 90.322082 -220.038311) (xy 90.368249 -220.014788) (xy 90.417528 -219.998776)
			(xy 90.468705 -219.99067) (xy 90.520519 -219.99067) (xy 90.571696 -219.998776) (xy 90.620975 -220.014788)
			(xy 90.667142 -220.038311) (xy 90.709061 -220.068767) (xy 90.745699 -220.105405) (xy 90.776155 -220.147324)
			(xy 90.799678 -220.193491) (xy 90.81569 -220.24277) (xy 90.823796 -220.293947) (xy 90.824304 -220.319854)
			(xy 90.823828 -220.345199) (xy 90.816049 -220.395289) (xy 90.800697 -220.443599) (xy 90.778134 -220.48899)
			(xy 90.748891 -220.530396) (xy 90.713657 -220.566839) (xy 90.673262 -220.597461) (xy 90.628657 -220.621543)
			(xy 90.580893 -220.638516) (xy 90.55608 -220.643704) (xy 90.53322 -220.648022) (xy 90.328242 -221.003114)
			(xy 90.336116 -221.024958) (xy 90.34471 -221.051373) (xy 90.353897 -221.106151) (xy 90.354404 -221.133924)
			(xy 90.635328 -221.133924) (xy 90.635836 -221.108037) (xy 90.643935 -221.056899) (xy 90.659934 -221.007659)
			(xy 90.68344 -220.961527) (xy 90.713872 -220.91964) (xy 90.750482 -220.88303) (xy 90.792369 -220.852598)
			(xy 90.838501 -220.829092) (xy 90.887741 -220.813093) (xy 90.938879 -220.804994) (xy 90.990653 -220.804994)
			(xy 91.041791 -220.813093) (xy 91.091031 -220.829092) (xy 91.137163 -220.852598) (xy 91.17905 -220.88303)
			(xy 91.21566 -220.91964) (xy 91.246092 -220.961527) (xy 91.269598 -221.007659) (xy 91.285597 -221.056899)
			(xy 91.293696 -221.108037) (xy 91.294204 -221.133924) (xy 91.575128 -221.133924) (xy 91.57561 -221.108589)
			(xy 91.58336 -221.058515) (xy 91.59868 -221.010217) (xy 91.621211 -220.964832) (xy 91.650421 -220.923429)
			(xy 91.685622 -220.886984) (xy 91.725986 -220.856354) (xy 91.770561 -220.83226) (xy 91.818298 -220.815272)
			(xy 91.843098 -220.810074) (xy 91.865958 -220.805756) (xy 92.070936 -220.450664) (xy 92.063062 -220.42882)
			(xy 92.054429 -220.402408) (xy 92.0451 -220.347635) (xy 92.04452 -220.319854) (xy 92.045028 -220.293947)
			(xy 92.053134 -220.24277) (xy 92.069146 -220.193491) (xy 92.092669 -220.147324) (xy 92.123125 -220.105405)
			(xy 92.159763 -220.068767) (xy 92.201682 -220.038311) (xy 92.247849 -220.014788) (xy 92.297128 -219.998776)
			(xy 92.348305 -219.99067) (xy 92.400119 -219.99067) (xy 92.451296 -219.998776) (xy 92.500575 -220.014788)
			(xy 92.546742 -220.038311) (xy 92.588661 -220.068767) (xy 92.625299 -220.105405) (xy 92.655755 -220.147324)
			(xy 92.679278 -220.193491) (xy 92.69529 -220.24277) (xy 92.703396 -220.293947) (xy 92.703904 -220.319854)
			(xy 92.703428 -220.345199) (xy 92.695649 -220.395289) (xy 92.680297 -220.443599) (xy 92.657734 -220.48899)
			(xy 92.628491 -220.530396) (xy 92.593257 -220.566839) (xy 92.552862 -220.597461) (xy 92.508257 -220.621543)
			(xy 92.460493 -220.638516) (xy 92.43568 -220.643704) (xy 92.41282 -220.648022) (xy 92.207842 -221.003114)
			(xy 92.215716 -221.024958) (xy 92.22431 -221.051373) (xy 92.233497 -221.106151) (xy 92.234004 -221.133924)
			(xy 92.514928 -221.133924) (xy 92.515436 -221.108037) (xy 92.523535 -221.056899) (xy 92.539534 -221.007659)
			(xy 92.56304 -220.961527) (xy 92.593472 -220.91964) (xy 92.630082 -220.88303) (xy 92.671969 -220.852598)
			(xy 92.718101 -220.829092) (xy 92.767341 -220.813093) (xy 92.818479 -220.804994) (xy 92.870253 -220.804994)
			(xy 92.921391 -220.813093) (xy 92.970631 -220.829092) (xy 93.016763 -220.852598) (xy 93.05865 -220.88303)
			(xy 93.09526 -220.91964) (xy 93.125692 -220.961527) (xy 93.149198 -221.007659) (xy 93.165197 -221.056899)
			(xy 93.173296 -221.108037) (xy 93.173804 -221.133924) (xy 93.454728 -221.133924) (xy 93.45521 -221.108589)
			(xy 93.46296 -221.058515) (xy 93.47828 -221.010217) (xy 93.500811 -220.964832) (xy 93.530021 -220.923429)
			(xy 93.565222 -220.886984) (xy 93.605586 -220.856354) (xy 93.650161 -220.83226) (xy 93.697898 -220.815272)
			(xy 93.722698 -220.810074) (xy 93.745558 -220.805756) (xy 93.950536 -220.450664) (xy 93.942662 -220.42882)
			(xy 93.934029 -220.402408) (xy 93.9247 -220.347635) (xy 93.92412 -220.319854) (xy 93.924628 -220.293947)
			(xy 93.932734 -220.24277) (xy 93.948746 -220.193491) (xy 93.972269 -220.147324) (xy 94.002725 -220.105405)
			(xy 94.039363 -220.068767) (xy 94.081282 -220.038311) (xy 94.127449 -220.014788) (xy 94.176728 -219.998776)
			(xy 94.227905 -219.99067) (xy 94.279719 -219.99067) (xy 94.330896 -219.998776) (xy 94.380175 -220.014788)
			(xy 94.426342 -220.038311) (xy 94.468261 -220.068767) (xy 94.504899 -220.105405) (xy 94.535355 -220.147324)
			(xy 94.558878 -220.193491) (xy 94.57489 -220.24277) (xy 94.582996 -220.293947) (xy 94.583504 -220.319854)
			(xy 94.583028 -220.345199) (xy 94.575249 -220.395289) (xy 94.559897 -220.443599) (xy 94.537334 -220.48899)
			(xy 94.508091 -220.530396) (xy 94.472857 -220.566839) (xy 94.432462 -220.597461) (xy 94.387857 -220.621543)
			(xy 94.340093 -220.638516) (xy 94.31528 -220.643704) (xy 94.29242 -220.648022) (xy 94.087442 -221.003114)
			(xy 94.095316 -221.024958) (xy 94.10391 -221.051373) (xy 94.113097 -221.106151) (xy 94.113604 -221.133924)
			(xy 94.394528 -221.133924) (xy 94.395036 -221.108037) (xy 94.403135 -221.056899) (xy 94.419134 -221.007659)
			(xy 94.44264 -220.961527) (xy 94.473072 -220.91964) (xy 94.509682 -220.88303) (xy 94.551569 -220.852598)
			(xy 94.597701 -220.829092) (xy 94.646941 -220.813093) (xy 94.698079 -220.804994) (xy 94.749853 -220.804994)
			(xy 94.800991 -220.813093) (xy 94.850231 -220.829092) (xy 94.896363 -220.852598) (xy 94.93825 -220.88303)
			(xy 94.97486 -220.91964) (xy 95.005292 -220.961527) (xy 95.028798 -221.007659) (xy 95.044797 -221.056899)
			(xy 95.052896 -221.108037) (xy 95.053404 -221.133924) (xy 95.334328 -221.133924) (xy 95.33481 -221.108589)
			(xy 95.34256 -221.058515) (xy 95.35788 -221.010217) (xy 95.380411 -220.964832) (xy 95.409621 -220.923429)
			(xy 95.444822 -220.886984) (xy 95.485186 -220.856354) (xy 95.529761 -220.83226) (xy 95.577498 -220.815272)
			(xy 95.602298 -220.810074) (xy 95.625158 -220.805756) (xy 95.830136 -220.450664) (xy 95.822262 -220.42882)
			(xy 95.813629 -220.402408) (xy 95.8043 -220.347635) (xy 95.80372 -220.319854) (xy 95.804228 -220.293947)
			(xy 95.812334 -220.24277) (xy 95.828346 -220.193491) (xy 95.851869 -220.147324) (xy 95.882325 -220.105405)
			(xy 95.918963 -220.068767) (xy 95.960882 -220.038311) (xy 96.007049 -220.014788) (xy 96.056328 -219.998776)
			(xy 96.107505 -219.99067) (xy 96.159319 -219.99067) (xy 96.210496 -219.998776) (xy 96.259775 -220.014788)
			(xy 96.305942 -220.038311) (xy 96.347861 -220.068767) (xy 96.384499 -220.105405) (xy 96.414955 -220.147324)
			(xy 96.438478 -220.193491) (xy 96.45449 -220.24277) (xy 96.462596 -220.293947) (xy 96.463104 -220.319854)
			(xy 96.462628 -220.345199) (xy 96.454849 -220.395289) (xy 96.439497 -220.443599) (xy 96.416934 -220.48899)
			(xy 96.387691 -220.530396) (xy 96.352457 -220.566839) (xy 96.312062 -220.597461) (xy 96.267457 -220.621543)
			(xy 96.219693 -220.638516) (xy 96.19488 -220.643704) (xy 96.17202 -220.648022) (xy 95.967042 -221.003114)
			(xy 95.974916 -221.024958) (xy 95.98351 -221.051373) (xy 95.992697 -221.106151) (xy 95.993204 -221.133924)
			(xy 96.274128 -221.133924) (xy 96.274636 -221.108037) (xy 96.282735 -221.056899) (xy 96.298734 -221.007659)
			(xy 96.32224 -220.961527) (xy 96.352672 -220.91964) (xy 96.389282 -220.88303) (xy 96.431169 -220.852598)
			(xy 96.477301 -220.829092) (xy 96.526541 -220.813093) (xy 96.577679 -220.804994) (xy 96.629453 -220.804994)
			(xy 96.680591 -220.813093) (xy 96.729831 -220.829092) (xy 96.775963 -220.852598) (xy 96.81785 -220.88303)
			(xy 96.85446 -220.91964) (xy 96.884892 -220.961527) (xy 96.908398 -221.007659) (xy 96.924397 -221.056899)
			(xy 96.932496 -221.108037) (xy 96.933004 -221.133924) (xy 97.213928 -221.133924) (xy 97.21441 -221.108589)
			(xy 97.22216 -221.058515) (xy 97.23748 -221.010217) (xy 97.260011 -220.964832) (xy 97.289221 -220.923429)
			(xy 97.324422 -220.886984) (xy 97.364786 -220.856354) (xy 97.409361 -220.83226) (xy 97.457098 -220.815272)
			(xy 97.481898 -220.810074) (xy 97.504758 -220.805756) (xy 97.709736 -220.450664) (xy 97.701862 -220.42882)
			(xy 97.693229 -220.402408) (xy 97.6839 -220.347635) (xy 97.68332 -220.319854) (xy 97.683828 -220.293947)
			(xy 97.691934 -220.24277) (xy 97.707946 -220.193491) (xy 97.731469 -220.147324) (xy 97.761925 -220.105405)
			(xy 97.798563 -220.068767) (xy 97.840482 -220.038311) (xy 97.886649 -220.014788) (xy 97.935928 -219.998776)
			(xy 97.987105 -219.99067) (xy 98.038919 -219.99067) (xy 98.090096 -219.998776) (xy 98.139375 -220.014788)
			(xy 98.185542 -220.038311) (xy 98.227461 -220.068767) (xy 98.264099 -220.105405) (xy 98.294555 -220.147324)
			(xy 98.318078 -220.193491) (xy 98.33409 -220.24277) (xy 98.342196 -220.293947) (xy 98.342704 -220.319854)
			(xy 98.342228 -220.345199) (xy 98.334449 -220.395289) (xy 98.319097 -220.443599) (xy 98.296534 -220.48899)
			(xy 98.267291 -220.530396) (xy 98.232057 -220.566839) (xy 98.191662 -220.597461) (xy 98.147057 -220.621543)
			(xy 98.099293 -220.638516) (xy 98.07448 -220.643704) (xy 98.05162 -220.648022) (xy 97.846642 -221.003114)
			(xy 97.854516 -221.024958) (xy 97.86311 -221.051373) (xy 97.872297 -221.106151) (xy 97.872804 -221.133924)
			(xy 98.153728 -221.133924) (xy 98.154236 -221.108037) (xy 98.162335 -221.056899) (xy 98.178334 -221.007659)
			(xy 98.20184 -220.961527) (xy 98.232272 -220.91964) (xy 98.268882 -220.88303) (xy 98.310769 -220.852598)
			(xy 98.356901 -220.829092) (xy 98.406141 -220.813093) (xy 98.457279 -220.804994) (xy 98.509053 -220.804994)
			(xy 98.560191 -220.813093) (xy 98.609431 -220.829092) (xy 98.655563 -220.852598) (xy 98.69745 -220.88303)
			(xy 98.73406 -220.91964) (xy 98.764492 -220.961527) (xy 98.787998 -221.007659) (xy 98.803997 -221.056899)
			(xy 98.812096 -221.108037) (xy 98.812604 -221.133924) (xy 99.093528 -221.133924) (xy 99.09401 -221.108589)
			(xy 99.10176 -221.058515) (xy 99.11708 -221.010217) (xy 99.139611 -220.964832) (xy 99.168821 -220.923429)
			(xy 99.204022 -220.886984) (xy 99.244386 -220.856354) (xy 99.288961 -220.83226) (xy 99.336698 -220.815272)
			(xy 99.361498 -220.810074) (xy 99.384358 -220.805756) (xy 99.589336 -220.450664) (xy 99.581462 -220.42882)
			(xy 99.572829 -220.402408) (xy 99.5635 -220.347635) (xy 99.56292 -220.319854) (xy 99.563428 -220.293947)
			(xy 99.571534 -220.24277) (xy 99.587546 -220.193491) (xy 99.611069 -220.147324) (xy 99.641525 -220.105405)
			(xy 99.678163 -220.068767) (xy 99.720082 -220.038311) (xy 99.766249 -220.014788) (xy 99.815528 -219.998776)
			(xy 99.866705 -219.99067) (xy 99.918519 -219.99067) (xy 99.969696 -219.998776) (xy 100.018975 -220.014788)
			(xy 100.065142 -220.038311) (xy 100.107061 -220.068767) (xy 100.143699 -220.105405) (xy 100.174155 -220.147324)
			(xy 100.197678 -220.193491) (xy 100.21369 -220.24277) (xy 100.221796 -220.293947) (xy 100.222304 -220.319854)
			(xy 100.221828 -220.345199) (xy 100.214049 -220.395289) (xy 100.198697 -220.443599) (xy 100.176134 -220.48899)
			(xy 100.146891 -220.530396) (xy 100.111657 -220.566839) (xy 100.071262 -220.597461) (xy 100.026657 -220.621543)
			(xy 99.978893 -220.638516) (xy 99.95408 -220.643704) (xy 99.93122 -220.648022) (xy 99.726242 -221.003114)
			(xy 99.734116 -221.024958) (xy 99.74271 -221.051373) (xy 99.751897 -221.106151) (xy 99.752404 -221.133924)
			(xy 100.033328 -221.133924) (xy 100.033836 -221.108037) (xy 100.041935 -221.056899) (xy 100.057934 -221.007659)
			(xy 100.08144 -220.961527) (xy 100.111872 -220.91964) (xy 100.148482 -220.88303) (xy 100.190369 -220.852598)
			(xy 100.236501 -220.829092) (xy 100.285741 -220.813093) (xy 100.336879 -220.804994) (xy 100.388653 -220.804994)
			(xy 100.439791 -220.813093) (xy 100.489031 -220.829092) (xy 100.535163 -220.852598) (xy 100.57705 -220.88303)
			(xy 100.61366 -220.91964) (xy 100.644092 -220.961527) (xy 100.667598 -221.007659) (xy 100.683597 -221.056899)
			(xy 100.691696 -221.108037) (xy 100.692204 -221.133924) (xy 100.973128 -221.133924) (xy 100.97361 -221.108589)
			(xy 100.98136 -221.058515) (xy 100.99668 -221.010217) (xy 101.019211 -220.964832) (xy 101.048421 -220.923429)
			(xy 101.083622 -220.886984) (xy 101.123986 -220.856354) (xy 101.168561 -220.83226) (xy 101.216298 -220.815272)
			(xy 101.241098 -220.810074) (xy 101.263958 -220.805756) (xy 101.468936 -220.450664) (xy 101.461062 -220.42882)
			(xy 101.452429 -220.402408) (xy 101.4431 -220.347635) (xy 101.44252 -220.319854) (xy 101.443028 -220.293947)
			(xy 101.451134 -220.24277) (xy 101.467146 -220.193491) (xy 101.490669 -220.147324) (xy 101.521125 -220.105405)
			(xy 101.557763 -220.068767) (xy 101.599682 -220.038311) (xy 101.645849 -220.014788) (xy 101.695128 -219.998776)
			(xy 101.746305 -219.99067) (xy 101.798119 -219.99067) (xy 101.849296 -219.998776) (xy 101.898575 -220.014788)
			(xy 101.944742 -220.038311) (xy 101.986661 -220.068767) (xy 102.023299 -220.105405) (xy 102.053755 -220.147324)
			(xy 102.077278 -220.193491) (xy 102.09329 -220.24277) (xy 102.101396 -220.293947) (xy 102.101904 -220.319854)
			(xy 102.101428 -220.345199) (xy 102.093649 -220.395289) (xy 102.078297 -220.443599) (xy 102.055734 -220.48899)
			(xy 102.026491 -220.530396) (xy 101.991257 -220.566839) (xy 101.950862 -220.597461) (xy 101.906257 -220.621543)
			(xy 101.858493 -220.638516) (xy 101.83368 -220.643704) (xy 101.81082 -220.648022) (xy 101.605842 -221.003114)
			(xy 101.613716 -221.024958) (xy 101.62231 -221.051373) (xy 101.631497 -221.106151) (xy 101.632004 -221.133924)
			(xy 101.912928 -221.133924) (xy 101.913436 -221.108037) (xy 101.921535 -221.056899) (xy 101.937534 -221.007659)
			(xy 101.96104 -220.961527) (xy 101.991472 -220.91964) (xy 102.028082 -220.88303) (xy 102.069969 -220.852598)
			(xy 102.116101 -220.829092) (xy 102.165341 -220.813093) (xy 102.216479 -220.804994) (xy 102.268253 -220.804994)
			(xy 102.319391 -220.813093) (xy 102.368631 -220.829092) (xy 102.414763 -220.852598) (xy 102.45665 -220.88303)
			(xy 102.49326 -220.91964) (xy 102.523692 -220.961527) (xy 102.547198 -221.007659) (xy 102.563197 -221.056899)
			(xy 102.571296 -221.108037) (xy 102.571804 -221.133924) (xy 102.852728 -221.133924) (xy 102.85321 -221.108589)
			(xy 102.86096 -221.058515) (xy 102.87628 -221.010217) (xy 102.898811 -220.964832) (xy 102.928021 -220.923429)
			(xy 102.963222 -220.886984) (xy 103.003586 -220.856354) (xy 103.048161 -220.83226) (xy 103.095898 -220.815272)
			(xy 103.120698 -220.810074) (xy 103.143558 -220.805756) (xy 103.348536 -220.450664) (xy 103.340662 -220.42882)
			(xy 103.332029 -220.402408) (xy 103.3227 -220.347635) (xy 103.32212 -220.319854) (xy 103.322628 -220.293947)
			(xy 103.330734 -220.24277) (xy 103.346746 -220.193491) (xy 103.370269 -220.147324) (xy 103.400725 -220.105405)
			(xy 103.437363 -220.068767) (xy 103.479282 -220.038311) (xy 103.525449 -220.014788) (xy 103.574728 -219.998776)
			(xy 103.625905 -219.99067) (xy 103.677719 -219.99067) (xy 103.728896 -219.998776) (xy 103.778175 -220.014788)
			(xy 103.824342 -220.038311) (xy 103.866261 -220.068767) (xy 103.902899 -220.105405) (xy 103.933355 -220.147324)
			(xy 103.956878 -220.193491) (xy 103.97289 -220.24277) (xy 103.980996 -220.293947) (xy 103.981504 -220.319854)
			(xy 105.20172 -220.319854) (xy 105.202228 -220.293947) (xy 105.210334 -220.24277) (xy 105.226346 -220.193491)
			(xy 105.249869 -220.147324) (xy 105.280325 -220.105405) (xy 105.316963 -220.068767) (xy 105.358882 -220.038311)
			(xy 105.405049 -220.014788) (xy 105.454328 -219.998776) (xy 105.505505 -219.99067) (xy 105.557319 -219.99067)
			(xy 105.608496 -219.998776) (xy 105.657775 -220.014788) (xy 105.703942 -220.038311) (xy 105.745861 -220.068767)
			(xy 105.782499 -220.105405) (xy 105.812955 -220.147324) (xy 105.836478 -220.193491) (xy 105.85249 -220.24277)
			(xy 105.860596 -220.293947) (xy 105.861104 -220.319854) (xy 107.08132 -220.319854) (xy 107.081828 -220.293947)
			(xy 107.089934 -220.24277) (xy 107.105946 -220.193491) (xy 107.129469 -220.147324) (xy 107.159925 -220.105405)
			(xy 107.196563 -220.068767) (xy 107.238482 -220.038311) (xy 107.284649 -220.014788) (xy 107.333928 -219.998776)
			(xy 107.385105 -219.99067) (xy 107.436919 -219.99067) (xy 107.488096 -219.998776) (xy 107.537375 -220.014788)
			(xy 107.583542 -220.038311) (xy 107.625461 -220.068767) (xy 107.662099 -220.105405) (xy 107.692555 -220.147324)
			(xy 107.716078 -220.193491) (xy 107.73209 -220.24277) (xy 107.740196 -220.293947) (xy 107.740704 -220.319854)
			(xy 108.96092 -220.319854) (xy 108.961428 -220.293947) (xy 108.969534 -220.24277) (xy 108.985546 -220.193491)
			(xy 109.009069 -220.147324) (xy 109.039525 -220.105405) (xy 109.076163 -220.068767) (xy 109.118082 -220.038311)
			(xy 109.164249 -220.014788) (xy 109.213528 -219.998776) (xy 109.264705 -219.99067) (xy 109.316519 -219.99067)
			(xy 109.367696 -219.998776) (xy 109.416975 -220.014788) (xy 109.463142 -220.038311) (xy 109.505061 -220.068767)
			(xy 109.541699 -220.105405) (xy 109.572155 -220.147324) (xy 109.595678 -220.193491) (xy 109.61169 -220.24277)
			(xy 109.619796 -220.293947) (xy 109.620304 -220.319854) (xy 110.84052 -220.319854) (xy 110.841028 -220.293947)
			(xy 110.849134 -220.24277) (xy 110.865146 -220.193491) (xy 110.888669 -220.147324) (xy 110.919125 -220.105405)
			(xy 110.955763 -220.068767) (xy 110.997682 -220.038311) (xy 111.043849 -220.014788) (xy 111.093128 -219.998776)
			(xy 111.144305 -219.99067) (xy 111.196119 -219.99067) (xy 111.247296 -219.998776) (xy 111.296575 -220.014788)
			(xy 111.342742 -220.038311) (xy 111.384661 -220.068767) (xy 111.421299 -220.105405) (xy 111.451755 -220.147324)
			(xy 111.475278 -220.193491) (xy 111.49129 -220.24277) (xy 111.499396 -220.293947) (xy 111.499904 -220.319854)
			(xy 112.72012 -220.319854) (xy 112.720628 -220.293947) (xy 112.728734 -220.24277) (xy 112.744746 -220.193491)
			(xy 112.768269 -220.147324) (xy 112.798725 -220.105405) (xy 112.835363 -220.068767) (xy 112.877282 -220.038311)
			(xy 112.923449 -220.014788) (xy 112.972728 -219.998776) (xy 113.023905 -219.99067) (xy 113.075719 -219.99067)
			(xy 113.126896 -219.998776) (xy 113.176175 -220.014788) (xy 113.222342 -220.038311) (xy 113.264261 -220.068767)
			(xy 113.300899 -220.105405) (xy 113.331355 -220.147324) (xy 113.354878 -220.193491) (xy 113.37089 -220.24277)
			(xy 113.378996 -220.293947) (xy 113.379504 -220.319854) (xy 114.59972 -220.319854) (xy 114.600228 -220.293947)
			(xy 114.608334 -220.24277) (xy 114.624346 -220.193491) (xy 114.647869 -220.147324) (xy 114.678325 -220.105405)
			(xy 114.714963 -220.068767) (xy 114.756882 -220.038311) (xy 114.803049 -220.014788) (xy 114.852328 -219.998776)
			(xy 114.903505 -219.99067) (xy 114.955319 -219.99067) (xy 115.006496 -219.998776) (xy 115.055775 -220.014788)
			(xy 115.101942 -220.038311) (xy 115.143861 -220.068767) (xy 115.180499 -220.105405) (xy 115.210955 -220.147324)
			(xy 115.234478 -220.193491) (xy 115.25049 -220.24277) (xy 115.258596 -220.293947) (xy 115.259104 -220.319854)
			(xy 116.47932 -220.319854) (xy 116.479828 -220.293947) (xy 116.487934 -220.24277) (xy 116.503946 -220.193491)
			(xy 116.527469 -220.147324) (xy 116.557925 -220.105405) (xy 116.594563 -220.068767) (xy 116.636482 -220.038311)
			(xy 116.682649 -220.014788) (xy 116.731928 -219.998776) (xy 116.783105 -219.99067) (xy 116.834919 -219.99067)
			(xy 116.886096 -219.998776) (xy 116.935375 -220.014788) (xy 116.981542 -220.038311) (xy 117.023461 -220.068767)
			(xy 117.060099 -220.105405) (xy 117.090555 -220.147324) (xy 117.114078 -220.193491) (xy 117.13009 -220.24277)
			(xy 117.138196 -220.293947) (xy 117.138704 -220.319854) (xy 118.35892 -220.319854) (xy 118.359428 -220.293947)
			(xy 118.367534 -220.24277) (xy 118.383546 -220.193491) (xy 118.407069 -220.147324) (xy 118.437525 -220.105405)
			(xy 118.474163 -220.068767) (xy 118.516082 -220.038311) (xy 118.562249 -220.014788) (xy 118.611528 -219.998776)
			(xy 118.662705 -219.99067) (xy 118.714519 -219.99067) (xy 118.765696 -219.998776) (xy 118.814975 -220.014788)
			(xy 118.861142 -220.038311) (xy 118.903061 -220.068767) (xy 118.939699 -220.105405) (xy 118.970155 -220.147324)
			(xy 118.993678 -220.193491) (xy 119.00969 -220.24277) (xy 119.017796 -220.293947) (xy 119.018304 -220.319854)
			(xy 120.23852 -220.319854) (xy 120.239028 -220.293947) (xy 120.247134 -220.24277) (xy 120.263146 -220.193491)
			(xy 120.286669 -220.147324) (xy 120.317125 -220.105405) (xy 120.353763 -220.068767) (xy 120.395682 -220.038311)
			(xy 120.441849 -220.014788) (xy 120.491128 -219.998776) (xy 120.542305 -219.99067) (xy 120.594119 -219.99067)
			(xy 120.645296 -219.998776) (xy 120.694575 -220.014788) (xy 120.740742 -220.038311) (xy 120.782661 -220.068767)
			(xy 120.819299 -220.105405) (xy 120.849755 -220.147324) (xy 120.873278 -220.193491) (xy 120.88929 -220.24277)
			(xy 120.897396 -220.293947) (xy 120.897904 -220.319854) (xy 122.11812 -220.319854) (xy 122.118628 -220.293947)
			(xy 122.126734 -220.24277) (xy 122.142746 -220.193491) (xy 122.166269 -220.147324) (xy 122.196725 -220.105405)
			(xy 122.233363 -220.068767) (xy 122.275282 -220.038311) (xy 122.321449 -220.014788) (xy 122.370728 -219.998776)
			(xy 122.421905 -219.99067) (xy 122.473719 -219.99067) (xy 122.524896 -219.998776) (xy 122.574175 -220.014788)
			(xy 122.620342 -220.038311) (xy 122.662261 -220.068767) (xy 122.698899 -220.105405) (xy 122.729355 -220.147324)
			(xy 122.752878 -220.193491) (xy 122.76889 -220.24277) (xy 122.776996 -220.293947) (xy 122.777504 -220.319854)
			(xy 123.99772 -220.319854) (xy 123.998228 -220.293947) (xy 124.006334 -220.24277) (xy 124.022346 -220.193491)
			(xy 124.045869 -220.147324) (xy 124.076325 -220.105405) (xy 124.112963 -220.068767) (xy 124.154882 -220.038311)
			(xy 124.201049 -220.014788) (xy 124.250328 -219.998776) (xy 124.301505 -219.99067) (xy 124.353319 -219.99067)
			(xy 124.404496 -219.998776) (xy 124.453775 -220.014788) (xy 124.499942 -220.038311) (xy 124.541861 -220.068767)
			(xy 124.578499 -220.105405) (xy 124.608955 -220.147324) (xy 124.632478 -220.193491) (xy 124.64849 -220.24277)
			(xy 124.656596 -220.293947) (xy 124.657104 -220.319854) (xy 125.87732 -220.319854) (xy 125.877828 -220.293947)
			(xy 125.885934 -220.24277) (xy 125.901946 -220.193491) (xy 125.925469 -220.147324) (xy 125.955925 -220.105405)
			(xy 125.992563 -220.068767) (xy 126.034482 -220.038311) (xy 126.080649 -220.014788) (xy 126.129928 -219.998776)
			(xy 126.181105 -219.99067) (xy 126.232919 -219.99067) (xy 126.284096 -219.998776) (xy 126.333375 -220.014788)
			(xy 126.379542 -220.038311) (xy 126.421461 -220.068767) (xy 126.458099 -220.105405) (xy 126.488555 -220.147324)
			(xy 126.512078 -220.193491) (xy 126.52809 -220.24277) (xy 126.536196 -220.293947) (xy 126.536704 -220.319854)
			(xy 127.75692 -220.319854) (xy 127.757428 -220.293947) (xy 127.765534 -220.24277) (xy 127.781546 -220.193491)
			(xy 127.805069 -220.147324) (xy 127.835525 -220.105405) (xy 127.872163 -220.068767) (xy 127.914082 -220.038311)
			(xy 127.960249 -220.014788) (xy 128.009528 -219.998776) (xy 128.060705 -219.99067) (xy 128.112519 -219.99067)
			(xy 128.163696 -219.998776) (xy 128.212975 -220.014788) (xy 128.259142 -220.038311) (xy 128.301061 -220.068767)
			(xy 128.337699 -220.105405) (xy 128.368155 -220.147324) (xy 128.391678 -220.193491) (xy 128.40769 -220.24277)
			(xy 128.415796 -220.293947) (xy 128.416304 -220.319854) (xy 129.63652 -220.319854) (xy 129.637028 -220.293947)
			(xy 129.645134 -220.24277) (xy 129.661146 -220.193491) (xy 129.684669 -220.147324) (xy 129.715125 -220.105405)
			(xy 129.751763 -220.068767) (xy 129.793682 -220.038311) (xy 129.839849 -220.014788) (xy 129.889128 -219.998776)
			(xy 129.940305 -219.99067) (xy 129.992119 -219.99067) (xy 130.043296 -219.998776) (xy 130.092575 -220.014788)
			(xy 130.138742 -220.038311) (xy 130.180661 -220.068767) (xy 130.217299 -220.105405) (xy 130.247755 -220.147324)
			(xy 130.271278 -220.193491) (xy 130.28729 -220.24277) (xy 130.295396 -220.293947) (xy 130.295904 -220.319854)
			(xy 131.51612 -220.319854) (xy 131.516628 -220.293947) (xy 131.524734 -220.24277) (xy 131.540746 -220.193491)
			(xy 131.564269 -220.147324) (xy 131.594725 -220.105405) (xy 131.631363 -220.068767) (xy 131.673282 -220.038311)
			(xy 131.719449 -220.014788) (xy 131.768728 -219.998776) (xy 131.819905 -219.99067) (xy 131.871719 -219.99067)
			(xy 131.922896 -219.998776) (xy 131.972175 -220.014788) (xy 132.018342 -220.038311) (xy 132.060261 -220.068767)
			(xy 132.096899 -220.105405) (xy 132.127355 -220.147324) (xy 132.150878 -220.193491) (xy 132.16689 -220.24277)
			(xy 132.174996 -220.293947) (xy 132.175504 -220.319854) (xy 133.396228 -220.319854) (xy 133.396736 -220.293967)
			(xy 133.404835 -220.242829) (xy 133.420834 -220.193589) (xy 133.44434 -220.147457) (xy 133.474772 -220.10557)
			(xy 133.511382 -220.06896) (xy 133.553269 -220.038528) (xy 133.599401 -220.015022) (xy 133.648641 -219.999023)
			(xy 133.699779 -219.990924) (xy 133.751553 -219.990924) (xy 133.802691 -219.999023) (xy 133.851931 -220.015022)
			(xy 133.898063 -220.038528) (xy 133.93995 -220.06896) (xy 133.97656 -220.10557) (xy 134.006992 -220.147457)
			(xy 134.030498 -220.193589) (xy 134.046497 -220.242829) (xy 134.054596 -220.293967) (xy 134.055104 -220.319854)
			(xy 134.054563 -220.347562) (xy 134.045375 -220.402208) (xy 134.036816 -220.428566) (xy 134.029196 -220.450664)
			(xy 134.234174 -220.805756) (xy 134.257034 -220.810074) (xy 134.281845 -220.815229) (xy 134.329584 -220.832223)
			(xy 134.374162 -220.856322) (xy 134.414527 -220.886957) (xy 134.44973 -220.923408) (xy 134.47894 -220.964816)
			(xy 134.501472 -221.010206) (xy 134.516792 -221.058509) (xy 134.524542 -221.108587) (xy 134.525004 -221.133924)
			(xy 336.695796 -221.133924) (xy 336.696304 -221.108037) (xy 336.704403 -221.056899) (xy 336.720402 -221.007659)
			(xy 336.743908 -220.961527) (xy 336.77434 -220.91964) (xy 336.81095 -220.88303) (xy 336.852837 -220.852598)
			(xy 336.898969 -220.829092) (xy 336.948209 -220.813093) (xy 336.999347 -220.804994) (xy 337.051121 -220.804994)
			(xy 337.102259 -220.813093) (xy 337.151499 -220.829092) (xy 337.197631 -220.852598) (xy 337.239518 -220.88303)
			(xy 337.276128 -220.91964) (xy 337.30656 -220.961527) (xy 337.330066 -221.007659) (xy 337.346065 -221.056899)
			(xy 337.354164 -221.108037) (xy 337.354672 -221.133924) (xy 337.635596 -221.133924) (xy 337.636104 -221.10859)
			(xy 337.643853 -221.058519) (xy 337.659172 -221.010223) (xy 337.6817 -220.96484) (xy 337.710906 -220.923438)
			(xy 337.746104 -220.886992) (xy 337.786463 -220.856361) (xy 337.831034 -220.832266) (xy 337.878767 -220.815274)
			(xy 337.903566 -220.810074) (xy 337.926426 -220.805756) (xy 338.131404 -220.450664) (xy 338.12353 -220.42882)
			(xy 338.114896 -220.402408) (xy 338.105568 -220.347635) (xy 338.104988 -220.319854) (xy 338.105496 -220.293947)
			(xy 338.113602 -220.24277) (xy 338.129614 -220.193491) (xy 338.153137 -220.147324) (xy 338.183593 -220.105405)
			(xy 338.220231 -220.068767) (xy 338.26215 -220.038311) (xy 338.308317 -220.014788) (xy 338.357596 -219.998776)
			(xy 338.408773 -219.99067) (xy 338.460587 -219.99067) (xy 338.511764 -219.998776) (xy 338.561043 -220.014788)
			(xy 338.60721 -220.038311) (xy 338.649129 -220.068767) (xy 338.685767 -220.105405) (xy 338.716223 -220.147324)
			(xy 338.739746 -220.193491) (xy 338.755758 -220.24277) (xy 338.763864 -220.293947) (xy 338.764372 -220.319854)
			(xy 338.763922 -220.3452) (xy 338.756142 -220.395293) (xy 338.740788 -220.443604) (xy 338.718222 -220.488998)
			(xy 338.688976 -220.530404) (xy 338.653739 -220.566847) (xy 338.61334 -220.597469) (xy 338.568731 -220.621548)
			(xy 338.520963 -220.638518) (xy 338.496148 -220.643704) (xy 338.473288 -220.648022) (xy 338.26831 -221.003114)
			(xy 338.276184 -221.024958) (xy 338.284777 -221.051373) (xy 338.293965 -221.106151) (xy 338.294472 -221.133924)
			(xy 338.575396 -221.133924) (xy 338.575904 -221.108037) (xy 338.584003 -221.056899) (xy 338.600002 -221.007659)
			(xy 338.623508 -220.961527) (xy 338.65394 -220.91964) (xy 338.69055 -220.88303) (xy 338.732437 -220.852598)
			(xy 338.778569 -220.829092) (xy 338.827809 -220.813093) (xy 338.878947 -220.804994) (xy 338.930721 -220.804994)
			(xy 338.981859 -220.813093) (xy 339.031099 -220.829092) (xy 339.077231 -220.852598) (xy 339.119118 -220.88303)
			(xy 339.155728 -220.91964) (xy 339.18616 -220.961527) (xy 339.209666 -221.007659) (xy 339.225665 -221.056899)
			(xy 339.233764 -221.108037) (xy 339.234272 -221.133924) (xy 339.515196 -221.133924) (xy 339.515704 -221.10859)
			(xy 339.523453 -221.058519) (xy 339.538772 -221.010223) (xy 339.5613 -220.96484) (xy 339.590506 -220.923438)
			(xy 339.625704 -220.886992) (xy 339.666063 -220.856361) (xy 339.710634 -220.832266) (xy 339.758367 -220.815274)
			(xy 339.783166 -220.810074) (xy 339.806026 -220.805756) (xy 340.011004 -220.450664) (xy 340.00313 -220.42882)
			(xy 339.994496 -220.402408) (xy 339.985168 -220.347635) (xy 339.984588 -220.319854) (xy 339.985096 -220.293947)
			(xy 339.993202 -220.24277) (xy 340.009214 -220.193491) (xy 340.032737 -220.147324) (xy 340.063193 -220.105405)
			(xy 340.099831 -220.068767) (xy 340.14175 -220.038311) (xy 340.187917 -220.014788) (xy 340.237196 -219.998776)
			(xy 340.288373 -219.99067) (xy 340.340187 -219.99067) (xy 340.391364 -219.998776) (xy 340.440643 -220.014788)
			(xy 340.48681 -220.038311) (xy 340.528729 -220.068767) (xy 340.565367 -220.105405) (xy 340.595823 -220.147324)
			(xy 340.619346 -220.193491) (xy 340.635358 -220.24277) (xy 340.643464 -220.293947) (xy 340.643972 -220.319854)
			(xy 340.643522 -220.3452) (xy 340.635742 -220.395293) (xy 340.620388 -220.443604) (xy 340.597822 -220.488998)
			(xy 340.568576 -220.530404) (xy 340.533339 -220.566847) (xy 340.49294 -220.597469) (xy 340.448331 -220.621548)
			(xy 340.400563 -220.638518) (xy 340.375748 -220.643704) (xy 340.352888 -220.648022) (xy 340.14791 -221.003114)
			(xy 340.155784 -221.024958) (xy 340.164377 -221.051373) (xy 340.173565 -221.106151) (xy 340.174072 -221.133924)
			(xy 340.454996 -221.133924) (xy 340.455504 -221.108037) (xy 340.463603 -221.056899) (xy 340.479602 -221.007659)
			(xy 340.503108 -220.961527) (xy 340.53354 -220.91964) (xy 340.57015 -220.88303) (xy 340.612037 -220.852598)
			(xy 340.658169 -220.829092) (xy 340.707409 -220.813093) (xy 340.758547 -220.804994) (xy 340.810321 -220.804994)
			(xy 340.861459 -220.813093) (xy 340.910699 -220.829092) (xy 340.956831 -220.852598) (xy 340.998718 -220.88303)
			(xy 341.035328 -220.91964) (xy 341.06576 -220.961527) (xy 341.089266 -221.007659) (xy 341.105265 -221.056899)
			(xy 341.113364 -221.108037) (xy 341.113872 -221.133924) (xy 341.394796 -221.133924) (xy 341.395304 -221.10859)
			(xy 341.403053 -221.058519) (xy 341.418372 -221.010223) (xy 341.4409 -220.96484) (xy 341.470106 -220.923438)
			(xy 341.505304 -220.886992) (xy 341.545663 -220.856361) (xy 341.590234 -220.832266) (xy 341.637967 -220.815274)
			(xy 341.662766 -220.810074) (xy 341.685626 -220.805756) (xy 341.890604 -220.450664) (xy 341.88273 -220.42882)
			(xy 341.874096 -220.402408) (xy 341.864768 -220.347635) (xy 341.864188 -220.319854) (xy 341.864696 -220.293947)
			(xy 341.872802 -220.24277) (xy 341.888814 -220.193491) (xy 341.912337 -220.147324) (xy 341.942793 -220.105405)
			(xy 341.979431 -220.068767) (xy 342.02135 -220.038311) (xy 342.067517 -220.014788) (xy 342.116796 -219.998776)
			(xy 342.167973 -219.99067) (xy 342.219787 -219.99067) (xy 342.270964 -219.998776) (xy 342.320243 -220.014788)
			(xy 342.36641 -220.038311) (xy 342.408329 -220.068767) (xy 342.444967 -220.105405) (xy 342.475423 -220.147324)
			(xy 342.498946 -220.193491) (xy 342.514958 -220.24277) (xy 342.523064 -220.293947) (xy 342.523572 -220.319854)
			(xy 342.523122 -220.3452) (xy 342.515342 -220.395293) (xy 342.499988 -220.443604) (xy 342.477422 -220.488998)
			(xy 342.448176 -220.530404) (xy 342.412939 -220.566847) (xy 342.37254 -220.597469) (xy 342.327931 -220.621548)
			(xy 342.280163 -220.638518) (xy 342.255348 -220.643704) (xy 342.232488 -220.648022) (xy 342.02751 -221.003114)
			(xy 342.035384 -221.024958) (xy 342.043977 -221.051373) (xy 342.053165 -221.106151) (xy 342.053672 -221.133924)
			(xy 342.334596 -221.133924) (xy 342.335104 -221.108037) (xy 342.343203 -221.056899) (xy 342.359202 -221.007659)
			(xy 342.382708 -220.961527) (xy 342.41314 -220.91964) (xy 342.44975 -220.88303) (xy 342.491637 -220.852598)
			(xy 342.537769 -220.829092) (xy 342.587009 -220.813093) (xy 342.638147 -220.804994) (xy 342.689921 -220.804994)
			(xy 342.741059 -220.813093) (xy 342.790299 -220.829092) (xy 342.836431 -220.852598) (xy 342.878318 -220.88303)
			(xy 342.914928 -220.91964) (xy 342.94536 -220.961527) (xy 342.968866 -221.007659) (xy 342.984865 -221.056899)
			(xy 342.992964 -221.108037) (xy 342.993472 -221.133924) (xy 343.274396 -221.133924) (xy 343.274904 -221.10859)
			(xy 343.282653 -221.058519) (xy 343.297972 -221.010223) (xy 343.3205 -220.96484) (xy 343.349706 -220.923438)
			(xy 343.384904 -220.886992) (xy 343.425263 -220.856361) (xy 343.469834 -220.832266) (xy 343.517567 -220.815274)
			(xy 343.542366 -220.810074) (xy 343.565226 -220.805756) (xy 343.770204 -220.450664) (xy 343.76233 -220.42882)
			(xy 343.753696 -220.402408) (xy 343.744368 -220.347635) (xy 343.743788 -220.319854) (xy 343.744296 -220.293947)
			(xy 343.752402 -220.24277) (xy 343.768414 -220.193491) (xy 343.791937 -220.147324) (xy 343.822393 -220.105405)
			(xy 343.859031 -220.068767) (xy 343.90095 -220.038311) (xy 343.947117 -220.014788) (xy 343.996396 -219.998776)
			(xy 344.047573 -219.99067) (xy 344.099387 -219.99067) (xy 344.150564 -219.998776) (xy 344.199843 -220.014788)
			(xy 344.24601 -220.038311) (xy 344.287929 -220.068767) (xy 344.324567 -220.105405) (xy 344.355023 -220.147324)
			(xy 344.378546 -220.193491) (xy 344.394558 -220.24277) (xy 344.402664 -220.293947) (xy 344.403172 -220.319854)
			(xy 344.402722 -220.3452) (xy 344.394942 -220.395293) (xy 344.379588 -220.443604) (xy 344.357022 -220.488998)
			(xy 344.327776 -220.530404) (xy 344.292539 -220.566847) (xy 344.25214 -220.597469) (xy 344.207531 -220.621548)
			(xy 344.159763 -220.638518) (xy 344.134948 -220.643704) (xy 344.112088 -220.648022) (xy 343.90711 -221.003114)
			(xy 343.914984 -221.024958) (xy 343.923577 -221.051373) (xy 343.932765 -221.106151) (xy 343.933272 -221.133924)
			(xy 344.214196 -221.133924) (xy 344.214704 -221.108037) (xy 344.222803 -221.056899) (xy 344.238802 -221.007659)
			(xy 344.262308 -220.961527) (xy 344.29274 -220.91964) (xy 344.32935 -220.88303) (xy 344.371237 -220.852598)
			(xy 344.417369 -220.829092) (xy 344.466609 -220.813093) (xy 344.517747 -220.804994) (xy 344.569521 -220.804994)
			(xy 344.620659 -220.813093) (xy 344.669899 -220.829092) (xy 344.716031 -220.852598) (xy 344.757918 -220.88303)
			(xy 344.794528 -220.91964) (xy 344.82496 -220.961527) (xy 344.848466 -221.007659) (xy 344.864465 -221.056899)
			(xy 344.872564 -221.108037) (xy 344.873072 -221.133924) (xy 345.153996 -221.133924) (xy 345.154504 -221.10859)
			(xy 345.162253 -221.058519) (xy 345.177572 -221.010223) (xy 345.2001 -220.96484) (xy 345.229306 -220.923438)
			(xy 345.264504 -220.886992) (xy 345.304863 -220.856361) (xy 345.349434 -220.832266) (xy 345.397167 -220.815274)
			(xy 345.421966 -220.810074) (xy 345.444826 -220.805756) (xy 345.649804 -220.450664) (xy 345.64193 -220.42882)
			(xy 345.633296 -220.402408) (xy 345.623968 -220.347635) (xy 345.623388 -220.319854) (xy 345.623896 -220.293947)
			(xy 345.632002 -220.24277) (xy 345.648014 -220.193491) (xy 345.671537 -220.147324) (xy 345.701993 -220.105405)
			(xy 345.738631 -220.068767) (xy 345.78055 -220.038311) (xy 345.826717 -220.014788) (xy 345.875996 -219.998776)
			(xy 345.927173 -219.99067) (xy 345.978987 -219.99067) (xy 346.030164 -219.998776) (xy 346.079443 -220.014788)
			(xy 346.12561 -220.038311) (xy 346.167529 -220.068767) (xy 346.204167 -220.105405) (xy 346.234623 -220.147324)
			(xy 346.258146 -220.193491) (xy 346.274158 -220.24277) (xy 346.282264 -220.293947) (xy 346.282772 -220.319854)
			(xy 346.282322 -220.3452) (xy 346.274542 -220.395293) (xy 346.259188 -220.443604) (xy 346.236622 -220.488998)
			(xy 346.207376 -220.530404) (xy 346.172139 -220.566847) (xy 346.13174 -220.597469) (xy 346.087131 -220.621548)
			(xy 346.039363 -220.638518) (xy 346.014548 -220.643704) (xy 345.991688 -220.648022) (xy 345.78671 -221.003114)
			(xy 345.794584 -221.024958) (xy 345.803177 -221.051373) (xy 345.812365 -221.106151) (xy 345.812872 -221.133924)
			(xy 346.093796 -221.133924) (xy 346.094304 -221.108037) (xy 346.102403 -221.056899) (xy 346.118402 -221.007659)
			(xy 346.141908 -220.961527) (xy 346.17234 -220.91964) (xy 346.20895 -220.88303) (xy 346.250837 -220.852598)
			(xy 346.296969 -220.829092) (xy 346.346209 -220.813093) (xy 346.397347 -220.804994) (xy 346.449121 -220.804994)
			(xy 346.500259 -220.813093) (xy 346.549499 -220.829092) (xy 346.595631 -220.852598) (xy 346.637518 -220.88303)
			(xy 346.674128 -220.91964) (xy 346.70456 -220.961527) (xy 346.728066 -221.007659) (xy 346.744065 -221.056899)
			(xy 346.752164 -221.108037) (xy 346.752672 -221.133924) (xy 347.033596 -221.133924) (xy 347.034104 -221.10859)
			(xy 347.041853 -221.058519) (xy 347.057172 -221.010223) (xy 347.0797 -220.96484) (xy 347.108906 -220.923438)
			(xy 347.144104 -220.886992) (xy 347.184463 -220.856361) (xy 347.229034 -220.832266) (xy 347.276767 -220.815274)
			(xy 347.301566 -220.810074) (xy 347.324426 -220.805756) (xy 347.529404 -220.450664) (xy 347.52153 -220.42882)
			(xy 347.512896 -220.402408) (xy 347.503568 -220.347635) (xy 347.502988 -220.319854) (xy 347.503496 -220.293947)
			(xy 347.511602 -220.24277) (xy 347.527614 -220.193491) (xy 347.551137 -220.147324) (xy 347.581593 -220.105405)
			(xy 347.618231 -220.068767) (xy 347.66015 -220.038311) (xy 347.706317 -220.014788) (xy 347.755596 -219.998776)
			(xy 347.806773 -219.99067) (xy 347.858587 -219.99067) (xy 347.909764 -219.998776) (xy 347.959043 -220.014788)
			(xy 348.00521 -220.038311) (xy 348.047129 -220.068767) (xy 348.083767 -220.105405) (xy 348.114223 -220.147324)
			(xy 348.137746 -220.193491) (xy 348.153758 -220.24277) (xy 348.161864 -220.293947) (xy 348.162372 -220.319854)
			(xy 348.161922 -220.3452) (xy 348.154142 -220.395293) (xy 348.138788 -220.443604) (xy 348.116222 -220.488998)
			(xy 348.086976 -220.530404) (xy 348.051739 -220.566847) (xy 348.01134 -220.597469) (xy 347.966731 -220.621548)
			(xy 347.918963 -220.638518) (xy 347.894148 -220.643704) (xy 347.871288 -220.648022) (xy 347.66631 -221.003114)
			(xy 347.674184 -221.024958) (xy 347.682777 -221.051373) (xy 347.691965 -221.106151) (xy 347.692472 -221.133924)
			(xy 347.973396 -221.133924) (xy 347.973904 -221.108037) (xy 347.982003 -221.056899) (xy 347.998002 -221.007659)
			(xy 348.021508 -220.961527) (xy 348.05194 -220.91964) (xy 348.08855 -220.88303) (xy 348.130437 -220.852598)
			(xy 348.176569 -220.829092) (xy 348.225809 -220.813093) (xy 348.276947 -220.804994) (xy 348.328721 -220.804994)
			(xy 348.379859 -220.813093) (xy 348.429099 -220.829092) (xy 348.475231 -220.852598) (xy 348.517118 -220.88303)
			(xy 348.553728 -220.91964) (xy 348.58416 -220.961527) (xy 348.607666 -221.007659) (xy 348.623665 -221.056899)
			(xy 348.631764 -221.108037) (xy 348.632272 -221.133924) (xy 348.913196 -221.133924) (xy 348.913704 -221.10859)
			(xy 348.921453 -221.058519) (xy 348.936772 -221.010223) (xy 348.9593 -220.96484) (xy 348.988506 -220.923438)
			(xy 349.023704 -220.886992) (xy 349.064063 -220.856361) (xy 349.108634 -220.832266) (xy 349.156367 -220.815274)
			(xy 349.181166 -220.810074) (xy 349.204026 -220.805756) (xy 349.409004 -220.450664) (xy 349.40113 -220.42882)
			(xy 349.392496 -220.402408) (xy 349.383168 -220.347635) (xy 349.382588 -220.319854) (xy 349.383096 -220.293947)
			(xy 349.391202 -220.24277) (xy 349.407214 -220.193491) (xy 349.430737 -220.147324) (xy 349.461193 -220.105405)
			(xy 349.497831 -220.068767) (xy 349.53975 -220.038311) (xy 349.585917 -220.014788) (xy 349.635196 -219.998776)
			(xy 349.686373 -219.99067) (xy 349.738187 -219.99067) (xy 349.789364 -219.998776) (xy 349.838643 -220.014788)
			(xy 349.88481 -220.038311) (xy 349.926729 -220.068767) (xy 349.963367 -220.105405) (xy 349.993823 -220.147324)
			(xy 350.017346 -220.193491) (xy 350.033358 -220.24277) (xy 350.041464 -220.293947) (xy 350.041972 -220.319854)
			(xy 350.041522 -220.3452) (xy 350.033742 -220.395293) (xy 350.018388 -220.443604) (xy 349.995822 -220.488998)
			(xy 349.966576 -220.530404) (xy 349.931339 -220.566847) (xy 349.89094 -220.597469) (xy 349.846331 -220.621548)
			(xy 349.798563 -220.638518) (xy 349.773748 -220.643704) (xy 349.750888 -220.648022) (xy 349.54591 -221.003114)
			(xy 349.553784 -221.024958) (xy 349.562377 -221.051373) (xy 349.571565 -221.106151) (xy 349.572072 -221.133924)
			(xy 349.852996 -221.133924) (xy 349.853504 -221.108037) (xy 349.861603 -221.056899) (xy 349.877602 -221.007659)
			(xy 349.901108 -220.961527) (xy 349.93154 -220.91964) (xy 349.96815 -220.88303) (xy 350.010037 -220.852598)
			(xy 350.056169 -220.829092) (xy 350.105409 -220.813093) (xy 350.156547 -220.804994) (xy 350.208321 -220.804994)
			(xy 350.259459 -220.813093) (xy 350.308699 -220.829092) (xy 350.354831 -220.852598) (xy 350.396718 -220.88303)
			(xy 350.433328 -220.91964) (xy 350.46376 -220.961527) (xy 350.487266 -221.007659) (xy 350.503265 -221.056899)
			(xy 350.511364 -221.108037) (xy 350.511872 -221.133924) (xy 350.792796 -221.133924) (xy 350.793304 -221.10859)
			(xy 350.801053 -221.058519) (xy 350.816372 -221.010223) (xy 350.8389 -220.96484) (xy 350.868106 -220.923438)
			(xy 350.903304 -220.886992) (xy 350.943663 -220.856361) (xy 350.988234 -220.832266) (xy 351.035967 -220.815274)
			(xy 351.060766 -220.810074) (xy 351.083626 -220.805756) (xy 351.288604 -220.450664) (xy 351.28073 -220.42882)
			(xy 351.272096 -220.402408) (xy 351.262768 -220.347635) (xy 351.262188 -220.319854) (xy 351.262696 -220.293947)
			(xy 351.270802 -220.24277) (xy 351.286814 -220.193491) (xy 351.310337 -220.147324) (xy 351.340793 -220.105405)
			(xy 351.377431 -220.068767) (xy 351.41935 -220.038311) (xy 351.465517 -220.014788) (xy 351.514796 -219.998776)
			(xy 351.565973 -219.99067) (xy 351.617787 -219.99067) (xy 351.668964 -219.998776) (xy 351.718243 -220.014788)
			(xy 351.76441 -220.038311) (xy 351.806329 -220.068767) (xy 351.842967 -220.105405) (xy 351.873423 -220.147324)
			(xy 351.896946 -220.193491) (xy 351.912958 -220.24277) (xy 351.921064 -220.293947) (xy 351.921572 -220.319854)
			(xy 353.141788 -220.319854) (xy 353.142296 -220.293947) (xy 353.150402 -220.24277) (xy 353.166414 -220.193491)
			(xy 353.189937 -220.147324) (xy 353.220393 -220.105405) (xy 353.257031 -220.068767) (xy 353.29895 -220.038311)
			(xy 353.345117 -220.014788) (xy 353.394396 -219.998776) (xy 353.445573 -219.99067) (xy 353.497387 -219.99067)
			(xy 353.548564 -219.998776) (xy 353.597843 -220.014788) (xy 353.64401 -220.038311) (xy 353.685929 -220.068767)
			(xy 353.722567 -220.105405) (xy 353.753023 -220.147324) (xy 353.776546 -220.193491) (xy 353.792558 -220.24277)
			(xy 353.800664 -220.293947) (xy 353.801172 -220.319854) (xy 355.021388 -220.319854) (xy 355.021896 -220.293947)
			(xy 355.030002 -220.24277) (xy 355.046014 -220.193491) (xy 355.069537 -220.147324) (xy 355.099993 -220.105405)
			(xy 355.136631 -220.068767) (xy 355.17855 -220.038311) (xy 355.224717 -220.014788) (xy 355.273996 -219.998776)
			(xy 355.325173 -219.99067) (xy 355.376987 -219.99067) (xy 355.428164 -219.998776) (xy 355.477443 -220.014788)
			(xy 355.52361 -220.038311) (xy 355.565529 -220.068767) (xy 355.602167 -220.105405) (xy 355.632623 -220.147324)
			(xy 355.656146 -220.193491) (xy 355.672158 -220.24277) (xy 355.680264 -220.293947) (xy 355.680772 -220.319854)
			(xy 356.900988 -220.319854) (xy 356.901496 -220.293947) (xy 356.909602 -220.24277) (xy 356.925614 -220.193491)
			(xy 356.949137 -220.147324) (xy 356.979593 -220.105405) (xy 357.016231 -220.068767) (xy 357.05815 -220.038311)
			(xy 357.104317 -220.014788) (xy 357.153596 -219.998776) (xy 357.204773 -219.99067) (xy 357.256587 -219.99067)
			(xy 357.307764 -219.998776) (xy 357.357043 -220.014788) (xy 357.40321 -220.038311) (xy 357.445129 -220.068767)
			(xy 357.481767 -220.105405) (xy 357.512223 -220.147324) (xy 357.535746 -220.193491) (xy 357.551758 -220.24277)
			(xy 357.559864 -220.293947) (xy 357.560372 -220.319854) (xy 358.780588 -220.319854) (xy 358.781096 -220.293947)
			(xy 358.789202 -220.24277) (xy 358.805214 -220.193491) (xy 358.828737 -220.147324) (xy 358.859193 -220.105405)
			(xy 358.895831 -220.068767) (xy 358.93775 -220.038311) (xy 358.983917 -220.014788) (xy 359.033196 -219.998776)
			(xy 359.084373 -219.99067) (xy 359.136187 -219.99067) (xy 359.187364 -219.998776) (xy 359.236643 -220.014788)
			(xy 359.28281 -220.038311) (xy 359.324729 -220.068767) (xy 359.361367 -220.105405) (xy 359.391823 -220.147324)
			(xy 359.415346 -220.193491) (xy 359.431358 -220.24277) (xy 359.439464 -220.293947) (xy 359.439972 -220.319854)
			(xy 360.660188 -220.319854) (xy 360.660696 -220.293947) (xy 360.668802 -220.24277) (xy 360.684814 -220.193491)
			(xy 360.708337 -220.147324) (xy 360.738793 -220.105405) (xy 360.775431 -220.068767) (xy 360.81735 -220.038311)
			(xy 360.863517 -220.014788) (xy 360.912796 -219.998776) (xy 360.963973 -219.99067) (xy 361.015787 -219.99067)
			(xy 361.066964 -219.998776) (xy 361.116243 -220.014788) (xy 361.16241 -220.038311) (xy 361.204329 -220.068767)
			(xy 361.240967 -220.105405) (xy 361.271423 -220.147324) (xy 361.294946 -220.193491) (xy 361.310958 -220.24277)
			(xy 361.319064 -220.293947) (xy 361.319572 -220.319854) (xy 362.539788 -220.319854) (xy 362.540296 -220.293947)
			(xy 362.548402 -220.24277) (xy 362.564414 -220.193491) (xy 362.587937 -220.147324) (xy 362.618393 -220.105405)
			(xy 362.655031 -220.068767) (xy 362.69695 -220.038311) (xy 362.743117 -220.014788) (xy 362.792396 -219.998776)
			(xy 362.843573 -219.99067) (xy 362.895387 -219.99067) (xy 362.946564 -219.998776) (xy 362.995843 -220.014788)
			(xy 363.04201 -220.038311) (xy 363.083929 -220.068767) (xy 363.120567 -220.105405) (xy 363.151023 -220.147324)
			(xy 363.174546 -220.193491) (xy 363.190558 -220.24277) (xy 363.198664 -220.293947) (xy 363.199172 -220.319854)
			(xy 364.419388 -220.319854) (xy 364.419896 -220.293947) (xy 364.428002 -220.24277) (xy 364.444014 -220.193491)
			(xy 364.467537 -220.147324) (xy 364.497993 -220.105405) (xy 364.534631 -220.068767) (xy 364.57655 -220.038311)
			(xy 364.622717 -220.014788) (xy 364.671996 -219.998776) (xy 364.723173 -219.99067) (xy 364.774987 -219.99067)
			(xy 364.826164 -219.998776) (xy 364.875443 -220.014788) (xy 364.92161 -220.038311) (xy 364.963529 -220.068767)
			(xy 365.000167 -220.105405) (xy 365.030623 -220.147324) (xy 365.054146 -220.193491) (xy 365.070158 -220.24277)
			(xy 365.078264 -220.293947) (xy 365.078772 -220.319854) (xy 366.298988 -220.319854) (xy 366.299496 -220.293947)
			(xy 366.307602 -220.24277) (xy 366.323614 -220.193491) (xy 366.347137 -220.147324) (xy 366.377593 -220.105405)
			(xy 366.414231 -220.068767) (xy 366.45615 -220.038311) (xy 366.502317 -220.014788) (xy 366.551596 -219.998776)
			(xy 366.602773 -219.99067) (xy 366.654587 -219.99067) (xy 366.705764 -219.998776) (xy 366.755043 -220.014788)
			(xy 366.80121 -220.038311) (xy 366.843129 -220.068767) (xy 366.879767 -220.105405) (xy 366.910223 -220.147324)
			(xy 366.933746 -220.193491) (xy 366.949758 -220.24277) (xy 366.957864 -220.293947) (xy 366.958372 -220.319854)
			(xy 368.178588 -220.319854) (xy 368.179096 -220.293947) (xy 368.187202 -220.24277) (xy 368.203214 -220.193491)
			(xy 368.226737 -220.147324) (xy 368.257193 -220.105405) (xy 368.293831 -220.068767) (xy 368.33575 -220.038311)
			(xy 368.381917 -220.014788) (xy 368.431196 -219.998776) (xy 368.482373 -219.99067) (xy 368.534187 -219.99067)
			(xy 368.585364 -219.998776) (xy 368.634643 -220.014788) (xy 368.68081 -220.038311) (xy 368.722729 -220.068767)
			(xy 368.759367 -220.105405) (xy 368.789823 -220.147324) (xy 368.813346 -220.193491) (xy 368.829358 -220.24277)
			(xy 368.837464 -220.293947) (xy 368.837972 -220.319854) (xy 370.058188 -220.319854) (xy 370.058696 -220.293947)
			(xy 370.066802 -220.24277) (xy 370.082814 -220.193491) (xy 370.106337 -220.147324) (xy 370.136793 -220.105405)
			(xy 370.173431 -220.068767) (xy 370.21535 -220.038311) (xy 370.261517 -220.014788) (xy 370.310796 -219.998776)
			(xy 370.361973 -219.99067) (xy 370.413787 -219.99067) (xy 370.464964 -219.998776) (xy 370.514243 -220.014788)
			(xy 370.56041 -220.038311) (xy 370.602329 -220.068767) (xy 370.638967 -220.105405) (xy 370.669423 -220.147324)
			(xy 370.692946 -220.193491) (xy 370.708958 -220.24277) (xy 370.717064 -220.293947) (xy 370.717572 -220.319854)
			(xy 371.937788 -220.319854) (xy 371.938296 -220.293947) (xy 371.946402 -220.24277) (xy 371.962414 -220.193491)
			(xy 371.985937 -220.147324) (xy 372.016393 -220.105405) (xy 372.053031 -220.068767) (xy 372.09495 -220.038311)
			(xy 372.141117 -220.014788) (xy 372.190396 -219.998776) (xy 372.241573 -219.99067) (xy 372.293387 -219.99067)
			(xy 372.344564 -219.998776) (xy 372.393843 -220.014788) (xy 372.44001 -220.038311) (xy 372.481929 -220.068767)
			(xy 372.518567 -220.105405) (xy 372.549023 -220.147324) (xy 372.572546 -220.193491) (xy 372.588558 -220.24277)
			(xy 372.596664 -220.293947) (xy 372.597172 -220.319854) (xy 373.817388 -220.319854) (xy 373.817896 -220.293947)
			(xy 373.826002 -220.24277) (xy 373.842014 -220.193491) (xy 373.865537 -220.147324) (xy 373.895993 -220.105405)
			(xy 373.932631 -220.068767) (xy 373.97455 -220.038311) (xy 374.020717 -220.014788) (xy 374.069996 -219.998776)
			(xy 374.121173 -219.99067) (xy 374.172987 -219.99067) (xy 374.224164 -219.998776) (xy 374.273443 -220.014788)
			(xy 374.31961 -220.038311) (xy 374.361529 -220.068767) (xy 374.398167 -220.105405) (xy 374.428623 -220.147324)
			(xy 374.452146 -220.193491) (xy 374.468158 -220.24277) (xy 374.476264 -220.293947) (xy 374.476772 -220.319854)
			(xy 375.696988 -220.319854) (xy 375.697496 -220.293947) (xy 375.705602 -220.24277) (xy 375.721614 -220.193491)
			(xy 375.745137 -220.147324) (xy 375.775593 -220.105405) (xy 375.812231 -220.068767) (xy 375.85415 -220.038311)
			(xy 375.900317 -220.014788) (xy 375.949596 -219.998776) (xy 376.000773 -219.99067) (xy 376.052587 -219.99067)
			(xy 376.103764 -219.998776) (xy 376.153043 -220.014788) (xy 376.19921 -220.038311) (xy 376.241129 -220.068767)
			(xy 376.277767 -220.105405) (xy 376.308223 -220.147324) (xy 376.331746 -220.193491) (xy 376.347758 -220.24277)
			(xy 376.355864 -220.293947) (xy 376.356372 -220.319854) (xy 377.576588 -220.319854) (xy 377.577096 -220.293947)
			(xy 377.585202 -220.24277) (xy 377.601214 -220.193491) (xy 377.624737 -220.147324) (xy 377.655193 -220.105405)
			(xy 377.691831 -220.068767) (xy 377.73375 -220.038311) (xy 377.779917 -220.014788) (xy 377.829196 -219.998776)
			(xy 377.880373 -219.99067) (xy 377.932187 -219.99067) (xy 377.983364 -219.998776) (xy 378.032643 -220.014788)
			(xy 378.07881 -220.038311) (xy 378.120729 -220.068767) (xy 378.157367 -220.105405) (xy 378.187823 -220.147324)
			(xy 378.211346 -220.193491) (xy 378.227358 -220.24277) (xy 378.235464 -220.293947) (xy 378.235972 -220.319854)
			(xy 379.456188 -220.319854) (xy 379.456696 -220.293947) (xy 379.464802 -220.24277) (xy 379.480814 -220.193491)
			(xy 379.504337 -220.147324) (xy 379.534793 -220.105405) (xy 379.571431 -220.068767) (xy 379.61335 -220.038311)
			(xy 379.659517 -220.014788) (xy 379.708796 -219.998776) (xy 379.759973 -219.99067) (xy 379.811787 -219.99067)
			(xy 379.862964 -219.998776) (xy 379.912243 -220.014788) (xy 379.95841 -220.038311) (xy 380.000329 -220.068767)
			(xy 380.036967 -220.105405) (xy 380.067423 -220.147324) (xy 380.090946 -220.193491) (xy 380.106958 -220.24277)
			(xy 380.115064 -220.293947) (xy 380.115572 -220.319854) (xy 381.336296 -220.319854) (xy 381.336804 -220.293967)
			(xy 381.344903 -220.242829) (xy 381.360902 -220.193589) (xy 381.384408 -220.147457) (xy 381.41484 -220.10557)
			(xy 381.45145 -220.06896) (xy 381.493337 -220.038528) (xy 381.539469 -220.015022) (xy 381.588709 -219.999023)
			(xy 381.639847 -219.990924) (xy 381.691621 -219.990924) (xy 381.742759 -219.999023) (xy 381.791999 -220.015022)
			(xy 381.838131 -220.038528) (xy 381.880018 -220.06896) (xy 381.916628 -220.10557) (xy 381.94706 -220.147457)
			(xy 381.970566 -220.193589) (xy 381.986565 -220.242829) (xy 381.994664 -220.293967) (xy 381.995172 -220.319854)
			(xy 381.994628 -220.347561) (xy 381.985442 -220.402208) (xy 381.976884 -220.428566) (xy 381.969264 -220.450664)
			(xy 382.174242 -220.805756) (xy 382.197102 -220.810074) (xy 382.221908 -220.815252) (xy 382.269647 -220.832242)
			(xy 382.314225 -220.856337) (xy 382.354591 -220.886969) (xy 382.389795 -220.923417) (xy 382.419006 -220.964822)
			(xy 382.441538 -221.01021) (xy 382.45686 -221.058511) (xy 382.46461 -221.108588) (xy 382.465072 -221.133924)
			(xy 382.464564 -221.159811) (xy 382.456465 -221.210949) (xy 382.440466 -221.260189) (xy 382.41696 -221.306321)
			(xy 382.386528 -221.348208) (xy 382.349918 -221.384818) (xy 382.308031 -221.41525) (xy 382.261899 -221.438756)
			(xy 382.212659 -221.454755) (xy 382.161521 -221.462854) (xy 382.109747 -221.462854) (xy 382.058609 -221.454755)
			(xy 382.009369 -221.438756) (xy 381.963237 -221.41525) (xy 381.92135 -221.384818) (xy 381.88474 -221.348208)
			(xy 381.854308 -221.306321) (xy 381.830802 -221.260189) (xy 381.814803 -221.210949) (xy 381.806704 -221.159811)
			(xy 381.806196 -221.133924) (xy 381.806732 -221.106216) (xy 381.815923 -221.051569) (xy 381.824484 -221.025212)
			(xy 381.832358 -221.003114) (xy 381.62738 -220.648022) (xy 381.60452 -220.643704) (xy 381.579694 -220.638559)
			(xy 381.531915 -220.6216) (xy 381.487296 -220.597525) (xy 381.446891 -220.566902) (xy 381.41165 -220.530452)
			(xy 381.382408 -220.489036) (xy 381.359851 -220.44363) (xy 381.344514 -220.395306) (xy 381.336758 -220.345204)
			(xy 381.336296 -220.319854) (xy 380.115572 -220.319854) (xy 380.114963 -220.347508) (xy 380.105639 -220.402026)
			(xy 380.09703 -220.428312) (xy 380.08941 -220.45041) (xy 380.294642 -220.805756) (xy 380.317502 -220.810074)
			(xy 380.342308 -220.815252) (xy 380.390047 -220.832242) (xy 380.434625 -220.856337) (xy 380.474991 -220.886969)
			(xy 380.510195 -220.923417) (xy 380.539406 -220.964822) (xy 380.561938 -221.01021) (xy 380.57726 -221.058511)
			(xy 380.58501 -221.108588) (xy 380.585472 -221.133924) (xy 380.584964 -221.159811) (xy 380.576865 -221.210949)
			(xy 380.560866 -221.260189) (xy 380.53736 -221.306321) (xy 380.506928 -221.348208) (xy 380.470318 -221.384818)
			(xy 380.428431 -221.41525) (xy 380.382299 -221.438756) (xy 380.333059 -221.454755) (xy 380.281921 -221.462854)
			(xy 380.230147 -221.462854) (xy 380.179009 -221.454755) (xy 380.129769 -221.438756) (xy 380.083637 -221.41525)
			(xy 380.04175 -221.384818) (xy 380.00514 -221.348208) (xy 379.974708 -221.306321) (xy 379.951202 -221.260189)
			(xy 379.935203 -221.210949) (xy 379.927104 -221.159811) (xy 379.926596 -221.133924) (xy 379.927132 -221.106216)
			(xy 379.936323 -221.051569) (xy 379.944884 -221.025212) (xy 379.952758 -221.003114) (xy 379.74778 -220.648022)
			(xy 379.72492 -220.643704) (xy 379.700079 -220.638521) (xy 379.652232 -220.621628) (xy 379.60754 -220.5976)
			(xy 379.567059 -220.567005) (xy 379.531748 -220.530566) (xy 379.502439 -220.489145) (xy 379.479827 -220.44372)
			(xy 379.464446 -220.395365) (xy 379.456659 -220.345225) (xy 379.456188 -220.319854) (xy 378.235972 -220.319854)
			(xy 378.235363 -220.347508) (xy 378.226039 -220.402026) (xy 378.21743 -220.428312) (xy 378.20981 -220.45041)
			(xy 378.415042 -220.805756) (xy 378.437902 -220.810074) (xy 378.462708 -220.815252) (xy 378.510447 -220.832242)
			(xy 378.555025 -220.856337) (xy 378.595391 -220.886969) (xy 378.630595 -220.923417) (xy 378.659806 -220.964822)
			(xy 378.682338 -221.01021) (xy 378.69766 -221.058511) (xy 378.70541 -221.108588) (xy 378.705872 -221.133924)
			(xy 378.705364 -221.159811) (xy 378.697265 -221.210949) (xy 378.681266 -221.260189) (xy 378.65776 -221.306321)
			(xy 378.627328 -221.348208) (xy 378.590718 -221.384818) (xy 378.548831 -221.41525) (xy 378.502699 -221.438756)
			(xy 378.453459 -221.454755) (xy 378.402321 -221.462854) (xy 378.350547 -221.462854) (xy 378.299409 -221.454755)
			(xy 378.250169 -221.438756) (xy 378.204037 -221.41525) (xy 378.16215 -221.384818) (xy 378.12554 -221.348208)
			(xy 378.095108 -221.306321) (xy 378.071602 -221.260189) (xy 378.055603 -221.210949) (xy 378.047504 -221.159811)
			(xy 378.046996 -221.133924) (xy 378.047532 -221.106216) (xy 378.056723 -221.051569) (xy 378.065284 -221.025212)
			(xy 378.073158 -221.003114) (xy 377.86818 -220.648022) (xy 377.84532 -220.643704) (xy 377.820479 -220.638521)
			(xy 377.772632 -220.621628) (xy 377.72794 -220.5976) (xy 377.687459 -220.567005) (xy 377.652148 -220.530566)
			(xy 377.622839 -220.489145) (xy 377.600227 -220.44372) (xy 377.584846 -220.395365) (xy 377.577059 -220.345225)
			(xy 377.576588 -220.319854) (xy 376.356372 -220.319854) (xy 376.355763 -220.347508) (xy 376.346439 -220.402026)
			(xy 376.33783 -220.428312) (xy 376.33021 -220.45041) (xy 376.535442 -220.805756) (xy 376.558302 -220.810074)
			(xy 376.583108 -220.815252) (xy 376.630847 -220.832242) (xy 376.675425 -220.856337) (xy 376.715791 -220.886969)
			(xy 376.750995 -220.923417) (xy 376.780206 -220.964822) (xy 376.802738 -221.01021) (xy 376.81806 -221.058511)
			(xy 376.82581 -221.108588) (xy 376.826272 -221.133924) (xy 376.825764 -221.159811) (xy 376.817665 -221.210949)
			(xy 376.801666 -221.260189) (xy 376.77816 -221.306321) (xy 376.747728 -221.348208) (xy 376.711118 -221.384818)
			(xy 376.669231 -221.41525) (xy 376.623099 -221.438756) (xy 376.573859 -221.454755) (xy 376.522721 -221.462854)
			(xy 376.470947 -221.462854) (xy 376.419809 -221.454755) (xy 376.370569 -221.438756) (xy 376.324437 -221.41525)
			(xy 376.28255 -221.384818) (xy 376.24594 -221.348208) (xy 376.215508 -221.306321) (xy 376.192002 -221.260189)
			(xy 376.176003 -221.210949) (xy 376.167904 -221.159811) (xy 376.167396 -221.133924) (xy 376.167932 -221.106216)
			(xy 376.177123 -221.051569) (xy 376.185684 -221.025212) (xy 376.193558 -221.003114) (xy 375.98858 -220.648022)
			(xy 375.96572 -220.643704) (xy 375.940879 -220.638521) (xy 375.893032 -220.621628) (xy 375.84834 -220.5976)
			(xy 375.807859 -220.567005) (xy 375.772548 -220.530566) (xy 375.743239 -220.489145) (xy 375.720627 -220.44372)
			(xy 375.705246 -220.395365) (xy 375.697459 -220.345225) (xy 375.696988 -220.319854) (xy 374.476772 -220.319854)
			(xy 374.476163 -220.347508) (xy 374.466839 -220.402026) (xy 374.45823 -220.428312) (xy 374.45061 -220.45041)
			(xy 374.655842 -220.805756) (xy 374.678702 -220.810074) (xy 374.703508 -220.815252) (xy 374.751247 -220.832242)
			(xy 374.795825 -220.856337) (xy 374.836191 -220.886969) (xy 374.871395 -220.923417) (xy 374.900606 -220.964822)
			(xy 374.923138 -221.01021) (xy 374.93846 -221.058511) (xy 374.94621 -221.108588) (xy 374.946672 -221.133924)
			(xy 374.946164 -221.159811) (xy 374.938065 -221.210949) (xy 374.922066 -221.260189) (xy 374.89856 -221.306321)
			(xy 374.868128 -221.348208) (xy 374.831518 -221.384818) (xy 374.789631 -221.41525) (xy 374.743499 -221.438756)
			(xy 374.694259 -221.454755) (xy 374.643121 -221.462854) (xy 374.591347 -221.462854) (xy 374.540209 -221.454755)
			(xy 374.490969 -221.438756) (xy 374.444837 -221.41525) (xy 374.40295 -221.384818) (xy 374.36634 -221.348208)
			(xy 374.335908 -221.306321) (xy 374.312402 -221.260189) (xy 374.296403 -221.210949) (xy 374.288304 -221.159811)
			(xy 374.287796 -221.133924) (xy 374.288332 -221.106216) (xy 374.297523 -221.051569) (xy 374.306084 -221.025212)
			(xy 374.313958 -221.003114) (xy 374.10898 -220.648022) (xy 374.08612 -220.643704) (xy 374.061279 -220.638521)
			(xy 374.013432 -220.621628) (xy 373.96874 -220.5976) (xy 373.928259 -220.567005) (xy 373.892948 -220.530566)
			(xy 373.863639 -220.489145) (xy 373.841027 -220.44372) (xy 373.825646 -220.395365) (xy 373.817859 -220.345225)
			(xy 373.817388 -220.319854) (xy 372.597172 -220.319854) (xy 372.596563 -220.347508) (xy 372.587239 -220.402026)
			(xy 372.57863 -220.428312) (xy 372.57101 -220.45041) (xy 372.776242 -220.805756) (xy 372.799102 -220.810074)
			(xy 372.823908 -220.815252) (xy 372.871647 -220.832242) (xy 372.916225 -220.856337) (xy 372.956591 -220.886969)
			(xy 372.991795 -220.923417) (xy 373.021006 -220.964822) (xy 373.043538 -221.01021) (xy 373.05886 -221.058511)
			(xy 373.06661 -221.108588) (xy 373.067072 -221.133924) (xy 373.066564 -221.159811) (xy 373.058465 -221.210949)
			(xy 373.042466 -221.260189) (xy 373.01896 -221.306321) (xy 372.988528 -221.348208) (xy 372.951918 -221.384818)
			(xy 372.910031 -221.41525) (xy 372.863899 -221.438756) (xy 372.814659 -221.454755) (xy 372.763521 -221.462854)
			(xy 372.711747 -221.462854) (xy 372.660609 -221.454755) (xy 372.611369 -221.438756) (xy 372.565237 -221.41525)
			(xy 372.52335 -221.384818) (xy 372.48674 -221.348208) (xy 372.456308 -221.306321) (xy 372.432802 -221.260189)
			(xy 372.416803 -221.210949) (xy 372.408704 -221.159811) (xy 372.408196 -221.133924) (xy 372.408732 -221.106216)
			(xy 372.417923 -221.051569) (xy 372.426484 -221.025212) (xy 372.434358 -221.003114) (xy 372.22938 -220.648022)
			(xy 372.20652 -220.643704) (xy 372.181679 -220.638521) (xy 372.133832 -220.621628) (xy 372.08914 -220.5976)
			(xy 372.048659 -220.567005) (xy 372.013348 -220.530566) (xy 371.984039 -220.489145) (xy 371.961427 -220.44372)
			(xy 371.946046 -220.395365) (xy 371.938259 -220.345225) (xy 371.937788 -220.319854) (xy 370.717572 -220.319854)
			(xy 370.716963 -220.347508) (xy 370.707639 -220.402026) (xy 370.69903 -220.428312) (xy 370.69141 -220.45041)
			(xy 370.896642 -220.805756) (xy 370.919502 -220.810074) (xy 370.944308 -220.815252) (xy 370.992047 -220.832242)
			(xy 371.036625 -220.856337) (xy 371.076991 -220.886969) (xy 371.112195 -220.923417) (xy 371.141406 -220.964822)
			(xy 371.163938 -221.01021) (xy 371.17926 -221.058511) (xy 371.18701 -221.108588) (xy 371.187472 -221.133924)
			(xy 371.186964 -221.159811) (xy 371.178865 -221.210949) (xy 371.162866 -221.260189) (xy 371.13936 -221.306321)
			(xy 371.108928 -221.348208) (xy 371.072318 -221.384818) (xy 371.030431 -221.41525) (xy 370.984299 -221.438756)
			(xy 370.935059 -221.454755) (xy 370.883921 -221.462854) (xy 370.832147 -221.462854) (xy 370.781009 -221.454755)
			(xy 370.731769 -221.438756) (xy 370.685637 -221.41525) (xy 370.64375 -221.384818) (xy 370.60714 -221.348208)
			(xy 370.576708 -221.306321) (xy 370.553202 -221.260189) (xy 370.537203 -221.210949) (xy 370.529104 -221.159811)
			(xy 370.528596 -221.133924) (xy 370.529132 -221.106216) (xy 370.538323 -221.051569) (xy 370.546884 -221.025212)
			(xy 370.554758 -221.003114) (xy 370.34978 -220.648022) (xy 370.32692 -220.643704) (xy 370.302079 -220.638521)
			(xy 370.254232 -220.621628) (xy 370.20954 -220.5976) (xy 370.169059 -220.567005) (xy 370.133748 -220.530566)
			(xy 370.104439 -220.489145) (xy 370.081827 -220.44372) (xy 370.066446 -220.395365) (xy 370.058659 -220.345225)
			(xy 370.058188 -220.319854) (xy 368.837972 -220.319854) (xy 368.837363 -220.347508) (xy 368.828039 -220.402026)
			(xy 368.81943 -220.428312) (xy 368.81181 -220.45041) (xy 369.017042 -220.805756) (xy 369.039902 -220.810074)
			(xy 369.064708 -220.815252) (xy 369.112447 -220.832242) (xy 369.157025 -220.856337) (xy 369.197391 -220.886969)
			(xy 369.232595 -220.923417) (xy 369.261806 -220.964822) (xy 369.284338 -221.01021) (xy 369.29966 -221.058511)
			(xy 369.30741 -221.108588) (xy 369.307872 -221.133924) (xy 369.307364 -221.159811) (xy 369.299265 -221.210949)
			(xy 369.283266 -221.260189) (xy 369.25976 -221.306321) (xy 369.229328 -221.348208) (xy 369.192718 -221.384818)
			(xy 369.150831 -221.41525) (xy 369.104699 -221.438756) (xy 369.055459 -221.454755) (xy 369.004321 -221.462854)
			(xy 368.952547 -221.462854) (xy 368.901409 -221.454755) (xy 368.852169 -221.438756) (xy 368.806037 -221.41525)
			(xy 368.76415 -221.384818) (xy 368.72754 -221.348208) (xy 368.697108 -221.306321) (xy 368.673602 -221.260189)
			(xy 368.657603 -221.210949) (xy 368.649504 -221.159811) (xy 368.648996 -221.133924) (xy 368.649532 -221.106216)
			(xy 368.658723 -221.051569) (xy 368.667284 -221.025212) (xy 368.675158 -221.003114) (xy 368.47018 -220.648022)
			(xy 368.44732 -220.643704) (xy 368.422479 -220.638521) (xy 368.374632 -220.621628) (xy 368.32994 -220.5976)
			(xy 368.289459 -220.567005) (xy 368.254148 -220.530566) (xy 368.224839 -220.489145) (xy 368.202227 -220.44372)
			(xy 368.186846 -220.395365) (xy 368.179059 -220.345225) (xy 368.178588 -220.319854) (xy 366.958372 -220.319854)
			(xy 366.957763 -220.347508) (xy 366.948439 -220.402026) (xy 366.93983 -220.428312) (xy 366.93221 -220.45041)
			(xy 367.137442 -220.805756) (xy 367.160302 -220.810074) (xy 367.185108 -220.815252) (xy 367.232847 -220.832242)
			(xy 367.277425 -220.856337) (xy 367.317791 -220.886969) (xy 367.352995 -220.923417) (xy 367.382206 -220.964822)
			(xy 367.404738 -221.01021) (xy 367.42006 -221.058511) (xy 367.42781 -221.108588) (xy 367.428272 -221.133924)
			(xy 367.427764 -221.159811) (xy 367.419665 -221.210949) (xy 367.403666 -221.260189) (xy 367.38016 -221.306321)
			(xy 367.349728 -221.348208) (xy 367.313118 -221.384818) (xy 367.271231 -221.41525) (xy 367.225099 -221.438756)
			(xy 367.175859 -221.454755) (xy 367.124721 -221.462854) (xy 367.072947 -221.462854) (xy 367.021809 -221.454755)
			(xy 366.972569 -221.438756) (xy 366.926437 -221.41525) (xy 366.88455 -221.384818) (xy 366.84794 -221.348208)
			(xy 366.817508 -221.306321) (xy 366.794002 -221.260189) (xy 366.778003 -221.210949) (xy 366.769904 -221.159811)
			(xy 366.769396 -221.133924) (xy 366.769932 -221.106216) (xy 366.779123 -221.051569) (xy 366.787684 -221.025212)
			(xy 366.795558 -221.003114) (xy 366.59058 -220.648022) (xy 366.56772 -220.643704) (xy 366.542879 -220.638521)
			(xy 366.495032 -220.621628) (xy 366.45034 -220.5976) (xy 366.409859 -220.567005) (xy 366.374548 -220.530566)
			(xy 366.345239 -220.489145) (xy 366.322627 -220.44372) (xy 366.307246 -220.395365) (xy 366.299459 -220.345225)
			(xy 366.298988 -220.319854) (xy 365.078772 -220.319854) (xy 365.078163 -220.347508) (xy 365.068839 -220.402026)
			(xy 365.06023 -220.428312) (xy 365.05261 -220.45041) (xy 365.257842 -220.805756) (xy 365.280702 -220.810074)
			(xy 365.305508 -220.815252) (xy 365.353247 -220.832242) (xy 365.397825 -220.856337) (xy 365.438191 -220.886969)
			(xy 365.473395 -220.923417) (xy 365.502606 -220.964822) (xy 365.525138 -221.01021) (xy 365.54046 -221.058511)
			(xy 365.54821 -221.108588) (xy 365.548672 -221.133924) (xy 365.548164 -221.159811) (xy 365.540065 -221.210949)
			(xy 365.524066 -221.260189) (xy 365.50056 -221.306321) (xy 365.470128 -221.348208) (xy 365.433518 -221.384818)
			(xy 365.391631 -221.41525) (xy 365.345499 -221.438756) (xy 365.296259 -221.454755) (xy 365.245121 -221.462854)
			(xy 365.193347 -221.462854) (xy 365.142209 -221.454755) (xy 365.092969 -221.438756) (xy 365.046837 -221.41525)
			(xy 365.00495 -221.384818) (xy 364.96834 -221.348208) (xy 364.937908 -221.306321) (xy 364.914402 -221.260189)
			(xy 364.898403 -221.210949) (xy 364.890304 -221.159811) (xy 364.889796 -221.133924) (xy 364.890332 -221.106216)
			(xy 364.899523 -221.051569) (xy 364.908084 -221.025212) (xy 364.915958 -221.003114) (xy 364.71098 -220.648022)
			(xy 364.68812 -220.643704) (xy 364.663279 -220.638521) (xy 364.615432 -220.621628) (xy 364.57074 -220.5976)
			(xy 364.530259 -220.567005) (xy 364.494948 -220.530566) (xy 364.465639 -220.489145) (xy 364.443027 -220.44372)
			(xy 364.427646 -220.395365) (xy 364.419859 -220.345225) (xy 364.419388 -220.319854) (xy 363.199172 -220.319854)
			(xy 363.198563 -220.347508) (xy 363.189239 -220.402026) (xy 363.18063 -220.428312) (xy 363.17301 -220.45041)
			(xy 363.378242 -220.805756) (xy 363.401102 -220.810074) (xy 363.425908 -220.815252) (xy 363.473647 -220.832242)
			(xy 363.518225 -220.856337) (xy 363.558591 -220.886969) (xy 363.593795 -220.923417) (xy 363.623006 -220.964822)
			(xy 363.645538 -221.01021) (xy 363.66086 -221.058511) (xy 363.66861 -221.108588) (xy 363.669072 -221.133924)
			(xy 363.668564 -221.159811) (xy 363.660465 -221.210949) (xy 363.644466 -221.260189) (xy 363.62096 -221.306321)
			(xy 363.590528 -221.348208) (xy 363.553918 -221.384818) (xy 363.512031 -221.41525) (xy 363.465899 -221.438756)
			(xy 363.416659 -221.454755) (xy 363.365521 -221.462854) (xy 363.313747 -221.462854) (xy 363.262609 -221.454755)
			(xy 363.213369 -221.438756) (xy 363.167237 -221.41525) (xy 363.12535 -221.384818) (xy 363.08874 -221.348208)
			(xy 363.058308 -221.306321) (xy 363.034802 -221.260189) (xy 363.018803 -221.210949) (xy 363.010704 -221.159811)
			(xy 363.010196 -221.133924) (xy 363.010732 -221.106216) (xy 363.019923 -221.051569) (xy 363.028484 -221.025212)
			(xy 363.036358 -221.003114) (xy 362.83138 -220.648022) (xy 362.80852 -220.643704) (xy 362.783679 -220.638521)
			(xy 362.735832 -220.621628) (xy 362.69114 -220.5976) (xy 362.650659 -220.567005) (xy 362.615348 -220.530566)
			(xy 362.586039 -220.489145) (xy 362.563427 -220.44372) (xy 362.548046 -220.395365) (xy 362.540259 -220.345225)
			(xy 362.539788 -220.319854) (xy 361.319572 -220.319854) (xy 361.318963 -220.347508) (xy 361.309639 -220.402026)
			(xy 361.30103 -220.428312) (xy 361.29341 -220.45041) (xy 361.498642 -220.805756) (xy 361.521502 -220.810074)
			(xy 361.546308 -220.815252) (xy 361.594047 -220.832242) (xy 361.638625 -220.856337) (xy 361.678991 -220.886969)
			(xy 361.714195 -220.923417) (xy 361.743406 -220.964822) (xy 361.765938 -221.01021) (xy 361.78126 -221.058511)
			(xy 361.78901 -221.108588) (xy 361.789472 -221.133924) (xy 361.788964 -221.159811) (xy 361.780865 -221.210949)
			(xy 361.764866 -221.260189) (xy 361.74136 -221.306321) (xy 361.710928 -221.348208) (xy 361.674318 -221.384818)
			(xy 361.632431 -221.41525) (xy 361.586299 -221.438756) (xy 361.537059 -221.454755) (xy 361.485921 -221.462854)
			(xy 361.434147 -221.462854) (xy 361.383009 -221.454755) (xy 361.333769 -221.438756) (xy 361.287637 -221.41525)
			(xy 361.24575 -221.384818) (xy 361.20914 -221.348208) (xy 361.178708 -221.306321) (xy 361.155202 -221.260189)
			(xy 361.139203 -221.210949) (xy 361.131104 -221.159811) (xy 361.130596 -221.133924) (xy 361.131132 -221.106216)
			(xy 361.140323 -221.051569) (xy 361.148884 -221.025212) (xy 361.156758 -221.003114) (xy 360.95178 -220.648022)
			(xy 360.92892 -220.643704) (xy 360.904079 -220.638521) (xy 360.856232 -220.621628) (xy 360.81154 -220.5976)
			(xy 360.771059 -220.567005) (xy 360.735748 -220.530566) (xy 360.706439 -220.489145) (xy 360.683827 -220.44372)
			(xy 360.668446 -220.395365) (xy 360.660659 -220.345225) (xy 360.660188 -220.319854) (xy 359.439972 -220.319854)
			(xy 359.439363 -220.347508) (xy 359.430039 -220.402026) (xy 359.42143 -220.428312) (xy 359.41381 -220.45041)
			(xy 359.619042 -220.805756) (xy 359.641902 -220.810074) (xy 359.666708 -220.815252) (xy 359.714447 -220.832242)
			(xy 359.759025 -220.856337) (xy 359.799391 -220.886969) (xy 359.834595 -220.923417) (xy 359.863806 -220.964822)
			(xy 359.886338 -221.01021) (xy 359.90166 -221.058511) (xy 359.90941 -221.108588) (xy 359.909872 -221.133924)
			(xy 359.909364 -221.159811) (xy 359.901265 -221.210949) (xy 359.885266 -221.260189) (xy 359.86176 -221.306321)
			(xy 359.831328 -221.348208) (xy 359.794718 -221.384818) (xy 359.752831 -221.41525) (xy 359.706699 -221.438756)
			(xy 359.657459 -221.454755) (xy 359.606321 -221.462854) (xy 359.554547 -221.462854) (xy 359.503409 -221.454755)
			(xy 359.454169 -221.438756) (xy 359.408037 -221.41525) (xy 359.36615 -221.384818) (xy 359.32954 -221.348208)
			(xy 359.299108 -221.306321) (xy 359.275602 -221.260189) (xy 359.259603 -221.210949) (xy 359.251504 -221.159811)
			(xy 359.250996 -221.133924) (xy 359.251532 -221.106216) (xy 359.260723 -221.051569) (xy 359.269284 -221.025212)
			(xy 359.277158 -221.003114) (xy 359.07218 -220.648022) (xy 359.04932 -220.643704) (xy 359.024479 -220.638521)
			(xy 358.976632 -220.621628) (xy 358.93194 -220.5976) (xy 358.891459 -220.567005) (xy 358.856148 -220.530566)
			(xy 358.826839 -220.489145) (xy 358.804227 -220.44372) (xy 358.788846 -220.395365) (xy 358.781059 -220.345225)
			(xy 358.780588 -220.319854) (xy 357.560372 -220.319854) (xy 357.559763 -220.347508) (xy 357.550439 -220.402026)
			(xy 357.54183 -220.428312) (xy 357.53421 -220.45041) (xy 357.739442 -220.805756) (xy 357.762302 -220.810074)
			(xy 357.787108 -220.815252) (xy 357.834847 -220.832242) (xy 357.879425 -220.856337) (xy 357.919791 -220.886969)
			(xy 357.954995 -220.923417) (xy 357.984206 -220.964822) (xy 358.006738 -221.01021) (xy 358.02206 -221.058511)
			(xy 358.02981 -221.108588) (xy 358.030272 -221.133924) (xy 358.029764 -221.159811) (xy 358.021665 -221.210949)
			(xy 358.005666 -221.260189) (xy 357.98216 -221.306321) (xy 357.951728 -221.348208) (xy 357.915118 -221.384818)
			(xy 357.873231 -221.41525) (xy 357.827099 -221.438756) (xy 357.777859 -221.454755) (xy 357.726721 -221.462854)
			(xy 357.674947 -221.462854) (xy 357.623809 -221.454755) (xy 357.574569 -221.438756) (xy 357.528437 -221.41525)
			(xy 357.48655 -221.384818) (xy 357.44994 -221.348208) (xy 357.419508 -221.306321) (xy 357.396002 -221.260189)
			(xy 357.380003 -221.210949) (xy 357.371904 -221.159811) (xy 357.371396 -221.133924) (xy 357.371932 -221.106216)
			(xy 357.381123 -221.051569) (xy 357.389684 -221.025212) (xy 357.397558 -221.003114) (xy 357.19258 -220.648022)
			(xy 357.16972 -220.643704) (xy 357.144879 -220.638521) (xy 357.097032 -220.621628) (xy 357.05234 -220.5976)
			(xy 357.011859 -220.567005) (xy 356.976548 -220.530566) (xy 356.947239 -220.489145) (xy 356.924627 -220.44372)
			(xy 356.909246 -220.395365) (xy 356.901459 -220.345225) (xy 356.900988 -220.319854) (xy 355.680772 -220.319854)
			(xy 355.680163 -220.347508) (xy 355.670839 -220.402026) (xy 355.66223 -220.428312) (xy 355.65461 -220.45041)
			(xy 355.859842 -220.805756) (xy 355.882702 -220.810074) (xy 355.907508 -220.815252) (xy 355.955247 -220.832242)
			(xy 355.999825 -220.856337) (xy 356.040191 -220.886969) (xy 356.075395 -220.923417) (xy 356.104606 -220.964822)
			(xy 356.127138 -221.01021) (xy 356.14246 -221.058511) (xy 356.15021 -221.108588) (xy 356.150672 -221.133924)
			(xy 356.150164 -221.159811) (xy 356.142065 -221.210949) (xy 356.126066 -221.260189) (xy 356.10256 -221.306321)
			(xy 356.072128 -221.348208) (xy 356.035518 -221.384818) (xy 355.993631 -221.41525) (xy 355.947499 -221.438756)
			(xy 355.898259 -221.454755) (xy 355.847121 -221.462854) (xy 355.795347 -221.462854) (xy 355.744209 -221.454755)
			(xy 355.694969 -221.438756) (xy 355.648837 -221.41525) (xy 355.60695 -221.384818) (xy 355.57034 -221.348208)
			(xy 355.539908 -221.306321) (xy 355.516402 -221.260189) (xy 355.500403 -221.210949) (xy 355.492304 -221.159811)
			(xy 355.491796 -221.133924) (xy 355.492332 -221.106216) (xy 355.501523 -221.051569) (xy 355.510084 -221.025212)
			(xy 355.517958 -221.003114) (xy 355.31298 -220.648022) (xy 355.29012 -220.643704) (xy 355.265279 -220.638521)
			(xy 355.217432 -220.621628) (xy 355.17274 -220.5976) (xy 355.132259 -220.567005) (xy 355.096948 -220.530566)
			(xy 355.067639 -220.489145) (xy 355.045027 -220.44372) (xy 355.029646 -220.395365) (xy 355.021859 -220.345225)
			(xy 355.021388 -220.319854) (xy 353.801172 -220.319854) (xy 353.800563 -220.347508) (xy 353.791239 -220.402026)
			(xy 353.78263 -220.428312) (xy 353.77501 -220.45041) (xy 353.980242 -220.805756) (xy 354.003102 -220.810074)
			(xy 354.027908 -220.815252) (xy 354.075647 -220.832242) (xy 354.120225 -220.856337) (xy 354.160591 -220.886969)
			(xy 354.195795 -220.923417) (xy 354.225006 -220.964822) (xy 354.247538 -221.01021) (xy 354.26286 -221.058511)
			(xy 354.27061 -221.108588) (xy 354.271072 -221.133924) (xy 354.270564 -221.159811) (xy 354.262465 -221.210949)
			(xy 354.246466 -221.260189) (xy 354.22296 -221.306321) (xy 354.192528 -221.348208) (xy 354.155918 -221.384818)
			(xy 354.114031 -221.41525) (xy 354.067899 -221.438756) (xy 354.018659 -221.454755) (xy 353.967521 -221.462854)
			(xy 353.915747 -221.462854) (xy 353.864609 -221.454755) (xy 353.815369 -221.438756) (xy 353.769237 -221.41525)
			(xy 353.72735 -221.384818) (xy 353.69074 -221.348208) (xy 353.660308 -221.306321) (xy 353.636802 -221.260189)
			(xy 353.620803 -221.210949) (xy 353.612704 -221.159811) (xy 353.612196 -221.133924) (xy 353.612732 -221.106216)
			(xy 353.621923 -221.051569) (xy 353.630484 -221.025212) (xy 353.638358 -221.003114) (xy 353.43338 -220.648022)
			(xy 353.41052 -220.643704) (xy 353.385679 -220.638521) (xy 353.337832 -220.621628) (xy 353.29314 -220.5976)
			(xy 353.252659 -220.567005) (xy 353.217348 -220.530566) (xy 353.188039 -220.489145) (xy 353.165427 -220.44372)
			(xy 353.150046 -220.395365) (xy 353.142259 -220.345225) (xy 353.141788 -220.319854) (xy 351.921572 -220.319854)
			(xy 351.921122 -220.3452) (xy 351.913342 -220.395293) (xy 351.897988 -220.443604) (xy 351.875422 -220.488998)
			(xy 351.846176 -220.530404) (xy 351.810939 -220.566847) (xy 351.77054 -220.597469) (xy 351.725931 -220.621548)
			(xy 351.678163 -220.638518) (xy 351.653348 -220.643704) (xy 351.630488 -220.648022) (xy 351.42551 -221.003114)
			(xy 351.433384 -221.024958) (xy 351.441977 -221.051373) (xy 351.451165 -221.106151) (xy 351.451672 -221.133924)
			(xy 351.451164 -221.159811) (xy 351.443065 -221.210949) (xy 351.427066 -221.260189) (xy 351.40356 -221.306321)
			(xy 351.373128 -221.348208) (xy 351.336518 -221.384818) (xy 351.294631 -221.41525) (xy 351.248499 -221.438756)
			(xy 351.199259 -221.454755) (xy 351.148121 -221.462854) (xy 351.096347 -221.462854) (xy 351.045209 -221.454755)
			(xy 350.995969 -221.438756) (xy 350.949837 -221.41525) (xy 350.90795 -221.384818) (xy 350.87134 -221.348208)
			(xy 350.840908 -221.306321) (xy 350.817402 -221.260189) (xy 350.801403 -221.210949) (xy 350.793304 -221.159811)
			(xy 350.792796 -221.133924) (xy 350.511872 -221.133924) (xy 350.511345 -221.161632) (xy 350.502148 -221.216279)
			(xy 350.493584 -221.242636) (xy 350.48571 -221.264734) (xy 350.690688 -221.619572) (xy 350.713548 -221.62389)
			(xy 350.738367 -221.629064) (xy 350.786146 -221.646018) (xy 350.830765 -221.670088) (xy 350.871172 -221.700708)
			(xy 350.906413 -221.737154) (xy 350.935657 -221.778566) (xy 350.958214 -221.823969) (xy 350.973552 -221.872291)
			(xy 350.98131 -221.922391) (xy 350.981772 -221.94774) (xy 352.201988 -221.94774) (xy 352.202465 -221.922395)
			(xy 352.210245 -221.872306) (xy 352.225597 -221.823996) (xy 352.24816 -221.778605) (xy 352.277403 -221.7372)
			(xy 352.312637 -221.700757) (xy 352.353031 -221.670134) (xy 352.397636 -221.646052) (xy 352.445399 -221.629078)
			(xy 352.470212 -221.62389) (xy 352.493072 -221.619572) (xy 352.698304 -221.264226) (xy 352.69043 -221.242128)
			(xy 352.681965 -221.215883) (xy 352.672893 -221.161495) (xy 352.672396 -221.133924) (xy 352.672904 -221.108037)
			(xy 352.681003 -221.056899) (xy 352.697002 -221.007659) (xy 352.720508 -220.961527) (xy 352.75094 -220.91964)
			(xy 352.78755 -220.88303) (xy 352.829437 -220.852598) (xy 352.875569 -220.829092) (xy 352.924809 -220.813093)
			(xy 352.975947 -220.804994) (xy 353.027721 -220.804994) (xy 353.078859 -220.813093) (xy 353.128099 -220.829092)
			(xy 353.174231 -220.852598) (xy 353.216118 -220.88303) (xy 353.252728 -220.91964) (xy 353.28316 -220.961527)
			(xy 353.306666 -221.007659) (xy 353.322665 -221.056899) (xy 353.330764 -221.108037) (xy 353.331272 -221.133924)
			(xy 353.330842 -221.1593) (xy 353.323069 -221.209454) (xy 353.307696 -221.257821) (xy 353.285086 -221.303259)
			(xy 353.255774 -221.344691) (xy 353.220455 -221.381137) (xy 353.179963 -221.411734) (xy 353.135258 -221.435759)
			(xy 353.087396 -221.452643) (xy 353.06254 -221.457774) (xy 353.03968 -221.462092) (xy 352.834956 -221.81693)
			(xy 352.84283 -221.838774) (xy 352.851486 -221.865179) (xy 352.8608 -221.919958) (xy 352.861372 -221.94774)
			(xy 354.081588 -221.94774) (xy 354.082065 -221.922395) (xy 354.089845 -221.872306) (xy 354.105197 -221.823996)
			(xy 354.12776 -221.778605) (xy 354.157003 -221.7372) (xy 354.192237 -221.700757) (xy 354.232631 -221.670134)
			(xy 354.277236 -221.646052) (xy 354.324999 -221.629078) (xy 354.349812 -221.62389) (xy 354.372672 -221.619572)
			(xy 354.577904 -221.264226) (xy 354.57003 -221.242128) (xy 354.561565 -221.215883) (xy 354.552493 -221.161495)
			(xy 354.551996 -221.133924) (xy 354.552504 -221.108037) (xy 354.560603 -221.056899) (xy 354.576602 -221.007659)
			(xy 354.600108 -220.961527) (xy 354.63054 -220.91964) (xy 354.66715 -220.88303) (xy 354.709037 -220.852598)
			(xy 354.755169 -220.829092) (xy 354.804409 -220.813093) (xy 354.855547 -220.804994) (xy 354.907321 -220.804994)
			(xy 354.958459 -220.813093) (xy 355.007699 -220.829092) (xy 355.053831 -220.852598) (xy 355.095718 -220.88303)
			(xy 355.132328 -220.91964) (xy 355.16276 -220.961527) (xy 355.186266 -221.007659) (xy 355.202265 -221.056899)
			(xy 355.210364 -221.108037) (xy 355.210872 -221.133924) (xy 355.210442 -221.1593) (xy 355.202669 -221.209454)
			(xy 355.187296 -221.257821) (xy 355.164686 -221.303259) (xy 355.135374 -221.344691) (xy 355.100055 -221.381137)
			(xy 355.059563 -221.411734) (xy 355.014858 -221.435759) (xy 354.966996 -221.452643) (xy 354.94214 -221.457774)
			(xy 354.91928 -221.462092) (xy 354.714556 -221.81693) (xy 354.72243 -221.838774) (xy 354.731086 -221.865179)
			(xy 354.7404 -221.919958) (xy 354.740972 -221.94774) (xy 355.961188 -221.94774) (xy 355.961665 -221.922395)
			(xy 355.969445 -221.872306) (xy 355.984797 -221.823996) (xy 356.00736 -221.778605) (xy 356.036603 -221.7372)
			(xy 356.071837 -221.700757) (xy 356.112231 -221.670134) (xy 356.156836 -221.646052) (xy 356.204599 -221.629078)
			(xy 356.229412 -221.62389) (xy 356.252272 -221.619572) (xy 356.457504 -221.264226) (xy 356.44963 -221.242128)
			(xy 356.441165 -221.215883) (xy 356.432093 -221.161495) (xy 356.431596 -221.133924) (xy 356.432104 -221.108037)
			(xy 356.440203 -221.056899) (xy 356.456202 -221.007659) (xy 356.479708 -220.961527) (xy 356.51014 -220.91964)
			(xy 356.54675 -220.88303) (xy 356.588637 -220.852598) (xy 356.634769 -220.829092) (xy 356.684009 -220.813093)
			(xy 356.735147 -220.804994) (xy 356.786921 -220.804994) (xy 356.838059 -220.813093) (xy 356.887299 -220.829092)
			(xy 356.933431 -220.852598) (xy 356.975318 -220.88303) (xy 357.011928 -220.91964) (xy 357.04236 -220.961527)
			(xy 357.065866 -221.007659) (xy 357.081865 -221.056899) (xy 357.089964 -221.108037) (xy 357.090472 -221.133924)
			(xy 357.090042 -221.1593) (xy 357.082269 -221.209454) (xy 357.066896 -221.257821) (xy 357.044286 -221.303259)
			(xy 357.014974 -221.344691) (xy 356.979655 -221.381137) (xy 356.939163 -221.411734) (xy 356.894458 -221.435759)
			(xy 356.846596 -221.452643) (xy 356.82174 -221.457774) (xy 356.79888 -221.462092) (xy 356.594156 -221.81693)
			(xy 356.60203 -221.838774) (xy 356.610686 -221.865179) (xy 356.62 -221.919958) (xy 356.620572 -221.94774)
			(xy 357.841296 -221.94774) (xy 357.841727 -221.922404) (xy 357.849489 -221.872329) (xy 357.864819 -221.824032)
			(xy 357.887358 -221.778648) (xy 357.916574 -221.737246) (xy 357.95178 -221.700802) (xy 357.992148 -221.670172)
			(xy 358.036725 -221.646079) (xy 358.084465 -221.629089) (xy 358.109266 -221.62389) (xy 358.132126 -221.619572)
			(xy 358.337104 -221.26448) (xy 358.329484 -221.242382) (xy 358.320964 -221.216211) (xy 358.311771 -221.161949)
			(xy 358.311196 -221.134432) (xy 358.311196 -221.133924) (xy 358.311704 -221.108037) (xy 358.319803 -221.056899)
			(xy 358.335802 -221.007659) (xy 358.359308 -220.961527) (xy 358.38974 -220.91964) (xy 358.42635 -220.88303)
			(xy 358.468237 -220.852598) (xy 358.514369 -220.829092) (xy 358.563609 -220.813093) (xy 358.614747 -220.804994)
			(xy 358.666521 -220.804994) (xy 358.717659 -220.813093) (xy 358.766899 -220.829092) (xy 358.813031 -220.852598)
			(xy 358.854918 -220.88303) (xy 358.891528 -220.91964) (xy 358.92196 -220.961527) (xy 358.945466 -221.007659)
			(xy 358.961465 -221.056899) (xy 358.969564 -221.108037) (xy 358.970072 -221.133924) (xy 358.969679 -221.159291)
			(xy 358.961926 -221.209429) (xy 358.946575 -221.257784) (xy 358.923991 -221.303213) (xy 358.894706 -221.344642)
			(xy 358.859415 -221.381089) (xy 358.818952 -221.411694) (xy 358.774274 -221.435731) (xy 358.726438 -221.452632)
			(xy 358.701594 -221.457774) (xy 358.678734 -221.462092) (xy 358.47401 -221.81693) (xy 358.481884 -221.838774)
			(xy 358.490481 -221.865188) (xy 358.499666 -221.919967) (xy 358.500172 -221.94774) (xy 359.720388 -221.94774)
			(xy 359.720865 -221.922395) (xy 359.728645 -221.872306) (xy 359.743997 -221.823996) (xy 359.76656 -221.778605)
			(xy 359.795803 -221.7372) (xy 359.831037 -221.700757) (xy 359.871431 -221.670134) (xy 359.916036 -221.646052)
			(xy 359.963799 -221.629078) (xy 359.988612 -221.62389) (xy 360.011472 -221.619572) (xy 360.216704 -221.264226)
			(xy 360.20883 -221.242128) (xy 360.200365 -221.215883) (xy 360.191293 -221.161495) (xy 360.190796 -221.133924)
			(xy 360.191304 -221.108037) (xy 360.199403 -221.056899) (xy 360.215402 -221.007659) (xy 360.238908 -220.961527)
			(xy 360.26934 -220.91964) (xy 360.30595 -220.88303) (xy 360.347837 -220.852598) (xy 360.393969 -220.829092)
			(xy 360.443209 -220.813093) (xy 360.494347 -220.804994) (xy 360.546121 -220.804994) (xy 360.597259 -220.813093)
			(xy 360.646499 -220.829092) (xy 360.692631 -220.852598) (xy 360.734518 -220.88303) (xy 360.771128 -220.91964)
			(xy 360.80156 -220.961527) (xy 360.825066 -221.007659) (xy 360.841065 -221.056899) (xy 360.849164 -221.108037)
			(xy 360.849672 -221.133924) (xy 360.849242 -221.1593) (xy 360.841469 -221.209454) (xy 360.826096 -221.257821)
			(xy 360.803486 -221.303259) (xy 360.774174 -221.344691) (xy 360.738855 -221.381137) (xy 360.698363 -221.411734)
			(xy 360.653658 -221.435759) (xy 360.605796 -221.452643) (xy 360.58094 -221.457774) (xy 360.55808 -221.462092)
			(xy 360.353356 -221.81693) (xy 360.36123 -221.838774) (xy 360.369886 -221.865179) (xy 360.3792 -221.919958)
			(xy 360.379772 -221.94774) (xy 361.600496 -221.94774) (xy 361.600927 -221.922404) (xy 361.608689 -221.872329)
			(xy 361.624019 -221.824032) (xy 361.646558 -221.778648) (xy 361.675774 -221.737246) (xy 361.71098 -221.700802)
			(xy 361.751348 -221.670172) (xy 361.795925 -221.646079) (xy 361.843665 -221.629089) (xy 361.868466 -221.62389)
			(xy 361.891326 -221.619572) (xy 362.096304 -221.26448) (xy 362.088684 -221.242382) (xy 362.080164 -221.216211)
			(xy 362.070971 -221.161949) (xy 362.070396 -221.134432) (xy 362.070396 -221.133924) (xy 362.070904 -221.108037)
			(xy 362.079003 -221.056899) (xy 362.095002 -221.007659) (xy 362.118508 -220.961527) (xy 362.14894 -220.91964)
			(xy 362.18555 -220.88303) (xy 362.227437 -220.852598) (xy 362.273569 -220.829092) (xy 362.322809 -220.813093)
			(xy 362.373947 -220.804994) (xy 362.425721 -220.804994) (xy 362.476859 -220.813093) (xy 362.526099 -220.829092)
			(xy 362.572231 -220.852598) (xy 362.614118 -220.88303) (xy 362.650728 -220.91964) (xy 362.68116 -220.961527)
			(xy 362.704666 -221.007659) (xy 362.720665 -221.056899) (xy 362.728764 -221.108037) (xy 362.729272 -221.133924)
			(xy 362.728879 -221.159291) (xy 362.721126 -221.209429) (xy 362.705775 -221.257784) (xy 362.683191 -221.303213)
			(xy 362.653906 -221.344642) (xy 362.618615 -221.381089) (xy 362.578152 -221.411694) (xy 362.533474 -221.435731)
			(xy 362.485638 -221.452632) (xy 362.460794 -221.457774) (xy 362.437934 -221.462092) (xy 362.23321 -221.81693)
			(xy 362.241084 -221.838774) (xy 362.249681 -221.865188) (xy 362.258866 -221.919967) (xy 362.259372 -221.94774)
			(xy 363.479588 -221.94774) (xy 363.480065 -221.922395) (xy 363.487845 -221.872306) (xy 363.503197 -221.823996)
			(xy 363.52576 -221.778605) (xy 363.555003 -221.7372) (xy 363.590237 -221.700757) (xy 363.630631 -221.670134)
			(xy 363.675236 -221.646052) (xy 363.722999 -221.629078) (xy 363.747812 -221.62389) (xy 363.770672 -221.619572)
			(xy 363.975904 -221.264226) (xy 363.96803 -221.242128) (xy 363.959565 -221.215883) (xy 363.950493 -221.161495)
			(xy 363.949996 -221.133924) (xy 363.950504 -221.108037) (xy 363.958603 -221.056899) (xy 363.974602 -221.007659)
			(xy 363.998108 -220.961527) (xy 364.02854 -220.91964) (xy 364.06515 -220.88303) (xy 364.107037 -220.852598)
			(xy 364.153169 -220.829092) (xy 364.202409 -220.813093) (xy 364.253547 -220.804994) (xy 364.305321 -220.804994)
			(xy 364.356459 -220.813093) (xy 364.405699 -220.829092) (xy 364.451831 -220.852598) (xy 364.493718 -220.88303)
			(xy 364.530328 -220.91964) (xy 364.56076 -220.961527) (xy 364.584266 -221.007659) (xy 364.600265 -221.056899)
			(xy 364.608364 -221.108037) (xy 364.608872 -221.133924) (xy 364.608442 -221.1593) (xy 364.600669 -221.209454)
			(xy 364.585296 -221.257821) (xy 364.562686 -221.303259) (xy 364.533374 -221.344691) (xy 364.498055 -221.381137)
			(xy 364.457563 -221.411734) (xy 364.412858 -221.435759) (xy 364.364996 -221.452643) (xy 364.34014 -221.457774)
			(xy 364.31728 -221.462092) (xy 364.112556 -221.81693) (xy 364.12043 -221.838774) (xy 364.129086 -221.865179)
			(xy 364.1384 -221.919958) (xy 364.138972 -221.94774) (xy 365.359188 -221.94774) (xy 365.359665 -221.922395)
			(xy 365.367445 -221.872306) (xy 365.382797 -221.823996) (xy 365.40536 -221.778605) (xy 365.434603 -221.7372)
			(xy 365.469837 -221.700757) (xy 365.510231 -221.670134) (xy 365.554836 -221.646052) (xy 365.602599 -221.629078)
			(xy 365.627412 -221.62389) (xy 365.650272 -221.619572) (xy 365.855504 -221.264226) (xy 365.84763 -221.242128)
			(xy 365.839165 -221.215883) (xy 365.830093 -221.161495) (xy 365.829596 -221.133924) (xy 365.830104 -221.108037)
			(xy 365.838203 -221.056899) (xy 365.854202 -221.007659) (xy 365.877708 -220.961527) (xy 365.90814 -220.91964)
			(xy 365.94475 -220.88303) (xy 365.986637 -220.852598) (xy 366.032769 -220.829092) (xy 366.082009 -220.813093)
			(xy 366.133147 -220.804994) (xy 366.184921 -220.804994) (xy 366.236059 -220.813093) (xy 366.285299 -220.829092)
			(xy 366.331431 -220.852598) (xy 366.373318 -220.88303) (xy 366.409928 -220.91964) (xy 366.44036 -220.961527)
			(xy 366.463866 -221.007659) (xy 366.479865 -221.056899) (xy 366.487964 -221.108037) (xy 366.488472 -221.133924)
			(xy 366.488042 -221.1593) (xy 366.480269 -221.209454) (xy 366.464896 -221.257821) (xy 366.442286 -221.303259)
			(xy 366.412974 -221.344691) (xy 366.377655 -221.381137) (xy 366.337163 -221.411734) (xy 366.292458 -221.435759)
			(xy 366.244596 -221.452643) (xy 366.21974 -221.457774) (xy 366.19688 -221.462092) (xy 365.992156 -221.81693)
			(xy 366.00003 -221.838774) (xy 366.008686 -221.865179) (xy 366.018 -221.919958) (xy 366.018572 -221.94774)
			(xy 369.118388 -221.94774) (xy 369.118865 -221.922395) (xy 369.126645 -221.872306) (xy 369.141997 -221.823996)
			(xy 369.16456 -221.778605) (xy 369.193803 -221.7372) (xy 369.229037 -221.700757) (xy 369.269431 -221.670134)
			(xy 369.314036 -221.646052) (xy 369.361799 -221.629078) (xy 369.386612 -221.62389) (xy 369.409472 -221.619572)
			(xy 369.614704 -221.264226) (xy 369.60683 -221.242128) (xy 369.598365 -221.215883) (xy 369.589293 -221.161495)
			(xy 369.588796 -221.133924) (xy 369.589304 -221.108037) (xy 369.597403 -221.056899) (xy 369.613402 -221.007659)
			(xy 369.636908 -220.961527) (xy 369.66734 -220.91964) (xy 369.70395 -220.88303) (xy 369.745837 -220.852598)
			(xy 369.791969 -220.829092) (xy 369.841209 -220.813093) (xy 369.892347 -220.804994) (xy 369.944121 -220.804994)
			(xy 369.995259 -220.813093) (xy 370.044499 -220.829092) (xy 370.090631 -220.852598) (xy 370.132518 -220.88303)
			(xy 370.169128 -220.91964) (xy 370.19956 -220.961527) (xy 370.223066 -221.007659) (xy 370.239065 -221.056899)
			(xy 370.247164 -221.108037) (xy 370.247672 -221.133924) (xy 370.247242 -221.1593) (xy 370.239469 -221.209454)
			(xy 370.224096 -221.257821) (xy 370.201486 -221.303259) (xy 370.172174 -221.344691) (xy 370.136855 -221.381137)
			(xy 370.096363 -221.411734) (xy 370.051658 -221.435759) (xy 370.003796 -221.452643) (xy 369.97894 -221.457774)
			(xy 369.95608 -221.462092) (xy 369.751356 -221.81693) (xy 369.75923 -221.838774) (xy 369.767886 -221.865179)
			(xy 369.7772 -221.919958) (xy 369.777772 -221.94774) (xy 370.997988 -221.94774) (xy 370.998465 -221.922395)
			(xy 371.006245 -221.872306) (xy 371.021597 -221.823996) (xy 371.04416 -221.778605) (xy 371.073403 -221.7372)
			(xy 371.108637 -221.700757) (xy 371.149031 -221.670134) (xy 371.193636 -221.646052) (xy 371.241399 -221.629078)
			(xy 371.266212 -221.62389) (xy 371.289072 -221.619572) (xy 371.494304 -221.264226) (xy 371.48643 -221.242128)
			(xy 371.477965 -221.215883) (xy 371.468893 -221.161495) (xy 371.468396 -221.133924) (xy 371.468904 -221.108037)
			(xy 371.477003 -221.056899) (xy 371.493002 -221.007659) (xy 371.516508 -220.961527) (xy 371.54694 -220.91964)
			(xy 371.58355 -220.88303) (xy 371.625437 -220.852598) (xy 371.671569 -220.829092) (xy 371.720809 -220.813093)
			(xy 371.771947 -220.804994) (xy 371.823721 -220.804994) (xy 371.874859 -220.813093) (xy 371.924099 -220.829092)
			(xy 371.970231 -220.852598) (xy 372.012118 -220.88303) (xy 372.048728 -220.91964) (xy 372.07916 -220.961527)
			(xy 372.102666 -221.007659) (xy 372.118665 -221.056899) (xy 372.126764 -221.108037) (xy 372.127272 -221.133924)
			(xy 372.126842 -221.1593) (xy 372.119069 -221.209454) (xy 372.103696 -221.257821) (xy 372.081086 -221.303259)
			(xy 372.051774 -221.344691) (xy 372.016455 -221.381137) (xy 371.975963 -221.411734) (xy 371.931258 -221.435759)
			(xy 371.883396 -221.452643) (xy 371.85854 -221.457774) (xy 371.83568 -221.462092) (xy 371.630956 -221.81693)
			(xy 371.63883 -221.838774) (xy 371.647486 -221.865179) (xy 371.6568 -221.919958) (xy 371.657372 -221.94774)
			(xy 372.877588 -221.94774) (xy 372.878065 -221.922395) (xy 372.885845 -221.872306) (xy 372.901197 -221.823996)
			(xy 372.92376 -221.778605) (xy 372.953003 -221.7372) (xy 372.988237 -221.700757) (xy 373.028631 -221.670134)
			(xy 373.073236 -221.646052) (xy 373.120999 -221.629078) (xy 373.145812 -221.62389) (xy 373.168672 -221.619572)
			(xy 373.373904 -221.264226) (xy 373.36603 -221.242128) (xy 373.357565 -221.215883) (xy 373.348493 -221.161495)
			(xy 373.347996 -221.133924) (xy 373.348504 -221.108037) (xy 373.356603 -221.056899) (xy 373.372602 -221.007659)
			(xy 373.396108 -220.961527) (xy 373.42654 -220.91964) (xy 373.46315 -220.88303) (xy 373.505037 -220.852598)
			(xy 373.551169 -220.829092) (xy 373.600409 -220.813093) (xy 373.651547 -220.804994) (xy 373.703321 -220.804994)
			(xy 373.754459 -220.813093) (xy 373.803699 -220.829092) (xy 373.849831 -220.852598) (xy 373.891718 -220.88303)
			(xy 373.928328 -220.91964) (xy 373.95876 -220.961527) (xy 373.982266 -221.007659) (xy 373.998265 -221.056899)
			(xy 374.006364 -221.108037) (xy 374.006872 -221.133924) (xy 374.006442 -221.1593) (xy 373.998669 -221.209454)
			(xy 373.983296 -221.257821) (xy 373.960686 -221.303259) (xy 373.931374 -221.344691) (xy 373.896055 -221.381137)
			(xy 373.855563 -221.411734) (xy 373.810858 -221.435759) (xy 373.762996 -221.452643) (xy 373.73814 -221.457774)
			(xy 373.71528 -221.462092) (xy 373.510556 -221.81693) (xy 373.51843 -221.838774) (xy 373.527086 -221.865179)
			(xy 373.5364 -221.919958) (xy 373.536972 -221.94774) (xy 374.757188 -221.94774) (xy 374.757665 -221.922395)
			(xy 374.765445 -221.872306) (xy 374.780797 -221.823996) (xy 374.80336 -221.778605) (xy 374.832603 -221.7372)
			(xy 374.867837 -221.700757) (xy 374.908231 -221.670134) (xy 374.952836 -221.646052) (xy 375.000599 -221.629078)
			(xy 375.025412 -221.62389) (xy 375.048272 -221.619572) (xy 375.253504 -221.264226) (xy 375.24563 -221.242128)
			(xy 375.237165 -221.215883) (xy 375.228093 -221.161495) (xy 375.227596 -221.133924) (xy 375.228104 -221.108037)
			(xy 375.236203 -221.056899) (xy 375.252202 -221.007659) (xy 375.275708 -220.961527) (xy 375.30614 -220.91964)
			(xy 375.34275 -220.88303) (xy 375.384637 -220.852598) (xy 375.430769 -220.829092) (xy 375.480009 -220.813093)
			(xy 375.531147 -220.804994) (xy 375.582921 -220.804994) (xy 375.634059 -220.813093) (xy 375.683299 -220.829092)
			(xy 375.729431 -220.852598) (xy 375.771318 -220.88303) (xy 375.807928 -220.91964) (xy 375.83836 -220.961527)
			(xy 375.861866 -221.007659) (xy 375.877865 -221.056899) (xy 375.885964 -221.108037) (xy 375.886472 -221.133924)
			(xy 375.886042 -221.1593) (xy 375.878269 -221.209454) (xy 375.862896 -221.257821) (xy 375.840286 -221.303259)
			(xy 375.810974 -221.344691) (xy 375.775655 -221.381137) (xy 375.735163 -221.411734) (xy 375.690458 -221.435759)
			(xy 375.642596 -221.452643) (xy 375.61774 -221.457774) (xy 375.59488 -221.462092) (xy 375.390156 -221.81693)
			(xy 375.39803 -221.838774) (xy 375.406686 -221.865179) (xy 375.416 -221.919958) (xy 375.416572 -221.94774)
			(xy 376.636788 -221.94774) (xy 376.637265 -221.922395) (xy 376.645045 -221.872306) (xy 376.660397 -221.823996)
			(xy 376.68296 -221.778605) (xy 376.712203 -221.7372) (xy 376.747437 -221.700757) (xy 376.787831 -221.670134)
			(xy 376.832436 -221.646052) (xy 376.880199 -221.629078) (xy 376.905012 -221.62389) (xy 376.927872 -221.619572)
			(xy 377.133104 -221.264226) (xy 377.12523 -221.242128) (xy 377.116765 -221.215883) (xy 377.107693 -221.161495)
			(xy 377.107196 -221.133924) (xy 377.107704 -221.108037) (xy 377.115803 -221.056899) (xy 377.131802 -221.007659)
			(xy 377.155308 -220.961527) (xy 377.18574 -220.91964) (xy 377.22235 -220.88303) (xy 377.264237 -220.852598)
			(xy 377.310369 -220.829092) (xy 377.359609 -220.813093) (xy 377.410747 -220.804994) (xy 377.462521 -220.804994)
			(xy 377.513659 -220.813093) (xy 377.562899 -220.829092) (xy 377.609031 -220.852598) (xy 377.650918 -220.88303)
			(xy 377.687528 -220.91964) (xy 377.71796 -220.961527) (xy 377.741466 -221.007659) (xy 377.757465 -221.056899)
			(xy 377.765564 -221.108037) (xy 377.766072 -221.133924) (xy 377.765642 -221.1593) (xy 377.757869 -221.209454)
			(xy 377.742496 -221.257821) (xy 377.719886 -221.303259) (xy 377.690574 -221.344691) (xy 377.655255 -221.381137)
			(xy 377.614763 -221.411734) (xy 377.570058 -221.435759) (xy 377.522196 -221.452643) (xy 377.49734 -221.457774)
			(xy 377.47448 -221.462092) (xy 377.269756 -221.81693) (xy 377.27763 -221.838774) (xy 377.286286 -221.865179)
			(xy 377.2956 -221.919958) (xy 377.296172 -221.94774) (xy 378.516388 -221.94774) (xy 378.516865 -221.922395)
			(xy 378.524645 -221.872306) (xy 378.539997 -221.823996) (xy 378.56256 -221.778605) (xy 378.591803 -221.7372)
			(xy 378.627037 -221.700757) (xy 378.667431 -221.670134) (xy 378.712036 -221.646052) (xy 378.759799 -221.629078)
			(xy 378.784612 -221.62389) (xy 378.807472 -221.619572) (xy 379.012704 -221.264226) (xy 379.00483 -221.242128)
			(xy 378.996365 -221.215883) (xy 378.987293 -221.161495) (xy 378.986796 -221.133924) (xy 378.987304 -221.108037)
			(xy 378.995403 -221.056899) (xy 379.011402 -221.007659) (xy 379.034908 -220.961527) (xy 379.06534 -220.91964)
			(xy 379.10195 -220.88303) (xy 379.143837 -220.852598) (xy 379.189969 -220.829092) (xy 379.239209 -220.813093)
			(xy 379.290347 -220.804994) (xy 379.342121 -220.804994) (xy 379.393259 -220.813093) (xy 379.442499 -220.829092)
			(xy 379.488631 -220.852598) (xy 379.530518 -220.88303) (xy 379.567128 -220.91964) (xy 379.59756 -220.961527)
			(xy 379.621066 -221.007659) (xy 379.637065 -221.056899) (xy 379.645164 -221.108037) (xy 379.645672 -221.133924)
			(xy 379.645242 -221.1593) (xy 379.637469 -221.209454) (xy 379.622096 -221.257821) (xy 379.599486 -221.303259)
			(xy 379.570174 -221.344691) (xy 379.534855 -221.381137) (xy 379.494363 -221.411734) (xy 379.449658 -221.435759)
			(xy 379.401796 -221.452643) (xy 379.37694 -221.457774) (xy 379.35408 -221.462092) (xy 379.149356 -221.81693)
			(xy 379.15723 -221.838774) (xy 379.165886 -221.865179) (xy 379.1752 -221.919958) (xy 379.175772 -221.94774)
			(xy 379.175264 -221.973647) (xy 379.167158 -222.024824) (xy 379.151146 -222.074103) (xy 379.127623 -222.12027)
			(xy 379.097167 -222.162189) (xy 379.060529 -222.198827) (xy 379.01861 -222.229283) (xy 378.972443 -222.252806)
			(xy 378.923164 -222.268818) (xy 378.871987 -222.276924) (xy 378.820173 -222.276924) (xy 378.768996 -222.268818)
			(xy 378.719717 -222.252806) (xy 378.67355 -222.229283) (xy 378.631631 -222.198827) (xy 378.594993 -222.162189)
			(xy 378.564537 -222.12027) (xy 378.541014 -222.074103) (xy 378.525002 -222.024824) (xy 378.516896 -221.973647)
			(xy 378.516388 -221.94774) (xy 377.296172 -221.94774) (xy 377.295664 -221.973647) (xy 377.287558 -222.024824)
			(xy 377.271546 -222.074103) (xy 377.248023 -222.12027) (xy 377.217567 -222.162189) (xy 377.180929 -222.198827)
			(xy 377.13901 -222.229283) (xy 377.092843 -222.252806) (xy 377.043564 -222.268818) (xy 376.992387 -222.276924)
			(xy 376.940573 -222.276924) (xy 376.889396 -222.268818) (xy 376.840117 -222.252806) (xy 376.79395 -222.229283)
			(xy 376.752031 -222.198827) (xy 376.715393 -222.162189) (xy 376.684937 -222.12027) (xy 376.661414 -222.074103)
			(xy 376.645402 -222.024824) (xy 376.637296 -221.973647) (xy 376.636788 -221.94774) (xy 375.416572 -221.94774)
			(xy 375.416064 -221.973647) (xy 375.407958 -222.024824) (xy 375.391946 -222.074103) (xy 375.368423 -222.12027)
			(xy 375.337967 -222.162189) (xy 375.301329 -222.198827) (xy 375.25941 -222.229283) (xy 375.213243 -222.252806)
			(xy 375.163964 -222.268818) (xy 375.112787 -222.276924) (xy 375.060973 -222.276924) (xy 375.009796 -222.268818)
			(xy 374.960517 -222.252806) (xy 374.91435 -222.229283) (xy 374.872431 -222.198827) (xy 374.835793 -222.162189)
			(xy 374.805337 -222.12027) (xy 374.781814 -222.074103) (xy 374.765802 -222.024824) (xy 374.757696 -221.973647)
			(xy 374.757188 -221.94774) (xy 373.536972 -221.94774) (xy 373.536464 -221.973647) (xy 373.528358 -222.024824)
			(xy 373.512346 -222.074103) (xy 373.488823 -222.12027) (xy 373.458367 -222.162189) (xy 373.421729 -222.198827)
			(xy 373.37981 -222.229283) (xy 373.333643 -222.252806) (xy 373.284364 -222.268818) (xy 373.233187 -222.276924)
			(xy 373.181373 -222.276924) (xy 373.130196 -222.268818) (xy 373.080917 -222.252806) (xy 373.03475 -222.229283)
			(xy 372.992831 -222.198827) (xy 372.956193 -222.162189) (xy 372.925737 -222.12027) (xy 372.902214 -222.074103)
			(xy 372.886202 -222.024824) (xy 372.878096 -221.973647) (xy 372.877588 -221.94774) (xy 371.657372 -221.94774)
			(xy 371.656864 -221.973647) (xy 371.648758 -222.024824) (xy 371.632746 -222.074103) (xy 371.609223 -222.12027)
			(xy 371.578767 -222.162189) (xy 371.542129 -222.198827) (xy 371.50021 -222.229283) (xy 371.454043 -222.252806)
			(xy 371.404764 -222.268818) (xy 371.353587 -222.276924) (xy 371.301773 -222.276924) (xy 371.250596 -222.268818)
			(xy 371.201317 -222.252806) (xy 371.15515 -222.229283) (xy 371.113231 -222.198827) (xy 371.076593 -222.162189)
			(xy 371.046137 -222.12027) (xy 371.022614 -222.074103) (xy 371.006602 -222.024824) (xy 370.998496 -221.973647)
			(xy 370.997988 -221.94774) (xy 369.777772 -221.94774) (xy 369.777264 -221.973647) (xy 369.769158 -222.024824)
			(xy 369.753146 -222.074103) (xy 369.729623 -222.12027) (xy 369.699167 -222.162189) (xy 369.662529 -222.198827)
			(xy 369.62061 -222.229283) (xy 369.574443 -222.252806) (xy 369.525164 -222.268818) (xy 369.473987 -222.276924)
			(xy 369.422173 -222.276924) (xy 369.370996 -222.268818) (xy 369.321717 -222.252806) (xy 369.27555 -222.229283)
			(xy 369.233631 -222.198827) (xy 369.196993 -222.162189) (xy 369.166537 -222.12027) (xy 369.143014 -222.074103)
			(xy 369.127002 -222.024824) (xy 369.118896 -221.973647) (xy 369.118388 -221.94774) (xy 366.018572 -221.94774)
			(xy 366.018064 -221.973647) (xy 366.009958 -222.024824) (xy 365.993946 -222.074103) (xy 365.970423 -222.12027)
			(xy 365.939967 -222.162189) (xy 365.903329 -222.198827) (xy 365.86141 -222.229283) (xy 365.815243 -222.252806)
			(xy 365.765964 -222.268818) (xy 365.714787 -222.276924) (xy 365.662973 -222.276924) (xy 365.611796 -222.268818)
			(xy 365.562517 -222.252806) (xy 365.51635 -222.229283) (xy 365.474431 -222.198827) (xy 365.437793 -222.162189)
			(xy 365.407337 -222.12027) (xy 365.383814 -222.074103) (xy 365.367802 -222.024824) (xy 365.359696 -221.973647)
			(xy 365.359188 -221.94774) (xy 364.138972 -221.94774) (xy 364.138464 -221.973647) (xy 364.130358 -222.024824)
			(xy 364.114346 -222.074103) (xy 364.090823 -222.12027) (xy 364.060367 -222.162189) (xy 364.023729 -222.198827)
			(xy 363.98181 -222.229283) (xy 363.935643 -222.252806) (xy 363.886364 -222.268818) (xy 363.835187 -222.276924)
			(xy 363.783373 -222.276924) (xy 363.732196 -222.268818) (xy 363.682917 -222.252806) (xy 363.63675 -222.229283)
			(xy 363.594831 -222.198827) (xy 363.558193 -222.162189) (xy 363.527737 -222.12027) (xy 363.504214 -222.074103)
			(xy 363.488202 -222.024824) (xy 363.480096 -221.973647) (xy 363.479588 -221.94774) (xy 362.259372 -221.94774)
			(xy 362.258864 -221.973627) (xy 362.250765 -222.024765) (xy 362.234766 -222.074005) (xy 362.21126 -222.120137)
			(xy 362.180828 -222.162024) (xy 362.144218 -222.198634) (xy 362.102331 -222.229066) (xy 362.056199 -222.252572)
			(xy 362.006959 -222.268571) (xy 361.955821 -222.27667) (xy 361.904047 -222.27667) (xy 361.852909 -222.268571)
			(xy 361.803669 -222.252572) (xy 361.757537 -222.229066) (xy 361.71565 -222.198634) (xy 361.67904 -222.162024)
			(xy 361.648608 -222.120137) (xy 361.625102 -222.074005) (xy 361.609103 -222.024765) (xy 361.601004 -221.973627)
			(xy 361.600496 -221.94774) (xy 360.379772 -221.94774) (xy 360.379264 -221.973647) (xy 360.371158 -222.024824)
			(xy 360.355146 -222.074103) (xy 360.331623 -222.12027) (xy 360.301167 -222.162189) (xy 360.264529 -222.198827)
			(xy 360.22261 -222.229283) (xy 360.176443 -222.252806) (xy 360.127164 -222.268818) (xy 360.075987 -222.276924)
			(xy 360.024173 -222.276924) (xy 359.972996 -222.268818) (xy 359.923717 -222.252806) (xy 359.87755 -222.229283)
			(xy 359.835631 -222.198827) (xy 359.798993 -222.162189) (xy 359.768537 -222.12027) (xy 359.745014 -222.074103)
			(xy 359.729002 -222.024824) (xy 359.720896 -221.973647) (xy 359.720388 -221.94774) (xy 358.500172 -221.94774)
			(xy 358.499664 -221.973627) (xy 358.491565 -222.024765) (xy 358.475566 -222.074005) (xy 358.45206 -222.120137)
			(xy 358.421628 -222.162024) (xy 358.385018 -222.198634) (xy 358.343131 -222.229066) (xy 358.296999 -222.252572)
			(xy 358.247759 -222.268571) (xy 358.196621 -222.27667) (xy 358.144847 -222.27667) (xy 358.093709 -222.268571)
			(xy 358.044469 -222.252572) (xy 357.998337 -222.229066) (xy 357.95645 -222.198634) (xy 357.91984 -222.162024)
			(xy 357.889408 -222.120137) (xy 357.865902 -222.074005) (xy 357.849903 -222.024765) (xy 357.841804 -221.973627)
			(xy 357.841296 -221.94774) (xy 356.620572 -221.94774) (xy 356.620064 -221.973647) (xy 356.611958 -222.024824)
			(xy 356.595946 -222.074103) (xy 356.572423 -222.12027) (xy 356.541967 -222.162189) (xy 356.505329 -222.198827)
			(xy 356.46341 -222.229283) (xy 356.417243 -222.252806) (xy 356.367964 -222.268818) (xy 356.316787 -222.276924)
			(xy 356.264973 -222.276924) (xy 356.213796 -222.268818) (xy 356.164517 -222.252806) (xy 356.11835 -222.229283)
			(xy 356.076431 -222.198827) (xy 356.039793 -222.162189) (xy 356.009337 -222.12027) (xy 355.985814 -222.074103)
			(xy 355.969802 -222.024824) (xy 355.961696 -221.973647) (xy 355.961188 -221.94774) (xy 354.740972 -221.94774)
			(xy 354.740464 -221.973647) (xy 354.732358 -222.024824) (xy 354.716346 -222.074103) (xy 354.692823 -222.12027)
			(xy 354.662367 -222.162189) (xy 354.625729 -222.198827) (xy 354.58381 -222.229283) (xy 354.537643 -222.252806)
			(xy 354.488364 -222.268818) (xy 354.437187 -222.276924) (xy 354.385373 -222.276924) (xy 354.334196 -222.268818)
			(xy 354.284917 -222.252806) (xy 354.23875 -222.229283) (xy 354.196831 -222.198827) (xy 354.160193 -222.162189)
			(xy 354.129737 -222.12027) (xy 354.106214 -222.074103) (xy 354.090202 -222.024824) (xy 354.082096 -221.973647)
			(xy 354.081588 -221.94774) (xy 352.861372 -221.94774) (xy 352.860864 -221.973647) (xy 352.852758 -222.024824)
			(xy 352.836746 -222.074103) (xy 352.813223 -222.12027) (xy 352.782767 -222.162189) (xy 352.746129 -222.198827)
			(xy 352.70421 -222.229283) (xy 352.658043 -222.252806) (xy 352.608764 -222.268818) (xy 352.557587 -222.276924)
			(xy 352.505773 -222.276924) (xy 352.454596 -222.268818) (xy 352.405317 -222.252806) (xy 352.35915 -222.229283)
			(xy 352.317231 -222.198827) (xy 352.280593 -222.162189) (xy 352.250137 -222.12027) (xy 352.226614 -222.074103)
			(xy 352.210602 -222.024824) (xy 352.202496 -221.973647) (xy 352.201988 -221.94774) (xy 350.981772 -221.94774)
			(xy 350.981264 -221.973647) (xy 350.973158 -222.024824) (xy 350.957146 -222.074103) (xy 350.933623 -222.12027)
			(xy 350.903167 -222.162189) (xy 350.866529 -222.198827) (xy 350.82461 -222.229283) (xy 350.778443 -222.252806)
			(xy 350.729164 -222.268818) (xy 350.677987 -222.276924) (xy 350.626173 -222.276924) (xy 350.574996 -222.268818)
			(xy 350.525717 -222.252806) (xy 350.47955 -222.229283) (xy 350.437631 -222.198827) (xy 350.400993 -222.162189)
			(xy 350.370537 -222.12027) (xy 350.347014 -222.074103) (xy 350.331002 -222.024824) (xy 350.322896 -221.973647)
			(xy 350.322388 -221.94774) (xy 350.322992 -221.920023) (xy 350.332309 -221.865377) (xy 350.34093 -221.839028)
			(xy 350.348804 -221.81693) (xy 350.143826 -221.462092) (xy 350.120966 -221.457774) (xy 350.096166 -221.452574)
			(xy 350.04843 -221.435583) (xy 350.003855 -221.411489) (xy 349.963491 -221.380859) (xy 349.928289 -221.344414)
			(xy 349.899076 -221.303012) (xy 349.876542 -221.257629) (xy 349.861217 -221.209332) (xy 349.853461 -221.159259)
			(xy 349.852996 -221.133924) (xy 349.572072 -221.133924) (xy 349.571564 -221.159811) (xy 349.563465 -221.210949)
			(xy 349.547466 -221.260189) (xy 349.52396 -221.306321) (xy 349.493528 -221.348208) (xy 349.456918 -221.384818)
			(xy 349.415031 -221.41525) (xy 349.368899 -221.438756) (xy 349.319659 -221.454755) (xy 349.268521 -221.462854)
			(xy 349.216747 -221.462854) (xy 349.165609 -221.454755) (xy 349.116369 -221.438756) (xy 349.070237 -221.41525)
			(xy 349.02835 -221.384818) (xy 348.99174 -221.348208) (xy 348.961308 -221.306321) (xy 348.937802 -221.260189)
			(xy 348.921803 -221.210949) (xy 348.913704 -221.159811) (xy 348.913196 -221.133924) (xy 348.632272 -221.133924)
			(xy 348.631745 -221.161632) (xy 348.622548 -221.216279) (xy 348.613984 -221.242636) (xy 348.60611 -221.264734)
			(xy 348.811088 -221.619572) (xy 348.833948 -221.62389) (xy 348.858767 -221.629064) (xy 348.906546 -221.646018)
			(xy 348.951165 -221.670088) (xy 348.991572 -221.700708) (xy 349.026813 -221.737154) (xy 349.056057 -221.778566)
			(xy 349.078614 -221.823969) (xy 349.093952 -221.872291) (xy 349.10171 -221.922391) (xy 349.102172 -221.94774)
			(xy 349.101664 -221.973647) (xy 349.093558 -222.024824) (xy 349.077546 -222.074103) (xy 349.054023 -222.12027)
			(xy 349.023567 -222.162189) (xy 348.986929 -222.198827) (xy 348.94501 -222.229283) (xy 348.898843 -222.252806)
			(xy 348.849564 -222.268818) (xy 348.798387 -222.276924) (xy 348.746573 -222.276924) (xy 348.695396 -222.268818)
			(xy 348.646117 -222.252806) (xy 348.59995 -222.229283) (xy 348.558031 -222.198827) (xy 348.521393 -222.162189)
			(xy 348.490937 -222.12027) (xy 348.467414 -222.074103) (xy 348.451402 -222.024824) (xy 348.443296 -221.973647)
			(xy 348.442788 -221.94774) (xy 348.443392 -221.920023) (xy 348.452709 -221.865377) (xy 348.46133 -221.839028)
			(xy 348.469204 -221.81693) (xy 348.264226 -221.462092) (xy 348.241366 -221.457774) (xy 348.216566 -221.452574)
			(xy 348.16883 -221.435583) (xy 348.124255 -221.411489) (xy 348.083891 -221.380859) (xy 348.048689 -221.344414)
			(xy 348.019476 -221.303012) (xy 347.996942 -221.257629) (xy 347.981617 -221.209332) (xy 347.973861 -221.159259)
			(xy 347.973396 -221.133924) (xy 347.692472 -221.133924) (xy 347.691964 -221.159811) (xy 347.683865 -221.210949)
			(xy 347.667866 -221.260189) (xy 347.64436 -221.306321) (xy 347.613928 -221.348208) (xy 347.577318 -221.384818)
			(xy 347.535431 -221.41525) (xy 347.489299 -221.438756) (xy 347.440059 -221.454755) (xy 347.388921 -221.462854)
			(xy 347.337147 -221.462854) (xy 347.286009 -221.454755) (xy 347.236769 -221.438756) (xy 347.190637 -221.41525)
			(xy 347.14875 -221.384818) (xy 347.11214 -221.348208) (xy 347.081708 -221.306321) (xy 347.058202 -221.260189)
			(xy 347.042203 -221.210949) (xy 347.034104 -221.159811) (xy 347.033596 -221.133924) (xy 346.752672 -221.133924)
			(xy 346.752145 -221.161632) (xy 346.742948 -221.216279) (xy 346.734384 -221.242636) (xy 346.72651 -221.264734)
			(xy 346.931488 -221.619572) (xy 346.954348 -221.62389) (xy 346.979167 -221.629064) (xy 347.026946 -221.646018)
			(xy 347.071565 -221.670088) (xy 347.111972 -221.700708) (xy 347.147213 -221.737154) (xy 347.176457 -221.778566)
			(xy 347.199014 -221.823969) (xy 347.214352 -221.872291) (xy 347.22211 -221.922391) (xy 347.222572 -221.94774)
			(xy 347.222064 -221.973647) (xy 347.213958 -222.024824) (xy 347.197946 -222.074103) (xy 347.174423 -222.12027)
			(xy 347.143967 -222.162189) (xy 347.107329 -222.198827) (xy 347.06541 -222.229283) (xy 347.019243 -222.252806)
			(xy 346.969964 -222.268818) (xy 346.918787 -222.276924) (xy 346.866973 -222.276924) (xy 346.815796 -222.268818)
			(xy 346.766517 -222.252806) (xy 346.72035 -222.229283) (xy 346.678431 -222.198827) (xy 346.641793 -222.162189)
			(xy 346.611337 -222.12027) (xy 346.587814 -222.074103) (xy 346.571802 -222.024824) (xy 346.563696 -221.973647)
			(xy 346.563188 -221.94774) (xy 346.563792 -221.920023) (xy 346.573109 -221.865377) (xy 346.58173 -221.839028)
			(xy 346.589604 -221.81693) (xy 346.384626 -221.462092) (xy 346.361766 -221.457774) (xy 346.336966 -221.452574)
			(xy 346.28923 -221.435583) (xy 346.244655 -221.411489) (xy 346.204291 -221.380859) (xy 346.169089 -221.344414)
			(xy 346.139876 -221.303012) (xy 346.117342 -221.257629) (xy 346.102017 -221.209332) (xy 346.094261 -221.159259)
			(xy 346.093796 -221.133924) (xy 345.812872 -221.133924) (xy 345.812364 -221.159811) (xy 345.804265 -221.210949)
			(xy 345.788266 -221.260189) (xy 345.76476 -221.306321) (xy 345.734328 -221.348208) (xy 345.697718 -221.384818)
			(xy 345.655831 -221.41525) (xy 345.609699 -221.438756) (xy 345.560459 -221.454755) (xy 345.509321 -221.462854)
			(xy 345.457547 -221.462854) (xy 345.406409 -221.454755) (xy 345.357169 -221.438756) (xy 345.311037 -221.41525)
			(xy 345.26915 -221.384818) (xy 345.23254 -221.348208) (xy 345.202108 -221.306321) (xy 345.178602 -221.260189)
			(xy 345.162603 -221.210949) (xy 345.154504 -221.159811) (xy 345.153996 -221.133924) (xy 344.873072 -221.133924)
			(xy 344.872545 -221.161632) (xy 344.863348 -221.216279) (xy 344.854784 -221.242636) (xy 344.84691 -221.264734)
			(xy 345.051888 -221.619572) (xy 345.074748 -221.62389) (xy 345.099567 -221.629064) (xy 345.147346 -221.646018)
			(xy 345.191965 -221.670088) (xy 345.232372 -221.700708) (xy 345.267613 -221.737154) (xy 345.296857 -221.778566)
			(xy 345.319414 -221.823969) (xy 345.334752 -221.872291) (xy 345.34251 -221.922391) (xy 345.342972 -221.94774)
			(xy 345.342464 -221.973647) (xy 345.334358 -222.024824) (xy 345.318346 -222.074103) (xy 345.294823 -222.12027)
			(xy 345.264367 -222.162189) (xy 345.227729 -222.198827) (xy 345.18581 -222.229283) (xy 345.139643 -222.252806)
			(xy 345.090364 -222.268818) (xy 345.039187 -222.276924) (xy 344.987373 -222.276924) (xy 344.936196 -222.268818)
			(xy 344.886917 -222.252806) (xy 344.84075 -222.229283) (xy 344.798831 -222.198827) (xy 344.762193 -222.162189)
			(xy 344.731737 -222.12027) (xy 344.708214 -222.074103) (xy 344.692202 -222.024824) (xy 344.684096 -221.973647)
			(xy 344.683588 -221.94774) (xy 344.684192 -221.920023) (xy 344.693509 -221.865377) (xy 344.70213 -221.839028)
			(xy 344.710004 -221.81693) (xy 344.505026 -221.462092) (xy 344.482166 -221.457774) (xy 344.457366 -221.452574)
			(xy 344.40963 -221.435583) (xy 344.365055 -221.411489) (xy 344.324691 -221.380859) (xy 344.289489 -221.344414)
			(xy 344.260276 -221.303012) (xy 344.237742 -221.257629) (xy 344.222417 -221.209332) (xy 344.214661 -221.159259)
			(xy 344.214196 -221.133924) (xy 343.933272 -221.133924) (xy 343.932764 -221.159811) (xy 343.924665 -221.210949)
			(xy 343.908666 -221.260189) (xy 343.88516 -221.306321) (xy 343.854728 -221.348208) (xy 343.818118 -221.384818)
			(xy 343.776231 -221.41525) (xy 343.730099 -221.438756) (xy 343.680859 -221.454755) (xy 343.629721 -221.462854)
			(xy 343.577947 -221.462854) (xy 343.526809 -221.454755) (xy 343.477569 -221.438756) (xy 343.431437 -221.41525)
			(xy 343.38955 -221.384818) (xy 343.35294 -221.348208) (xy 343.322508 -221.306321) (xy 343.299002 -221.260189)
			(xy 343.283003 -221.210949) (xy 343.274904 -221.159811) (xy 343.274396 -221.133924) (xy 342.993472 -221.133924)
			(xy 342.992945 -221.161632) (xy 342.983748 -221.216279) (xy 342.975184 -221.242636) (xy 342.96731 -221.264734)
			(xy 343.172288 -221.619572) (xy 343.195148 -221.62389) (xy 343.219967 -221.629064) (xy 343.267746 -221.646018)
			(xy 343.312365 -221.670088) (xy 343.352772 -221.700708) (xy 343.388013 -221.737154) (xy 343.417257 -221.778566)
			(xy 343.439814 -221.823969) (xy 343.455152 -221.872291) (xy 343.46291 -221.922391) (xy 343.463372 -221.94774)
			(xy 343.462864 -221.973647) (xy 343.454758 -222.024824) (xy 343.438746 -222.074103) (xy 343.415223 -222.12027)
			(xy 343.384767 -222.162189) (xy 343.348129 -222.198827) (xy 343.30621 -222.229283) (xy 343.260043 -222.252806)
			(xy 343.210764 -222.268818) (xy 343.159587 -222.276924) (xy 343.107773 -222.276924) (xy 343.056596 -222.268818)
			(xy 343.007317 -222.252806) (xy 342.96115 -222.229283) (xy 342.919231 -222.198827) (xy 342.882593 -222.162189)
			(xy 342.852137 -222.12027) (xy 342.828614 -222.074103) (xy 342.812602 -222.024824) (xy 342.804496 -221.973647)
			(xy 342.803988 -221.94774) (xy 342.804592 -221.920023) (xy 342.813909 -221.865377) (xy 342.82253 -221.839028)
			(xy 342.830404 -221.81693) (xy 342.625426 -221.462092) (xy 342.602566 -221.457774) (xy 342.577766 -221.452574)
			(xy 342.53003 -221.435583) (xy 342.485455 -221.411489) (xy 342.445091 -221.380859) (xy 342.409889 -221.344414)
			(xy 342.380676 -221.303012) (xy 342.358142 -221.257629) (xy 342.342817 -221.209332) (xy 342.335061 -221.159259)
			(xy 342.334596 -221.133924) (xy 342.053672 -221.133924) (xy 342.053164 -221.159811) (xy 342.045065 -221.210949)
			(xy 342.029066 -221.260189) (xy 342.00556 -221.306321) (xy 341.975128 -221.348208) (xy 341.938518 -221.384818)
			(xy 341.896631 -221.41525) (xy 341.850499 -221.438756) (xy 341.801259 -221.454755) (xy 341.750121 -221.462854)
			(xy 341.698347 -221.462854) (xy 341.647209 -221.454755) (xy 341.597969 -221.438756) (xy 341.551837 -221.41525)
			(xy 341.50995 -221.384818) (xy 341.47334 -221.348208) (xy 341.442908 -221.306321) (xy 341.419402 -221.260189)
			(xy 341.403403 -221.210949) (xy 341.395304 -221.159811) (xy 341.394796 -221.133924) (xy 341.113872 -221.133924)
			(xy 341.113345 -221.161632) (xy 341.104148 -221.216279) (xy 341.095584 -221.242636) (xy 341.08771 -221.264734)
			(xy 341.292688 -221.619572) (xy 341.315548 -221.62389) (xy 341.340367 -221.629064) (xy 341.388146 -221.646018)
			(xy 341.432765 -221.670088) (xy 341.473172 -221.700708) (xy 341.508413 -221.737154) (xy 341.537657 -221.778566)
			(xy 341.560214 -221.823969) (xy 341.575552 -221.872291) (xy 341.58331 -221.922391) (xy 341.583772 -221.94774)
			(xy 341.583264 -221.973647) (xy 341.575158 -222.024824) (xy 341.559146 -222.074103) (xy 341.535623 -222.12027)
			(xy 341.505167 -222.162189) (xy 341.468529 -222.198827) (xy 341.42661 -222.229283) (xy 341.380443 -222.252806)
			(xy 341.331164 -222.268818) (xy 341.279987 -222.276924) (xy 341.228173 -222.276924) (xy 341.176996 -222.268818)
			(xy 341.127717 -222.252806) (xy 341.08155 -222.229283) (xy 341.039631 -222.198827) (xy 341.002993 -222.162189)
			(xy 340.972537 -222.12027) (xy 340.949014 -222.074103) (xy 340.933002 -222.024824) (xy 340.924896 -221.973647)
			(xy 340.924388 -221.94774) (xy 340.924992 -221.920023) (xy 340.934309 -221.865377) (xy 340.94293 -221.839028)
			(xy 340.950804 -221.81693) (xy 340.745826 -221.462092) (xy 340.722966 -221.457774) (xy 340.698166 -221.452574)
			(xy 340.65043 -221.435583) (xy 340.605855 -221.411489) (xy 340.565491 -221.380859) (xy 340.530289 -221.344414)
			(xy 340.501076 -221.303012) (xy 340.478542 -221.257629) (xy 340.463217 -221.209332) (xy 340.455461 -221.159259)
			(xy 340.454996 -221.133924) (xy 340.174072 -221.133924) (xy 340.173564 -221.159811) (xy 340.165465 -221.210949)
			(xy 340.149466 -221.260189) (xy 340.12596 -221.306321) (xy 340.095528 -221.348208) (xy 340.058918 -221.384818)
			(xy 340.017031 -221.41525) (xy 339.970899 -221.438756) (xy 339.921659 -221.454755) (xy 339.870521 -221.462854)
			(xy 339.818747 -221.462854) (xy 339.767609 -221.454755) (xy 339.718369 -221.438756) (xy 339.672237 -221.41525)
			(xy 339.63035 -221.384818) (xy 339.59374 -221.348208) (xy 339.563308 -221.306321) (xy 339.539802 -221.260189)
			(xy 339.523803 -221.210949) (xy 339.515704 -221.159811) (xy 339.515196 -221.133924) (xy 339.234272 -221.133924)
			(xy 339.233745 -221.161632) (xy 339.224548 -221.216279) (xy 339.215984 -221.242636) (xy 339.20811 -221.264734)
			(xy 339.413088 -221.619572) (xy 339.435948 -221.62389) (xy 339.460767 -221.629064) (xy 339.508546 -221.646018)
			(xy 339.553165 -221.670088) (xy 339.593572 -221.700708) (xy 339.628813 -221.737154) (xy 339.658057 -221.778566)
			(xy 339.680614 -221.823969) (xy 339.695952 -221.872291) (xy 339.70371 -221.922391) (xy 339.704172 -221.94774)
			(xy 339.703664 -221.973647) (xy 339.695558 -222.024824) (xy 339.679546 -222.074103) (xy 339.656023 -222.12027)
			(xy 339.625567 -222.162189) (xy 339.588929 -222.198827) (xy 339.54701 -222.229283) (xy 339.500843 -222.252806)
			(xy 339.451564 -222.268818) (xy 339.400387 -222.276924) (xy 339.348573 -222.276924) (xy 339.297396 -222.268818)
			(xy 339.248117 -222.252806) (xy 339.20195 -222.229283) (xy 339.160031 -222.198827) (xy 339.123393 -222.162189)
			(xy 339.092937 -222.12027) (xy 339.069414 -222.074103) (xy 339.053402 -222.024824) (xy 339.045296 -221.973647)
			(xy 339.044788 -221.94774) (xy 339.045392 -221.920023) (xy 339.054709 -221.865377) (xy 339.06333 -221.839028)
			(xy 339.071204 -221.81693) (xy 338.866226 -221.462092) (xy 338.843366 -221.457774) (xy 338.818566 -221.452574)
			(xy 338.77083 -221.435583) (xy 338.726255 -221.411489) (xy 338.685891 -221.380859) (xy 338.650689 -221.344414)
			(xy 338.621476 -221.303012) (xy 338.598942 -221.257629) (xy 338.583617 -221.209332) (xy 338.575861 -221.159259)
			(xy 338.575396 -221.133924) (xy 338.294472 -221.133924) (xy 338.293964 -221.159811) (xy 338.285865 -221.210949)
			(xy 338.269866 -221.260189) (xy 338.24636 -221.306321) (xy 338.215928 -221.348208) (xy 338.179318 -221.384818)
			(xy 338.137431 -221.41525) (xy 338.091299 -221.438756) (xy 338.042059 -221.454755) (xy 337.990921 -221.462854)
			(xy 337.939147 -221.462854) (xy 337.888009 -221.454755) (xy 337.838769 -221.438756) (xy 337.792637 -221.41525)
			(xy 337.75075 -221.384818) (xy 337.71414 -221.348208) (xy 337.683708 -221.306321) (xy 337.660202 -221.260189)
			(xy 337.644203 -221.210949) (xy 337.636104 -221.159811) (xy 337.635596 -221.133924) (xy 337.354672 -221.133924)
			(xy 337.354145 -221.161632) (xy 337.344948 -221.216279) (xy 337.336384 -221.242636) (xy 337.32851 -221.264734)
			(xy 337.533488 -221.619572) (xy 337.556348 -221.62389) (xy 337.581167 -221.629064) (xy 337.628946 -221.646018)
			(xy 337.673565 -221.670088) (xy 337.713972 -221.700708) (xy 337.749213 -221.737154) (xy 337.778457 -221.778566)
			(xy 337.801014 -221.823969) (xy 337.816352 -221.872291) (xy 337.82411 -221.922391) (xy 337.824572 -221.94774)
			(xy 337.824064 -221.973647) (xy 337.815958 -222.024824) (xy 337.799946 -222.074103) (xy 337.776423 -222.12027)
			(xy 337.745967 -222.162189) (xy 337.709329 -222.198827) (xy 337.66741 -222.229283) (xy 337.621243 -222.252806)
			(xy 337.571964 -222.268818) (xy 337.520787 -222.276924) (xy 337.468973 -222.276924) (xy 337.417796 -222.268818)
			(xy 337.368517 -222.252806) (xy 337.32235 -222.229283) (xy 337.280431 -222.198827) (xy 337.243793 -222.162189)
			(xy 337.213337 -222.12027) (xy 337.189814 -222.074103) (xy 337.173802 -222.024824) (xy 337.165696 -221.973647)
			(xy 337.165188 -221.94774) (xy 337.165792 -221.920023) (xy 337.175109 -221.865377) (xy 337.18373 -221.839028)
			(xy 337.191604 -221.81693) (xy 336.986626 -221.462092) (xy 336.963766 -221.457774) (xy 336.938966 -221.452574)
			(xy 336.89123 -221.435583) (xy 336.846655 -221.411489) (xy 336.806291 -221.380859) (xy 336.771089 -221.344414)
			(xy 336.741876 -221.303012) (xy 336.719342 -221.257629) (xy 336.704017 -221.209332) (xy 336.696261 -221.159259)
			(xy 336.695796 -221.133924) (xy 134.525004 -221.133924) (xy 134.524496 -221.159811) (xy 134.516397 -221.210949)
			(xy 134.500398 -221.260189) (xy 134.476892 -221.306321) (xy 134.44646 -221.348208) (xy 134.40985 -221.384818)
			(xy 134.367963 -221.41525) (xy 134.321831 -221.438756) (xy 134.272591 -221.454755) (xy 134.221453 -221.462854)
			(xy 134.169679 -221.462854) (xy 134.118541 -221.454755) (xy 134.069301 -221.438756) (xy 134.023169 -221.41525)
			(xy 133.981282 -221.384818) (xy 133.944672 -221.348208) (xy 133.91424 -221.306321) (xy 133.890734 -221.260189)
			(xy 133.874735 -221.210949) (xy 133.866636 -221.159811) (xy 133.866128 -221.133924) (xy 133.866667 -221.106216)
			(xy 133.875856 -221.05157) (xy 133.884416 -221.025212) (xy 133.89229 -221.003114) (xy 133.687312 -220.648022)
			(xy 133.664452 -220.643704) (xy 133.639631 -220.638536) (xy 133.591852 -220.621582) (xy 133.547233 -220.59751)
			(xy 133.506826 -220.56689) (xy 133.471585 -220.530444) (xy 133.442341 -220.48903) (xy 133.419784 -220.443627)
			(xy 133.404447 -220.395304) (xy 133.39669 -220.345203) (xy 133.396228 -220.319854) (xy 132.175504 -220.319854)
			(xy 132.174894 -220.347507) (xy 132.165571 -220.402025) (xy 132.156962 -220.428312) (xy 132.149342 -220.45041)
			(xy 132.354574 -220.805756) (xy 132.377434 -220.810074) (xy 132.402245 -220.815229) (xy 132.449984 -220.832223)
			(xy 132.494562 -220.856322) (xy 132.534927 -220.886957) (xy 132.57013 -220.923408) (xy 132.59934 -220.964816)
			(xy 132.621872 -221.010206) (xy 132.637192 -221.058509) (xy 132.644942 -221.108587) (xy 132.645404 -221.133924)
			(xy 132.644896 -221.159811) (xy 132.636797 -221.210949) (xy 132.620798 -221.260189) (xy 132.597292 -221.306321)
			(xy 132.56686 -221.348208) (xy 132.53025 -221.384818) (xy 132.488363 -221.41525) (xy 132.442231 -221.438756)
			(xy 132.392991 -221.454755) (xy 132.341853 -221.462854) (xy 132.290079 -221.462854) (xy 132.238941 -221.454755)
			(xy 132.189701 -221.438756) (xy 132.143569 -221.41525) (xy 132.101682 -221.384818) (xy 132.065072 -221.348208)
			(xy 132.03464 -221.306321) (xy 132.011134 -221.260189) (xy 131.995135 -221.210949) (xy 131.987036 -221.159811)
			(xy 131.986528 -221.133924) (xy 131.987067 -221.106216) (xy 131.996256 -221.05157) (xy 132.004816 -221.025212)
			(xy 132.01269 -221.003114) (xy 131.807712 -220.648022) (xy 131.784852 -220.643704) (xy 131.76 -220.63857)
			(xy 131.712153 -220.621668) (xy 131.667462 -220.597632) (xy 131.626984 -220.567029) (xy 131.591674 -220.530584)
			(xy 131.562368 -220.489157) (xy 131.539757 -220.443728) (xy 131.524377 -220.39537) (xy 131.516591 -220.345226)
			(xy 131.51612 -220.319854) (xy 130.295904 -220.319854) (xy 130.295294 -220.347507) (xy 130.285971 -220.402025)
			(xy 130.277362 -220.428312) (xy 130.269742 -220.45041) (xy 130.474974 -220.805756) (xy 130.497834 -220.810074)
			(xy 130.522645 -220.815229) (xy 130.570384 -220.832223) (xy 130.614962 -220.856322) (xy 130.655327 -220.886957)
			(xy 130.69053 -220.923408) (xy 130.71974 -220.964816) (xy 130.742272 -221.010206) (xy 130.757592 -221.058509)
			(xy 130.765342 -221.108587) (xy 130.765804 -221.133924) (xy 130.765296 -221.159811) (xy 130.757197 -221.210949)
			(xy 130.741198 -221.260189) (xy 130.717692 -221.306321) (xy 130.68726 -221.348208) (xy 130.65065 -221.384818)
			(xy 130.608763 -221.41525) (xy 130.562631 -221.438756) (xy 130.513391 -221.454755) (xy 130.462253 -221.462854)
			(xy 130.410479 -221.462854) (xy 130.359341 -221.454755) (xy 130.310101 -221.438756) (xy 130.263969 -221.41525)
			(xy 130.222082 -221.384818) (xy 130.185472 -221.348208) (xy 130.15504 -221.306321) (xy 130.131534 -221.260189)
			(xy 130.115535 -221.210949) (xy 130.107436 -221.159811) (xy 130.106928 -221.133924) (xy 130.107467 -221.106216)
			(xy 130.116656 -221.05157) (xy 130.125216 -221.025212) (xy 130.13309 -221.003114) (xy 129.928112 -220.648022)
			(xy 129.905252 -220.643704) (xy 129.8804 -220.63857) (xy 129.832553 -220.621668) (xy 129.787862 -220.597632)
			(xy 129.747384 -220.567029) (xy 129.712074 -220.530584) (xy 129.682768 -220.489157) (xy 129.660157 -220.443728)
			(xy 129.644777 -220.39537) (xy 129.636991 -220.345226) (xy 129.63652 -220.319854) (xy 128.416304 -220.319854)
			(xy 128.415694 -220.347507) (xy 128.406371 -220.402025) (xy 128.397762 -220.428312) (xy 128.390142 -220.45041)
			(xy 128.595374 -220.805756) (xy 128.618234 -220.810074) (xy 128.643045 -220.815229) (xy 128.690784 -220.832223)
			(xy 128.735362 -220.856322) (xy 128.775727 -220.886957) (xy 128.81093 -220.923408) (xy 128.84014 -220.964816)
			(xy 128.862672 -221.010206) (xy 128.877992 -221.058509) (xy 128.885742 -221.108587) (xy 128.886204 -221.133924)
			(xy 128.885696 -221.159811) (xy 128.877597 -221.210949) (xy 128.861598 -221.260189) (xy 128.838092 -221.306321)
			(xy 128.80766 -221.348208) (xy 128.77105 -221.384818) (xy 128.729163 -221.41525) (xy 128.683031 -221.438756)
			(xy 128.633791 -221.454755) (xy 128.582653 -221.462854) (xy 128.530879 -221.462854) (xy 128.479741 -221.454755)
			(xy 128.430501 -221.438756) (xy 128.384369 -221.41525) (xy 128.342482 -221.384818) (xy 128.305872 -221.348208)
			(xy 128.27544 -221.306321) (xy 128.251934 -221.260189) (xy 128.235935 -221.210949) (xy 128.227836 -221.159811)
			(xy 128.227328 -221.133924) (xy 128.227867 -221.106216) (xy 128.237056 -221.05157) (xy 128.245616 -221.025212)
			(xy 128.25349 -221.003114) (xy 128.048512 -220.648022) (xy 128.025652 -220.643704) (xy 128.0008 -220.63857)
			(xy 127.952953 -220.621668) (xy 127.908262 -220.597632) (xy 127.867784 -220.567029) (xy 127.832474 -220.530584)
			(xy 127.803168 -220.489157) (xy 127.780557 -220.443728) (xy 127.765177 -220.39537) (xy 127.757391 -220.345226)
			(xy 127.75692 -220.319854) (xy 126.536704 -220.319854) (xy 126.536094 -220.347507) (xy 126.526771 -220.402025)
			(xy 126.518162 -220.428312) (xy 126.510542 -220.45041) (xy 126.715774 -220.805756) (xy 126.738634 -220.810074)
			(xy 126.763445 -220.815229) (xy 126.811184 -220.832223) (xy 126.855762 -220.856322) (xy 126.896127 -220.886957)
			(xy 126.93133 -220.923408) (xy 126.96054 -220.964816) (xy 126.983072 -221.010206) (xy 126.998392 -221.058509)
			(xy 127.006142 -221.108587) (xy 127.006604 -221.133924) (xy 127.006096 -221.159811) (xy 126.997997 -221.210949)
			(xy 126.981998 -221.260189) (xy 126.958492 -221.306321) (xy 126.92806 -221.348208) (xy 126.89145 -221.384818)
			(xy 126.849563 -221.41525) (xy 126.803431 -221.438756) (xy 126.754191 -221.454755) (xy 126.703053 -221.462854)
			(xy 126.651279 -221.462854) (xy 126.600141 -221.454755) (xy 126.550901 -221.438756) (xy 126.504769 -221.41525)
			(xy 126.462882 -221.384818) (xy 126.426272 -221.348208) (xy 126.39584 -221.306321) (xy 126.372334 -221.260189)
			(xy 126.356335 -221.210949) (xy 126.348236 -221.159811) (xy 126.347728 -221.133924) (xy 126.348267 -221.106216)
			(xy 126.357456 -221.05157) (xy 126.366016 -221.025212) (xy 126.37389 -221.003114) (xy 126.168912 -220.648022)
			(xy 126.146052 -220.643704) (xy 126.1212 -220.63857) (xy 126.073353 -220.621668) (xy 126.028662 -220.597632)
			(xy 125.988184 -220.567029) (xy 125.952874 -220.530584) (xy 125.923568 -220.489157) (xy 125.900957 -220.443728)
			(xy 125.885577 -220.39537) (xy 125.877791 -220.345226) (xy 125.87732 -220.319854) (xy 124.657104 -220.319854)
			(xy 124.656494 -220.347507) (xy 124.647171 -220.402025) (xy 124.638562 -220.428312) (xy 124.630942 -220.45041)
			(xy 124.836174 -220.805756) (xy 124.859034 -220.810074) (xy 124.883845 -220.815229) (xy 124.931584 -220.832223)
			(xy 124.976162 -220.856322) (xy 125.016527 -220.886957) (xy 125.05173 -220.923408) (xy 125.08094 -220.964816)
			(xy 125.103472 -221.010206) (xy 125.118792 -221.058509) (xy 125.126542 -221.108587) (xy 125.127004 -221.133924)
			(xy 125.126496 -221.159811) (xy 125.118397 -221.210949) (xy 125.102398 -221.260189) (xy 125.078892 -221.306321)
			(xy 125.04846 -221.348208) (xy 125.01185 -221.384818) (xy 124.969963 -221.41525) (xy 124.923831 -221.438756)
			(xy 124.874591 -221.454755) (xy 124.823453 -221.462854) (xy 124.771679 -221.462854) (xy 124.720541 -221.454755)
			(xy 124.671301 -221.438756) (xy 124.625169 -221.41525) (xy 124.583282 -221.384818) (xy 124.546672 -221.348208)
			(xy 124.51624 -221.306321) (xy 124.492734 -221.260189) (xy 124.476735 -221.210949) (xy 124.468636 -221.159811)
			(xy 124.468128 -221.133924) (xy 124.468667 -221.106216) (xy 124.477856 -221.05157) (xy 124.486416 -221.025212)
			(xy 124.49429 -221.003114) (xy 124.289312 -220.648022) (xy 124.266452 -220.643704) (xy 124.2416 -220.63857)
			(xy 124.193753 -220.621668) (xy 124.149062 -220.597632) (xy 124.108584 -220.567029) (xy 124.073274 -220.530584)
			(xy 124.043968 -220.489157) (xy 124.021357 -220.443728) (xy 124.005977 -220.39537) (xy 123.998191 -220.345226)
			(xy 123.99772 -220.319854) (xy 122.777504 -220.319854) (xy 122.776894 -220.347507) (xy 122.767571 -220.402025)
			(xy 122.758962 -220.428312) (xy 122.751342 -220.45041) (xy 122.956574 -220.805756) (xy 122.979434 -220.810074)
			(xy 123.004245 -220.815229) (xy 123.051984 -220.832223) (xy 123.096562 -220.856322) (xy 123.136927 -220.886957)
			(xy 123.17213 -220.923408) (xy 123.20134 -220.964816) (xy 123.223872 -221.010206) (xy 123.239192 -221.058509)
			(xy 123.246942 -221.108587) (xy 123.247404 -221.133924) (xy 123.246896 -221.159811) (xy 123.238797 -221.210949)
			(xy 123.222798 -221.260189) (xy 123.199292 -221.306321) (xy 123.16886 -221.348208) (xy 123.13225 -221.384818)
			(xy 123.090363 -221.41525) (xy 123.044231 -221.438756) (xy 122.994991 -221.454755) (xy 122.943853 -221.462854)
			(xy 122.892079 -221.462854) (xy 122.840941 -221.454755) (xy 122.791701 -221.438756) (xy 122.745569 -221.41525)
			(xy 122.703682 -221.384818) (xy 122.667072 -221.348208) (xy 122.63664 -221.306321) (xy 122.613134 -221.260189)
			(xy 122.597135 -221.210949) (xy 122.589036 -221.159811) (xy 122.588528 -221.133924) (xy 122.589067 -221.106216)
			(xy 122.598256 -221.05157) (xy 122.606816 -221.025212) (xy 122.61469 -221.003114) (xy 122.409712 -220.648022)
			(xy 122.386852 -220.643704) (xy 122.362 -220.63857) (xy 122.314153 -220.621668) (xy 122.269462 -220.597632)
			(xy 122.228984 -220.567029) (xy 122.193674 -220.530584) (xy 122.164368 -220.489157) (xy 122.141757 -220.443728)
			(xy 122.126377 -220.39537) (xy 122.118591 -220.345226) (xy 122.11812 -220.319854) (xy 120.897904 -220.319854)
			(xy 120.897294 -220.347507) (xy 120.887971 -220.402025) (xy 120.879362 -220.428312) (xy 120.871742 -220.45041)
			(xy 121.076974 -220.805756) (xy 121.099834 -220.810074) (xy 121.124645 -220.815229) (xy 121.172384 -220.832223)
			(xy 121.216962 -220.856322) (xy 121.257327 -220.886957) (xy 121.29253 -220.923408) (xy 121.32174 -220.964816)
			(xy 121.344272 -221.010206) (xy 121.359592 -221.058509) (xy 121.367342 -221.108587) (xy 121.367804 -221.133924)
			(xy 121.367296 -221.159811) (xy 121.359197 -221.210949) (xy 121.343198 -221.260189) (xy 121.319692 -221.306321)
			(xy 121.28926 -221.348208) (xy 121.25265 -221.384818) (xy 121.210763 -221.41525) (xy 121.164631 -221.438756)
			(xy 121.115391 -221.454755) (xy 121.064253 -221.462854) (xy 121.012479 -221.462854) (xy 120.961341 -221.454755)
			(xy 120.912101 -221.438756) (xy 120.865969 -221.41525) (xy 120.824082 -221.384818) (xy 120.787472 -221.348208)
			(xy 120.75704 -221.306321) (xy 120.733534 -221.260189) (xy 120.717535 -221.210949) (xy 120.709436 -221.159811)
			(xy 120.708928 -221.133924) (xy 120.709467 -221.106216) (xy 120.718656 -221.05157) (xy 120.727216 -221.025212)
			(xy 120.73509 -221.003114) (xy 120.530112 -220.648022) (xy 120.507252 -220.643704) (xy 120.4824 -220.63857)
			(xy 120.434553 -220.621668) (xy 120.389862 -220.597632) (xy 120.349384 -220.567029) (xy 120.314074 -220.530584)
			(xy 120.284768 -220.489157) (xy 120.262157 -220.443728) (xy 120.246777 -220.39537) (xy 120.238991 -220.345226)
			(xy 120.23852 -220.319854) (xy 119.018304 -220.319854) (xy 119.017694 -220.347507) (xy 119.008371 -220.402025)
			(xy 118.999762 -220.428312) (xy 118.992142 -220.45041) (xy 119.197374 -220.805756) (xy 119.220234 -220.810074)
			(xy 119.245045 -220.815229) (xy 119.292784 -220.832223) (xy 119.337362 -220.856322) (xy 119.377727 -220.886957)
			(xy 119.41293 -220.923408) (xy 119.44214 -220.964816) (xy 119.464672 -221.010206) (xy 119.479992 -221.058509)
			(xy 119.487742 -221.108587) (xy 119.488204 -221.133924) (xy 119.487696 -221.159811) (xy 119.479597 -221.210949)
			(xy 119.463598 -221.260189) (xy 119.440092 -221.306321) (xy 119.40966 -221.348208) (xy 119.37305 -221.384818)
			(xy 119.331163 -221.41525) (xy 119.285031 -221.438756) (xy 119.235791 -221.454755) (xy 119.184653 -221.462854)
			(xy 119.132879 -221.462854) (xy 119.081741 -221.454755) (xy 119.032501 -221.438756) (xy 118.986369 -221.41525)
			(xy 118.944482 -221.384818) (xy 118.907872 -221.348208) (xy 118.87744 -221.306321) (xy 118.853934 -221.260189)
			(xy 118.837935 -221.210949) (xy 118.829836 -221.159811) (xy 118.829328 -221.133924) (xy 118.829867 -221.106216)
			(xy 118.839056 -221.05157) (xy 118.847616 -221.025212) (xy 118.85549 -221.003114) (xy 118.650512 -220.648022)
			(xy 118.627652 -220.643704) (xy 118.6028 -220.63857) (xy 118.554953 -220.621668) (xy 118.510262 -220.597632)
			(xy 118.469784 -220.567029) (xy 118.434474 -220.530584) (xy 118.405168 -220.489157) (xy 118.382557 -220.443728)
			(xy 118.367177 -220.39537) (xy 118.359391 -220.345226) (xy 118.35892 -220.319854) (xy 117.138704 -220.319854)
			(xy 117.138094 -220.347507) (xy 117.128771 -220.402025) (xy 117.120162 -220.428312) (xy 117.112542 -220.45041)
			(xy 117.317774 -220.805756) (xy 117.340634 -220.810074) (xy 117.365445 -220.815229) (xy 117.413184 -220.832223)
			(xy 117.457762 -220.856322) (xy 117.498127 -220.886957) (xy 117.53333 -220.923408) (xy 117.56254 -220.964816)
			(xy 117.585072 -221.010206) (xy 117.600392 -221.058509) (xy 117.608142 -221.108587) (xy 117.608604 -221.133924)
			(xy 117.608096 -221.159811) (xy 117.599997 -221.210949) (xy 117.583998 -221.260189) (xy 117.560492 -221.306321)
			(xy 117.53006 -221.348208) (xy 117.49345 -221.384818) (xy 117.451563 -221.41525) (xy 117.405431 -221.438756)
			(xy 117.356191 -221.454755) (xy 117.305053 -221.462854) (xy 117.253279 -221.462854) (xy 117.202141 -221.454755)
			(xy 117.152901 -221.438756) (xy 117.106769 -221.41525) (xy 117.064882 -221.384818) (xy 117.028272 -221.348208)
			(xy 116.99784 -221.306321) (xy 116.974334 -221.260189) (xy 116.958335 -221.210949) (xy 116.950236 -221.159811)
			(xy 116.949728 -221.133924) (xy 116.950267 -221.106216) (xy 116.959456 -221.05157) (xy 116.968016 -221.025212)
			(xy 116.97589 -221.003114) (xy 116.770912 -220.648022) (xy 116.748052 -220.643704) (xy 116.7232 -220.63857)
			(xy 116.675353 -220.621668) (xy 116.630662 -220.597632) (xy 116.590184 -220.567029) (xy 116.554874 -220.530584)
			(xy 116.525568 -220.489157) (xy 116.502957 -220.443728) (xy 116.487577 -220.39537) (xy 116.479791 -220.345226)
			(xy 116.47932 -220.319854) (xy 115.259104 -220.319854) (xy 115.258494 -220.347507) (xy 115.249171 -220.402025)
			(xy 115.240562 -220.428312) (xy 115.232942 -220.45041) (xy 115.438174 -220.805756) (xy 115.461034 -220.810074)
			(xy 115.485845 -220.815229) (xy 115.533584 -220.832223) (xy 115.578162 -220.856322) (xy 115.618527 -220.886957)
			(xy 115.65373 -220.923408) (xy 115.68294 -220.964816) (xy 115.705472 -221.010206) (xy 115.720792 -221.058509)
			(xy 115.728542 -221.108587) (xy 115.729004 -221.133924) (xy 115.728496 -221.159811) (xy 115.720397 -221.210949)
			(xy 115.704398 -221.260189) (xy 115.680892 -221.306321) (xy 115.65046 -221.348208) (xy 115.61385 -221.384818)
			(xy 115.571963 -221.41525) (xy 115.525831 -221.438756) (xy 115.476591 -221.454755) (xy 115.425453 -221.462854)
			(xy 115.373679 -221.462854) (xy 115.322541 -221.454755) (xy 115.273301 -221.438756) (xy 115.227169 -221.41525)
			(xy 115.185282 -221.384818) (xy 115.148672 -221.348208) (xy 115.11824 -221.306321) (xy 115.094734 -221.260189)
			(xy 115.078735 -221.210949) (xy 115.070636 -221.159811) (xy 115.070128 -221.133924) (xy 115.070667 -221.106216)
			(xy 115.079856 -221.05157) (xy 115.088416 -221.025212) (xy 115.09629 -221.003114) (xy 114.891312 -220.648022)
			(xy 114.868452 -220.643704) (xy 114.8436 -220.63857) (xy 114.795753 -220.621668) (xy 114.751062 -220.597632)
			(xy 114.710584 -220.567029) (xy 114.675274 -220.530584) (xy 114.645968 -220.489157) (xy 114.623357 -220.443728)
			(xy 114.607977 -220.39537) (xy 114.600191 -220.345226) (xy 114.59972 -220.319854) (xy 113.379504 -220.319854)
			(xy 113.378894 -220.347507) (xy 113.369571 -220.402025) (xy 113.360962 -220.428312) (xy 113.353342 -220.45041)
			(xy 113.558574 -220.805756) (xy 113.581434 -220.810074) (xy 113.606245 -220.815229) (xy 113.653984 -220.832223)
			(xy 113.698562 -220.856322) (xy 113.738927 -220.886957) (xy 113.77413 -220.923408) (xy 113.80334 -220.964816)
			(xy 113.825872 -221.010206) (xy 113.841192 -221.058509) (xy 113.848942 -221.108587) (xy 113.849404 -221.133924)
			(xy 113.848896 -221.159811) (xy 113.840797 -221.210949) (xy 113.824798 -221.260189) (xy 113.801292 -221.306321)
			(xy 113.77086 -221.348208) (xy 113.73425 -221.384818) (xy 113.692363 -221.41525) (xy 113.646231 -221.438756)
			(xy 113.596991 -221.454755) (xy 113.545853 -221.462854) (xy 113.494079 -221.462854) (xy 113.442941 -221.454755)
			(xy 113.393701 -221.438756) (xy 113.347569 -221.41525) (xy 113.305682 -221.384818) (xy 113.269072 -221.348208)
			(xy 113.23864 -221.306321) (xy 113.215134 -221.260189) (xy 113.199135 -221.210949) (xy 113.191036 -221.159811)
			(xy 113.190528 -221.133924) (xy 113.191067 -221.106216) (xy 113.200256 -221.05157) (xy 113.208816 -221.025212)
			(xy 113.21669 -221.003114) (xy 113.011712 -220.648022) (xy 112.988852 -220.643704) (xy 112.964 -220.63857)
			(xy 112.916153 -220.621668) (xy 112.871462 -220.597632) (xy 112.830984 -220.567029) (xy 112.795674 -220.530584)
			(xy 112.766368 -220.489157) (xy 112.743757 -220.443728) (xy 112.728377 -220.39537) (xy 112.720591 -220.345226)
			(xy 112.72012 -220.319854) (xy 111.499904 -220.319854) (xy 111.499294 -220.347507) (xy 111.489971 -220.402025)
			(xy 111.481362 -220.428312) (xy 111.473742 -220.45041) (xy 111.678974 -220.805756) (xy 111.701834 -220.810074)
			(xy 111.726645 -220.815229) (xy 111.774384 -220.832223) (xy 111.818962 -220.856322) (xy 111.859327 -220.886957)
			(xy 111.89453 -220.923408) (xy 111.92374 -220.964816) (xy 111.946272 -221.010206) (xy 111.961592 -221.058509)
			(xy 111.969342 -221.108587) (xy 111.969804 -221.133924) (xy 111.969296 -221.159811) (xy 111.961197 -221.210949)
			(xy 111.945198 -221.260189) (xy 111.921692 -221.306321) (xy 111.89126 -221.348208) (xy 111.85465 -221.384818)
			(xy 111.812763 -221.41525) (xy 111.766631 -221.438756) (xy 111.717391 -221.454755) (xy 111.666253 -221.462854)
			(xy 111.614479 -221.462854) (xy 111.563341 -221.454755) (xy 111.514101 -221.438756) (xy 111.467969 -221.41525)
			(xy 111.426082 -221.384818) (xy 111.389472 -221.348208) (xy 111.35904 -221.306321) (xy 111.335534 -221.260189)
			(xy 111.319535 -221.210949) (xy 111.311436 -221.159811) (xy 111.310928 -221.133924) (xy 111.311467 -221.106216)
			(xy 111.320656 -221.05157) (xy 111.329216 -221.025212) (xy 111.33709 -221.003114) (xy 111.132112 -220.648022)
			(xy 111.109252 -220.643704) (xy 111.0844 -220.63857) (xy 111.036553 -220.621668) (xy 110.991862 -220.597632)
			(xy 110.951384 -220.567029) (xy 110.916074 -220.530584) (xy 110.886768 -220.489157) (xy 110.864157 -220.443728)
			(xy 110.848777 -220.39537) (xy 110.840991 -220.345226) (xy 110.84052 -220.319854) (xy 109.620304 -220.319854)
			(xy 109.619694 -220.347507) (xy 109.610371 -220.402025) (xy 109.601762 -220.428312) (xy 109.594142 -220.45041)
			(xy 109.799374 -220.805756) (xy 109.822234 -220.810074) (xy 109.847045 -220.815229) (xy 109.894784 -220.832223)
			(xy 109.939362 -220.856322) (xy 109.979727 -220.886957) (xy 110.01493 -220.923408) (xy 110.04414 -220.964816)
			(xy 110.066672 -221.010206) (xy 110.081992 -221.058509) (xy 110.089742 -221.108587) (xy 110.090204 -221.133924)
			(xy 110.089696 -221.159811) (xy 110.081597 -221.210949) (xy 110.065598 -221.260189) (xy 110.042092 -221.306321)
			(xy 110.01166 -221.348208) (xy 109.97505 -221.384818) (xy 109.933163 -221.41525) (xy 109.887031 -221.438756)
			(xy 109.837791 -221.454755) (xy 109.786653 -221.462854) (xy 109.734879 -221.462854) (xy 109.683741 -221.454755)
			(xy 109.634501 -221.438756) (xy 109.588369 -221.41525) (xy 109.546482 -221.384818) (xy 109.509872 -221.348208)
			(xy 109.47944 -221.306321) (xy 109.455934 -221.260189) (xy 109.439935 -221.210949) (xy 109.431836 -221.159811)
			(xy 109.431328 -221.133924) (xy 109.431867 -221.106216) (xy 109.441056 -221.05157) (xy 109.449616 -221.025212)
			(xy 109.45749 -221.003114) (xy 109.252512 -220.648022) (xy 109.229652 -220.643704) (xy 109.2048 -220.63857)
			(xy 109.156953 -220.621668) (xy 109.112262 -220.597632) (xy 109.071784 -220.567029) (xy 109.036474 -220.530584)
			(xy 109.007168 -220.489157) (xy 108.984557 -220.443728) (xy 108.969177 -220.39537) (xy 108.961391 -220.345226)
			(xy 108.96092 -220.319854) (xy 107.740704 -220.319854) (xy 107.740094 -220.347507) (xy 107.730771 -220.402025)
			(xy 107.722162 -220.428312) (xy 107.714542 -220.45041) (xy 107.919774 -220.805756) (xy 107.942634 -220.810074)
			(xy 107.967445 -220.815229) (xy 108.015184 -220.832223) (xy 108.059762 -220.856322) (xy 108.100127 -220.886957)
			(xy 108.13533 -220.923408) (xy 108.16454 -220.964816) (xy 108.187072 -221.010206) (xy 108.202392 -221.058509)
			(xy 108.210142 -221.108587) (xy 108.210604 -221.133924) (xy 108.210096 -221.159811) (xy 108.201997 -221.210949)
			(xy 108.185998 -221.260189) (xy 108.162492 -221.306321) (xy 108.13206 -221.348208) (xy 108.09545 -221.384818)
			(xy 108.053563 -221.41525) (xy 108.007431 -221.438756) (xy 107.958191 -221.454755) (xy 107.907053 -221.462854)
			(xy 107.855279 -221.462854) (xy 107.804141 -221.454755) (xy 107.754901 -221.438756) (xy 107.708769 -221.41525)
			(xy 107.666882 -221.384818) (xy 107.630272 -221.348208) (xy 107.59984 -221.306321) (xy 107.576334 -221.260189)
			(xy 107.560335 -221.210949) (xy 107.552236 -221.159811) (xy 107.551728 -221.133924) (xy 107.552267 -221.106216)
			(xy 107.561456 -221.05157) (xy 107.570016 -221.025212) (xy 107.57789 -221.003114) (xy 107.372912 -220.648022)
			(xy 107.350052 -220.643704) (xy 107.3252 -220.63857) (xy 107.277353 -220.621668) (xy 107.232662 -220.597632)
			(xy 107.192184 -220.567029) (xy 107.156874 -220.530584) (xy 107.127568 -220.489157) (xy 107.104957 -220.443728)
			(xy 107.089577 -220.39537) (xy 107.081791 -220.345226) (xy 107.08132 -220.319854) (xy 105.861104 -220.319854)
			(xy 105.860494 -220.347507) (xy 105.851171 -220.402025) (xy 105.842562 -220.428312) (xy 105.834942 -220.45041)
			(xy 106.040174 -220.805756) (xy 106.063034 -220.810074) (xy 106.087845 -220.815229) (xy 106.135584 -220.832223)
			(xy 106.180162 -220.856322) (xy 106.220527 -220.886957) (xy 106.25573 -220.923408) (xy 106.28494 -220.964816)
			(xy 106.307472 -221.010206) (xy 106.322792 -221.058509) (xy 106.330542 -221.108587) (xy 106.331004 -221.133924)
			(xy 106.330496 -221.159811) (xy 106.322397 -221.210949) (xy 106.306398 -221.260189) (xy 106.282892 -221.306321)
			(xy 106.25246 -221.348208) (xy 106.21585 -221.384818) (xy 106.173963 -221.41525) (xy 106.127831 -221.438756)
			(xy 106.078591 -221.454755) (xy 106.027453 -221.462854) (xy 105.975679 -221.462854) (xy 105.924541 -221.454755)
			(xy 105.875301 -221.438756) (xy 105.829169 -221.41525) (xy 105.787282 -221.384818) (xy 105.750672 -221.348208)
			(xy 105.72024 -221.306321) (xy 105.696734 -221.260189) (xy 105.680735 -221.210949) (xy 105.672636 -221.159811)
			(xy 105.672128 -221.133924) (xy 105.672667 -221.106216) (xy 105.681856 -221.05157) (xy 105.690416 -221.025212)
			(xy 105.69829 -221.003114) (xy 105.493312 -220.648022) (xy 105.470452 -220.643704) (xy 105.4456 -220.63857)
			(xy 105.397753 -220.621668) (xy 105.353062 -220.597632) (xy 105.312584 -220.567029) (xy 105.277274 -220.530584)
			(xy 105.247968 -220.489157) (xy 105.225357 -220.443728) (xy 105.209977 -220.39537) (xy 105.202191 -220.345226)
			(xy 105.20172 -220.319854) (xy 103.981504 -220.319854) (xy 103.981028 -220.345199) (xy 103.973249 -220.395289)
			(xy 103.957897 -220.443599) (xy 103.935334 -220.48899) (xy 103.906091 -220.530396) (xy 103.870857 -220.566839)
			(xy 103.830462 -220.597461) (xy 103.785857 -220.621543) (xy 103.738093 -220.638516) (xy 103.71328 -220.643704)
			(xy 103.69042 -220.648022) (xy 103.485442 -221.003114) (xy 103.493316 -221.024958) (xy 103.50191 -221.051373)
			(xy 103.511097 -221.106151) (xy 103.511604 -221.133924) (xy 103.511096 -221.159811) (xy 103.502997 -221.210949)
			(xy 103.486998 -221.260189) (xy 103.463492 -221.306321) (xy 103.43306 -221.348208) (xy 103.39645 -221.384818)
			(xy 103.354563 -221.41525) (xy 103.308431 -221.438756) (xy 103.259191 -221.454755) (xy 103.208053 -221.462854)
			(xy 103.156279 -221.462854) (xy 103.105141 -221.454755) (xy 103.055901 -221.438756) (xy 103.009769 -221.41525)
			(xy 102.967882 -221.384818) (xy 102.931272 -221.348208) (xy 102.90084 -221.306321) (xy 102.877334 -221.260189)
			(xy 102.861335 -221.210949) (xy 102.853236 -221.159811) (xy 102.852728 -221.133924) (xy 102.571804 -221.133924)
			(xy 102.57128 -221.161632) (xy 102.562081 -221.216279) (xy 102.553516 -221.242636) (xy 102.545642 -221.264734)
			(xy 102.75062 -221.619572) (xy 102.77348 -221.62389) (xy 102.798305 -221.629041) (xy 102.846083 -221.645999)
			(xy 102.890702 -221.670074) (xy 102.931107 -221.700696) (xy 102.966347 -221.737145) (xy 102.99559 -221.778561)
			(xy 103.018147 -221.823965) (xy 103.033485 -221.872289) (xy 103.041242 -221.92239) (xy 103.041704 -221.94774)
			(xy 104.26192 -221.94774) (xy 104.262371 -221.922394) (xy 104.270152 -221.872302) (xy 104.285506 -221.82399)
			(xy 104.308072 -221.778597) (xy 104.337318 -221.737192) (xy 104.372555 -221.700749) (xy 104.412954 -221.670127)
			(xy 104.457562 -221.646047) (xy 104.50533 -221.629076) (xy 104.530144 -221.62389) (xy 104.553004 -221.619572)
			(xy 104.758236 -221.264226) (xy 104.750362 -221.242128) (xy 104.741898 -221.215883) (xy 104.732825 -221.161495)
			(xy 104.732328 -221.133924) (xy 104.732836 -221.108037) (xy 104.740935 -221.056899) (xy 104.756934 -221.007659)
			(xy 104.78044 -220.961527) (xy 104.810872 -220.91964) (xy 104.847482 -220.88303) (xy 104.889369 -220.852598)
			(xy 104.935501 -220.829092) (xy 104.984741 -220.813093) (xy 105.035879 -220.804994) (xy 105.087653 -220.804994)
			(xy 105.138791 -220.813093) (xy 105.188031 -220.829092) (xy 105.234163 -220.852598) (xy 105.27605 -220.88303)
			(xy 105.31266 -220.91964) (xy 105.343092 -220.961527) (xy 105.366598 -221.007659) (xy 105.382597 -221.056899)
			(xy 105.390696 -221.108037) (xy 105.391204 -221.133924) (xy 105.390748 -221.159299) (xy 105.382976 -221.20945)
			(xy 105.367604 -221.257815) (xy 105.344997 -221.303251) (xy 105.315689 -221.344682) (xy 105.280373 -221.381128)
			(xy 105.239885 -221.411727) (xy 105.195184 -221.435754) (xy 105.147326 -221.452641) (xy 105.122472 -221.457774)
			(xy 105.099612 -221.462092) (xy 104.894888 -221.81693) (xy 104.902762 -221.838774) (xy 104.911419 -221.865179)
			(xy 104.920732 -221.919958) (xy 104.921304 -221.94774) (xy 106.14152 -221.94774) (xy 106.141971 -221.922394)
			(xy 106.149752 -221.872302) (xy 106.165106 -221.82399) (xy 106.187672 -221.778597) (xy 106.216918 -221.737192)
			(xy 106.252155 -221.700749) (xy 106.292554 -221.670127) (xy 106.337162 -221.646047) (xy 106.38493 -221.629076)
			(xy 106.409744 -221.62389) (xy 106.432604 -221.619572) (xy 106.637836 -221.264226) (xy 106.629962 -221.242128)
			(xy 106.621498 -221.215883) (xy 106.612425 -221.161495) (xy 106.611928 -221.133924) (xy 106.612436 -221.108037)
			(xy 106.620535 -221.056899) (xy 106.636534 -221.007659) (xy 106.66004 -220.961527) (xy 106.690472 -220.91964)
			(xy 106.727082 -220.88303) (xy 106.768969 -220.852598) (xy 106.815101 -220.829092) (xy 106.864341 -220.813093)
			(xy 106.915479 -220.804994) (xy 106.967253 -220.804994) (xy 107.018391 -220.813093) (xy 107.067631 -220.829092)
			(xy 107.113763 -220.852598) (xy 107.15565 -220.88303) (xy 107.19226 -220.91964) (xy 107.222692 -220.961527)
			(xy 107.246198 -221.007659) (xy 107.262197 -221.056899) (xy 107.270296 -221.108037) (xy 107.270804 -221.133924)
			(xy 107.270348 -221.159299) (xy 107.262576 -221.20945) (xy 107.247204 -221.257815) (xy 107.224597 -221.303251)
			(xy 107.195289 -221.344682) (xy 107.159973 -221.381128) (xy 107.119485 -221.411727) (xy 107.074784 -221.435754)
			(xy 107.026926 -221.452641) (xy 107.002072 -221.457774) (xy 106.979212 -221.462092) (xy 106.774488 -221.81693)
			(xy 106.782362 -221.838774) (xy 106.791019 -221.865179) (xy 106.800332 -221.919958) (xy 106.800904 -221.94774)
			(xy 108.02112 -221.94774) (xy 108.021571 -221.922394) (xy 108.029352 -221.872302) (xy 108.044706 -221.82399)
			(xy 108.067272 -221.778597) (xy 108.096518 -221.737192) (xy 108.131755 -221.700749) (xy 108.172154 -221.670127)
			(xy 108.216762 -221.646047) (xy 108.26453 -221.629076) (xy 108.289344 -221.62389) (xy 108.312204 -221.619572)
			(xy 108.517436 -221.264226) (xy 108.509562 -221.242128) (xy 108.501098 -221.215883) (xy 108.492025 -221.161495)
			(xy 108.491528 -221.133924) (xy 108.492036 -221.108037) (xy 108.500135 -221.056899) (xy 108.516134 -221.007659)
			(xy 108.53964 -220.961527) (xy 108.570072 -220.91964) (xy 108.606682 -220.88303) (xy 108.648569 -220.852598)
			(xy 108.694701 -220.829092) (xy 108.743941 -220.813093) (xy 108.795079 -220.804994) (xy 108.846853 -220.804994)
			(xy 108.897991 -220.813093) (xy 108.947231 -220.829092) (xy 108.993363 -220.852598) (xy 109.03525 -220.88303)
			(xy 109.07186 -220.91964) (xy 109.102292 -220.961527) (xy 109.125798 -221.007659) (xy 109.141797 -221.056899)
			(xy 109.149896 -221.108037) (xy 109.150404 -221.133924) (xy 109.149948 -221.159299) (xy 109.142176 -221.20945)
			(xy 109.126804 -221.257815) (xy 109.104197 -221.303251) (xy 109.074889 -221.344682) (xy 109.039573 -221.381128)
			(xy 108.999085 -221.411727) (xy 108.954384 -221.435754) (xy 108.906526 -221.452641) (xy 108.881672 -221.457774)
			(xy 108.858812 -221.462092) (xy 108.654088 -221.81693) (xy 108.661962 -221.838774) (xy 108.670619 -221.865179)
			(xy 108.679932 -221.919958) (xy 108.680504 -221.94774) (xy 109.901228 -221.94774) (xy 109.901634 -221.922403)
			(xy 109.909396 -221.872326) (xy 109.924728 -221.824026) (xy 109.947269 -221.77864) (xy 109.976489 -221.737238)
			(xy 110.011699 -221.700794) (xy 110.05207 -221.670165) (xy 110.096652 -221.646074) (xy 110.144395 -221.629087)
			(xy 110.169198 -221.62389) (xy 110.192058 -221.619572) (xy 110.397036 -221.26448) (xy 110.389416 -221.242382)
			(xy 110.380897 -221.216211) (xy 110.371703 -221.161949) (xy 110.371128 -221.134432) (xy 110.371128 -221.133924)
			(xy 110.371636 -221.108037) (xy 110.379735 -221.056899) (xy 110.395734 -221.007659) (xy 110.41924 -220.961527)
			(xy 110.449672 -220.91964) (xy 110.486282 -220.88303) (xy 110.528169 -220.852598) (xy 110.574301 -220.829092)
			(xy 110.623541 -220.813093) (xy 110.674679 -220.804994) (xy 110.726453 -220.804994) (xy 110.777591 -220.813093)
			(xy 110.826831 -220.829092) (xy 110.872963 -220.852598) (xy 110.91485 -220.88303) (xy 110.95146 -220.91964)
			(xy 110.981892 -220.961527) (xy 111.005398 -221.007659) (xy 111.021397 -221.056899) (xy 111.029496 -221.108037)
			(xy 111.030004 -221.133924) (xy 111.029585 -221.15929) (xy 111.021833 -221.209425) (xy 111.006484 -221.257778)
			(xy 110.983902 -221.303206) (xy 110.954621 -221.344633) (xy 110.919333 -221.381081) (xy 110.878874 -221.411686)
			(xy 110.8342 -221.435725) (xy 110.786369 -221.45263) (xy 110.761526 -221.457774) (xy 110.738666 -221.462092)
			(xy 110.533942 -221.81693) (xy 110.541816 -221.838774) (xy 110.550414 -221.865187) (xy 110.559598 -221.919967)
			(xy 110.560104 -221.94774) (xy 111.78032 -221.94774) (xy 111.780771 -221.922394) (xy 111.788552 -221.872302)
			(xy 111.803906 -221.82399) (xy 111.826472 -221.778597) (xy 111.855718 -221.737192) (xy 111.890955 -221.700749)
			(xy 111.931354 -221.670127) (xy 111.975962 -221.646047) (xy 112.02373 -221.629076) (xy 112.048544 -221.62389)
			(xy 112.071404 -221.619572) (xy 112.276636 -221.264226) (xy 112.268762 -221.242128) (xy 112.260298 -221.215883)
			(xy 112.251225 -221.161495) (xy 112.250728 -221.133924) (xy 112.251236 -221.108037) (xy 112.259335 -221.056899)
			(xy 112.275334 -221.007659) (xy 112.29884 -220.961527) (xy 112.329272 -220.91964) (xy 112.365882 -220.88303)
			(xy 112.407769 -220.852598) (xy 112.453901 -220.829092) (xy 112.503141 -220.813093) (xy 112.554279 -220.804994)
			(xy 112.606053 -220.804994) (xy 112.657191 -220.813093) (xy 112.706431 -220.829092) (xy 112.752563 -220.852598)
			(xy 112.79445 -220.88303) (xy 112.83106 -220.91964) (xy 112.861492 -220.961527) (xy 112.884998 -221.007659)
			(xy 112.900997 -221.056899) (xy 112.909096 -221.108037) (xy 112.909604 -221.133924) (xy 112.909148 -221.159299)
			(xy 112.901376 -221.20945) (xy 112.886004 -221.257815) (xy 112.863397 -221.303251) (xy 112.834089 -221.344682)
			(xy 112.798773 -221.381128) (xy 112.758285 -221.411727) (xy 112.713584 -221.435754) (xy 112.665726 -221.452641)
			(xy 112.640872 -221.457774) (xy 112.618012 -221.462092) (xy 112.413288 -221.81693) (xy 112.421162 -221.838774)
			(xy 112.429819 -221.865179) (xy 112.439132 -221.919958) (xy 112.439704 -221.94774) (xy 113.660428 -221.94774)
			(xy 113.660834 -221.922403) (xy 113.668596 -221.872326) (xy 113.683928 -221.824026) (xy 113.706469 -221.77864)
			(xy 113.735689 -221.737238) (xy 113.770899 -221.700794) (xy 113.81127 -221.670165) (xy 113.855852 -221.646074)
			(xy 113.903595 -221.629087) (xy 113.928398 -221.62389) (xy 113.951258 -221.619572) (xy 114.156236 -221.26448)
			(xy 114.148616 -221.242382) (xy 114.140097 -221.216211) (xy 114.130903 -221.161949) (xy 114.130328 -221.134432)
			(xy 114.130328 -221.133924) (xy 114.130836 -221.108037) (xy 114.138935 -221.056899) (xy 114.154934 -221.007659)
			(xy 114.17844 -220.961527) (xy 114.208872 -220.91964) (xy 114.245482 -220.88303) (xy 114.287369 -220.852598)
			(xy 114.333501 -220.829092) (xy 114.382741 -220.813093) (xy 114.433879 -220.804994) (xy 114.485653 -220.804994)
			(xy 114.536791 -220.813093) (xy 114.586031 -220.829092) (xy 114.632163 -220.852598) (xy 114.67405 -220.88303)
			(xy 114.71066 -220.91964) (xy 114.741092 -220.961527) (xy 114.764598 -221.007659) (xy 114.780597 -221.056899)
			(xy 114.788696 -221.108037) (xy 114.789204 -221.133924) (xy 114.788785 -221.15929) (xy 114.781033 -221.209425)
			(xy 114.765684 -221.257778) (xy 114.743102 -221.303206) (xy 114.713821 -221.344633) (xy 114.678533 -221.381081)
			(xy 114.638074 -221.411686) (xy 114.5934 -221.435725) (xy 114.545569 -221.45263) (xy 114.520726 -221.457774)
			(xy 114.497866 -221.462092) (xy 114.293142 -221.81693) (xy 114.301016 -221.838774) (xy 114.309614 -221.865187)
			(xy 114.318798 -221.919967) (xy 114.319304 -221.94774) (xy 115.53952 -221.94774) (xy 115.539971 -221.922394)
			(xy 115.547752 -221.872302) (xy 115.563106 -221.82399) (xy 115.585672 -221.778597) (xy 115.614918 -221.737192)
			(xy 115.650155 -221.700749) (xy 115.690554 -221.670127) (xy 115.735162 -221.646047) (xy 115.78293 -221.629076)
			(xy 115.807744 -221.62389) (xy 115.830604 -221.619572) (xy 116.035836 -221.264226) (xy 116.027962 -221.242128)
			(xy 116.019498 -221.215883) (xy 116.010425 -221.161495) (xy 116.009928 -221.133924) (xy 116.010436 -221.108037)
			(xy 116.018535 -221.056899) (xy 116.034534 -221.007659) (xy 116.05804 -220.961527) (xy 116.088472 -220.91964)
			(xy 116.125082 -220.88303) (xy 116.166969 -220.852598) (xy 116.213101 -220.829092) (xy 116.262341 -220.813093)
			(xy 116.313479 -220.804994) (xy 116.365253 -220.804994) (xy 116.416391 -220.813093) (xy 116.465631 -220.829092)
			(xy 116.511763 -220.852598) (xy 116.55365 -220.88303) (xy 116.59026 -220.91964) (xy 116.620692 -220.961527)
			(xy 116.644198 -221.007659) (xy 116.660197 -221.056899) (xy 116.668296 -221.108037) (xy 116.668804 -221.133924)
			(xy 116.668348 -221.159299) (xy 116.660576 -221.20945) (xy 116.645204 -221.257815) (xy 116.622597 -221.303251)
			(xy 116.593289 -221.344682) (xy 116.557973 -221.381128) (xy 116.517485 -221.411727) (xy 116.472784 -221.435754)
			(xy 116.424926 -221.452641) (xy 116.400072 -221.457774) (xy 116.377212 -221.462092) (xy 116.172488 -221.81693)
			(xy 116.180362 -221.838774) (xy 116.189019 -221.865179) (xy 116.198332 -221.919958) (xy 116.198904 -221.94774)
			(xy 117.41912 -221.94774) (xy 117.419571 -221.922394) (xy 117.427352 -221.872302) (xy 117.442706 -221.82399)
			(xy 117.465272 -221.778597) (xy 117.494518 -221.737192) (xy 117.529755 -221.700749) (xy 117.570154 -221.670127)
			(xy 117.614762 -221.646047) (xy 117.66253 -221.629076) (xy 117.687344 -221.62389) (xy 117.710204 -221.619572)
			(xy 117.915436 -221.264226) (xy 117.907562 -221.242128) (xy 117.899098 -221.215883) (xy 117.890025 -221.161495)
			(xy 117.889528 -221.133924) (xy 117.890036 -221.108037) (xy 117.898135 -221.056899) (xy 117.914134 -221.007659)
			(xy 117.93764 -220.961527) (xy 117.968072 -220.91964) (xy 118.004682 -220.88303) (xy 118.046569 -220.852598)
			(xy 118.092701 -220.829092) (xy 118.141941 -220.813093) (xy 118.193079 -220.804994) (xy 118.244853 -220.804994)
			(xy 118.295991 -220.813093) (xy 118.345231 -220.829092) (xy 118.391363 -220.852598) (xy 118.43325 -220.88303)
			(xy 118.46986 -220.91964) (xy 118.500292 -220.961527) (xy 118.523798 -221.007659) (xy 118.539797 -221.056899)
			(xy 118.547896 -221.108037) (xy 118.548404 -221.133924) (xy 118.547948 -221.159299) (xy 118.540176 -221.20945)
			(xy 118.524804 -221.257815) (xy 118.502197 -221.303251) (xy 118.472889 -221.344682) (xy 118.437573 -221.381128)
			(xy 118.397085 -221.411727) (xy 118.352384 -221.435754) (xy 118.304526 -221.452641) (xy 118.279672 -221.457774)
			(xy 118.256812 -221.462092) (xy 118.052088 -221.81693) (xy 118.059962 -221.838774) (xy 118.068619 -221.865179)
			(xy 118.077932 -221.919958) (xy 118.078504 -221.94774) (xy 121.17832 -221.94774) (xy 121.178771 -221.922394)
			(xy 121.186552 -221.872302) (xy 121.201906 -221.82399) (xy 121.224472 -221.778597) (xy 121.253718 -221.737192)
			(xy 121.288955 -221.700749) (xy 121.329354 -221.670127) (xy 121.373962 -221.646047) (xy 121.42173 -221.629076)
			(xy 121.446544 -221.62389) (xy 121.469404 -221.619572) (xy 121.674636 -221.264226) (xy 121.666762 -221.242128)
			(xy 121.658298 -221.215883) (xy 121.649225 -221.161495) (xy 121.648728 -221.133924) (xy 121.649236 -221.108037)
			(xy 121.657335 -221.056899) (xy 121.673334 -221.007659) (xy 121.69684 -220.961527) (xy 121.727272 -220.91964)
			(xy 121.763882 -220.88303) (xy 121.805769 -220.852598) (xy 121.851901 -220.829092) (xy 121.901141 -220.813093)
			(xy 121.952279 -220.804994) (xy 122.004053 -220.804994) (xy 122.055191 -220.813093) (xy 122.104431 -220.829092)
			(xy 122.150563 -220.852598) (xy 122.19245 -220.88303) (xy 122.22906 -220.91964) (xy 122.259492 -220.961527)
			(xy 122.282998 -221.007659) (xy 122.298997 -221.056899) (xy 122.307096 -221.108037) (xy 122.307604 -221.133924)
			(xy 122.307148 -221.159299) (xy 122.299376 -221.20945) (xy 122.284004 -221.257815) (xy 122.261397 -221.303251)
			(xy 122.232089 -221.344682) (xy 122.196773 -221.381128) (xy 122.156285 -221.411727) (xy 122.111584 -221.435754)
			(xy 122.063726 -221.452641) (xy 122.038872 -221.457774) (xy 122.016012 -221.462092) (xy 121.811288 -221.81693)
			(xy 121.819162 -221.838774) (xy 121.827819 -221.865179) (xy 121.837132 -221.919958) (xy 121.837704 -221.94774)
			(xy 123.05792 -221.94774) (xy 123.058371 -221.922394) (xy 123.066152 -221.872302) (xy 123.081506 -221.82399)
			(xy 123.104072 -221.778597) (xy 123.133318 -221.737192) (xy 123.168555 -221.700749) (xy 123.208954 -221.670127)
			(xy 123.253562 -221.646047) (xy 123.30133 -221.629076) (xy 123.326144 -221.62389) (xy 123.349004 -221.619572)
			(xy 123.554236 -221.264226) (xy 123.546362 -221.242128) (xy 123.537898 -221.215883) (xy 123.528825 -221.161495)
			(xy 123.528328 -221.133924) (xy 123.528836 -221.108037) (xy 123.536935 -221.056899) (xy 123.552934 -221.007659)
			(xy 123.57644 -220.961527) (xy 123.606872 -220.91964) (xy 123.643482 -220.88303) (xy 123.685369 -220.852598)
			(xy 123.731501 -220.829092) (xy 123.780741 -220.813093) (xy 123.831879 -220.804994) (xy 123.883653 -220.804994)
			(xy 123.934791 -220.813093) (xy 123.984031 -220.829092) (xy 124.030163 -220.852598) (xy 124.07205 -220.88303)
			(xy 124.10866 -220.91964) (xy 124.139092 -220.961527) (xy 124.162598 -221.007659) (xy 124.178597 -221.056899)
			(xy 124.186696 -221.108037) (xy 124.187204 -221.133924) (xy 124.186748 -221.159299) (xy 124.178976 -221.20945)
			(xy 124.163604 -221.257815) (xy 124.140997 -221.303251) (xy 124.111689 -221.344682) (xy 124.076373 -221.381128)
			(xy 124.035885 -221.411727) (xy 123.991184 -221.435754) (xy 123.943326 -221.452641) (xy 123.918472 -221.457774)
			(xy 123.895612 -221.462092) (xy 123.690888 -221.81693) (xy 123.698762 -221.838774) (xy 123.707419 -221.865179)
			(xy 123.716732 -221.919958) (xy 123.717304 -221.94774) (xy 124.93752 -221.94774) (xy 124.937971 -221.922394)
			(xy 124.945752 -221.872302) (xy 124.961106 -221.82399) (xy 124.983672 -221.778597) (xy 125.012918 -221.737192)
			(xy 125.048155 -221.700749) (xy 125.088554 -221.670127) (xy 125.133162 -221.646047) (xy 125.18093 -221.629076)
			(xy 125.205744 -221.62389) (xy 125.228604 -221.619572) (xy 125.433836 -221.264226) (xy 125.425962 -221.242128)
			(xy 125.417498 -221.215883) (xy 125.408425 -221.161495) (xy 125.407928 -221.133924) (xy 125.408436 -221.108037)
			(xy 125.416535 -221.056899) (xy 125.432534 -221.007659) (xy 125.45604 -220.961527) (xy 125.486472 -220.91964)
			(xy 125.523082 -220.88303) (xy 125.564969 -220.852598) (xy 125.611101 -220.829092) (xy 125.660341 -220.813093)
			(xy 125.711479 -220.804994) (xy 125.763253 -220.804994) (xy 125.814391 -220.813093) (xy 125.863631 -220.829092)
			(xy 125.909763 -220.852598) (xy 125.95165 -220.88303) (xy 125.98826 -220.91964) (xy 126.018692 -220.961527)
			(xy 126.042198 -221.007659) (xy 126.058197 -221.056899) (xy 126.066296 -221.108037) (xy 126.066804 -221.133924)
			(xy 126.066348 -221.159299) (xy 126.058576 -221.20945) (xy 126.043204 -221.257815) (xy 126.020597 -221.303251)
			(xy 125.991289 -221.344682) (xy 125.955973 -221.381128) (xy 125.915485 -221.411727) (xy 125.870784 -221.435754)
			(xy 125.822926 -221.452641) (xy 125.798072 -221.457774) (xy 125.775212 -221.462092) (xy 125.570488 -221.81693)
			(xy 125.578362 -221.838774) (xy 125.587019 -221.865179) (xy 125.596332 -221.919958) (xy 125.596904 -221.94774)
			(xy 126.81712 -221.94774) (xy 126.817571 -221.922394) (xy 126.825352 -221.872302) (xy 126.840706 -221.82399)
			(xy 126.863272 -221.778597) (xy 126.892518 -221.737192) (xy 126.927755 -221.700749) (xy 126.968154 -221.670127)
			(xy 127.012762 -221.646047) (xy 127.06053 -221.629076) (xy 127.085344 -221.62389) (xy 127.108204 -221.619572)
			(xy 127.313436 -221.264226) (xy 127.305562 -221.242128) (xy 127.297098 -221.215883) (xy 127.288025 -221.161495)
			(xy 127.287528 -221.133924) (xy 127.288036 -221.108037) (xy 127.296135 -221.056899) (xy 127.312134 -221.007659)
			(xy 127.33564 -220.961527) (xy 127.366072 -220.91964) (xy 127.402682 -220.88303) (xy 127.444569 -220.852598)
			(xy 127.490701 -220.829092) (xy 127.539941 -220.813093) (xy 127.591079 -220.804994) (xy 127.642853 -220.804994)
			(xy 127.693991 -220.813093) (xy 127.743231 -220.829092) (xy 127.789363 -220.852598) (xy 127.83125 -220.88303)
			(xy 127.86786 -220.91964) (xy 127.898292 -220.961527) (xy 127.921798 -221.007659) (xy 127.937797 -221.056899)
			(xy 127.945896 -221.108037) (xy 127.946404 -221.133924) (xy 127.945948 -221.159299) (xy 127.938176 -221.20945)
			(xy 127.922804 -221.257815) (xy 127.900197 -221.303251) (xy 127.870889 -221.344682) (xy 127.835573 -221.381128)
			(xy 127.795085 -221.411727) (xy 127.750384 -221.435754) (xy 127.702526 -221.452641) (xy 127.677672 -221.457774)
			(xy 127.654812 -221.462092) (xy 127.450088 -221.81693) (xy 127.457962 -221.838774) (xy 127.466619 -221.865179)
			(xy 127.475932 -221.919958) (xy 127.476504 -221.94774) (xy 128.69672 -221.94774) (xy 128.697171 -221.922394)
			(xy 128.704952 -221.872302) (xy 128.720306 -221.82399) (xy 128.742872 -221.778597) (xy 128.772118 -221.737192)
			(xy 128.807355 -221.700749) (xy 128.847754 -221.670127) (xy 128.892362 -221.646047) (xy 128.94013 -221.629076)
			(xy 128.964944 -221.62389) (xy 128.987804 -221.619572) (xy 129.193036 -221.264226) (xy 129.185162 -221.242128)
			(xy 129.176698 -221.215883) (xy 129.167625 -221.161495) (xy 129.167128 -221.133924) (xy 129.167636 -221.108037)
			(xy 129.175735 -221.056899) (xy 129.191734 -221.007659) (xy 129.21524 -220.961527) (xy 129.245672 -220.91964)
			(xy 129.282282 -220.88303) (xy 129.324169 -220.852598) (xy 129.370301 -220.829092) (xy 129.419541 -220.813093)
			(xy 129.470679 -220.804994) (xy 129.522453 -220.804994) (xy 129.573591 -220.813093) (xy 129.622831 -220.829092)
			(xy 129.668963 -220.852598) (xy 129.71085 -220.88303) (xy 129.74746 -220.91964) (xy 129.777892 -220.961527)
			(xy 129.801398 -221.007659) (xy 129.817397 -221.056899) (xy 129.825496 -221.108037) (xy 129.826004 -221.133924)
			(xy 129.825548 -221.159299) (xy 129.817776 -221.20945) (xy 129.802404 -221.257815) (xy 129.779797 -221.303251)
			(xy 129.750489 -221.344682) (xy 129.715173 -221.381128) (xy 129.674685 -221.411727) (xy 129.629984 -221.435754)
			(xy 129.582126 -221.452641) (xy 129.557272 -221.457774) (xy 129.534412 -221.462092) (xy 129.329688 -221.81693)
			(xy 129.337562 -221.838774) (xy 129.346219 -221.865179) (xy 129.355532 -221.919958) (xy 129.356104 -221.94774)
			(xy 130.57632 -221.94774) (xy 130.576771 -221.922394) (xy 130.584552 -221.872302) (xy 130.599906 -221.82399)
			(xy 130.622472 -221.778597) (xy 130.651718 -221.737192) (xy 130.686955 -221.700749) (xy 130.727354 -221.670127)
			(xy 130.771962 -221.646047) (xy 130.81973 -221.629076) (xy 130.844544 -221.62389) (xy 130.867404 -221.619572)
			(xy 131.072636 -221.264226) (xy 131.064762 -221.242128) (xy 131.056298 -221.215883) (xy 131.047225 -221.161495)
			(xy 131.046728 -221.133924) (xy 131.047236 -221.108037) (xy 131.055335 -221.056899) (xy 131.071334 -221.007659)
			(xy 131.09484 -220.961527) (xy 131.125272 -220.91964) (xy 131.161882 -220.88303) (xy 131.203769 -220.852598)
			(xy 131.249901 -220.829092) (xy 131.299141 -220.813093) (xy 131.350279 -220.804994) (xy 131.402053 -220.804994)
			(xy 131.453191 -220.813093) (xy 131.502431 -220.829092) (xy 131.548563 -220.852598) (xy 131.59045 -220.88303)
			(xy 131.62706 -220.91964) (xy 131.657492 -220.961527) (xy 131.680998 -221.007659) (xy 131.696997 -221.056899)
			(xy 131.705096 -221.108037) (xy 131.705604 -221.133924) (xy 131.705148 -221.159299) (xy 131.697376 -221.20945)
			(xy 131.682004 -221.257815) (xy 131.659397 -221.303251) (xy 131.630089 -221.344682) (xy 131.594773 -221.381128)
			(xy 131.554285 -221.411727) (xy 131.509584 -221.435754) (xy 131.461726 -221.452641) (xy 131.436872 -221.457774)
			(xy 131.414012 -221.462092) (xy 131.209288 -221.81693) (xy 131.217162 -221.838774) (xy 131.225819 -221.865179)
			(xy 131.235132 -221.919958) (xy 131.235704 -221.94774) (xy 131.235196 -221.973647) (xy 131.22709 -222.024824)
			(xy 131.211078 -222.074103) (xy 131.187555 -222.12027) (xy 131.157099 -222.162189) (xy 131.120461 -222.198827)
			(xy 131.078542 -222.229283) (xy 131.032375 -222.252806) (xy 130.983096 -222.268818) (xy 130.931919 -222.276924)
			(xy 130.880105 -222.276924) (xy 130.828928 -222.268818) (xy 130.779649 -222.252806) (xy 130.733482 -222.229283)
			(xy 130.691563 -222.198827) (xy 130.654925 -222.162189) (xy 130.624469 -222.12027) (xy 130.600946 -222.074103)
			(xy 130.584934 -222.024824) (xy 130.576828 -221.973647) (xy 130.57632 -221.94774) (xy 129.356104 -221.94774)
			(xy 129.355596 -221.973647) (xy 129.34749 -222.024824) (xy 129.331478 -222.074103) (xy 129.307955 -222.12027)
			(xy 129.277499 -222.162189) (xy 129.240861 -222.198827) (xy 129.198942 -222.229283) (xy 129.152775 -222.252806)
			(xy 129.103496 -222.268818) (xy 129.052319 -222.276924) (xy 129.000505 -222.276924) (xy 128.949328 -222.268818)
			(xy 128.900049 -222.252806) (xy 128.853882 -222.229283) (xy 128.811963 -222.198827) (xy 128.775325 -222.162189)
			(xy 128.744869 -222.12027) (xy 128.721346 -222.074103) (xy 128.705334 -222.024824) (xy 128.697228 -221.973647)
			(xy 128.69672 -221.94774) (xy 127.476504 -221.94774) (xy 127.475996 -221.973647) (xy 127.46789 -222.024824)
			(xy 127.451878 -222.074103) (xy 127.428355 -222.12027) (xy 127.397899 -222.162189) (xy 127.361261 -222.198827)
			(xy 127.319342 -222.229283) (xy 127.273175 -222.252806) (xy 127.223896 -222.268818) (xy 127.172719 -222.276924)
			(xy 127.120905 -222.276924) (xy 127.069728 -222.268818) (xy 127.020449 -222.252806) (xy 126.974282 -222.229283)
			(xy 126.932363 -222.198827) (xy 126.895725 -222.162189) (xy 126.865269 -222.12027) (xy 126.841746 -222.074103)
			(xy 126.825734 -222.024824) (xy 126.817628 -221.973647) (xy 126.81712 -221.94774) (xy 125.596904 -221.94774)
			(xy 125.596396 -221.973647) (xy 125.58829 -222.024824) (xy 125.572278 -222.074103) (xy 125.548755 -222.12027)
			(xy 125.518299 -222.162189) (xy 125.481661 -222.198827) (xy 125.439742 -222.229283) (xy 125.393575 -222.252806)
			(xy 125.344296 -222.268818) (xy 125.293119 -222.276924) (xy 125.241305 -222.276924) (xy 125.190128 -222.268818)
			(xy 125.140849 -222.252806) (xy 125.094682 -222.229283) (xy 125.052763 -222.198827) (xy 125.016125 -222.162189)
			(xy 124.985669 -222.12027) (xy 124.962146 -222.074103) (xy 124.946134 -222.024824) (xy 124.938028 -221.973647)
			(xy 124.93752 -221.94774) (xy 123.717304 -221.94774) (xy 123.716796 -221.973647) (xy 123.70869 -222.024824)
			(xy 123.692678 -222.074103) (xy 123.669155 -222.12027) (xy 123.638699 -222.162189) (xy 123.602061 -222.198827)
			(xy 123.560142 -222.229283) (xy 123.513975 -222.252806) (xy 123.464696 -222.268818) (xy 123.413519 -222.276924)
			(xy 123.361705 -222.276924) (xy 123.310528 -222.268818) (xy 123.261249 -222.252806) (xy 123.215082 -222.229283)
			(xy 123.173163 -222.198827) (xy 123.136525 -222.162189) (xy 123.106069 -222.12027) (xy 123.082546 -222.074103)
			(xy 123.066534 -222.024824) (xy 123.058428 -221.973647) (xy 123.05792 -221.94774) (xy 121.837704 -221.94774)
			(xy 121.837196 -221.973647) (xy 121.82909 -222.024824) (xy 121.813078 -222.074103) (xy 121.789555 -222.12027)
			(xy 121.759099 -222.162189) (xy 121.722461 -222.198827) (xy 121.680542 -222.229283) (xy 121.634375 -222.252806)
			(xy 121.585096 -222.268818) (xy 121.533919 -222.276924) (xy 121.482105 -222.276924) (xy 121.430928 -222.268818)
			(xy 121.381649 -222.252806) (xy 121.335482 -222.229283) (xy 121.293563 -222.198827) (xy 121.256925 -222.162189)
			(xy 121.226469 -222.12027) (xy 121.202946 -222.074103) (xy 121.186934 -222.024824) (xy 121.178828 -221.973647)
			(xy 121.17832 -221.94774) (xy 118.078504 -221.94774) (xy 118.077996 -221.973647) (xy 118.06989 -222.024824)
			(xy 118.053878 -222.074103) (xy 118.030355 -222.12027) (xy 117.999899 -222.162189) (xy 117.963261 -222.198827)
			(xy 117.921342 -222.229283) (xy 117.875175 -222.252806) (xy 117.825896 -222.268818) (xy 117.774719 -222.276924)
			(xy 117.722905 -222.276924) (xy 117.671728 -222.268818) (xy 117.622449 -222.252806) (xy 117.576282 -222.229283)
			(xy 117.534363 -222.198827) (xy 117.497725 -222.162189) (xy 117.467269 -222.12027) (xy 117.443746 -222.074103)
			(xy 117.427734 -222.024824) (xy 117.419628 -221.973647) (xy 117.41912 -221.94774) (xy 116.198904 -221.94774)
			(xy 116.198396 -221.973647) (xy 116.19029 -222.024824) (xy 116.174278 -222.074103) (xy 116.150755 -222.12027)
			(xy 116.120299 -222.162189) (xy 116.083661 -222.198827) (xy 116.041742 -222.229283) (xy 115.995575 -222.252806)
			(xy 115.946296 -222.268818) (xy 115.895119 -222.276924) (xy 115.843305 -222.276924) (xy 115.792128 -222.268818)
			(xy 115.742849 -222.252806) (xy 115.696682 -222.229283) (xy 115.654763 -222.198827) (xy 115.618125 -222.162189)
			(xy 115.587669 -222.12027) (xy 115.564146 -222.074103) (xy 115.548134 -222.024824) (xy 115.540028 -221.973647)
			(xy 115.53952 -221.94774) (xy 114.319304 -221.94774) (xy 114.318796 -221.973627) (xy 114.310697 -222.024765)
			(xy 114.294698 -222.074005) (xy 114.271192 -222.120137) (xy 114.24076 -222.162024) (xy 114.20415 -222.198634)
			(xy 114.162263 -222.229066) (xy 114.116131 -222.252572) (xy 114.066891 -222.268571) (xy 114.015753 -222.27667)
			(xy 113.963979 -222.27667) (xy 113.912841 -222.268571) (xy 113.863601 -222.252572) (xy 113.817469 -222.229066)
			(xy 113.775582 -222.198634) (xy 113.738972 -222.162024) (xy 113.70854 -222.120137) (xy 113.685034 -222.074005)
			(xy 113.669035 -222.024765) (xy 113.660936 -221.973627) (xy 113.660428 -221.94774) (xy 112.439704 -221.94774)
			(xy 112.439196 -221.973647) (xy 112.43109 -222.024824) (xy 112.415078 -222.074103) (xy 112.391555 -222.12027)
			(xy 112.361099 -222.162189) (xy 112.324461 -222.198827) (xy 112.282542 -222.229283) (xy 112.236375 -222.252806)
			(xy 112.187096 -222.268818) (xy 112.135919 -222.276924) (xy 112.084105 -222.276924) (xy 112.032928 -222.268818)
			(xy 111.983649 -222.252806) (xy 111.937482 -222.229283) (xy 111.895563 -222.198827) (xy 111.858925 -222.162189)
			(xy 111.828469 -222.12027) (xy 111.804946 -222.074103) (xy 111.788934 -222.024824) (xy 111.780828 -221.973647)
			(xy 111.78032 -221.94774) (xy 110.560104 -221.94774) (xy 110.559596 -221.973627) (xy 110.551497 -222.024765)
			(xy 110.535498 -222.074005) (xy 110.511992 -222.120137) (xy 110.48156 -222.162024) (xy 110.44495 -222.198634)
			(xy 110.403063 -222.229066) (xy 110.356931 -222.252572) (xy 110.307691 -222.268571) (xy 110.256553 -222.27667)
			(xy 110.204779 -222.27667) (xy 110.153641 -222.268571) (xy 110.104401 -222.252572) (xy 110.058269 -222.229066)
			(xy 110.016382 -222.198634) (xy 109.979772 -222.162024) (xy 109.94934 -222.120137) (xy 109.925834 -222.074005)
			(xy 109.909835 -222.024765) (xy 109.901736 -221.973627) (xy 109.901228 -221.94774) (xy 108.680504 -221.94774)
			(xy 108.679996 -221.973647) (xy 108.67189 -222.024824) (xy 108.655878 -222.074103) (xy 108.632355 -222.12027)
			(xy 108.601899 -222.162189) (xy 108.565261 -222.198827) (xy 108.523342 -222.229283) (xy 108.477175 -222.252806)
			(xy 108.427896 -222.268818) (xy 108.376719 -222.276924) (xy 108.324905 -222.276924) (xy 108.273728 -222.268818)
			(xy 108.224449 -222.252806) (xy 108.178282 -222.229283) (xy 108.136363 -222.198827) (xy 108.099725 -222.162189)
			(xy 108.069269 -222.12027) (xy 108.045746 -222.074103) (xy 108.029734 -222.024824) (xy 108.021628 -221.973647)
			(xy 108.02112 -221.94774) (xy 106.800904 -221.94774) (xy 106.800396 -221.973647) (xy 106.79229 -222.024824)
			(xy 106.776278 -222.074103) (xy 106.752755 -222.12027) (xy 106.722299 -222.162189) (xy 106.685661 -222.198827)
			(xy 106.643742 -222.229283) (xy 106.597575 -222.252806) (xy 106.548296 -222.268818) (xy 106.497119 -222.276924)
			(xy 106.445305 -222.276924) (xy 106.394128 -222.268818) (xy 106.344849 -222.252806) (xy 106.298682 -222.229283)
			(xy 106.256763 -222.198827) (xy 106.220125 -222.162189) (xy 106.189669 -222.12027) (xy 106.166146 -222.074103)
			(xy 106.150134 -222.024824) (xy 106.142028 -221.973647) (xy 106.14152 -221.94774) (xy 104.921304 -221.94774)
			(xy 104.920796 -221.973647) (xy 104.91269 -222.024824) (xy 104.896678 -222.074103) (xy 104.873155 -222.12027)
			(xy 104.842699 -222.162189) (xy 104.806061 -222.198827) (xy 104.764142 -222.229283) (xy 104.717975 -222.252806)
			(xy 104.668696 -222.268818) (xy 104.617519 -222.276924) (xy 104.565705 -222.276924) (xy 104.514528 -222.268818)
			(xy 104.465249 -222.252806) (xy 104.419082 -222.229283) (xy 104.377163 -222.198827) (xy 104.340525 -222.162189)
			(xy 104.310069 -222.12027) (xy 104.286546 -222.074103) (xy 104.270534 -222.024824) (xy 104.262428 -221.973647)
			(xy 104.26192 -221.94774) (xy 103.041704 -221.94774) (xy 103.041196 -221.973647) (xy 103.03309 -222.024824)
			(xy 103.017078 -222.074103) (xy 102.993555 -222.12027) (xy 102.963099 -222.162189) (xy 102.926461 -222.198827)
			(xy 102.884542 -222.229283) (xy 102.838375 -222.252806) (xy 102.789096 -222.268818) (xy 102.737919 -222.276924)
			(xy 102.686105 -222.276924) (xy 102.634928 -222.268818) (xy 102.585649 -222.252806) (xy 102.539482 -222.229283)
			(xy 102.497563 -222.198827) (xy 102.460925 -222.162189) (xy 102.430469 -222.12027) (xy 102.406946 -222.074103)
			(xy 102.390934 -222.024824) (xy 102.382828 -221.973647) (xy 102.38232 -221.94774) (xy 102.382923 -221.920023)
			(xy 102.39224 -221.865377) (xy 102.400862 -221.839028) (xy 102.408736 -221.81693) (xy 102.203758 -221.462092)
			(xy 102.180898 -221.457774) (xy 102.156103 -221.45255) (xy 102.108367 -221.435564) (xy 102.063792 -221.411474)
			(xy 102.023427 -221.380847) (xy 101.988224 -221.344405) (xy 101.959011 -221.303006) (xy 101.936476 -221.257625)
			(xy 101.92115 -221.20933) (xy 101.913394 -221.159258) (xy 101.912928 -221.133924) (xy 101.632004 -221.133924)
			(xy 101.631496 -221.159811) (xy 101.623397 -221.210949) (xy 101.607398 -221.260189) (xy 101.583892 -221.306321)
			(xy 101.55346 -221.348208) (xy 101.51685 -221.384818) (xy 101.474963 -221.41525) (xy 101.428831 -221.438756)
			(xy 101.379591 -221.454755) (xy 101.328453 -221.462854) (xy 101.276679 -221.462854) (xy 101.225541 -221.454755)
			(xy 101.176301 -221.438756) (xy 101.130169 -221.41525) (xy 101.088282 -221.384818) (xy 101.051672 -221.348208)
			(xy 101.02124 -221.306321) (xy 100.997734 -221.260189) (xy 100.981735 -221.210949) (xy 100.973636 -221.159811)
			(xy 100.973128 -221.133924) (xy 100.692204 -221.133924) (xy 100.69168 -221.161632) (xy 100.682481 -221.216279)
			(xy 100.673916 -221.242636) (xy 100.666042 -221.264734) (xy 100.87102 -221.619572) (xy 100.89388 -221.62389)
			(xy 100.918705 -221.629041) (xy 100.966483 -221.645999) (xy 101.011102 -221.670074) (xy 101.051507 -221.700696)
			(xy 101.086747 -221.737145) (xy 101.11599 -221.778561) (xy 101.138547 -221.823965) (xy 101.153885 -221.872289)
			(xy 101.161642 -221.92239) (xy 101.162104 -221.94774) (xy 101.161596 -221.973647) (xy 101.15349 -222.024824)
			(xy 101.137478 -222.074103) (xy 101.113955 -222.12027) (xy 101.083499 -222.162189) (xy 101.046861 -222.198827)
			(xy 101.004942 -222.229283) (xy 100.958775 -222.252806) (xy 100.909496 -222.268818) (xy 100.858319 -222.276924)
			(xy 100.806505 -222.276924) (xy 100.755328 -222.268818) (xy 100.706049 -222.252806) (xy 100.659882 -222.229283)
			(xy 100.617963 -222.198827) (xy 100.581325 -222.162189) (xy 100.550869 -222.12027) (xy 100.527346 -222.074103)
			(xy 100.511334 -222.024824) (xy 100.503228 -221.973647) (xy 100.50272 -221.94774) (xy 100.503323 -221.920023)
			(xy 100.51264 -221.865377) (xy 100.521262 -221.839028) (xy 100.529136 -221.81693) (xy 100.324158 -221.462092)
			(xy 100.301298 -221.457774) (xy 100.276503 -221.45255) (xy 100.228767 -221.435564) (xy 100.184192 -221.411474)
			(xy 100.143827 -221.380847) (xy 100.108624 -221.344405) (xy 100.079411 -221.303006) (xy 100.056876 -221.257625)
			(xy 100.04155 -221.20933) (xy 100.033794 -221.159258) (xy 100.033328 -221.133924) (xy 99.752404 -221.133924)
			(xy 99.751896 -221.159811) (xy 99.743797 -221.210949) (xy 99.727798 -221.260189) (xy 99.704292 -221.306321)
			(xy 99.67386 -221.348208) (xy 99.63725 -221.384818) (xy 99.595363 -221.41525) (xy 99.549231 -221.438756)
			(xy 99.499991 -221.454755) (xy 99.448853 -221.462854) (xy 99.397079 -221.462854) (xy 99.345941 -221.454755)
			(xy 99.296701 -221.438756) (xy 99.250569 -221.41525) (xy 99.208682 -221.384818) (xy 99.172072 -221.348208)
			(xy 99.14164 -221.306321) (xy 99.118134 -221.260189) (xy 99.102135 -221.210949) (xy 99.094036 -221.159811)
			(xy 99.093528 -221.133924) (xy 98.812604 -221.133924) (xy 98.81208 -221.161632) (xy 98.802881 -221.216279)
			(xy 98.794316 -221.242636) (xy 98.786442 -221.264734) (xy 98.99142 -221.619572) (xy 99.01428 -221.62389)
			(xy 99.039105 -221.629041) (xy 99.086883 -221.645999) (xy 99.131502 -221.670074) (xy 99.171907 -221.700696)
			(xy 99.207147 -221.737145) (xy 99.23639 -221.778561) (xy 99.258947 -221.823965) (xy 99.274285 -221.872289)
			(xy 99.282042 -221.92239) (xy 99.282504 -221.94774) (xy 99.281996 -221.973647) (xy 99.27389 -222.024824)
			(xy 99.257878 -222.074103) (xy 99.234355 -222.12027) (xy 99.203899 -222.162189) (xy 99.167261 -222.198827)
			(xy 99.125342 -222.229283) (xy 99.079175 -222.252806) (xy 99.029896 -222.268818) (xy 98.978719 -222.276924)
			(xy 98.926905 -222.276924) (xy 98.875728 -222.268818) (xy 98.826449 -222.252806) (xy 98.780282 -222.229283)
			(xy 98.738363 -222.198827) (xy 98.701725 -222.162189) (xy 98.671269 -222.12027) (xy 98.647746 -222.074103)
			(xy 98.631734 -222.024824) (xy 98.623628 -221.973647) (xy 98.62312 -221.94774) (xy 98.623723 -221.920023)
			(xy 98.63304 -221.865377) (xy 98.641662 -221.839028) (xy 98.649536 -221.81693) (xy 98.444558 -221.462092)
			(xy 98.421698 -221.457774) (xy 98.396903 -221.45255) (xy 98.349167 -221.435564) (xy 98.304592 -221.411474)
			(xy 98.264227 -221.380847) (xy 98.229024 -221.344405) (xy 98.199811 -221.303006) (xy 98.177276 -221.257625)
			(xy 98.16195 -221.20933) (xy 98.154194 -221.159258) (xy 98.153728 -221.133924) (xy 97.872804 -221.133924)
			(xy 97.872296 -221.159811) (xy 97.864197 -221.210949) (xy 97.848198 -221.260189) (xy 97.824692 -221.306321)
			(xy 97.79426 -221.348208) (xy 97.75765 -221.384818) (xy 97.715763 -221.41525) (xy 97.669631 -221.438756)
			(xy 97.620391 -221.454755) (xy 97.569253 -221.462854) (xy 97.517479 -221.462854) (xy 97.466341 -221.454755)
			(xy 97.417101 -221.438756) (xy 97.370969 -221.41525) (xy 97.329082 -221.384818) (xy 97.292472 -221.348208)
			(xy 97.26204 -221.306321) (xy 97.238534 -221.260189) (xy 97.222535 -221.210949) (xy 97.214436 -221.159811)
			(xy 97.213928 -221.133924) (xy 96.933004 -221.133924) (xy 96.93248 -221.161632) (xy 96.923281 -221.216279)
			(xy 96.914716 -221.242636) (xy 96.906842 -221.264734) (xy 97.11182 -221.619572) (xy 97.13468 -221.62389)
			(xy 97.159505 -221.629041) (xy 97.207283 -221.645999) (xy 97.251902 -221.670074) (xy 97.292307 -221.700696)
			(xy 97.327547 -221.737145) (xy 97.35679 -221.778561) (xy 97.379347 -221.823965) (xy 97.394685 -221.872289)
			(xy 97.402442 -221.92239) (xy 97.402904 -221.94774) (xy 97.402396 -221.973647) (xy 97.39429 -222.024824)
			(xy 97.378278 -222.074103) (xy 97.354755 -222.12027) (xy 97.324299 -222.162189) (xy 97.287661 -222.198827)
			(xy 97.245742 -222.229283) (xy 97.199575 -222.252806) (xy 97.150296 -222.268818) (xy 97.099119 -222.276924)
			(xy 97.047305 -222.276924) (xy 96.996128 -222.268818) (xy 96.946849 -222.252806) (xy 96.900682 -222.229283)
			(xy 96.858763 -222.198827) (xy 96.822125 -222.162189) (xy 96.791669 -222.12027) (xy 96.768146 -222.074103)
			(xy 96.752134 -222.024824) (xy 96.744028 -221.973647) (xy 96.74352 -221.94774) (xy 96.744123 -221.920023)
			(xy 96.75344 -221.865377) (xy 96.762062 -221.839028) (xy 96.769936 -221.81693) (xy 96.564958 -221.462092)
			(xy 96.542098 -221.457774) (xy 96.517303 -221.45255) (xy 96.469567 -221.435564) (xy 96.424992 -221.411474)
			(xy 96.384627 -221.380847) (xy 96.349424 -221.344405) (xy 96.320211 -221.303006) (xy 96.297676 -221.257625)
			(xy 96.28235 -221.20933) (xy 96.274594 -221.159258) (xy 96.274128 -221.133924) (xy 95.993204 -221.133924)
			(xy 95.992696 -221.159811) (xy 95.984597 -221.210949) (xy 95.968598 -221.260189) (xy 95.945092 -221.306321)
			(xy 95.91466 -221.348208) (xy 95.87805 -221.384818) (xy 95.836163 -221.41525) (xy 95.790031 -221.438756)
			(xy 95.740791 -221.454755) (xy 95.689653 -221.462854) (xy 95.637879 -221.462854) (xy 95.586741 -221.454755)
			(xy 95.537501 -221.438756) (xy 95.491369 -221.41525) (xy 95.449482 -221.384818) (xy 95.412872 -221.348208)
			(xy 95.38244 -221.306321) (xy 95.358934 -221.260189) (xy 95.342935 -221.210949) (xy 95.334836 -221.159811)
			(xy 95.334328 -221.133924) (xy 95.053404 -221.133924) (xy 95.05288 -221.161632) (xy 95.043681 -221.216279)
			(xy 95.035116 -221.242636) (xy 95.027242 -221.264734) (xy 95.23222 -221.619572) (xy 95.25508 -221.62389)
			(xy 95.279905 -221.629041) (xy 95.327683 -221.645999) (xy 95.372302 -221.670074) (xy 95.412707 -221.700696)
			(xy 95.447947 -221.737145) (xy 95.47719 -221.778561) (xy 95.499747 -221.823965) (xy 95.515085 -221.872289)
			(xy 95.522842 -221.92239) (xy 95.523304 -221.94774) (xy 95.522796 -221.973647) (xy 95.51469 -222.024824)
			(xy 95.498678 -222.074103) (xy 95.475155 -222.12027) (xy 95.444699 -222.162189) (xy 95.408061 -222.198827)
			(xy 95.366142 -222.229283) (xy 95.319975 -222.252806) (xy 95.270696 -222.268818) (xy 95.219519 -222.276924)
			(xy 95.167705 -222.276924) (xy 95.116528 -222.268818) (xy 95.067249 -222.252806) (xy 95.021082 -222.229283)
			(xy 94.979163 -222.198827) (xy 94.942525 -222.162189) (xy 94.912069 -222.12027) (xy 94.888546 -222.074103)
			(xy 94.872534 -222.024824) (xy 94.864428 -221.973647) (xy 94.86392 -221.94774) (xy 94.864523 -221.920023)
			(xy 94.87384 -221.865377) (xy 94.882462 -221.839028) (xy 94.890336 -221.81693) (xy 94.685358 -221.462092)
			(xy 94.662498 -221.457774) (xy 94.637703 -221.45255) (xy 94.589967 -221.435564) (xy 94.545392 -221.411474)
			(xy 94.505027 -221.380847) (xy 94.469824 -221.344405) (xy 94.440611 -221.303006) (xy 94.418076 -221.257625)
			(xy 94.40275 -221.20933) (xy 94.394994 -221.159258) (xy 94.394528 -221.133924) (xy 94.113604 -221.133924)
			(xy 94.113096 -221.159811) (xy 94.104997 -221.210949) (xy 94.088998 -221.260189) (xy 94.065492 -221.306321)
			(xy 94.03506 -221.348208) (xy 93.99845 -221.384818) (xy 93.956563 -221.41525) (xy 93.910431 -221.438756)
			(xy 93.861191 -221.454755) (xy 93.810053 -221.462854) (xy 93.758279 -221.462854) (xy 93.707141 -221.454755)
			(xy 93.657901 -221.438756) (xy 93.611769 -221.41525) (xy 93.569882 -221.384818) (xy 93.533272 -221.348208)
			(xy 93.50284 -221.306321) (xy 93.479334 -221.260189) (xy 93.463335 -221.210949) (xy 93.455236 -221.159811)
			(xy 93.454728 -221.133924) (xy 93.173804 -221.133924) (xy 93.17328 -221.161632) (xy 93.164081 -221.216279)
			(xy 93.155516 -221.242636) (xy 93.147642 -221.264734) (xy 93.35262 -221.619572) (xy 93.37548 -221.62389)
			(xy 93.400305 -221.629041) (xy 93.448083 -221.645999) (xy 93.492702 -221.670074) (xy 93.533107 -221.700696)
			(xy 93.568347 -221.737145) (xy 93.59759 -221.778561) (xy 93.620147 -221.823965) (xy 93.635485 -221.872289)
			(xy 93.643242 -221.92239) (xy 93.643704 -221.94774) (xy 93.643196 -221.973647) (xy 93.63509 -222.024824)
			(xy 93.619078 -222.074103) (xy 93.595555 -222.12027) (xy 93.565099 -222.162189) (xy 93.528461 -222.198827)
			(xy 93.486542 -222.229283) (xy 93.440375 -222.252806) (xy 93.391096 -222.268818) (xy 93.339919 -222.276924)
			(xy 93.288105 -222.276924) (xy 93.236928 -222.268818) (xy 93.187649 -222.252806) (xy 93.141482 -222.229283)
			(xy 93.099563 -222.198827) (xy 93.062925 -222.162189) (xy 93.032469 -222.12027) (xy 93.008946 -222.074103)
			(xy 92.992934 -222.024824) (xy 92.984828 -221.973647) (xy 92.98432 -221.94774) (xy 92.984923 -221.920023)
			(xy 92.99424 -221.865377) (xy 93.002862 -221.839028) (xy 93.010736 -221.81693) (xy 92.805758 -221.462092)
			(xy 92.782898 -221.457774) (xy 92.758103 -221.45255) (xy 92.710367 -221.435564) (xy 92.665792 -221.411474)
			(xy 92.625427 -221.380847) (xy 92.590224 -221.344405) (xy 92.561011 -221.303006) (xy 92.538476 -221.257625)
			(xy 92.52315 -221.20933) (xy 92.515394 -221.159258) (xy 92.514928 -221.133924) (xy 92.234004 -221.133924)
			(xy 92.233496 -221.159811) (xy 92.225397 -221.210949) (xy 92.209398 -221.260189) (xy 92.185892 -221.306321)
			(xy 92.15546 -221.348208) (xy 92.11885 -221.384818) (xy 92.076963 -221.41525) (xy 92.030831 -221.438756)
			(xy 91.981591 -221.454755) (xy 91.930453 -221.462854) (xy 91.878679 -221.462854) (xy 91.827541 -221.454755)
			(xy 91.778301 -221.438756) (xy 91.732169 -221.41525) (xy 91.690282 -221.384818) (xy 91.653672 -221.348208)
			(xy 91.62324 -221.306321) (xy 91.599734 -221.260189) (xy 91.583735 -221.210949) (xy 91.575636 -221.159811)
			(xy 91.575128 -221.133924) (xy 91.294204 -221.133924) (xy 91.29368 -221.161632) (xy 91.284481 -221.216279)
			(xy 91.275916 -221.242636) (xy 91.268042 -221.264734) (xy 91.47302 -221.619572) (xy 91.49588 -221.62389)
			(xy 91.520705 -221.629041) (xy 91.568483 -221.645999) (xy 91.613102 -221.670074) (xy 91.653507 -221.700696)
			(xy 91.688747 -221.737145) (xy 91.71799 -221.778561) (xy 91.740547 -221.823965) (xy 91.755885 -221.872289)
			(xy 91.763642 -221.92239) (xy 91.764104 -221.94774) (xy 91.763596 -221.973647) (xy 91.75549 -222.024824)
			(xy 91.739478 -222.074103) (xy 91.715955 -222.12027) (xy 91.685499 -222.162189) (xy 91.648861 -222.198827)
			(xy 91.606942 -222.229283) (xy 91.560775 -222.252806) (xy 91.511496 -222.268818) (xy 91.460319 -222.276924)
			(xy 91.408505 -222.276924) (xy 91.357328 -222.268818) (xy 91.308049 -222.252806) (xy 91.261882 -222.229283)
			(xy 91.219963 -222.198827) (xy 91.183325 -222.162189) (xy 91.152869 -222.12027) (xy 91.129346 -222.074103)
			(xy 91.113334 -222.024824) (xy 91.105228 -221.973647) (xy 91.10472 -221.94774) (xy 91.105323 -221.920023)
			(xy 91.11464 -221.865377) (xy 91.123262 -221.839028) (xy 91.131136 -221.81693) (xy 90.926158 -221.462092)
			(xy 90.903298 -221.457774) (xy 90.878503 -221.45255) (xy 90.830767 -221.435564) (xy 90.786192 -221.411474)
			(xy 90.745827 -221.380847) (xy 90.710624 -221.344405) (xy 90.681411 -221.303006) (xy 90.658876 -221.257625)
			(xy 90.64355 -221.20933) (xy 90.635794 -221.159258) (xy 90.635328 -221.133924) (xy 90.354404 -221.133924)
			(xy 90.353896 -221.159811) (xy 90.345797 -221.210949) (xy 90.329798 -221.260189) (xy 90.306292 -221.306321)
			(xy 90.27586 -221.348208) (xy 90.23925 -221.384818) (xy 90.197363 -221.41525) (xy 90.151231 -221.438756)
			(xy 90.101991 -221.454755) (xy 90.050853 -221.462854) (xy 89.999079 -221.462854) (xy 89.947941 -221.454755)
			(xy 89.898701 -221.438756) (xy 89.852569 -221.41525) (xy 89.810682 -221.384818) (xy 89.774072 -221.348208)
			(xy 89.74364 -221.306321) (xy 89.720134 -221.260189) (xy 89.704135 -221.210949) (xy 89.696036 -221.159811)
			(xy 89.695528 -221.133924) (xy 89.414604 -221.133924) (xy 89.41408 -221.161632) (xy 89.404881 -221.216279)
			(xy 89.396316 -221.242636) (xy 89.388442 -221.264734) (xy 89.59342 -221.619572) (xy 89.61628 -221.62389)
			(xy 89.641105 -221.629041) (xy 89.688883 -221.645999) (xy 89.733502 -221.670074) (xy 89.773907 -221.700696)
			(xy 89.809147 -221.737145) (xy 89.83839 -221.778561) (xy 89.860947 -221.823965) (xy 89.876285 -221.872289)
			(xy 89.884042 -221.92239) (xy 89.884504 -221.94774) (xy 89.883996 -221.973647) (xy 89.87589 -222.024824)
			(xy 89.859878 -222.074103) (xy 89.836355 -222.12027) (xy 89.805899 -222.162189) (xy 89.769261 -222.198827)
			(xy 89.727342 -222.229283) (xy 89.681175 -222.252806) (xy 89.631896 -222.268818) (xy 89.580719 -222.276924)
			(xy 89.528905 -222.276924) (xy 89.477728 -222.268818) (xy 89.428449 -222.252806) (xy 89.382282 -222.229283)
			(xy 89.340363 -222.198827) (xy 89.303725 -222.162189) (xy 89.273269 -222.12027) (xy 89.249746 -222.074103)
			(xy 89.233734 -222.024824) (xy 89.225628 -221.973647) (xy 89.22512 -221.94774) (xy 89.225723 -221.920023)
			(xy 89.23504 -221.865377) (xy 89.243662 -221.839028) (xy 89.251536 -221.81693) (xy 89.046558 -221.462092)
			(xy 89.023698 -221.457774) (xy 88.998903 -221.45255) (xy 88.951167 -221.435564) (xy 88.906592 -221.411474)
			(xy 88.866227 -221.380847) (xy 88.831024 -221.344405) (xy 88.801811 -221.303006) (xy 88.779276 -221.257625)
			(xy 88.76395 -221.20933) (xy 88.756194 -221.159258) (xy 88.755728 -221.133924) (xy 2.509012 -221.133924)
			(xy 2.509012 -224.389442) (xy 93.454728 -224.389442) (xy 93.455135 -224.364105) (xy 93.462897 -224.314028)
			(xy 93.478229 -224.265728) (xy 93.50077 -224.220343) (xy 93.529989 -224.17894) (xy 93.565199 -224.142496)
			(xy 93.60557 -224.111867) (xy 93.650152 -224.087776) (xy 93.697895 -224.070789) (xy 93.722698 -224.065592)
			(xy 93.745558 -224.061274) (xy 93.950282 -223.706436) (xy 93.942662 -223.684338) (xy 93.934031 -223.657991)
			(xy 93.92471 -223.603344) (xy 93.92412 -223.575626) (xy 93.924628 -223.549719) (xy 93.932734 -223.498542)
			(xy 93.948746 -223.449263) (xy 93.972269 -223.403096) (xy 94.002725 -223.361177) (xy 94.039363 -223.324539)
			(xy 94.081282 -223.294083) (xy 94.127449 -223.27056) (xy 94.176728 -223.254548) (xy 94.227905 -223.246442)
			(xy 94.279719 -223.246442) (xy 94.330896 -223.254548) (xy 94.380175 -223.27056) (xy 94.426342 -223.294083)
			(xy 94.468261 -223.324539) (xy 94.504899 -223.361177) (xy 94.535355 -223.403096) (xy 94.558878 -223.449263)
			(xy 94.57489 -223.498542) (xy 94.582996 -223.549719) (xy 94.583504 -223.575626) (xy 94.583087 -223.600992)
			(xy 94.575334 -223.651127) (xy 94.559985 -223.69948) (xy 94.537403 -223.744908) (xy 94.508122 -223.786336)
			(xy 94.472834 -223.822783) (xy 94.432375 -223.853388) (xy 94.387701 -223.877427) (xy 94.339869 -223.894332)
			(xy 94.315026 -223.899476) (xy 94.292166 -223.903794) (xy 94.087442 -224.258632) (xy 94.095316 -224.280476)
			(xy 94.10389 -224.306896) (xy 94.11309 -224.36167) (xy 94.113604 -224.389442) (xy 94.394528 -224.389442)
			(xy 94.395036 -224.363555) (xy 94.403135 -224.312417) (xy 94.419134 -224.263177) (xy 94.44264 -224.217045)
			(xy 94.473072 -224.175158) (xy 94.509682 -224.138548) (xy 94.551569 -224.108116) (xy 94.597701 -224.08461)
			(xy 94.646941 -224.068611) (xy 94.698079 -224.060512) (xy 94.749853 -224.060512) (xy 94.800991 -224.068611)
			(xy 94.850231 -224.08461) (xy 94.896363 -224.108116) (xy 94.93825 -224.138548) (xy 94.97486 -224.175158)
			(xy 95.005292 -224.217045) (xy 95.028798 -224.263177) (xy 95.044797 -224.312417) (xy 95.052896 -224.363555)
			(xy 95.053404 -224.389442) (xy 95.334328 -224.389442) (xy 95.334735 -224.364105) (xy 95.342497 -224.314028)
			(xy 95.357829 -224.265728) (xy 95.38037 -224.220343) (xy 95.409589 -224.17894) (xy 95.444799 -224.142496)
			(xy 95.48517 -224.111867) (xy 95.529752 -224.087776) (xy 95.577495 -224.070789) (xy 95.602298 -224.065592)
			(xy 95.625158 -224.061274) (xy 95.829882 -223.706436) (xy 95.822262 -223.684338) (xy 95.813631 -223.657991)
			(xy 95.80431 -223.603344) (xy 95.80372 -223.575626) (xy 95.804228 -223.549719) (xy 95.812334 -223.498542)
			(xy 95.828346 -223.449263) (xy 95.851869 -223.403096) (xy 95.882325 -223.361177) (xy 95.918963 -223.324539)
			(xy 95.960882 -223.294083) (xy 96.007049 -223.27056) (xy 96.056328 -223.254548) (xy 96.107505 -223.246442)
			(xy 96.159319 -223.246442) (xy 96.210496 -223.254548) (xy 96.259775 -223.27056) (xy 96.305942 -223.294083)
			(xy 96.347861 -223.324539) (xy 96.384499 -223.361177) (xy 96.414955 -223.403096) (xy 96.438478 -223.449263)
			(xy 96.45449 -223.498542) (xy 96.462596 -223.549719) (xy 96.463104 -223.575626) (xy 96.462687 -223.600992)
			(xy 96.454934 -223.651127) (xy 96.439585 -223.69948) (xy 96.417003 -223.744908) (xy 96.387722 -223.786336)
			(xy 96.352434 -223.822783) (xy 96.311975 -223.853388) (xy 96.267301 -223.877427) (xy 96.219469 -223.894332)
			(xy 96.194626 -223.899476) (xy 96.171766 -223.903794) (xy 95.967042 -224.258632) (xy 95.974916 -224.280476)
			(xy 95.98349 -224.306896) (xy 95.99269 -224.36167) (xy 95.993204 -224.389442) (xy 96.274128 -224.389442)
			(xy 96.274636 -224.363555) (xy 96.282735 -224.312417) (xy 96.298734 -224.263177) (xy 96.32224 -224.217045)
			(xy 96.352672 -224.175158) (xy 96.389282 -224.138548) (xy 96.431169 -224.108116) (xy 96.477301 -224.08461)
			(xy 96.526541 -224.068611) (xy 96.577679 -224.060512) (xy 96.629453 -224.060512) (xy 96.680591 -224.068611)
			(xy 96.729831 -224.08461) (xy 96.775963 -224.108116) (xy 96.81785 -224.138548) (xy 96.85446 -224.175158)
			(xy 96.884892 -224.217045) (xy 96.908398 -224.263177) (xy 96.924397 -224.312417) (xy 96.932496 -224.363555)
			(xy 96.933004 -224.389442) (xy 97.213928 -224.389442) (xy 97.214335 -224.364105) (xy 97.222097 -224.314028)
			(xy 97.237429 -224.265728) (xy 97.25997 -224.220343) (xy 97.289189 -224.17894) (xy 97.324399 -224.142496)
			(xy 97.36477 -224.111867) (xy 97.409352 -224.087776) (xy 97.457095 -224.070789) (xy 97.481898 -224.065592)
			(xy 97.504758 -224.061274) (xy 97.709482 -223.706436) (xy 97.701862 -223.684338) (xy 97.693231 -223.657991)
			(xy 97.68391 -223.603344) (xy 97.68332 -223.575626) (xy 97.683828 -223.549719) (xy 97.691934 -223.498542)
			(xy 97.707946 -223.449263) (xy 97.731469 -223.403096) (xy 97.761925 -223.361177) (xy 97.798563 -223.324539)
			(xy 97.840482 -223.294083) (xy 97.886649 -223.27056) (xy 97.935928 -223.254548) (xy 97.987105 -223.246442)
			(xy 98.038919 -223.246442) (xy 98.090096 -223.254548) (xy 98.139375 -223.27056) (xy 98.185542 -223.294083)
			(xy 98.227461 -223.324539) (xy 98.264099 -223.361177) (xy 98.294555 -223.403096) (xy 98.318078 -223.449263)
			(xy 98.33409 -223.498542) (xy 98.342196 -223.549719) (xy 98.342704 -223.575626) (xy 98.342287 -223.600992)
			(xy 98.334534 -223.651127) (xy 98.319185 -223.69948) (xy 98.296603 -223.744908) (xy 98.267322 -223.786336)
			(xy 98.232034 -223.822783) (xy 98.191575 -223.853388) (xy 98.146901 -223.877427) (xy 98.099069 -223.894332)
			(xy 98.074226 -223.899476) (xy 98.051366 -223.903794) (xy 97.846642 -224.258632) (xy 97.854516 -224.280476)
			(xy 97.86309 -224.306896) (xy 97.87229 -224.36167) (xy 97.872804 -224.389442) (xy 98.153728 -224.389442)
			(xy 98.154236 -224.363555) (xy 98.162335 -224.312417) (xy 98.178334 -224.263177) (xy 98.20184 -224.217045)
			(xy 98.232272 -224.175158) (xy 98.268882 -224.138548) (xy 98.310769 -224.108116) (xy 98.356901 -224.08461)
			(xy 98.406141 -224.068611) (xy 98.457279 -224.060512) (xy 98.509053 -224.060512) (xy 98.560191 -224.068611)
			(xy 98.609431 -224.08461) (xy 98.655563 -224.108116) (xy 98.69745 -224.138548) (xy 98.73406 -224.175158)
			(xy 98.764492 -224.217045) (xy 98.787998 -224.263177) (xy 98.803997 -224.312417) (xy 98.812096 -224.363555)
			(xy 98.812604 -224.389442) (xy 99.093528 -224.389442) (xy 99.093935 -224.364105) (xy 99.101697 -224.314028)
			(xy 99.117029 -224.265728) (xy 99.13957 -224.220343) (xy 99.168789 -224.17894) (xy 99.203999 -224.142496)
			(xy 99.24437 -224.111867) (xy 99.288952 -224.087776) (xy 99.336695 -224.070789) (xy 99.361498 -224.065592)
			(xy 99.384358 -224.061274) (xy 99.589082 -223.706436) (xy 99.581462 -223.684338) (xy 99.572831 -223.657991)
			(xy 99.56351 -223.603344) (xy 99.56292 -223.575626) (xy 99.563428 -223.549719) (xy 99.571534 -223.498542)
			(xy 99.587546 -223.449263) (xy 99.611069 -223.403096) (xy 99.641525 -223.361177) (xy 99.678163 -223.324539)
			(xy 99.720082 -223.294083) (xy 99.766249 -223.27056) (xy 99.815528 -223.254548) (xy 99.866705 -223.246442)
			(xy 99.918519 -223.246442) (xy 99.969696 -223.254548) (xy 100.018975 -223.27056) (xy 100.065142 -223.294083)
			(xy 100.107061 -223.324539) (xy 100.143699 -223.361177) (xy 100.174155 -223.403096) (xy 100.197678 -223.449263)
			(xy 100.21369 -223.498542) (xy 100.221796 -223.549719) (xy 100.222304 -223.575626) (xy 100.221887 -223.600992)
			(xy 100.214134 -223.651127) (xy 100.198785 -223.69948) (xy 100.176203 -223.744908) (xy 100.146922 -223.786336)
			(xy 100.111634 -223.822783) (xy 100.071175 -223.853388) (xy 100.026501 -223.877427) (xy 99.978669 -223.894332)
			(xy 99.953826 -223.899476) (xy 99.930966 -223.903794) (xy 99.726242 -224.258632) (xy 99.734116 -224.280476)
			(xy 99.74269 -224.306896) (xy 99.75189 -224.36167) (xy 99.752404 -224.389442) (xy 100.033328 -224.389442)
			(xy 100.033836 -224.363555) (xy 100.041935 -224.312417) (xy 100.057934 -224.263177) (xy 100.08144 -224.217045)
			(xy 100.111872 -224.175158) (xy 100.148482 -224.138548) (xy 100.190369 -224.108116) (xy 100.236501 -224.08461)
			(xy 100.285741 -224.068611) (xy 100.336879 -224.060512) (xy 100.388653 -224.060512) (xy 100.439791 -224.068611)
			(xy 100.489031 -224.08461) (xy 100.535163 -224.108116) (xy 100.57705 -224.138548) (xy 100.61366 -224.175158)
			(xy 100.644092 -224.217045) (xy 100.667598 -224.263177) (xy 100.683597 -224.312417) (xy 100.691696 -224.363555)
			(xy 100.692204 -224.389442) (xy 100.973128 -224.389442) (xy 100.973535 -224.364105) (xy 100.981297 -224.314028)
			(xy 100.996629 -224.265728) (xy 101.01917 -224.220343) (xy 101.048389 -224.17894) (xy 101.083599 -224.142496)
			(xy 101.12397 -224.111867) (xy 101.168552 -224.087776) (xy 101.216295 -224.070789) (xy 101.241098 -224.065592)
			(xy 101.263958 -224.061274) (xy 101.468682 -223.706436) (xy 101.461062 -223.684338) (xy 101.452431 -223.657991)
			(xy 101.44311 -223.603344) (xy 101.44252 -223.575626) (xy 101.443028 -223.549719) (xy 101.451134 -223.498542)
			(xy 101.467146 -223.449263) (xy 101.490669 -223.403096) (xy 101.521125 -223.361177) (xy 101.557763 -223.324539)
			(xy 101.599682 -223.294083) (xy 101.645849 -223.27056) (xy 101.695128 -223.254548) (xy 101.746305 -223.246442)
			(xy 101.798119 -223.246442) (xy 101.849296 -223.254548) (xy 101.898575 -223.27056) (xy 101.944742 -223.294083)
			(xy 101.986661 -223.324539) (xy 102.023299 -223.361177) (xy 102.053755 -223.403096) (xy 102.077278 -223.449263)
			(xy 102.09329 -223.498542) (xy 102.101396 -223.549719) (xy 102.101904 -223.575626) (xy 102.101487 -223.600992)
			(xy 102.093734 -223.651127) (xy 102.078385 -223.69948) (xy 102.055803 -223.744908) (xy 102.026522 -223.786336)
			(xy 101.991234 -223.822783) (xy 101.950775 -223.853388) (xy 101.906101 -223.877427) (xy 101.858269 -223.894332)
			(xy 101.833426 -223.899476) (xy 101.810566 -223.903794) (xy 101.605842 -224.258632) (xy 101.613716 -224.280476)
			(xy 101.62229 -224.306896) (xy 101.63149 -224.36167) (xy 101.632004 -224.389442) (xy 101.912928 -224.389442)
			(xy 101.913436 -224.363555) (xy 101.921535 -224.312417) (xy 101.937534 -224.263177) (xy 101.96104 -224.217045)
			(xy 101.991472 -224.175158) (xy 102.028082 -224.138548) (xy 102.069969 -224.108116) (xy 102.116101 -224.08461)
			(xy 102.165341 -224.068611) (xy 102.216479 -224.060512) (xy 102.268253 -224.060512) (xy 102.319391 -224.068611)
			(xy 102.368631 -224.08461) (xy 102.414763 -224.108116) (xy 102.45665 -224.138548) (xy 102.49326 -224.175158)
			(xy 102.523692 -224.217045) (xy 102.547198 -224.263177) (xy 102.563197 -224.312417) (xy 102.571296 -224.363555)
			(xy 102.571804 -224.389442) (xy 102.852728 -224.389442) (xy 102.853135 -224.364105) (xy 102.860897 -224.314028)
			(xy 102.876229 -224.265728) (xy 102.89877 -224.220343) (xy 102.927989 -224.17894) (xy 102.963199 -224.142496)
			(xy 103.00357 -224.111867) (xy 103.048152 -224.087776) (xy 103.095895 -224.070789) (xy 103.120698 -224.065592)
			(xy 103.143558 -224.061274) (xy 103.348282 -223.706436) (xy 103.340662 -223.684338) (xy 103.332031 -223.657991)
			(xy 103.32271 -223.603344) (xy 103.32212 -223.575626) (xy 103.322628 -223.549719) (xy 103.330734 -223.498542)
			(xy 103.346746 -223.449263) (xy 103.370269 -223.403096) (xy 103.400725 -223.361177) (xy 103.437363 -223.324539)
			(xy 103.479282 -223.294083) (xy 103.525449 -223.27056) (xy 103.574728 -223.254548) (xy 103.625905 -223.246442)
			(xy 103.677719 -223.246442) (xy 103.728896 -223.254548) (xy 103.778175 -223.27056) (xy 103.824342 -223.294083)
			(xy 103.866261 -223.324539) (xy 103.902899 -223.361177) (xy 103.933355 -223.403096) (xy 103.956878 -223.449263)
			(xy 103.97289 -223.498542) (xy 103.980996 -223.549719) (xy 103.981504 -223.575626) (xy 103.981087 -223.600992)
			(xy 103.973334 -223.651127) (xy 103.957985 -223.69948) (xy 103.935403 -223.744908) (xy 103.906122 -223.786336)
			(xy 103.870834 -223.822783) (xy 103.830375 -223.853388) (xy 103.785701 -223.877427) (xy 103.737869 -223.894332)
			(xy 103.713026 -223.899476) (xy 103.690166 -223.903794) (xy 103.485442 -224.258632) (xy 103.493316 -224.280476)
			(xy 103.50189 -224.306896) (xy 103.51109 -224.36167) (xy 103.511604 -224.389442) (xy 103.792528 -224.389442)
			(xy 103.793036 -224.363555) (xy 103.801135 -224.312417) (xy 103.817134 -224.263177) (xy 103.84064 -224.217045)
			(xy 103.871072 -224.175158) (xy 103.907682 -224.138548) (xy 103.949569 -224.108116) (xy 103.995701 -224.08461)
			(xy 104.044941 -224.068611) (xy 104.096079 -224.060512) (xy 104.147853 -224.060512) (xy 104.198991 -224.068611)
			(xy 104.248231 -224.08461) (xy 104.294363 -224.108116) (xy 104.33625 -224.138548) (xy 104.37286 -224.175158)
			(xy 104.403292 -224.217045) (xy 104.426798 -224.263177) (xy 104.442797 -224.312417) (xy 104.450896 -224.363555)
			(xy 104.451404 -224.389442) (xy 104.732328 -224.389442) (xy 104.732735 -224.364105) (xy 104.740497 -224.314028)
			(xy 104.755829 -224.265728) (xy 104.77837 -224.220343) (xy 104.807589 -224.17894) (xy 104.842799 -224.142496)
			(xy 104.88317 -224.111867) (xy 104.927752 -224.087776) (xy 104.975495 -224.070789) (xy 105.000298 -224.065592)
			(xy 105.023158 -224.061274) (xy 105.227882 -223.706436) (xy 105.220262 -223.684338) (xy 105.211631 -223.657991)
			(xy 105.20231 -223.603344) (xy 105.20172 -223.575626) (xy 105.202228 -223.549719) (xy 105.210334 -223.498542)
			(xy 105.226346 -223.449263) (xy 105.249869 -223.403096) (xy 105.280325 -223.361177) (xy 105.316963 -223.324539)
			(xy 105.358882 -223.294083) (xy 105.405049 -223.27056) (xy 105.454328 -223.254548) (xy 105.505505 -223.246442)
			(xy 105.557319 -223.246442) (xy 105.608496 -223.254548) (xy 105.657775 -223.27056) (xy 105.703942 -223.294083)
			(xy 105.745861 -223.324539) (xy 105.782499 -223.361177) (xy 105.812955 -223.403096) (xy 105.836478 -223.449263)
			(xy 105.85249 -223.498542) (xy 105.860596 -223.549719) (xy 105.861104 -223.575626) (xy 105.860687 -223.600992)
			(xy 105.852934 -223.651127) (xy 105.837585 -223.69948) (xy 105.815003 -223.744908) (xy 105.785722 -223.786336)
			(xy 105.750434 -223.822783) (xy 105.709975 -223.853388) (xy 105.665301 -223.877427) (xy 105.617469 -223.894332)
			(xy 105.592626 -223.899476) (xy 105.569766 -223.903794) (xy 105.365042 -224.258632) (xy 105.372916 -224.280476)
			(xy 105.38149 -224.306896) (xy 105.39069 -224.36167) (xy 105.391204 -224.389442) (xy 105.672128 -224.389442)
			(xy 105.672636 -224.363555) (xy 105.680735 -224.312417) (xy 105.696734 -224.263177) (xy 105.72024 -224.217045)
			(xy 105.750672 -224.175158) (xy 105.787282 -224.138548) (xy 105.829169 -224.108116) (xy 105.875301 -224.08461)
			(xy 105.924541 -224.068611) (xy 105.975679 -224.060512) (xy 106.027453 -224.060512) (xy 106.078591 -224.068611)
			(xy 106.127831 -224.08461) (xy 106.173963 -224.108116) (xy 106.21585 -224.138548) (xy 106.25246 -224.175158)
			(xy 106.282892 -224.217045) (xy 106.306398 -224.263177) (xy 106.322397 -224.312417) (xy 106.330496 -224.363555)
			(xy 106.331004 -224.389442) (xy 106.611928 -224.389442) (xy 106.612335 -224.364105) (xy 106.620097 -224.314028)
			(xy 106.635429 -224.265728) (xy 106.65797 -224.220343) (xy 106.687189 -224.17894) (xy 106.722399 -224.142496)
			(xy 106.76277 -224.111867) (xy 106.807352 -224.087776) (xy 106.855095 -224.070789) (xy 106.879898 -224.065592)
			(xy 106.902758 -224.061274) (xy 107.107482 -223.706436) (xy 107.099862 -223.684338) (xy 107.091231 -223.657991)
			(xy 107.08191 -223.603344) (xy 107.08132 -223.575626) (xy 107.081828 -223.549719) (xy 107.089934 -223.498542)
			(xy 107.105946 -223.449263) (xy 107.129469 -223.403096) (xy 107.159925 -223.361177) (xy 107.196563 -223.324539)
			(xy 107.238482 -223.294083) (xy 107.284649 -223.27056) (xy 107.333928 -223.254548) (xy 107.385105 -223.246442)
			(xy 107.436919 -223.246442) (xy 107.488096 -223.254548) (xy 107.537375 -223.27056) (xy 107.583542 -223.294083)
			(xy 107.625461 -223.324539) (xy 107.662099 -223.361177) (xy 107.692555 -223.403096) (xy 107.716078 -223.449263)
			(xy 107.73209 -223.498542) (xy 107.740196 -223.549719) (xy 107.740704 -223.575626) (xy 107.740287 -223.600992)
			(xy 107.732534 -223.651127) (xy 107.717185 -223.69948) (xy 107.694603 -223.744908) (xy 107.665322 -223.786336)
			(xy 107.630034 -223.822783) (xy 107.589575 -223.853388) (xy 107.544901 -223.877427) (xy 107.497069 -223.894332)
			(xy 107.472226 -223.899476) (xy 107.449366 -223.903794) (xy 107.244642 -224.258632) (xy 107.252516 -224.280476)
			(xy 107.26109 -224.306896) (xy 107.27029 -224.36167) (xy 107.270804 -224.389442) (xy 107.551728 -224.389442)
			(xy 107.552236 -224.363555) (xy 107.560335 -224.312417) (xy 107.576334 -224.263177) (xy 107.59984 -224.217045)
			(xy 107.630272 -224.175158) (xy 107.666882 -224.138548) (xy 107.708769 -224.108116) (xy 107.754901 -224.08461)
			(xy 107.804141 -224.068611) (xy 107.855279 -224.060512) (xy 107.907053 -224.060512) (xy 107.958191 -224.068611)
			(xy 108.007431 -224.08461) (xy 108.053563 -224.108116) (xy 108.09545 -224.138548) (xy 108.13206 -224.175158)
			(xy 108.162492 -224.217045) (xy 108.185998 -224.263177) (xy 108.201997 -224.312417) (xy 108.210096 -224.363555)
			(xy 108.210604 -224.389442) (xy 108.491528 -224.389442) (xy 108.491935 -224.364105) (xy 108.499697 -224.314028)
			(xy 108.515029 -224.265728) (xy 108.53757 -224.220343) (xy 108.566789 -224.17894) (xy 108.601999 -224.142496)
			(xy 108.64237 -224.111867) (xy 108.686952 -224.087776) (xy 108.734695 -224.070789) (xy 108.759498 -224.065592)
			(xy 108.782358 -224.061274) (xy 108.987082 -223.706436) (xy 108.979462 -223.684338) (xy 108.970831 -223.657991)
			(xy 108.96151 -223.603344) (xy 108.96092 -223.575626) (xy 108.961428 -223.549719) (xy 108.969534 -223.498542)
			(xy 108.985546 -223.449263) (xy 109.009069 -223.403096) (xy 109.039525 -223.361177) (xy 109.076163 -223.324539)
			(xy 109.118082 -223.294083) (xy 109.164249 -223.27056) (xy 109.213528 -223.254548) (xy 109.264705 -223.246442)
			(xy 109.316519 -223.246442) (xy 109.367696 -223.254548) (xy 109.416975 -223.27056) (xy 109.463142 -223.294083)
			(xy 109.505061 -223.324539) (xy 109.541699 -223.361177) (xy 109.572155 -223.403096) (xy 109.595678 -223.449263)
			(xy 109.61169 -223.498542) (xy 109.619796 -223.549719) (xy 109.620304 -223.575626) (xy 109.619887 -223.600992)
			(xy 109.612134 -223.651127) (xy 109.596785 -223.69948) (xy 109.574203 -223.744908) (xy 109.544922 -223.786336)
			(xy 109.509634 -223.822783) (xy 109.469175 -223.853388) (xy 109.424501 -223.877427) (xy 109.376669 -223.894332)
			(xy 109.351826 -223.899476) (xy 109.328966 -223.903794) (xy 109.124242 -224.258632) (xy 109.132116 -224.280476)
			(xy 109.14069 -224.306896) (xy 109.14989 -224.36167) (xy 109.150404 -224.389442) (xy 109.431328 -224.389442)
			(xy 109.431836 -224.363555) (xy 109.439935 -224.312417) (xy 109.455934 -224.263177) (xy 109.47944 -224.217045)
			(xy 109.509872 -224.175158) (xy 109.546482 -224.138548) (xy 109.588369 -224.108116) (xy 109.634501 -224.08461)
			(xy 109.683741 -224.068611) (xy 109.734879 -224.060512) (xy 109.786653 -224.060512) (xy 109.837791 -224.068611)
			(xy 109.887031 -224.08461) (xy 109.933163 -224.108116) (xy 109.97505 -224.138548) (xy 110.01166 -224.175158)
			(xy 110.042092 -224.217045) (xy 110.065598 -224.263177) (xy 110.081597 -224.312417) (xy 110.089696 -224.363555)
			(xy 110.090204 -224.389442) (xy 110.371128 -224.389442) (xy 110.371535 -224.364105) (xy 110.379297 -224.314028)
			(xy 110.394629 -224.265728) (xy 110.41717 -224.220343) (xy 110.446389 -224.17894) (xy 110.481599 -224.142496)
			(xy 110.52197 -224.111867) (xy 110.566552 -224.087776) (xy 110.614295 -224.070789) (xy 110.639098 -224.065592)
			(xy 110.661958 -224.061274) (xy 110.866682 -223.706436) (xy 110.859062 -223.684338) (xy 110.850431 -223.657991)
			(xy 110.84111 -223.603344) (xy 110.84052 -223.575626) (xy 110.841028 -223.549719) (xy 110.849134 -223.498542)
			(xy 110.865146 -223.449263) (xy 110.888669 -223.403096) (xy 110.919125 -223.361177) (xy 110.955763 -223.324539)
			(xy 110.997682 -223.294083) (xy 111.043849 -223.27056) (xy 111.093128 -223.254548) (xy 111.144305 -223.246442)
			(xy 111.196119 -223.246442) (xy 111.247296 -223.254548) (xy 111.296575 -223.27056) (xy 111.342742 -223.294083)
			(xy 111.384661 -223.324539) (xy 111.421299 -223.361177) (xy 111.451755 -223.403096) (xy 111.475278 -223.449263)
			(xy 111.49129 -223.498542) (xy 111.499396 -223.549719) (xy 111.499904 -223.575626) (xy 111.499487 -223.600992)
			(xy 111.491734 -223.651127) (xy 111.476385 -223.69948) (xy 111.453803 -223.744908) (xy 111.424522 -223.786336)
			(xy 111.389234 -223.822783) (xy 111.348775 -223.853388) (xy 111.304101 -223.877427) (xy 111.256269 -223.894332)
			(xy 111.231426 -223.899476) (xy 111.208566 -223.903794) (xy 111.003842 -224.258632) (xy 111.011716 -224.280476)
			(xy 111.02029 -224.306896) (xy 111.02949 -224.36167) (xy 111.030004 -224.389442) (xy 111.310928 -224.389442)
			(xy 111.311436 -224.363555) (xy 111.319535 -224.312417) (xy 111.335534 -224.263177) (xy 111.35904 -224.217045)
			(xy 111.389472 -224.175158) (xy 111.426082 -224.138548) (xy 111.467969 -224.108116) (xy 111.514101 -224.08461)
			(xy 111.563341 -224.068611) (xy 111.614479 -224.060512) (xy 111.666253 -224.060512) (xy 111.717391 -224.068611)
			(xy 111.766631 -224.08461) (xy 111.812763 -224.108116) (xy 111.85465 -224.138548) (xy 111.89126 -224.175158)
			(xy 111.921692 -224.217045) (xy 111.945198 -224.263177) (xy 111.961197 -224.312417) (xy 111.969296 -224.363555)
			(xy 111.969804 -224.389442) (xy 112.250728 -224.389442) (xy 112.251135 -224.364105) (xy 112.258897 -224.314028)
			(xy 112.274229 -224.265728) (xy 112.29677 -224.220343) (xy 112.325989 -224.17894) (xy 112.361199 -224.142496)
			(xy 112.40157 -224.111867) (xy 112.446152 -224.087776) (xy 112.493895 -224.070789) (xy 112.518698 -224.065592)
			(xy 112.541558 -224.061274) (xy 112.746282 -223.706436) (xy 112.738662 -223.684338) (xy 112.730031 -223.657991)
			(xy 112.72071 -223.603344) (xy 112.72012 -223.575626) (xy 112.720628 -223.549719) (xy 112.728734 -223.498542)
			(xy 112.744746 -223.449263) (xy 112.768269 -223.403096) (xy 112.798725 -223.361177) (xy 112.835363 -223.324539)
			(xy 112.877282 -223.294083) (xy 112.923449 -223.27056) (xy 112.972728 -223.254548) (xy 113.023905 -223.246442)
			(xy 113.075719 -223.246442) (xy 113.126896 -223.254548) (xy 113.176175 -223.27056) (xy 113.222342 -223.294083)
			(xy 113.264261 -223.324539) (xy 113.300899 -223.361177) (xy 113.331355 -223.403096) (xy 113.354878 -223.449263)
			(xy 113.37089 -223.498542) (xy 113.378996 -223.549719) (xy 113.379504 -223.575626) (xy 113.379087 -223.600992)
			(xy 113.371334 -223.651127) (xy 113.355985 -223.69948) (xy 113.333403 -223.744908) (xy 113.304122 -223.786336)
			(xy 113.268834 -223.822783) (xy 113.228375 -223.853388) (xy 113.183701 -223.877427) (xy 113.135869 -223.894332)
			(xy 113.111026 -223.899476) (xy 113.088166 -223.903794) (xy 112.883442 -224.258632) (xy 112.891316 -224.280476)
			(xy 112.89989 -224.306896) (xy 112.90909 -224.36167) (xy 112.909604 -224.389442) (xy 113.190528 -224.389442)
			(xy 113.191036 -224.363555) (xy 113.199135 -224.312417) (xy 113.215134 -224.263177) (xy 113.23864 -224.217045)
			(xy 113.269072 -224.175158) (xy 113.305682 -224.138548) (xy 113.347569 -224.108116) (xy 113.393701 -224.08461)
			(xy 113.442941 -224.068611) (xy 113.494079 -224.060512) (xy 113.545853 -224.060512) (xy 113.596991 -224.068611)
			(xy 113.646231 -224.08461) (xy 113.692363 -224.108116) (xy 113.73425 -224.138548) (xy 113.77086 -224.175158)
			(xy 113.801292 -224.217045) (xy 113.824798 -224.263177) (xy 113.840797 -224.312417) (xy 113.848896 -224.363555)
			(xy 113.849404 -224.389442) (xy 114.130328 -224.389442) (xy 114.130735 -224.364105) (xy 114.138497 -224.314028)
			(xy 114.153829 -224.265728) (xy 114.17637 -224.220343) (xy 114.205589 -224.17894) (xy 114.240799 -224.142496)
			(xy 114.28117 -224.111867) (xy 114.325752 -224.087776) (xy 114.373495 -224.070789) (xy 114.398298 -224.065592)
			(xy 114.421158 -224.061274) (xy 114.626136 -223.706182) (xy 114.618516 -223.684084) (xy 114.609997 -223.657912)
			(xy 114.600803 -223.603651) (xy 114.600228 -223.576134) (xy 114.600228 -223.575626) (xy 114.600736 -223.549739)
			(xy 114.608835 -223.498601) (xy 114.624834 -223.449361) (xy 114.64834 -223.403229) (xy 114.678772 -223.361342)
			(xy 114.715382 -223.324732) (xy 114.757269 -223.2943) (xy 114.803401 -223.270794) (xy 114.852641 -223.254795)
			(xy 114.903779 -223.246696) (xy 114.955553 -223.246696) (xy 115.006691 -223.254795) (xy 115.055931 -223.270794)
			(xy 115.102063 -223.2943) (xy 115.14395 -223.324732) (xy 115.18056 -223.361342) (xy 115.210992 -223.403229)
			(xy 115.234498 -223.449361) (xy 115.250497 -223.498601) (xy 115.258596 -223.549739) (xy 115.259104 -223.575626)
			(xy 115.258687 -223.600992) (xy 115.250934 -223.651127) (xy 115.235585 -223.69948) (xy 115.213003 -223.744908)
			(xy 115.183722 -223.786336) (xy 115.148434 -223.822783) (xy 115.107975 -223.853388) (xy 115.063301 -223.877427)
			(xy 115.015469 -223.894332) (xy 114.990626 -223.899476) (xy 114.967766 -223.903794) (xy 114.763042 -224.258632)
			(xy 114.770916 -224.280476) (xy 114.77949 -224.306896) (xy 114.78869 -224.36167) (xy 114.789204 -224.389442)
			(xy 115.070128 -224.389442) (xy 115.070636 -224.363555) (xy 115.078735 -224.312417) (xy 115.094734 -224.263177)
			(xy 115.11824 -224.217045) (xy 115.148672 -224.175158) (xy 115.185282 -224.138548) (xy 115.227169 -224.108116)
			(xy 115.273301 -224.08461) (xy 115.322541 -224.068611) (xy 115.373679 -224.060512) (xy 115.425453 -224.060512)
			(xy 115.476591 -224.068611) (xy 115.525831 -224.08461) (xy 115.571963 -224.108116) (xy 115.61385 -224.138548)
			(xy 115.65046 -224.175158) (xy 115.680892 -224.217045) (xy 115.704398 -224.263177) (xy 115.720397 -224.312417)
			(xy 115.728496 -224.363555) (xy 115.729004 -224.389442) (xy 116.009928 -224.389442) (xy 116.010335 -224.364105)
			(xy 116.018097 -224.314028) (xy 116.033429 -224.265728) (xy 116.05597 -224.220343) (xy 116.085189 -224.17894)
			(xy 116.120399 -224.142496) (xy 116.16077 -224.111867) (xy 116.205352 -224.087776) (xy 116.253095 -224.070789)
			(xy 116.277898 -224.065592) (xy 116.300758 -224.061274) (xy 116.505482 -223.706436) (xy 116.497862 -223.684338)
			(xy 116.489231 -223.657991) (xy 116.47991 -223.603344) (xy 116.47932 -223.575626) (xy 116.479828 -223.549719)
			(xy 116.487934 -223.498542) (xy 116.503946 -223.449263) (xy 116.527469 -223.403096) (xy 116.557925 -223.361177)
			(xy 116.594563 -223.324539) (xy 116.636482 -223.294083) (xy 116.682649 -223.27056) (xy 116.731928 -223.254548)
			(xy 116.783105 -223.246442) (xy 116.834919 -223.246442) (xy 116.886096 -223.254548) (xy 116.935375 -223.27056)
			(xy 116.981542 -223.294083) (xy 117.023461 -223.324539) (xy 117.060099 -223.361177) (xy 117.090555 -223.403096)
			(xy 117.114078 -223.449263) (xy 117.13009 -223.498542) (xy 117.138196 -223.549719) (xy 117.138704 -223.575626)
			(xy 117.138287 -223.600992) (xy 117.130534 -223.651127) (xy 117.115185 -223.69948) (xy 117.092603 -223.744908)
			(xy 117.063322 -223.786336) (xy 117.028034 -223.822783) (xy 116.987575 -223.853388) (xy 116.942901 -223.877427)
			(xy 116.895069 -223.894332) (xy 116.870226 -223.899476) (xy 116.847366 -223.903794) (xy 116.642642 -224.258632)
			(xy 116.650516 -224.280476) (xy 116.65909 -224.306896) (xy 116.66829 -224.36167) (xy 116.668804 -224.389442)
			(xy 116.949728 -224.389442) (xy 116.950236 -224.363555) (xy 116.958335 -224.312417) (xy 116.974334 -224.263177)
			(xy 116.99784 -224.217045) (xy 117.028272 -224.175158) (xy 117.064882 -224.138548) (xy 117.106769 -224.108116)
			(xy 117.152901 -224.08461) (xy 117.202141 -224.068611) (xy 117.253279 -224.060512) (xy 117.305053 -224.060512)
			(xy 117.356191 -224.068611) (xy 117.405431 -224.08461) (xy 117.451563 -224.108116) (xy 117.49345 -224.138548)
			(xy 117.53006 -224.175158) (xy 117.560492 -224.217045) (xy 117.583998 -224.263177) (xy 117.599997 -224.312417)
			(xy 117.608096 -224.363555) (xy 117.608604 -224.389442) (xy 117.889528 -224.389442) (xy 117.889935 -224.364105)
			(xy 117.897697 -224.314028) (xy 117.913029 -224.265728) (xy 117.93557 -224.220343) (xy 117.964789 -224.17894)
			(xy 117.999999 -224.142496) (xy 118.04037 -224.111867) (xy 118.084952 -224.087776) (xy 118.132695 -224.070789)
			(xy 118.157498 -224.065592) (xy 118.180358 -224.061274) (xy 118.385082 -223.706436) (xy 118.377462 -223.684338)
			(xy 118.368831 -223.657991) (xy 118.35951 -223.603344) (xy 118.35892 -223.575626) (xy 118.359428 -223.549719)
			(xy 118.367534 -223.498542) (xy 118.383546 -223.449263) (xy 118.407069 -223.403096) (xy 118.437525 -223.361177)
			(xy 118.474163 -223.324539) (xy 118.516082 -223.294083) (xy 118.562249 -223.27056) (xy 118.611528 -223.254548)
			(xy 118.662705 -223.246442) (xy 118.714519 -223.246442) (xy 118.765696 -223.254548) (xy 118.814975 -223.27056)
			(xy 118.861142 -223.294083) (xy 118.903061 -223.324539) (xy 118.939699 -223.361177) (xy 118.970155 -223.403096)
			(xy 118.993678 -223.449263) (xy 119.00969 -223.498542) (xy 119.017796 -223.549719) (xy 119.018304 -223.575626)
			(xy 119.017887 -223.600992) (xy 119.010134 -223.651127) (xy 118.994785 -223.69948) (xy 118.972203 -223.744908)
			(xy 118.942922 -223.786336) (xy 118.907634 -223.822783) (xy 118.867175 -223.853388) (xy 118.822501 -223.877427)
			(xy 118.774669 -223.894332) (xy 118.749826 -223.899476) (xy 118.726966 -223.903794) (xy 118.522242 -224.258632)
			(xy 118.530116 -224.280476) (xy 118.53869 -224.306896) (xy 118.54789 -224.36167) (xy 118.548404 -224.389442)
			(xy 118.829328 -224.389442) (xy 118.829836 -224.363555) (xy 118.837935 -224.312417) (xy 118.853934 -224.263177)
			(xy 118.87744 -224.217045) (xy 118.907872 -224.175158) (xy 118.944482 -224.138548) (xy 118.986369 -224.108116)
			(xy 119.032501 -224.08461) (xy 119.081741 -224.068611) (xy 119.132879 -224.060512) (xy 119.184653 -224.060512)
			(xy 119.235791 -224.068611) (xy 119.285031 -224.08461) (xy 119.331163 -224.108116) (xy 119.37305 -224.138548)
			(xy 119.40966 -224.175158) (xy 119.440092 -224.217045) (xy 119.463598 -224.263177) (xy 119.479597 -224.312417)
			(xy 119.487696 -224.363555) (xy 119.488204 -224.389442) (xy 119.769128 -224.389442) (xy 119.769535 -224.364105)
			(xy 119.777297 -224.314028) (xy 119.792629 -224.265728) (xy 119.81517 -224.220343) (xy 119.844389 -224.17894)
			(xy 119.879599 -224.142496) (xy 119.91997 -224.111867) (xy 119.964552 -224.087776) (xy 120.012295 -224.070789)
			(xy 120.037098 -224.065592) (xy 120.059958 -224.061274) (xy 120.264682 -223.706436) (xy 120.257062 -223.684338)
			(xy 120.248431 -223.657991) (xy 120.23911 -223.603344) (xy 120.23852 -223.575626) (xy 120.239028 -223.549719)
			(xy 120.247134 -223.498542) (xy 120.263146 -223.449263) (xy 120.286669 -223.403096) (xy 120.317125 -223.361177)
			(xy 120.353763 -223.324539) (xy 120.395682 -223.294083) (xy 120.441849 -223.27056) (xy 120.491128 -223.254548)
			(xy 120.542305 -223.246442) (xy 120.594119 -223.246442) (xy 120.645296 -223.254548) (xy 120.694575 -223.27056)
			(xy 120.740742 -223.294083) (xy 120.782661 -223.324539) (xy 120.819299 -223.361177) (xy 120.849755 -223.403096)
			(xy 120.873278 -223.449263) (xy 120.88929 -223.498542) (xy 120.897396 -223.549719) (xy 120.897904 -223.575626)
			(xy 120.897487 -223.600992) (xy 120.889734 -223.651127) (xy 120.874385 -223.69948) (xy 120.851803 -223.744908)
			(xy 120.822522 -223.786336) (xy 120.787234 -223.822783) (xy 120.746775 -223.853388) (xy 120.702101 -223.877427)
			(xy 120.654269 -223.894332) (xy 120.629426 -223.899476) (xy 120.606566 -223.903794) (xy 120.401842 -224.258632)
			(xy 120.409716 -224.280476) (xy 120.41829 -224.306896) (xy 120.42749 -224.36167) (xy 120.428004 -224.389442)
			(xy 120.708928 -224.389442) (xy 120.709436 -224.363555) (xy 120.717535 -224.312417) (xy 120.733534 -224.263177)
			(xy 120.75704 -224.217045) (xy 120.787472 -224.175158) (xy 120.824082 -224.138548) (xy 120.865969 -224.108116)
			(xy 120.912101 -224.08461) (xy 120.961341 -224.068611) (xy 121.012479 -224.060512) (xy 121.064253 -224.060512)
			(xy 121.115391 -224.068611) (xy 121.164631 -224.08461) (xy 121.210763 -224.108116) (xy 121.25265 -224.138548)
			(xy 121.28926 -224.175158) (xy 121.319692 -224.217045) (xy 121.343198 -224.263177) (xy 121.359197 -224.312417)
			(xy 121.367296 -224.363555) (xy 121.367804 -224.389442) (xy 121.648728 -224.389442) (xy 121.649135 -224.364105)
			(xy 121.656897 -224.314028) (xy 121.672229 -224.265728) (xy 121.69477 -224.220343) (xy 121.723989 -224.17894)
			(xy 121.759199 -224.142496) (xy 121.79957 -224.111867) (xy 121.844152 -224.087776) (xy 121.891895 -224.070789)
			(xy 121.916698 -224.065592) (xy 121.939558 -224.061274) (xy 122.144282 -223.706436) (xy 122.136662 -223.684338)
			(xy 122.128031 -223.657991) (xy 122.11871 -223.603344) (xy 122.11812 -223.575626) (xy 122.118628 -223.549719)
			(xy 122.126734 -223.498542) (xy 122.142746 -223.449263) (xy 122.166269 -223.403096) (xy 122.196725 -223.361177)
			(xy 122.233363 -223.324539) (xy 122.275282 -223.294083) (xy 122.321449 -223.27056) (xy 122.370728 -223.254548)
			(xy 122.421905 -223.246442) (xy 122.473719 -223.246442) (xy 122.524896 -223.254548) (xy 122.574175 -223.27056)
			(xy 122.620342 -223.294083) (xy 122.662261 -223.324539) (xy 122.698899 -223.361177) (xy 122.729355 -223.403096)
			(xy 122.752878 -223.449263) (xy 122.76889 -223.498542) (xy 122.776996 -223.549719) (xy 122.777504 -223.575626)
			(xy 122.777087 -223.600992) (xy 122.769334 -223.651127) (xy 122.753985 -223.69948) (xy 122.731403 -223.744908)
			(xy 122.702122 -223.786336) (xy 122.666834 -223.822783) (xy 122.626375 -223.853388) (xy 122.581701 -223.877427)
			(xy 122.533869 -223.894332) (xy 122.509026 -223.899476) (xy 122.486166 -223.903794) (xy 122.281442 -224.258632)
			(xy 122.289316 -224.280476) (xy 122.29789 -224.306896) (xy 122.30709 -224.36167) (xy 122.307604 -224.389442)
			(xy 122.588528 -224.389442) (xy 122.589036 -224.363555) (xy 122.597135 -224.312417) (xy 122.613134 -224.263177)
			(xy 122.63664 -224.217045) (xy 122.667072 -224.175158) (xy 122.703682 -224.138548) (xy 122.745569 -224.108116)
			(xy 122.791701 -224.08461) (xy 122.840941 -224.068611) (xy 122.892079 -224.060512) (xy 122.943853 -224.060512)
			(xy 122.994991 -224.068611) (xy 123.044231 -224.08461) (xy 123.090363 -224.108116) (xy 123.13225 -224.138548)
			(xy 123.16886 -224.175158) (xy 123.199292 -224.217045) (xy 123.222798 -224.263177) (xy 123.238797 -224.312417)
			(xy 123.246896 -224.363555) (xy 123.247404 -224.389442) (xy 123.528328 -224.389442) (xy 123.528735 -224.364105)
			(xy 123.536497 -224.314028) (xy 123.551829 -224.265728) (xy 123.57437 -224.220343) (xy 123.603589 -224.17894)
			(xy 123.638799 -224.142496) (xy 123.67917 -224.111867) (xy 123.723752 -224.087776) (xy 123.771495 -224.070789)
			(xy 123.796298 -224.065592) (xy 123.819158 -224.061274) (xy 124.023882 -223.706436) (xy 124.016262 -223.684338)
			(xy 124.007631 -223.657991) (xy 123.99831 -223.603344) (xy 123.99772 -223.575626) (xy 123.998228 -223.549719)
			(xy 124.006334 -223.498542) (xy 124.022346 -223.449263) (xy 124.045869 -223.403096) (xy 124.076325 -223.361177)
			(xy 124.112963 -223.324539) (xy 124.154882 -223.294083) (xy 124.201049 -223.27056) (xy 124.250328 -223.254548)
			(xy 124.301505 -223.246442) (xy 124.353319 -223.246442) (xy 124.404496 -223.254548) (xy 124.453775 -223.27056)
			(xy 124.499942 -223.294083) (xy 124.541861 -223.324539) (xy 124.578499 -223.361177) (xy 124.608955 -223.403096)
			(xy 124.632478 -223.449263) (xy 124.64849 -223.498542) (xy 124.656596 -223.549719) (xy 124.657104 -223.575626)
			(xy 124.656687 -223.600992) (xy 124.648934 -223.651127) (xy 124.633585 -223.69948) (xy 124.611003 -223.744908)
			(xy 124.581722 -223.786336) (xy 124.546434 -223.822783) (xy 124.505975 -223.853388) (xy 124.461301 -223.877427)
			(xy 124.413469 -223.894332) (xy 124.388626 -223.899476) (xy 124.365766 -223.903794) (xy 124.161042 -224.258632)
			(xy 124.168916 -224.280476) (xy 124.17749 -224.306896) (xy 124.18669 -224.36167) (xy 124.187204 -224.389442)
			(xy 124.468128 -224.389442) (xy 124.468636 -224.363555) (xy 124.476735 -224.312417) (xy 124.492734 -224.263177)
			(xy 124.51624 -224.217045) (xy 124.546672 -224.175158) (xy 124.583282 -224.138548) (xy 124.625169 -224.108116)
			(xy 124.671301 -224.08461) (xy 124.720541 -224.068611) (xy 124.771679 -224.060512) (xy 124.823453 -224.060512)
			(xy 124.874591 -224.068611) (xy 124.923831 -224.08461) (xy 124.969963 -224.108116) (xy 125.01185 -224.138548)
			(xy 125.04846 -224.175158) (xy 125.078892 -224.217045) (xy 125.102398 -224.263177) (xy 125.118397 -224.312417)
			(xy 125.126496 -224.363555) (xy 125.127004 -224.389442) (xy 125.407928 -224.389442) (xy 125.408335 -224.364105)
			(xy 125.416097 -224.314028) (xy 125.431429 -224.265728) (xy 125.45397 -224.220343) (xy 125.483189 -224.17894)
			(xy 125.518399 -224.142496) (xy 125.55877 -224.111867) (xy 125.603352 -224.087776) (xy 125.651095 -224.070789)
			(xy 125.675898 -224.065592) (xy 125.698758 -224.061274) (xy 125.903482 -223.706436) (xy 125.895862 -223.684338)
			(xy 125.887231 -223.657991) (xy 125.87791 -223.603344) (xy 125.87732 -223.575626) (xy 125.877828 -223.549719)
			(xy 125.885934 -223.498542) (xy 125.901946 -223.449263) (xy 125.925469 -223.403096) (xy 125.955925 -223.361177)
			(xy 125.992563 -223.324539) (xy 126.034482 -223.294083) (xy 126.080649 -223.27056) (xy 126.129928 -223.254548)
			(xy 126.181105 -223.246442) (xy 126.232919 -223.246442) (xy 126.284096 -223.254548) (xy 126.333375 -223.27056)
			(xy 126.379542 -223.294083) (xy 126.421461 -223.324539) (xy 126.458099 -223.361177) (xy 126.488555 -223.403096)
			(xy 126.512078 -223.449263) (xy 126.52809 -223.498542) (xy 126.536196 -223.549719) (xy 126.536704 -223.575626)
			(xy 126.536287 -223.600992) (xy 126.528534 -223.651127) (xy 126.513185 -223.69948) (xy 126.490603 -223.744908)
			(xy 126.461322 -223.786336) (xy 126.426034 -223.822783) (xy 126.385575 -223.853388) (xy 126.340901 -223.877427)
			(xy 126.293069 -223.894332) (xy 126.268226 -223.899476) (xy 126.245366 -223.903794) (xy 126.040642 -224.258632)
			(xy 126.048516 -224.280476) (xy 126.05709 -224.306896) (xy 126.06629 -224.36167) (xy 126.066804 -224.389442)
			(xy 126.347728 -224.389442) (xy 126.348236 -224.363555) (xy 126.356335 -224.312417) (xy 126.372334 -224.263177)
			(xy 126.39584 -224.217045) (xy 126.426272 -224.175158) (xy 126.462882 -224.138548) (xy 126.504769 -224.108116)
			(xy 126.550901 -224.08461) (xy 126.600141 -224.068611) (xy 126.651279 -224.060512) (xy 126.703053 -224.060512)
			(xy 126.754191 -224.068611) (xy 126.803431 -224.08461) (xy 126.849563 -224.108116) (xy 126.89145 -224.138548)
			(xy 126.92806 -224.175158) (xy 126.958492 -224.217045) (xy 126.981998 -224.263177) (xy 126.997997 -224.312417)
			(xy 127.006096 -224.363555) (xy 127.006604 -224.389442) (xy 127.287528 -224.389442) (xy 127.287935 -224.364105)
			(xy 127.295697 -224.314028) (xy 127.311029 -224.265728) (xy 127.33357 -224.220343) (xy 127.362789 -224.17894)
			(xy 127.397999 -224.142496) (xy 127.43837 -224.111867) (xy 127.482952 -224.087776) (xy 127.530695 -224.070789)
			(xy 127.555498 -224.065592) (xy 127.578358 -224.061274) (xy 127.783082 -223.706436) (xy 127.775462 -223.684338)
			(xy 127.766831 -223.657991) (xy 127.75751 -223.603344) (xy 127.75692 -223.575626) (xy 127.757428 -223.549719)
			(xy 127.765534 -223.498542) (xy 127.781546 -223.449263) (xy 127.805069 -223.403096) (xy 127.835525 -223.361177)
			(xy 127.872163 -223.324539) (xy 127.914082 -223.294083) (xy 127.960249 -223.27056) (xy 128.009528 -223.254548)
			(xy 128.060705 -223.246442) (xy 128.112519 -223.246442) (xy 128.163696 -223.254548) (xy 128.212975 -223.27056)
			(xy 128.259142 -223.294083) (xy 128.301061 -223.324539) (xy 128.337699 -223.361177) (xy 128.368155 -223.403096)
			(xy 128.391678 -223.449263) (xy 128.40769 -223.498542) (xy 128.415796 -223.549719) (xy 128.416304 -223.575626)
			(xy 128.415887 -223.600992) (xy 128.408134 -223.651127) (xy 128.392785 -223.69948) (xy 128.370203 -223.744908)
			(xy 128.340922 -223.786336) (xy 128.305634 -223.822783) (xy 128.265175 -223.853388) (xy 128.220501 -223.877427)
			(xy 128.172669 -223.894332) (xy 128.147826 -223.899476) (xy 128.124966 -223.903794) (xy 127.920242 -224.258632)
			(xy 127.928116 -224.280476) (xy 127.93669 -224.306896) (xy 127.94589 -224.36167) (xy 127.946404 -224.389442)
			(xy 128.227328 -224.389442) (xy 128.227836 -224.363555) (xy 128.235935 -224.312417) (xy 128.251934 -224.263177)
			(xy 128.27544 -224.217045) (xy 128.305872 -224.175158) (xy 128.342482 -224.138548) (xy 128.384369 -224.108116)
			(xy 128.430501 -224.08461) (xy 128.479741 -224.068611) (xy 128.530879 -224.060512) (xy 128.582653 -224.060512)
			(xy 128.633791 -224.068611) (xy 128.683031 -224.08461) (xy 128.729163 -224.108116) (xy 128.77105 -224.138548)
			(xy 128.80766 -224.175158) (xy 128.838092 -224.217045) (xy 128.861598 -224.263177) (xy 128.877597 -224.312417)
			(xy 128.885696 -224.363555) (xy 128.886204 -224.389442) (xy 129.167128 -224.389442) (xy 129.167535 -224.364105)
			(xy 129.175297 -224.314028) (xy 129.190629 -224.265728) (xy 129.21317 -224.220343) (xy 129.242389 -224.17894)
			(xy 129.277599 -224.142496) (xy 129.31797 -224.111867) (xy 129.362552 -224.087776) (xy 129.410295 -224.070789)
			(xy 129.435098 -224.065592) (xy 129.457958 -224.061274) (xy 129.662682 -223.706436) (xy 129.655062 -223.684338)
			(xy 129.646431 -223.657991) (xy 129.63711 -223.603344) (xy 129.63652 -223.575626) (xy 129.637028 -223.549719)
			(xy 129.645134 -223.498542) (xy 129.661146 -223.449263) (xy 129.684669 -223.403096) (xy 129.715125 -223.361177)
			(xy 129.751763 -223.324539) (xy 129.793682 -223.294083) (xy 129.839849 -223.27056) (xy 129.889128 -223.254548)
			(xy 129.940305 -223.246442) (xy 129.992119 -223.246442) (xy 130.043296 -223.254548) (xy 130.092575 -223.27056)
			(xy 130.138742 -223.294083) (xy 130.180661 -223.324539) (xy 130.217299 -223.361177) (xy 130.247755 -223.403096)
			(xy 130.271278 -223.449263) (xy 130.28729 -223.498542) (xy 130.295396 -223.549719) (xy 130.295904 -223.575626)
			(xy 130.295487 -223.600992) (xy 130.287734 -223.651127) (xy 130.272385 -223.69948) (xy 130.249803 -223.744908)
			(xy 130.220522 -223.786336) (xy 130.185234 -223.822783) (xy 130.144775 -223.853388) (xy 130.100101 -223.877427)
			(xy 130.052269 -223.894332) (xy 130.027426 -223.899476) (xy 130.004566 -223.903794) (xy 129.799842 -224.258632)
			(xy 129.807716 -224.280476) (xy 129.81629 -224.306896) (xy 129.82549 -224.36167) (xy 129.826004 -224.389442)
			(xy 130.106928 -224.389442) (xy 130.107436 -224.363555) (xy 130.115535 -224.312417) (xy 130.131534 -224.263177)
			(xy 130.15504 -224.217045) (xy 130.185472 -224.175158) (xy 130.222082 -224.138548) (xy 130.263969 -224.108116)
			(xy 130.310101 -224.08461) (xy 130.359341 -224.068611) (xy 130.410479 -224.060512) (xy 130.462253 -224.060512)
			(xy 130.513391 -224.068611) (xy 130.562631 -224.08461) (xy 130.608763 -224.108116) (xy 130.65065 -224.138548)
			(xy 130.68726 -224.175158) (xy 130.717692 -224.217045) (xy 130.741198 -224.263177) (xy 130.757197 -224.312417)
			(xy 130.765296 -224.363555) (xy 130.765804 -224.389442) (xy 131.986528 -224.389442) (xy 131.987036 -224.363555)
			(xy 131.995135 -224.312417) (xy 132.011134 -224.263177) (xy 132.03464 -224.217045) (xy 132.065072 -224.175158)
			(xy 132.101682 -224.138548) (xy 132.143569 -224.108116) (xy 132.189701 -224.08461) (xy 132.238941 -224.068611)
			(xy 132.290079 -224.060512) (xy 132.341853 -224.060512) (xy 132.392991 -224.068611) (xy 132.442231 -224.08461)
			(xy 132.488363 -224.108116) (xy 132.53025 -224.138548) (xy 132.56686 -224.175158) (xy 132.597292 -224.217045)
			(xy 132.620798 -224.263177) (xy 132.636797 -224.312417) (xy 132.644896 -224.363555) (xy 132.645404 -224.389442)
			(xy 341.394796 -224.389442) (xy 341.395229 -224.364106) (xy 341.40299 -224.314032) (xy 341.41832 -224.265734)
			(xy 341.440859 -224.22035) (xy 341.470075 -224.178949) (xy 341.505281 -224.142504) (xy 341.545648 -224.111874)
			(xy 341.590226 -224.087781) (xy 341.637965 -224.070791) (xy 341.662766 -224.065592) (xy 341.685626 -224.061274)
			(xy 341.89035 -223.706436) (xy 341.88273 -223.684338) (xy 341.874102 -223.657991) (xy 341.864779 -223.603344)
			(xy 341.864188 -223.575626) (xy 341.864696 -223.549719) (xy 341.872802 -223.498542) (xy 341.888814 -223.449263)
			(xy 341.912337 -223.403096) (xy 341.942793 -223.361177) (xy 341.979431 -223.324539) (xy 342.02135 -223.294083)
			(xy 342.067517 -223.27056) (xy 342.116796 -223.254548) (xy 342.167973 -223.246442) (xy 342.219787 -223.246442)
			(xy 342.270964 -223.254548) (xy 342.320243 -223.27056) (xy 342.36641 -223.294083) (xy 342.408329 -223.324539)
			(xy 342.444967 -223.361177) (xy 342.475423 -223.403096) (xy 342.498946 -223.449263) (xy 342.514958 -223.498542)
			(xy 342.523064 -223.549719) (xy 342.523572 -223.575626) (xy 342.523181 -223.600993) (xy 342.515428 -223.651131)
			(xy 342.500077 -223.699486) (xy 342.477492 -223.744915) (xy 342.448207 -223.786344) (xy 342.412916 -223.822791)
			(xy 342.372452 -223.853396) (xy 342.327774 -223.877433) (xy 342.279939 -223.894334) (xy 342.255094 -223.899476)
			(xy 342.232234 -223.903794) (xy 342.02751 -224.258632) (xy 342.035384 -224.280476) (xy 342.043957 -224.306897)
			(xy 342.053158 -224.36167) (xy 342.053672 -224.389442) (xy 342.334596 -224.389442) (xy 342.335104 -224.363555)
			(xy 342.343203 -224.312417) (xy 342.359202 -224.263177) (xy 342.382708 -224.217045) (xy 342.41314 -224.175158)
			(xy 342.44975 -224.138548) (xy 342.491637 -224.108116) (xy 342.537769 -224.08461) (xy 342.587009 -224.068611)
			(xy 342.638147 -224.060512) (xy 342.689921 -224.060512) (xy 342.741059 -224.068611) (xy 342.790299 -224.08461)
			(xy 342.836431 -224.108116) (xy 342.878318 -224.138548) (xy 342.914928 -224.175158) (xy 342.94536 -224.217045)
			(xy 342.968866 -224.263177) (xy 342.984865 -224.312417) (xy 342.992964 -224.363555) (xy 342.993472 -224.389442)
			(xy 343.274396 -224.389442) (xy 343.274829 -224.364106) (xy 343.28259 -224.314032) (xy 343.29792 -224.265734)
			(xy 343.320459 -224.22035) (xy 343.349675 -224.178949) (xy 343.384881 -224.142504) (xy 343.425248 -224.111874)
			(xy 343.469826 -224.087781) (xy 343.517565 -224.070791) (xy 343.542366 -224.065592) (xy 343.565226 -224.061274)
			(xy 343.76995 -223.706436) (xy 343.76233 -223.684338) (xy 343.753702 -223.657991) (xy 343.744379 -223.603344)
			(xy 343.743788 -223.575626) (xy 343.744296 -223.549719) (xy 343.752402 -223.498542) (xy 343.768414 -223.449263)
			(xy 343.791937 -223.403096) (xy 343.822393 -223.361177) (xy 343.859031 -223.324539) (xy 343.90095 -223.294083)
			(xy 343.947117 -223.27056) (xy 343.996396 -223.254548) (xy 344.047573 -223.246442) (xy 344.099387 -223.246442)
			(xy 344.150564 -223.254548) (xy 344.199843 -223.27056) (xy 344.24601 -223.294083) (xy 344.287929 -223.324539)
			(xy 344.324567 -223.361177) (xy 344.355023 -223.403096) (xy 344.378546 -223.449263) (xy 344.394558 -223.498542)
			(xy 344.402664 -223.549719) (xy 344.403172 -223.575626) (xy 344.402781 -223.600993) (xy 344.395028 -223.651131)
			(xy 344.379677 -223.699486) (xy 344.357092 -223.744915) (xy 344.327807 -223.786344) (xy 344.292516 -223.822791)
			(xy 344.252052 -223.853396) (xy 344.207374 -223.877433) (xy 344.159539 -223.894334) (xy 344.134694 -223.899476)
			(xy 344.111834 -223.903794) (xy 343.90711 -224.258632) (xy 343.914984 -224.280476) (xy 343.923557 -224.306897)
			(xy 343.932758 -224.36167) (xy 343.933272 -224.389442) (xy 344.214196 -224.389442) (xy 344.214704 -224.363555)
			(xy 344.222803 -224.312417) (xy 344.238802 -224.263177) (xy 344.262308 -224.217045) (xy 344.29274 -224.175158)
			(xy 344.32935 -224.138548) (xy 344.371237 -224.108116) (xy 344.417369 -224.08461) (xy 344.466609 -224.068611)
			(xy 344.517747 -224.060512) (xy 344.569521 -224.060512) (xy 344.620659 -224.068611) (xy 344.669899 -224.08461)
			(xy 344.716031 -224.108116) (xy 344.757918 -224.138548) (xy 344.794528 -224.175158) (xy 344.82496 -224.217045)
			(xy 344.848466 -224.263177) (xy 344.864465 -224.312417) (xy 344.872564 -224.363555) (xy 344.873072 -224.389442)
			(xy 345.153996 -224.389442) (xy 345.154429 -224.364106) (xy 345.16219 -224.314032) (xy 345.17752 -224.265734)
			(xy 345.200059 -224.22035) (xy 345.229275 -224.178949) (xy 345.264481 -224.142504) (xy 345.304848 -224.111874)
			(xy 345.349426 -224.087781) (xy 345.397165 -224.070791) (xy 345.421966 -224.065592) (xy 345.444826 -224.061274)
			(xy 345.64955 -223.706436) (xy 345.64193 -223.684338) (xy 345.633302 -223.657991) (xy 345.623979 -223.603344)
			(xy 345.623388 -223.575626) (xy 345.623896 -223.549719) (xy 345.632002 -223.498542) (xy 345.648014 -223.449263)
			(xy 345.671537 -223.403096) (xy 345.701993 -223.361177) (xy 345.738631 -223.324539) (xy 345.78055 -223.294083)
			(xy 345.826717 -223.27056) (xy 345.875996 -223.254548) (xy 345.927173 -223.246442) (xy 345.978987 -223.246442)
			(xy 346.030164 -223.254548) (xy 346.079443 -223.27056) (xy 346.12561 -223.294083) (xy 346.167529 -223.324539)
			(xy 346.204167 -223.361177) (xy 346.234623 -223.403096) (xy 346.258146 -223.449263) (xy 346.274158 -223.498542)
			(xy 346.282264 -223.549719) (xy 346.282772 -223.575626) (xy 346.282381 -223.600993) (xy 346.274628 -223.651131)
			(xy 346.259277 -223.699486) (xy 346.236692 -223.744915) (xy 346.207407 -223.786344) (xy 346.172116 -223.822791)
			(xy 346.131652 -223.853396) (xy 346.086974 -223.877433) (xy 346.039139 -223.894334) (xy 346.014294 -223.899476)
			(xy 345.991434 -223.903794) (xy 345.78671 -224.258632) (xy 345.794584 -224.280476) (xy 345.803157 -224.306897)
			(xy 345.812358 -224.36167) (xy 345.812872 -224.389442) (xy 346.093796 -224.389442) (xy 346.094304 -224.363555)
			(xy 346.102403 -224.312417) (xy 346.118402 -224.263177) (xy 346.141908 -224.217045) (xy 346.17234 -224.175158)
			(xy 346.20895 -224.138548) (xy 346.250837 -224.108116) (xy 346.296969 -224.08461) (xy 346.346209 -224.068611)
			(xy 346.397347 -224.060512) (xy 346.449121 -224.060512) (xy 346.500259 -224.068611) (xy 346.549499 -224.08461)
			(xy 346.595631 -224.108116) (xy 346.637518 -224.138548) (xy 346.674128 -224.175158) (xy 346.70456 -224.217045)
			(xy 346.728066 -224.263177) (xy 346.744065 -224.312417) (xy 346.752164 -224.363555) (xy 346.752672 -224.389442)
			(xy 347.033596 -224.389442) (xy 347.034029 -224.364106) (xy 347.04179 -224.314032) (xy 347.05712 -224.265734)
			(xy 347.079659 -224.22035) (xy 347.108875 -224.178949) (xy 347.144081 -224.142504) (xy 347.184448 -224.111874)
			(xy 347.229026 -224.087781) (xy 347.276765 -224.070791) (xy 347.301566 -224.065592) (xy 347.324426 -224.061274)
			(xy 347.52915 -223.706436) (xy 347.52153 -223.684338) (xy 347.512902 -223.657991) (xy 347.503579 -223.603344)
			(xy 347.502988 -223.575626) (xy 347.503496 -223.549719) (xy 347.511602 -223.498542) (xy 347.527614 -223.449263)
			(xy 347.551137 -223.403096) (xy 347.581593 -223.361177) (xy 347.618231 -223.324539) (xy 347.66015 -223.294083)
			(xy 347.706317 -223.27056) (xy 347.755596 -223.254548) (xy 347.806773 -223.246442) (xy 347.858587 -223.246442)
			(xy 347.909764 -223.254548) (xy 347.959043 -223.27056) (xy 348.00521 -223.294083) (xy 348.047129 -223.324539)
			(xy 348.083767 -223.361177) (xy 348.114223 -223.403096) (xy 348.137746 -223.449263) (xy 348.153758 -223.498542)
			(xy 348.161864 -223.549719) (xy 348.162372 -223.575626) (xy 348.161981 -223.600993) (xy 348.154228 -223.651131)
			(xy 348.138877 -223.699486) (xy 348.116292 -223.744915) (xy 348.087007 -223.786344) (xy 348.051716 -223.822791)
			(xy 348.011252 -223.853396) (xy 347.966574 -223.877433) (xy 347.918739 -223.894334) (xy 347.893894 -223.899476)
			(xy 347.871034 -223.903794) (xy 347.66631 -224.258632) (xy 347.674184 -224.280476) (xy 347.682757 -224.306897)
			(xy 347.691958 -224.36167) (xy 347.692472 -224.389442) (xy 347.973396 -224.389442) (xy 347.973904 -224.363555)
			(xy 347.982003 -224.312417) (xy 347.998002 -224.263177) (xy 348.021508 -224.217045) (xy 348.05194 -224.175158)
			(xy 348.08855 -224.138548) (xy 348.130437 -224.108116) (xy 348.176569 -224.08461) (xy 348.225809 -224.068611)
			(xy 348.276947 -224.060512) (xy 348.328721 -224.060512) (xy 348.379859 -224.068611) (xy 348.429099 -224.08461)
			(xy 348.475231 -224.108116) (xy 348.517118 -224.138548) (xy 348.553728 -224.175158) (xy 348.58416 -224.217045)
			(xy 348.607666 -224.263177) (xy 348.623665 -224.312417) (xy 348.631764 -224.363555) (xy 348.632272 -224.389442)
			(xy 348.913196 -224.389442) (xy 348.913629 -224.364106) (xy 348.92139 -224.314032) (xy 348.93672 -224.265734)
			(xy 348.959259 -224.22035) (xy 348.988475 -224.178949) (xy 349.023681 -224.142504) (xy 349.064048 -224.111874)
			(xy 349.108626 -224.087781) (xy 349.156365 -224.070791) (xy 349.181166 -224.065592) (xy 349.204026 -224.061274)
			(xy 349.40875 -223.706436) (xy 349.40113 -223.684338) (xy 349.392502 -223.657991) (xy 349.383179 -223.603344)
			(xy 349.382588 -223.575626) (xy 349.383096 -223.549719) (xy 349.391202 -223.498542) (xy 349.407214 -223.449263)
			(xy 349.430737 -223.403096) (xy 349.461193 -223.361177) (xy 349.497831 -223.324539) (xy 349.53975 -223.294083)
			(xy 349.585917 -223.27056) (xy 349.635196 -223.254548) (xy 349.686373 -223.246442) (xy 349.738187 -223.246442)
			(xy 349.789364 -223.254548) (xy 349.838643 -223.27056) (xy 349.88481 -223.294083) (xy 349.926729 -223.324539)
			(xy 349.963367 -223.361177) (xy 349.993823 -223.403096) (xy 350.017346 -223.449263) (xy 350.033358 -223.498542)
			(xy 350.041464 -223.549719) (xy 350.041972 -223.575626) (xy 350.041581 -223.600993) (xy 350.033828 -223.651131)
			(xy 350.018477 -223.699486) (xy 349.995892 -223.744915) (xy 349.966607 -223.786344) (xy 349.931316 -223.822791)
			(xy 349.890852 -223.853396) (xy 349.846174 -223.877433) (xy 349.798339 -223.894334) (xy 349.773494 -223.899476)
			(xy 349.750634 -223.903794) (xy 349.54591 -224.258632) (xy 349.553784 -224.280476) (xy 349.562357 -224.306897)
			(xy 349.571558 -224.36167) (xy 349.572072 -224.389442) (xy 349.852996 -224.389442) (xy 349.853504 -224.363555)
			(xy 349.861603 -224.312417) (xy 349.877602 -224.263177) (xy 349.901108 -224.217045) (xy 349.93154 -224.175158)
			(xy 349.96815 -224.138548) (xy 350.010037 -224.108116) (xy 350.056169 -224.08461) (xy 350.105409 -224.068611)
			(xy 350.156547 -224.060512) (xy 350.208321 -224.060512) (xy 350.259459 -224.068611) (xy 350.308699 -224.08461)
			(xy 350.354831 -224.108116) (xy 350.396718 -224.138548) (xy 350.433328 -224.175158) (xy 350.46376 -224.217045)
			(xy 350.487266 -224.263177) (xy 350.503265 -224.312417) (xy 350.511364 -224.363555) (xy 350.511872 -224.389442)
			(xy 350.792796 -224.389442) (xy 350.793229 -224.364106) (xy 350.80099 -224.314032) (xy 350.81632 -224.265734)
			(xy 350.838859 -224.22035) (xy 350.868075 -224.178949) (xy 350.903281 -224.142504) (xy 350.943648 -224.111874)
			(xy 350.988226 -224.087781) (xy 351.035965 -224.070791) (xy 351.060766 -224.065592) (xy 351.083626 -224.061274)
			(xy 351.28835 -223.706436) (xy 351.28073 -223.684338) (xy 351.272102 -223.657991) (xy 351.262779 -223.603344)
			(xy 351.262188 -223.575626) (xy 351.262696 -223.549719) (xy 351.270802 -223.498542) (xy 351.286814 -223.449263)
			(xy 351.310337 -223.403096) (xy 351.340793 -223.361177) (xy 351.377431 -223.324539) (xy 351.41935 -223.294083)
			(xy 351.465517 -223.27056) (xy 351.514796 -223.254548) (xy 351.565973 -223.246442) (xy 351.617787 -223.246442)
			(xy 351.668964 -223.254548) (xy 351.718243 -223.27056) (xy 351.76441 -223.294083) (xy 351.806329 -223.324539)
			(xy 351.842967 -223.361177) (xy 351.873423 -223.403096) (xy 351.896946 -223.449263) (xy 351.912958 -223.498542)
			(xy 351.921064 -223.549719) (xy 351.921572 -223.575626) (xy 351.921181 -223.600993) (xy 351.913428 -223.651131)
			(xy 351.898077 -223.699486) (xy 351.875492 -223.744915) (xy 351.846207 -223.786344) (xy 351.810916 -223.822791)
			(xy 351.770452 -223.853396) (xy 351.725774 -223.877433) (xy 351.677939 -223.894334) (xy 351.653094 -223.899476)
			(xy 351.630234 -223.903794) (xy 351.42551 -224.258632) (xy 351.433384 -224.280476) (xy 351.441957 -224.306897)
			(xy 351.451158 -224.36167) (xy 351.451672 -224.389442) (xy 351.732596 -224.389442) (xy 351.733104 -224.363555)
			(xy 351.741203 -224.312417) (xy 351.757202 -224.263177) (xy 351.780708 -224.217045) (xy 351.81114 -224.175158)
			(xy 351.84775 -224.138548) (xy 351.889637 -224.108116) (xy 351.935769 -224.08461) (xy 351.985009 -224.068611)
			(xy 352.036147 -224.060512) (xy 352.087921 -224.060512) (xy 352.139059 -224.068611) (xy 352.188299 -224.08461)
			(xy 352.234431 -224.108116) (xy 352.276318 -224.138548) (xy 352.312928 -224.175158) (xy 352.34336 -224.217045)
			(xy 352.366866 -224.263177) (xy 352.382865 -224.312417) (xy 352.390964 -224.363555) (xy 352.391472 -224.389442)
			(xy 352.672396 -224.389442) (xy 352.672829 -224.364106) (xy 352.68059 -224.314032) (xy 352.69592 -224.265734)
			(xy 352.718459 -224.22035) (xy 352.747675 -224.178949) (xy 352.782881 -224.142504) (xy 352.823248 -224.111874)
			(xy 352.867826 -224.087781) (xy 352.915565 -224.070791) (xy 352.940366 -224.065592) (xy 352.963226 -224.061274)
			(xy 353.16795 -223.706436) (xy 353.16033 -223.684338) (xy 353.151702 -223.657991) (xy 353.142379 -223.603344)
			(xy 353.141788 -223.575626) (xy 353.142296 -223.549719) (xy 353.150402 -223.498542) (xy 353.166414 -223.449263)
			(xy 353.189937 -223.403096) (xy 353.220393 -223.361177) (xy 353.257031 -223.324539) (xy 353.29895 -223.294083)
			(xy 353.345117 -223.27056) (xy 353.394396 -223.254548) (xy 353.445573 -223.246442) (xy 353.497387 -223.246442)
			(xy 353.548564 -223.254548) (xy 353.597843 -223.27056) (xy 353.64401 -223.294083) (xy 353.685929 -223.324539)
			(xy 353.722567 -223.361177) (xy 353.753023 -223.403096) (xy 353.776546 -223.449263) (xy 353.792558 -223.498542)
			(xy 353.800664 -223.549719) (xy 353.801172 -223.575626) (xy 353.800781 -223.600993) (xy 353.793028 -223.651131)
			(xy 353.777677 -223.699486) (xy 353.755092 -223.744915) (xy 353.725807 -223.786344) (xy 353.690516 -223.822791)
			(xy 353.650052 -223.853396) (xy 353.605374 -223.877433) (xy 353.557539 -223.894334) (xy 353.532694 -223.899476)
			(xy 353.509834 -223.903794) (xy 353.30511 -224.258632) (xy 353.312984 -224.280476) (xy 353.321557 -224.306897)
			(xy 353.330758 -224.36167) (xy 353.331272 -224.389442) (xy 353.612196 -224.389442) (xy 353.612704 -224.363555)
			(xy 353.620803 -224.312417) (xy 353.636802 -224.263177) (xy 353.660308 -224.217045) (xy 353.69074 -224.175158)
			(xy 353.72735 -224.138548) (xy 353.769237 -224.108116) (xy 353.815369 -224.08461) (xy 353.864609 -224.068611)
			(xy 353.915747 -224.060512) (xy 353.967521 -224.060512) (xy 354.018659 -224.068611) (xy 354.067899 -224.08461)
			(xy 354.114031 -224.108116) (xy 354.155918 -224.138548) (xy 354.192528 -224.175158) (xy 354.22296 -224.217045)
			(xy 354.246466 -224.263177) (xy 354.262465 -224.312417) (xy 354.270564 -224.363555) (xy 354.271072 -224.389442)
			(xy 354.551996 -224.389442) (xy 354.552429 -224.364106) (xy 354.56019 -224.314032) (xy 354.57552 -224.265734)
			(xy 354.598059 -224.22035) (xy 354.627275 -224.178949) (xy 354.662481 -224.142504) (xy 354.702848 -224.111874)
			(xy 354.747426 -224.087781) (xy 354.795165 -224.070791) (xy 354.819966 -224.065592) (xy 354.842826 -224.061274)
			(xy 355.04755 -223.706436) (xy 355.03993 -223.684338) (xy 355.031302 -223.657991) (xy 355.021979 -223.603344)
			(xy 355.021388 -223.575626) (xy 355.021896 -223.549719) (xy 355.030002 -223.498542) (xy 355.046014 -223.449263)
			(xy 355.069537 -223.403096) (xy 355.099993 -223.361177) (xy 355.136631 -223.324539) (xy 355.17855 -223.294083)
			(xy 355.224717 -223.27056) (xy 355.273996 -223.254548) (xy 355.325173 -223.246442) (xy 355.376987 -223.246442)
			(xy 355.428164 -223.254548) (xy 355.477443 -223.27056) (xy 355.52361 -223.294083) (xy 355.565529 -223.324539)
			(xy 355.602167 -223.361177) (xy 355.632623 -223.403096) (xy 355.656146 -223.449263) (xy 355.672158 -223.498542)
			(xy 355.680264 -223.549719) (xy 355.680772 -223.575626) (xy 355.680381 -223.600993) (xy 355.672628 -223.651131)
			(xy 355.657277 -223.699486) (xy 355.634692 -223.744915) (xy 355.605407 -223.786344) (xy 355.570116 -223.822791)
			(xy 355.529652 -223.853396) (xy 355.484974 -223.877433) (xy 355.437139 -223.894334) (xy 355.412294 -223.899476)
			(xy 355.389434 -223.903794) (xy 355.18471 -224.258632) (xy 355.192584 -224.280476) (xy 355.201157 -224.306897)
			(xy 355.210358 -224.36167) (xy 355.210872 -224.389442) (xy 355.491796 -224.389442) (xy 355.492304 -224.363555)
			(xy 355.500403 -224.312417) (xy 355.516402 -224.263177) (xy 355.539908 -224.217045) (xy 355.57034 -224.175158)
			(xy 355.60695 -224.138548) (xy 355.648837 -224.108116) (xy 355.694969 -224.08461) (xy 355.744209 -224.068611)
			(xy 355.795347 -224.060512) (xy 355.847121 -224.060512) (xy 355.898259 -224.068611) (xy 355.947499 -224.08461)
			(xy 355.993631 -224.108116) (xy 356.035518 -224.138548) (xy 356.072128 -224.175158) (xy 356.10256 -224.217045)
			(xy 356.126066 -224.263177) (xy 356.142065 -224.312417) (xy 356.150164 -224.363555) (xy 356.150672 -224.389442)
			(xy 356.431596 -224.389442) (xy 356.432029 -224.364106) (xy 356.43979 -224.314032) (xy 356.45512 -224.265734)
			(xy 356.477659 -224.22035) (xy 356.506875 -224.178949) (xy 356.542081 -224.142504) (xy 356.582448 -224.111874)
			(xy 356.627026 -224.087781) (xy 356.674765 -224.070791) (xy 356.699566 -224.065592) (xy 356.722426 -224.061274)
			(xy 356.92715 -223.706436) (xy 356.91953 -223.684338) (xy 356.910902 -223.657991) (xy 356.901579 -223.603344)
			(xy 356.900988 -223.575626) (xy 356.901496 -223.549719) (xy 356.909602 -223.498542) (xy 356.925614 -223.449263)
			(xy 356.949137 -223.403096) (xy 356.979593 -223.361177) (xy 357.016231 -223.324539) (xy 357.05815 -223.294083)
			(xy 357.104317 -223.27056) (xy 357.153596 -223.254548) (xy 357.204773 -223.246442) (xy 357.256587 -223.246442)
			(xy 357.307764 -223.254548) (xy 357.357043 -223.27056) (xy 357.40321 -223.294083) (xy 357.445129 -223.324539)
			(xy 357.481767 -223.361177) (xy 357.512223 -223.403096) (xy 357.535746 -223.449263) (xy 357.551758 -223.498542)
			(xy 357.559864 -223.549719) (xy 357.560372 -223.575626) (xy 357.559981 -223.600993) (xy 357.552228 -223.651131)
			(xy 357.536877 -223.699486) (xy 357.514292 -223.744915) (xy 357.485007 -223.786344) (xy 357.449716 -223.822791)
			(xy 357.409252 -223.853396) (xy 357.364574 -223.877433) (xy 357.316739 -223.894334) (xy 357.291894 -223.899476)
			(xy 357.269034 -223.903794) (xy 357.06431 -224.258632) (xy 357.072184 -224.280476) (xy 357.080757 -224.306897)
			(xy 357.089958 -224.36167) (xy 357.090472 -224.389442) (xy 357.371396 -224.389442) (xy 357.371904 -224.363555)
			(xy 357.380003 -224.312417) (xy 357.396002 -224.263177) (xy 357.419508 -224.217045) (xy 357.44994 -224.175158)
			(xy 357.48655 -224.138548) (xy 357.528437 -224.108116) (xy 357.574569 -224.08461) (xy 357.623809 -224.068611)
			(xy 357.674947 -224.060512) (xy 357.726721 -224.060512) (xy 357.777859 -224.068611) (xy 357.827099 -224.08461)
			(xy 357.873231 -224.108116) (xy 357.915118 -224.138548) (xy 357.951728 -224.175158) (xy 357.98216 -224.217045)
			(xy 358.005666 -224.263177) (xy 358.021665 -224.312417) (xy 358.029764 -224.363555) (xy 358.030272 -224.389442)
			(xy 358.311196 -224.389442) (xy 358.311629 -224.364106) (xy 358.31939 -224.314032) (xy 358.33472 -224.265734)
			(xy 358.357259 -224.22035) (xy 358.386475 -224.178949) (xy 358.421681 -224.142504) (xy 358.462048 -224.111874)
			(xy 358.506626 -224.087781) (xy 358.554365 -224.070791) (xy 358.579166 -224.065592) (xy 358.602026 -224.061274)
			(xy 358.80675 -223.706436) (xy 358.79913 -223.684338) (xy 358.790502 -223.657991) (xy 358.781179 -223.603344)
			(xy 358.780588 -223.575626) (xy 358.781096 -223.549719) (xy 358.789202 -223.498542) (xy 358.805214 -223.449263)
			(xy 358.828737 -223.403096) (xy 358.859193 -223.361177) (xy 358.895831 -223.324539) (xy 358.93775 -223.294083)
			(xy 358.983917 -223.27056) (xy 359.033196 -223.254548) (xy 359.084373 -223.246442) (xy 359.136187 -223.246442)
			(xy 359.187364 -223.254548) (xy 359.236643 -223.27056) (xy 359.28281 -223.294083) (xy 359.324729 -223.324539)
			(xy 359.361367 -223.361177) (xy 359.391823 -223.403096) (xy 359.415346 -223.449263) (xy 359.431358 -223.498542)
			(xy 359.439464 -223.549719) (xy 359.439972 -223.575626) (xy 359.439581 -223.600993) (xy 359.431828 -223.651131)
			(xy 359.416477 -223.699486) (xy 359.393892 -223.744915) (xy 359.364607 -223.786344) (xy 359.329316 -223.822791)
			(xy 359.288852 -223.853396) (xy 359.244174 -223.877433) (xy 359.196339 -223.894334) (xy 359.171494 -223.899476)
			(xy 359.148634 -223.903794) (xy 358.94391 -224.258632) (xy 358.951784 -224.280476) (xy 358.960357 -224.306897)
			(xy 358.969558 -224.36167) (xy 358.970072 -224.389442) (xy 359.250996 -224.389442) (xy 359.251504 -224.363555)
			(xy 359.259603 -224.312417) (xy 359.275602 -224.263177) (xy 359.299108 -224.217045) (xy 359.32954 -224.175158)
			(xy 359.36615 -224.138548) (xy 359.408037 -224.108116) (xy 359.454169 -224.08461) (xy 359.503409 -224.068611)
			(xy 359.554547 -224.060512) (xy 359.606321 -224.060512) (xy 359.657459 -224.068611) (xy 359.706699 -224.08461)
			(xy 359.752831 -224.108116) (xy 359.794718 -224.138548) (xy 359.831328 -224.175158) (xy 359.86176 -224.217045)
			(xy 359.885266 -224.263177) (xy 359.901265 -224.312417) (xy 359.909364 -224.363555) (xy 359.909872 -224.389442)
			(xy 360.190796 -224.389442) (xy 360.191229 -224.364106) (xy 360.19899 -224.314032) (xy 360.21432 -224.265734)
			(xy 360.236859 -224.22035) (xy 360.266075 -224.178949) (xy 360.301281 -224.142504) (xy 360.341648 -224.111874)
			(xy 360.386226 -224.087781) (xy 360.433965 -224.070791) (xy 360.458766 -224.065592) (xy 360.481626 -224.061274)
			(xy 360.68635 -223.706436) (xy 360.67873 -223.684338) (xy 360.670102 -223.657991) (xy 360.660779 -223.603344)
			(xy 360.660188 -223.575626) (xy 360.660696 -223.549719) (xy 360.668802 -223.498542) (xy 360.684814 -223.449263)
			(xy 360.708337 -223.403096) (xy 360.738793 -223.361177) (xy 360.775431 -223.324539) (xy 360.81735 -223.294083)
			(xy 360.863517 -223.27056) (xy 360.912796 -223.254548) (xy 360.963973 -223.246442) (xy 361.015787 -223.246442)
			(xy 361.066964 -223.254548) (xy 361.116243 -223.27056) (xy 361.16241 -223.294083) (xy 361.204329 -223.324539)
			(xy 361.240967 -223.361177) (xy 361.271423 -223.403096) (xy 361.294946 -223.449263) (xy 361.310958 -223.498542)
			(xy 361.319064 -223.549719) (xy 361.319572 -223.575626) (xy 361.319181 -223.600993) (xy 361.311428 -223.651131)
			(xy 361.296077 -223.699486) (xy 361.273492 -223.744915) (xy 361.244207 -223.786344) (xy 361.208916 -223.822791)
			(xy 361.168452 -223.853396) (xy 361.123774 -223.877433) (xy 361.075939 -223.894334) (xy 361.051094 -223.899476)
			(xy 361.028234 -223.903794) (xy 360.82351 -224.258632) (xy 360.831384 -224.280476) (xy 360.839957 -224.306897)
			(xy 360.849158 -224.36167) (xy 360.849672 -224.389442) (xy 361.130596 -224.389442) (xy 361.131104 -224.363555)
			(xy 361.139203 -224.312417) (xy 361.155202 -224.263177) (xy 361.178708 -224.217045) (xy 361.20914 -224.175158)
			(xy 361.24575 -224.138548) (xy 361.287637 -224.108116) (xy 361.333769 -224.08461) (xy 361.383009 -224.068611)
			(xy 361.434147 -224.060512) (xy 361.485921 -224.060512) (xy 361.537059 -224.068611) (xy 361.586299 -224.08461)
			(xy 361.632431 -224.108116) (xy 361.674318 -224.138548) (xy 361.710928 -224.175158) (xy 361.74136 -224.217045)
			(xy 361.764866 -224.263177) (xy 361.780865 -224.312417) (xy 361.788964 -224.363555) (xy 361.789472 -224.389442)
			(xy 362.070396 -224.389442) (xy 362.070829 -224.364106) (xy 362.07859 -224.314032) (xy 362.09392 -224.265734)
			(xy 362.116459 -224.22035) (xy 362.145675 -224.178949) (xy 362.180881 -224.142504) (xy 362.221248 -224.111874)
			(xy 362.265826 -224.087781) (xy 362.313565 -224.070791) (xy 362.338366 -224.065592) (xy 362.361226 -224.061274)
			(xy 362.566204 -223.706182) (xy 362.558584 -223.684084) (xy 362.550064 -223.657913) (xy 362.540871 -223.603651)
			(xy 362.540296 -223.576134) (xy 362.540296 -223.575626) (xy 362.540804 -223.549739) (xy 362.548903 -223.498601)
			(xy 362.564902 -223.449361) (xy 362.588408 -223.403229) (xy 362.61884 -223.361342) (xy 362.65545 -223.324732)
			(xy 362.697337 -223.2943) (xy 362.743469 -223.270794) (xy 362.792709 -223.254795) (xy 362.843847 -223.246696)
			(xy 362.895621 -223.246696) (xy 362.946759 -223.254795) (xy 362.995999 -223.270794) (xy 363.042131 -223.2943)
			(xy 363.084018 -223.324732) (xy 363.120628 -223.361342) (xy 363.15106 -223.403229) (xy 363.174566 -223.449361)
			(xy 363.190565 -223.498601) (xy 363.198664 -223.549739) (xy 363.199172 -223.575626) (xy 363.198781 -223.600993)
			(xy 363.191028 -223.651131) (xy 363.175677 -223.699486) (xy 363.153092 -223.744915) (xy 363.123807 -223.786344)
			(xy 363.088516 -223.822791) (xy 363.048052 -223.853396) (xy 363.003374 -223.877433) (xy 362.955539 -223.894334)
			(xy 362.930694 -223.899476) (xy 362.907834 -223.903794) (xy 362.70311 -224.258632) (xy 362.710984 -224.280476)
			(xy 362.719557 -224.306897) (xy 362.728758 -224.36167) (xy 362.729272 -224.389442) (xy 363.010196 -224.389442)
			(xy 363.010704 -224.363555) (xy 363.018803 -224.312417) (xy 363.034802 -224.263177) (xy 363.058308 -224.217045)
			(xy 363.08874 -224.175158) (xy 363.12535 -224.138548) (xy 363.167237 -224.108116) (xy 363.213369 -224.08461)
			(xy 363.262609 -224.068611) (xy 363.313747 -224.060512) (xy 363.365521 -224.060512) (xy 363.416659 -224.068611)
			(xy 363.465899 -224.08461) (xy 363.512031 -224.108116) (xy 363.553918 -224.138548) (xy 363.590528 -224.175158)
			(xy 363.62096 -224.217045) (xy 363.644466 -224.263177) (xy 363.660465 -224.312417) (xy 363.668564 -224.363555)
			(xy 363.669072 -224.389442) (xy 363.949996 -224.389442) (xy 363.950429 -224.364106) (xy 363.95819 -224.314032)
			(xy 363.97352 -224.265734) (xy 363.996059 -224.22035) (xy 364.025275 -224.178949) (xy 364.060481 -224.142504)
			(xy 364.100848 -224.111874) (xy 364.145426 -224.087781) (xy 364.193165 -224.070791) (xy 364.217966 -224.065592)
			(xy 364.240826 -224.061274) (xy 364.44555 -223.706436) (xy 364.43793 -223.684338) (xy 364.429302 -223.657991)
			(xy 364.419979 -223.603344) (xy 364.419388 -223.575626) (xy 364.419896 -223.549719) (xy 364.428002 -223.498542)
			(xy 364.444014 -223.449263) (xy 364.467537 -223.403096) (xy 364.497993 -223.361177) (xy 364.534631 -223.324539)
			(xy 364.57655 -223.294083) (xy 364.622717 -223.27056) (xy 364.671996 -223.254548) (xy 364.723173 -223.246442)
			(xy 364.774987 -223.246442) (xy 364.826164 -223.254548) (xy 364.875443 -223.27056) (xy 364.92161 -223.294083)
			(xy 364.963529 -223.324539) (xy 365.000167 -223.361177) (xy 365.030623 -223.403096) (xy 365.054146 -223.449263)
			(xy 365.070158 -223.498542) (xy 365.078264 -223.549719) (xy 365.078772 -223.575626) (xy 365.078381 -223.600993)
			(xy 365.070628 -223.651131) (xy 365.055277 -223.699486) (xy 365.032692 -223.744915) (xy 365.003407 -223.786344)
			(xy 364.968116 -223.822791) (xy 364.927652 -223.853396) (xy 364.882974 -223.877433) (xy 364.835139 -223.894334)
			(xy 364.810294 -223.899476) (xy 364.787434 -223.903794) (xy 364.58271 -224.258632) (xy 364.590584 -224.280476)
			(xy 364.599157 -224.306897) (xy 364.608358 -224.36167) (xy 364.608872 -224.389442) (xy 364.889796 -224.389442)
			(xy 364.890304 -224.363555) (xy 364.898403 -224.312417) (xy 364.914402 -224.263177) (xy 364.937908 -224.217045)
			(xy 364.96834 -224.175158) (xy 365.00495 -224.138548) (xy 365.046837 -224.108116) (xy 365.092969 -224.08461)
			(xy 365.142209 -224.068611) (xy 365.193347 -224.060512) (xy 365.245121 -224.060512) (xy 365.296259 -224.068611)
			(xy 365.345499 -224.08461) (xy 365.391631 -224.108116) (xy 365.433518 -224.138548) (xy 365.470128 -224.175158)
			(xy 365.50056 -224.217045) (xy 365.524066 -224.263177) (xy 365.540065 -224.312417) (xy 365.548164 -224.363555)
			(xy 365.548672 -224.389442) (xy 365.829596 -224.389442) (xy 365.830029 -224.364106) (xy 365.83779 -224.314032)
			(xy 365.85312 -224.265734) (xy 365.875659 -224.22035) (xy 365.904875 -224.178949) (xy 365.940081 -224.142504)
			(xy 365.980448 -224.111874) (xy 366.025026 -224.087781) (xy 366.072765 -224.070791) (xy 366.097566 -224.065592)
			(xy 366.120426 -224.061274) (xy 366.32515 -223.706436) (xy 366.31753 -223.684338) (xy 366.308902 -223.657991)
			(xy 366.299579 -223.603344) (xy 366.298988 -223.575626) (xy 366.299496 -223.549719) (xy 366.307602 -223.498542)
			(xy 366.323614 -223.449263) (xy 366.347137 -223.403096) (xy 366.377593 -223.361177) (xy 366.414231 -223.324539)
			(xy 366.45615 -223.294083) (xy 366.502317 -223.27056) (xy 366.551596 -223.254548) (xy 366.602773 -223.246442)
			(xy 366.654587 -223.246442) (xy 366.705764 -223.254548) (xy 366.755043 -223.27056) (xy 366.80121 -223.294083)
			(xy 366.843129 -223.324539) (xy 366.879767 -223.361177) (xy 366.910223 -223.403096) (xy 366.933746 -223.449263)
			(xy 366.949758 -223.498542) (xy 366.957864 -223.549719) (xy 366.958372 -223.575626) (xy 366.957981 -223.600993)
			(xy 366.950228 -223.651131) (xy 366.934877 -223.699486) (xy 366.912292 -223.744915) (xy 366.883007 -223.786344)
			(xy 366.847716 -223.822791) (xy 366.807252 -223.853396) (xy 366.762574 -223.877433) (xy 366.714739 -223.894334)
			(xy 366.689894 -223.899476) (xy 366.667034 -223.903794) (xy 366.46231 -224.258632) (xy 366.470184 -224.280476)
			(xy 366.478757 -224.306897) (xy 366.487958 -224.36167) (xy 366.488472 -224.389442) (xy 366.769396 -224.389442)
			(xy 366.769904 -224.363555) (xy 366.778003 -224.312417) (xy 366.794002 -224.263177) (xy 366.817508 -224.217045)
			(xy 366.84794 -224.175158) (xy 366.88455 -224.138548) (xy 366.926437 -224.108116) (xy 366.972569 -224.08461)
			(xy 367.021809 -224.068611) (xy 367.072947 -224.060512) (xy 367.124721 -224.060512) (xy 367.175859 -224.068611)
			(xy 367.225099 -224.08461) (xy 367.271231 -224.108116) (xy 367.313118 -224.138548) (xy 367.349728 -224.175158)
			(xy 367.38016 -224.217045) (xy 367.403666 -224.263177) (xy 367.419665 -224.312417) (xy 367.427764 -224.363555)
			(xy 367.428272 -224.389442) (xy 367.709196 -224.389442) (xy 367.709629 -224.364106) (xy 367.71739 -224.314032)
			(xy 367.73272 -224.265734) (xy 367.755259 -224.22035) (xy 367.784475 -224.178949) (xy 367.819681 -224.142504)
			(xy 367.860048 -224.111874) (xy 367.904626 -224.087781) (xy 367.952365 -224.070791) (xy 367.977166 -224.065592)
			(xy 368.000026 -224.061274) (xy 368.20475 -223.706436) (xy 368.19713 -223.684338) (xy 368.188502 -223.657991)
			(xy 368.179179 -223.603344) (xy 368.178588 -223.575626) (xy 368.179096 -223.549719) (xy 368.187202 -223.498542)
			(xy 368.203214 -223.449263) (xy 368.226737 -223.403096) (xy 368.257193 -223.361177) (xy 368.293831 -223.324539)
			(xy 368.33575 -223.294083) (xy 368.381917 -223.27056) (xy 368.431196 -223.254548) (xy 368.482373 -223.246442)
			(xy 368.534187 -223.246442) (xy 368.585364 -223.254548) (xy 368.634643 -223.27056) (xy 368.68081 -223.294083)
			(xy 368.722729 -223.324539) (xy 368.759367 -223.361177) (xy 368.789823 -223.403096) (xy 368.813346 -223.449263)
			(xy 368.829358 -223.498542) (xy 368.837464 -223.549719) (xy 368.837972 -223.575626) (xy 368.837581 -223.600993)
			(xy 368.829828 -223.651131) (xy 368.814477 -223.699486) (xy 368.791892 -223.744915) (xy 368.762607 -223.786344)
			(xy 368.727316 -223.822791) (xy 368.686852 -223.853396) (xy 368.642174 -223.877433) (xy 368.594339 -223.894334)
			(xy 368.569494 -223.899476) (xy 368.546634 -223.903794) (xy 368.34191 -224.258632) (xy 368.349784 -224.280476)
			(xy 368.358357 -224.306897) (xy 368.367558 -224.36167) (xy 368.368072 -224.389442) (xy 368.648996 -224.389442)
			(xy 368.649504 -224.363555) (xy 368.657603 -224.312417) (xy 368.673602 -224.263177) (xy 368.697108 -224.217045)
			(xy 368.72754 -224.175158) (xy 368.76415 -224.138548) (xy 368.806037 -224.108116) (xy 368.852169 -224.08461)
			(xy 368.901409 -224.068611) (xy 368.952547 -224.060512) (xy 369.004321 -224.060512) (xy 369.055459 -224.068611)
			(xy 369.104699 -224.08461) (xy 369.150831 -224.108116) (xy 369.192718 -224.138548) (xy 369.229328 -224.175158)
			(xy 369.25976 -224.217045) (xy 369.283266 -224.263177) (xy 369.299265 -224.312417) (xy 369.307364 -224.363555)
			(xy 369.307872 -224.389442) (xy 369.588796 -224.389442) (xy 369.589229 -224.364106) (xy 369.59699 -224.314032)
			(xy 369.61232 -224.265734) (xy 369.634859 -224.22035) (xy 369.664075 -224.178949) (xy 369.699281 -224.142504)
			(xy 369.739648 -224.111874) (xy 369.784226 -224.087781) (xy 369.831965 -224.070791) (xy 369.856766 -224.065592)
			(xy 369.879626 -224.061274) (xy 370.08435 -223.706436) (xy 370.07673 -223.684338) (xy 370.068102 -223.657991)
			(xy 370.058779 -223.603344) (xy 370.058188 -223.575626) (xy 370.058696 -223.549719) (xy 370.066802 -223.498542)
			(xy 370.082814 -223.449263) (xy 370.106337 -223.403096) (xy 370.136793 -223.361177) (xy 370.173431 -223.324539)
			(xy 370.21535 -223.294083) (xy 370.261517 -223.27056) (xy 370.310796 -223.254548) (xy 370.361973 -223.246442)
			(xy 370.413787 -223.246442) (xy 370.464964 -223.254548) (xy 370.514243 -223.27056) (xy 370.56041 -223.294083)
			(xy 370.602329 -223.324539) (xy 370.638967 -223.361177) (xy 370.669423 -223.403096) (xy 370.692946 -223.449263)
			(xy 370.708958 -223.498542) (xy 370.717064 -223.549719) (xy 370.717572 -223.575626) (xy 370.717181 -223.600993)
			(xy 370.709428 -223.651131) (xy 370.694077 -223.699486) (xy 370.671492 -223.744915) (xy 370.642207 -223.786344)
			(xy 370.606916 -223.822791) (xy 370.566452 -223.853396) (xy 370.521774 -223.877433) (xy 370.473939 -223.894334)
			(xy 370.449094 -223.899476) (xy 370.426234 -223.903794) (xy 370.22151 -224.258632) (xy 370.229384 -224.280476)
			(xy 370.237957 -224.306897) (xy 370.247158 -224.36167) (xy 370.247672 -224.389442) (xy 370.528596 -224.389442)
			(xy 370.529104 -224.363555) (xy 370.537203 -224.312417) (xy 370.553202 -224.263177) (xy 370.576708 -224.217045)
			(xy 370.60714 -224.175158) (xy 370.64375 -224.138548) (xy 370.685637 -224.108116) (xy 370.731769 -224.08461)
			(xy 370.781009 -224.068611) (xy 370.832147 -224.060512) (xy 370.883921 -224.060512) (xy 370.935059 -224.068611)
			(xy 370.984299 -224.08461) (xy 371.030431 -224.108116) (xy 371.072318 -224.138548) (xy 371.108928 -224.175158)
			(xy 371.13936 -224.217045) (xy 371.162866 -224.263177) (xy 371.178865 -224.312417) (xy 371.186964 -224.363555)
			(xy 371.187472 -224.389442) (xy 371.468396 -224.389442) (xy 371.468829 -224.364106) (xy 371.47659 -224.314032)
			(xy 371.49192 -224.265734) (xy 371.514459 -224.22035) (xy 371.543675 -224.178949) (xy 371.578881 -224.142504)
			(xy 371.619248 -224.111874) (xy 371.663826 -224.087781) (xy 371.711565 -224.070791) (xy 371.736366 -224.065592)
			(xy 371.759226 -224.061274) (xy 371.96395 -223.706436) (xy 371.95633 -223.684338) (xy 371.947702 -223.657991)
			(xy 371.938379 -223.603344) (xy 371.937788 -223.575626) (xy 371.938296 -223.549719) (xy 371.946402 -223.498542)
			(xy 371.962414 -223.449263) (xy 371.985937 -223.403096) (xy 372.016393 -223.361177) (xy 372.053031 -223.324539)
			(xy 372.09495 -223.294083) (xy 372.141117 -223.27056) (xy 372.190396 -223.254548) (xy 372.241573 -223.246442)
			(xy 372.293387 -223.246442) (xy 372.344564 -223.254548) (xy 372.393843 -223.27056) (xy 372.44001 -223.294083)
			(xy 372.481929 -223.324539) (xy 372.518567 -223.361177) (xy 372.549023 -223.403096) (xy 372.572546 -223.449263)
			(xy 372.588558 -223.498542) (xy 372.596664 -223.549719) (xy 372.597172 -223.575626) (xy 372.596781 -223.600993)
			(xy 372.589028 -223.651131) (xy 372.573677 -223.699486) (xy 372.551092 -223.744915) (xy 372.521807 -223.786344)
			(xy 372.486516 -223.822791) (xy 372.446052 -223.853396) (xy 372.401374 -223.877433) (xy 372.353539 -223.894334)
			(xy 372.328694 -223.899476) (xy 372.305834 -223.903794) (xy 372.10111 -224.258632) (xy 372.108984 -224.280476)
			(xy 372.117557 -224.306897) (xy 372.126758 -224.36167) (xy 372.127272 -224.389442) (xy 372.408196 -224.389442)
			(xy 372.408704 -224.363555) (xy 372.416803 -224.312417) (xy 372.432802 -224.263177) (xy 372.456308 -224.217045)
			(xy 372.48674 -224.175158) (xy 372.52335 -224.138548) (xy 372.565237 -224.108116) (xy 372.611369 -224.08461)
			(xy 372.660609 -224.068611) (xy 372.711747 -224.060512) (xy 372.763521 -224.060512) (xy 372.814659 -224.068611)
			(xy 372.863899 -224.08461) (xy 372.910031 -224.108116) (xy 372.951918 -224.138548) (xy 372.988528 -224.175158)
			(xy 373.01896 -224.217045) (xy 373.042466 -224.263177) (xy 373.058465 -224.312417) (xy 373.066564 -224.363555)
			(xy 373.067072 -224.389442) (xy 373.347996 -224.389442) (xy 373.348429 -224.364106) (xy 373.35619 -224.314032)
			(xy 373.37152 -224.265734) (xy 373.394059 -224.22035) (xy 373.423275 -224.178949) (xy 373.458481 -224.142504)
			(xy 373.498848 -224.111874) (xy 373.543426 -224.087781) (xy 373.591165 -224.070791) (xy 373.615966 -224.065592)
			(xy 373.638826 -224.061274) (xy 373.84355 -223.706436) (xy 373.83593 -223.684338) (xy 373.827302 -223.657991)
			(xy 373.817979 -223.603344) (xy 373.817388 -223.575626) (xy 373.817896 -223.549719) (xy 373.826002 -223.498542)
			(xy 373.842014 -223.449263) (xy 373.865537 -223.403096) (xy 373.895993 -223.361177) (xy 373.932631 -223.324539)
			(xy 373.97455 -223.294083) (xy 374.020717 -223.27056) (xy 374.069996 -223.254548) (xy 374.121173 -223.246442)
			(xy 374.172987 -223.246442) (xy 374.224164 -223.254548) (xy 374.273443 -223.27056) (xy 374.31961 -223.294083)
			(xy 374.361529 -223.324539) (xy 374.398167 -223.361177) (xy 374.428623 -223.403096) (xy 374.452146 -223.449263)
			(xy 374.468158 -223.498542) (xy 374.476264 -223.549719) (xy 374.476772 -223.575626) (xy 374.476381 -223.600993)
			(xy 374.468628 -223.651131) (xy 374.453277 -223.699486) (xy 374.430692 -223.744915) (xy 374.401407 -223.786344)
			(xy 374.366116 -223.822791) (xy 374.325652 -223.853396) (xy 374.280974 -223.877433) (xy 374.233139 -223.894334)
			(xy 374.208294 -223.899476) (xy 374.185434 -223.903794) (xy 373.98071 -224.258632) (xy 373.988584 -224.280476)
			(xy 373.997157 -224.306897) (xy 374.006358 -224.36167) (xy 374.006872 -224.389442) (xy 374.287796 -224.389442)
			(xy 374.288304 -224.363555) (xy 374.296403 -224.312417) (xy 374.312402 -224.263177) (xy 374.335908 -224.217045)
			(xy 374.36634 -224.175158) (xy 374.40295 -224.138548) (xy 374.444837 -224.108116) (xy 374.490969 -224.08461)
			(xy 374.540209 -224.068611) (xy 374.591347 -224.060512) (xy 374.643121 -224.060512) (xy 374.694259 -224.068611)
			(xy 374.743499 -224.08461) (xy 374.789631 -224.108116) (xy 374.831518 -224.138548) (xy 374.868128 -224.175158)
			(xy 374.89856 -224.217045) (xy 374.922066 -224.263177) (xy 374.938065 -224.312417) (xy 374.946164 -224.363555)
			(xy 374.946672 -224.389442) (xy 375.227596 -224.389442) (xy 375.228029 -224.364106) (xy 375.23579 -224.314032)
			(xy 375.25112 -224.265734) (xy 375.273659 -224.22035) (xy 375.302875 -224.178949) (xy 375.338081 -224.142504)
			(xy 375.378448 -224.111874) (xy 375.423026 -224.087781) (xy 375.470765 -224.070791) (xy 375.495566 -224.065592)
			(xy 375.518426 -224.061274) (xy 375.72315 -223.706436) (xy 375.71553 -223.684338) (xy 375.706902 -223.657991)
			(xy 375.697579 -223.603344) (xy 375.696988 -223.575626) (xy 375.697496 -223.549719) (xy 375.705602 -223.498542)
			(xy 375.721614 -223.449263) (xy 375.745137 -223.403096) (xy 375.775593 -223.361177) (xy 375.812231 -223.324539)
			(xy 375.85415 -223.294083) (xy 375.900317 -223.27056) (xy 375.949596 -223.254548) (xy 376.000773 -223.246442)
			(xy 376.052587 -223.246442) (xy 376.103764 -223.254548) (xy 376.153043 -223.27056) (xy 376.19921 -223.294083)
			(xy 376.241129 -223.324539) (xy 376.277767 -223.361177) (xy 376.308223 -223.403096) (xy 376.331746 -223.449263)
			(xy 376.347758 -223.498542) (xy 376.355864 -223.549719) (xy 376.356372 -223.575626) (xy 376.355981 -223.600993)
			(xy 376.348228 -223.651131) (xy 376.332877 -223.699486) (xy 376.310292 -223.744915) (xy 376.281007 -223.786344)
			(xy 376.245716 -223.822791) (xy 376.205252 -223.853396) (xy 376.160574 -223.877433) (xy 376.112739 -223.894334)
			(xy 376.087894 -223.899476) (xy 376.065034 -223.903794) (xy 375.86031 -224.258632) (xy 375.868184 -224.280476)
			(xy 375.876757 -224.306897) (xy 375.885958 -224.36167) (xy 375.886472 -224.389442) (xy 376.167396 -224.389442)
			(xy 376.167904 -224.363555) (xy 376.176003 -224.312417) (xy 376.192002 -224.263177) (xy 376.215508 -224.217045)
			(xy 376.24594 -224.175158) (xy 376.28255 -224.138548) (xy 376.324437 -224.108116) (xy 376.370569 -224.08461)
			(xy 376.419809 -224.068611) (xy 376.470947 -224.060512) (xy 376.522721 -224.060512) (xy 376.573859 -224.068611)
			(xy 376.623099 -224.08461) (xy 376.669231 -224.108116) (xy 376.711118 -224.138548) (xy 376.747728 -224.175158)
			(xy 376.77816 -224.217045) (xy 376.801666 -224.263177) (xy 376.817665 -224.312417) (xy 376.825764 -224.363555)
			(xy 376.826272 -224.389442) (xy 377.107196 -224.389442) (xy 377.107629 -224.364106) (xy 377.11539 -224.314032)
			(xy 377.13072 -224.265734) (xy 377.153259 -224.22035) (xy 377.182475 -224.178949) (xy 377.217681 -224.142504)
			(xy 377.258048 -224.111874) (xy 377.302626 -224.087781) (xy 377.350365 -224.070791) (xy 377.375166 -224.065592)
			(xy 377.398026 -224.061274) (xy 377.60275 -223.706436) (xy 377.59513 -223.684338) (xy 377.586502 -223.657991)
			(xy 377.577179 -223.603344) (xy 377.576588 -223.575626) (xy 377.577096 -223.549719) (xy 377.585202 -223.498542)
			(xy 377.601214 -223.449263) (xy 377.624737 -223.403096) (xy 377.655193 -223.361177) (xy 377.691831 -223.324539)
			(xy 377.73375 -223.294083) (xy 377.779917 -223.27056) (xy 377.829196 -223.254548) (xy 377.880373 -223.246442)
			(xy 377.932187 -223.246442) (xy 377.983364 -223.254548) (xy 378.032643 -223.27056) (xy 378.07881 -223.294083)
			(xy 378.120729 -223.324539) (xy 378.157367 -223.361177) (xy 378.187823 -223.403096) (xy 378.211346 -223.449263)
			(xy 378.227358 -223.498542) (xy 378.235464 -223.549719) (xy 378.235972 -223.575626) (xy 378.235581 -223.600993)
			(xy 378.227828 -223.651131) (xy 378.212477 -223.699486) (xy 378.189892 -223.744915) (xy 378.160607 -223.786344)
			(xy 378.125316 -223.822791) (xy 378.084852 -223.853396) (xy 378.040174 -223.877433) (xy 377.992339 -223.894334)
			(xy 377.967494 -223.899476) (xy 377.944634 -223.903794) (xy 377.73991 -224.258632) (xy 377.747784 -224.280476)
			(xy 377.756357 -224.306897) (xy 377.765558 -224.36167) (xy 377.766072 -224.389442) (xy 378.046996 -224.389442)
			(xy 378.047504 -224.363555) (xy 378.055603 -224.312417) (xy 378.071602 -224.263177) (xy 378.095108 -224.217045)
			(xy 378.12554 -224.175158) (xy 378.16215 -224.138548) (xy 378.204037 -224.108116) (xy 378.250169 -224.08461)
			(xy 378.299409 -224.068611) (xy 378.350547 -224.060512) (xy 378.402321 -224.060512) (xy 378.453459 -224.068611)
			(xy 378.502699 -224.08461) (xy 378.548831 -224.108116) (xy 378.590718 -224.138548) (xy 378.627328 -224.175158)
			(xy 378.65776 -224.217045) (xy 378.681266 -224.263177) (xy 378.697265 -224.312417) (xy 378.705364 -224.363555)
			(xy 378.705872 -224.389442) (xy 379.926596 -224.389442) (xy 379.927104 -224.363555) (xy 379.935203 -224.312417)
			(xy 379.951202 -224.263177) (xy 379.974708 -224.217045) (xy 380.00514 -224.175158) (xy 380.04175 -224.138548)
			(xy 380.083637 -224.108116) (xy 380.129769 -224.08461) (xy 380.179009 -224.068611) (xy 380.230147 -224.060512)
			(xy 380.281921 -224.060512) (xy 380.333059 -224.068611) (xy 380.382299 -224.08461) (xy 380.428431 -224.108116)
			(xy 380.470318 -224.138548) (xy 380.506928 -224.175158) (xy 380.53736 -224.217045) (xy 380.560866 -224.263177)
			(xy 380.576865 -224.312417) (xy 380.584964 -224.363555) (xy 380.585472 -224.389442) (xy 380.584925 -224.417149)
			(xy 380.575741 -224.471796) (xy 380.567184 -224.498154) (xy 380.55931 -224.520252) (xy 380.764288 -224.87509)
			(xy 380.787148 -224.879408) (xy 380.811971 -224.884565) (xy 380.859751 -224.90152) (xy 380.904371 -224.925592)
			(xy 380.944778 -224.956214) (xy 380.980019 -224.992662) (xy 381.009263 -225.034077) (xy 381.031819 -225.079482)
			(xy 381.047156 -225.127806) (xy 381.054911 -225.177908) (xy 381.055372 -225.203258) (xy 381.054864 -225.229165)
			(xy 381.046758 -225.280342) (xy 381.030746 -225.329621) (xy 381.007223 -225.375788) (xy 380.976767 -225.417707)
			(xy 380.940129 -225.454345) (xy 380.89821 -225.484801) (xy 380.852043 -225.508324) (xy 380.802764 -225.524336)
			(xy 380.751587 -225.532442) (xy 380.699773 -225.532442) (xy 380.648596 -225.524336) (xy 380.599317 -225.508324)
			(xy 380.55315 -225.484801) (xy 380.511231 -225.454345) (xy 380.474593 -225.417707) (xy 380.444137 -225.375788)
			(xy 380.420614 -225.329621) (xy 380.404602 -225.280342) (xy 380.396496 -225.229165) (xy 380.395988 -225.203258)
			(xy 380.396597 -225.175541) (xy 380.40591 -225.120895) (xy 380.41453 -225.094546) (xy 380.422404 -225.072448)
			(xy 380.217426 -224.71761) (xy 380.194566 -224.713292) (xy 380.169748 -224.708169) (xy 380.122005 -224.691172)
			(xy 380.077426 -224.667071) (xy 380.03706 -224.636431) (xy 380.001857 -224.599976) (xy 379.972648 -224.558564)
			(xy 379.950119 -224.51317) (xy 379.934801 -224.464863) (xy 379.927055 -224.414781) (xy 379.926596 -224.389442)
			(xy 378.705872 -224.389442) (xy 378.705325 -224.417149) (xy 378.696141 -224.471796) (xy 378.687584 -224.498154)
			(xy 378.67971 -224.520252) (xy 378.884688 -224.87509) (xy 378.907548 -224.879408) (xy 378.932371 -224.884565)
			(xy 378.980151 -224.90152) (xy 379.024771 -224.925592) (xy 379.065178 -224.956214) (xy 379.100419 -224.992662)
			(xy 379.129663 -225.034077) (xy 379.152219 -225.079482) (xy 379.167556 -225.127806) (xy 379.175311 -225.177908)
			(xy 379.175772 -225.203258) (xy 379.175264 -225.229165) (xy 379.167158 -225.280342) (xy 379.151146 -225.329621)
			(xy 379.127623 -225.375788) (xy 379.097167 -225.417707) (xy 379.060529 -225.454345) (xy 379.01861 -225.484801)
			(xy 378.972443 -225.508324) (xy 378.923164 -225.524336) (xy 378.871987 -225.532442) (xy 378.820173 -225.532442)
			(xy 378.768996 -225.524336) (xy 378.719717 -225.508324) (xy 378.67355 -225.484801) (xy 378.631631 -225.454345)
			(xy 378.594993 -225.417707) (xy 378.564537 -225.375788) (xy 378.541014 -225.329621) (xy 378.525002 -225.280342)
			(xy 378.516896 -225.229165) (xy 378.516388 -225.203258) (xy 378.516997 -225.175541) (xy 378.52631 -225.120895)
			(xy 378.53493 -225.094546) (xy 378.542804 -225.072448) (xy 378.337826 -224.71761) (xy 378.314966 -224.713292)
			(xy 378.290148 -224.708169) (xy 378.242405 -224.691172) (xy 378.197826 -224.667071) (xy 378.15746 -224.636431)
			(xy 378.122257 -224.599976) (xy 378.093048 -224.558564) (xy 378.070519 -224.51317) (xy 378.055201 -224.464863)
			(xy 378.047455 -224.414781) (xy 378.046996 -224.389442) (xy 377.766072 -224.389442) (xy 377.765564 -224.415329)
			(xy 377.757465 -224.466467) (xy 377.741466 -224.515707) (xy 377.71796 -224.561839) (xy 377.687528 -224.603726)
			(xy 377.650918 -224.640336) (xy 377.609031 -224.670768) (xy 377.562899 -224.694274) (xy 377.513659 -224.710273)
			(xy 377.462521 -224.718372) (xy 377.410747 -224.718372) (xy 377.359609 -224.710273) (xy 377.310369 -224.694274)
			(xy 377.264237 -224.670768) (xy 377.22235 -224.640336) (xy 377.18574 -224.603726) (xy 377.155308 -224.561839)
			(xy 377.131802 -224.515707) (xy 377.115803 -224.466467) (xy 377.107704 -224.415329) (xy 377.107196 -224.389442)
			(xy 376.826272 -224.389442) (xy 376.825725 -224.417149) (xy 376.816541 -224.471796) (xy 376.807984 -224.498154)
			(xy 376.80011 -224.520252) (xy 377.005088 -224.87509) (xy 377.027948 -224.879408) (xy 377.052771 -224.884565)
			(xy 377.100551 -224.90152) (xy 377.145171 -224.925592) (xy 377.185578 -224.956214) (xy 377.220819 -224.992662)
			(xy 377.250063 -225.034077) (xy 377.272619 -225.079482) (xy 377.287956 -225.127806) (xy 377.295711 -225.177908)
			(xy 377.296172 -225.203258) (xy 377.295664 -225.229165) (xy 377.287558 -225.280342) (xy 377.271546 -225.329621)
			(xy 377.248023 -225.375788) (xy 377.217567 -225.417707) (xy 377.180929 -225.454345) (xy 377.13901 -225.484801)
			(xy 377.092843 -225.508324) (xy 377.043564 -225.524336) (xy 376.992387 -225.532442) (xy 376.940573 -225.532442)
			(xy 376.889396 -225.524336) (xy 376.840117 -225.508324) (xy 376.79395 -225.484801) (xy 376.752031 -225.454345)
			(xy 376.715393 -225.417707) (xy 376.684937 -225.375788) (xy 376.661414 -225.329621) (xy 376.645402 -225.280342)
			(xy 376.637296 -225.229165) (xy 376.636788 -225.203258) (xy 376.637397 -225.175541) (xy 376.64671 -225.120895)
			(xy 376.65533 -225.094546) (xy 376.663204 -225.072448) (xy 376.458226 -224.71761) (xy 376.435366 -224.713292)
			(xy 376.410548 -224.708169) (xy 376.362805 -224.691172) (xy 376.318226 -224.667071) (xy 376.27786 -224.636431)
			(xy 376.242657 -224.599976) (xy 376.213448 -224.558564) (xy 376.190919 -224.51317) (xy 376.175601 -224.464863)
			(xy 376.167855 -224.414781) (xy 376.167396 -224.389442) (xy 375.886472 -224.389442) (xy 375.885964 -224.415329)
			(xy 375.877865 -224.466467) (xy 375.861866 -224.515707) (xy 375.83836 -224.561839) (xy 375.807928 -224.603726)
			(xy 375.771318 -224.640336) (xy 375.729431 -224.670768) (xy 375.683299 -224.694274) (xy 375.634059 -224.710273)
			(xy 375.582921 -224.718372) (xy 375.531147 -224.718372) (xy 375.480009 -224.710273) (xy 375.430769 -224.694274)
			(xy 375.384637 -224.670768) (xy 375.34275 -224.640336) (xy 375.30614 -224.603726) (xy 375.275708 -224.561839)
			(xy 375.252202 -224.515707) (xy 375.236203 -224.466467) (xy 375.228104 -224.415329) (xy 375.227596 -224.389442)
			(xy 374.946672 -224.389442) (xy 374.946125 -224.417149) (xy 374.936941 -224.471796) (xy 374.928384 -224.498154)
			(xy 374.92051 -224.520252) (xy 375.125488 -224.87509) (xy 375.148348 -224.879408) (xy 375.173171 -224.884565)
			(xy 375.220951 -224.90152) (xy 375.265571 -224.925592) (xy 375.305978 -224.956214) (xy 375.341219 -224.992662)
			(xy 375.370463 -225.034077) (xy 375.393019 -225.079482) (xy 375.408356 -225.127806) (xy 375.416111 -225.177908)
			(xy 375.416572 -225.203258) (xy 375.416064 -225.229165) (xy 375.407958 -225.280342) (xy 375.391946 -225.329621)
			(xy 375.368423 -225.375788) (xy 375.337967 -225.417707) (xy 375.301329 -225.454345) (xy 375.25941 -225.484801)
			(xy 375.213243 -225.508324) (xy 375.163964 -225.524336) (xy 375.112787 -225.532442) (xy 375.060973 -225.532442)
			(xy 375.009796 -225.524336) (xy 374.960517 -225.508324) (xy 374.91435 -225.484801) (xy 374.872431 -225.454345)
			(xy 374.835793 -225.417707) (xy 374.805337 -225.375788) (xy 374.781814 -225.329621) (xy 374.765802 -225.280342)
			(xy 374.757696 -225.229165) (xy 374.757188 -225.203258) (xy 374.757797 -225.175541) (xy 374.76711 -225.120895)
			(xy 374.77573 -225.094546) (xy 374.783604 -225.072448) (xy 374.578626 -224.71761) (xy 374.555766 -224.713292)
			(xy 374.530948 -224.708169) (xy 374.483205 -224.691172) (xy 374.438626 -224.667071) (xy 374.39826 -224.636431)
			(xy 374.363057 -224.599976) (xy 374.333848 -224.558564) (xy 374.311319 -224.51317) (xy 374.296001 -224.464863)
			(xy 374.288255 -224.414781) (xy 374.287796 -224.389442) (xy 374.006872 -224.389442) (xy 374.006364 -224.415329)
			(xy 373.998265 -224.466467) (xy 373.982266 -224.515707) (xy 373.95876 -224.561839) (xy 373.928328 -224.603726)
			(xy 373.891718 -224.640336) (xy 373.849831 -224.670768) (xy 373.803699 -224.694274) (xy 373.754459 -224.710273)
			(xy 373.703321 -224.718372) (xy 373.651547 -224.718372) (xy 373.600409 -224.710273) (xy 373.551169 -224.694274)
			(xy 373.505037 -224.670768) (xy 373.46315 -224.640336) (xy 373.42654 -224.603726) (xy 373.396108 -224.561839)
			(xy 373.372602 -224.515707) (xy 373.356603 -224.466467) (xy 373.348504 -224.415329) (xy 373.347996 -224.389442)
			(xy 373.067072 -224.389442) (xy 373.066525 -224.417149) (xy 373.057341 -224.471796) (xy 373.048784 -224.498154)
			(xy 373.04091 -224.520252) (xy 373.245888 -224.87509) (xy 373.268748 -224.879408) (xy 373.293571 -224.884565)
			(xy 373.341351 -224.90152) (xy 373.385971 -224.925592) (xy 373.426378 -224.956214) (xy 373.461619 -224.992662)
			(xy 373.490863 -225.034077) (xy 373.513419 -225.079482) (xy 373.528756 -225.127806) (xy 373.536511 -225.177908)
			(xy 373.536972 -225.203258) (xy 373.536464 -225.229165) (xy 373.528358 -225.280342) (xy 373.512346 -225.329621)
			(xy 373.488823 -225.375788) (xy 373.458367 -225.417707) (xy 373.421729 -225.454345) (xy 373.37981 -225.484801)
			(xy 373.333643 -225.508324) (xy 373.284364 -225.524336) (xy 373.233187 -225.532442) (xy 373.181373 -225.532442)
			(xy 373.130196 -225.524336) (xy 373.080917 -225.508324) (xy 373.03475 -225.484801) (xy 372.992831 -225.454345)
			(xy 372.956193 -225.417707) (xy 372.925737 -225.375788) (xy 372.902214 -225.329621) (xy 372.886202 -225.280342)
			(xy 372.878096 -225.229165) (xy 372.877588 -225.203258) (xy 372.878197 -225.175541) (xy 372.88751 -225.120895)
			(xy 372.89613 -225.094546) (xy 372.904004 -225.072448) (xy 372.699026 -224.71761) (xy 372.676166 -224.713292)
			(xy 372.651348 -224.708169) (xy 372.603605 -224.691172) (xy 372.559026 -224.667071) (xy 372.51866 -224.636431)
			(xy 372.483457 -224.599976) (xy 372.454248 -224.558564) (xy 372.431719 -224.51317) (xy 372.416401 -224.464863)
			(xy 372.408655 -224.414781) (xy 372.408196 -224.389442) (xy 372.127272 -224.389442) (xy 372.126764 -224.415329)
			(xy 372.118665 -224.466467) (xy 372.102666 -224.515707) (xy 372.07916 -224.561839) (xy 372.048728 -224.603726)
			(xy 372.012118 -224.640336) (xy 371.970231 -224.670768) (xy 371.924099 -224.694274) (xy 371.874859 -224.710273)
			(xy 371.823721 -224.718372) (xy 371.771947 -224.718372) (xy 371.720809 -224.710273) (xy 371.671569 -224.694274)
			(xy 371.625437 -224.670768) (xy 371.58355 -224.640336) (xy 371.54694 -224.603726) (xy 371.516508 -224.561839)
			(xy 371.493002 -224.515707) (xy 371.477003 -224.466467) (xy 371.468904 -224.415329) (xy 371.468396 -224.389442)
			(xy 371.187472 -224.389442) (xy 371.186925 -224.417149) (xy 371.177741 -224.471796) (xy 371.169184 -224.498154)
			(xy 371.16131 -224.520252) (xy 371.366288 -224.87509) (xy 371.389148 -224.879408) (xy 371.413971 -224.884565)
			(xy 371.461751 -224.90152) (xy 371.506371 -224.925592) (xy 371.546778 -224.956214) (xy 371.582019 -224.992662)
			(xy 371.611263 -225.034077) (xy 371.633819 -225.079482) (xy 371.649156 -225.127806) (xy 371.656911 -225.177908)
			(xy 371.657372 -225.203258) (xy 371.656864 -225.229165) (xy 371.648758 -225.280342) (xy 371.632746 -225.329621)
			(xy 371.609223 -225.375788) (xy 371.578767 -225.417707) (xy 371.542129 -225.454345) (xy 371.50021 -225.484801)
			(xy 371.454043 -225.508324) (xy 371.404764 -225.524336) (xy 371.353587 -225.532442) (xy 371.301773 -225.532442)
			(xy 371.250596 -225.524336) (xy 371.201317 -225.508324) (xy 371.15515 -225.484801) (xy 371.113231 -225.454345)
			(xy 371.076593 -225.417707) (xy 371.046137 -225.375788) (xy 371.022614 -225.329621) (xy 371.006602 -225.280342)
			(xy 370.998496 -225.229165) (xy 370.997988 -225.203258) (xy 370.998597 -225.175541) (xy 371.00791 -225.120895)
			(xy 371.01653 -225.094546) (xy 371.024404 -225.072448) (xy 370.819426 -224.71761) (xy 370.796566 -224.713292)
			(xy 370.771748 -224.708169) (xy 370.724005 -224.691172) (xy 370.679426 -224.667071) (xy 370.63906 -224.636431)
			(xy 370.603857 -224.599976) (xy 370.574648 -224.558564) (xy 370.552119 -224.51317) (xy 370.536801 -224.464863)
			(xy 370.529055 -224.414781) (xy 370.528596 -224.389442) (xy 370.247672 -224.389442) (xy 370.247164 -224.415329)
			(xy 370.239065 -224.466467) (xy 370.223066 -224.515707) (xy 370.19956 -224.561839) (xy 370.169128 -224.603726)
			(xy 370.132518 -224.640336) (xy 370.090631 -224.670768) (xy 370.044499 -224.694274) (xy 369.995259 -224.710273)
			(xy 369.944121 -224.718372) (xy 369.892347 -224.718372) (xy 369.841209 -224.710273) (xy 369.791969 -224.694274)
			(xy 369.745837 -224.670768) (xy 369.70395 -224.640336) (xy 369.66734 -224.603726) (xy 369.636908 -224.561839)
			(xy 369.613402 -224.515707) (xy 369.597403 -224.466467) (xy 369.589304 -224.415329) (xy 369.588796 -224.389442)
			(xy 369.307872 -224.389442) (xy 369.307325 -224.417149) (xy 369.298141 -224.471796) (xy 369.289584 -224.498154)
			(xy 369.28171 -224.520252) (xy 369.486688 -224.87509) (xy 369.509548 -224.879408) (xy 369.534371 -224.884565)
			(xy 369.582151 -224.90152) (xy 369.626771 -224.925592) (xy 369.667178 -224.956214) (xy 369.702419 -224.992662)
			(xy 369.731663 -225.034077) (xy 369.754219 -225.079482) (xy 369.769556 -225.127806) (xy 369.777311 -225.177908)
			(xy 369.777772 -225.203258) (xy 369.777264 -225.229165) (xy 369.769158 -225.280342) (xy 369.753146 -225.329621)
			(xy 369.729623 -225.375788) (xy 369.699167 -225.417707) (xy 369.662529 -225.454345) (xy 369.62061 -225.484801)
			(xy 369.574443 -225.508324) (xy 369.525164 -225.524336) (xy 369.473987 -225.532442) (xy 369.422173 -225.532442)
			(xy 369.370996 -225.524336) (xy 369.321717 -225.508324) (xy 369.27555 -225.484801) (xy 369.233631 -225.454345)
			(xy 369.196993 -225.417707) (xy 369.166537 -225.375788) (xy 369.143014 -225.329621) (xy 369.127002 -225.280342)
			(xy 369.118896 -225.229165) (xy 369.118388 -225.203258) (xy 369.118997 -225.175541) (xy 369.12831 -225.120895)
			(xy 369.13693 -225.094546) (xy 369.144804 -225.072448) (xy 368.939826 -224.71761) (xy 368.916966 -224.713292)
			(xy 368.892148 -224.708169) (xy 368.844405 -224.691172) (xy 368.799826 -224.667071) (xy 368.75946 -224.636431)
			(xy 368.724257 -224.599976) (xy 368.695048 -224.558564) (xy 368.672519 -224.51317) (xy 368.657201 -224.464863)
			(xy 368.649455 -224.414781) (xy 368.648996 -224.389442) (xy 368.368072 -224.389442) (xy 368.367564 -224.415329)
			(xy 368.359465 -224.466467) (xy 368.343466 -224.515707) (xy 368.31996 -224.561839) (xy 368.289528 -224.603726)
			(xy 368.252918 -224.640336) (xy 368.211031 -224.670768) (xy 368.164899 -224.694274) (xy 368.115659 -224.710273)
			(xy 368.064521 -224.718372) (xy 368.012747 -224.718372) (xy 367.961609 -224.710273) (xy 367.912369 -224.694274)
			(xy 367.866237 -224.670768) (xy 367.82435 -224.640336) (xy 367.78774 -224.603726) (xy 367.757308 -224.561839)
			(xy 367.733802 -224.515707) (xy 367.717803 -224.466467) (xy 367.709704 -224.415329) (xy 367.709196 -224.389442)
			(xy 367.428272 -224.389442) (xy 367.427725 -224.417149) (xy 367.418541 -224.471796) (xy 367.409984 -224.498154)
			(xy 367.40211 -224.520252) (xy 367.607088 -224.87509) (xy 367.629948 -224.879408) (xy 367.654771 -224.884565)
			(xy 367.702551 -224.90152) (xy 367.747171 -224.925592) (xy 367.787578 -224.956214) (xy 367.822819 -224.992662)
			(xy 367.852063 -225.034077) (xy 367.874619 -225.079482) (xy 367.889956 -225.127806) (xy 367.897711 -225.177908)
			(xy 367.898172 -225.203258) (xy 367.897664 -225.229165) (xy 367.889558 -225.280342) (xy 367.873546 -225.329621)
			(xy 367.850023 -225.375788) (xy 367.819567 -225.417707) (xy 367.782929 -225.454345) (xy 367.74101 -225.484801)
			(xy 367.694843 -225.508324) (xy 367.645564 -225.524336) (xy 367.594387 -225.532442) (xy 367.542573 -225.532442)
			(xy 367.491396 -225.524336) (xy 367.442117 -225.508324) (xy 367.39595 -225.484801) (xy 367.354031 -225.454345)
			(xy 367.317393 -225.417707) (xy 367.286937 -225.375788) (xy 367.263414 -225.329621) (xy 367.247402 -225.280342)
			(xy 367.239296 -225.229165) (xy 367.238788 -225.203258) (xy 367.239397 -225.175541) (xy 367.24871 -225.120895)
			(xy 367.25733 -225.094546) (xy 367.265204 -225.072448) (xy 367.060226 -224.71761) (xy 367.037366 -224.713292)
			(xy 367.012548 -224.708169) (xy 366.964805 -224.691172) (xy 366.920226 -224.667071) (xy 366.87986 -224.636431)
			(xy 366.844657 -224.599976) (xy 366.815448 -224.558564) (xy 366.792919 -224.51317) (xy 366.777601 -224.464863)
			(xy 366.769855 -224.414781) (xy 366.769396 -224.389442) (xy 366.488472 -224.389442) (xy 366.487964 -224.415329)
			(xy 366.479865 -224.466467) (xy 366.463866 -224.515707) (xy 366.44036 -224.561839) (xy 366.409928 -224.603726)
			(xy 366.373318 -224.640336) (xy 366.331431 -224.670768) (xy 366.285299 -224.694274) (xy 366.236059 -224.710273)
			(xy 366.184921 -224.718372) (xy 366.133147 -224.718372) (xy 366.082009 -224.710273) (xy 366.032769 -224.694274)
			(xy 365.986637 -224.670768) (xy 365.94475 -224.640336) (xy 365.90814 -224.603726) (xy 365.877708 -224.561839)
			(xy 365.854202 -224.515707) (xy 365.838203 -224.466467) (xy 365.830104 -224.415329) (xy 365.829596 -224.389442)
			(xy 365.548672 -224.389442) (xy 365.548125 -224.417149) (xy 365.538941 -224.471796) (xy 365.530384 -224.498154)
			(xy 365.52251 -224.520252) (xy 365.727488 -224.87509) (xy 365.750348 -224.879408) (xy 365.775171 -224.884565)
			(xy 365.822951 -224.90152) (xy 365.867571 -224.925592) (xy 365.907978 -224.956214) (xy 365.943219 -224.992662)
			(xy 365.972463 -225.034077) (xy 365.995019 -225.079482) (xy 366.010356 -225.127806) (xy 366.018111 -225.177908)
			(xy 366.018572 -225.203258) (xy 366.018064 -225.229165) (xy 366.009958 -225.280342) (xy 365.993946 -225.329621)
			(xy 365.970423 -225.375788) (xy 365.939967 -225.417707) (xy 365.903329 -225.454345) (xy 365.86141 -225.484801)
			(xy 365.815243 -225.508324) (xy 365.765964 -225.524336) (xy 365.714787 -225.532442) (xy 365.662973 -225.532442)
			(xy 365.611796 -225.524336) (xy 365.562517 -225.508324) (xy 365.51635 -225.484801) (xy 365.474431 -225.454345)
			(xy 365.437793 -225.417707) (xy 365.407337 -225.375788) (xy 365.383814 -225.329621) (xy 365.367802 -225.280342)
			(xy 365.359696 -225.229165) (xy 365.359188 -225.203258) (xy 365.359797 -225.175541) (xy 365.36911 -225.120895)
			(xy 365.37773 -225.094546) (xy 365.385604 -225.072448) (xy 365.180626 -224.71761) (xy 365.157766 -224.713292)
			(xy 365.132948 -224.708169) (xy 365.085205 -224.691172) (xy 365.040626 -224.667071) (xy 365.00026 -224.636431)
			(xy 364.965057 -224.599976) (xy 364.935848 -224.558564) (xy 364.913319 -224.51317) (xy 364.898001 -224.464863)
			(xy 364.890255 -224.414781) (xy 364.889796 -224.389442) (xy 364.608872 -224.389442) (xy 364.608364 -224.415329)
			(xy 364.600265 -224.466467) (xy 364.584266 -224.515707) (xy 364.56076 -224.561839) (xy 364.530328 -224.603726)
			(xy 364.493718 -224.640336) (xy 364.451831 -224.670768) (xy 364.405699 -224.694274) (xy 364.356459 -224.710273)
			(xy 364.305321 -224.718372) (xy 364.253547 -224.718372) (xy 364.202409 -224.710273) (xy 364.153169 -224.694274)
			(xy 364.107037 -224.670768) (xy 364.06515 -224.640336) (xy 364.02854 -224.603726) (xy 363.998108 -224.561839)
			(xy 363.974602 -224.515707) (xy 363.958603 -224.466467) (xy 363.950504 -224.415329) (xy 363.949996 -224.389442)
			(xy 363.669072 -224.389442) (xy 363.668525 -224.417149) (xy 363.659341 -224.471796) (xy 363.650784 -224.498154)
			(xy 363.64291 -224.520252) (xy 363.847888 -224.87509) (xy 363.870748 -224.879408) (xy 363.895571 -224.884565)
			(xy 363.943351 -224.90152) (xy 363.987971 -224.925592) (xy 364.028378 -224.956214) (xy 364.063619 -224.992662)
			(xy 364.092863 -225.034077) (xy 364.115419 -225.079482) (xy 364.130756 -225.127806) (xy 364.138511 -225.177908)
			(xy 364.138972 -225.203258) (xy 364.138464 -225.229165) (xy 364.130358 -225.280342) (xy 364.114346 -225.329621)
			(xy 364.090823 -225.375788) (xy 364.060367 -225.417707) (xy 364.023729 -225.454345) (xy 363.98181 -225.484801)
			(xy 363.935643 -225.508324) (xy 363.886364 -225.524336) (xy 363.835187 -225.532442) (xy 363.783373 -225.532442)
			(xy 363.732196 -225.524336) (xy 363.682917 -225.508324) (xy 363.63675 -225.484801) (xy 363.594831 -225.454345)
			(xy 363.558193 -225.417707) (xy 363.527737 -225.375788) (xy 363.504214 -225.329621) (xy 363.488202 -225.280342)
			(xy 363.480096 -225.229165) (xy 363.479588 -225.203258) (xy 363.480197 -225.175541) (xy 363.48951 -225.120895)
			(xy 363.49813 -225.094546) (xy 363.506004 -225.072448) (xy 363.301026 -224.71761) (xy 363.278166 -224.713292)
			(xy 363.253348 -224.708169) (xy 363.205605 -224.691172) (xy 363.161026 -224.667071) (xy 363.12066 -224.636431)
			(xy 363.085457 -224.599976) (xy 363.056248 -224.558564) (xy 363.033719 -224.51317) (xy 363.018401 -224.464863)
			(xy 363.010655 -224.414781) (xy 363.010196 -224.389442) (xy 362.729272 -224.389442) (xy 362.728764 -224.415329)
			(xy 362.720665 -224.466467) (xy 362.704666 -224.515707) (xy 362.68116 -224.561839) (xy 362.650728 -224.603726)
			(xy 362.614118 -224.640336) (xy 362.572231 -224.670768) (xy 362.526099 -224.694274) (xy 362.476859 -224.710273)
			(xy 362.425721 -224.718372) (xy 362.373947 -224.718372) (xy 362.322809 -224.710273) (xy 362.273569 -224.694274)
			(xy 362.227437 -224.670768) (xy 362.18555 -224.640336) (xy 362.14894 -224.603726) (xy 362.118508 -224.561839)
			(xy 362.095002 -224.515707) (xy 362.079003 -224.466467) (xy 362.070904 -224.415329) (xy 362.070396 -224.389442)
			(xy 361.789472 -224.389442) (xy 361.788925 -224.417149) (xy 361.779741 -224.471796) (xy 361.771184 -224.498154)
			(xy 361.76331 -224.520252) (xy 361.968288 -224.87509) (xy 361.991148 -224.879408) (xy 362.015971 -224.884565)
			(xy 362.063751 -224.90152) (xy 362.108371 -224.925592) (xy 362.148778 -224.956214) (xy 362.184019 -224.992662)
			(xy 362.213263 -225.034077) (xy 362.235819 -225.079482) (xy 362.251156 -225.127806) (xy 362.258911 -225.177908)
			(xy 362.259372 -225.203258) (xy 362.258864 -225.229165) (xy 362.250758 -225.280342) (xy 362.234746 -225.329621)
			(xy 362.211223 -225.375788) (xy 362.180767 -225.417707) (xy 362.144129 -225.454345) (xy 362.10221 -225.484801)
			(xy 362.056043 -225.508324) (xy 362.006764 -225.524336) (xy 361.955587 -225.532442) (xy 361.903773 -225.532442)
			(xy 361.852596 -225.524336) (xy 361.803317 -225.508324) (xy 361.75715 -225.484801) (xy 361.715231 -225.454345)
			(xy 361.678593 -225.417707) (xy 361.648137 -225.375788) (xy 361.624614 -225.329621) (xy 361.608602 -225.280342)
			(xy 361.600496 -225.229165) (xy 361.599988 -225.203258) (xy 361.600597 -225.175541) (xy 361.60991 -225.120895)
			(xy 361.61853 -225.094546) (xy 361.626404 -225.072448) (xy 361.421426 -224.71761) (xy 361.398566 -224.713292)
			(xy 361.373748 -224.708169) (xy 361.326005 -224.691172) (xy 361.281426 -224.667071) (xy 361.24106 -224.636431)
			(xy 361.205857 -224.599976) (xy 361.176648 -224.558564) (xy 361.154119 -224.51317) (xy 361.138801 -224.464863)
			(xy 361.131055 -224.414781) (xy 361.130596 -224.389442) (xy 360.849672 -224.389442) (xy 360.849164 -224.415329)
			(xy 360.841065 -224.466467) (xy 360.825066 -224.515707) (xy 360.80156 -224.561839) (xy 360.771128 -224.603726)
			(xy 360.734518 -224.640336) (xy 360.692631 -224.670768) (xy 360.646499 -224.694274) (xy 360.597259 -224.710273)
			(xy 360.546121 -224.718372) (xy 360.494347 -224.718372) (xy 360.443209 -224.710273) (xy 360.393969 -224.694274)
			(xy 360.347837 -224.670768) (xy 360.30595 -224.640336) (xy 360.26934 -224.603726) (xy 360.238908 -224.561839)
			(xy 360.215402 -224.515707) (xy 360.199403 -224.466467) (xy 360.191304 -224.415329) (xy 360.190796 -224.389442)
			(xy 359.909872 -224.389442) (xy 359.909325 -224.417149) (xy 359.900141 -224.471796) (xy 359.891584 -224.498154)
			(xy 359.88371 -224.520252) (xy 360.088688 -224.87509) (xy 360.111548 -224.879408) (xy 360.136371 -224.884565)
			(xy 360.184151 -224.90152) (xy 360.228771 -224.925592) (xy 360.269178 -224.956214) (xy 360.304419 -224.992662)
			(xy 360.333663 -225.034077) (xy 360.356219 -225.079482) (xy 360.371556 -225.127806) (xy 360.379311 -225.177908)
			(xy 360.379772 -225.203258) (xy 360.379264 -225.229165) (xy 360.371158 -225.280342) (xy 360.355146 -225.329621)
			(xy 360.331623 -225.375788) (xy 360.301167 -225.417707) (xy 360.264529 -225.454345) (xy 360.22261 -225.484801)
			(xy 360.176443 -225.508324) (xy 360.127164 -225.524336) (xy 360.075987 -225.532442) (xy 360.024173 -225.532442)
			(xy 359.972996 -225.524336) (xy 359.923717 -225.508324) (xy 359.87755 -225.484801) (xy 359.835631 -225.454345)
			(xy 359.798993 -225.417707) (xy 359.768537 -225.375788) (xy 359.745014 -225.329621) (xy 359.729002 -225.280342)
			(xy 359.720896 -225.229165) (xy 359.720388 -225.203258) (xy 359.720997 -225.175541) (xy 359.73031 -225.120895)
			(xy 359.73893 -225.094546) (xy 359.746804 -225.072448) (xy 359.541826 -224.71761) (xy 359.518966 -224.713292)
			(xy 359.494148 -224.708169) (xy 359.446405 -224.691172) (xy 359.401826 -224.667071) (xy 359.36146 -224.636431)
			(xy 359.326257 -224.599976) (xy 359.297048 -224.558564) (xy 359.274519 -224.51317) (xy 359.259201 -224.464863)
			(xy 359.251455 -224.414781) (xy 359.250996 -224.389442) (xy 358.970072 -224.389442) (xy 358.969564 -224.415329)
			(xy 358.961465 -224.466467) (xy 358.945466 -224.515707) (xy 358.92196 -224.561839) (xy 358.891528 -224.603726)
			(xy 358.854918 -224.640336) (xy 358.813031 -224.670768) (xy 358.766899 -224.694274) (xy 358.717659 -224.710273)
			(xy 358.666521 -224.718372) (xy 358.614747 -224.718372) (xy 358.563609 -224.710273) (xy 358.514369 -224.694274)
			(xy 358.468237 -224.670768) (xy 358.42635 -224.640336) (xy 358.38974 -224.603726) (xy 358.359308 -224.561839)
			(xy 358.335802 -224.515707) (xy 358.319803 -224.466467) (xy 358.311704 -224.415329) (xy 358.311196 -224.389442)
			(xy 358.030272 -224.389442) (xy 358.029725 -224.417149) (xy 358.020541 -224.471796) (xy 358.011984 -224.498154)
			(xy 358.00411 -224.520252) (xy 358.209088 -224.87509) (xy 358.231948 -224.879408) (xy 358.256771 -224.884565)
			(xy 358.304551 -224.90152) (xy 358.349171 -224.925592) (xy 358.389578 -224.956214) (xy 358.424819 -224.992662)
			(xy 358.454063 -225.034077) (xy 358.476619 -225.079482) (xy 358.491956 -225.127806) (xy 358.499711 -225.177908)
			(xy 358.500172 -225.203258) (xy 358.499664 -225.229165) (xy 358.491558 -225.280342) (xy 358.475546 -225.329621)
			(xy 358.452023 -225.375788) (xy 358.421567 -225.417707) (xy 358.384929 -225.454345) (xy 358.34301 -225.484801)
			(xy 358.296843 -225.508324) (xy 358.247564 -225.524336) (xy 358.196387 -225.532442) (xy 358.144573 -225.532442)
			(xy 358.093396 -225.524336) (xy 358.044117 -225.508324) (xy 357.99795 -225.484801) (xy 357.956031 -225.454345)
			(xy 357.919393 -225.417707) (xy 357.888937 -225.375788) (xy 357.865414 -225.329621) (xy 357.849402 -225.280342)
			(xy 357.841296 -225.229165) (xy 357.840788 -225.203258) (xy 357.841397 -225.175541) (xy 357.85071 -225.120895)
			(xy 357.85933 -225.094546) (xy 357.867204 -225.072448) (xy 357.662226 -224.71761) (xy 357.639366 -224.713292)
			(xy 357.614548 -224.708169) (xy 357.566805 -224.691172) (xy 357.522226 -224.667071) (xy 357.48186 -224.636431)
			(xy 357.446657 -224.599976) (xy 357.417448 -224.558564) (xy 357.394919 -224.51317) (xy 357.379601 -224.464863)
			(xy 357.371855 -224.414781) (xy 357.371396 -224.389442) (xy 357.090472 -224.389442) (xy 357.089964 -224.415329)
			(xy 357.081865 -224.466467) (xy 357.065866 -224.515707) (xy 357.04236 -224.561839) (xy 357.011928 -224.603726)
			(xy 356.975318 -224.640336) (xy 356.933431 -224.670768) (xy 356.887299 -224.694274) (xy 356.838059 -224.710273)
			(xy 356.786921 -224.718372) (xy 356.735147 -224.718372) (xy 356.684009 -224.710273) (xy 356.634769 -224.694274)
			(xy 356.588637 -224.670768) (xy 356.54675 -224.640336) (xy 356.51014 -224.603726) (xy 356.479708 -224.561839)
			(xy 356.456202 -224.515707) (xy 356.440203 -224.466467) (xy 356.432104 -224.415329) (xy 356.431596 -224.389442)
			(xy 356.150672 -224.389442) (xy 356.150125 -224.417149) (xy 356.140941 -224.471796) (xy 356.132384 -224.498154)
			(xy 356.12451 -224.520252) (xy 356.329488 -224.87509) (xy 356.352348 -224.879408) (xy 356.377171 -224.884565)
			(xy 356.424951 -224.90152) (xy 356.469571 -224.925592) (xy 356.509978 -224.956214) (xy 356.545219 -224.992662)
			(xy 356.574463 -225.034077) (xy 356.597019 -225.079482) (xy 356.612356 -225.127806) (xy 356.620111 -225.177908)
			(xy 356.620572 -225.203258) (xy 356.620064 -225.229165) (xy 356.611958 -225.280342) (xy 356.595946 -225.329621)
			(xy 356.572423 -225.375788) (xy 356.541967 -225.417707) (xy 356.505329 -225.454345) (xy 356.46341 -225.484801)
			(xy 356.417243 -225.508324) (xy 356.367964 -225.524336) (xy 356.316787 -225.532442) (xy 356.264973 -225.532442)
			(xy 356.213796 -225.524336) (xy 356.164517 -225.508324) (xy 356.11835 -225.484801) (xy 356.076431 -225.454345)
			(xy 356.039793 -225.417707) (xy 356.009337 -225.375788) (xy 355.985814 -225.329621) (xy 355.969802 -225.280342)
			(xy 355.961696 -225.229165) (xy 355.961188 -225.203258) (xy 355.961797 -225.175541) (xy 355.97111 -225.120895)
			(xy 355.97973 -225.094546) (xy 355.987604 -225.072448) (xy 355.782626 -224.71761) (xy 355.759766 -224.713292)
			(xy 355.734948 -224.708169) (xy 355.687205 -224.691172) (xy 355.642626 -224.667071) (xy 355.60226 -224.636431)
			(xy 355.567057 -224.599976) (xy 355.537848 -224.558564) (xy 355.515319 -224.51317) (xy 355.500001 -224.464863)
			(xy 355.492255 -224.414781) (xy 355.491796 -224.389442) (xy 355.210872 -224.389442) (xy 355.210364 -224.415329)
			(xy 355.202265 -224.466467) (xy 355.186266 -224.515707) (xy 355.16276 -224.561839) (xy 355.132328 -224.603726)
			(xy 355.095718 -224.640336) (xy 355.053831 -224.670768) (xy 355.007699 -224.694274) (xy 354.958459 -224.710273)
			(xy 354.907321 -224.718372) (xy 354.855547 -224.718372) (xy 354.804409 -224.710273) (xy 354.755169 -224.694274)
			(xy 354.709037 -224.670768) (xy 354.66715 -224.640336) (xy 354.63054 -224.603726) (xy 354.600108 -224.561839)
			(xy 354.576602 -224.515707) (xy 354.560603 -224.466467) (xy 354.552504 -224.415329) (xy 354.551996 -224.389442)
			(xy 354.271072 -224.389442) (xy 354.270525 -224.417149) (xy 354.261341 -224.471796) (xy 354.252784 -224.498154)
			(xy 354.24491 -224.520252) (xy 354.449888 -224.87509) (xy 354.472748 -224.879408) (xy 354.497571 -224.884565)
			(xy 354.545351 -224.90152) (xy 354.589971 -224.925592) (xy 354.630378 -224.956214) (xy 354.665619 -224.992662)
			(xy 354.694863 -225.034077) (xy 354.717419 -225.079482) (xy 354.732756 -225.127806) (xy 354.740511 -225.177908)
			(xy 354.740972 -225.203258) (xy 354.740464 -225.229165) (xy 354.732358 -225.280342) (xy 354.716346 -225.329621)
			(xy 354.692823 -225.375788) (xy 354.662367 -225.417707) (xy 354.625729 -225.454345) (xy 354.58381 -225.484801)
			(xy 354.537643 -225.508324) (xy 354.488364 -225.524336) (xy 354.437187 -225.532442) (xy 354.385373 -225.532442)
			(xy 354.334196 -225.524336) (xy 354.284917 -225.508324) (xy 354.23875 -225.484801) (xy 354.196831 -225.454345)
			(xy 354.160193 -225.417707) (xy 354.129737 -225.375788) (xy 354.106214 -225.329621) (xy 354.090202 -225.280342)
			(xy 354.082096 -225.229165) (xy 354.081588 -225.203258) (xy 354.082197 -225.175541) (xy 354.09151 -225.120895)
			(xy 354.10013 -225.094546) (xy 354.108004 -225.072448) (xy 353.903026 -224.71761) (xy 353.880166 -224.713292)
			(xy 353.855348 -224.708169) (xy 353.807605 -224.691172) (xy 353.763026 -224.667071) (xy 353.72266 -224.636431)
			(xy 353.687457 -224.599976) (xy 353.658248 -224.558564) (xy 353.635719 -224.51317) (xy 353.620401 -224.464863)
			(xy 353.612655 -224.414781) (xy 353.612196 -224.389442) (xy 353.331272 -224.389442) (xy 353.330764 -224.415329)
			(xy 353.322665 -224.466467) (xy 353.306666 -224.515707) (xy 353.28316 -224.561839) (xy 353.252728 -224.603726)
			(xy 353.216118 -224.640336) (xy 353.174231 -224.670768) (xy 353.128099 -224.694274) (xy 353.078859 -224.710273)
			(xy 353.027721 -224.718372) (xy 352.975947 -224.718372) (xy 352.924809 -224.710273) (xy 352.875569 -224.694274)
			(xy 352.829437 -224.670768) (xy 352.78755 -224.640336) (xy 352.75094 -224.603726) (xy 352.720508 -224.561839)
			(xy 352.697002 -224.515707) (xy 352.681003 -224.466467) (xy 352.672904 -224.415329) (xy 352.672396 -224.389442)
			(xy 352.391472 -224.389442) (xy 352.390925 -224.417149) (xy 352.381741 -224.471796) (xy 352.373184 -224.498154)
			(xy 352.36531 -224.520252) (xy 352.570288 -224.87509) (xy 352.593148 -224.879408) (xy 352.617971 -224.884565)
			(xy 352.665751 -224.90152) (xy 352.710371 -224.925592) (xy 352.750778 -224.956214) (xy 352.786019 -224.992662)
			(xy 352.815263 -225.034077) (xy 352.837819 -225.079482) (xy 352.853156 -225.127806) (xy 352.860911 -225.177908)
			(xy 352.861372 -225.203258) (xy 352.860864 -225.229165) (xy 352.852758 -225.280342) (xy 352.836746 -225.329621)
			(xy 352.813223 -225.375788) (xy 352.782767 -225.417707) (xy 352.746129 -225.454345) (xy 352.70421 -225.484801)
			(xy 352.658043 -225.508324) (xy 352.608764 -225.524336) (xy 352.557587 -225.532442) (xy 352.505773 -225.532442)
			(xy 352.454596 -225.524336) (xy 352.405317 -225.508324) (xy 352.35915 -225.484801) (xy 352.317231 -225.454345)
			(xy 352.280593 -225.417707) (xy 352.250137 -225.375788) (xy 352.226614 -225.329621) (xy 352.210602 -225.280342)
			(xy 352.202496 -225.229165) (xy 352.201988 -225.203258) (xy 352.202597 -225.175541) (xy 352.21191 -225.120895)
			(xy 352.22053 -225.094546) (xy 352.228404 -225.072448) (xy 352.023426 -224.71761) (xy 352.000566 -224.713292)
			(xy 351.975748 -224.708169) (xy 351.928005 -224.691172) (xy 351.883426 -224.667071) (xy 351.84306 -224.636431)
			(xy 351.807857 -224.599976) (xy 351.778648 -224.558564) (xy 351.756119 -224.51317) (xy 351.740801 -224.464863)
			(xy 351.733055 -224.414781) (xy 351.732596 -224.389442) (xy 351.451672 -224.389442) (xy 351.451164 -224.415329)
			(xy 351.443065 -224.466467) (xy 351.427066 -224.515707) (xy 351.40356 -224.561839) (xy 351.373128 -224.603726)
			(xy 351.336518 -224.640336) (xy 351.294631 -224.670768) (xy 351.248499 -224.694274) (xy 351.199259 -224.710273)
			(xy 351.148121 -224.718372) (xy 351.096347 -224.718372) (xy 351.045209 -224.710273) (xy 350.995969 -224.694274)
			(xy 350.949837 -224.670768) (xy 350.90795 -224.640336) (xy 350.87134 -224.603726) (xy 350.840908 -224.561839)
			(xy 350.817402 -224.515707) (xy 350.801403 -224.466467) (xy 350.793304 -224.415329) (xy 350.792796 -224.389442)
			(xy 350.511872 -224.389442) (xy 350.511325 -224.417149) (xy 350.502141 -224.471796) (xy 350.493584 -224.498154)
			(xy 350.48571 -224.520252) (xy 350.690688 -224.87509) (xy 350.713548 -224.879408) (xy 350.738371 -224.884565)
			(xy 350.786151 -224.90152) (xy 350.830771 -224.925592) (xy 350.871178 -224.956214) (xy 350.906419 -224.992662)
			(xy 350.935663 -225.034077) (xy 350.958219 -225.079482) (xy 350.973556 -225.127806) (xy 350.981311 -225.177908)
			(xy 350.981772 -225.203258) (xy 350.981264 -225.229165) (xy 350.973158 -225.280342) (xy 350.957146 -225.329621)
			(xy 350.933623 -225.375788) (xy 350.903167 -225.417707) (xy 350.866529 -225.454345) (xy 350.82461 -225.484801)
			(xy 350.778443 -225.508324) (xy 350.729164 -225.524336) (xy 350.677987 -225.532442) (xy 350.626173 -225.532442)
			(xy 350.574996 -225.524336) (xy 350.525717 -225.508324) (xy 350.47955 -225.484801) (xy 350.437631 -225.454345)
			(xy 350.400993 -225.417707) (xy 350.370537 -225.375788) (xy 350.347014 -225.329621) (xy 350.331002 -225.280342)
			(xy 350.322896 -225.229165) (xy 350.322388 -225.203258) (xy 350.322997 -225.175541) (xy 350.33231 -225.120895)
			(xy 350.34093 -225.094546) (xy 350.348804 -225.072448) (xy 350.143826 -224.71761) (xy 350.120966 -224.713292)
			(xy 350.096148 -224.708169) (xy 350.048405 -224.691172) (xy 350.003826 -224.667071) (xy 349.96346 -224.636431)
			(xy 349.928257 -224.599976) (xy 349.899048 -224.558564) (xy 349.876519 -224.51317) (xy 349.861201 -224.464863)
			(xy 349.853455 -224.414781) (xy 349.852996 -224.389442) (xy 349.572072 -224.389442) (xy 349.571564 -224.415329)
			(xy 349.563465 -224.466467) (xy 349.547466 -224.515707) (xy 349.52396 -224.561839) (xy 349.493528 -224.603726)
			(xy 349.456918 -224.640336) (xy 349.415031 -224.670768) (xy 349.368899 -224.694274) (xy 349.319659 -224.710273)
			(xy 349.268521 -224.718372) (xy 349.216747 -224.718372) (xy 349.165609 -224.710273) (xy 349.116369 -224.694274)
			(xy 349.070237 -224.670768) (xy 349.02835 -224.640336) (xy 348.99174 -224.603726) (xy 348.961308 -224.561839)
			(xy 348.937802 -224.515707) (xy 348.921803 -224.466467) (xy 348.913704 -224.415329) (xy 348.913196 -224.389442)
			(xy 348.632272 -224.389442) (xy 348.631725 -224.417149) (xy 348.622541 -224.471796) (xy 348.613984 -224.498154)
			(xy 348.60611 -224.520252) (xy 348.811088 -224.87509) (xy 348.833948 -224.879408) (xy 348.858771 -224.884565)
			(xy 348.906551 -224.90152) (xy 348.951171 -224.925592) (xy 348.991578 -224.956214) (xy 349.026819 -224.992662)
			(xy 349.056063 -225.034077) (xy 349.078619 -225.079482) (xy 349.093956 -225.127806) (xy 349.101711 -225.177908)
			(xy 349.102172 -225.203258) (xy 349.101664 -225.229165) (xy 349.093558 -225.280342) (xy 349.077546 -225.329621)
			(xy 349.054023 -225.375788) (xy 349.023567 -225.417707) (xy 348.986929 -225.454345) (xy 348.94501 -225.484801)
			(xy 348.898843 -225.508324) (xy 348.849564 -225.524336) (xy 348.798387 -225.532442) (xy 348.746573 -225.532442)
			(xy 348.695396 -225.524336) (xy 348.646117 -225.508324) (xy 348.59995 -225.484801) (xy 348.558031 -225.454345)
			(xy 348.521393 -225.417707) (xy 348.490937 -225.375788) (xy 348.467414 -225.329621) (xy 348.451402 -225.280342)
			(xy 348.443296 -225.229165) (xy 348.442788 -225.203258) (xy 348.443397 -225.175541) (xy 348.45271 -225.120895)
			(xy 348.46133 -225.094546) (xy 348.469204 -225.072448) (xy 348.264226 -224.71761) (xy 348.241366 -224.713292)
			(xy 348.216548 -224.708169) (xy 348.168805 -224.691172) (xy 348.124226 -224.667071) (xy 348.08386 -224.636431)
			(xy 348.048657 -224.599976) (xy 348.019448 -224.558564) (xy 347.996919 -224.51317) (xy 347.981601 -224.464863)
			(xy 347.973855 -224.414781) (xy 347.973396 -224.389442) (xy 347.692472 -224.389442) (xy 347.691964 -224.415329)
			(xy 347.683865 -224.466467) (xy 347.667866 -224.515707) (xy 347.64436 -224.561839) (xy 347.613928 -224.603726)
			(xy 347.577318 -224.640336) (xy 347.535431 -224.670768) (xy 347.489299 -224.694274) (xy 347.440059 -224.710273)
			(xy 347.388921 -224.718372) (xy 347.337147 -224.718372) (xy 347.286009 -224.710273) (xy 347.236769 -224.694274)
			(xy 347.190637 -224.670768) (xy 347.14875 -224.640336) (xy 347.11214 -224.603726) (xy 347.081708 -224.561839)
			(xy 347.058202 -224.515707) (xy 347.042203 -224.466467) (xy 347.034104 -224.415329) (xy 347.033596 -224.389442)
			(xy 346.752672 -224.389442) (xy 346.752125 -224.417149) (xy 346.742941 -224.471796) (xy 346.734384 -224.498154)
			(xy 346.72651 -224.520252) (xy 346.931488 -224.87509) (xy 346.954348 -224.879408) (xy 346.979171 -224.884565)
			(xy 347.026951 -224.90152) (xy 347.071571 -224.925592) (xy 347.111978 -224.956214) (xy 347.147219 -224.992662)
			(xy 347.176463 -225.034077) (xy 347.199019 -225.079482) (xy 347.214356 -225.127806) (xy 347.222111 -225.177908)
			(xy 347.222572 -225.203258) (xy 347.222064 -225.229165) (xy 347.213958 -225.280342) (xy 347.197946 -225.329621)
			(xy 347.174423 -225.375788) (xy 347.143967 -225.417707) (xy 347.107329 -225.454345) (xy 347.06541 -225.484801)
			(xy 347.019243 -225.508324) (xy 346.969964 -225.524336) (xy 346.918787 -225.532442) (xy 346.866973 -225.532442)
			(xy 346.815796 -225.524336) (xy 346.766517 -225.508324) (xy 346.72035 -225.484801) (xy 346.678431 -225.454345)
			(xy 346.641793 -225.417707) (xy 346.611337 -225.375788) (xy 346.587814 -225.329621) (xy 346.571802 -225.280342)
			(xy 346.563696 -225.229165) (xy 346.563188 -225.203258) (xy 346.563797 -225.175541) (xy 346.57311 -225.120895)
			(xy 346.58173 -225.094546) (xy 346.589604 -225.072448) (xy 346.384626 -224.71761) (xy 346.361766 -224.713292)
			(xy 346.336948 -224.708169) (xy 346.289205 -224.691172) (xy 346.244626 -224.667071) (xy 346.20426 -224.636431)
			(xy 346.169057 -224.599976) (xy 346.139848 -224.558564) (xy 346.117319 -224.51317) (xy 346.102001 -224.464863)
			(xy 346.094255 -224.414781) (xy 346.093796 -224.389442) (xy 345.812872 -224.389442) (xy 345.812364 -224.415329)
			(xy 345.804265 -224.466467) (xy 345.788266 -224.515707) (xy 345.76476 -224.561839) (xy 345.734328 -224.603726)
			(xy 345.697718 -224.640336) (xy 345.655831 -224.670768) (xy 345.609699 -224.694274) (xy 345.560459 -224.710273)
			(xy 345.509321 -224.718372) (xy 345.457547 -224.718372) (xy 345.406409 -224.710273) (xy 345.357169 -224.694274)
			(xy 345.311037 -224.670768) (xy 345.26915 -224.640336) (xy 345.23254 -224.603726) (xy 345.202108 -224.561839)
			(xy 345.178602 -224.515707) (xy 345.162603 -224.466467) (xy 345.154504 -224.415329) (xy 345.153996 -224.389442)
			(xy 344.873072 -224.389442) (xy 344.872525 -224.417149) (xy 344.863341 -224.471796) (xy 344.854784 -224.498154)
			(xy 344.84691 -224.520252) (xy 345.051888 -224.87509) (xy 345.074748 -224.879408) (xy 345.099571 -224.884565)
			(xy 345.147351 -224.90152) (xy 345.191971 -224.925592) (xy 345.232378 -224.956214) (xy 345.267619 -224.992662)
			(xy 345.296863 -225.034077) (xy 345.319419 -225.079482) (xy 345.334756 -225.127806) (xy 345.342511 -225.177908)
			(xy 345.342972 -225.203258) (xy 345.342464 -225.229165) (xy 345.334358 -225.280342) (xy 345.318346 -225.329621)
			(xy 345.294823 -225.375788) (xy 345.264367 -225.417707) (xy 345.227729 -225.454345) (xy 345.18581 -225.484801)
			(xy 345.139643 -225.508324) (xy 345.090364 -225.524336) (xy 345.039187 -225.532442) (xy 344.987373 -225.532442)
			(xy 344.936196 -225.524336) (xy 344.886917 -225.508324) (xy 344.84075 -225.484801) (xy 344.798831 -225.454345)
			(xy 344.762193 -225.417707) (xy 344.731737 -225.375788) (xy 344.708214 -225.329621) (xy 344.692202 -225.280342)
			(xy 344.684096 -225.229165) (xy 344.683588 -225.203258) (xy 344.684197 -225.175541) (xy 344.69351 -225.120895)
			(xy 344.70213 -225.094546) (xy 344.710004 -225.072448) (xy 344.505026 -224.71761) (xy 344.482166 -224.713292)
			(xy 344.457348 -224.708169) (xy 344.409605 -224.691172) (xy 344.365026 -224.667071) (xy 344.32466 -224.636431)
			(xy 344.289457 -224.599976) (xy 344.260248 -224.558564) (xy 344.237719 -224.51317) (xy 344.222401 -224.464863)
			(xy 344.214655 -224.414781) (xy 344.214196 -224.389442) (xy 343.933272 -224.389442) (xy 343.932764 -224.415329)
			(xy 343.924665 -224.466467) (xy 343.908666 -224.515707) (xy 343.88516 -224.561839) (xy 343.854728 -224.603726)
			(xy 343.818118 -224.640336) (xy 343.776231 -224.670768) (xy 343.730099 -224.694274) (xy 343.680859 -224.710273)
			(xy 343.629721 -224.718372) (xy 343.577947 -224.718372) (xy 343.526809 -224.710273) (xy 343.477569 -224.694274)
			(xy 343.431437 -224.670768) (xy 343.38955 -224.640336) (xy 343.35294 -224.603726) (xy 343.322508 -224.561839)
			(xy 343.299002 -224.515707) (xy 343.283003 -224.466467) (xy 343.274904 -224.415329) (xy 343.274396 -224.389442)
			(xy 342.993472 -224.389442) (xy 342.992925 -224.417149) (xy 342.983741 -224.471796) (xy 342.975184 -224.498154)
			(xy 342.96731 -224.520252) (xy 343.172288 -224.87509) (xy 343.195148 -224.879408) (xy 343.219971 -224.884565)
			(xy 343.267751 -224.90152) (xy 343.312371 -224.925592) (xy 343.352778 -224.956214) (xy 343.388019 -224.992662)
			(xy 343.417263 -225.034077) (xy 343.439819 -225.079482) (xy 343.455156 -225.127806) (xy 343.462911 -225.177908)
			(xy 343.463372 -225.203258) (xy 343.462864 -225.229165) (xy 343.454758 -225.280342) (xy 343.438746 -225.329621)
			(xy 343.415223 -225.375788) (xy 343.384767 -225.417707) (xy 343.348129 -225.454345) (xy 343.30621 -225.484801)
			(xy 343.260043 -225.508324) (xy 343.210764 -225.524336) (xy 343.159587 -225.532442) (xy 343.107773 -225.532442)
			(xy 343.056596 -225.524336) (xy 343.007317 -225.508324) (xy 342.96115 -225.484801) (xy 342.919231 -225.454345)
			(xy 342.882593 -225.417707) (xy 342.852137 -225.375788) (xy 342.828614 -225.329621) (xy 342.812602 -225.280342)
			(xy 342.804496 -225.229165) (xy 342.803988 -225.203258) (xy 342.804597 -225.175541) (xy 342.81391 -225.120895)
			(xy 342.82253 -225.094546) (xy 342.830404 -225.072448) (xy 342.625426 -224.71761) (xy 342.602566 -224.713292)
			(xy 342.577748 -224.708169) (xy 342.530005 -224.691172) (xy 342.485426 -224.667071) (xy 342.44506 -224.636431)
			(xy 342.409857 -224.599976) (xy 342.380648 -224.558564) (xy 342.358119 -224.51317) (xy 342.342801 -224.464863)
			(xy 342.335055 -224.414781) (xy 342.334596 -224.389442) (xy 342.053672 -224.389442) (xy 342.053164 -224.415329)
			(xy 342.045065 -224.466467) (xy 342.029066 -224.515707) (xy 342.00556 -224.561839) (xy 341.975128 -224.603726)
			(xy 341.938518 -224.640336) (xy 341.896631 -224.670768) (xy 341.850499 -224.694274) (xy 341.801259 -224.710273)
			(xy 341.750121 -224.718372) (xy 341.698347 -224.718372) (xy 341.647209 -224.710273) (xy 341.597969 -224.694274)
			(xy 341.551837 -224.670768) (xy 341.50995 -224.640336) (xy 341.47334 -224.603726) (xy 341.442908 -224.561839)
			(xy 341.419402 -224.515707) (xy 341.403403 -224.466467) (xy 341.395304 -224.415329) (xy 341.394796 -224.389442)
			(xy 132.645404 -224.389442) (xy 132.64486 -224.417149) (xy 132.635674 -224.471796) (xy 132.627116 -224.498154)
			(xy 132.619242 -224.520252) (xy 132.82422 -224.87509) (xy 132.84708 -224.879408) (xy 132.871909 -224.884542)
			(xy 132.919688 -224.901501) (xy 132.964308 -224.925578) (xy 133.004714 -224.956202) (xy 133.039954 -224.992654)
			(xy 133.069197 -225.034071) (xy 133.091752 -225.079478) (xy 133.107088 -225.127804) (xy 133.114843 -225.177908)
			(xy 133.115304 -225.203258) (xy 133.114796 -225.229165) (xy 133.10669 -225.280342) (xy 133.090678 -225.329621)
			(xy 133.067155 -225.375788) (xy 133.036699 -225.417707) (xy 133.000061 -225.454345) (xy 132.958142 -225.484801)
			(xy 132.911975 -225.508324) (xy 132.862696 -225.524336) (xy 132.811519 -225.532442) (xy 132.759705 -225.532442)
			(xy 132.708528 -225.524336) (xy 132.659249 -225.508324) (xy 132.613082 -225.484801) (xy 132.571163 -225.454345)
			(xy 132.534525 -225.417707) (xy 132.504069 -225.375788) (xy 132.480546 -225.329621) (xy 132.464534 -225.280342)
			(xy 132.456428 -225.229165) (xy 132.45592 -225.203258) (xy 132.456527 -225.175541) (xy 132.465842 -225.120895)
			(xy 132.474462 -225.094546) (xy 132.482336 -225.072448) (xy 132.277358 -224.71761) (xy 132.254498 -224.713292)
			(xy 132.229685 -224.708145) (xy 132.181943 -224.691153) (xy 132.137363 -224.667056) (xy 132.096996 -224.63642)
			(xy 132.061793 -224.599968) (xy 132.032582 -224.558558) (xy 132.010052 -224.513166) (xy 131.994734 -224.46486)
			(xy 131.986988 -224.41478) (xy 131.986528 -224.389442) (xy 130.765804 -224.389442) (xy 130.76526 -224.417149)
			(xy 130.756074 -224.471796) (xy 130.747516 -224.498154) (xy 130.739642 -224.520252) (xy 130.94462 -224.87509)
			(xy 130.96748 -224.879408) (xy 130.992309 -224.884542) (xy 131.040088 -224.901501) (xy 131.084708 -224.925578)
			(xy 131.125114 -224.956202) (xy 131.160354 -224.992654) (xy 131.189597 -225.034071) (xy 131.212152 -225.079478)
			(xy 131.227488 -225.127804) (xy 131.235243 -225.177908) (xy 131.235704 -225.203258) (xy 131.235196 -225.229165)
			(xy 131.22709 -225.280342) (xy 131.211078 -225.329621) (xy 131.187555 -225.375788) (xy 131.157099 -225.417707)
			(xy 131.120461 -225.454345) (xy 131.078542 -225.484801) (xy 131.032375 -225.508324) (xy 130.983096 -225.524336)
			(xy 130.931919 -225.532442) (xy 130.880105 -225.532442) (xy 130.828928 -225.524336) (xy 130.779649 -225.508324)
			(xy 130.733482 -225.484801) (xy 130.691563 -225.454345) (xy 130.654925 -225.417707) (xy 130.624469 -225.375788)
			(xy 130.600946 -225.329621) (xy 130.584934 -225.280342) (xy 130.576828 -225.229165) (xy 130.57632 -225.203258)
			(xy 130.576927 -225.175541) (xy 130.586242 -225.120895) (xy 130.594862 -225.094546) (xy 130.602736 -225.072448)
			(xy 130.397758 -224.71761) (xy 130.374898 -224.713292) (xy 130.350085 -224.708145) (xy 130.302343 -224.691153)
			(xy 130.257763 -224.667056) (xy 130.217396 -224.63642) (xy 130.182193 -224.599968) (xy 130.152982 -224.558558)
			(xy 130.130452 -224.513166) (xy 130.115134 -224.46486) (xy 130.107388 -224.41478) (xy 130.106928 -224.389442)
			(xy 129.826004 -224.389442) (xy 129.825496 -224.415329) (xy 129.817397 -224.466467) (xy 129.801398 -224.515707)
			(xy 129.777892 -224.561839) (xy 129.74746 -224.603726) (xy 129.71085 -224.640336) (xy 129.668963 -224.670768)
			(xy 129.622831 -224.694274) (xy 129.573591 -224.710273) (xy 129.522453 -224.718372) (xy 129.470679 -224.718372)
			(xy 129.419541 -224.710273) (xy 129.370301 -224.694274) (xy 129.324169 -224.670768) (xy 129.282282 -224.640336)
			(xy 129.245672 -224.603726) (xy 129.21524 -224.561839) (xy 129.191734 -224.515707) (xy 129.175735 -224.466467)
			(xy 129.167636 -224.415329) (xy 129.167128 -224.389442) (xy 128.886204 -224.389442) (xy 128.88566 -224.417149)
			(xy 128.876474 -224.471796) (xy 128.867916 -224.498154) (xy 128.860042 -224.520252) (xy 129.06502 -224.87509)
			(xy 129.08788 -224.879408) (xy 129.112709 -224.884542) (xy 129.160488 -224.901501) (xy 129.205108 -224.925578)
			(xy 129.245514 -224.956202) (xy 129.280754 -224.992654) (xy 129.309997 -225.034071) (xy 129.332552 -225.079478)
			(xy 129.347888 -225.127804) (xy 129.355643 -225.177908) (xy 129.356104 -225.203258) (xy 129.355596 -225.229165)
			(xy 129.34749 -225.280342) (xy 129.331478 -225.329621) (xy 129.307955 -225.375788) (xy 129.277499 -225.417707)
			(xy 129.240861 -225.454345) (xy 129.198942 -225.484801) (xy 129.152775 -225.508324) (xy 129.103496 -225.524336)
			(xy 129.052319 -225.532442) (xy 129.000505 -225.532442) (xy 128.949328 -225.524336) (xy 128.900049 -225.508324)
			(xy 128.853882 -225.484801) (xy 128.811963 -225.454345) (xy 128.775325 -225.417707) (xy 128.744869 -225.375788)
			(xy 128.721346 -225.329621) (xy 128.705334 -225.280342) (xy 128.697228 -225.229165) (xy 128.69672 -225.203258)
			(xy 128.697327 -225.175541) (xy 128.706642 -225.120895) (xy 128.715262 -225.094546) (xy 128.723136 -225.072448)
			(xy 128.518158 -224.71761) (xy 128.495298 -224.713292) (xy 128.470485 -224.708145) (xy 128.422743 -224.691153)
			(xy 128.378163 -224.667056) (xy 128.337796 -224.63642) (xy 128.302593 -224.599968) (xy 128.273382 -224.558558)
			(xy 128.250852 -224.513166) (xy 128.235534 -224.46486) (xy 128.227788 -224.41478) (xy 128.227328 -224.389442)
			(xy 127.946404 -224.389442) (xy 127.945896 -224.415329) (xy 127.937797 -224.466467) (xy 127.921798 -224.515707)
			(xy 127.898292 -224.561839) (xy 127.86786 -224.603726) (xy 127.83125 -224.640336) (xy 127.789363 -224.670768)
			(xy 127.743231 -224.694274) (xy 127.693991 -224.710273) (xy 127.642853 -224.718372) (xy 127.591079 -224.718372)
			(xy 127.539941 -224.710273) (xy 127.490701 -224.694274) (xy 127.444569 -224.670768) (xy 127.402682 -224.640336)
			(xy 127.366072 -224.603726) (xy 127.33564 -224.561839) (xy 127.312134 -224.515707) (xy 127.296135 -224.466467)
			(xy 127.288036 -224.415329) (xy 127.287528 -224.389442) (xy 127.006604 -224.389442) (xy 127.00606 -224.417149)
			(xy 126.996874 -224.471796) (xy 126.988316 -224.498154) (xy 126.980442 -224.520252) (xy 127.18542 -224.87509)
			(xy 127.20828 -224.879408) (xy 127.233109 -224.884542) (xy 127.280888 -224.901501) (xy 127.325508 -224.925578)
			(xy 127.365914 -224.956202) (xy 127.401154 -224.992654) (xy 127.430397 -225.034071) (xy 127.452952 -225.079478)
			(xy 127.468288 -225.127804) (xy 127.476043 -225.177908) (xy 127.476504 -225.203258) (xy 127.475996 -225.229165)
			(xy 127.46789 -225.280342) (xy 127.451878 -225.329621) (xy 127.428355 -225.375788) (xy 127.397899 -225.417707)
			(xy 127.361261 -225.454345) (xy 127.319342 -225.484801) (xy 127.273175 -225.508324) (xy 127.223896 -225.524336)
			(xy 127.172719 -225.532442) (xy 127.120905 -225.532442) (xy 127.069728 -225.524336) (xy 127.020449 -225.508324)
			(xy 126.974282 -225.484801) (xy 126.932363 -225.454345) (xy 126.895725 -225.417707) (xy 126.865269 -225.375788)
			(xy 126.841746 -225.329621) (xy 126.825734 -225.280342) (xy 126.817628 -225.229165) (xy 126.81712 -225.203258)
			(xy 126.817727 -225.175541) (xy 126.827042 -225.120895) (xy 126.835662 -225.094546) (xy 126.843536 -225.072448)
			(xy 126.638558 -224.71761) (xy 126.615698 -224.713292) (xy 126.590885 -224.708145) (xy 126.543143 -224.691153)
			(xy 126.498563 -224.667056) (xy 126.458196 -224.63642) (xy 126.422993 -224.599968) (xy 126.393782 -224.558558)
			(xy 126.371252 -224.513166) (xy 126.355934 -224.46486) (xy 126.348188 -224.41478) (xy 126.347728 -224.389442)
			(xy 126.066804 -224.389442) (xy 126.066296 -224.415329) (xy 126.058197 -224.466467) (xy 126.042198 -224.515707)
			(xy 126.018692 -224.561839) (xy 125.98826 -224.603726) (xy 125.95165 -224.640336) (xy 125.909763 -224.670768)
			(xy 125.863631 -224.694274) (xy 125.814391 -224.710273) (xy 125.763253 -224.718372) (xy 125.711479 -224.718372)
			(xy 125.660341 -224.710273) (xy 125.611101 -224.694274) (xy 125.564969 -224.670768) (xy 125.523082 -224.640336)
			(xy 125.486472 -224.603726) (xy 125.45604 -224.561839) (xy 125.432534 -224.515707) (xy 125.416535 -224.466467)
			(xy 125.408436 -224.415329) (xy 125.407928 -224.389442) (xy 125.127004 -224.389442) (xy 125.12646 -224.417149)
			(xy 125.117274 -224.471796) (xy 125.108716 -224.498154) (xy 125.100842 -224.520252) (xy 125.30582 -224.87509)
			(xy 125.32868 -224.879408) (xy 125.353509 -224.884542) (xy 125.401288 -224.901501) (xy 125.445908 -224.925578)
			(xy 125.486314 -224.956202) (xy 125.521554 -224.992654) (xy 125.550797 -225.034071) (xy 125.573352 -225.079478)
			(xy 125.588688 -225.127804) (xy 125.596443 -225.177908) (xy 125.596904 -225.203258) (xy 125.596396 -225.229165)
			(xy 125.58829 -225.280342) (xy 125.572278 -225.329621) (xy 125.548755 -225.375788) (xy 125.518299 -225.417707)
			(xy 125.481661 -225.454345) (xy 125.439742 -225.484801) (xy 125.393575 -225.508324) (xy 125.344296 -225.524336)
			(xy 125.293119 -225.532442) (xy 125.241305 -225.532442) (xy 125.190128 -225.524336) (xy 125.140849 -225.508324)
			(xy 125.094682 -225.484801) (xy 125.052763 -225.454345) (xy 125.016125 -225.417707) (xy 124.985669 -225.375788)
			(xy 124.962146 -225.329621) (xy 124.946134 -225.280342) (xy 124.938028 -225.229165) (xy 124.93752 -225.203258)
			(xy 124.938127 -225.175541) (xy 124.947442 -225.120895) (xy 124.956062 -225.094546) (xy 124.963936 -225.072448)
			(xy 124.758958 -224.71761) (xy 124.736098 -224.713292) (xy 124.711285 -224.708145) (xy 124.663543 -224.691153)
			(xy 124.618963 -224.667056) (xy 124.578596 -224.63642) (xy 124.543393 -224.599968) (xy 124.514182 -224.558558)
			(xy 124.491652 -224.513166) (xy 124.476334 -224.46486) (xy 124.468588 -224.41478) (xy 124.468128 -224.389442)
			(xy 124.187204 -224.389442) (xy 124.186696 -224.415329) (xy 124.178597 -224.466467) (xy 124.162598 -224.515707)
			(xy 124.139092 -224.561839) (xy 124.10866 -224.603726) (xy 124.07205 -224.640336) (xy 124.030163 -224.670768)
			(xy 123.984031 -224.694274) (xy 123.934791 -224.710273) (xy 123.883653 -224.718372) (xy 123.831879 -224.718372)
			(xy 123.780741 -224.710273) (xy 123.731501 -224.694274) (xy 123.685369 -224.670768) (xy 123.643482 -224.640336)
			(xy 123.606872 -224.603726) (xy 123.57644 -224.561839) (xy 123.552934 -224.515707) (xy 123.536935 -224.466467)
			(xy 123.528836 -224.415329) (xy 123.528328 -224.389442) (xy 123.247404 -224.389442) (xy 123.24686 -224.417149)
			(xy 123.237674 -224.471796) (xy 123.229116 -224.498154) (xy 123.221242 -224.520252) (xy 123.42622 -224.87509)
			(xy 123.44908 -224.879408) (xy 123.473909 -224.884542) (xy 123.521688 -224.901501) (xy 123.566308 -224.925578)
			(xy 123.606714 -224.956202) (xy 123.641954 -224.992654) (xy 123.671197 -225.034071) (xy 123.693752 -225.079478)
			(xy 123.709088 -225.127804) (xy 123.716843 -225.177908) (xy 123.717304 -225.203258) (xy 123.716796 -225.229165)
			(xy 123.70869 -225.280342) (xy 123.692678 -225.329621) (xy 123.669155 -225.375788) (xy 123.638699 -225.417707)
			(xy 123.602061 -225.454345) (xy 123.560142 -225.484801) (xy 123.513975 -225.508324) (xy 123.464696 -225.524336)
			(xy 123.413519 -225.532442) (xy 123.361705 -225.532442) (xy 123.310528 -225.524336) (xy 123.261249 -225.508324)
			(xy 123.215082 -225.484801) (xy 123.173163 -225.454345) (xy 123.136525 -225.417707) (xy 123.106069 -225.375788)
			(xy 123.082546 -225.329621) (xy 123.066534 -225.280342) (xy 123.058428 -225.229165) (xy 123.05792 -225.203258)
			(xy 123.058527 -225.175541) (xy 123.067842 -225.120895) (xy 123.076462 -225.094546) (xy 123.084336 -225.072448)
			(xy 122.879358 -224.71761) (xy 122.856498 -224.713292) (xy 122.831685 -224.708145) (xy 122.783943 -224.691153)
			(xy 122.739363 -224.667056) (xy 122.698996 -224.63642) (xy 122.663793 -224.599968) (xy 122.634582 -224.558558)
			(xy 122.612052 -224.513166) (xy 122.596734 -224.46486) (xy 122.588988 -224.41478) (xy 122.588528 -224.389442)
			(xy 122.307604 -224.389442) (xy 122.307096 -224.415329) (xy 122.298997 -224.466467) (xy 122.282998 -224.515707)
			(xy 122.259492 -224.561839) (xy 122.22906 -224.603726) (xy 122.19245 -224.640336) (xy 122.150563 -224.670768)
			(xy 122.104431 -224.694274) (xy 122.055191 -224.710273) (xy 122.004053 -224.718372) (xy 121.952279 -224.718372)
			(xy 121.901141 -224.710273) (xy 121.851901 -224.694274) (xy 121.805769 -224.670768) (xy 121.763882 -224.640336)
			(xy 121.727272 -224.603726) (xy 121.69684 -224.561839) (xy 121.673334 -224.515707) (xy 121.657335 -224.466467)
			(xy 121.649236 -224.415329) (xy 121.648728 -224.389442) (xy 121.367804 -224.389442) (xy 121.36726 -224.417149)
			(xy 121.358074 -224.471796) (xy 121.349516 -224.498154) (xy 121.341642 -224.520252) (xy 121.54662 -224.87509)
			(xy 121.56948 -224.879408) (xy 121.594309 -224.884542) (xy 121.642088 -224.901501) (xy 121.686708 -224.925578)
			(xy 121.727114 -224.956202) (xy 121.762354 -224.992654) (xy 121.791597 -225.034071) (xy 121.814152 -225.079478)
			(xy 121.829488 -225.127804) (xy 121.837243 -225.177908) (xy 121.837704 -225.203258) (xy 121.837196 -225.229165)
			(xy 121.82909 -225.280342) (xy 121.813078 -225.329621) (xy 121.789555 -225.375788) (xy 121.759099 -225.417707)
			(xy 121.722461 -225.454345) (xy 121.680542 -225.484801) (xy 121.634375 -225.508324) (xy 121.585096 -225.524336)
			(xy 121.533919 -225.532442) (xy 121.482105 -225.532442) (xy 121.430928 -225.524336) (xy 121.381649 -225.508324)
			(xy 121.335482 -225.484801) (xy 121.293563 -225.454345) (xy 121.256925 -225.417707) (xy 121.226469 -225.375788)
			(xy 121.202946 -225.329621) (xy 121.186934 -225.280342) (xy 121.178828 -225.229165) (xy 121.17832 -225.203258)
			(xy 121.178927 -225.175541) (xy 121.188242 -225.120895) (xy 121.196862 -225.094546) (xy 121.204736 -225.072448)
			(xy 120.999758 -224.71761) (xy 120.976898 -224.713292) (xy 120.952085 -224.708145) (xy 120.904343 -224.691153)
			(xy 120.859763 -224.667056) (xy 120.819396 -224.63642) (xy 120.784193 -224.599968) (xy 120.754982 -224.558558)
			(xy 120.732452 -224.513166) (xy 120.717134 -224.46486) (xy 120.709388 -224.41478) (xy 120.708928 -224.389442)
			(xy 120.428004 -224.389442) (xy 120.427496 -224.415329) (xy 120.419397 -224.466467) (xy 120.403398 -224.515707)
			(xy 120.379892 -224.561839) (xy 120.34946 -224.603726) (xy 120.31285 -224.640336) (xy 120.270963 -224.670768)
			(xy 120.224831 -224.694274) (xy 120.175591 -224.710273) (xy 120.124453 -224.718372) (xy 120.072679 -224.718372)
			(xy 120.021541 -224.710273) (xy 119.972301 -224.694274) (xy 119.926169 -224.670768) (xy 119.884282 -224.640336)
			(xy 119.847672 -224.603726) (xy 119.81724 -224.561839) (xy 119.793734 -224.515707) (xy 119.777735 -224.466467)
			(xy 119.769636 -224.415329) (xy 119.769128 -224.389442) (xy 119.488204 -224.389442) (xy 119.48766 -224.417149)
			(xy 119.478474 -224.471796) (xy 119.469916 -224.498154) (xy 119.462042 -224.520252) (xy 119.66702 -224.87509)
			(xy 119.68988 -224.879408) (xy 119.714709 -224.884542) (xy 119.762488 -224.901501) (xy 119.807108 -224.925578)
			(xy 119.847514 -224.956202) (xy 119.882754 -224.992654) (xy 119.911997 -225.034071) (xy 119.934552 -225.079478)
			(xy 119.949888 -225.127804) (xy 119.957643 -225.177908) (xy 119.958104 -225.203258) (xy 119.957596 -225.229165)
			(xy 119.94949 -225.280342) (xy 119.933478 -225.329621) (xy 119.909955 -225.375788) (xy 119.879499 -225.417707)
			(xy 119.842861 -225.454345) (xy 119.800942 -225.484801) (xy 119.754775 -225.508324) (xy 119.705496 -225.524336)
			(xy 119.654319 -225.532442) (xy 119.602505 -225.532442) (xy 119.551328 -225.524336) (xy 119.502049 -225.508324)
			(xy 119.455882 -225.484801) (xy 119.413963 -225.454345) (xy 119.377325 -225.417707) (xy 119.346869 -225.375788)
			(xy 119.323346 -225.329621) (xy 119.307334 -225.280342) (xy 119.299228 -225.229165) (xy 119.29872 -225.203258)
			(xy 119.299327 -225.175541) (xy 119.308642 -225.120895) (xy 119.317262 -225.094546) (xy 119.325136 -225.072448)
			(xy 119.120158 -224.71761) (xy 119.097298 -224.713292) (xy 119.072485 -224.708145) (xy 119.024743 -224.691153)
			(xy 118.980163 -224.667056) (xy 118.939796 -224.63642) (xy 118.904593 -224.599968) (xy 118.875382 -224.558558)
			(xy 118.852852 -224.513166) (xy 118.837534 -224.46486) (xy 118.829788 -224.41478) (xy 118.829328 -224.389442)
			(xy 118.548404 -224.389442) (xy 118.547896 -224.415329) (xy 118.539797 -224.466467) (xy 118.523798 -224.515707)
			(xy 118.500292 -224.561839) (xy 118.46986 -224.603726) (xy 118.43325 -224.640336) (xy 118.391363 -224.670768)
			(xy 118.345231 -224.694274) (xy 118.295991 -224.710273) (xy 118.244853 -224.718372) (xy 118.193079 -224.718372)
			(xy 118.141941 -224.710273) (xy 118.092701 -224.694274) (xy 118.046569 -224.670768) (xy 118.004682 -224.640336)
			(xy 117.968072 -224.603726) (xy 117.93764 -224.561839) (xy 117.914134 -224.515707) (xy 117.898135 -224.466467)
			(xy 117.890036 -224.415329) (xy 117.889528 -224.389442) (xy 117.608604 -224.389442) (xy 117.60806 -224.417149)
			(xy 117.598874 -224.471796) (xy 117.590316 -224.498154) (xy 117.582442 -224.520252) (xy 117.78742 -224.87509)
			(xy 117.81028 -224.879408) (xy 117.835109 -224.884542) (xy 117.882888 -224.901501) (xy 117.927508 -224.925578)
			(xy 117.967914 -224.956202) (xy 118.003154 -224.992654) (xy 118.032397 -225.034071) (xy 118.054952 -225.079478)
			(xy 118.070288 -225.127804) (xy 118.078043 -225.177908) (xy 118.078504 -225.203258) (xy 118.077996 -225.229165)
			(xy 118.06989 -225.280342) (xy 118.053878 -225.329621) (xy 118.030355 -225.375788) (xy 117.999899 -225.417707)
			(xy 117.963261 -225.454345) (xy 117.921342 -225.484801) (xy 117.875175 -225.508324) (xy 117.825896 -225.524336)
			(xy 117.774719 -225.532442) (xy 117.722905 -225.532442) (xy 117.671728 -225.524336) (xy 117.622449 -225.508324)
			(xy 117.576282 -225.484801) (xy 117.534363 -225.454345) (xy 117.497725 -225.417707) (xy 117.467269 -225.375788)
			(xy 117.443746 -225.329621) (xy 117.427734 -225.280342) (xy 117.419628 -225.229165) (xy 117.41912 -225.203258)
			(xy 117.419727 -225.175541) (xy 117.429042 -225.120895) (xy 117.437662 -225.094546) (xy 117.445536 -225.072448)
			(xy 117.240558 -224.71761) (xy 117.217698 -224.713292) (xy 117.192885 -224.708145) (xy 117.145143 -224.691153)
			(xy 117.100563 -224.667056) (xy 117.060196 -224.63642) (xy 117.024993 -224.599968) (xy 116.995782 -224.558558)
			(xy 116.973252 -224.513166) (xy 116.957934 -224.46486) (xy 116.950188 -224.41478) (xy 116.949728 -224.389442)
			(xy 116.668804 -224.389442) (xy 116.668296 -224.415329) (xy 116.660197 -224.466467) (xy 116.644198 -224.515707)
			(xy 116.620692 -224.561839) (xy 116.59026 -224.603726) (xy 116.55365 -224.640336) (xy 116.511763 -224.670768)
			(xy 116.465631 -224.694274) (xy 116.416391 -224.710273) (xy 116.365253 -224.718372) (xy 116.313479 -224.718372)
			(xy 116.262341 -224.710273) (xy 116.213101 -224.694274) (xy 116.166969 -224.670768) (xy 116.125082 -224.640336)
			(xy 116.088472 -224.603726) (xy 116.05804 -224.561839) (xy 116.034534 -224.515707) (xy 116.018535 -224.466467)
			(xy 116.010436 -224.415329) (xy 116.009928 -224.389442) (xy 115.729004 -224.389442) (xy 115.72846 -224.417149)
			(xy 115.719274 -224.471796) (xy 115.710716 -224.498154) (xy 115.702842 -224.520252) (xy 115.90782 -224.87509)
			(xy 115.93068 -224.879408) (xy 115.955509 -224.884542) (xy 116.003288 -224.901501) (xy 116.047908 -224.925578)
			(xy 116.088314 -224.956202) (xy 116.123554 -224.992654) (xy 116.152797 -225.034071) (xy 116.175352 -225.079478)
			(xy 116.190688 -225.127804) (xy 116.198443 -225.177908) (xy 116.198904 -225.203258) (xy 116.198396 -225.229165)
			(xy 116.19029 -225.280342) (xy 116.174278 -225.329621) (xy 116.150755 -225.375788) (xy 116.120299 -225.417707)
			(xy 116.083661 -225.454345) (xy 116.041742 -225.484801) (xy 115.995575 -225.508324) (xy 115.946296 -225.524336)
			(xy 115.895119 -225.532442) (xy 115.843305 -225.532442) (xy 115.792128 -225.524336) (xy 115.742849 -225.508324)
			(xy 115.696682 -225.484801) (xy 115.654763 -225.454345) (xy 115.618125 -225.417707) (xy 115.587669 -225.375788)
			(xy 115.564146 -225.329621) (xy 115.548134 -225.280342) (xy 115.540028 -225.229165) (xy 115.53952 -225.203258)
			(xy 115.540127 -225.175541) (xy 115.549442 -225.120895) (xy 115.558062 -225.094546) (xy 115.565936 -225.072448)
			(xy 115.360958 -224.71761) (xy 115.338098 -224.713292) (xy 115.313285 -224.708145) (xy 115.265543 -224.691153)
			(xy 115.220963 -224.667056) (xy 115.180596 -224.63642) (xy 115.145393 -224.599968) (xy 115.116182 -224.558558)
			(xy 115.093652 -224.513166) (xy 115.078334 -224.46486) (xy 115.070588 -224.41478) (xy 115.070128 -224.389442)
			(xy 114.789204 -224.389442) (xy 114.788696 -224.415329) (xy 114.780597 -224.466467) (xy 114.764598 -224.515707)
			(xy 114.741092 -224.561839) (xy 114.71066 -224.603726) (xy 114.67405 -224.640336) (xy 114.632163 -224.670768)
			(xy 114.586031 -224.694274) (xy 114.536791 -224.710273) (xy 114.485653 -224.718372) (xy 114.433879 -224.718372)
			(xy 114.382741 -224.710273) (xy 114.333501 -224.694274) (xy 114.287369 -224.670768) (xy 114.245482 -224.640336)
			(xy 114.208872 -224.603726) (xy 114.17844 -224.561839) (xy 114.154934 -224.515707) (xy 114.138935 -224.466467)
			(xy 114.130836 -224.415329) (xy 114.130328 -224.389442) (xy 113.849404 -224.389442) (xy 113.84886 -224.417149)
			(xy 113.839674 -224.471796) (xy 113.831116 -224.498154) (xy 113.823242 -224.520252) (xy 114.02822 -224.87509)
			(xy 114.05108 -224.879408) (xy 114.075909 -224.884542) (xy 114.123688 -224.901501) (xy 114.168308 -224.925578)
			(xy 114.208714 -224.956202) (xy 114.243954 -224.992654) (xy 114.273197 -225.034071) (xy 114.295752 -225.079478)
			(xy 114.311088 -225.127804) (xy 114.318843 -225.177908) (xy 114.319304 -225.203258) (xy 114.318796 -225.229165)
			(xy 114.31069 -225.280342) (xy 114.294678 -225.329621) (xy 114.271155 -225.375788) (xy 114.240699 -225.417707)
			(xy 114.204061 -225.454345) (xy 114.162142 -225.484801) (xy 114.115975 -225.508324) (xy 114.066696 -225.524336)
			(xy 114.015519 -225.532442) (xy 113.963705 -225.532442) (xy 113.912528 -225.524336) (xy 113.863249 -225.508324)
			(xy 113.817082 -225.484801) (xy 113.775163 -225.454345) (xy 113.738525 -225.417707) (xy 113.708069 -225.375788)
			(xy 113.684546 -225.329621) (xy 113.668534 -225.280342) (xy 113.660428 -225.229165) (xy 113.65992 -225.203258)
			(xy 113.660527 -225.175541) (xy 113.669842 -225.120895) (xy 113.678462 -225.094546) (xy 113.686336 -225.072448)
			(xy 113.481358 -224.71761) (xy 113.458498 -224.713292) (xy 113.433685 -224.708145) (xy 113.385943 -224.691153)
			(xy 113.341363 -224.667056) (xy 113.300996 -224.63642) (xy 113.265793 -224.599968) (xy 113.236582 -224.558558)
			(xy 113.214052 -224.513166) (xy 113.198734 -224.46486) (xy 113.190988 -224.41478) (xy 113.190528 -224.389442)
			(xy 112.909604 -224.389442) (xy 112.909096 -224.415329) (xy 112.900997 -224.466467) (xy 112.884998 -224.515707)
			(xy 112.861492 -224.561839) (xy 112.83106 -224.603726) (xy 112.79445 -224.640336) (xy 112.752563 -224.670768)
			(xy 112.706431 -224.694274) (xy 112.657191 -224.710273) (xy 112.606053 -224.718372) (xy 112.554279 -224.718372)
			(xy 112.503141 -224.710273) (xy 112.453901 -224.694274) (xy 112.407769 -224.670768) (xy 112.365882 -224.640336)
			(xy 112.329272 -224.603726) (xy 112.29884 -224.561839) (xy 112.275334 -224.515707) (xy 112.259335 -224.466467)
			(xy 112.251236 -224.415329) (xy 112.250728 -224.389442) (xy 111.969804 -224.389442) (xy 111.96926 -224.417149)
			(xy 111.960074 -224.471796) (xy 111.951516 -224.498154) (xy 111.943642 -224.520252) (xy 112.14862 -224.87509)
			(xy 112.17148 -224.879408) (xy 112.196309 -224.884542) (xy 112.244088 -224.901501) (xy 112.288708 -224.925578)
			(xy 112.329114 -224.956202) (xy 112.364354 -224.992654) (xy 112.393597 -225.034071) (xy 112.416152 -225.079478)
			(xy 112.431488 -225.127804) (xy 112.439243 -225.177908) (xy 112.439704 -225.203258) (xy 112.439196 -225.229165)
			(xy 112.43109 -225.280342) (xy 112.415078 -225.329621) (xy 112.391555 -225.375788) (xy 112.361099 -225.417707)
			(xy 112.324461 -225.454345) (xy 112.282542 -225.484801) (xy 112.236375 -225.508324) (xy 112.187096 -225.524336)
			(xy 112.135919 -225.532442) (xy 112.084105 -225.532442) (xy 112.032928 -225.524336) (xy 111.983649 -225.508324)
			(xy 111.937482 -225.484801) (xy 111.895563 -225.454345) (xy 111.858925 -225.417707) (xy 111.828469 -225.375788)
			(xy 111.804946 -225.329621) (xy 111.788934 -225.280342) (xy 111.780828 -225.229165) (xy 111.78032 -225.203258)
			(xy 111.780927 -225.175541) (xy 111.790242 -225.120895) (xy 111.798862 -225.094546) (xy 111.806736 -225.072448)
			(xy 111.601758 -224.71761) (xy 111.578898 -224.713292) (xy 111.554085 -224.708145) (xy 111.506343 -224.691153)
			(xy 111.461763 -224.667056) (xy 111.421396 -224.63642) (xy 111.386193 -224.599968) (xy 111.356982 -224.558558)
			(xy 111.334452 -224.513166) (xy 111.319134 -224.46486) (xy 111.311388 -224.41478) (xy 111.310928 -224.389442)
			(xy 111.030004 -224.389442) (xy 111.029496 -224.415329) (xy 111.021397 -224.466467) (xy 111.005398 -224.515707)
			(xy 110.981892 -224.561839) (xy 110.95146 -224.603726) (xy 110.91485 -224.640336) (xy 110.872963 -224.670768)
			(xy 110.826831 -224.694274) (xy 110.777591 -224.710273) (xy 110.726453 -224.718372) (xy 110.674679 -224.718372)
			(xy 110.623541 -224.710273) (xy 110.574301 -224.694274) (xy 110.528169 -224.670768) (xy 110.486282 -224.640336)
			(xy 110.449672 -224.603726) (xy 110.41924 -224.561839) (xy 110.395734 -224.515707) (xy 110.379735 -224.466467)
			(xy 110.371636 -224.415329) (xy 110.371128 -224.389442) (xy 110.090204 -224.389442) (xy 110.08966 -224.417149)
			(xy 110.080474 -224.471796) (xy 110.071916 -224.498154) (xy 110.064042 -224.520252) (xy 110.26902 -224.87509)
			(xy 110.29188 -224.879408) (xy 110.316709 -224.884542) (xy 110.364488 -224.901501) (xy 110.409108 -224.925578)
			(xy 110.449514 -224.956202) (xy 110.484754 -224.992654) (xy 110.513997 -225.034071) (xy 110.536552 -225.079478)
			(xy 110.551888 -225.127804) (xy 110.559643 -225.177908) (xy 110.560104 -225.203258) (xy 110.559596 -225.229165)
			(xy 110.55149 -225.280342) (xy 110.535478 -225.329621) (xy 110.511955 -225.375788) (xy 110.481499 -225.417707)
			(xy 110.444861 -225.454345) (xy 110.402942 -225.484801) (xy 110.356775 -225.508324) (xy 110.307496 -225.524336)
			(xy 110.256319 -225.532442) (xy 110.204505 -225.532442) (xy 110.153328 -225.524336) (xy 110.104049 -225.508324)
			(xy 110.057882 -225.484801) (xy 110.015963 -225.454345) (xy 109.979325 -225.417707) (xy 109.948869 -225.375788)
			(xy 109.925346 -225.329621) (xy 109.909334 -225.280342) (xy 109.901228 -225.229165) (xy 109.90072 -225.203258)
			(xy 109.901327 -225.175541) (xy 109.910642 -225.120895) (xy 109.919262 -225.094546) (xy 109.927136 -225.072448)
			(xy 109.722158 -224.71761) (xy 109.699298 -224.713292) (xy 109.674485 -224.708145) (xy 109.626743 -224.691153)
			(xy 109.582163 -224.667056) (xy 109.541796 -224.63642) (xy 109.506593 -224.599968) (xy 109.477382 -224.558558)
			(xy 109.454852 -224.513166) (xy 109.439534 -224.46486) (xy 109.431788 -224.41478) (xy 109.431328 -224.389442)
			(xy 109.150404 -224.389442) (xy 109.149896 -224.415329) (xy 109.141797 -224.466467) (xy 109.125798 -224.515707)
			(xy 109.102292 -224.561839) (xy 109.07186 -224.603726) (xy 109.03525 -224.640336) (xy 108.993363 -224.670768)
			(xy 108.947231 -224.694274) (xy 108.897991 -224.710273) (xy 108.846853 -224.718372) (xy 108.795079 -224.718372)
			(xy 108.743941 -224.710273) (xy 108.694701 -224.694274) (xy 108.648569 -224.670768) (xy 108.606682 -224.640336)
			(xy 108.570072 -224.603726) (xy 108.53964 -224.561839) (xy 108.516134 -224.515707) (xy 108.500135 -224.466467)
			(xy 108.492036 -224.415329) (xy 108.491528 -224.389442) (xy 108.210604 -224.389442) (xy 108.21006 -224.417149)
			(xy 108.200874 -224.471796) (xy 108.192316 -224.498154) (xy 108.184442 -224.520252) (xy 108.38942 -224.87509)
			(xy 108.41228 -224.879408) (xy 108.437109 -224.884542) (xy 108.484888 -224.901501) (xy 108.529508 -224.925578)
			(xy 108.569914 -224.956202) (xy 108.605154 -224.992654) (xy 108.634397 -225.034071) (xy 108.656952 -225.079478)
			(xy 108.672288 -225.127804) (xy 108.680043 -225.177908) (xy 108.680504 -225.203258) (xy 108.679996 -225.229165)
			(xy 108.67189 -225.280342) (xy 108.655878 -225.329621) (xy 108.632355 -225.375788) (xy 108.601899 -225.417707)
			(xy 108.565261 -225.454345) (xy 108.523342 -225.484801) (xy 108.477175 -225.508324) (xy 108.427896 -225.524336)
			(xy 108.376719 -225.532442) (xy 108.324905 -225.532442) (xy 108.273728 -225.524336) (xy 108.224449 -225.508324)
			(xy 108.178282 -225.484801) (xy 108.136363 -225.454345) (xy 108.099725 -225.417707) (xy 108.069269 -225.375788)
			(xy 108.045746 -225.329621) (xy 108.029734 -225.280342) (xy 108.021628 -225.229165) (xy 108.02112 -225.203258)
			(xy 108.021727 -225.175541) (xy 108.031042 -225.120895) (xy 108.039662 -225.094546) (xy 108.047536 -225.072448)
			(xy 107.842558 -224.71761) (xy 107.819698 -224.713292) (xy 107.794885 -224.708145) (xy 107.747143 -224.691153)
			(xy 107.702563 -224.667056) (xy 107.662196 -224.63642) (xy 107.626993 -224.599968) (xy 107.597782 -224.558558)
			(xy 107.575252 -224.513166) (xy 107.559934 -224.46486) (xy 107.552188 -224.41478) (xy 107.551728 -224.389442)
			(xy 107.270804 -224.389442) (xy 107.270296 -224.415329) (xy 107.262197 -224.466467) (xy 107.246198 -224.515707)
			(xy 107.222692 -224.561839) (xy 107.19226 -224.603726) (xy 107.15565 -224.640336) (xy 107.113763 -224.670768)
			(xy 107.067631 -224.694274) (xy 107.018391 -224.710273) (xy 106.967253 -224.718372) (xy 106.915479 -224.718372)
			(xy 106.864341 -224.710273) (xy 106.815101 -224.694274) (xy 106.768969 -224.670768) (xy 106.727082 -224.640336)
			(xy 106.690472 -224.603726) (xy 106.66004 -224.561839) (xy 106.636534 -224.515707) (xy 106.620535 -224.466467)
			(xy 106.612436 -224.415329) (xy 106.611928 -224.389442) (xy 106.331004 -224.389442) (xy 106.33046 -224.417149)
			(xy 106.321274 -224.471796) (xy 106.312716 -224.498154) (xy 106.304842 -224.520252) (xy 106.50982 -224.87509)
			(xy 106.53268 -224.879408) (xy 106.557509 -224.884542) (xy 106.605288 -224.901501) (xy 106.649908 -224.925578)
			(xy 106.690314 -224.956202) (xy 106.725554 -224.992654) (xy 106.754797 -225.034071) (xy 106.777352 -225.079478)
			(xy 106.792688 -225.127804) (xy 106.800443 -225.177908) (xy 106.800904 -225.203258) (xy 106.800396 -225.229165)
			(xy 106.79229 -225.280342) (xy 106.776278 -225.329621) (xy 106.752755 -225.375788) (xy 106.722299 -225.417707)
			(xy 106.685661 -225.454345) (xy 106.643742 -225.484801) (xy 106.597575 -225.508324) (xy 106.548296 -225.524336)
			(xy 106.497119 -225.532442) (xy 106.445305 -225.532442) (xy 106.394128 -225.524336) (xy 106.344849 -225.508324)
			(xy 106.298682 -225.484801) (xy 106.256763 -225.454345) (xy 106.220125 -225.417707) (xy 106.189669 -225.375788)
			(xy 106.166146 -225.329621) (xy 106.150134 -225.280342) (xy 106.142028 -225.229165) (xy 106.14152 -225.203258)
			(xy 106.142127 -225.175541) (xy 106.151442 -225.120895) (xy 106.160062 -225.094546) (xy 106.167936 -225.072448)
			(xy 105.962958 -224.71761) (xy 105.940098 -224.713292) (xy 105.915285 -224.708145) (xy 105.867543 -224.691153)
			(xy 105.822963 -224.667056) (xy 105.782596 -224.63642) (xy 105.747393 -224.599968) (xy 105.718182 -224.558558)
			(xy 105.695652 -224.513166) (xy 105.680334 -224.46486) (xy 105.672588 -224.41478) (xy 105.672128 -224.389442)
			(xy 105.391204 -224.389442) (xy 105.390696 -224.415329) (xy 105.382597 -224.466467) (xy 105.366598 -224.515707)
			(xy 105.343092 -224.561839) (xy 105.31266 -224.603726) (xy 105.27605 -224.640336) (xy 105.234163 -224.670768)
			(xy 105.188031 -224.694274) (xy 105.138791 -224.710273) (xy 105.087653 -224.718372) (xy 105.035879 -224.718372)
			(xy 104.984741 -224.710273) (xy 104.935501 -224.694274) (xy 104.889369 -224.670768) (xy 104.847482 -224.640336)
			(xy 104.810872 -224.603726) (xy 104.78044 -224.561839) (xy 104.756934 -224.515707) (xy 104.740935 -224.466467)
			(xy 104.732836 -224.415329) (xy 104.732328 -224.389442) (xy 104.451404 -224.389442) (xy 104.45086 -224.417149)
			(xy 104.441674 -224.471796) (xy 104.433116 -224.498154) (xy 104.425242 -224.520252) (xy 104.63022 -224.87509)
			(xy 104.65308 -224.879408) (xy 104.677909 -224.884542) (xy 104.725688 -224.901501) (xy 104.770308 -224.925578)
			(xy 104.810714 -224.956202) (xy 104.845954 -224.992654) (xy 104.875197 -225.034071) (xy 104.897752 -225.079478)
			(xy 104.913088 -225.127804) (xy 104.920843 -225.177908) (xy 104.921304 -225.203258) (xy 104.920796 -225.229165)
			(xy 104.91269 -225.280342) (xy 104.896678 -225.329621) (xy 104.873155 -225.375788) (xy 104.842699 -225.417707)
			(xy 104.806061 -225.454345) (xy 104.764142 -225.484801) (xy 104.717975 -225.508324) (xy 104.668696 -225.524336)
			(xy 104.617519 -225.532442) (xy 104.565705 -225.532442) (xy 104.514528 -225.524336) (xy 104.465249 -225.508324)
			(xy 104.419082 -225.484801) (xy 104.377163 -225.454345) (xy 104.340525 -225.417707) (xy 104.310069 -225.375788)
			(xy 104.286546 -225.329621) (xy 104.270534 -225.280342) (xy 104.262428 -225.229165) (xy 104.26192 -225.203258)
			(xy 104.262527 -225.175541) (xy 104.271842 -225.120895) (xy 104.280462 -225.094546) (xy 104.288336 -225.072448)
			(xy 104.083358 -224.71761) (xy 104.060498 -224.713292) (xy 104.035685 -224.708145) (xy 103.987943 -224.691153)
			(xy 103.943363 -224.667056) (xy 103.902996 -224.63642) (xy 103.867793 -224.599968) (xy 103.838582 -224.558558)
			(xy 103.816052 -224.513166) (xy 103.800734 -224.46486) (xy 103.792988 -224.41478) (xy 103.792528 -224.389442)
			(xy 103.511604 -224.389442) (xy 103.511096 -224.415329) (xy 103.502997 -224.466467) (xy 103.486998 -224.515707)
			(xy 103.463492 -224.561839) (xy 103.43306 -224.603726) (xy 103.39645 -224.640336) (xy 103.354563 -224.670768)
			(xy 103.308431 -224.694274) (xy 103.259191 -224.710273) (xy 103.208053 -224.718372) (xy 103.156279 -224.718372)
			(xy 103.105141 -224.710273) (xy 103.055901 -224.694274) (xy 103.009769 -224.670768) (xy 102.967882 -224.640336)
			(xy 102.931272 -224.603726) (xy 102.90084 -224.561839) (xy 102.877334 -224.515707) (xy 102.861335 -224.466467)
			(xy 102.853236 -224.415329) (xy 102.852728 -224.389442) (xy 102.571804 -224.389442) (xy 102.57126 -224.417149)
			(xy 102.562074 -224.471796) (xy 102.553516 -224.498154) (xy 102.545642 -224.520252) (xy 102.75062 -224.87509)
			(xy 102.77348 -224.879408) (xy 102.798309 -224.884542) (xy 102.846088 -224.901501) (xy 102.890708 -224.925578)
			(xy 102.931114 -224.956202) (xy 102.966354 -224.992654) (xy 102.995597 -225.034071) (xy 103.018152 -225.079478)
			(xy 103.033488 -225.127804) (xy 103.041243 -225.177908) (xy 103.041704 -225.203258) (xy 103.041196 -225.229165)
			(xy 103.03309 -225.280342) (xy 103.017078 -225.329621) (xy 102.993555 -225.375788) (xy 102.963099 -225.417707)
			(xy 102.926461 -225.454345) (xy 102.884542 -225.484801) (xy 102.838375 -225.508324) (xy 102.789096 -225.524336)
			(xy 102.737919 -225.532442) (xy 102.686105 -225.532442) (xy 102.634928 -225.524336) (xy 102.585649 -225.508324)
			(xy 102.539482 -225.484801) (xy 102.497563 -225.454345) (xy 102.460925 -225.417707) (xy 102.430469 -225.375788)
			(xy 102.406946 -225.329621) (xy 102.390934 -225.280342) (xy 102.382828 -225.229165) (xy 102.38232 -225.203258)
			(xy 102.382927 -225.175541) (xy 102.392242 -225.120895) (xy 102.400862 -225.094546) (xy 102.408736 -225.072448)
			(xy 102.203758 -224.71761) (xy 102.180898 -224.713292) (xy 102.156085 -224.708145) (xy 102.108343 -224.691153)
			(xy 102.063763 -224.667056) (xy 102.023396 -224.63642) (xy 101.988193 -224.599968) (xy 101.958982 -224.558558)
			(xy 101.936452 -224.513166) (xy 101.921134 -224.46486) (xy 101.913388 -224.41478) (xy 101.912928 -224.389442)
			(xy 101.632004 -224.389442) (xy 101.631496 -224.415329) (xy 101.623397 -224.466467) (xy 101.607398 -224.515707)
			(xy 101.583892 -224.561839) (xy 101.55346 -224.603726) (xy 101.51685 -224.640336) (xy 101.474963 -224.670768)
			(xy 101.428831 -224.694274) (xy 101.379591 -224.710273) (xy 101.328453 -224.718372) (xy 101.276679 -224.718372)
			(xy 101.225541 -224.710273) (xy 101.176301 -224.694274) (xy 101.130169 -224.670768) (xy 101.088282 -224.640336)
			(xy 101.051672 -224.603726) (xy 101.02124 -224.561839) (xy 100.997734 -224.515707) (xy 100.981735 -224.466467)
			(xy 100.973636 -224.415329) (xy 100.973128 -224.389442) (xy 100.692204 -224.389442) (xy 100.69166 -224.417149)
			(xy 100.682474 -224.471796) (xy 100.673916 -224.498154) (xy 100.666042 -224.520252) (xy 100.87102 -224.87509)
			(xy 100.89388 -224.879408) (xy 100.918709 -224.884542) (xy 100.966488 -224.901501) (xy 101.011108 -224.925578)
			(xy 101.051514 -224.956202) (xy 101.086754 -224.992654) (xy 101.115997 -225.034071) (xy 101.138552 -225.079478)
			(xy 101.153888 -225.127804) (xy 101.161643 -225.177908) (xy 101.162104 -225.203258) (xy 101.161596 -225.229165)
			(xy 101.15349 -225.280342) (xy 101.137478 -225.329621) (xy 101.113955 -225.375788) (xy 101.083499 -225.417707)
			(xy 101.046861 -225.454345) (xy 101.004942 -225.484801) (xy 100.958775 -225.508324) (xy 100.909496 -225.524336)
			(xy 100.858319 -225.532442) (xy 100.806505 -225.532442) (xy 100.755328 -225.524336) (xy 100.706049 -225.508324)
			(xy 100.659882 -225.484801) (xy 100.617963 -225.454345) (xy 100.581325 -225.417707) (xy 100.550869 -225.375788)
			(xy 100.527346 -225.329621) (xy 100.511334 -225.280342) (xy 100.503228 -225.229165) (xy 100.50272 -225.203258)
			(xy 100.503327 -225.175541) (xy 100.512642 -225.120895) (xy 100.521262 -225.094546) (xy 100.529136 -225.072448)
			(xy 100.324158 -224.71761) (xy 100.301298 -224.713292) (xy 100.276485 -224.708145) (xy 100.228743 -224.691153)
			(xy 100.184163 -224.667056) (xy 100.143796 -224.63642) (xy 100.108593 -224.599968) (xy 100.079382 -224.558558)
			(xy 100.056852 -224.513166) (xy 100.041534 -224.46486) (xy 100.033788 -224.41478) (xy 100.033328 -224.389442)
			(xy 99.752404 -224.389442) (xy 99.751896 -224.415329) (xy 99.743797 -224.466467) (xy 99.727798 -224.515707)
			(xy 99.704292 -224.561839) (xy 99.67386 -224.603726) (xy 99.63725 -224.640336) (xy 99.595363 -224.670768)
			(xy 99.549231 -224.694274) (xy 99.499991 -224.710273) (xy 99.448853 -224.718372) (xy 99.397079 -224.718372)
			(xy 99.345941 -224.710273) (xy 99.296701 -224.694274) (xy 99.250569 -224.670768) (xy 99.208682 -224.640336)
			(xy 99.172072 -224.603726) (xy 99.14164 -224.561839) (xy 99.118134 -224.515707) (xy 99.102135 -224.466467)
			(xy 99.094036 -224.415329) (xy 99.093528 -224.389442) (xy 98.812604 -224.389442) (xy 98.81206 -224.417149)
			(xy 98.802874 -224.471796) (xy 98.794316 -224.498154) (xy 98.786442 -224.520252) (xy 98.99142 -224.87509)
			(xy 99.01428 -224.879408) (xy 99.039109 -224.884542) (xy 99.086888 -224.901501) (xy 99.131508 -224.925578)
			(xy 99.171914 -224.956202) (xy 99.207154 -224.992654) (xy 99.236397 -225.034071) (xy 99.258952 -225.079478)
			(xy 99.274288 -225.127804) (xy 99.282043 -225.177908) (xy 99.282504 -225.203258) (xy 99.281996 -225.229165)
			(xy 99.27389 -225.280342) (xy 99.257878 -225.329621) (xy 99.234355 -225.375788) (xy 99.203899 -225.417707)
			(xy 99.167261 -225.454345) (xy 99.125342 -225.484801) (xy 99.079175 -225.508324) (xy 99.029896 -225.524336)
			(xy 98.978719 -225.532442) (xy 98.926905 -225.532442) (xy 98.875728 -225.524336) (xy 98.826449 -225.508324)
			(xy 98.780282 -225.484801) (xy 98.738363 -225.454345) (xy 98.701725 -225.417707) (xy 98.671269 -225.375788)
			(xy 98.647746 -225.329621) (xy 98.631734 -225.280342) (xy 98.623628 -225.229165) (xy 98.62312 -225.203258)
			(xy 98.623727 -225.175541) (xy 98.633042 -225.120895) (xy 98.641662 -225.094546) (xy 98.649536 -225.072448)
			(xy 98.444558 -224.71761) (xy 98.421698 -224.713292) (xy 98.396885 -224.708145) (xy 98.349143 -224.691153)
			(xy 98.304563 -224.667056) (xy 98.264196 -224.63642) (xy 98.228993 -224.599968) (xy 98.199782 -224.558558)
			(xy 98.177252 -224.513166) (xy 98.161934 -224.46486) (xy 98.154188 -224.41478) (xy 98.153728 -224.389442)
			(xy 97.872804 -224.389442) (xy 97.872296 -224.415329) (xy 97.864197 -224.466467) (xy 97.848198 -224.515707)
			(xy 97.824692 -224.561839) (xy 97.79426 -224.603726) (xy 97.75765 -224.640336) (xy 97.715763 -224.670768)
			(xy 97.669631 -224.694274) (xy 97.620391 -224.710273) (xy 97.569253 -224.718372) (xy 97.517479 -224.718372)
			(xy 97.466341 -224.710273) (xy 97.417101 -224.694274) (xy 97.370969 -224.670768) (xy 97.329082 -224.640336)
			(xy 97.292472 -224.603726) (xy 97.26204 -224.561839) (xy 97.238534 -224.515707) (xy 97.222535 -224.466467)
			(xy 97.214436 -224.415329) (xy 97.213928 -224.389442) (xy 96.933004 -224.389442) (xy 96.93246 -224.417149)
			(xy 96.923274 -224.471796) (xy 96.914716 -224.498154) (xy 96.906842 -224.520252) (xy 97.11182 -224.87509)
			(xy 97.13468 -224.879408) (xy 97.159509 -224.884542) (xy 97.207288 -224.901501) (xy 97.251908 -224.925578)
			(xy 97.292314 -224.956202) (xy 97.327554 -224.992654) (xy 97.356797 -225.034071) (xy 97.379352 -225.079478)
			(xy 97.394688 -225.127804) (xy 97.402443 -225.177908) (xy 97.402904 -225.203258) (xy 97.402396 -225.229165)
			(xy 97.39429 -225.280342) (xy 97.378278 -225.329621) (xy 97.354755 -225.375788) (xy 97.324299 -225.417707)
			(xy 97.287661 -225.454345) (xy 97.245742 -225.484801) (xy 97.199575 -225.508324) (xy 97.150296 -225.524336)
			(xy 97.099119 -225.532442) (xy 97.047305 -225.532442) (xy 96.996128 -225.524336) (xy 96.946849 -225.508324)
			(xy 96.900682 -225.484801) (xy 96.858763 -225.454345) (xy 96.822125 -225.417707) (xy 96.791669 -225.375788)
			(xy 96.768146 -225.329621) (xy 96.752134 -225.280342) (xy 96.744028 -225.229165) (xy 96.74352 -225.203258)
			(xy 96.744127 -225.175541) (xy 96.753442 -225.120895) (xy 96.762062 -225.094546) (xy 96.769936 -225.072448)
			(xy 96.564958 -224.71761) (xy 96.542098 -224.713292) (xy 96.517285 -224.708145) (xy 96.469543 -224.691153)
			(xy 96.424963 -224.667056) (xy 96.384596 -224.63642) (xy 96.349393 -224.599968) (xy 96.320182 -224.558558)
			(xy 96.297652 -224.513166) (xy 96.282334 -224.46486) (xy 96.274588 -224.41478) (xy 96.274128 -224.389442)
			(xy 95.993204 -224.389442) (xy 95.992696 -224.415329) (xy 95.984597 -224.466467) (xy 95.968598 -224.515707)
			(xy 95.945092 -224.561839) (xy 95.91466 -224.603726) (xy 95.87805 -224.640336) (xy 95.836163 -224.670768)
			(xy 95.790031 -224.694274) (xy 95.740791 -224.710273) (xy 95.689653 -224.718372) (xy 95.637879 -224.718372)
			(xy 95.586741 -224.710273) (xy 95.537501 -224.694274) (xy 95.491369 -224.670768) (xy 95.449482 -224.640336)
			(xy 95.412872 -224.603726) (xy 95.38244 -224.561839) (xy 95.358934 -224.515707) (xy 95.342935 -224.466467)
			(xy 95.334836 -224.415329) (xy 95.334328 -224.389442) (xy 95.053404 -224.389442) (xy 95.05286 -224.417149)
			(xy 95.043674 -224.471796) (xy 95.035116 -224.498154) (xy 95.027242 -224.520252) (xy 95.23222 -224.87509)
			(xy 95.25508 -224.879408) (xy 95.279909 -224.884542) (xy 95.327688 -224.901501) (xy 95.372308 -224.925578)
			(xy 95.412714 -224.956202) (xy 95.447954 -224.992654) (xy 95.477197 -225.034071) (xy 95.499752 -225.079478)
			(xy 95.515088 -225.127804) (xy 95.522843 -225.177908) (xy 95.523304 -225.203258) (xy 95.522796 -225.229165)
			(xy 95.51469 -225.280342) (xy 95.498678 -225.329621) (xy 95.475155 -225.375788) (xy 95.444699 -225.417707)
			(xy 95.408061 -225.454345) (xy 95.366142 -225.484801) (xy 95.319975 -225.508324) (xy 95.270696 -225.524336)
			(xy 95.219519 -225.532442) (xy 95.167705 -225.532442) (xy 95.116528 -225.524336) (xy 95.067249 -225.508324)
			(xy 95.021082 -225.484801) (xy 94.979163 -225.454345) (xy 94.942525 -225.417707) (xy 94.912069 -225.375788)
			(xy 94.888546 -225.329621) (xy 94.872534 -225.280342) (xy 94.864428 -225.229165) (xy 94.86392 -225.203258)
			(xy 94.864527 -225.175541) (xy 94.873842 -225.120895) (xy 94.882462 -225.094546) (xy 94.890336 -225.072448)
			(xy 94.685358 -224.71761) (xy 94.662498 -224.713292) (xy 94.637685 -224.708145) (xy 94.589943 -224.691153)
			(xy 94.545363 -224.667056) (xy 94.504996 -224.63642) (xy 94.469793 -224.599968) (xy 94.440582 -224.558558)
			(xy 94.418052 -224.513166) (xy 94.402734 -224.46486) (xy 94.394988 -224.41478) (xy 94.394528 -224.389442)
			(xy 94.113604 -224.389442) (xy 94.113096 -224.415329) (xy 94.104997 -224.466467) (xy 94.088998 -224.515707)
			(xy 94.065492 -224.561839) (xy 94.03506 -224.603726) (xy 93.99845 -224.640336) (xy 93.956563 -224.670768)
			(xy 93.910431 -224.694274) (xy 93.861191 -224.710273) (xy 93.810053 -224.718372) (xy 93.758279 -224.718372)
			(xy 93.707141 -224.710273) (xy 93.657901 -224.694274) (xy 93.611769 -224.670768) (xy 93.569882 -224.640336)
			(xy 93.533272 -224.603726) (xy 93.50284 -224.561839) (xy 93.479334 -224.515707) (xy 93.463335 -224.466467)
			(xy 93.455236 -224.415329) (xy 93.454728 -224.389442) (xy 2.509012 -224.389442) (xy 2.509012 -247.620536)
			(xy 228.175312 -247.620536) (xy 228.175312 -246.756936) (xy 228.175798 -246.729685) (xy 228.183554 -246.675737)
			(xy 228.198909 -246.623442) (xy 228.221551 -246.573865) (xy 228.251017 -246.528015) (xy 228.286708 -246.486824)
			(xy 228.327899 -246.451133) (xy 228.373749 -246.421667) (xy 228.423326 -246.399025) (xy 228.475621 -246.38367)
			(xy 228.529569 -246.375914) (xy 228.584071 -246.375914) (xy 228.638019 -246.38367) (xy 228.690314 -246.399025)
			(xy 228.739891 -246.421667) (xy 228.785741 -246.451133) (xy 228.826932 -246.486824) (xy 228.862623 -246.528015)
			(xy 228.892089 -246.573865) (xy 228.914731 -246.623442) (xy 228.930086 -246.675737) (xy 228.937842 -246.729685)
			(xy 228.938328 -246.756936) (xy 228.938328 -247.620536) (xy 228.937842 -247.647787) (xy 228.930086 -247.701735)
			(xy 228.914731 -247.75403) (xy 228.892089 -247.803607) (xy 228.862623 -247.849457) (xy 228.826932 -247.890648)
			(xy 228.785741 -247.926339) (xy 228.739891 -247.955805) (xy 228.690314 -247.978447) (xy 228.638019 -247.993802)
			(xy 228.584071 -248.001558) (xy 228.529569 -248.001558) (xy 228.475621 -247.993802) (xy 228.423326 -247.978447)
			(xy 228.373749 -247.955805) (xy 228.327899 -247.926339) (xy 228.286708 -247.890648) (xy 228.251017 -247.849457)
			(xy 228.221551 -247.803607) (xy 228.198909 -247.75403) (xy 228.183554 -247.701735) (xy 228.175798 -247.647787)
			(xy 228.175312 -247.620536) (xy 2.509012 -247.620536) (xy 2.509012 -251.76988) (xy 75.695566 -251.76988)
			(xy 75.699547 -251.63686) (xy 75.711476 -251.504315) (xy 75.731311 -251.372722) (xy 75.75898 -251.24255)
			(xy 75.794384 -251.114265) (xy 75.837397 -250.988328) (xy 75.887864 -250.865189) (xy 75.945605 -250.745288)
			(xy 76.010414 -250.629055) (xy 76.082058 -250.516905) (xy 76.16028 -250.409241) (xy 76.244801 -250.306448)
			(xy 76.335319 -250.208893) (xy 76.431508 -250.116927) (xy 76.533026 -250.030877) (xy 76.639507 -249.951053)
			(xy 76.750572 -249.87774) (xy 76.865823 -249.8112) (xy 76.984847 -249.751671) (xy 77.107218 -249.699367)
			(xy 77.232497 -249.654475) (xy 77.360238 -249.617156) (xy 77.489981 -249.587543) (xy 77.621263 -249.565742)
			(xy 77.753614 -249.551832) (xy 77.88656 -249.545861) (xy 78.019625 -249.547852) (xy 78.152333 -249.557797)
			(xy 78.284209 -249.575661) (xy 78.41478 -249.601379) (xy 78.54358 -249.63486) (xy 78.670146 -249.675984)
			(xy 78.794027 -249.724604) (xy 78.914778 -249.780545) (xy 79.031968 -249.843607) (xy 79.145177 -249.913565)
			(xy 79.253999 -249.990169) (xy 79.358045 -250.073143) (xy 79.456943 -250.162191) (xy 79.550338 -250.256994)
			(xy 79.637896 -250.357212) (xy 79.719305 -250.462488) (xy 79.794271 -250.572444) (xy 79.862528 -250.686686)
			(xy 79.92383 -250.804806) (xy 79.977959 -250.926381) (xy 80.02472 -251.050975) (xy 80.063946 -251.178143)
			(xy 80.095496 -251.307429) (xy 80.119259 -251.43837) (xy 80.135148 -251.570498) (xy 80.143106 -251.70334)
			(xy 80.143604 -251.76988) (xy 143.715496 -251.76988) (xy 143.719477 -251.63686) (xy 143.731406 -251.504315)
			(xy 143.751241 -251.372722) (xy 143.77891 -251.24255) (xy 143.814314 -251.114265) (xy 143.857327 -250.988328)
			(xy 143.907794 -250.865189) (xy 143.965535 -250.745288) (xy 144.030344 -250.629055) (xy 144.101988 -250.516905)
			(xy 144.18021 -250.409241) (xy 144.264731 -250.306448) (xy 144.355249 -250.208893) (xy 144.451438 -250.116927)
			(xy 144.552956 -250.030877) (xy 144.659437 -249.951053) (xy 144.770502 -249.87774) (xy 144.885753 -249.8112)
			(xy 145.004777 -249.751671) (xy 145.127148 -249.699367) (xy 145.252427 -249.654475) (xy 145.380168 -249.617156)
			(xy 145.509911 -249.587543) (xy 145.641193 -249.565742) (xy 145.773544 -249.551832) (xy 145.90649 -249.545861)
			(xy 146.039555 -249.547852) (xy 146.172263 -249.557797) (xy 146.304139 -249.575661) (xy 146.43471 -249.601379)
			(xy 146.56351 -249.63486) (xy 146.690076 -249.675984) (xy 146.813957 -249.724604) (xy 146.934708 -249.780545)
			(xy 147.051898 -249.843607) (xy 147.165107 -249.913565) (xy 147.273929 -249.990169) (xy 147.377975 -250.073143)
			(xy 147.476873 -250.162191) (xy 147.570268 -250.256994) (xy 147.657826 -250.357212) (xy 147.739235 -250.462488)
			(xy 147.814201 -250.572444) (xy 147.882458 -250.686686) (xy 147.94376 -250.804806) (xy 147.997889 -250.926381)
			(xy 148.04465 -251.050975) (xy 148.083876 -251.178143) (xy 148.115426 -251.307429) (xy 148.139189 -251.43837)
			(xy 148.155078 -251.570498) (xy 148.163036 -251.70334) (xy 148.163534 -251.76988) (xy 323.635634 -251.76988)
			(xy 323.639615 -251.63686) (xy 323.651544 -251.504315) (xy 323.671379 -251.372722) (xy 323.699048 -251.24255)
			(xy 323.734452 -251.114265) (xy 323.777465 -250.988328) (xy 323.827932 -250.865189) (xy 323.885673 -250.745288)
			(xy 323.950482 -250.629055) (xy 324.022126 -250.516905) (xy 324.100348 -250.409241) (xy 324.184869 -250.306448)
			(xy 324.275387 -250.208893) (xy 324.371576 -250.116927) (xy 324.473094 -250.030877) (xy 324.579575 -249.951053)
			(xy 324.69064 -249.87774) (xy 324.805891 -249.8112) (xy 324.924915 -249.751671) (xy 325.047286 -249.699367)
			(xy 325.172565 -249.654475) (xy 325.300306 -249.617156) (xy 325.430049 -249.587543) (xy 325.561331 -249.565742)
			(xy 325.693682 -249.551832) (xy 325.826628 -249.545861) (xy 325.959693 -249.547852) (xy 326.092401 -249.557797)
			(xy 326.224277 -249.575661) (xy 326.354848 -249.601379) (xy 326.483648 -249.63486) (xy 326.610214 -249.675984)
			(xy 326.734095 -249.724604) (xy 326.854846 -249.780545) (xy 326.972036 -249.843607) (xy 327.085245 -249.913565)
			(xy 327.194067 -249.990169) (xy 327.298113 -250.073143) (xy 327.397011 -250.162191) (xy 327.490406 -250.256994)
			(xy 327.577964 -250.357212) (xy 327.659373 -250.462488) (xy 327.734339 -250.572444) (xy 327.802596 -250.686686)
			(xy 327.863898 -250.804806) (xy 327.918027 -250.926381) (xy 327.964788 -251.050975) (xy 328.004014 -251.178143)
			(xy 328.035564 -251.307429) (xy 328.059327 -251.43837) (xy 328.075216 -251.570498) (xy 328.083174 -251.70334)
			(xy 328.083672 -251.76988) (xy 391.655564 -251.76988) (xy 391.659545 -251.63686) (xy 391.671474 -251.504315)
			(xy 391.691309 -251.372722) (xy 391.718978 -251.24255) (xy 391.754382 -251.114265) (xy 391.797395 -250.988328)
			(xy 391.847862 -250.865189) (xy 391.905603 -250.745288) (xy 391.970412 -250.629055) (xy 392.042056 -250.516905)
			(xy 392.120278 -250.409241) (xy 392.204799 -250.306448) (xy 392.295317 -250.208893) (xy 392.391506 -250.116927)
			(xy 392.493024 -250.030877) (xy 392.599505 -249.951053) (xy 392.71057 -249.87774) (xy 392.825821 -249.8112)
			(xy 392.944845 -249.751671) (xy 393.067216 -249.699367) (xy 393.192495 -249.654475) (xy 393.320236 -249.617156)
			(xy 393.449979 -249.587543) (xy 393.581261 -249.565742) (xy 393.713612 -249.551832) (xy 393.846558 -249.545861)
			(xy 393.979623 -249.547852) (xy 394.112331 -249.557797) (xy 394.244207 -249.575661) (xy 394.374778 -249.601379)
			(xy 394.503578 -249.63486) (xy 394.630144 -249.675984) (xy 394.754025 -249.724604) (xy 394.874776 -249.780545)
			(xy 394.991966 -249.843607) (xy 395.105175 -249.913565) (xy 395.213997 -249.990169) (xy 395.318043 -250.073143)
			(xy 395.416941 -250.162191) (xy 395.510336 -250.256994) (xy 395.597894 -250.357212) (xy 395.679303 -250.462488)
			(xy 395.754269 -250.572444) (xy 395.822526 -250.686686) (xy 395.883828 -250.804806) (xy 395.937957 -250.926381)
			(xy 395.984718 -251.050975) (xy 396.023944 -251.178143) (xy 396.055494 -251.307429) (xy 396.079257 -251.43837)
			(xy 396.095146 -251.570498) (xy 396.103104 -251.70334) (xy 396.103602 -251.76988) (xy 396.103104 -251.83642)
			(xy 396.095146 -251.969262) (xy 396.079257 -252.10139) (xy 396.055494 -252.232331) (xy 396.023944 -252.361617)
			(xy 395.984718 -252.488785) (xy 395.937957 -252.613379) (xy 395.883828 -252.734954) (xy 395.822526 -252.853074)
			(xy 395.754269 -252.967316) (xy 395.679303 -253.077272) (xy 395.597894 -253.182548) (xy 395.510336 -253.282766)
			(xy 395.416941 -253.377569) (xy 395.318043 -253.466617) (xy 395.213997 -253.549591) (xy 395.105175 -253.626195)
			(xy 394.991966 -253.696153) (xy 394.874776 -253.759215) (xy 394.754025 -253.815156) (xy 394.630144 -253.863776)
			(xy 394.503578 -253.9049) (xy 394.374778 -253.938381) (xy 394.244207 -253.964099) (xy 394.112331 -253.981963)
			(xy 393.979623 -253.991908) (xy 393.846558 -253.993899) (xy 393.713612 -253.987928) (xy 393.581261 -253.974018)
			(xy 393.449979 -253.952217) (xy 393.320236 -253.922604) (xy 393.192495 -253.885285) (xy 393.067216 -253.840393)
			(xy 392.944845 -253.788089) (xy 392.825821 -253.72856) (xy 392.71057 -253.66202) (xy 392.599505 -253.588707)
			(xy 392.493024 -253.508883) (xy 392.391506 -253.422833) (xy 392.295317 -253.330867) (xy 392.204799 -253.233312)
			(xy 392.120278 -253.130519) (xy 392.042056 -253.022855) (xy 391.970412 -252.910705) (xy 391.905603 -252.794472)
			(xy 391.847862 -252.674571) (xy 391.797395 -252.551432) (xy 391.754382 -252.425495) (xy 391.718978 -252.29721)
			(xy 391.691309 -252.167038) (xy 391.671474 -252.035445) (xy 391.659545 -251.9029) (xy 391.655564 -251.76988)
			(xy 328.083672 -251.76988) (xy 328.083174 -251.83642) (xy 328.075216 -251.969262) (xy 328.059327 -252.10139)
			(xy 328.035564 -252.232331) (xy 328.004014 -252.361617) (xy 327.964788 -252.488785) (xy 327.918027 -252.613379)
			(xy 327.863898 -252.734954) (xy 327.802596 -252.853074) (xy 327.734339 -252.967316) (xy 327.659373 -253.077272)
			(xy 327.577964 -253.182548) (xy 327.490406 -253.282766) (xy 327.397011 -253.377569) (xy 327.298113 -253.466617)
			(xy 327.194067 -253.549591) (xy 327.085245 -253.626195) (xy 326.972036 -253.696153) (xy 326.854846 -253.759215)
			(xy 326.734095 -253.815156) (xy 326.610214 -253.863776) (xy 326.483648 -253.9049) (xy 326.354848 -253.938381)
			(xy 326.224277 -253.964099) (xy 326.092401 -253.981963) (xy 325.959693 -253.991908) (xy 325.826628 -253.993899)
			(xy 325.693682 -253.987928) (xy 325.561331 -253.974018) (xy 325.430049 -253.952217) (xy 325.300306 -253.922604)
			(xy 325.172565 -253.885285) (xy 325.047286 -253.840393) (xy 324.924915 -253.788089) (xy 324.805891 -253.72856)
			(xy 324.69064 -253.66202) (xy 324.579575 -253.588707) (xy 324.473094 -253.508883) (xy 324.371576 -253.422833)
			(xy 324.275387 -253.330867) (xy 324.184869 -253.233312) (xy 324.100348 -253.130519) (xy 324.022126 -253.022855)
			(xy 323.950482 -252.910705) (xy 323.885673 -252.794472) (xy 323.827932 -252.674571) (xy 323.777465 -252.551432)
			(xy 323.734452 -252.425495) (xy 323.699048 -252.29721) (xy 323.671379 -252.167038) (xy 323.651544 -252.035445)
			(xy 323.639615 -251.9029) (xy 323.635634 -251.76988) (xy 148.163534 -251.76988) (xy 148.163036 -251.83642)
			(xy 148.155078 -251.969262) (xy 148.139189 -252.10139) (xy 148.115426 -252.232331) (xy 148.083876 -252.361617)
			(xy 148.04465 -252.488785) (xy 147.997889 -252.613379) (xy 147.94376 -252.734954) (xy 147.882458 -252.853074)
			(xy 147.814201 -252.967316) (xy 147.739235 -253.077272) (xy 147.657826 -253.182548) (xy 147.570268 -253.282766)
			(xy 147.476873 -253.377569) (xy 147.377975 -253.466617) (xy 147.273929 -253.549591) (xy 147.165107 -253.626195)
			(xy 147.051898 -253.696153) (xy 146.934708 -253.759215) (xy 146.813957 -253.815156) (xy 146.690076 -253.863776)
			(xy 146.56351 -253.9049) (xy 146.43471 -253.938381) (xy 146.304139 -253.964099) (xy 146.172263 -253.981963)
			(xy 146.039555 -253.991908) (xy 145.90649 -253.993899) (xy 145.773544 -253.987928) (xy 145.641193 -253.974018)
			(xy 145.509911 -253.952217) (xy 145.380168 -253.922604) (xy 145.252427 -253.885285) (xy 145.127148 -253.840393)
			(xy 145.004777 -253.788089) (xy 144.885753 -253.72856) (xy 144.770502 -253.66202) (xy 144.659437 -253.588707)
			(xy 144.552956 -253.508883) (xy 144.451438 -253.422833) (xy 144.355249 -253.330867) (xy 144.264731 -253.233312)
			(xy 144.18021 -253.130519) (xy 144.101988 -253.022855) (xy 144.030344 -252.910705) (xy 143.965535 -252.794472)
			(xy 143.907794 -252.674571) (xy 143.857327 -252.551432) (xy 143.814314 -252.425495) (xy 143.77891 -252.29721)
			(xy 143.751241 -252.167038) (xy 143.731406 -252.035445) (xy 143.719477 -251.9029) (xy 143.715496 -251.76988)
			(xy 80.143604 -251.76988) (xy 80.143106 -251.83642) (xy 80.135148 -251.969262) (xy 80.119259 -252.10139)
			(xy 80.095496 -252.232331) (xy 80.063946 -252.361617) (xy 80.02472 -252.488785) (xy 79.977959 -252.613379)
			(xy 79.92383 -252.734954) (xy 79.862528 -252.853074) (xy 79.794271 -252.967316) (xy 79.719305 -253.077272)
			(xy 79.637896 -253.182548) (xy 79.550338 -253.282766) (xy 79.456943 -253.377569) (xy 79.358045 -253.466617)
			(xy 79.253999 -253.549591) (xy 79.145177 -253.626195) (xy 79.031968 -253.696153) (xy 78.914778 -253.759215)
			(xy 78.794027 -253.815156) (xy 78.670146 -253.863776) (xy 78.54358 -253.9049) (xy 78.41478 -253.938381)
			(xy 78.284209 -253.964099) (xy 78.152333 -253.981963) (xy 78.019625 -253.991908) (xy 77.88656 -253.993899)
			(xy 77.753614 -253.987928) (xy 77.621263 -253.974018) (xy 77.489981 -253.952217) (xy 77.360238 -253.922604)
			(xy 77.232497 -253.885285) (xy 77.107218 -253.840393) (xy 76.984847 -253.788089) (xy 76.865823 -253.72856)
			(xy 76.750572 -253.66202) (xy 76.639507 -253.588707) (xy 76.533026 -253.508883) (xy 76.431508 -253.422833)
			(xy 76.335319 -253.330867) (xy 76.244801 -253.233312) (xy 76.16028 -253.130519) (xy 76.082058 -253.022855)
			(xy 76.010414 -252.910705) (xy 75.945605 -252.794472) (xy 75.887864 -252.674571) (xy 75.837397 -252.551432)
			(xy 75.794384 -252.425495) (xy 75.75898 -252.29721) (xy 75.731311 -252.167038) (xy 75.711476 -252.035445)
			(xy 75.699547 -251.9029) (xy 75.695566 -251.76988) (xy 2.509012 -251.76988) (xy 2.509012 -273.453098)
			(xy 108.601256 -273.453098) (xy 108.601764 -273.427211) (xy 108.609863 -273.376073) (xy 108.625862 -273.326833)
			(xy 108.649368 -273.280701) (xy 108.6798 -273.238814) (xy 108.71641 -273.202204) (xy 108.758297 -273.171772)
			(xy 108.804429 -273.148266) (xy 108.853669 -273.132267) (xy 108.904807 -273.124168) (xy 108.956581 -273.124168)
			(xy 109.007719 -273.132267) (xy 109.056959 -273.148266) (xy 109.103091 -273.171772) (xy 109.144978 -273.202204)
			(xy 109.181588 -273.238814) (xy 109.21202 -273.280701) (xy 109.235526 -273.326833) (xy 109.251525 -273.376073)
			(xy 109.259624 -273.427211) (xy 109.260132 -273.453098) (xy 356.541324 -273.453098) (xy 356.541832 -273.427211)
			(xy 356.549931 -273.376073) (xy 356.56593 -273.326833) (xy 356.589436 -273.280701) (xy 356.619868 -273.238814)
			(xy 356.656478 -273.202204) (xy 356.698365 -273.171772) (xy 356.744497 -273.148266) (xy 356.793737 -273.132267)
			(xy 356.844875 -273.124168) (xy 356.896649 -273.124168) (xy 356.947787 -273.132267) (xy 356.997027 -273.148266)
			(xy 357.043159 -273.171772) (xy 357.085046 -273.202204) (xy 357.121656 -273.238814) (xy 357.152088 -273.280701)
			(xy 357.175594 -273.326833) (xy 357.191593 -273.376073) (xy 357.199692 -273.427211) (xy 357.2002 -273.453098)
			(xy 357.19967 -273.480806) (xy 357.190475 -273.535453) (xy 357.181912 -273.56181) (xy 357.174292 -273.583654)
			(xy 357.37927 -273.938746) (xy 357.40213 -273.943064) (xy 357.426938 -273.948232) (xy 357.474677 -273.965225)
			(xy 357.519254 -273.989322) (xy 357.559619 -274.019956) (xy 357.594821 -274.056405) (xy 357.624032 -274.097811)
			(xy 357.646564 -274.143199) (xy 357.661886 -274.191501) (xy 357.669637 -274.241577) (xy 357.6701 -274.266914)
			(xy 357.669592 -274.292801) (xy 357.661493 -274.343939) (xy 357.645494 -274.393179) (xy 357.621988 -274.439311)
			(xy 357.591556 -274.481198) (xy 357.554946 -274.517808) (xy 357.513059 -274.54824) (xy 357.466927 -274.571746)
			(xy 357.417687 -274.587745) (xy 357.366549 -274.595844) (xy 357.314775 -274.595844) (xy 357.263637 -274.587745)
			(xy 357.214397 -274.571746) (xy 357.168265 -274.54824) (xy 357.126378 -274.517808) (xy 357.089768 -274.481198)
			(xy 357.059336 -274.439311) (xy 357.03583 -274.393179) (xy 357.019831 -274.343939) (xy 357.011732 -274.292801)
			(xy 357.011224 -274.266914) (xy 357.011756 -274.239206) (xy 357.020949 -274.184559) (xy 357.029512 -274.158202)
			(xy 357.037386 -274.136104) (xy 356.832408 -273.781266) (xy 356.809548 -273.776948) (xy 356.784736 -273.771741)
			(xy 356.73696 -273.75479) (xy 356.692344 -273.730722) (xy 356.651938 -273.700106) (xy 356.616698 -273.663665)
			(xy 356.587453 -273.622257) (xy 356.564893 -273.576859) (xy 356.549551 -273.528542) (xy 356.541789 -273.478445)
			(xy 356.541324 -273.453098) (xy 109.260132 -273.453098) (xy 109.259601 -273.480806) (xy 109.250407 -273.535453)
			(xy 109.241844 -273.56181) (xy 109.234224 -273.583654) (xy 109.439202 -273.938746) (xy 109.462062 -273.943064)
			(xy 109.486859 -273.948281) (xy 109.534598 -273.965264) (xy 109.579176 -273.989353) (xy 109.619543 -274.019979)
			(xy 109.654747 -274.056422) (xy 109.683961 -274.097824) (xy 109.706494 -274.143208) (xy 109.721817 -274.191505)
			(xy 109.729569 -274.241579) (xy 109.730032 -274.266914) (xy 351.372424 -274.266914) (xy 351.372932 -274.241027)
			(xy 351.381031 -274.189889) (xy 351.39703 -274.140649) (xy 351.420536 -274.094517) (xy 351.450968 -274.05263)
			(xy 351.487578 -274.01602) (xy 351.529465 -273.985588) (xy 351.575597 -273.962082) (xy 351.624837 -273.946083)
			(xy 351.675975 -273.937984) (xy 351.727749 -273.937984) (xy 351.778887 -273.946083) (xy 351.828127 -273.962082)
			(xy 351.874259 -273.985588) (xy 351.916146 -274.01602) (xy 351.952756 -274.05263) (xy 351.983188 -274.094517)
			(xy 352.006694 -274.140649) (xy 352.022693 -274.189889) (xy 352.030792 -274.241027) (xy 352.0313 -274.266914)
			(xy 352.0313 -274.267422) (xy 352.030713 -274.294938) (xy 352.021525 -274.349199) (xy 352.013012 -274.375372)
			(xy 352.005392 -274.397216) (xy 352.210624 -274.752562) (xy 352.233484 -274.75688) (xy 352.258307 -274.762037)
			(xy 352.306085 -274.778995) (xy 352.350703 -274.80307) (xy 352.391108 -274.833692) (xy 352.426348 -274.87014)
			(xy 352.455591 -274.911554) (xy 352.478148 -274.956958) (xy 352.493487 -275.00528) (xy 352.501245 -275.055381)
			(xy 352.501708 -275.08073) (xy 352.5012 -275.106637) (xy 352.493094 -275.157814) (xy 352.477082 -275.207093)
			(xy 352.453559 -275.25326) (xy 352.423103 -275.295179) (xy 352.386465 -275.331817) (xy 352.344546 -275.362273)
			(xy 352.298379 -275.385796) (xy 352.2491 -275.401808) (xy 352.197923 -275.409914) (xy 352.146109 -275.409914)
			(xy 352.094932 -275.401808) (xy 352.045653 -275.385796) (xy 351.999486 -275.362273) (xy 351.957567 -275.331817)
			(xy 351.920929 -275.295179) (xy 351.890473 -275.25326) (xy 351.86695 -275.207093) (xy 351.850938 -275.157814)
			(xy 351.842832 -275.106637) (xy 351.842324 -275.08073) (xy 351.842924 -275.053013) (xy 351.852243 -274.998366)
			(xy 351.860866 -274.972018) (xy 351.86874 -274.94992) (xy 351.663762 -274.595082) (xy 351.640902 -274.590764)
			(xy 351.616074 -274.585582) (xy 351.568269 -274.568647) (xy 351.523622 -274.544591) (xy 351.483185 -274.513981)
			(xy 351.447913 -274.47754) (xy 351.418638 -274.436127) (xy 351.39605 -274.390718) (xy 351.380683 -274.342387)
			(xy 351.372898 -274.292272) (xy 351.372424 -274.266914) (xy 109.730032 -274.266914) (xy 109.729524 -274.292801)
			(xy 109.721425 -274.343939) (xy 109.705426 -274.393179) (xy 109.68192 -274.439311) (xy 109.651488 -274.481198)
			(xy 109.614878 -274.517808) (xy 109.572991 -274.54824) (xy 109.526859 -274.571746) (xy 109.477619 -274.587745)
			(xy 109.426481 -274.595844) (xy 109.374707 -274.595844) (xy 109.323569 -274.587745) (xy 109.274329 -274.571746)
			(xy 109.228197 -274.54824) (xy 109.18631 -274.517808) (xy 109.1497 -274.481198) (xy 109.119268 -274.439311)
			(xy 109.095762 -274.393179) (xy 109.079763 -274.343939) (xy 109.071664 -274.292801) (xy 109.071156 -274.266914)
			(xy 109.071691 -274.239206) (xy 109.080883 -274.184559) (xy 109.089444 -274.158202) (xy 109.097318 -274.136104)
			(xy 108.89234 -273.781266) (xy 108.86948 -273.776948) (xy 108.844673 -273.771718) (xy 108.796897 -273.754771)
			(xy 108.75228 -273.730708) (xy 108.711874 -273.700095) (xy 108.676632 -273.663656) (xy 108.647386 -273.622251)
			(xy 108.624826 -273.576855) (xy 108.609484 -273.528539) (xy 108.601721 -273.478444) (xy 108.601256 -273.453098)
			(xy 2.509012 -273.453098) (xy 2.509012 -274.266914) (xy 103.432356 -274.266914) (xy 103.432864 -274.241027)
			(xy 103.440963 -274.189889) (xy 103.456962 -274.140649) (xy 103.480468 -274.094517) (xy 103.5109 -274.05263)
			(xy 103.54751 -274.01602) (xy 103.589397 -273.985588) (xy 103.635529 -273.962082) (xy 103.684769 -273.946083)
			(xy 103.735907 -273.937984) (xy 103.787681 -273.937984) (xy 103.838819 -273.946083) (xy 103.888059 -273.962082)
			(xy 103.934191 -273.985588) (xy 103.976078 -274.01602) (xy 104.012688 -274.05263) (xy 104.04312 -274.094517)
			(xy 104.066626 -274.140649) (xy 104.082625 -274.189889) (xy 104.090724 -274.241027) (xy 104.091232 -274.266914)
			(xy 104.091232 -274.267422) (xy 104.090643 -274.294938) (xy 104.081456 -274.349199) (xy 104.072944 -274.375372)
			(xy 104.065324 -274.397216) (xy 104.270556 -274.752562) (xy 104.293416 -274.75688) (xy 104.318228 -274.762086)
			(xy 104.366006 -274.779035) (xy 104.410625 -274.803101) (xy 104.451032 -274.833715) (xy 104.486274 -274.870157)
			(xy 104.515519 -274.911566) (xy 104.538078 -274.956966) (xy 104.553418 -275.005285) (xy 104.561177 -275.055382)
			(xy 104.56164 -275.08073) (xy 104.561132 -275.106637) (xy 104.553026 -275.157814) (xy 104.537014 -275.207093)
			(xy 104.513491 -275.25326) (xy 104.483035 -275.295179) (xy 104.446397 -275.331817) (xy 104.404478 -275.362273)
			(xy 104.358311 -275.385796) (xy 104.309032 -275.401808) (xy 104.257855 -275.409914) (xy 104.206041 -275.409914)
			(xy 104.154864 -275.401808) (xy 104.105585 -275.385796) (xy 104.059418 -275.362273) (xy 104.017499 -275.331817)
			(xy 103.980861 -275.295179) (xy 103.950405 -275.25326) (xy 103.926882 -275.207093) (xy 103.91087 -275.157814)
			(xy 103.902764 -275.106637) (xy 103.902256 -275.08073) (xy 103.902854 -275.053013) (xy 103.912174 -274.998366)
			(xy 103.920798 -274.972018) (xy 103.928672 -274.94992) (xy 103.723694 -274.595082) (xy 103.700834 -274.590764)
			(xy 103.676011 -274.585559) (xy 103.628206 -274.568629) (xy 103.583558 -274.544577) (xy 103.543121 -274.51397)
			(xy 103.507847 -274.477532) (xy 103.478571 -274.436121) (xy 103.455983 -274.390715) (xy 103.440615 -274.342385)
			(xy 103.43283 -274.292271) (xy 103.432356 -274.266914) (xy 2.509012 -274.266914) (xy 2.509012 -275.10659)
			(xy 102.023373 -275.10659) (xy 102.023373 -275.05481) (xy 102.031474 -275.003669) (xy 102.047476 -274.954425)
			(xy 102.070985 -274.90829) (xy 102.101423 -274.866402) (xy 102.138039 -274.829791) (xy 102.179931 -274.79936)
			(xy 102.226069 -274.775858) (xy 102.275316 -274.759863) (xy 102.326458 -274.75177) (xy 102.352348 -274.751292)
			(xy 102.377861 -274.751741) (xy 102.428277 -274.759608) (xy 102.476879 -274.775148) (xy 102.522507 -274.79799)
			(xy 102.564072 -274.827588) (xy 102.600581 -274.863235) (xy 102.616254 -274.883372) (xy 103.028242 -274.883372)
			(xy 103.043883 -274.86321) (xy 103.0804 -274.827569) (xy 103.121973 -274.797979) (xy 103.167607 -274.775148)
			(xy 103.216215 -274.75962) (xy 103.266634 -274.751765) (xy 103.292148 -274.751292) (xy 103.318035 -274.751743)
			(xy 103.369171 -274.759849) (xy 103.41841 -274.775854) (xy 103.464539 -274.799364) (xy 103.506423 -274.8298)
			(xy 103.543031 -274.866413) (xy 103.573461 -274.908302) (xy 103.596964 -274.954434) (xy 103.612962 -275.003675)
			(xy 103.62106 -275.054813) (xy 103.62106 -275.106587) (xy 103.612962 -275.157725) (xy 103.596964 -275.206966)
			(xy 103.573461 -275.253098) (xy 103.543031 -275.294987) (xy 103.506423 -275.3316) (xy 103.464539 -275.362036)
			(xy 103.41841 -275.385546) (xy 103.369171 -275.401551) (xy 103.318035 -275.409657) (xy 103.292148 -275.410168)
			(xy 103.266637 -275.409665) (xy 103.216223 -275.401811) (xy 103.167621 -275.386283) (xy 103.121992 -275.363452)
			(xy 103.080426 -275.333862) (xy 103.043916 -275.298222) (xy 103.028242 -275.278088) (xy 102.616254 -275.278088)
			(xy 102.600546 -275.298195) (xy 102.564044 -275.333841) (xy 102.522486 -275.363438) (xy 102.476864 -275.386279)
			(xy 102.428268 -275.401819) (xy 102.377858 -275.409687) (xy 102.352348 -275.410168) (xy 102.326458 -275.40963)
			(xy 102.275316 -275.401537) (xy 102.226069 -275.385542) (xy 102.179931 -275.36204) (xy 102.138039 -275.331609)
			(xy 102.101423 -275.294998) (xy 102.070985 -275.25311) (xy 102.047476 -275.206975) (xy 102.031474 -275.157731)
			(xy 102.023373 -275.10659) (xy 2.509012 -275.10659) (xy 2.509012 -276.708616) (xy 102.022656 -276.708616)
			(xy 102.023189 -276.683284) (xy 102.030938 -276.633215) (xy 102.046256 -276.584922) (xy 102.068781 -276.53954)
			(xy 102.097985 -276.498139) (xy 102.133179 -276.461694) (xy 102.173534 -276.431062) (xy 102.218101 -276.406964)
			(xy 102.265829 -276.389968) (xy 102.290626 -276.384766) (xy 102.313486 -276.380448) (xy 102.518464 -276.025356)
			(xy 102.510844 -276.003512) (xy 102.502285 -275.977153) (xy 102.493085 -275.922508) (xy 102.492556 -275.8948)
			(xy 102.493064 -275.868913) (xy 102.501163 -275.817775) (xy 102.517162 -275.768535) (xy 102.540668 -275.722403)
			(xy 102.5711 -275.680516) (xy 102.60771 -275.643906) (xy 102.649597 -275.613474) (xy 102.695729 -275.589968)
			(xy 102.744969 -275.573969) (xy 102.796107 -275.56587) (xy 102.847881 -275.56587) (xy 102.899019 -275.573969)
			(xy 102.948259 -275.589968) (xy 102.994391 -275.613474) (xy 103.036278 -275.643906) (xy 103.072888 -275.680516)
			(xy 103.10332 -275.722403) (xy 103.126826 -275.768535) (xy 103.142825 -275.817775) (xy 103.150924 -275.868913)
			(xy 103.151432 -275.8948) (xy 104.372156 -275.8948) (xy 104.372675 -275.869467) (xy 104.380426 -275.819398)
			(xy 104.395746 -275.771105) (xy 104.418273 -275.725723) (xy 104.447479 -275.684322) (xy 104.482674 -275.647877)
			(xy 104.523031 -275.617245) (xy 104.567599 -275.593147) (xy 104.615329 -275.576152) (xy 104.640126 -275.57095)
			(xy 104.662986 -275.566632) (xy 104.868218 -275.211286) (xy 104.860598 -275.189188) (xy 104.851972 -275.162906)
			(xy 104.842659 -275.108385) (xy 104.842056 -275.08073) (xy 104.842564 -275.054823) (xy 104.85067 -275.003646)
			(xy 104.866682 -274.954367) (xy 104.890205 -274.9082) (xy 104.920661 -274.866281) (xy 104.957299 -274.829643)
			(xy 104.999218 -274.799187) (xy 105.045385 -274.775664) (xy 105.094664 -274.759652) (xy 105.145841 -274.751546)
			(xy 105.197655 -274.751546) (xy 105.248832 -274.759652) (xy 105.298111 -274.775664) (xy 105.344278 -274.799187)
			(xy 105.386197 -274.829643) (xy 105.422835 -274.866281) (xy 105.453291 -274.9082) (xy 105.476814 -274.954367)
			(xy 105.492826 -275.003646) (xy 105.500932 -275.054823) (xy 105.50144 -275.08073) (xy 107.661456 -275.08073)
			(xy 107.661964 -275.054823) (xy 107.67007 -275.003646) (xy 107.686082 -274.954367) (xy 107.709605 -274.9082)
			(xy 107.740061 -274.866281) (xy 107.776699 -274.829643) (xy 107.818618 -274.799187) (xy 107.864785 -274.775664)
			(xy 107.914064 -274.759652) (xy 107.965241 -274.751546) (xy 108.017055 -274.751546) (xy 108.068232 -274.759652)
			(xy 108.117511 -274.775664) (xy 108.163678 -274.799187) (xy 108.205597 -274.829643) (xy 108.242235 -274.866281)
			(xy 108.272691 -274.9082) (xy 108.296214 -274.954367) (xy 108.312226 -275.003646) (xy 108.320332 -275.054823)
			(xy 108.32084 -275.08073) (xy 108.320273 -275.106588) (xy 349.963473 -275.106588) (xy 349.963473 -275.054812)
			(xy 349.971573 -275.003674) (xy 349.987573 -274.954432) (xy 350.011079 -274.9083) (xy 350.041513 -274.866413)
			(xy 350.078125 -274.829803) (xy 350.120014 -274.799371) (xy 350.166147 -274.775867) (xy 350.215389 -274.759869)
			(xy 350.266528 -274.751772) (xy 350.292416 -274.751292) (xy 350.317928 -274.751764) (xy 350.368343 -274.759627)
			(xy 350.416945 -274.775162) (xy 350.462573 -274.797999) (xy 350.504138 -274.827593) (xy 350.540648 -274.863237)
			(xy 350.556322 -274.883372) (xy 350.96831 -274.883372) (xy 350.98397 -274.863226) (xy 351.020483 -274.827584)
			(xy 351.062052 -274.797992) (xy 351.107683 -274.775158) (xy 351.156287 -274.759626) (xy 351.206703 -274.751768)
			(xy 351.232216 -274.751292) (xy 351.258105 -274.751741) (xy 351.309245 -274.759843) (xy 351.358488 -274.775845)
			(xy 351.404622 -274.799353) (xy 351.44651 -274.829789) (xy 351.483122 -274.866402) (xy 351.513555 -274.908292)
			(xy 351.537061 -274.954427) (xy 351.553061 -275.003671) (xy 351.56116 -275.054811) (xy 351.56116 -275.106589)
			(xy 351.553061 -275.157729) (xy 351.537061 -275.206973) (xy 351.513555 -275.253108) (xy 351.483122 -275.294998)
			(xy 351.44651 -275.331611) (xy 351.404622 -275.362047) (xy 351.358488 -275.385555) (xy 351.309245 -275.401557)
			(xy 351.258105 -275.409659) (xy 351.232216 -275.410168) (xy 351.206704 -275.409689) (xy 351.156289 -275.401829)
			(xy 351.107687 -275.386297) (xy 351.062058 -275.363461) (xy 351.020493 -275.333868) (xy 350.983983 -275.298224)
			(xy 350.96831 -275.278088) (xy 350.556322 -275.278088) (xy 350.540633 -275.29821) (xy 350.504126 -275.333856)
			(xy 350.462565 -275.363451) (xy 350.416939 -275.386289) (xy 350.36834 -275.401826) (xy 350.317927 -275.409689)
			(xy 350.292416 -275.410168) (xy 350.266528 -275.409628) (xy 350.215389 -275.401531) (xy 350.166147 -275.385533)
			(xy 350.120014 -275.362029) (xy 350.078125 -275.331597) (xy 350.041513 -275.294987) (xy 350.011079 -275.2531)
			(xy 349.987573 -275.206968) (xy 349.971573 -275.157726) (xy 349.963473 -275.106588) (xy 108.320273 -275.106588)
			(xy 108.320232 -275.108447) (xy 108.310918 -275.163093) (xy 108.302298 -275.189442) (xy 108.294424 -275.21154)
			(xy 108.499656 -275.566632) (xy 108.522516 -275.57095) (xy 108.547321 -275.576185) (xy 108.595097 -275.593131)
			(xy 108.639715 -275.617194) (xy 108.680121 -275.647805) (xy 108.715363 -275.684244) (xy 108.744609 -275.725649)
			(xy 108.767169 -275.771044) (xy 108.782512 -275.819359) (xy 108.790275 -275.869454) (xy 108.79074 -275.8948)
			(xy 108.790232 -275.920707) (xy 108.782126 -275.971884) (xy 108.766114 -276.021163) (xy 108.742591 -276.06733)
			(xy 108.712135 -276.109249) (xy 108.675497 -276.145887) (xy 108.633578 -276.176343) (xy 108.587411 -276.199866)
			(xy 108.538132 -276.215878) (xy 108.486955 -276.223984) (xy 108.435141 -276.223984) (xy 108.383964 -276.215878)
			(xy 108.334685 -276.199866) (xy 108.288518 -276.176343) (xy 108.246599 -276.145887) (xy 108.209961 -276.109249)
			(xy 108.179505 -276.06733) (xy 108.155982 -276.021163) (xy 108.13997 -275.971884) (xy 108.131864 -275.920707)
			(xy 108.131356 -275.8948) (xy 108.131947 -275.867082) (xy 108.141272 -275.812436) (xy 108.149898 -275.786088)
			(xy 108.157772 -275.76399) (xy 107.95254 -275.408898) (xy 107.92968 -275.40458) (xy 107.904858 -275.399414)
			(xy 107.857077 -275.382462) (xy 107.812456 -275.358392) (xy 107.772048 -275.327773) (xy 107.736806 -275.291325)
			(xy 107.707562 -275.249911) (xy 107.685006 -275.204506) (xy 107.66967 -275.156182) (xy 107.661916 -275.10608)
			(xy 107.661456 -275.08073) (xy 105.50144 -275.08073) (xy 105.500998 -275.106094) (xy 105.493245 -275.156227)
			(xy 105.477898 -275.204578) (xy 105.455318 -275.250004) (xy 105.42604 -275.291431) (xy 105.390756 -275.327878)
			(xy 105.350301 -275.358484) (xy 105.305631 -275.382526) (xy 105.257803 -275.399433) (xy 105.232962 -275.40458)
			(xy 105.209848 -275.408898) (xy 105.00487 -275.76399) (xy 105.012744 -275.786088) (xy 105.021303 -275.812447)
			(xy 105.030503 -275.867092) (xy 105.031032 -275.8948) (xy 105.030524 -275.920687) (xy 105.030521 -275.920707)
			(xy 106.252016 -275.920707) (xy 106.252016 -275.868893) (xy 106.260122 -275.817717) (xy 106.276133 -275.768439)
			(xy 106.299656 -275.722272) (xy 106.330111 -275.680353) (xy 106.366749 -275.643715) (xy 106.408667 -275.613259)
			(xy 106.454833 -275.589735) (xy 106.504111 -275.573723) (xy 106.555287 -275.565617) (xy 106.581194 -275.565108)
			(xy 106.606706 -275.56559) (xy 106.65712 -275.57345) (xy 106.705722 -275.588983) (xy 106.75135 -275.611818)
			(xy 106.792916 -275.64141) (xy 106.829426 -275.677053) (xy 106.8451 -275.697188) (xy 107.257088 -275.697188)
			(xy 107.272765 -275.677056) (xy 107.309275 -275.641412) (xy 107.350839 -275.611819) (xy 107.396467 -275.588982)
			(xy 107.445068 -275.573448) (xy 107.495482 -275.565586) (xy 107.520994 -275.565108) (xy 107.546904 -275.565589)
			(xy 107.598085 -275.573695) (xy 107.647369 -275.589707) (xy 107.693541 -275.613232) (xy 107.735464 -275.64369)
			(xy 107.772106 -275.680332) (xy 107.802565 -275.722254) (xy 107.826091 -275.768426) (xy 107.842104 -275.817709)
			(xy 107.85021 -275.86889) (xy 107.85021 -275.92071) (xy 107.842104 -275.971891) (xy 107.826091 -276.021174)
			(xy 107.802565 -276.067346) (xy 107.772106 -276.109268) (xy 107.735464 -276.14591) (xy 107.693541 -276.176368)
			(xy 107.647369 -276.199893) (xy 107.598085 -276.215905) (xy 107.546904 -276.224011) (xy 107.520994 -276.224492)
			(xy 107.495482 -276.224019) (xy 107.445067 -276.216157) (xy 107.396465 -276.200622) (xy 107.350837 -276.177785)
			(xy 107.309271 -276.148192) (xy 107.272762 -276.112547) (xy 107.257088 -276.092412) (xy 106.8451 -276.092412)
			(xy 106.82943 -276.11255) (xy 106.792919 -276.148193) (xy 106.751353 -276.177786) (xy 106.705724 -276.200622)
			(xy 106.657121 -276.216155) (xy 106.606706 -276.224015) (xy 106.581194 -276.224492) (xy 106.555287 -276.223983)
			(xy 106.504111 -276.215877) (xy 106.454833 -276.199865) (xy 106.408667 -276.176341) (xy 106.366749 -276.145885)
			(xy 106.330111 -276.109247) (xy 106.299656 -276.067328) (xy 106.276133 -276.021161) (xy 106.260122 -275.971883)
			(xy 106.252016 -275.920707) (xy 105.030521 -275.920707) (xy 105.022425 -275.971825) (xy 105.006426 -276.021065)
			(xy 104.98292 -276.067197) (xy 104.952488 -276.109084) (xy 104.915878 -276.145694) (xy 104.873991 -276.176126)
			(xy 104.827859 -276.199632) (xy 104.778619 -276.215631) (xy 104.727481 -276.22373) (xy 104.675707 -276.22373)
			(xy 104.624569 -276.215631) (xy 104.575329 -276.199632) (xy 104.529197 -276.176126) (xy 104.48731 -276.145694)
			(xy 104.4507 -276.109084) (xy 104.420268 -276.067197) (xy 104.396762 -276.021065) (xy 104.380763 -275.971825)
			(xy 104.372664 -275.920687) (xy 104.372156 -275.8948) (xy 103.151432 -275.8948) (xy 103.150966 -275.920146)
			(xy 103.143192 -275.97024) (xy 103.127843 -276.018553) (xy 103.105281 -276.063948) (xy 103.076038 -276.105356)
			(xy 103.040801 -276.1418) (xy 103.000402 -276.172421) (xy 102.955792 -276.196499) (xy 102.908023 -276.213466)
			(xy 102.883208 -276.21865) (xy 102.860348 -276.222968) (xy 102.65537 -276.577806) (xy 102.663244 -276.599904)
			(xy 102.671807 -276.626262) (xy 102.681004 -276.680908) (xy 102.681532 -276.708616) (xy 102.962456 -276.708616)
			(xy 102.962964 -276.682709) (xy 102.97107 -276.631532) (xy 102.987082 -276.582253) (xy 103.010605 -276.536086)
			(xy 103.041061 -276.494167) (xy 103.077699 -276.457529) (xy 103.119618 -276.427073) (xy 103.165785 -276.40355)
			(xy 103.215064 -276.387538) (xy 103.266241 -276.379432) (xy 103.318055 -276.379432) (xy 103.369232 -276.387538)
			(xy 103.418511 -276.40355) (xy 103.464678 -276.427073) (xy 103.506597 -276.457529) (xy 103.543235 -276.494167)
			(xy 103.573691 -276.536086) (xy 103.597214 -276.582253) (xy 103.613226 -276.631532) (xy 103.621332 -276.682709)
			(xy 103.62184 -276.708616) (xy 103.621308 -276.734511) (xy 103.902706 -276.734511) (xy 103.902706 -276.682689)
			(xy 103.910813 -276.631506) (xy 103.926828 -276.582222) (xy 103.950356 -276.53605) (xy 103.980818 -276.494128)
			(xy 104.017464 -276.457487) (xy 104.059391 -276.427031) (xy 104.105566 -276.40351) (xy 104.154853 -276.387502)
			(xy 104.206037 -276.379402) (xy 104.231948 -276.378924) (xy 104.257462 -276.37936) (xy 104.307879 -276.387228)
			(xy 104.356482 -276.40277) (xy 104.40211 -276.425614) (xy 104.443674 -276.455215) (xy 104.480182 -276.490865)
			(xy 104.495854 -276.511004) (xy 104.907842 -276.511004) (xy 104.923492 -276.490849) (xy 104.960006 -276.455206)
			(xy 105.001577 -276.425615) (xy 105.04721 -276.402782) (xy 105.095816 -276.387253) (xy 105.146235 -276.379398)
			(xy 105.171748 -276.378924) (xy 105.197654 -276.379404) (xy 105.248828 -276.387515) (xy 105.298102 -276.403532)
			(xy 105.344265 -276.427059) (xy 105.38618 -276.457517) (xy 105.422814 -276.494157) (xy 105.453266 -276.536076)
			(xy 105.476786 -276.582242) (xy 105.492796 -276.631519) (xy 105.5009 -276.682694) (xy 105.5009 -276.734506)
			(xy 105.492796 -276.785681) (xy 105.476786 -276.834958) (xy 105.453266 -276.881124) (xy 105.422814 -276.923043)
			(xy 105.38618 -276.959683) (xy 105.344265 -276.990141) (xy 105.298102 -277.013668) (xy 105.248828 -277.029685)
			(xy 105.197654 -277.037796) (xy 105.171748 -277.038308) (xy 105.146238 -277.037789) (xy 105.095825 -277.029936)
			(xy 105.047224 -277.01441) (xy 105.001596 -276.991582) (xy 104.960029 -276.961996) (xy 104.923517 -276.92636)
			(xy 104.907842 -276.906228) (xy 104.495854 -276.906228) (xy 104.480157 -276.926344) (xy 104.443651 -276.961988)
			(xy 104.40209 -276.991583) (xy 104.356467 -277.014422) (xy 104.307869 -277.029961) (xy 104.257458 -277.037827)
			(xy 104.231948 -277.038308) (xy 104.206037 -277.037798) (xy 104.154853 -277.029698) (xy 104.105566 -277.01369)
			(xy 104.059391 -276.990169) (xy 104.017464 -276.959713) (xy 103.980818 -276.923072) (xy 103.950356 -276.88115)
			(xy 103.926828 -276.834978) (xy 103.910813 -276.785694) (xy 103.902706 -276.734511) (xy 103.621308 -276.734511)
			(xy 103.621269 -276.736398) (xy 103.611945 -276.791174) (xy 103.603298 -276.817582) (xy 103.595424 -276.839426)
			(xy 103.800402 -277.194264) (xy 103.823262 -277.198582) (xy 103.848063 -277.203782) (xy 103.895803 -277.220766)
			(xy 103.940382 -277.244857) (xy 103.98075 -277.275485) (xy 104.015954 -277.311931) (xy 104.045167 -277.353334)
			(xy 104.067699 -277.398721) (xy 104.083021 -277.44702) (xy 104.09077 -277.497096) (xy 104.091232 -277.522432)
			(xy 106.251756 -277.522432) (xy 106.252213 -277.497097) (xy 106.259974 -277.447026) (xy 106.275303 -277.39873)
			(xy 106.297839 -277.353349) (xy 106.327053 -277.311948) (xy 106.362255 -277.275504) (xy 106.402618 -277.244873)
			(xy 106.447192 -277.220777) (xy 106.494926 -277.203783) (xy 106.519726 -277.198582) (xy 106.542586 -277.194264)
			(xy 106.747818 -276.838918) (xy 106.740198 -276.817074) (xy 106.731593 -276.790786) (xy 106.722266 -276.736269)
			(xy 106.721656 -276.708616) (xy 106.722164 -276.682709) (xy 106.73027 -276.631532) (xy 106.746282 -276.582253)
			(xy 106.769805 -276.536086) (xy 106.800261 -276.494167) (xy 106.836899 -276.457529) (xy 106.878818 -276.427073)
			(xy 106.924985 -276.40355) (xy 106.974264 -276.387538) (xy 107.025441 -276.379432) (xy 107.077255 -276.379432)
			(xy 107.128432 -276.387538) (xy 107.177711 -276.40355) (xy 107.223878 -276.427073) (xy 107.265797 -276.457529)
			(xy 107.302435 -276.494167) (xy 107.332891 -276.536086) (xy 107.356414 -276.582253) (xy 107.372426 -276.631532)
			(xy 107.380532 -276.682709) (xy 107.38104 -276.708616) (xy 108.601256 -276.708616) (xy 108.601789 -276.683284)
			(xy 108.609538 -276.633215) (xy 108.624856 -276.584922) (xy 108.647381 -276.53954) (xy 108.676585 -276.498139)
			(xy 108.711779 -276.461694) (xy 108.752134 -276.431062) (xy 108.796701 -276.406964) (xy 108.844429 -276.389968)
			(xy 108.869226 -276.384766) (xy 108.892086 -276.380448) (xy 109.097064 -276.02561) (xy 109.08919 -276.003766)
			(xy 109.080545 -275.977358) (xy 109.071224 -275.922582) (xy 109.070648 -275.8948) (xy 109.071156 -275.868893)
			(xy 109.079262 -275.817716) (xy 109.095274 -275.768437) (xy 109.118797 -275.72227) (xy 109.149253 -275.680351)
			(xy 109.185891 -275.643713) (xy 109.22781 -275.613257) (xy 109.273977 -275.589734) (xy 109.323256 -275.573722)
			(xy 109.374433 -275.565616) (xy 109.426247 -275.565616) (xy 109.477424 -275.573722) (xy 109.526703 -275.589734)
			(xy 109.57287 -275.613257) (xy 109.614789 -275.643713) (xy 109.651427 -275.680351) (xy 109.681883 -275.72227)
			(xy 109.705406 -275.768437) (xy 109.721418 -275.817716) (xy 109.729524 -275.868893) (xy 109.730032 -275.8948)
			(xy 109.729566 -275.920146) (xy 109.721792 -275.97024) (xy 109.706443 -276.018553) (xy 109.683881 -276.063948)
			(xy 109.654638 -276.105356) (xy 109.619401 -276.1418) (xy 109.579002 -276.172421) (xy 109.534392 -276.196499)
			(xy 109.486623 -276.213466) (xy 109.461808 -276.21865) (xy 109.438948 -276.222968) (xy 109.23397 -276.577806)
			(xy 109.241844 -276.599904) (xy 109.250407 -276.626262) (xy 109.259604 -276.680908) (xy 109.260132 -276.708616)
			(xy 349.962724 -276.708616) (xy 349.963202 -276.683281) (xy 349.970953 -276.633207) (xy 349.986274 -276.584909)
			(xy 350.008806 -276.539525) (xy 350.038016 -276.498122) (xy 350.073218 -276.461676) (xy 350.113581 -276.431046)
			(xy 350.158157 -276.406953) (xy 350.205894 -276.389964) (xy 350.230694 -276.384766) (xy 350.253554 -276.380448)
			(xy 350.458532 -276.025356) (xy 350.450912 -276.003512) (xy 350.442352 -275.977154) (xy 350.433153 -275.922508)
			(xy 350.432624 -275.8948) (xy 350.433132 -275.868913) (xy 350.441231 -275.817775) (xy 350.45723 -275.768535)
			(xy 350.480736 -275.722403) (xy 350.511168 -275.680516) (xy 350.547778 -275.643906) (xy 350.589665 -275.613474)
			(xy 350.635797 -275.589968) (xy 350.685037 -275.573969) (xy 350.736175 -275.56587) (xy 350.787949 -275.56587)
			(xy 350.839087 -275.573969) (xy 350.888327 -275.589968) (xy 350.934459 -275.613474) (xy 350.976346 -275.643906)
			(xy 351.012956 -275.680516) (xy 351.043388 -275.722403) (xy 351.066894 -275.768535) (xy 351.082893 -275.817775)
			(xy 351.090992 -275.868913) (xy 351.0915 -275.8948) (xy 352.312224 -275.8948) (xy 352.312688 -275.869465)
			(xy 352.320441 -275.81939) (xy 352.335764 -275.771092) (xy 352.358298 -275.725707) (xy 352.38751 -275.684304)
			(xy 352.422713 -275.647859) (xy 352.463078 -275.617229) (xy 352.507655 -275.593136) (xy 352.555393 -275.576148)
			(xy 352.580194 -275.57095) (xy 352.603054 -275.566632) (xy 352.808286 -275.211286) (xy 352.800666 -275.189188)
			(xy 352.792042 -275.162906) (xy 352.782727 -275.108385) (xy 352.782124 -275.08073) (xy 352.782632 -275.054823)
			(xy 352.790738 -275.003646) (xy 352.80675 -274.954367) (xy 352.830273 -274.9082) (xy 352.860729 -274.866281)
			(xy 352.897367 -274.829643) (xy 352.939286 -274.799187) (xy 352.985453 -274.775664) (xy 353.034732 -274.759652)
			(xy 353.085909 -274.751546) (xy 353.137723 -274.751546) (xy 353.1889 -274.759652) (xy 353.238179 -274.775664)
			(xy 353.284346 -274.799187) (xy 353.326265 -274.829643) (xy 353.362903 -274.866281) (xy 353.393359 -274.9082)
			(xy 353.416882 -274.954367) (xy 353.432894 -275.003646) (xy 353.441 -275.054823) (xy 353.441508 -275.08073)
			(xy 355.601524 -275.08073) (xy 355.602032 -275.054823) (xy 355.610138 -275.003646) (xy 355.62615 -274.954367)
			(xy 355.649673 -274.9082) (xy 355.680129 -274.866281) (xy 355.716767 -274.829643) (xy 355.758686 -274.799187)
			(xy 355.804853 -274.775664) (xy 355.854132 -274.759652) (xy 355.905309 -274.751546) (xy 355.957123 -274.751546)
			(xy 356.0083 -274.759652) (xy 356.057579 -274.775664) (xy 356.103746 -274.799187) (xy 356.145665 -274.829643)
			(xy 356.182303 -274.866281) (xy 356.212759 -274.9082) (xy 356.236282 -274.954367) (xy 356.252294 -275.003646)
			(xy 356.2604 -275.054823) (xy 356.260908 -275.08073) (xy 356.260296 -275.108446) (xy 356.250985 -275.163093)
			(xy 356.242366 -275.189442) (xy 356.234492 -275.21154) (xy 356.439724 -275.566632) (xy 356.462584 -275.57095)
			(xy 356.4874 -275.576135) (xy 356.535176 -275.593092) (xy 356.579792 -275.617163) (xy 356.620197 -275.647782)
			(xy 356.655436 -275.684226) (xy 356.684681 -275.725636) (xy 356.707239 -275.771036) (xy 356.722581 -275.819355)
			(xy 356.730343 -275.869452) (xy 356.730808 -275.8948) (xy 356.7303 -275.920707) (xy 356.722194 -275.971884)
			(xy 356.706182 -276.021163) (xy 356.682659 -276.06733) (xy 356.652203 -276.109249) (xy 356.615565 -276.145887)
			(xy 356.573646 -276.176343) (xy 356.527479 -276.199866) (xy 356.4782 -276.215878) (xy 356.427023 -276.223984)
			(xy 356.375209 -276.223984) (xy 356.324032 -276.215878) (xy 356.274753 -276.199866) (xy 356.228586 -276.176343)
			(xy 356.186667 -276.145887) (xy 356.150029 -276.109249) (xy 356.119573 -276.06733) (xy 356.09605 -276.021163)
			(xy 356.080038 -275.971884) (xy 356.071932 -275.920707) (xy 356.071424 -275.8948) (xy 356.072017 -275.867083)
			(xy 356.081341 -275.812436) (xy 356.089966 -275.786088) (xy 356.09784 -275.76399) (xy 355.892608 -275.408898)
			(xy 355.869748 -275.40458) (xy 355.844921 -275.399437) (xy 355.79714 -275.382481) (xy 355.75252 -275.358407)
			(xy 355.712113 -275.327784) (xy 355.676872 -275.291334) (xy 355.647629 -275.249917) (xy 355.625073 -275.20451)
			(xy 355.609738 -275.156184) (xy 355.601984 -275.10608) (xy 355.601524 -275.08073) (xy 353.441508 -275.08073)
			(xy 353.441092 -275.106096) (xy 353.433338 -275.156231) (xy 353.417989 -275.204584) (xy 353.395406 -275.250011)
			(xy 353.366125 -275.291439) (xy 353.330837 -275.327886) (xy 353.290378 -275.358492) (xy 353.245704 -275.382531)
			(xy 353.197873 -275.399435) (xy 353.17303 -275.40458) (xy 353.149916 -275.408898) (xy 352.944938 -275.76399)
			(xy 352.952812 -275.786088) (xy 352.96137 -275.812447) (xy 352.97057 -275.867092) (xy 352.9711 -275.8948)
			(xy 352.970592 -275.920687) (xy 352.970589 -275.920705) (xy 354.192116 -275.920705) (xy 354.192116 -275.868895)
			(xy 354.200221 -275.817722) (xy 354.21623 -275.768446) (xy 354.23975 -275.722282) (xy 354.270202 -275.680364)
			(xy 354.306835 -275.643726) (xy 354.348749 -275.61327) (xy 354.394911 -275.589745) (xy 354.444185 -275.57373)
			(xy 354.495357 -275.565619) (xy 354.521262 -275.565108) (xy 354.546773 -275.565613) (xy 354.597186 -275.573468)
			(xy 354.645788 -275.588996) (xy 354.691416 -275.611827) (xy 354.732982 -275.641416) (xy 354.769494 -275.677055)
			(xy 354.785168 -275.697188) (xy 355.197156 -275.697188) (xy 355.212852 -275.677071) (xy 355.249357 -275.641427)
			(xy 355.290918 -275.611831) (xy 355.336542 -275.588992) (xy 355.38514 -275.573454) (xy 355.435551 -275.565588)
			(xy 355.461062 -275.565108) (xy 355.486973 -275.565587) (xy 355.538159 -275.573688) (xy 355.587447 -275.589698)
			(xy 355.633623 -275.613221) (xy 355.67555 -275.643679) (xy 355.712197 -275.680321) (xy 355.742659 -275.722245)
			(xy 355.766188 -275.768418) (xy 355.782203 -275.817704) (xy 355.79031 -275.868889) (xy 355.79031 -275.920711)
			(xy 355.782203 -275.971896) (xy 355.766188 -276.021182) (xy 355.742659 -276.067355) (xy 355.712197 -276.109279)
			(xy 355.67555 -276.145921) (xy 355.633623 -276.176379) (xy 355.587447 -276.199902) (xy 355.538159 -276.215912)
			(xy 355.486973 -276.224013) (xy 355.461062 -276.224492) (xy 355.435549 -276.224043) (xy 355.385133 -276.216176)
			(xy 355.336531 -276.200636) (xy 355.290902 -276.177795) (xy 355.249337 -276.148197) (xy 355.212829 -276.112549)
			(xy 355.197156 -276.092412) (xy 354.785168 -276.092412) (xy 354.769516 -276.112565) (xy 354.733002 -276.148208)
			(xy 354.691432 -276.177799) (xy 354.645799 -276.200632) (xy 354.597193 -276.216162) (xy 354.546775 -276.224017)
			(xy 354.521262 -276.224492) (xy 354.495357 -276.223981) (xy 354.444185 -276.21587) (xy 354.394911 -276.199855)
			(xy 354.348749 -276.17633) (xy 354.306835 -276.145874) (xy 354.270202 -276.109236) (xy 354.23975 -276.067318)
			(xy 354.21623 -276.021154) (xy 354.200221 -275.971878) (xy 354.192116 -275.920705) (xy 352.970589 -275.920705)
			(xy 352.962493 -275.971825) (xy 352.946494 -276.021065) (xy 352.922988 -276.067197) (xy 352.892556 -276.109084)
			(xy 352.855946 -276.145694) (xy 352.814059 -276.176126) (xy 352.767927 -276.199632) (xy 352.718687 -276.215631)
			(xy 352.667549 -276.22373) (xy 352.615775 -276.22373) (xy 352.564637 -276.215631) (xy 352.515397 -276.199632)
			(xy 352.469265 -276.176126) (xy 352.427378 -276.145694) (xy 352.390768 -276.109084) (xy 352.360336 -276.067197)
			(xy 352.33683 -276.021065) (xy 352.320831 -275.971825) (xy 352.312732 -275.920687) (xy 352.312224 -275.8948)
			(xy 351.0915 -275.8948) (xy 351.090979 -275.920144) (xy 351.083207 -275.970232) (xy 351.067862 -276.018541)
			(xy 351.045306 -276.063932) (xy 351.016069 -276.105338) (xy 350.98084 -276.141782) (xy 350.940449 -276.172406)
			(xy 350.895848 -276.196488) (xy 350.848087 -276.213462) (xy 350.823276 -276.21865) (xy 350.800416 -276.222968)
			(xy 350.595438 -276.577806) (xy 350.603312 -276.599904) (xy 350.611874 -276.626262) (xy 350.621072 -276.680908)
			(xy 350.6216 -276.708616) (xy 350.902524 -276.708616) (xy 350.903032 -276.682709) (xy 350.911138 -276.631532)
			(xy 350.92715 -276.582253) (xy 350.950673 -276.536086) (xy 350.981129 -276.494167) (xy 351.017767 -276.457529)
			(xy 351.059686 -276.427073) (xy 351.105853 -276.40355) (xy 351.155132 -276.387538) (xy 351.206309 -276.379432)
			(xy 351.258123 -276.379432) (xy 351.3093 -276.387538) (xy 351.358579 -276.40355) (xy 351.404746 -276.427073)
			(xy 351.446665 -276.457529) (xy 351.483303 -276.494167) (xy 351.513759 -276.536086) (xy 351.537282 -276.582253)
			(xy 351.553294 -276.631532) (xy 351.5614 -276.682709) (xy 351.561908 -276.708616) (xy 351.561377 -276.734509)
			(xy 351.842805 -276.734509) (xy 351.842805 -276.682691) (xy 351.850912 -276.631511) (xy 351.866925 -276.582229)
			(xy 351.89045 -276.53606) (xy 351.920909 -276.494139) (xy 351.957551 -276.457499) (xy 351.999473 -276.427042)
			(xy 352.045644 -276.403519) (xy 352.094927 -276.387508) (xy 352.146107 -276.379404) (xy 352.172016 -276.378924)
			(xy 352.197529 -276.379383) (xy 352.247945 -276.387247) (xy 352.296547 -276.402784) (xy 352.342175 -276.425624)
			(xy 352.38374 -276.45522) (xy 352.420249 -276.490867) (xy 352.435922 -276.511004) (xy 352.84791 -276.511004)
			(xy 352.863579 -276.490865) (xy 352.900089 -276.455221) (xy 352.941656 -276.425628) (xy 352.987285 -276.402792)
			(xy 353.035888 -276.387259) (xy 353.086304 -276.3794) (xy 353.111816 -276.378924) (xy 353.137724 -276.379401)
			(xy 353.188901 -276.387509) (xy 353.23818 -276.403523) (xy 353.284347 -276.427048) (xy 353.326266 -276.457506)
			(xy 353.362904 -276.494146) (xy 353.39336 -276.536066) (xy 353.416883 -276.582235) (xy 353.432895 -276.631514)
			(xy 353.441 -276.682692) (xy 353.441 -276.734508) (xy 353.432895 -276.785686) (xy 353.416883 -276.834965)
			(xy 353.39336 -276.881134) (xy 353.362904 -276.923054) (xy 353.326266 -276.959694) (xy 353.284347 -276.990152)
			(xy 353.23818 -277.013677) (xy 353.188901 -277.029691) (xy 353.137724 -277.037799) (xy 353.111816 -277.038308)
			(xy 353.086305 -277.037813) (xy 353.035891 -277.029955) (xy 352.98729 -277.014424) (xy 352.941662 -276.991591)
			(xy 352.900096 -276.962001) (xy 352.863585 -276.926361) (xy 352.84791 -276.906228) (xy 352.435922 -276.906228)
			(xy 352.420244 -276.926359) (xy 352.383734 -276.962002) (xy 352.342169 -276.991595) (xy 352.296542 -277.014432)
			(xy 352.247941 -277.029967) (xy 352.197528 -277.03783) (xy 352.172016 -277.038308) (xy 352.146107 -277.037796)
			(xy 352.094927 -277.029692) (xy 352.045644 -277.013681) (xy 351.999473 -276.990158) (xy 351.957551 -276.959701)
			(xy 351.920909 -276.923061) (xy 351.89045 -276.88114) (xy 351.866925 -276.834971) (xy 351.850912 -276.785689)
			(xy 351.842805 -276.734509) (xy 351.561377 -276.734509) (xy 351.561338 -276.736398) (xy 351.552014 -276.791174)
			(xy 351.543366 -276.817582) (xy 351.535492 -276.839426) (xy 351.74047 -277.194264) (xy 351.76333 -277.198582)
			(xy 351.788142 -277.203733) (xy 351.835882 -277.220727) (xy 351.88046 -277.244826) (xy 351.920825 -277.275462)
			(xy 351.956028 -277.311913) (xy 351.985239 -277.353322) (xy 352.007769 -277.398712) (xy 352.02309 -277.447016)
			(xy 352.030838 -277.497095) (xy 352.0313 -277.522432) (xy 354.191824 -277.522432) (xy 354.192226 -277.497095)
			(xy 354.199989 -277.447018) (xy 354.215322 -277.398718) (xy 354.237864 -277.353333) (xy 354.267084 -277.31193)
			(xy 354.302294 -277.275486) (xy 354.342666 -277.244857) (xy 354.387248 -277.220766) (xy 354.434991 -277.203779)
			(xy 354.459794 -277.198582) (xy 354.482654 -277.194264) (xy 354.687886 -276.838918) (xy 354.680266 -276.817074)
			(xy 354.671663 -276.790785) (xy 354.662334 -276.736269) (xy 354.661724 -276.708616) (xy 354.662232 -276.682709)
			(xy 354.670338 -276.631532) (xy 354.68635 -276.582253) (xy 354.709873 -276.536086) (xy 354.740329 -276.494167)
			(xy 354.776967 -276.457529) (xy 354.818886 -276.427073) (xy 354.865053 -276.40355) (xy 354.914332 -276.387538)
			(xy 354.965509 -276.379432) (xy 355.017323 -276.379432) (xy 355.0685 -276.387538) (xy 355.117779 -276.40355)
			(xy 355.163946 -276.427073) (xy 355.205865 -276.457529) (xy 355.242503 -276.494167) (xy 355.272959 -276.536086)
			(xy 355.296482 -276.582253) (xy 355.312494 -276.631532) (xy 355.3206 -276.682709) (xy 355.321108 -276.708616)
			(xy 356.541324 -276.708616) (xy 356.541802 -276.683281) (xy 356.549553 -276.633207) (xy 356.564874 -276.584909)
			(xy 356.587406 -276.539525) (xy 356.616616 -276.498122) (xy 356.651818 -276.461676) (xy 356.692181 -276.431046)
			(xy 356.736757 -276.406953) (xy 356.784494 -276.389964) (xy 356.809294 -276.384766) (xy 356.832154 -276.380448)
			(xy 357.037132 -276.02561) (xy 357.029258 -276.003766) (xy 357.020612 -275.977358) (xy 357.011292 -275.922582)
			(xy 357.010716 -275.8948) (xy 357.011224 -275.868893) (xy 357.01933 -275.817716) (xy 357.035342 -275.768437)
			(xy 357.058865 -275.72227) (xy 357.089321 -275.680351) (xy 357.125959 -275.643713) (xy 357.167878 -275.613257)
			(xy 357.214045 -275.589734) (xy 357.263324 -275.573722) (xy 357.314501 -275.565616) (xy 357.366315 -275.565616)
			(xy 357.417492 -275.573722) (xy 357.466771 -275.589734) (xy 357.512938 -275.613257) (xy 357.554857 -275.643713)
			(xy 357.591495 -275.680351) (xy 357.621951 -275.72227) (xy 357.645474 -275.768437) (xy 357.661486 -275.817716)
			(xy 357.669592 -275.868893) (xy 357.6701 -275.8948) (xy 357.669579 -275.920144) (xy 357.661807 -275.970232)
			(xy 357.646462 -276.018541) (xy 357.623906 -276.063932) (xy 357.594669 -276.105338) (xy 357.55944 -276.141782)
			(xy 357.519049 -276.172406) (xy 357.474448 -276.196488) (xy 357.426687 -276.213462) (xy 357.401876 -276.21865)
			(xy 357.379016 -276.222968) (xy 357.174038 -276.577806) (xy 357.181912 -276.599904) (xy 357.190474 -276.626262)
			(xy 357.199672 -276.680908) (xy 357.2002 -276.708616) (xy 357.199692 -276.734503) (xy 357.191593 -276.785641)
			(xy 357.175594 -276.834881) (xy 357.152088 -276.881013) (xy 357.121656 -276.9229) (xy 357.085046 -276.95951)
			(xy 357.043159 -276.989942) (xy 356.997027 -277.013448) (xy 356.947787 -277.029447) (xy 356.896649 -277.037546)
			(xy 356.844875 -277.037546) (xy 356.793737 -277.029447) (xy 356.744497 -277.013448) (xy 356.698365 -276.989942)
			(xy 356.656478 -276.95951) (xy 356.619868 -276.9229) (xy 356.589436 -276.881013) (xy 356.56593 -276.834881)
			(xy 356.549931 -276.785641) (xy 356.541832 -276.734503) (xy 356.541324 -276.708616) (xy 355.321108 -276.708616)
			(xy 355.320641 -276.73399) (xy 355.312871 -276.784141) (xy 355.297501 -276.832506) (xy 355.274895 -276.877942)
			(xy 355.245588 -276.919373) (xy 355.210273 -276.955819) (xy 355.169787 -276.986418) (xy 355.125087 -277.010445)
			(xy 355.07723 -277.027332) (xy 355.052376 -277.032466) (xy 355.029516 -277.036784) (xy 354.824538 -277.391622)
			(xy 354.832412 -277.41372) (xy 354.840977 -277.440077) (xy 354.850173 -277.494724) (xy 354.8507 -277.522432)
			(xy 355.131624 -277.522432) (xy 355.132132 -277.496545) (xy 355.140231 -277.445407) (xy 355.15623 -277.396167)
			(xy 355.179736 -277.350035) (xy 355.210168 -277.308148) (xy 355.246778 -277.271538) (xy 355.288665 -277.241106)
			(xy 355.334797 -277.2176) (xy 355.384037 -277.201601) (xy 355.435175 -277.193502) (xy 355.486949 -277.193502)
			(xy 355.538087 -277.201601) (xy 355.587327 -277.2176) (xy 355.633459 -277.241106) (xy 355.675346 -277.271538)
			(xy 355.711956 -277.308148) (xy 355.742388 -277.350035) (xy 355.765894 -277.396167) (xy 355.781893 -277.445407)
			(xy 355.789992 -277.496545) (xy 355.7905 -277.522432) (xy 355.7905 -277.52294) (xy 355.789963 -277.548303)
			(xy 356.071748 -277.548303) (xy 356.071748 -277.496497) (xy 356.079852 -277.445329) (xy 356.09586 -277.396058)
			(xy 356.119377 -277.349898) (xy 356.149826 -277.307985) (xy 356.186456 -277.271351) (xy 356.228366 -277.240897)
			(xy 356.274523 -277.217374) (xy 356.323792 -277.201361) (xy 356.374959 -277.193251) (xy 356.400862 -277.19274)
			(xy 356.426374 -277.193232) (xy 356.476788 -277.201088) (xy 356.52539 -277.216618) (xy 356.571019 -277.239452)
			(xy 356.612585 -277.269043) (xy 356.649095 -277.304685) (xy 356.664768 -277.32482) (xy 357.076756 -277.32482)
			(xy 357.09246 -277.30471) (xy 357.128963 -277.269063) (xy 357.170522 -277.239467) (xy 357.216144 -277.216626)
			(xy 357.264741 -277.201087) (xy 357.315152 -277.19322) (xy 357.340662 -277.19274) (xy 357.366576 -277.193155)
			(xy 357.417766 -277.201257) (xy 357.467059 -277.217268) (xy 357.51324 -277.240794) (xy 357.555171 -277.271254)
			(xy 357.591821 -277.3079) (xy 357.622286 -277.349828) (xy 357.645817 -277.396006) (xy 357.661834 -277.445297)
			(xy 357.669942 -277.496486) (xy 357.669942 -277.548314) (xy 357.661834 -277.599503) (xy 357.645817 -277.648794)
			(xy 357.622286 -277.694972) (xy 357.591821 -277.7369) (xy 357.555171 -277.773546) (xy 357.51324 -277.804006)
			(xy 357.467059 -277.827532) (xy 357.417766 -277.843543) (xy 357.366576 -277.851645) (xy 357.340662 -277.852124)
			(xy 357.31515 -277.851662) (xy 357.264735 -277.843796) (xy 357.216133 -277.828258) (xy 357.170505 -277.805419)
			(xy 357.12894 -277.775824) (xy 357.09243 -277.74018) (xy 357.076756 -277.720044) (xy 356.664768 -277.720044)
			(xy 356.649125 -277.740204) (xy 356.612608 -277.775845) (xy 356.571036 -277.805434) (xy 356.525401 -277.828266)
			(xy 356.476795 -277.843795) (xy 356.426376 -277.85165) (xy 356.400862 -277.852124) (xy 356.374959 -277.851549)
			(xy 356.323792 -277.843439) (xy 356.274523 -277.827426) (xy 356.228366 -277.803903) (xy 356.186456 -277.773449)
			(xy 356.149826 -277.736815) (xy 356.119377 -277.694902) (xy 356.09586 -277.648742) (xy 356.079852 -277.599471)
			(xy 356.071748 -277.548303) (xy 355.789963 -277.548303) (xy 355.789917 -277.550456) (xy 355.780726 -277.604717)
			(xy 355.772212 -277.63089) (xy 355.764592 -277.652988) (xy 355.969824 -278.008334) (xy 355.992684 -278.012652)
			(xy 356.017501 -278.017836) (xy 356.065277 -278.034792) (xy 356.109893 -278.058863) (xy 356.150297 -278.089482)
			(xy 356.185537 -278.125927) (xy 356.214781 -278.167338) (xy 356.23734 -278.212738) (xy 356.252681 -278.261056)
			(xy 356.260443 -278.311154) (xy 356.260908 -278.336502) (xy 356.2604 -278.362409) (xy 356.252294 -278.413586)
			(xy 356.236282 -278.462865) (xy 356.212759 -278.509032) (xy 356.182303 -278.550951) (xy 356.145665 -278.587589)
			(xy 356.103746 -278.618045) (xy 356.057579 -278.641568) (xy 356.0083 -278.65758) (xy 355.957123 -278.665686)
			(xy 355.905309 -278.665686) (xy 355.854132 -278.65758) (xy 355.804853 -278.641568) (xy 355.758686 -278.618045)
			(xy 355.716767 -278.587589) (xy 355.680129 -278.550951) (xy 355.649673 -278.509032) (xy 355.62615 -278.462865)
			(xy 355.610138 -278.413586) (xy 355.602032 -278.362409) (xy 355.601524 -278.336502) (xy 355.602117 -278.308785)
			(xy 355.611441 -278.254138) (xy 355.620066 -278.22779) (xy 355.62794 -278.205692) (xy 355.422962 -277.8506)
			(xy 355.399848 -277.846282) (xy 355.375022 -277.841137) (xy 355.327241 -277.824181) (xy 355.282621 -277.800107)
			(xy 355.242213 -277.769484) (xy 355.206972 -277.733035) (xy 355.177729 -277.691618) (xy 355.155174 -277.646211)
			(xy 355.139838 -277.597886) (xy 355.132084 -277.547782) (xy 355.131624 -277.522432) (xy 354.8507 -277.522432)
			(xy 354.850192 -277.548319) (xy 354.842093 -277.599457) (xy 354.826094 -277.648697) (xy 354.802588 -277.694829)
			(xy 354.772156 -277.736716) (xy 354.735546 -277.773326) (xy 354.693659 -277.803758) (xy 354.647527 -277.827264)
			(xy 354.598287 -277.843263) (xy 354.547149 -277.851362) (xy 354.495375 -277.851362) (xy 354.444237 -277.843263)
			(xy 354.394997 -277.827264) (xy 354.348865 -277.803758) (xy 354.306978 -277.773326) (xy 354.270368 -277.736716)
			(xy 354.239936 -277.694829) (xy 354.21643 -277.648697) (xy 354.200431 -277.599457) (xy 354.192332 -277.548319)
			(xy 354.191824 -277.522432) (xy 352.0313 -277.522432) (xy 352.030792 -277.548319) (xy 352.022693 -277.599457)
			(xy 352.006694 -277.648697) (xy 351.983188 -277.694829) (xy 351.952756 -277.736716) (xy 351.916146 -277.773326)
			(xy 351.874259 -277.803758) (xy 351.828127 -277.827264) (xy 351.778887 -277.843263) (xy 351.727749 -277.851362)
			(xy 351.675975 -277.851362) (xy 351.624837 -277.843263) (xy 351.575597 -277.827264) (xy 351.529465 -277.803758)
			(xy 351.487578 -277.773326) (xy 351.450968 -277.736716) (xy 351.420536 -277.694829) (xy 351.39703 -277.648697)
			(xy 351.381031 -277.599457) (xy 351.372932 -277.548319) (xy 351.372424 -277.522432) (xy 351.37296 -277.494724)
			(xy 351.382151 -277.440077) (xy 351.390712 -277.41372) (xy 351.398586 -277.391622) (xy 351.193608 -277.036784)
			(xy 351.170748 -277.032466) (xy 351.145918 -277.027336) (xy 351.098136 -277.010379) (xy 351.053515 -276.986304)
			(xy 351.013107 -276.955679) (xy 350.977866 -276.919227) (xy 350.948624 -276.877808) (xy 350.926069 -276.8324)
			(xy 350.910735 -276.784072) (xy 350.902983 -276.733967) (xy 350.902524 -276.708616) (xy 350.6216 -276.708616)
			(xy 350.621092 -276.734503) (xy 350.612993 -276.785641) (xy 350.596994 -276.834881) (xy 350.573488 -276.881013)
			(xy 350.543056 -276.9229) (xy 350.506446 -276.95951) (xy 350.464559 -276.989942) (xy 350.418427 -277.013448)
			(xy 350.369187 -277.029447) (xy 350.318049 -277.037546) (xy 350.266275 -277.037546) (xy 350.215137 -277.029447)
			(xy 350.165897 -277.013448) (xy 350.119765 -276.989942) (xy 350.077878 -276.95951) (xy 350.041268 -276.9229)
			(xy 350.010836 -276.881013) (xy 349.98733 -276.834881) (xy 349.971331 -276.785641) (xy 349.963232 -276.734503)
			(xy 349.962724 -276.708616) (xy 109.260132 -276.708616) (xy 109.259624 -276.734503) (xy 109.251525 -276.785641)
			(xy 109.235526 -276.834881) (xy 109.21202 -276.881013) (xy 109.181588 -276.9229) (xy 109.144978 -276.95951)
			(xy 109.103091 -276.989942) (xy 109.056959 -277.013448) (xy 109.007719 -277.029447) (xy 108.956581 -277.037546)
			(xy 108.904807 -277.037546) (xy 108.853669 -277.029447) (xy 108.804429 -277.013448) (xy 108.758297 -276.989942)
			(xy 108.71641 -276.95951) (xy 108.6798 -276.9229) (xy 108.649368 -276.881013) (xy 108.625862 -276.834881)
			(xy 108.609863 -276.785641) (xy 108.601764 -276.734503) (xy 108.601256 -276.708616) (xy 107.38104 -276.708616)
			(xy 107.380628 -276.733993) (xy 107.372856 -276.784149) (xy 107.357482 -276.832518) (xy 107.334871 -276.877958)
			(xy 107.305557 -276.91939) (xy 107.270234 -276.955836) (xy 107.229739 -276.986433) (xy 107.18503 -277.010456)
			(xy 107.137166 -277.027337) (xy 107.112308 -277.032466) (xy 107.089448 -277.036784) (xy 106.88447 -277.391622)
			(xy 106.892344 -277.41372) (xy 106.90091 -277.440076) (xy 106.910105 -277.494723) (xy 106.910632 -277.522432)
			(xy 107.191556 -277.522432) (xy 107.192064 -277.496545) (xy 107.200163 -277.445407) (xy 107.216162 -277.396167)
			(xy 107.239668 -277.350035) (xy 107.2701 -277.308148) (xy 107.30671 -277.271538) (xy 107.348597 -277.241106)
			(xy 107.394729 -277.2176) (xy 107.443969 -277.201601) (xy 107.495107 -277.193502) (xy 107.546881 -277.193502)
			(xy 107.598019 -277.201601) (xy 107.647259 -277.2176) (xy 107.693391 -277.241106) (xy 107.735278 -277.271538)
			(xy 107.771888 -277.308148) (xy 107.80232 -277.350035) (xy 107.825826 -277.396167) (xy 107.841825 -277.445407)
			(xy 107.849924 -277.496545) (xy 107.850432 -277.522432) (xy 107.850432 -277.52294) (xy 107.849894 -277.548305)
			(xy 108.131648 -277.548305) (xy 108.131648 -277.496495) (xy 108.139753 -277.445324) (xy 108.155763 -277.396051)
			(xy 108.179283 -277.349889) (xy 108.209735 -277.307974) (xy 108.24637 -277.271339) (xy 108.288284 -277.240886)
			(xy 108.334445 -277.217365) (xy 108.383718 -277.201354) (xy 108.43489 -277.193249) (xy 108.460794 -277.19274)
			(xy 108.486306 -277.193209) (xy 108.536722 -277.20107) (xy 108.585325 -277.216605) (xy 108.630953 -277.239442)
			(xy 108.672518 -277.269037) (xy 108.709027 -277.304684) (xy 108.7247 -277.32482) (xy 109.136688 -277.32482)
			(xy 109.152374 -277.304695) (xy 109.18888 -277.269049) (xy 109.230443 -277.239454) (xy 109.276069 -277.216616)
			(xy 109.324669 -277.20108) (xy 109.375083 -277.193218) (xy 109.400594 -277.19274) (xy 109.426506 -277.193157)
			(xy 109.477693 -277.201263) (xy 109.526981 -277.217277) (xy 109.573157 -277.240805) (xy 109.615085 -277.271266)
			(xy 109.65173 -277.307911) (xy 109.682192 -277.349838) (xy 109.70572 -277.396013) (xy 109.721735 -277.445301)
			(xy 109.729842 -277.496488) (xy 109.729842 -277.548312) (xy 109.721735 -277.599499) (xy 109.70572 -277.648787)
			(xy 109.682192 -277.694962) (xy 109.65173 -277.736889) (xy 109.615085 -277.773534) (xy 109.573157 -277.803995)
			(xy 109.526981 -277.827523) (xy 109.477693 -277.843537) (xy 109.426506 -277.851643) (xy 109.400594 -277.852124)
			(xy 109.375083 -277.851639) (xy 109.324669 -277.843778) (xy 109.276068 -277.828245) (xy 109.230439 -277.80541)
			(xy 109.188874 -277.775819) (xy 109.152362 -277.740178) (xy 109.136688 -277.720044) (xy 108.7247 -277.720044)
			(xy 108.709039 -277.740189) (xy 108.672525 -277.77583) (xy 108.630957 -277.805422) (xy 108.585326 -277.828256)
			(xy 108.536723 -277.843788) (xy 108.486307 -277.851647) (xy 108.460794 -277.852124) (xy 108.43489 -277.851551)
			(xy 108.383718 -277.843446) (xy 108.334445 -277.827435) (xy 108.288284 -277.803914) (xy 108.24637 -277.773461)
			(xy 108.209735 -277.736826) (xy 108.179283 -277.694911) (xy 108.155763 -277.648749) (xy 108.139753 -277.599476)
			(xy 108.131648 -277.548305) (xy 107.849894 -277.548305) (xy 107.849848 -277.550456) (xy 107.840658 -277.604717)
			(xy 107.832144 -277.63089) (xy 107.824524 -277.652988) (xy 108.029756 -278.008334) (xy 108.052616 -278.012652)
			(xy 108.077422 -278.017885) (xy 108.125198 -278.034831) (xy 108.169815 -278.058894) (xy 108.210222 -278.089506)
			(xy 108.245463 -278.125945) (xy 108.27471 -278.16735) (xy 108.29727 -278.212746) (xy 108.312612 -278.261061)
			(xy 108.320375 -278.311156) (xy 108.32084 -278.336502) (xy 108.320332 -278.362409) (xy 108.312226 -278.413586)
			(xy 108.296214 -278.462865) (xy 108.272691 -278.509032) (xy 108.242235 -278.550951) (xy 108.205597 -278.587589)
			(xy 108.163678 -278.618045) (xy 108.117511 -278.641568) (xy 108.068232 -278.65758) (xy 108.017055 -278.665686)
			(xy 107.965241 -278.665686) (xy 107.914064 -278.65758) (xy 107.864785 -278.641568) (xy 107.818618 -278.618045)
			(xy 107.776699 -278.587589) (xy 107.740061 -278.550951) (xy 107.709605 -278.509032) (xy 107.686082 -278.462865)
			(xy 107.67007 -278.413586) (xy 107.661964 -278.362409) (xy 107.661456 -278.336502) (xy 107.662047 -278.308784)
			(xy 107.671372 -278.254138) (xy 107.679998 -278.22779) (xy 107.687872 -278.205692) (xy 107.482894 -277.8506)
			(xy 107.45978 -277.846282) (xy 107.434959 -277.841114) (xy 107.387178 -277.824162) (xy 107.342557 -277.800093)
			(xy 107.302149 -277.769473) (xy 107.266907 -277.733026) (xy 107.237663 -277.691612) (xy 107.215107 -277.646207)
			(xy 107.199771 -277.597884) (xy 107.192016 -277.547781) (xy 107.191556 -277.522432) (xy 106.910632 -277.522432)
			(xy 106.910124 -277.548319) (xy 106.902025 -277.599457) (xy 106.886026 -277.648697) (xy 106.86252 -277.694829)
			(xy 106.832088 -277.736716) (xy 106.795478 -277.773326) (xy 106.753591 -277.803758) (xy 106.707459 -277.827264)
			(xy 106.658219 -277.843263) (xy 106.607081 -277.851362) (xy 106.555307 -277.851362) (xy 106.504169 -277.843263)
			(xy 106.454929 -277.827264) (xy 106.408797 -277.803758) (xy 106.36691 -277.773326) (xy 106.3303 -277.736716)
			(xy 106.299868 -277.694829) (xy 106.276362 -277.648697) (xy 106.260363 -277.599457) (xy 106.252264 -277.548319)
			(xy 106.251756 -277.522432) (xy 104.091232 -277.522432) (xy 104.090724 -277.548319) (xy 104.082625 -277.599457)
			(xy 104.066626 -277.648697) (xy 104.04312 -277.694829) (xy 104.012688 -277.736716) (xy 103.976078 -277.773326)
			(xy 103.934191 -277.803758) (xy 103.888059 -277.827264) (xy 103.838819 -277.843263) (xy 103.787681 -277.851362)
			(xy 103.735907 -277.851362) (xy 103.684769 -277.843263) (xy 103.635529 -277.827264) (xy 103.589397 -277.803758)
			(xy 103.54751 -277.773326) (xy 103.5109 -277.736716) (xy 103.480468 -277.694829) (xy 103.456962 -277.648697)
			(xy 103.440963 -277.599457) (xy 103.432864 -277.548319) (xy 103.432356 -277.522432) (xy 103.432895 -277.494724)
			(xy 103.442084 -277.440078) (xy 103.450644 -277.41372) (xy 103.458518 -277.391622) (xy 103.25354 -277.036784)
			(xy 103.23068 -277.032466) (xy 103.205855 -277.027313) (xy 103.158073 -277.01036) (xy 103.113452 -276.986289)
			(xy 103.073043 -276.955668) (xy 103.037801 -276.919219) (xy 103.008557 -276.877803) (xy 102.986002 -276.832396)
			(xy 102.970667 -276.78407) (xy 102.962915 -276.733966) (xy 102.962456 -276.708616) (xy 102.681532 -276.708616)
			(xy 102.681024 -276.734503) (xy 102.672925 -276.785641) (xy 102.656926 -276.834881) (xy 102.63342 -276.881013)
			(xy 102.602988 -276.9229) (xy 102.566378 -276.95951) (xy 102.524491 -276.989942) (xy 102.478359 -277.013448)
			(xy 102.429119 -277.029447) (xy 102.377981 -277.037546) (xy 102.326207 -277.037546) (xy 102.275069 -277.029447)
			(xy 102.225829 -277.013448) (xy 102.179697 -276.989942) (xy 102.13781 -276.95951) (xy 102.1012 -276.9229)
			(xy 102.070768 -276.881013) (xy 102.047262 -276.834881) (xy 102.031263 -276.785641) (xy 102.023164 -276.734503)
			(xy 102.022656 -276.708616) (xy 2.509012 -276.708616) (xy 2.509012 -279.150318) (xy 101.552756 -279.150318)
			(xy 101.553264 -279.124431) (xy 101.561363 -279.073293) (xy 101.577362 -279.024053) (xy 101.600868 -278.977921)
			(xy 101.6313 -278.936034) (xy 101.66791 -278.899424) (xy 101.709797 -278.868992) (xy 101.755929 -278.845486)
			(xy 101.805169 -278.829487) (xy 101.856307 -278.821388) (xy 101.908081 -278.821388) (xy 101.959219 -278.829487)
			(xy 102.008459 -278.845486) (xy 102.054591 -278.868992) (xy 102.096478 -278.899424) (xy 102.133088 -278.936034)
			(xy 102.16352 -278.977921) (xy 102.187026 -279.024053) (xy 102.203025 -279.073293) (xy 102.211124 -279.124431)
			(xy 102.211632 -279.150318) (xy 102.211632 -279.150826) (xy 102.21109 -279.176186) (xy 102.493088 -279.176186)
			(xy 102.493088 -279.124414) (xy 102.501186 -279.07328) (xy 102.517184 -279.024043) (xy 102.540688 -278.977914)
			(xy 102.571118 -278.93603) (xy 102.607725 -278.899422) (xy 102.649609 -278.868991) (xy 102.695737 -278.845487)
			(xy 102.744975 -278.829488) (xy 102.796108 -278.821388) (xy 102.821994 -278.82088) (xy 102.847505 -278.821372)
			(xy 102.897919 -278.829232) (xy 102.94652 -278.844763) (xy 102.992148 -278.867597) (xy 103.033714 -278.897186)
			(xy 103.070226 -278.932826) (xy 103.0859 -278.95296) (xy 103.497888 -278.95296) (xy 103.513557 -278.932822)
			(xy 103.550069 -278.89718) (xy 103.591636 -278.867588) (xy 103.637265 -278.844752) (xy 103.685867 -278.829219)
			(xy 103.736282 -278.821357) (xy 103.761794 -278.82088) (xy 103.787685 -278.821325) (xy 103.83883 -278.829425)
			(xy 103.888078 -278.845425) (xy 103.934217 -278.868934) (xy 103.97611 -278.89937) (xy 104.012726 -278.935985)
			(xy 104.043163 -278.977878) (xy 104.066672 -279.024016) (xy 104.082674 -279.073264) (xy 104.090775 -279.124409)
			(xy 104.090775 -279.150318) (xy 349.492824 -279.150318) (xy 349.493332 -279.124431) (xy 349.501431 -279.073293)
			(xy 349.51743 -279.024053) (xy 349.540936 -278.977921) (xy 349.571368 -278.936034) (xy 349.607978 -278.899424)
			(xy 349.649865 -278.868992) (xy 349.695997 -278.845486) (xy 349.745237 -278.829487) (xy 349.796375 -278.821388)
			(xy 349.848149 -278.821388) (xy 349.899287 -278.829487) (xy 349.948527 -278.845486) (xy 349.994659 -278.868992)
			(xy 350.036546 -278.899424) (xy 350.073156 -278.936034) (xy 350.103588 -278.977921) (xy 350.127094 -279.024053)
			(xy 350.143093 -279.073293) (xy 350.151192 -279.124431) (xy 350.1517 -279.150318) (xy 350.1517 -279.150826)
			(xy 350.15116 -279.176184) (xy 350.433187 -279.176184) (xy 350.433187 -279.124416) (xy 350.441285 -279.073285)
			(xy 350.457281 -279.02405) (xy 350.480782 -278.977924) (xy 350.511209 -278.936041) (xy 350.547812 -278.899433)
			(xy 350.589691 -278.869002) (xy 350.635815 -278.845496) (xy 350.685048 -278.829494) (xy 350.736178 -278.82139)
			(xy 350.762062 -278.82088) (xy 350.787572 -278.821396) (xy 350.837985 -278.82925) (xy 350.886585 -278.844777)
			(xy 350.932214 -278.867606) (xy 350.97378 -278.897192) (xy 351.010293 -278.932828) (xy 351.025968 -278.95296)
			(xy 351.437956 -278.95296) (xy 351.453644 -278.932837) (xy 351.490152 -278.897194) (xy 351.531715 -278.8676)
			(xy 351.57734 -278.844762) (xy 351.625939 -278.829225) (xy 351.676351 -278.82136) (xy 351.701862 -278.82088)
			(xy 351.727755 -278.821322) (xy 351.778904 -278.829418) (xy 351.828156 -278.845416) (xy 351.874299 -278.868923)
			(xy 351.916197 -278.899359) (xy 351.952817 -278.935974) (xy 351.983257 -278.977868) (xy 352.006769 -279.024009)
			(xy 352.022773 -279.073259) (xy 352.030875 -279.124407) (xy 352.030875 -279.176193) (xy 352.022773 -279.227341)
			(xy 352.006769 -279.276591) (xy 351.983257 -279.322732) (xy 351.952817 -279.364626) (xy 351.916197 -279.401241)
			(xy 351.874299 -279.431677) (xy 351.828156 -279.455184) (xy 351.778904 -279.471182) (xy 351.727755 -279.479278)
			(xy 351.701862 -279.479756) (xy 351.676348 -279.47932) (xy 351.625931 -279.471453) (xy 351.577328 -279.455912)
			(xy 351.531699 -279.433068) (xy 351.490135 -279.403466) (xy 351.453628 -279.367815) (xy 351.437956 -279.347676)
			(xy 351.025968 -279.347676) (xy 351.010307 -279.367822) (xy 350.973795 -279.403466) (xy 350.932228 -279.433059)
			(xy 350.886597 -279.455894) (xy 350.837992 -279.471425) (xy 350.787575 -279.479281) (xy 350.762062 -279.479756)
			(xy 350.736178 -279.47921) (xy 350.685048 -279.471106) (xy 350.635815 -279.455104) (xy 350.589691 -279.431598)
			(xy 350.547812 -279.401167) (xy 350.511209 -279.364559) (xy 350.480782 -279.322676) (xy 350.457281 -279.27655)
			(xy 350.441285 -279.227315) (xy 350.433187 -279.176184) (xy 350.15116 -279.176184) (xy 350.151114 -279.178342)
			(xy 350.141925 -279.232603) (xy 350.133412 -279.258776) (xy 350.125792 -279.28062) (xy 350.331024 -279.635966)
			(xy 350.353884 -279.640284) (xy 350.378708 -279.645438) (xy 350.426486 -279.662396) (xy 350.471104 -279.68647)
			(xy 350.511509 -279.717093) (xy 350.546749 -279.753542) (xy 350.575992 -279.794956) (xy 350.598549 -279.84036)
			(xy 350.613887 -279.888683) (xy 350.621645 -279.938785) (xy 350.622108 -279.964134) (xy 350.6216 -279.990041)
			(xy 350.613494 -280.041218) (xy 350.597482 -280.090497) (xy 350.573959 -280.136664) (xy 350.543503 -280.178583)
			(xy 350.506865 -280.215221) (xy 350.464946 -280.245677) (xy 350.418779 -280.2692) (xy 350.3695 -280.285212)
			(xy 350.318323 -280.293318) (xy 350.266509 -280.293318) (xy 350.215332 -280.285212) (xy 350.166053 -280.2692)
			(xy 350.119886 -280.245677) (xy 350.077967 -280.215221) (xy 350.041329 -280.178583) (xy 350.010873 -280.136664)
			(xy 349.98735 -280.090497) (xy 349.971338 -280.041218) (xy 349.963232 -279.990041) (xy 349.962724 -279.964134)
			(xy 349.963325 -279.936417) (xy 349.972644 -279.88177) (xy 349.981266 -279.855422) (xy 349.98914 -279.833324)
			(xy 349.784162 -279.478486) (xy 349.761302 -279.474168) (xy 349.736475 -279.468982) (xy 349.688671 -279.452048)
			(xy 349.644023 -279.427992) (xy 349.603586 -279.397383) (xy 349.568314 -279.360942) (xy 349.539039 -279.319529)
			(xy 349.516451 -279.274121) (xy 349.501083 -279.22579) (xy 349.493299 -279.175676) (xy 349.492824 -279.150318)
			(xy 104.090775 -279.150318) (xy 104.090775 -279.176191) (xy 104.082674 -279.227336) (xy 104.066672 -279.276584)
			(xy 104.043163 -279.322722) (xy 104.012726 -279.364615) (xy 103.97611 -279.40123) (xy 103.934217 -279.431666)
			(xy 103.888078 -279.455175) (xy 103.83883 -279.471175) (xy 103.787685 -279.479275) (xy 103.761794 -279.479756)
			(xy 103.736281 -279.479297) (xy 103.685865 -279.471435) (xy 103.637262 -279.455898) (xy 103.591633 -279.433058)
			(xy 103.550069 -279.403461) (xy 103.51356 -279.367813) (xy 103.497888 -279.347676) (xy 103.0859 -279.347676)
			(xy 103.07022 -279.367806) (xy 103.033713 -279.403452) (xy 102.992149 -279.433046) (xy 102.946521 -279.455884)
			(xy 102.89792 -279.471418) (xy 102.847506 -279.479279) (xy 102.821994 -279.479756) (xy 102.796108 -279.479212)
			(xy 102.744975 -279.471112) (xy 102.695737 -279.455113) (xy 102.649609 -279.431609) (xy 102.607725 -279.401178)
			(xy 102.571118 -279.36457) (xy 102.540688 -279.322686) (xy 102.517184 -279.276557) (xy 102.501186 -279.22732)
			(xy 102.493088 -279.176186) (xy 102.21109 -279.176186) (xy 102.211044 -279.178342) (xy 102.201856 -279.232603)
			(xy 102.193344 -279.258776) (xy 102.185724 -279.28062) (xy 102.390956 -279.635966) (xy 102.413816 -279.640284)
			(xy 102.438629 -279.645487) (xy 102.486407 -279.662435) (xy 102.531027 -279.686501) (xy 102.571434 -279.717117)
			(xy 102.606676 -279.753559) (xy 102.635921 -279.794969) (xy 102.658479 -279.840369) (xy 102.673819 -279.888688)
			(xy 102.681577 -279.938786) (xy 102.68204 -279.964134) (xy 102.681532 -279.990041) (xy 102.673426 -280.041218)
			(xy 102.657414 -280.090497) (xy 102.633891 -280.136664) (xy 102.603435 -280.178583) (xy 102.566797 -280.215221)
			(xy 102.524878 -280.245677) (xy 102.478711 -280.2692) (xy 102.429432 -280.285212) (xy 102.378255 -280.293318)
			(xy 102.326441 -280.293318) (xy 102.275264 -280.285212) (xy 102.225985 -280.2692) (xy 102.179818 -280.245677)
			(xy 102.137899 -280.215221) (xy 102.101261 -280.178583) (xy 102.070805 -280.136664) (xy 102.047282 -280.090497)
			(xy 102.03127 -280.041218) (xy 102.023164 -279.990041) (xy 102.022656 -279.964134) (xy 102.023255 -279.936417)
			(xy 102.032575 -279.88177) (xy 102.041198 -279.855422) (xy 102.049072 -279.833324) (xy 101.844094 -279.478486)
			(xy 101.821234 -279.474168) (xy 101.796412 -279.468959) (xy 101.748608 -279.452029) (xy 101.70396 -279.427978)
			(xy 101.663522 -279.397372) (xy 101.628249 -279.360934) (xy 101.598973 -279.319523) (xy 101.576384 -279.274117)
			(xy 101.561016 -279.225788) (xy 101.553231 -279.175675) (xy 101.552756 -279.150318) (xy 2.509012 -279.150318)
			(xy 2.509012 -279.989984) (xy 88.866003 -279.989984) (xy 88.866003 -279.938216) (xy 88.874102 -279.887084)
			(xy 88.890099 -279.837849) (xy 88.913601 -279.791722) (xy 88.94403 -279.74984) (xy 88.980636 -279.713234)
			(xy 89.022517 -279.682805) (xy 89.068643 -279.659301) (xy 89.117878 -279.643303) (xy 89.16901 -279.635204)
			(xy 89.194894 -279.634696) (xy 89.220406 -279.635183) (xy 89.27082 -279.643042) (xy 89.319421 -279.658575)
			(xy 89.365049 -279.681409) (xy 89.406615 -279.711) (xy 89.443126 -279.746642) (xy 89.4588 -279.766776)
			(xy 89.870788 -279.766776) (xy 89.886462 -279.746641) (xy 89.922972 -279.710998) (xy 89.964538 -279.681405)
			(xy 90.010166 -279.658569) (xy 90.058768 -279.643035) (xy 90.109182 -279.635173) (xy 90.134694 -279.634696)
			(xy 90.160586 -279.635109) (xy 90.211734 -279.643209) (xy 90.260984 -279.659211) (xy 90.307125 -279.68272)
			(xy 90.349021 -279.713158) (xy 90.385638 -279.749775) (xy 90.416077 -279.791669) (xy 90.439587 -279.83781)
			(xy 90.45559 -279.88706) (xy 90.463691 -279.938208) (xy 90.463691 -279.964134) (xy 96.383856 -279.964134)
			(xy 96.384364 -279.938227) (xy 96.39247 -279.88705) (xy 96.408482 -279.837771) (xy 96.432005 -279.791604)
			(xy 96.462461 -279.749685) (xy 96.499099 -279.713047) (xy 96.541018 -279.682591) (xy 96.587185 -279.659068)
			(xy 96.636464 -279.643056) (xy 96.687641 -279.63495) (xy 96.739455 -279.63495) (xy 96.790632 -279.643056)
			(xy 96.839911 -279.659068) (xy 96.886078 -279.682591) (xy 96.927997 -279.713047) (xy 96.964635 -279.749685)
			(xy 96.995091 -279.791604) (xy 97.018614 -279.837771) (xy 97.034626 -279.88705) (xy 97.042732 -279.938227)
			(xy 97.04324 -279.964134) (xy 97.042606 -279.991926) (xy 97.033158 -280.046702) (xy 97.024444 -280.0731)
			(xy 97.016824 -280.095198) (xy 97.221802 -280.450036) (xy 97.244662 -280.454354) (xy 97.269457 -280.45958)
			(xy 97.317195 -280.476563) (xy 97.361773 -280.50065) (xy 97.402139 -280.531276) (xy 97.437344 -280.567718)
			(xy 97.466557 -280.609118) (xy 97.489091 -280.6545) (xy 97.504415 -280.702797) (xy 97.512168 -280.752869)
			(xy 97.512632 -280.778204) (xy 97.512124 -280.804091) (xy 97.504025 -280.855229) (xy 97.488026 -280.904469)
			(xy 97.46452 -280.950601) (xy 97.434088 -280.992488) (xy 97.397478 -281.029098) (xy 97.355591 -281.05953)
			(xy 97.309459 -281.083036) (xy 97.260219 -281.099035) (xy 97.209081 -281.107134) (xy 97.157307 -281.107134)
			(xy 97.106169 -281.099035) (xy 97.056929 -281.083036) (xy 97.010797 -281.05953) (xy 96.96891 -281.029098)
			(xy 96.9323 -280.992488) (xy 96.901868 -280.950601) (xy 96.878362 -280.904469) (xy 96.862363 -280.855229)
			(xy 96.854264 -280.804091) (xy 96.853756 -280.778204) (xy 96.854288 -280.750496) (xy 96.863482 -280.695849)
			(xy 96.872044 -280.669492) (xy 96.879918 -280.647394) (xy 96.674686 -280.292302) (xy 96.651826 -280.287984)
			(xy 96.627038 -280.282731) (xy 96.579302 -280.265749) (xy 96.534727 -280.241664) (xy 96.494362 -280.211041)
			(xy 96.459158 -280.174603) (xy 96.429944 -280.133207) (xy 96.407407 -280.087828) (xy 96.39208 -280.039536)
			(xy 96.384322 -279.989467) (xy 96.383856 -279.964134) (xy 90.463691 -279.964134) (xy 90.463691 -279.989992)
			(xy 90.45559 -280.04114) (xy 90.439587 -280.09039) (xy 90.416077 -280.13653) (xy 90.385638 -280.178425)
			(xy 90.349021 -280.215042) (xy 90.307125 -280.24548) (xy 90.260984 -280.268989) (xy 90.211734 -280.284991)
			(xy 90.160586 -280.293091) (xy 90.134694 -280.293572) (xy 90.109181 -280.293107) (xy 90.058766 -280.285245)
			(xy 90.010163 -280.269709) (xy 89.964535 -280.24687) (xy 89.92297 -280.217275) (xy 89.886461 -280.181628)
			(xy 89.870788 -280.161492) (xy 89.4588 -280.161492) (xy 89.443124 -280.181626) (xy 89.406615 -280.21727)
			(xy 89.365051 -280.246864) (xy 89.319422 -280.269701) (xy 89.270821 -280.285235) (xy 89.220406 -280.293095)
			(xy 89.194894 -280.293572) (xy 89.16901 -280.292996) (xy 89.117878 -280.284897) (xy 89.068643 -280.268899)
			(xy 89.022517 -280.245395) (xy 88.980636 -280.214966) (xy 88.94403 -280.17836) (xy 88.913601 -280.136478)
			(xy 88.890099 -280.090351) (xy 88.874102 -280.041116) (xy 88.866003 -279.989984) (xy 2.509012 -279.989984)
			(xy 2.509012 -280.804107) (xy 94.97442 -280.804107) (xy 94.97442 -280.752293) (xy 94.982526 -280.701118)
			(xy 94.998537 -280.65184) (xy 95.022059 -280.605674) (xy 95.052514 -280.563756) (xy 95.089151 -280.527118)
			(xy 95.131069 -280.496662) (xy 95.177235 -280.473139) (xy 95.226512 -280.457127) (xy 95.277687 -280.449021)
			(xy 95.303594 -280.448512) (xy 95.329106 -280.448992) (xy 95.379521 -280.456852) (xy 95.428122 -280.472385)
			(xy 95.473751 -280.495221) (xy 95.515316 -280.524814) (xy 95.551826 -280.560457) (xy 95.5675 -280.580592)
			(xy 95.979742 -280.580592) (xy 95.995389 -280.560435) (xy 96.031904 -280.524793) (xy 96.073475 -280.495202)
			(xy 96.119109 -280.472369) (xy 96.167716 -280.45684) (xy 96.218134 -280.448986) (xy 96.243648 -280.448512)
			(xy 96.269553 -280.449016) (xy 96.320725 -280.457128) (xy 96.369997 -280.473144) (xy 96.416159 -280.49667)
			(xy 96.458071 -280.527127) (xy 96.494704 -280.563765) (xy 96.525155 -280.605682) (xy 96.548675 -280.651847)
			(xy 96.564684 -280.701122) (xy 96.572788 -280.752295) (xy 96.572788 -280.804105) (xy 96.564684 -280.855278)
			(xy 96.548675 -280.904553) (xy 96.525155 -280.950718) (xy 96.494704 -280.992635) (xy 96.458071 -281.029273)
			(xy 96.416159 -281.05973) (xy 96.369997 -281.083256) (xy 96.320725 -281.099272) (xy 96.269553 -281.107384)
			(xy 96.243648 -281.107896) (xy 96.218137 -281.107382) (xy 96.167724 -281.099529) (xy 96.119123 -281.084002)
			(xy 96.073495 -281.061173) (xy 96.031928 -281.031586) (xy 95.995417 -280.995948) (xy 95.979742 -280.975816)
			(xy 95.5675 -280.975816) (xy 95.551831 -280.995955) (xy 95.51532 -281.031598) (xy 95.473753 -281.06119)
			(xy 95.428124 -281.084026) (xy 95.379522 -281.099559) (xy 95.329106 -281.107419) (xy 95.303594 -281.107896)
			(xy 95.277687 -281.107379) (xy 95.226512 -281.099273) (xy 95.177235 -281.083261) (xy 95.131069 -281.059738)
			(xy 95.089151 -281.029282) (xy 95.052514 -280.992644) (xy 95.022059 -280.950726) (xy 94.998537 -280.90456)
			(xy 94.982526 -280.855282) (xy 94.97442 -280.804107) (xy 2.509012 -280.804107) (xy 2.509012 -281.617905)
			(xy 90.745336 -281.617905) (xy 90.745336 -281.566095) (xy 90.753441 -281.514922) (xy 90.769451 -281.465646)
			(xy 90.792973 -281.419482) (xy 90.823426 -281.377566) (xy 90.860062 -281.34093) (xy 90.901977 -281.310476)
			(xy 90.948141 -281.286954) (xy 90.997416 -281.270943) (xy 91.048589 -281.262837) (xy 91.074494 -281.262328)
			(xy 91.100006 -281.262802) (xy 91.150421 -281.270662) (xy 91.199024 -281.286196) (xy 91.244652 -281.309033)
			(xy 91.286218 -281.338627) (xy 91.322727 -281.374272) (xy 91.3384 -281.394408) (xy 91.750388 -281.394408)
			(xy 91.766071 -281.37428) (xy 91.802578 -281.338635) (xy 91.844142 -281.309041) (xy 91.889768 -281.286203)
			(xy 91.938369 -281.270668) (xy 91.988782 -281.262806) (xy 92.014294 -281.262328) (xy 92.040205 -281.262769)
			(xy 92.09139 -281.270875) (xy 92.140676 -281.286888) (xy 92.186851 -281.310415) (xy 92.228777 -281.340875)
			(xy 92.265421 -281.377519) (xy 92.295882 -281.419444) (xy 92.319409 -281.465618) (xy 92.335423 -281.514904)
			(xy 92.34353 -281.566089) (xy 92.34353 -281.617911) (xy 92.335423 -281.669096) (xy 92.319409 -281.718382)
			(xy 92.295882 -281.764556) (xy 92.265421 -281.806481) (xy 92.228777 -281.843125) (xy 92.186851 -281.873585)
			(xy 92.140676 -281.897112) (xy 92.09139 -281.913125) (xy 92.040205 -281.921231) (xy 92.014294 -281.921712)
			(xy 91.988782 -281.921231) (xy 91.938368 -281.91337) (xy 91.889767 -281.897836) (xy 91.844138 -281.875001)
			(xy 91.802573 -281.845409) (xy 91.766062 -281.809767) (xy 91.750388 -281.789632) (xy 91.3384 -281.789632)
			(xy 91.322735 -281.809774) (xy 91.286223 -281.845417) (xy 91.244655 -281.875008) (xy 91.199025 -281.897843)
			(xy 91.150422 -281.913376) (xy 91.100006 -281.921235) (xy 91.074494 -281.921712) (xy 91.048589 -281.921163)
			(xy 90.997416 -281.913057) (xy 90.948141 -281.897046) (xy 90.901977 -281.873524) (xy 90.860062 -281.84307)
			(xy 90.823426 -281.806434) (xy 90.792973 -281.764518) (xy 90.769451 -281.718354) (xy 90.753441 -281.669078)
			(xy 90.745336 -281.617905) (xy 2.509012 -281.617905) (xy 2.509012 -282.405836) (xy 87.455756 -282.405836)
			(xy 87.456264 -282.379949) (xy 87.464363 -282.328811) (xy 87.480362 -282.279571) (xy 87.503868 -282.233439)
			(xy 87.5343 -282.191552) (xy 87.57091 -282.154942) (xy 87.612797 -282.12451) (xy 87.658929 -282.101004)
			(xy 87.708169 -282.085005) (xy 87.759307 -282.076906) (xy 87.811081 -282.076906) (xy 87.862219 -282.085005)
			(xy 87.911459 -282.101004) (xy 87.957591 -282.12451) (xy 87.999478 -282.154942) (xy 88.036088 -282.191552)
			(xy 88.06652 -282.233439) (xy 88.090026 -282.279571) (xy 88.106025 -282.328811) (xy 88.114124 -282.379949)
			(xy 88.114632 -282.405836) (xy 93.094556 -282.405836) (xy 93.094974 -282.380488) (xy 93.102757 -282.330393)
			(xy 93.118114 -282.282079) (xy 93.140683 -282.236685) (xy 93.169933 -282.195278) (xy 93.205175 -282.158835)
			(xy 93.245578 -282.128214) (xy 93.290191 -282.104137) (xy 93.337964 -282.08717) (xy 93.36278 -282.081986)
			(xy 93.38564 -282.077668) (xy 93.590618 -281.72283) (xy 93.582744 -281.700986) (xy 93.574162 -281.674568)
			(xy 93.564967 -281.619792) (xy 93.564456 -281.59202) (xy 93.564964 -281.566133) (xy 93.573063 -281.514995)
			(xy 93.589062 -281.465755) (xy 93.612568 -281.419623) (xy 93.643 -281.377736) (xy 93.67961 -281.341126)
			(xy 93.721497 -281.310694) (xy 93.767629 -281.287188) (xy 93.816869 -281.271189) (xy 93.868007 -281.26309)
			(xy 93.919781 -281.26309) (xy 93.970919 -281.271189) (xy 94.020159 -281.287188) (xy 94.066291 -281.310694)
			(xy 94.108178 -281.341126) (xy 94.144788 -281.377736) (xy 94.17522 -281.419623) (xy 94.198726 -281.465755)
			(xy 94.214725 -281.514995) (xy 94.222824 -281.566133) (xy 94.223332 -281.59202) (xy 94.222842 -281.617354)
			(xy 94.215087 -281.667425) (xy 94.199764 -281.71572) (xy 94.177233 -281.761102) (xy 94.148024 -281.802503)
			(xy 94.112825 -281.838948) (xy 94.072465 -281.869579) (xy 94.027893 -281.893676) (xy 93.980161 -281.910669)
			(xy 93.955362 -281.91587) (xy 93.932502 -281.920188) (xy 93.727524 -282.275026) (xy 93.735398 -282.297124)
			(xy 93.744018 -282.323474) (xy 93.753346 -282.378119) (xy 93.75394 -282.405836) (xy 94.974156 -282.405836)
			(xy 94.974616 -282.380501) (xy 94.982377 -282.33043) (xy 94.997705 -282.282135) (xy 95.020241 -282.236753)
			(xy 95.049454 -282.195352) (xy 95.084656 -282.158908) (xy 95.125019 -282.128277) (xy 95.169592 -282.104181)
			(xy 95.217327 -282.087187) (xy 95.242126 -282.081986) (xy 95.264986 -282.077668) (xy 95.470218 -281.722322)
			(xy 95.462598 -281.700478) (xy 95.45397 -281.674197) (xy 95.444658 -281.619675) (xy 95.444056 -281.59202)
			(xy 95.444564 -281.566113) (xy 95.45267 -281.514936) (xy 95.468682 -281.465657) (xy 95.492205 -281.41949)
			(xy 95.522661 -281.377571) (xy 95.559299 -281.340933) (xy 95.601218 -281.310477) (xy 95.647385 -281.286954)
			(xy 95.696664 -281.270942) (xy 95.747841 -281.262836) (xy 95.799655 -281.262836) (xy 95.850832 -281.270942)
			(xy 95.900111 -281.286954) (xy 95.946278 -281.310477) (xy 95.988197 -281.340933) (xy 96.024835 -281.377571)
			(xy 96.055291 -281.41949) (xy 96.078814 -281.465657) (xy 96.094826 -281.514936) (xy 96.102932 -281.566113)
			(xy 96.10344 -281.59202) (xy 97.323656 -281.59202) (xy 97.32415 -281.566675) (xy 97.33192 -281.516583)
			(xy 97.347266 -281.468271) (xy 97.369824 -281.422876) (xy 97.399064 -281.381469) (xy 97.434298 -281.345025)
			(xy 97.474693 -281.314403) (xy 97.5193 -281.290323) (xy 97.567066 -281.273355) (xy 97.59188 -281.26817)
			(xy 97.61474 -281.263852) (xy 97.819718 -280.909014) (xy 97.811844 -280.88717) (xy 97.803259 -280.860753)
			(xy 97.794066 -280.805977) (xy 97.793556 -280.778204) (xy 97.794064 -280.752317) (xy 97.802163 -280.701179)
			(xy 97.818162 -280.651939) (xy 97.841668 -280.605807) (xy 97.8721 -280.56392) (xy 97.90871 -280.52731)
			(xy 97.950597 -280.496878) (xy 97.996729 -280.473372) (xy 98.045969 -280.457373) (xy 98.097107 -280.449274)
			(xy 98.148881 -280.449274) (xy 98.200019 -280.457373) (xy 98.249259 -280.473372) (xy 98.295391 -280.496878)
			(xy 98.337278 -280.52731) (xy 98.373888 -280.56392) (xy 98.40432 -280.605807) (xy 98.427826 -280.651939)
			(xy 98.443825 -280.701179) (xy 98.451924 -280.752317) (xy 98.452432 -280.778204) (xy 100.612956 -280.778204)
			(xy 100.613464 -280.752317) (xy 100.621563 -280.701179) (xy 100.637562 -280.651939) (xy 100.661068 -280.605807)
			(xy 100.6915 -280.56392) (xy 100.72811 -280.52731) (xy 100.769997 -280.496878) (xy 100.816129 -280.473372)
			(xy 100.865369 -280.457373) (xy 100.916507 -280.449274) (xy 100.968281 -280.449274) (xy 101.019419 -280.457373)
			(xy 101.068659 -280.473372) (xy 101.114791 -280.496878) (xy 101.156678 -280.52731) (xy 101.193288 -280.56392)
			(xy 101.22372 -280.605807) (xy 101.247226 -280.651939) (xy 101.263225 -280.701179) (xy 101.271324 -280.752317)
			(xy 101.271832 -280.778204) (xy 103.432356 -280.778204) (xy 103.432864 -280.752317) (xy 103.440963 -280.701179)
			(xy 103.456962 -280.651939) (xy 103.480468 -280.605807) (xy 103.5109 -280.56392) (xy 103.54751 -280.52731)
			(xy 103.589397 -280.496878) (xy 103.635529 -280.473372) (xy 103.684769 -280.457373) (xy 103.735907 -280.449274)
			(xy 103.787681 -280.449274) (xy 103.838819 -280.457373) (xy 103.888059 -280.473372) (xy 103.934191 -280.496878)
			(xy 103.976078 -280.52731) (xy 104.012688 -280.56392) (xy 104.04312 -280.605807) (xy 104.066626 -280.651939)
			(xy 104.082625 -280.701179) (xy 104.090724 -280.752317) (xy 104.091232 -280.778204) (xy 104.372156 -280.778204)
			(xy 104.372678 -280.752871) (xy 104.380429 -280.702803) (xy 104.395748 -280.654509) (xy 104.418275 -280.609127)
			(xy 104.44748 -280.567726) (xy 104.482675 -280.531281) (xy 104.523032 -280.500649) (xy 104.567599 -280.476552)
			(xy 104.615329 -280.459556) (xy 104.640126 -280.454354) (xy 104.662986 -280.450036) (xy 104.868218 -280.09469)
			(xy 104.860598 -280.072592) (xy 104.851973 -280.04631) (xy 104.842659 -279.991789) (xy 104.842056 -279.964134)
			(xy 104.842564 -279.938227) (xy 104.85067 -279.88705) (xy 104.866682 -279.837771) (xy 104.890205 -279.791604)
			(xy 104.920661 -279.749685) (xy 104.957299 -279.713047) (xy 104.999218 -279.682591) (xy 105.045385 -279.659068)
			(xy 105.094664 -279.643056) (xy 105.145841 -279.63495) (xy 105.197655 -279.63495) (xy 105.248832 -279.643056)
			(xy 105.298111 -279.659068) (xy 105.344278 -279.682591) (xy 105.386197 -279.713047) (xy 105.422835 -279.749685)
			(xy 105.453291 -279.791604) (xy 105.476814 -279.837771) (xy 105.492826 -279.88705) (xy 105.500932 -279.938227)
			(xy 105.50144 -279.964134) (xy 105.501001 -279.989499) (xy 105.500926 -279.989983) (xy 336.806103 -279.989983)
			(xy 336.806103 -279.938217) (xy 336.814201 -279.887089) (xy 336.830196 -279.837856) (xy 336.853696 -279.791732)
			(xy 336.884121 -279.749851) (xy 336.920722 -279.713245) (xy 336.9626 -279.682815) (xy 337.008721 -279.659311)
			(xy 337.057952 -279.64331) (xy 337.109079 -279.635206) (xy 337.134962 -279.634696) (xy 337.160473 -279.635206)
			(xy 337.210886 -279.64306) (xy 337.259487 -279.658588) (xy 337.305115 -279.681418) (xy 337.346681 -279.711006)
			(xy 337.383193 -279.746643) (xy 337.398868 -279.766776) (xy 337.810856 -279.766776) (xy 337.826548 -279.746656)
			(xy 337.863055 -279.711012) (xy 337.904617 -279.681418) (xy 337.950241 -279.658579) (xy 337.998839 -279.643041)
			(xy 338.049251 -279.635176) (xy 338.074762 -279.634696) (xy 338.100656 -279.635106) (xy 338.151807 -279.643203)
			(xy 338.201062 -279.659201) (xy 338.247208 -279.682709) (xy 338.289107 -279.713146) (xy 338.325729 -279.749764)
			(xy 338.356171 -279.79166) (xy 338.379684 -279.837803) (xy 338.395689 -279.887056) (xy 338.403791 -279.938206)
			(xy 338.403791 -279.964134) (xy 344.323924 -279.964134) (xy 344.324432 -279.938227) (xy 344.332538 -279.88705)
			(xy 344.34855 -279.837771) (xy 344.372073 -279.791604) (xy 344.402529 -279.749685) (xy 344.439167 -279.713047)
			(xy 344.481086 -279.682591) (xy 344.527253 -279.659068) (xy 344.576532 -279.643056) (xy 344.627709 -279.63495)
			(xy 344.679523 -279.63495) (xy 344.7307 -279.643056) (xy 344.779979 -279.659068) (xy 344.826146 -279.682591)
			(xy 344.868065 -279.713047) (xy 344.904703 -279.749685) (xy 344.935159 -279.791604) (xy 344.958682 -279.837771)
			(xy 344.974694 -279.88705) (xy 344.9828 -279.938227) (xy 344.983308 -279.964134) (xy 344.982671 -279.991925)
			(xy 344.973225 -280.046702) (xy 344.964512 -280.0731) (xy 344.956892 -280.095198) (xy 345.16187 -280.450036)
			(xy 345.18473 -280.454354) (xy 345.209535 -280.459531) (xy 345.257274 -280.476523) (xy 345.30185 -280.500619)
			(xy 345.342215 -280.531252) (xy 345.377417 -280.5677) (xy 345.406629 -280.609105) (xy 345.429161 -280.654492)
			(xy 345.444484 -280.702792) (xy 345.452236 -280.752868) (xy 345.4527 -280.778204) (xy 345.452192 -280.804091)
			(xy 345.444093 -280.855229) (xy 345.428094 -280.904469) (xy 345.404588 -280.950601) (xy 345.374156 -280.992488)
			(xy 345.337546 -281.029098) (xy 345.295659 -281.05953) (xy 345.249527 -281.083036) (xy 345.200287 -281.099035)
			(xy 345.149149 -281.107134) (xy 345.097375 -281.107134) (xy 345.046237 -281.099035) (xy 344.996997 -281.083036)
			(xy 344.950865 -281.05953) (xy 344.908978 -281.029098) (xy 344.872368 -280.992488) (xy 344.841936 -280.950601)
			(xy 344.81843 -280.904469) (xy 344.802431 -280.855229) (xy 344.794332 -280.804091) (xy 344.793824 -280.778204)
			(xy 344.794353 -280.750496) (xy 344.803549 -280.695849) (xy 344.812112 -280.669492) (xy 344.819986 -280.647394)
			(xy 344.614754 -280.292302) (xy 344.591894 -280.287984) (xy 344.567101 -280.282754) (xy 344.519365 -280.265768)
			(xy 344.47479 -280.241678) (xy 344.434426 -280.211052) (xy 344.399223 -280.174611) (xy 344.37001 -280.133213)
			(xy 344.347475 -280.087832) (xy 344.332148 -280.039538) (xy 344.32439 -279.989468) (xy 344.323924 -279.964134)
			(xy 338.403791 -279.964134) (xy 338.403791 -279.989994) (xy 338.395689 -280.041144) (xy 338.379684 -280.090397)
			(xy 338.356171 -280.13654) (xy 338.325729 -280.178436) (xy 338.289107 -280.215054) (xy 338.247208 -280.245491)
			(xy 338.201062 -280.268999) (xy 338.151807 -280.284997) (xy 338.100656 -280.293094) (xy 338.074762 -280.293572)
			(xy 338.049249 -280.293131) (xy 337.998832 -280.285263) (xy 337.950229 -280.269723) (xy 337.9046 -280.24688)
			(xy 337.863036 -280.21728) (xy 337.826528 -280.18163) (xy 337.810856 -280.161492) (xy 337.398868 -280.161492)
			(xy 337.383211 -280.181641) (xy 337.346698 -280.217284) (xy 337.305129 -280.246877) (xy 337.259498 -280.269711)
			(xy 337.210893 -280.285241) (xy 337.160475 -280.293097) (xy 337.134962 -280.293572) (xy 337.109079 -280.292994)
			(xy 337.057952 -280.28489) (xy 337.008721 -280.268889) (xy 336.9626 -280.245385) (xy 336.920722 -280.214955)
			(xy 336.884121 -280.178349) (xy 336.853696 -280.136468) (xy 336.830196 -280.090344) (xy 336.814201 -280.041111)
			(xy 336.806103 -279.989983) (xy 105.500926 -279.989983) (xy 105.493248 -280.039631) (xy 105.4779 -280.087982)
			(xy 105.45532 -280.133408) (xy 105.426041 -280.174835) (xy 105.390757 -280.211282) (xy 105.350301 -280.241888)
			(xy 105.305631 -280.26593) (xy 105.257803 -280.282837) (xy 105.232962 -280.287984) (xy 105.209848 -280.292302)
			(xy 105.00487 -280.647394) (xy 105.012744 -280.669492) (xy 105.021304 -280.69585) (xy 105.030503 -280.750496)
			(xy 105.031032 -280.778204) (xy 105.030524 -280.804091) (xy 105.030521 -280.804107) (xy 105.31222 -280.804107)
			(xy 105.31222 -280.752293) (xy 105.320326 -280.701118) (xy 105.336337 -280.65184) (xy 105.359859 -280.605674)
			(xy 105.390314 -280.563756) (xy 105.426951 -280.527118) (xy 105.468869 -280.496662) (xy 105.515035 -280.473139)
			(xy 105.564312 -280.457127) (xy 105.615487 -280.449021) (xy 105.641394 -280.448512) (xy 105.666906 -280.448992)
			(xy 105.717321 -280.456852) (xy 105.765922 -280.472385) (xy 105.811551 -280.495221) (xy 105.853116 -280.524814)
			(xy 105.889626 -280.560457) (xy 105.9053 -280.580592) (xy 106.317288 -280.580592) (xy 106.332966 -280.560461)
			(xy 106.369475 -280.524817) (xy 106.41104 -280.495223) (xy 106.456667 -280.472386) (xy 106.505268 -280.456852)
			(xy 106.555682 -280.44899) (xy 106.581194 -280.448512) (xy 106.607104 -280.448985) (xy 106.658286 -280.457091)
			(xy 106.70757 -280.473103) (xy 106.753743 -280.496628) (xy 106.795666 -280.527087) (xy 106.832309 -280.563729)
			(xy 106.862768 -280.605652) (xy 106.886294 -280.651824) (xy 106.902308 -280.701108) (xy 106.910414 -280.75229)
			(xy 106.910414 -280.804105) (xy 342.91452 -280.804105) (xy 342.91452 -280.752295) (xy 342.922625 -280.701122)
			(xy 342.938634 -280.651848) (xy 342.962153 -280.605684) (xy 342.992605 -280.563767) (xy 343.029238 -280.527129)
			(xy 343.071151 -280.496673) (xy 343.117313 -280.473148) (xy 343.166585 -280.457133) (xy 343.217757 -280.449023)
			(xy 343.243662 -280.448512) (xy 343.269173 -280.449015) (xy 343.319587 -280.45687) (xy 343.368188 -280.472399)
			(xy 343.413817 -280.49523) (xy 343.455383 -280.524819) (xy 343.491894 -280.560459) (xy 343.507568 -280.580592)
			(xy 343.91981 -280.580592) (xy 343.935476 -280.56045) (xy 343.971987 -280.524807) (xy 344.013554 -280.495214)
			(xy 344.059184 -280.472379) (xy 344.107788 -280.456847) (xy 344.158204 -280.448988) (xy 344.183716 -280.448512)
			(xy 344.209623 -280.449014) (xy 344.260798 -280.457121) (xy 344.310075 -280.473134) (xy 344.356241 -280.496659)
			(xy 344.398158 -280.527115) (xy 344.434795 -280.563754) (xy 344.465249 -280.605673) (xy 344.488772 -280.65184)
			(xy 344.504782 -280.701117) (xy 344.512888 -280.752293) (xy 344.512888 -280.804107) (xy 344.504782 -280.855283)
			(xy 344.488772 -280.90456) (xy 344.465249 -280.950727) (xy 344.434795 -280.992646) (xy 344.398158 -281.029285)
			(xy 344.356241 -281.059741) (xy 344.310075 -281.083266) (xy 344.260798 -281.099279) (xy 344.209623 -281.107386)
			(xy 344.183716 -281.107896) (xy 344.158205 -281.107405) (xy 344.107791 -281.099547) (xy 344.059189 -281.084016)
			(xy 344.013561 -281.061182) (xy 343.971995 -281.031591) (xy 343.935484 -280.99595) (xy 343.91981 -280.975816)
			(xy 343.507568 -280.975816) (xy 343.491917 -280.99597) (xy 343.455403 -281.031612) (xy 343.413832 -281.061203)
			(xy 343.368199 -281.084036) (xy 343.319593 -281.099566) (xy 343.269175 -281.107421) (xy 343.243662 -281.107896)
			(xy 343.217757 -281.107377) (xy 343.166585 -281.099267) (xy 343.117313 -281.083252) (xy 343.071151 -281.059727)
			(xy 343.029238 -281.029271) (xy 342.992605 -280.992633) (xy 342.962153 -280.950716) (xy 342.938634 -280.904552)
			(xy 342.922625 -280.855278) (xy 342.91452 -280.804105) (xy 106.910414 -280.804105) (xy 106.910414 -280.80411)
			(xy 106.902308 -280.855292) (xy 106.886294 -280.904576) (xy 106.862768 -280.950748) (xy 106.832309 -280.992671)
			(xy 106.795666 -281.029313) (xy 106.753743 -281.059772) (xy 106.70757 -281.083297) (xy 106.658286 -281.099309)
			(xy 106.607104 -281.107415) (xy 106.581194 -281.107896) (xy 106.555682 -281.107421) (xy 106.505267 -281.09956)
			(xy 106.456665 -281.084025) (xy 106.411037 -281.061188) (xy 106.369472 -281.031595) (xy 106.332962 -280.995951)
			(xy 106.317288 -280.975816) (xy 105.9053 -280.975816) (xy 105.889631 -280.995955) (xy 105.85312 -281.031598)
			(xy 105.811553 -281.06119) (xy 105.765924 -281.084026) (xy 105.717322 -281.099559) (xy 105.666906 -281.107419)
			(xy 105.641394 -281.107896) (xy 105.615487 -281.107379) (xy 105.564312 -281.099273) (xy 105.515035 -281.083261)
			(xy 105.468869 -281.059738) (xy 105.426951 -281.029282) (xy 105.390314 -280.992644) (xy 105.359859 -280.950726)
			(xy 105.336337 -280.90456) (xy 105.320326 -280.855282) (xy 105.31222 -280.804107) (xy 105.030521 -280.804107)
			(xy 105.022425 -280.855229) (xy 105.006426 -280.904469) (xy 104.98292 -280.950601) (xy 104.952488 -280.992488)
			(xy 104.915878 -281.029098) (xy 104.873991 -281.05953) (xy 104.827859 -281.083036) (xy 104.778619 -281.099035)
			(xy 104.727481 -281.107134) (xy 104.675707 -281.107134) (xy 104.624569 -281.099035) (xy 104.575329 -281.083036)
			(xy 104.529197 -281.05953) (xy 104.48731 -281.029098) (xy 104.4507 -280.992488) (xy 104.420268 -280.950601)
			(xy 104.396762 -280.904469) (xy 104.380763 -280.855229) (xy 104.372664 -280.804091) (xy 104.372156 -280.778204)
			(xy 104.091232 -280.778204) (xy 104.091232 -280.778712) (xy 104.090641 -280.806228) (xy 104.081455 -280.860489)
			(xy 104.072944 -280.886662) (xy 104.065324 -280.908506) (xy 104.270556 -281.263852) (xy 104.293416 -281.26817)
			(xy 104.318226 -281.273386) (xy 104.366003 -281.290334) (xy 104.410622 -281.314398) (xy 104.451028 -281.345012)
			(xy 104.48627 -281.381453) (xy 104.515516 -281.422861) (xy 104.538075 -281.468259) (xy 104.553416 -281.516576)
			(xy 104.561176 -281.566673) (xy 104.56164 -281.59202) (xy 105.781856 -281.59202) (xy 105.782364 -281.566113)
			(xy 105.79047 -281.514936) (xy 105.806482 -281.465657) (xy 105.830005 -281.41949) (xy 105.860461 -281.377571)
			(xy 105.897099 -281.340933) (xy 105.939018 -281.310477) (xy 105.985185 -281.286954) (xy 106.034464 -281.270942)
			(xy 106.085641 -281.262836) (xy 106.137455 -281.262836) (xy 106.188632 -281.270942) (xy 106.237911 -281.286954)
			(xy 106.284078 -281.310477) (xy 106.325997 -281.340933) (xy 106.362635 -281.377571) (xy 106.393091 -281.41949)
			(xy 106.416614 -281.465657) (xy 106.432626 -281.514936) (xy 106.440732 -281.566113) (xy 106.44124 -281.59202)
			(xy 106.440709 -281.617904) (xy 338.685436 -281.617904) (xy 338.685436 -281.566096) (xy 338.69354 -281.514926)
			(xy 338.709548 -281.465654) (xy 338.733067 -281.419492) (xy 338.763517 -281.377577) (xy 338.800148 -281.340942)
			(xy 338.84206 -281.310487) (xy 338.888219 -281.286963) (xy 338.937489 -281.270949) (xy 338.988658 -281.262839)
			(xy 339.014562 -281.262328) (xy 339.040073 -281.262825) (xy 339.090487 -281.270681) (xy 339.139089 -281.28621)
			(xy 339.184718 -281.309042) (xy 339.226284 -281.338633) (xy 339.262794 -281.374274) (xy 339.278468 -281.394408)
			(xy 339.690456 -281.394408) (xy 339.706157 -281.374295) (xy 339.742661 -281.33865) (xy 339.784221 -281.309053)
			(xy 339.829844 -281.286213) (xy 339.878441 -281.270675) (xy 339.928852 -281.262808) (xy 339.954362 -281.262328)
			(xy 339.980275 -281.262767) (xy 340.031464 -281.270869) (xy 340.080754 -281.286879) (xy 340.126933 -281.310404)
			(xy 340.168863 -281.340863) (xy 340.205512 -281.377508) (xy 340.235976 -281.419434) (xy 340.259506 -281.465611)
			(xy 340.275522 -281.514899) (xy 340.28363 -281.566087) (xy 340.28363 -281.617913) (xy 340.275522 -281.669101)
			(xy 340.259506 -281.718389) (xy 340.235976 -281.764566) (xy 340.205512 -281.806492) (xy 340.168863 -281.843137)
			(xy 340.126933 -281.873596) (xy 340.080754 -281.897121) (xy 340.031464 -281.913131) (xy 339.980275 -281.921233)
			(xy 339.954362 -281.921712) (xy 339.928849 -281.921255) (xy 339.878434 -281.913389) (xy 339.829832 -281.89785)
			(xy 339.784204 -281.87501) (xy 339.742639 -281.845414) (xy 339.706129 -281.809768) (xy 339.690456 -281.789632)
			(xy 339.278468 -281.789632) (xy 339.262822 -281.80979) (xy 339.226306 -281.845431) (xy 339.184734 -281.875021)
			(xy 339.139101 -281.897853) (xy 339.090494 -281.913382) (xy 339.040076 -281.921238) (xy 339.014562 -281.921712)
			(xy 338.988658 -281.921161) (xy 338.937489 -281.913051) (xy 338.888219 -281.897037) (xy 338.84206 -281.873513)
			(xy 338.800148 -281.843058) (xy 338.763517 -281.806423) (xy 338.733067 -281.764508) (xy 338.709548 -281.718346)
			(xy 338.69354 -281.669074) (xy 338.685436 -281.617904) (xy 106.440709 -281.617904) (xy 106.44067 -281.619802)
			(xy 106.431345 -281.674578) (xy 106.422698 -281.700986) (xy 106.414824 -281.72283) (xy 106.619802 -282.077668)
			(xy 106.642662 -282.081986) (xy 106.667464 -282.087182) (xy 106.715205 -282.104167) (xy 106.759784 -282.128258)
			(xy 106.800151 -282.158887) (xy 106.835356 -282.195333) (xy 106.864568 -282.236737) (xy 106.8871 -282.282123)
			(xy 106.902422 -282.330424) (xy 106.910171 -282.3805) (xy 106.910632 -282.405836) (xy 335.395824 -282.405836)
			(xy 335.396332 -282.379949) (xy 335.404431 -282.328811) (xy 335.42043 -282.279571) (xy 335.443936 -282.233439)
			(xy 335.474368 -282.191552) (xy 335.510978 -282.154942) (xy 335.552865 -282.12451) (xy 335.598997 -282.101004)
			(xy 335.648237 -282.085005) (xy 335.699375 -282.076906) (xy 335.751149 -282.076906) (xy 335.802287 -282.085005)
			(xy 335.851527 -282.101004) (xy 335.897659 -282.12451) (xy 335.939546 -282.154942) (xy 335.976156 -282.191552)
			(xy 336.006588 -282.233439) (xy 336.030094 -282.279571) (xy 336.046093 -282.328811) (xy 336.054192 -282.379949)
			(xy 336.0547 -282.405836) (xy 341.034624 -282.405836) (xy 341.035068 -282.38049) (xy 341.04285 -282.330397)
			(xy 341.058205 -282.282085) (xy 341.080771 -282.236692) (xy 341.110018 -282.195286) (xy 341.145256 -282.158843)
			(xy 341.185656 -282.128222) (xy 341.230265 -282.104142) (xy 341.278033 -282.087172) (xy 341.302848 -282.081986)
			(xy 341.325708 -282.077668) (xy 341.530686 -281.72283) (xy 341.522812 -281.700986) (xy 341.514229 -281.674568)
			(xy 341.505035 -281.619792) (xy 341.504524 -281.59202) (xy 341.505032 -281.566133) (xy 341.513131 -281.514995)
			(xy 341.52913 -281.465755) (xy 341.552636 -281.419623) (xy 341.583068 -281.377736) (xy 341.619678 -281.341126)
			(xy 341.661565 -281.310694) (xy 341.707697 -281.287188) (xy 341.756937 -281.271189) (xy 341.808075 -281.26309)
			(xy 341.859849 -281.26309) (xy 341.910987 -281.271189) (xy 341.960227 -281.287188) (xy 342.006359 -281.310694)
			(xy 342.048246 -281.341126) (xy 342.084856 -281.377736) (xy 342.115288 -281.419623) (xy 342.138794 -281.465755)
			(xy 342.154793 -281.514995) (xy 342.162892 -281.566133) (xy 342.1634 -281.59202) (xy 342.162935 -281.617355)
			(xy 342.15518 -281.667428) (xy 342.139855 -281.715725) (xy 342.117321 -281.761109) (xy 342.088109 -281.802511)
			(xy 342.052906 -281.838956) (xy 342.012542 -281.869586) (xy 341.967967 -281.89368) (xy 341.92023 -281.910671)
			(xy 341.89543 -281.91587) (xy 341.87257 -281.920188) (xy 341.667592 -282.275026) (xy 341.675466 -282.297124)
			(xy 341.684085 -282.323474) (xy 341.693414 -282.378119) (xy 341.694008 -282.405836) (xy 342.914224 -282.405836)
			(xy 342.914629 -282.380499) (xy 342.922392 -282.330422) (xy 342.937724 -282.282122) (xy 342.960266 -282.236737)
			(xy 342.989485 -282.195335) (xy 343.024695 -282.15889) (xy 343.065066 -282.128262) (xy 343.109648 -282.10417)
			(xy 343.157391 -282.087183) (xy 343.182194 -282.081986) (xy 343.205054 -282.077668) (xy 343.410286 -281.722322)
			(xy 343.402666 -281.700478) (xy 343.39404 -281.674196) (xy 343.384726 -281.619675) (xy 343.384124 -281.59202)
			(xy 343.384632 -281.566113) (xy 343.392738 -281.514936) (xy 343.40875 -281.465657) (xy 343.432273 -281.41949)
			(xy 343.462729 -281.377571) (xy 343.499367 -281.340933) (xy 343.541286 -281.310477) (xy 343.587453 -281.286954)
			(xy 343.636732 -281.270942) (xy 343.687909 -281.262836) (xy 343.739723 -281.262836) (xy 343.7909 -281.270942)
			(xy 343.840179 -281.286954) (xy 343.886346 -281.310477) (xy 343.928265 -281.340933) (xy 343.964903 -281.377571)
			(xy 343.995359 -281.41949) (xy 344.018882 -281.465657) (xy 344.034894 -281.514936) (xy 344.043 -281.566113)
			(xy 344.043508 -281.59202) (xy 345.263724 -281.59202) (xy 345.264244 -281.566676) (xy 345.272013 -281.516587)
			(xy 345.287357 -281.468277) (xy 345.309913 -281.422884) (xy 345.33915 -281.381477) (xy 345.374379 -281.345033)
			(xy 345.414771 -281.31441) (xy 345.459374 -281.290329) (xy 345.507136 -281.273357) (xy 345.531948 -281.26817)
			(xy 345.554808 -281.263852) (xy 345.759786 -280.909014) (xy 345.751912 -280.88717) (xy 345.743326 -280.860753)
			(xy 345.734134 -280.805977) (xy 345.733624 -280.778204) (xy 345.734132 -280.752317) (xy 345.742231 -280.701179)
			(xy 345.75823 -280.651939) (xy 345.781736 -280.605807) (xy 345.812168 -280.56392) (xy 345.848778 -280.52731)
			(xy 345.890665 -280.496878) (xy 345.936797 -280.473372) (xy 345.986037 -280.457373) (xy 346.037175 -280.449274)
			(xy 346.088949 -280.449274) (xy 346.140087 -280.457373) (xy 346.189327 -280.473372) (xy 346.235459 -280.496878)
			(xy 346.277346 -280.52731) (xy 346.313956 -280.56392) (xy 346.344388 -280.605807) (xy 346.367894 -280.651939)
			(xy 346.383893 -280.701179) (xy 346.391992 -280.752317) (xy 346.3925 -280.778204) (xy 348.553024 -280.778204)
			(xy 348.553532 -280.752317) (xy 348.561631 -280.701179) (xy 348.57763 -280.651939) (xy 348.601136 -280.605807)
			(xy 348.631568 -280.56392) (xy 348.668178 -280.52731) (xy 348.710065 -280.496878) (xy 348.756197 -280.473372)
			(xy 348.805437 -280.457373) (xy 348.856575 -280.449274) (xy 348.908349 -280.449274) (xy 348.959487 -280.457373)
			(xy 349.008727 -280.473372) (xy 349.054859 -280.496878) (xy 349.096746 -280.52731) (xy 349.133356 -280.56392)
			(xy 349.163788 -280.605807) (xy 349.187294 -280.651939) (xy 349.203293 -280.701179) (xy 349.211392 -280.752317)
			(xy 349.2119 -280.778204) (xy 351.372424 -280.778204) (xy 351.372932 -280.752317) (xy 351.381031 -280.701179)
			(xy 351.39703 -280.651939) (xy 351.420536 -280.605807) (xy 351.450968 -280.56392) (xy 351.487578 -280.52731)
			(xy 351.529465 -280.496878) (xy 351.575597 -280.473372) (xy 351.624837 -280.457373) (xy 351.675975 -280.449274)
			(xy 351.727749 -280.449274) (xy 351.778887 -280.457373) (xy 351.828127 -280.473372) (xy 351.874259 -280.496878)
			(xy 351.916146 -280.52731) (xy 351.952756 -280.56392) (xy 351.983188 -280.605807) (xy 352.006694 -280.651939)
			(xy 352.022693 -280.701179) (xy 352.030792 -280.752317) (xy 352.0313 -280.778204) (xy 352.312224 -280.778204)
			(xy 352.312691 -280.752869) (xy 352.320444 -280.702795) (xy 352.335767 -280.654496) (xy 352.3583 -280.609112)
			(xy 352.387511 -280.567709) (xy 352.422714 -280.531263) (xy 352.463079 -280.500633) (xy 352.507655 -280.47654)
			(xy 352.555393 -280.459552) (xy 352.580194 -280.454354) (xy 352.603054 -280.450036) (xy 352.808286 -280.09469)
			(xy 352.800666 -280.072592) (xy 352.792043 -280.046309) (xy 352.782727 -279.991789) (xy 352.782124 -279.964134)
			(xy 352.782632 -279.938227) (xy 352.790738 -279.88705) (xy 352.80675 -279.837771) (xy 352.830273 -279.791604)
			(xy 352.860729 -279.749685) (xy 352.897367 -279.713047) (xy 352.939286 -279.682591) (xy 352.985453 -279.659068)
			(xy 353.034732 -279.643056) (xy 353.085909 -279.63495) (xy 353.137723 -279.63495) (xy 353.1889 -279.643056)
			(xy 353.238179 -279.659068) (xy 353.284346 -279.682591) (xy 353.326265 -279.713047) (xy 353.362903 -279.749685)
			(xy 353.393359 -279.791604) (xy 353.416882 -279.837771) (xy 353.432894 -279.88705) (xy 353.441 -279.938227)
			(xy 353.441508 -279.964134) (xy 353.441095 -279.9895) (xy 353.433341 -280.039635) (xy 353.417991 -280.087988)
			(xy 353.395408 -280.133416) (xy 353.366127 -280.174843) (xy 353.330839 -280.211291) (xy 353.290379 -280.241896)
			(xy 353.245705 -280.265935) (xy 353.197873 -280.282839) (xy 353.17303 -280.287984) (xy 353.149916 -280.292302)
			(xy 352.944938 -280.647394) (xy 352.952812 -280.669492) (xy 352.961371 -280.695851) (xy 352.970571 -280.750496)
			(xy 352.9711 -280.778204) (xy 352.970592 -280.804091) (xy 352.97059 -280.804105) (xy 353.25232 -280.804105)
			(xy 353.25232 -280.752295) (xy 353.260425 -280.701122) (xy 353.276434 -280.651848) (xy 353.299953 -280.605684)
			(xy 353.330405 -280.563767) (xy 353.367038 -280.527129) (xy 353.408951 -280.496673) (xy 353.455113 -280.473148)
			(xy 353.504385 -280.457133) (xy 353.555557 -280.449023) (xy 353.581462 -280.448512) (xy 353.606973 -280.449015)
			(xy 353.657387 -280.45687) (xy 353.705988 -280.472399) (xy 353.751617 -280.49523) (xy 353.793183 -280.524819)
			(xy 353.829694 -280.560459) (xy 353.845368 -280.580592) (xy 354.257356 -280.580592) (xy 354.273053 -280.560476)
			(xy 354.309558 -280.524831) (xy 354.351119 -280.495236) (xy 354.396742 -280.472396) (xy 354.44534 -280.456858)
			(xy 354.495751 -280.448992) (xy 354.521262 -280.448512) (xy 354.547174 -280.448983) (xy 354.59836 -280.457084)
			(xy 354.647648 -280.473094) (xy 354.693825 -280.496618) (xy 354.735753 -280.527076) (xy 354.7724 -280.563718)
			(xy 354.802863 -280.605643) (xy 354.826391 -280.651817) (xy 354.842407 -280.701103) (xy 354.850514 -280.752288)
			(xy 354.850514 -280.804112) (xy 354.842407 -280.855297) (xy 354.826391 -280.904583) (xy 354.802863 -280.950757)
			(xy 354.7724 -280.992682) (xy 354.735753 -281.029324) (xy 354.693825 -281.059782) (xy 354.647648 -281.083306)
			(xy 354.59836 -281.099316) (xy 354.547174 -281.107417) (xy 354.521262 -281.107896) (xy 354.495749 -281.107445)
			(xy 354.445333 -281.099578) (xy 354.396731 -281.084039) (xy 354.351103 -281.061198) (xy 354.309538 -281.031601)
			(xy 354.273029 -280.995953) (xy 354.257356 -280.975816) (xy 353.845368 -280.975816) (xy 353.829717 -280.99597)
			(xy 353.793203 -281.031612) (xy 353.751632 -281.061203) (xy 353.705999 -281.084036) (xy 353.657393 -281.099566)
			(xy 353.606975 -281.107421) (xy 353.581462 -281.107896) (xy 353.555557 -281.107377) (xy 353.504385 -281.099267)
			(xy 353.455113 -281.083252) (xy 353.408951 -281.059727) (xy 353.367038 -281.029271) (xy 353.330405 -280.992633)
			(xy 353.299953 -280.950716) (xy 353.276434 -280.904552) (xy 353.260425 -280.855278) (xy 353.25232 -280.804105)
			(xy 352.97059 -280.804105) (xy 352.962493 -280.855229) (xy 352.946494 -280.904469) (xy 352.922988 -280.950601)
			(xy 352.892556 -280.992488) (xy 352.855946 -281.029098) (xy 352.814059 -281.05953) (xy 352.767927 -281.083036)
			(xy 352.718687 -281.099035) (xy 352.667549 -281.107134) (xy 352.615775 -281.107134) (xy 352.564637 -281.099035)
			(xy 352.515397 -281.083036) (xy 352.469265 -281.05953) (xy 352.427378 -281.029098) (xy 352.390768 -280.992488)
			(xy 352.360336 -280.950601) (xy 352.33683 -280.904469) (xy 352.320831 -280.855229) (xy 352.312732 -280.804091)
			(xy 352.312224 -280.778204) (xy 352.0313 -280.778204) (xy 352.0313 -280.778712) (xy 352.03071 -280.806228)
			(xy 352.021524 -280.860489) (xy 352.013012 -280.886662) (xy 352.005392 -280.908506) (xy 352.210624 -281.263852)
			(xy 352.233484 -281.26817) (xy 352.258305 -281.273337) (xy 352.306082 -281.290294) (xy 352.350699 -281.314367)
			(xy 352.391104 -281.344988) (xy 352.426344 -281.381435) (xy 352.455588 -281.422848) (xy 352.478145 -281.46825)
			(xy 352.493485 -281.516571) (xy 352.501244 -281.566671) (xy 352.501708 -281.59202) (xy 353.721924 -281.59202)
			(xy 353.722432 -281.566113) (xy 353.730538 -281.514936) (xy 353.74655 -281.465657) (xy 353.770073 -281.41949)
			(xy 353.800529 -281.377571) (xy 353.837167 -281.340933) (xy 353.879086 -281.310477) (xy 353.925253 -281.286954)
			(xy 353.974532 -281.270942) (xy 354.025709 -281.262836) (xy 354.077523 -281.262836) (xy 354.1287 -281.270942)
			(xy 354.177979 -281.286954) (xy 354.224146 -281.310477) (xy 354.266065 -281.340933) (xy 354.302703 -281.377571)
			(xy 354.333159 -281.41949) (xy 354.356682 -281.465657) (xy 354.372694 -281.514936) (xy 354.3808 -281.566113)
			(xy 354.381308 -281.59202) (xy 354.380739 -281.619802) (xy 354.371414 -281.674578) (xy 354.362766 -281.700986)
			(xy 354.354892 -281.72283) (xy 354.55987 -282.077668) (xy 354.58273 -282.081986) (xy 354.607543 -282.087133)
			(xy 354.655283 -282.104127) (xy 354.699861 -282.128227) (xy 354.740227 -282.158863) (xy 354.775429 -282.195315)
			(xy 354.80464 -282.236724) (xy 354.82717 -282.282115) (xy 354.84249 -282.330419) (xy 354.850239 -282.380498)
			(xy 354.8507 -282.405836) (xy 354.850192 -282.431723) (xy 354.842093 -282.482861) (xy 354.826094 -282.532101)
			(xy 354.802588 -282.578233) (xy 354.772156 -282.62012) (xy 354.735546 -282.65673) (xy 354.693659 -282.687162)
			(xy 354.647527 -282.710668) (xy 354.598287 -282.726667) (xy 354.547149 -282.734766) (xy 354.495375 -282.734766)
			(xy 354.444237 -282.726667) (xy 354.394997 -282.710668) (xy 354.348865 -282.687162) (xy 354.306978 -282.65673)
			(xy 354.270368 -282.62012) (xy 354.239936 -282.578233) (xy 354.21643 -282.532101) (xy 354.200431 -282.482861)
			(xy 354.192332 -282.431723) (xy 354.191824 -282.405836) (xy 354.192361 -282.378128) (xy 354.201551 -282.323481)
			(xy 354.210112 -282.297124) (xy 354.217986 -282.275026) (xy 354.013008 -281.920188) (xy 353.990148 -281.91587)
			(xy 353.965319 -281.910737) (xy 353.917537 -281.893779) (xy 353.872916 -281.869705) (xy 353.832509 -281.83908)
			(xy 353.797268 -281.802629) (xy 353.768025 -281.761211) (xy 353.74547 -281.715803) (xy 353.730136 -281.667476)
			(xy 353.722383 -281.617371) (xy 353.721924 -281.59202) (xy 352.501708 -281.59202) (xy 352.5012 -281.617927)
			(xy 352.493094 -281.669104) (xy 352.477082 -281.718383) (xy 352.453559 -281.76455) (xy 352.423103 -281.806469)
			(xy 352.386465 -281.843107) (xy 352.344546 -281.873563) (xy 352.298379 -281.897086) (xy 352.2491 -281.913098)
			(xy 352.197923 -281.921204) (xy 352.146109 -281.921204) (xy 352.094932 -281.913098) (xy 352.045653 -281.897086)
			(xy 351.999486 -281.873563) (xy 351.957567 -281.843107) (xy 351.920929 -281.806469) (xy 351.890473 -281.76455)
			(xy 351.86695 -281.718383) (xy 351.850938 -281.669104) (xy 351.842832 -281.617927) (xy 351.842324 -281.59202)
			(xy 351.842922 -281.564303) (xy 351.852242 -281.509656) (xy 351.860866 -281.483308) (xy 351.86874 -281.46121)
			(xy 351.663762 -281.106372) (xy 351.640902 -281.102054) (xy 351.616072 -281.096882) (xy 351.568266 -281.079946)
			(xy 351.523618 -281.055889) (xy 351.483181 -281.025278) (xy 351.447909 -280.988835) (xy 351.418634 -280.947421)
			(xy 351.396047 -280.902011) (xy 351.380681 -280.853678) (xy 351.372898 -280.803562) (xy 351.372424 -280.778204)
			(xy 349.2119 -280.778204) (xy 349.2119 -280.778712) (xy 349.21131 -280.806228) (xy 349.202124 -280.860489)
			(xy 349.193612 -280.886662) (xy 349.185992 -280.908506) (xy 349.391224 -281.263852) (xy 349.414084 -281.26817)
			(xy 349.438905 -281.273337) (xy 349.486682 -281.290294) (xy 349.531299 -281.314367) (xy 349.571704 -281.344988)
			(xy 349.606944 -281.381435) (xy 349.636188 -281.422848) (xy 349.658745 -281.46825) (xy 349.674085 -281.516571)
			(xy 349.681844 -281.566671) (xy 349.682308 -281.59202) (xy 349.6818 -281.617927) (xy 349.673694 -281.669104)
			(xy 349.657682 -281.718383) (xy 349.634159 -281.76455) (xy 349.603703 -281.806469) (xy 349.567065 -281.843107)
			(xy 349.525146 -281.873563) (xy 349.478979 -281.897086) (xy 349.4297 -281.913098) (xy 349.378523 -281.921204)
			(xy 349.326709 -281.921204) (xy 349.275532 -281.913098) (xy 349.226253 -281.897086) (xy 349.180086 -281.873563)
			(xy 349.138167 -281.843107) (xy 349.101529 -281.806469) (xy 349.071073 -281.76455) (xy 349.04755 -281.718383)
			(xy 349.031538 -281.669104) (xy 349.023432 -281.617927) (xy 349.022924 -281.59202) (xy 349.023522 -281.564303)
			(xy 349.032842 -281.509656) (xy 349.041466 -281.483308) (xy 349.04934 -281.46121) (xy 348.844362 -281.106372)
			(xy 348.821502 -281.102054) (xy 348.796672 -281.096882) (xy 348.748866 -281.079946) (xy 348.704218 -281.055889)
			(xy 348.663781 -281.025278) (xy 348.628509 -280.988835) (xy 348.599234 -280.947421) (xy 348.576647 -280.902011)
			(xy 348.561281 -280.853678) (xy 348.553498 -280.803562) (xy 348.553024 -280.778204) (xy 346.3925 -280.778204)
			(xy 346.392021 -280.803539) (xy 346.384268 -280.853611) (xy 346.368945 -280.901908) (xy 346.346413 -280.947292)
			(xy 346.317203 -280.988694) (xy 346.282002 -281.025139) (xy 346.241639 -281.055769) (xy 346.197065 -281.079864)
			(xy 346.14933 -281.096855) (xy 346.12453 -281.102054) (xy 346.10167 -281.106372) (xy 345.896692 -281.46121)
			(xy 345.904566 -281.483308) (xy 345.913205 -281.509652) (xy 345.922521 -281.564301) (xy 345.923108 -281.59202)
			(xy 345.9226 -281.617909) (xy 347.143809 -281.617909) (xy 347.143809 -281.566091) (xy 347.151916 -281.514912)
			(xy 347.167929 -281.465631) (xy 347.191454 -281.419462) (xy 347.221912 -281.377541) (xy 347.258553 -281.340902)
			(xy 347.300475 -281.310446) (xy 347.346646 -281.286923) (xy 347.395928 -281.270912) (xy 347.447107 -281.262808)
			(xy 347.473016 -281.262328) (xy 347.498529 -281.262786) (xy 347.548945 -281.27065) (xy 347.597547 -281.286187)
			(xy 347.643176 -281.309027) (xy 347.684741 -281.338624) (xy 347.721249 -281.374271) (xy 347.736922 -281.394408)
			(xy 348.14891 -281.394408) (xy 348.16458 -281.37427) (xy 348.20109 -281.338625) (xy 348.242656 -281.309032)
			(xy 348.288285 -281.286196) (xy 348.336888 -281.270663) (xy 348.387304 -281.262804) (xy 348.412816 -281.262328)
			(xy 348.438724 -281.262797) (xy 348.489902 -281.270905) (xy 348.539182 -281.286919) (xy 348.585349 -281.310445)
			(xy 348.627269 -281.340903) (xy 348.663907 -281.377543) (xy 348.694363 -281.419464) (xy 348.717887 -281.465633)
			(xy 348.733899 -281.514914) (xy 348.742004 -281.566092) (xy 348.742004 -281.617908) (xy 348.733899 -281.669086)
			(xy 348.717887 -281.718367) (xy 348.694363 -281.764536) (xy 348.663907 -281.806457) (xy 348.627269 -281.843097)
			(xy 348.585349 -281.873555) (xy 348.539182 -281.897081) (xy 348.489902 -281.913095) (xy 348.438724 -281.921203)
			(xy 348.412816 -281.921712) (xy 348.387305 -281.921215) (xy 348.336891 -281.913357) (xy 348.28829 -281.897827)
			(xy 348.242662 -281.874994) (xy 348.201096 -281.845405) (xy 348.164585 -281.809765) (xy 348.14891 -281.789632)
			(xy 347.736922 -281.789632) (xy 347.721245 -281.809764) (xy 347.684735 -281.845407) (xy 347.64317 -281.875)
			(xy 347.597542 -281.897836) (xy 347.548942 -281.913371) (xy 347.498528 -281.921234) (xy 347.473016 -281.921712)
			(xy 347.447107 -281.921192) (xy 347.395928 -281.913088) (xy 347.346646 -281.897077) (xy 347.300475 -281.873554)
			(xy 347.258553 -281.843098) (xy 347.221912 -281.806459) (xy 347.191454 -281.764538) (xy 347.167929 -281.718369)
			(xy 347.151916 -281.669088) (xy 347.143809 -281.617909) (xy 345.9226 -281.617909) (xy 345.9226 -281.617927)
			(xy 345.914494 -281.669104) (xy 345.898482 -281.718383) (xy 345.874959 -281.76455) (xy 345.844503 -281.806469)
			(xy 345.807865 -281.843107) (xy 345.765946 -281.873563) (xy 345.719779 -281.897086) (xy 345.6705 -281.913098)
			(xy 345.619323 -281.921204) (xy 345.567509 -281.921204) (xy 345.516332 -281.913098) (xy 345.467053 -281.897086)
			(xy 345.420886 -281.873563) (xy 345.378967 -281.843107) (xy 345.342329 -281.806469) (xy 345.311873 -281.76455)
			(xy 345.28835 -281.718383) (xy 345.272338 -281.669104) (xy 345.264232 -281.617927) (xy 345.263724 -281.59202)
			(xy 344.043508 -281.59202) (xy 344.043045 -281.617395) (xy 344.035274 -281.667545) (xy 344.019903 -281.71591)
			(xy 343.997297 -281.761346) (xy 343.967989 -281.802777) (xy 343.932674 -281.839223) (xy 343.892188 -281.869822)
			(xy 343.847487 -281.893849) (xy 343.79963 -281.910736) (xy 343.774776 -281.91587) (xy 343.751916 -281.920188)
			(xy 343.546938 -282.275026) (xy 343.554812 -282.297124) (xy 343.563378 -282.32348) (xy 343.572573 -282.378127)
			(xy 343.5731 -282.405836) (xy 343.854024 -282.405836) (xy 343.854532 -282.379949) (xy 343.862631 -282.328811)
			(xy 343.87863 -282.279571) (xy 343.902136 -282.233439) (xy 343.932568 -282.191552) (xy 343.969178 -282.154942)
			(xy 344.011065 -282.12451) (xy 344.057197 -282.101004) (xy 344.106437 -282.085005) (xy 344.157575 -282.076906)
			(xy 344.209349 -282.076906) (xy 344.260487 -282.085005) (xy 344.309727 -282.101004) (xy 344.355859 -282.12451)
			(xy 344.397746 -282.154942) (xy 344.434356 -282.191552) (xy 344.464788 -282.233439) (xy 344.488294 -282.279571)
			(xy 344.504293 -282.328811) (xy 344.512392 -282.379949) (xy 344.5129 -282.405836) (xy 344.5129 -282.406344)
			(xy 344.512364 -282.431703) (xy 344.794152 -282.431703) (xy 344.794152 -282.379897) (xy 344.802256 -282.32873)
			(xy 344.818263 -282.27946) (xy 344.841781 -282.2333) (xy 344.872229 -282.191388) (xy 344.908859 -282.154754)
			(xy 344.950768 -282.124301) (xy 344.996925 -282.100778) (xy 345.046193 -282.084765) (xy 345.097359 -282.076655)
			(xy 345.123262 -282.076144) (xy 345.148774 -282.076635) (xy 345.199188 -282.084491) (xy 345.247791 -282.100021)
			(xy 345.293419 -282.122855) (xy 345.334985 -282.152446) (xy 345.371495 -282.188089) (xy 345.387168 -282.208224)
			(xy 345.799156 -282.208224) (xy 345.814861 -282.188115) (xy 345.851364 -282.152468) (xy 345.892922 -282.122871)
			(xy 345.938545 -282.10003) (xy 345.987141 -282.084491) (xy 346.037552 -282.076624) (xy 346.063062 -282.076144)
			(xy 346.088976 -282.076551) (xy 346.140167 -282.084653) (xy 346.18946 -282.100664) (xy 346.235642 -282.12419)
			(xy 346.277574 -282.154651) (xy 346.314224 -282.191297) (xy 346.34469 -282.233226) (xy 346.368221 -282.279404)
			(xy 346.384238 -282.328696) (xy 346.392346 -282.379886) (xy 346.392346 -282.431714) (xy 346.384238 -282.482904)
			(xy 346.368221 -282.532196) (xy 346.34469 -282.578374) (xy 346.314224 -282.620303) (xy 346.277574 -282.656949)
			(xy 346.235642 -282.68741) (xy 346.18946 -282.710936) (xy 346.140167 -282.726947) (xy 346.088976 -282.735049)
			(xy 346.063062 -282.735528) (xy 346.03755 -282.735064) (xy 345.987135 -282.727199) (xy 345.938534 -282.711661)
			(xy 345.892906 -282.688822) (xy 345.85134 -282.659228) (xy 345.81483 -282.623584) (xy 345.799156 -282.603448)
			(xy 345.387168 -282.603448) (xy 345.371526 -282.623609) (xy 345.335009 -282.659249) (xy 345.293436 -282.688839)
			(xy 345.247802 -282.71167) (xy 345.199195 -282.727199) (xy 345.148776 -282.735054) (xy 345.123262 -282.735528)
			(xy 345.097359 -282.734945) (xy 345.046193 -282.726835) (xy 344.996925 -282.710822) (xy 344.950768 -282.687299)
			(xy 344.908859 -282.656846) (xy 344.872229 -282.620212) (xy 344.841781 -282.5783) (xy 344.818263 -282.53214)
			(xy 344.802256 -282.48287) (xy 344.794152 -282.431703) (xy 344.512364 -282.431703) (xy 344.512318 -282.43386)
			(xy 344.503126 -282.488122) (xy 344.494612 -282.514294) (xy 344.486992 -282.536392) (xy 344.692224 -282.891738)
			(xy 344.715084 -282.896056) (xy 344.739902 -282.901236) (xy 344.787678 -282.918192) (xy 344.832294 -282.942264)
			(xy 344.872699 -282.972884) (xy 344.907939 -283.009329) (xy 344.937183 -283.05074) (xy 344.959741 -283.09614)
			(xy 344.975082 -283.14446) (xy 344.982843 -283.194558) (xy 344.983308 -283.219906) (xy 347.143324 -283.219906)
			(xy 347.143831 -283.194562) (xy 347.151603 -283.144472) (xy 347.166948 -283.096161) (xy 347.189506 -283.050768)
			(xy 347.218745 -283.009362) (xy 347.253975 -282.972918) (xy 347.294368 -282.942295) (xy 347.338972 -282.918214)
			(xy 347.386736 -282.901243) (xy 347.411548 -282.896056) (xy 347.434408 -282.891738) (xy 347.639386 -282.5369)
			(xy 347.631766 -282.514802) (xy 347.623129 -282.488391) (xy 347.613803 -282.433617) (xy 347.613224 -282.405836)
			(xy 347.613732 -282.379949) (xy 347.621831 -282.328811) (xy 347.63783 -282.279571) (xy 347.661336 -282.233439)
			(xy 347.691768 -282.191552) (xy 347.728378 -282.154942) (xy 347.770265 -282.12451) (xy 347.816397 -282.101004)
			(xy 347.865637 -282.085005) (xy 347.916775 -282.076906) (xy 347.968549 -282.076906) (xy 348.019687 -282.085005)
			(xy 348.068927 -282.101004) (xy 348.115059 -282.12451) (xy 348.156946 -282.154942) (xy 348.193556 -282.191552)
			(xy 348.223988 -282.233439) (xy 348.247494 -282.279571) (xy 348.263493 -282.328811) (xy 348.271592 -282.379949)
			(xy 348.2721 -282.405836) (xy 349.492824 -282.405836) (xy 349.493229 -282.380499) (xy 349.500992 -282.330422)
			(xy 349.516324 -282.282122) (xy 349.538866 -282.236737) (xy 349.568085 -282.195335) (xy 349.603295 -282.15889)
			(xy 349.643666 -282.128262) (xy 349.688248 -282.10417) (xy 349.735991 -282.087183) (xy 349.760794 -282.081986)
			(xy 349.783654 -282.077668) (xy 349.988886 -281.722322) (xy 349.981266 -281.700478) (xy 349.97264 -281.674196)
			(xy 349.963326 -281.619675) (xy 349.962724 -281.59202) (xy 349.963232 -281.566113) (xy 349.971338 -281.514936)
			(xy 349.98735 -281.465657) (xy 350.010873 -281.41949) (xy 350.041329 -281.377571) (xy 350.077967 -281.340933)
			(xy 350.119886 -281.310477) (xy 350.166053 -281.286954) (xy 350.215332 -281.270942) (xy 350.266509 -281.262836)
			(xy 350.318323 -281.262836) (xy 350.3695 -281.270942) (xy 350.418779 -281.286954) (xy 350.464946 -281.310477)
			(xy 350.506865 -281.340933) (xy 350.543503 -281.377571) (xy 350.573959 -281.41949) (xy 350.597482 -281.465657)
			(xy 350.613494 -281.514936) (xy 350.6216 -281.566113) (xy 350.622108 -281.59202) (xy 350.621645 -281.617395)
			(xy 350.613874 -281.667545) (xy 350.598503 -281.71591) (xy 350.575897 -281.761346) (xy 350.546589 -281.802777)
			(xy 350.511274 -281.839223) (xy 350.470788 -281.869822) (xy 350.426087 -281.893849) (xy 350.37823 -281.910736)
			(xy 350.353376 -281.91587) (xy 350.330516 -281.920188) (xy 350.125538 -282.275026) (xy 350.133412 -282.297124)
			(xy 350.141978 -282.32348) (xy 350.151173 -282.378127) (xy 350.1517 -282.405836) (xy 350.151192 -282.431703)
			(xy 351.372752 -282.431703) (xy 351.372752 -282.379897) (xy 351.380856 -282.32873) (xy 351.396863 -282.27946)
			(xy 351.420381 -282.2333) (xy 351.450829 -282.191388) (xy 351.487459 -282.154754) (xy 351.529368 -282.124301)
			(xy 351.575525 -282.100778) (xy 351.624793 -282.084765) (xy 351.675959 -282.076655) (xy 351.701862 -282.076144)
			(xy 351.727374 -282.076635) (xy 351.777788 -282.084491) (xy 351.826391 -282.100021) (xy 351.872019 -282.122855)
			(xy 351.913585 -282.152446) (xy 351.950095 -282.188089) (xy 351.965768 -282.208224) (xy 352.377756 -282.208224)
			(xy 352.393461 -282.188115) (xy 352.429964 -282.152468) (xy 352.471522 -282.122871) (xy 352.517145 -282.10003)
			(xy 352.565741 -282.084491) (xy 352.616152 -282.076624) (xy 352.641662 -282.076144) (xy 352.667576 -282.076551)
			(xy 352.718767 -282.084653) (xy 352.76806 -282.100664) (xy 352.814242 -282.12419) (xy 352.856174 -282.154651)
			(xy 352.892824 -282.191297) (xy 352.92329 -282.233226) (xy 352.946821 -282.279404) (xy 352.962838 -282.328696)
			(xy 352.970946 -282.379886) (xy 352.970946 -282.431714) (xy 352.962838 -282.482904) (xy 352.946821 -282.532196)
			(xy 352.92329 -282.578374) (xy 352.892824 -282.620303) (xy 352.856174 -282.656949) (xy 352.814242 -282.68741)
			(xy 352.76806 -282.710936) (xy 352.718767 -282.726947) (xy 352.667576 -282.735049) (xy 352.641662 -282.735528)
			(xy 352.61615 -282.735064) (xy 352.565735 -282.727199) (xy 352.517134 -282.711661) (xy 352.471506 -282.688822)
			(xy 352.42994 -282.659228) (xy 352.39343 -282.623584) (xy 352.377756 -282.603448) (xy 351.965768 -282.603448)
			(xy 351.950126 -282.623609) (xy 351.913609 -282.659249) (xy 351.872036 -282.688839) (xy 351.826402 -282.71167)
			(xy 351.777795 -282.727199) (xy 351.727376 -282.735054) (xy 351.701862 -282.735528) (xy 351.675959 -282.734945)
			(xy 351.624793 -282.726835) (xy 351.575525 -282.710822) (xy 351.529368 -282.687299) (xy 351.487459 -282.656846)
			(xy 351.450829 -282.620212) (xy 351.420381 -282.5783) (xy 351.396863 -282.53214) (xy 351.380856 -282.48287)
			(xy 351.372752 -282.431703) (xy 350.151192 -282.431703) (xy 350.151192 -282.431723) (xy 350.143093 -282.482861)
			(xy 350.127094 -282.532101) (xy 350.103588 -282.578233) (xy 350.073156 -282.62012) (xy 350.036546 -282.65673)
			(xy 349.994659 -282.687162) (xy 349.948527 -282.710668) (xy 349.899287 -282.726667) (xy 349.848149 -282.734766)
			(xy 349.796375 -282.734766) (xy 349.745237 -282.726667) (xy 349.695997 -282.710668) (xy 349.649865 -282.687162)
			(xy 349.607978 -282.65673) (xy 349.571368 -282.62012) (xy 349.540936 -282.578233) (xy 349.51743 -282.532101)
			(xy 349.501431 -282.482861) (xy 349.493332 -282.431723) (xy 349.492824 -282.405836) (xy 348.2721 -282.405836)
			(xy 348.271608 -282.431158) (xy 348.263872 -282.481209) (xy 348.248573 -282.529487) (xy 348.22607 -282.574858)
			(xy 348.196893 -282.616254) (xy 348.161729 -282.6527) (xy 348.121404 -282.68334) (xy 348.076868 -282.707453)
			(xy 348.029168 -282.72447) (xy 348.004384 -282.729686) (xy 347.981524 -282.734004) (xy 347.776292 -283.089096)
			(xy 347.784166 -283.111194) (xy 347.792802 -283.137539) (xy 347.80212 -283.192188) (xy 347.802708 -283.219906)
			(xy 347.8022 -283.24579) (xy 349.023649 -283.24579) (xy 349.023649 -283.19401) (xy 349.03175 -283.142868)
			(xy 349.047751 -283.093623) (xy 349.071259 -283.047487) (xy 349.101695 -283.005597) (xy 349.13831 -282.968985)
			(xy 349.180201 -282.938551) (xy 349.226338 -282.915045) (xy 349.275584 -282.899046) (xy 349.326726 -282.890948)
			(xy 349.352616 -282.890468) (xy 349.378128 -282.890949) (xy 349.428541 -282.898811) (xy 349.477143 -282.914346)
			(xy 349.522771 -282.937181) (xy 349.564336 -282.966773) (xy 349.600848 -283.002414) (xy 349.616522 -283.022548)
			(xy 350.02851 -283.022548) (xy 350.044163 -283.002397) (xy 350.080679 -282.966756) (xy 350.122249 -282.937166)
			(xy 350.167881 -282.914333) (xy 350.216486 -282.898802) (xy 350.266903 -282.890944) (xy 350.292416 -282.890468)
			(xy 350.318303 -282.890965) (xy 350.369439 -282.899066) (xy 350.418679 -282.915067) (xy 350.464809 -282.938574)
			(xy 350.506694 -282.969007) (xy 350.543303 -283.005618) (xy 350.573735 -283.047505) (xy 350.597239 -283.093636)
			(xy 350.613237 -283.142876) (xy 350.621336 -283.194013) (xy 350.621336 -283.219906) (xy 352.782124 -283.219906)
			(xy 352.782631 -283.194562) (xy 352.790403 -283.144472) (xy 352.805748 -283.096161) (xy 352.828306 -283.050768)
			(xy 352.857545 -283.009362) (xy 352.892775 -282.972918) (xy 352.933168 -282.942295) (xy 352.977772 -282.918214)
			(xy 353.025536 -282.901243) (xy 353.050348 -282.896056) (xy 353.073208 -282.891738) (xy 353.278186 -282.5369)
			(xy 353.270566 -282.514802) (xy 353.261929 -282.488391) (xy 353.252603 -282.433617) (xy 353.252024 -282.405836)
			(xy 353.252532 -282.379949) (xy 353.260631 -282.328811) (xy 353.27663 -282.279571) (xy 353.300136 -282.233439)
			(xy 353.330568 -282.191552) (xy 353.367178 -282.154942) (xy 353.409065 -282.12451) (xy 353.455197 -282.101004)
			(xy 353.504437 -282.085005) (xy 353.555575 -282.076906) (xy 353.607349 -282.076906) (xy 353.658487 -282.085005)
			(xy 353.707727 -282.101004) (xy 353.753859 -282.12451) (xy 353.795746 -282.154942) (xy 353.832356 -282.191552)
			(xy 353.862788 -282.233439) (xy 353.886294 -282.279571) (xy 353.902293 -282.328811) (xy 353.910392 -282.379949)
			(xy 353.9109 -282.405836) (xy 353.910408 -282.431158) (xy 353.902672 -282.481209) (xy 353.887373 -282.529487)
			(xy 353.86487 -282.574858) (xy 353.835693 -282.616254) (xy 353.800529 -282.6527) (xy 353.760204 -282.68334)
			(xy 353.715668 -282.707453) (xy 353.667968 -282.72447) (xy 353.643184 -282.729686) (xy 353.620324 -282.734004)
			(xy 353.415092 -283.089096) (xy 353.422966 -283.111194) (xy 353.431602 -283.137539) (xy 353.44092 -283.192188)
			(xy 353.441508 -283.219906) (xy 353.441 -283.245813) (xy 353.432894 -283.29699) (xy 353.416882 -283.346269)
			(xy 353.393359 -283.392436) (xy 353.362903 -283.434355) (xy 353.326265 -283.470993) (xy 353.284346 -283.501449)
			(xy 353.238179 -283.524972) (xy 353.1889 -283.540984) (xy 353.137723 -283.54909) (xy 353.085909 -283.54909)
			(xy 353.034732 -283.540984) (xy 352.985453 -283.524972) (xy 352.939286 -283.501449) (xy 352.897367 -283.470993)
			(xy 352.860729 -283.434355) (xy 352.830273 -283.392436) (xy 352.80675 -283.346269) (xy 352.790738 -283.29699)
			(xy 352.782632 -283.245813) (xy 352.782124 -283.219906) (xy 350.621336 -283.219906) (xy 350.621336 -283.245787)
			(xy 350.613237 -283.296924) (xy 350.597239 -283.346164) (xy 350.573735 -283.392295) (xy 350.543303 -283.434182)
			(xy 350.506694 -283.470793) (xy 350.464809 -283.501226) (xy 350.418679 -283.524733) (xy 350.369439 -283.540734)
			(xy 350.318303 -283.548835) (xy 350.292416 -283.549344) (xy 350.266904 -283.548874) (xy 350.216488 -283.541014)
			(xy 350.167885 -283.52548) (xy 350.122256 -283.502643) (xy 350.080691 -283.473047) (xy 350.044182 -283.437401)
			(xy 350.02851 -283.417264) (xy 349.616522 -283.417264) (xy 349.600826 -283.437381) (xy 349.564322 -283.473028)
			(xy 349.522762 -283.502625) (xy 349.477138 -283.525464) (xy 349.428539 -283.541001) (xy 349.378127 -283.548865)
			(xy 349.352616 -283.549344) (xy 349.326726 -283.548852) (xy 349.275584 -283.540754) (xy 349.226338 -283.524755)
			(xy 349.180201 -283.501249) (xy 349.13831 -283.470815) (xy 349.101695 -283.434203) (xy 349.071259 -283.392313)
			(xy 349.047751 -283.346177) (xy 349.03175 -283.296932) (xy 349.023649 -283.24579) (xy 347.8022 -283.24579)
			(xy 347.8022 -283.245813) (xy 347.794094 -283.29699) (xy 347.778082 -283.346269) (xy 347.754559 -283.392436)
			(xy 347.724103 -283.434355) (xy 347.687465 -283.470993) (xy 347.645546 -283.501449) (xy 347.599379 -283.524972)
			(xy 347.5501 -283.540984) (xy 347.498923 -283.54909) (xy 347.447109 -283.54909) (xy 347.395932 -283.540984)
			(xy 347.346653 -283.524972) (xy 347.300486 -283.501449) (xy 347.258567 -283.470993) (xy 347.221929 -283.434355)
			(xy 347.191473 -283.392436) (xy 347.16795 -283.346269) (xy 347.151938 -283.29699) (xy 347.143832 -283.245813)
			(xy 347.143324 -283.219906) (xy 344.983308 -283.219906) (xy 344.9828 -283.245813) (xy 344.974694 -283.29699)
			(xy 344.958682 -283.346269) (xy 344.935159 -283.392436) (xy 344.904703 -283.434355) (xy 344.868065 -283.470993)
			(xy 344.826146 -283.501449) (xy 344.779979 -283.524972) (xy 344.7307 -283.540984) (xy 344.679523 -283.54909)
			(xy 344.627709 -283.54909) (xy 344.576532 -283.540984) (xy 344.527253 -283.524972) (xy 344.481086 -283.501449)
			(xy 344.439167 -283.470993) (xy 344.402529 -283.434355) (xy 344.372073 -283.392436) (xy 344.34855 -283.346269)
			(xy 344.332538 -283.29699) (xy 344.324432 -283.245813) (xy 344.323924 -283.219906) (xy 344.324518 -283.192189)
			(xy 344.333841 -283.137542) (xy 344.342466 -283.111194) (xy 344.35034 -283.089096) (xy 344.145362 -282.734004)
			(xy 344.122248 -282.729686) (xy 344.097423 -282.724538) (xy 344.049642 -282.707582) (xy 344.005022 -282.683508)
			(xy 343.964615 -282.652886) (xy 343.929374 -282.616436) (xy 343.900131 -282.57502) (xy 343.877575 -282.529614)
			(xy 343.862239 -282.481289) (xy 343.854484 -282.431186) (xy 343.854024 -282.405836) (xy 343.5731 -282.405836)
			(xy 343.572592 -282.431723) (xy 343.564493 -282.482861) (xy 343.548494 -282.532101) (xy 343.524988 -282.578233)
			(xy 343.494556 -282.62012) (xy 343.457946 -282.65673) (xy 343.416059 -282.687162) (xy 343.369927 -282.710668)
			(xy 343.320687 -282.726667) (xy 343.269549 -282.734766) (xy 343.217775 -282.734766) (xy 343.166637 -282.726667)
			(xy 343.117397 -282.710668) (xy 343.071265 -282.687162) (xy 343.029378 -282.65673) (xy 342.992768 -282.62012)
			(xy 342.962336 -282.578233) (xy 342.93883 -282.532101) (xy 342.922831 -282.482861) (xy 342.914732 -282.431723)
			(xy 342.914224 -282.405836) (xy 341.694008 -282.405836) (xy 341.6935 -282.431743) (xy 341.685394 -282.48292)
			(xy 341.669382 -282.532199) (xy 341.645859 -282.578366) (xy 341.615403 -282.620285) (xy 341.578765 -282.656923)
			(xy 341.536846 -282.687379) (xy 341.490679 -282.710902) (xy 341.4414 -282.726914) (xy 341.390223 -282.73502)
			(xy 341.338409 -282.73502) (xy 341.287232 -282.726914) (xy 341.237953 -282.710902) (xy 341.191786 -282.687379)
			(xy 341.149867 -282.656923) (xy 341.113229 -282.620285) (xy 341.082773 -282.578366) (xy 341.05925 -282.532199)
			(xy 341.043238 -282.48292) (xy 341.035132 -282.431743) (xy 341.034624 -282.405836) (xy 336.0547 -282.405836)
			(xy 336.054179 -282.433545) (xy 336.044978 -282.488191) (xy 336.036412 -282.514548) (xy 336.028538 -282.536646)
			(xy 336.23377 -282.891738) (xy 336.25663 -282.896056) (xy 336.281436 -282.901231) (xy 336.329174 -282.918223)
			(xy 336.373751 -282.94232) (xy 336.414116 -282.972953) (xy 336.449318 -283.009401) (xy 336.478529 -283.050806)
			(xy 336.501062 -283.096194) (xy 336.516384 -283.144494) (xy 336.524137 -283.19457) (xy 336.5246 -283.219906)
			(xy 336.524092 -283.245785) (xy 340.565275 -283.245785) (xy 340.565275 -283.194015) (xy 340.573373 -283.142882)
			(xy 340.58937 -283.093646) (xy 340.612872 -283.047517) (xy 340.643299 -283.005633) (xy 340.679904 -282.969024)
			(xy 340.721785 -282.938592) (xy 340.76791 -282.915085) (xy 340.817145 -282.899082) (xy 340.868277 -282.890978)
			(xy 340.894162 -282.890468) (xy 340.919672 -282.890989) (xy 340.970084 -282.898843) (xy 341.018684 -282.914369)
			(xy 341.064312 -282.937197) (xy 341.105879 -282.966782) (xy 341.142392 -283.002417) (xy 341.158068 -283.022548)
			(xy 341.570056 -283.022548) (xy 341.585741 -283.002422) (xy 341.62225 -282.96678) (xy 341.663813 -282.937187)
			(xy 341.709439 -282.91435) (xy 341.758039 -282.898813) (xy 341.808451 -282.890948) (xy 341.833962 -282.890468)
			(xy 341.859854 -282.890934) (xy 341.911001 -282.89903) (xy 341.960252 -282.915027) (xy 342.006393 -282.938533)
			(xy 342.048289 -282.968968) (xy 342.084908 -283.005582) (xy 342.115347 -283.047475) (xy 342.138858 -283.093613)
			(xy 342.154861 -283.142862) (xy 342.162963 -283.194008) (xy 342.162963 -283.245792) (xy 342.154861 -283.296938)
			(xy 342.138858 -283.346187) (xy 342.115347 -283.392325) (xy 342.084908 -283.434218) (xy 342.048289 -283.470832)
			(xy 342.006393 -283.501267) (xy 341.960252 -283.524773) (xy 341.911001 -283.54077) (xy 341.859854 -283.548866)
			(xy 341.833962 -283.549344) (xy 341.808448 -283.548913) (xy 341.75803 -283.541045) (xy 341.709427 -283.525503)
			(xy 341.663798 -283.502658) (xy 341.622234 -283.473056) (xy 341.585727 -283.437404) (xy 341.570056 -283.417264)
			(xy 341.158068 -283.417264) (xy 341.142404 -283.437407) (xy 341.105893 -283.473052) (xy 341.064326 -283.502646)
			(xy 341.018696 -283.525481) (xy 340.970092 -283.541013) (xy 340.919675 -283.548869) (xy 340.894162 -283.549344)
			(xy 340.868277 -283.548822) (xy 340.817145 -283.540718) (xy 340.76791 -283.524715) (xy 340.721785 -283.501208)
			(xy 340.679904 -283.470776) (xy 340.643299 -283.434167) (xy 340.612872 -283.392283) (xy 340.58937 -283.346154)
			(xy 340.573373 -283.296918) (xy 340.565275 -283.245785) (xy 336.524092 -283.245785) (xy 336.524092 -283.245793)
			(xy 336.515993 -283.296931) (xy 336.499994 -283.346171) (xy 336.476488 -283.392303) (xy 336.446056 -283.43419)
			(xy 336.409446 -283.4708) (xy 336.367559 -283.501232) (xy 336.321427 -283.524738) (xy 336.272187 -283.540737)
			(xy 336.221049 -283.548836) (xy 336.169275 -283.548836) (xy 336.118137 -283.540737) (xy 336.068897 -283.524738)
			(xy 336.022765 -283.501232) (xy 335.980878 -283.4708) (xy 335.944268 -283.43419) (xy 335.913836 -283.392303)
			(xy 335.89033 -283.346171) (xy 335.874331 -283.296931) (xy 335.866232 -283.245793) (xy 335.865724 -283.219906)
			(xy 335.866254 -283.192198) (xy 335.875449 -283.137551) (xy 335.884012 -283.111194) (xy 335.891886 -283.089096)
			(xy 335.686654 -282.734004) (xy 335.663794 -282.729686) (xy 335.639001 -282.724454) (xy 335.591266 -282.707468)
			(xy 335.546691 -282.683379) (xy 335.506327 -282.652753) (xy 335.471124 -282.616312) (xy 335.441911 -282.574914)
			(xy 335.419375 -282.529534) (xy 335.404048 -282.48124) (xy 335.396291 -282.43117) (xy 335.395824 -282.405836)
			(xy 106.910632 -282.405836) (xy 106.910124 -282.431723) (xy 106.902025 -282.482861) (xy 106.886026 -282.532101)
			(xy 106.86252 -282.578233) (xy 106.832088 -282.62012) (xy 106.795478 -282.65673) (xy 106.753591 -282.687162)
			(xy 106.707459 -282.710668) (xy 106.658219 -282.726667) (xy 106.607081 -282.734766) (xy 106.555307 -282.734766)
			(xy 106.504169 -282.726667) (xy 106.454929 -282.710668) (xy 106.408797 -282.687162) (xy 106.36691 -282.65673)
			(xy 106.3303 -282.62012) (xy 106.299868 -282.578233) (xy 106.276362 -282.532101) (xy 106.260363 -282.482861)
			(xy 106.252264 -282.431723) (xy 106.251756 -282.405836) (xy 106.252296 -282.378128) (xy 106.261484 -282.323482)
			(xy 106.270044 -282.297124) (xy 106.277918 -282.275026) (xy 106.07294 -281.920188) (xy 106.05008 -281.91587)
			(xy 106.025256 -281.910713) (xy 105.977474 -281.893761) (xy 105.932853 -281.86969) (xy 105.892445 -281.839069)
			(xy 105.857203 -281.802621) (xy 105.827959 -281.761205) (xy 105.805403 -281.715799) (xy 105.790068 -281.667474)
			(xy 105.782315 -281.61737) (xy 105.781856 -281.59202) (xy 104.56164 -281.59202) (xy 104.561132 -281.617927)
			(xy 104.553026 -281.669104) (xy 104.537014 -281.718383) (xy 104.513491 -281.76455) (xy 104.483035 -281.806469)
			(xy 104.446397 -281.843107) (xy 104.404478 -281.873563) (xy 104.358311 -281.897086) (xy 104.309032 -281.913098)
			(xy 104.257855 -281.921204) (xy 104.206041 -281.921204) (xy 104.154864 -281.913098) (xy 104.105585 -281.897086)
			(xy 104.059418 -281.873563) (xy 104.017499 -281.843107) (xy 103.980861 -281.806469) (xy 103.950405 -281.76455)
			(xy 103.926882 -281.718383) (xy 103.91087 -281.669104) (xy 103.902764 -281.617927) (xy 103.902256 -281.59202)
			(xy 103.902852 -281.564303) (xy 103.912174 -281.509656) (xy 103.920798 -281.483308) (xy 103.928672 -281.46121)
			(xy 103.723694 -281.106372) (xy 103.700834 -281.102054) (xy 103.676009 -281.096858) (xy 103.628203 -281.079927)
			(xy 103.583555 -281.055874) (xy 103.543117 -281.025267) (xy 103.507844 -280.988827) (xy 103.478568 -280.947415)
			(xy 103.45598 -280.902007) (xy 103.440613 -280.853676) (xy 103.43283 -280.803562) (xy 103.432356 -280.778204)
			(xy 101.271832 -280.778204) (xy 101.271832 -280.778712) (xy 101.271241 -280.806228) (xy 101.262055 -280.860489)
			(xy 101.253544 -280.886662) (xy 101.245924 -280.908506) (xy 101.451156 -281.263852) (xy 101.474016 -281.26817)
			(xy 101.498826 -281.273386) (xy 101.546603 -281.290334) (xy 101.591222 -281.314398) (xy 101.631628 -281.345012)
			(xy 101.66687 -281.381453) (xy 101.696116 -281.422861) (xy 101.718675 -281.468259) (xy 101.734016 -281.516576)
			(xy 101.741776 -281.566673) (xy 101.74224 -281.59202) (xy 101.741732 -281.617927) (xy 101.733626 -281.669104)
			(xy 101.717614 -281.718383) (xy 101.694091 -281.76455) (xy 101.663635 -281.806469) (xy 101.626997 -281.843107)
			(xy 101.585078 -281.873563) (xy 101.538911 -281.897086) (xy 101.489632 -281.913098) (xy 101.438455 -281.921204)
			(xy 101.386641 -281.921204) (xy 101.335464 -281.913098) (xy 101.286185 -281.897086) (xy 101.240018 -281.873563)
			(xy 101.198099 -281.843107) (xy 101.161461 -281.806469) (xy 101.131005 -281.76455) (xy 101.107482 -281.718383)
			(xy 101.09147 -281.669104) (xy 101.083364 -281.617927) (xy 101.082856 -281.59202) (xy 101.083452 -281.564303)
			(xy 101.092774 -281.509656) (xy 101.101398 -281.483308) (xy 101.109272 -281.46121) (xy 100.904294 -281.106372)
			(xy 100.881434 -281.102054) (xy 100.856609 -281.096858) (xy 100.808803 -281.079927) (xy 100.764155 -281.055874)
			(xy 100.723717 -281.025267) (xy 100.688444 -280.988827) (xy 100.659168 -280.947415) (xy 100.63658 -280.902007)
			(xy 100.621213 -280.853676) (xy 100.61343 -280.803562) (xy 100.612956 -280.778204) (xy 98.452432 -280.778204)
			(xy 98.451927 -280.803537) (xy 98.444175 -280.853607) (xy 98.428854 -280.901902) (xy 98.406324 -280.947284)
			(xy 98.377117 -280.988685) (xy 98.34192 -281.025131) (xy 98.301561 -281.055762) (xy 98.256992 -281.079859)
			(xy 98.20926 -281.096853) (xy 98.184462 -281.102054) (xy 98.161602 -281.106372) (xy 97.956624 -281.46121)
			(xy 97.964498 -281.483308) (xy 97.973138 -281.509652) (xy 97.982453 -281.564301) (xy 97.98304 -281.59202)
			(xy 97.982532 -281.61791) (xy 99.20371 -281.61791) (xy 99.20371 -281.56609) (xy 99.211817 -281.514907)
			(xy 99.227832 -281.465624) (xy 99.25136 -281.419452) (xy 99.281822 -281.37753) (xy 99.318467 -281.34089)
			(xy 99.360393 -281.310435) (xy 99.406568 -281.286913) (xy 99.455854 -281.270906) (xy 99.507038 -281.262806)
			(xy 99.532948 -281.262328) (xy 99.558462 -281.262762) (xy 99.608879 -281.270631) (xy 99.657482 -281.286173)
			(xy 99.70311 -281.309017) (xy 99.744675 -281.338618) (xy 99.781182 -281.374269) (xy 99.796854 -281.394408)
			(xy 100.208842 -281.394408) (xy 100.224493 -281.374254) (xy 100.261007 -281.338611) (xy 100.302577 -281.309019)
			(xy 100.34821 -281.286186) (xy 100.396816 -281.270657) (xy 100.447235 -281.262802) (xy 100.472748 -281.262328)
			(xy 100.498654 -281.2628) (xy 100.549829 -281.270912) (xy 100.599104 -281.286928) (xy 100.645267 -281.310456)
			(xy 100.687182 -281.340914) (xy 100.723817 -281.377554) (xy 100.754269 -281.419474) (xy 100.77779 -281.465641)
			(xy 100.7938 -281.514918) (xy 100.801904 -281.566093) (xy 100.801904 -281.617907) (xy 100.7938 -281.669082)
			(xy 100.77779 -281.718359) (xy 100.754269 -281.764526) (xy 100.723817 -281.806446) (xy 100.687182 -281.843086)
			(xy 100.645267 -281.873544) (xy 100.599104 -281.897072) (xy 100.549829 -281.913088) (xy 100.498654 -281.9212)
			(xy 100.472748 -281.921712) (xy 100.447238 -281.921192) (xy 100.396825 -281.913339) (xy 100.348225 -281.897813)
			(xy 100.302596 -281.874985) (xy 100.26103 -281.8454) (xy 100.224517 -281.809764) (xy 100.208842 -281.789632)
			(xy 99.796854 -281.789632) (xy 99.781158 -281.809749) (xy 99.744652 -281.845392) (xy 99.703091 -281.874987)
			(xy 99.657467 -281.897826) (xy 99.60887 -281.913365) (xy 99.558459 -281.921231) (xy 99.532948 -281.921712)
			(xy 99.507038 -281.921194) (xy 99.455854 -281.913094) (xy 99.406568 -281.897087) (xy 99.360393 -281.873565)
			(xy 99.318467 -281.84311) (xy 99.281822 -281.80647) (xy 99.25136 -281.764548) (xy 99.227832 -281.718376)
			(xy 99.211817 -281.669093) (xy 99.20371 -281.61791) (xy 97.982532 -281.61791) (xy 97.982532 -281.617927)
			(xy 97.974426 -281.669104) (xy 97.958414 -281.718383) (xy 97.934891 -281.76455) (xy 97.904435 -281.806469)
			(xy 97.867797 -281.843107) (xy 97.825878 -281.873563) (xy 97.779711 -281.897086) (xy 97.730432 -281.913098)
			(xy 97.679255 -281.921204) (xy 97.627441 -281.921204) (xy 97.576264 -281.913098) (xy 97.526985 -281.897086)
			(xy 97.480818 -281.873563) (xy 97.438899 -281.843107) (xy 97.402261 -281.806469) (xy 97.371805 -281.76455)
			(xy 97.348282 -281.718383) (xy 97.33227 -281.669104) (xy 97.324164 -281.617927) (xy 97.323656 -281.59202)
			(xy 96.10344 -281.59202) (xy 96.103032 -281.617397) (xy 96.095259 -281.667553) (xy 96.079885 -281.715923)
			(xy 96.057273 -281.761362) (xy 96.027958 -281.802795) (xy 95.992635 -281.839241) (xy 95.95214 -281.869837)
			(xy 95.907431 -281.89386) (xy 95.859566 -281.910741) (xy 95.834708 -281.91587) (xy 95.811848 -281.920188)
			(xy 95.60687 -282.275026) (xy 95.614744 -282.297124) (xy 95.623311 -282.32348) (xy 95.632506 -282.378127)
			(xy 95.633032 -282.405836) (xy 95.913956 -282.405836) (xy 95.914464 -282.379949) (xy 95.922563 -282.328811)
			(xy 95.938562 -282.279571) (xy 95.962068 -282.233439) (xy 95.9925 -282.191552) (xy 96.02911 -282.154942)
			(xy 96.070997 -282.12451) (xy 96.117129 -282.101004) (xy 96.166369 -282.085005) (xy 96.217507 -282.076906)
			(xy 96.269281 -282.076906) (xy 96.320419 -282.085005) (xy 96.369659 -282.101004) (xy 96.415791 -282.12451)
			(xy 96.457678 -282.154942) (xy 96.494288 -282.191552) (xy 96.52472 -282.233439) (xy 96.548226 -282.279571)
			(xy 96.564225 -282.328811) (xy 96.572324 -282.379949) (xy 96.572832 -282.405836) (xy 96.572832 -282.406344)
			(xy 96.572295 -282.431704) (xy 96.854052 -282.431704) (xy 96.854052 -282.379896) (xy 96.862157 -282.328725)
			(xy 96.878166 -282.279453) (xy 96.901687 -282.233291) (xy 96.932138 -282.191377) (xy 96.968772 -282.154742)
			(xy 97.010686 -282.12429) (xy 97.056847 -282.100769) (xy 97.106119 -282.084758) (xy 97.15729 -282.076653)
			(xy 97.183194 -282.076144) (xy 97.208707 -282.076611) (xy 97.259122 -282.084472) (xy 97.307725 -282.100007)
			(xy 97.353354 -282.122845) (xy 97.394919 -282.152441) (xy 97.431427 -282.188087) (xy 97.4471 -282.208224)
			(xy 97.859088 -282.208224) (xy 97.874775 -282.188099) (xy 97.911281 -282.152454) (xy 97.952843 -282.122858)
			(xy 97.998469 -282.10002) (xy 98.047069 -282.084484) (xy 98.097483 -282.076622) (xy 98.122994 -282.076144)
			(xy 98.148907 -282.076553) (xy 98.200094 -282.08466) (xy 98.249383 -282.100674) (xy 98.295559 -282.124201)
			(xy 98.337487 -282.154663) (xy 98.374133 -282.191308) (xy 98.404596 -282.233235) (xy 98.428124 -282.279412)
			(xy 98.444139 -282.3287) (xy 98.452246 -282.379887) (xy 98.452246 -282.431713) (xy 98.444139 -282.4829)
			(xy 98.428124 -282.532188) (xy 98.404596 -282.578365) (xy 98.374133 -282.620292) (xy 98.337487 -282.656937)
			(xy 98.295559 -282.687399) (xy 98.249383 -282.710926) (xy 98.200094 -282.72694) (xy 98.148907 -282.735047)
			(xy 98.122994 -282.735528) (xy 98.097483 -282.735041) (xy 98.047069 -282.72718) (xy 97.998468 -282.711647)
			(xy 97.95284 -282.688813) (xy 97.911274 -282.659222) (xy 97.874762 -282.623582) (xy 97.859088 -282.603448)
			(xy 97.4471 -282.603448) (xy 97.43144 -282.623594) (xy 97.394926 -282.659235) (xy 97.353357 -282.688826)
			(xy 97.307726 -282.71166) (xy 97.259123 -282.727192) (xy 97.208707 -282.735052) (xy 97.183194 -282.735528)
			(xy 97.15729 -282.734947) (xy 97.106119 -282.726842) (xy 97.056847 -282.710831) (xy 97.010686 -282.68731)
			(xy 96.968772 -282.656858) (xy 96.932138 -282.620223) (xy 96.901687 -282.578309) (xy 96.878166 -282.532147)
			(xy 96.862157 -282.482875) (xy 96.854052 -282.431704) (xy 96.572295 -282.431704) (xy 96.572249 -282.43386)
			(xy 96.563058 -282.488121) (xy 96.554544 -282.514294) (xy 96.546924 -282.536392) (xy 96.752156 -282.891738)
			(xy 96.775016 -282.896056) (xy 96.799823 -282.901285) (xy 96.847599 -282.918232) (xy 96.892217 -282.942295)
			(xy 96.932623 -282.972907) (xy 96.967865 -283.009346) (xy 96.997111 -283.050752) (xy 97.019671 -283.096149)
			(xy 97.035013 -283.144464) (xy 97.042775 -283.194559) (xy 97.04324 -283.219906) (xy 99.203256 -283.219906)
			(xy 99.203737 -283.19456) (xy 99.21151 -283.144468) (xy 99.226857 -283.096156) (xy 99.249417 -283.050761)
			(xy 99.278659 -283.009354) (xy 99.313894 -282.97291) (xy 99.354291 -282.942288) (xy 99.398899 -282.918209)
			(xy 99.446666 -282.901241) (xy 99.47148 -282.896056) (xy 99.49434 -282.891738) (xy 99.699318 -282.5369)
			(xy 99.691698 -282.514802) (xy 99.683062 -282.488391) (xy 99.673735 -282.433617) (xy 99.673156 -282.405836)
			(xy 99.673664 -282.379949) (xy 99.681763 -282.328811) (xy 99.697762 -282.279571) (xy 99.721268 -282.233439)
			(xy 99.7517 -282.191552) (xy 99.78831 -282.154942) (xy 99.830197 -282.12451) (xy 99.876329 -282.101004)
			(xy 99.925569 -282.085005) (xy 99.976707 -282.076906) (xy 100.028481 -282.076906) (xy 100.079619 -282.085005)
			(xy 100.128859 -282.101004) (xy 100.174991 -282.12451) (xy 100.216878 -282.154942) (xy 100.253488 -282.191552)
			(xy 100.28392 -282.233439) (xy 100.307426 -282.279571) (xy 100.323425 -282.328811) (xy 100.331524 -282.379949)
			(xy 100.332032 -282.405836) (xy 101.552756 -282.405836) (xy 101.553216 -282.380501) (xy 101.560977 -282.33043)
			(xy 101.576305 -282.282135) (xy 101.598841 -282.236753) (xy 101.628054 -282.195352) (xy 101.663256 -282.158908)
			(xy 101.703619 -282.128277) (xy 101.748192 -282.104181) (xy 101.795927 -282.087187) (xy 101.820726 -282.081986)
			(xy 101.843586 -282.077668) (xy 102.048818 -281.722322) (xy 102.041198 -281.700478) (xy 102.03257 -281.674197)
			(xy 102.023258 -281.619675) (xy 102.022656 -281.59202) (xy 102.023164 -281.566113) (xy 102.03127 -281.514936)
			(xy 102.047282 -281.465657) (xy 102.070805 -281.41949) (xy 102.101261 -281.377571) (xy 102.137899 -281.340933)
			(xy 102.179818 -281.310477) (xy 102.225985 -281.286954) (xy 102.275264 -281.270942) (xy 102.326441 -281.262836)
			(xy 102.378255 -281.262836) (xy 102.429432 -281.270942) (xy 102.478711 -281.286954) (xy 102.524878 -281.310477)
			(xy 102.566797 -281.340933) (xy 102.603435 -281.377571) (xy 102.633891 -281.41949) (xy 102.657414 -281.465657)
			(xy 102.673426 -281.514936) (xy 102.681532 -281.566113) (xy 102.68204 -281.59202) (xy 102.681632 -281.617397)
			(xy 102.673859 -281.667553) (xy 102.658485 -281.715923) (xy 102.635873 -281.761362) (xy 102.606558 -281.802795)
			(xy 102.571235 -281.839241) (xy 102.53074 -281.869837) (xy 102.486031 -281.89386) (xy 102.438166 -281.910741)
			(xy 102.413308 -281.91587) (xy 102.390448 -281.920188) (xy 102.18547 -282.275026) (xy 102.193344 -282.297124)
			(xy 102.201911 -282.32348) (xy 102.211106 -282.378127) (xy 102.211632 -282.405836) (xy 102.211124 -282.431704)
			(xy 103.432652 -282.431704) (xy 103.432652 -282.379896) (xy 103.440757 -282.328725) (xy 103.456766 -282.279453)
			(xy 103.480287 -282.233291) (xy 103.510738 -282.191377) (xy 103.547372 -282.154742) (xy 103.589286 -282.12429)
			(xy 103.635447 -282.100769) (xy 103.684719 -282.084758) (xy 103.73589 -282.076653) (xy 103.761794 -282.076144)
			(xy 103.787307 -282.076611) (xy 103.837722 -282.084472) (xy 103.886325 -282.100007) (xy 103.931954 -282.122845)
			(xy 103.973519 -282.152441) (xy 104.010027 -282.188087) (xy 104.0257 -282.208224) (xy 104.437688 -282.208224)
			(xy 104.453375 -282.188099) (xy 104.489881 -282.152454) (xy 104.531443 -282.122858) (xy 104.577069 -282.10002)
			(xy 104.625669 -282.084484) (xy 104.676083 -282.076622) (xy 104.701594 -282.076144) (xy 104.727507 -282.076553)
			(xy 104.778694 -282.08466) (xy 104.827983 -282.100674) (xy 104.874159 -282.124201) (xy 104.916087 -282.154663)
			(xy 104.952733 -282.191308) (xy 104.983196 -282.233235) (xy 105.006724 -282.279412) (xy 105.022739 -282.3287)
			(xy 105.030846 -282.379887) (xy 105.030846 -282.431713) (xy 105.022739 -282.4829) (xy 105.006724 -282.532188)
			(xy 104.983196 -282.578365) (xy 104.952733 -282.620292) (xy 104.916087 -282.656937) (xy 104.874159 -282.687399)
			(xy 104.827983 -282.710926) (xy 104.778694 -282.72694) (xy 104.727507 -282.735047) (xy 104.701594 -282.735528)
			(xy 104.676083 -282.735041) (xy 104.625669 -282.72718) (xy 104.577068 -282.711647) (xy 104.53144 -282.688813)
			(xy 104.489874 -282.659222) (xy 104.453362 -282.623582) (xy 104.437688 -282.603448) (xy 104.0257 -282.603448)
			(xy 104.01004 -282.623594) (xy 103.973526 -282.659235) (xy 103.931957 -282.688826) (xy 103.886326 -282.71166)
			(xy 103.837723 -282.727192) (xy 103.787307 -282.735052) (xy 103.761794 -282.735528) (xy 103.73589 -282.734947)
			(xy 103.684719 -282.726842) (xy 103.635447 -282.710831) (xy 103.589286 -282.68731) (xy 103.547372 -282.656858)
			(xy 103.510738 -282.620223) (xy 103.480287 -282.578309) (xy 103.456766 -282.532147) (xy 103.440757 -282.482875)
			(xy 103.432652 -282.431704) (xy 102.211124 -282.431704) (xy 102.211124 -282.431723) (xy 102.203025 -282.482861)
			(xy 102.187026 -282.532101) (xy 102.16352 -282.578233) (xy 102.133088 -282.62012) (xy 102.096478 -282.65673)
			(xy 102.054591 -282.687162) (xy 102.008459 -282.710668) (xy 101.959219 -282.726667) (xy 101.908081 -282.734766)
			(xy 101.856307 -282.734766) (xy 101.805169 -282.726667) (xy 101.755929 -282.710668) (xy 101.709797 -282.687162)
			(xy 101.66791 -282.65673) (xy 101.6313 -282.62012) (xy 101.600868 -282.578233) (xy 101.577362 -282.532101)
			(xy 101.561363 -282.482861) (xy 101.553264 -282.431723) (xy 101.552756 -282.405836) (xy 100.332032 -282.405836)
			(xy 100.331594 -282.431161) (xy 100.323857 -282.481217) (xy 100.308554 -282.5295) (xy 100.286046 -282.574874)
			(xy 100.256862 -282.616272) (xy 100.22169 -282.652718) (xy 100.181356 -282.683356) (xy 100.136812 -282.707464)
			(xy 100.089103 -282.724474) (xy 100.064316 -282.729686) (xy 100.041456 -282.734004) (xy 99.836224 -283.089096)
			(xy 99.844098 -283.111194) (xy 99.852735 -283.137539) (xy 99.862052 -283.192188) (xy 99.86264 -283.219906)
			(xy 99.862132 -283.245791) (xy 101.083549 -283.245791) (xy 101.083549 -283.194009) (xy 101.091651 -283.142863)
			(xy 101.107654 -283.093616) (xy 101.131165 -283.047478) (xy 101.161604 -283.005586) (xy 101.198223 -282.968973)
			(xy 101.240119 -282.93854) (xy 101.28626 -282.915036) (xy 101.33551 -282.89904) (xy 101.386657 -282.890946)
			(xy 101.412548 -282.890468) (xy 101.43806 -282.890926) (xy 101.488475 -282.898793) (xy 101.537077 -282.914332)
			(xy 101.582705 -282.937172) (xy 101.62427 -282.966767) (xy 101.66078 -283.002412) (xy 101.676454 -283.022548)
			(xy 102.088442 -283.022548) (xy 102.104077 -283.002381) (xy 102.140596 -282.966741) (xy 102.18217 -282.937153)
			(xy 102.227806 -282.914323) (xy 102.276414 -282.898795) (xy 102.326834 -282.890941) (xy 102.352348 -282.890468)
			(xy 102.378233 -282.890967) (xy 102.429366 -282.899073) (xy 102.478601 -282.915077) (xy 102.524727 -282.938585)
			(xy 102.566608 -282.969019) (xy 102.603213 -283.005629) (xy 102.63364 -283.047514) (xy 102.657142 -283.093643)
			(xy 102.673139 -283.142881) (xy 102.681237 -283.194015) (xy 102.681237 -283.219906) (xy 104.842056 -283.219906)
			(xy 104.842537 -283.19456) (xy 104.85031 -283.144468) (xy 104.865657 -283.096156) (xy 104.888217 -283.050761)
			(xy 104.917459 -283.009354) (xy 104.952694 -282.97291) (xy 104.993091 -282.942288) (xy 105.037699 -282.918209)
			(xy 105.085466 -282.901241) (xy 105.11028 -282.896056) (xy 105.13314 -282.891738) (xy 105.338118 -282.5369)
			(xy 105.330498 -282.514802) (xy 105.321862 -282.488391) (xy 105.312535 -282.433617) (xy 105.311956 -282.405836)
			(xy 105.312464 -282.379949) (xy 105.320563 -282.328811) (xy 105.336562 -282.279571) (xy 105.360068 -282.233439)
			(xy 105.3905 -282.191552) (xy 105.42711 -282.154942) (xy 105.468997 -282.12451) (xy 105.515129 -282.101004)
			(xy 105.564369 -282.085005) (xy 105.615507 -282.076906) (xy 105.667281 -282.076906) (xy 105.718419 -282.085005)
			(xy 105.767659 -282.101004) (xy 105.813791 -282.12451) (xy 105.855678 -282.154942) (xy 105.892288 -282.191552)
			(xy 105.92272 -282.233439) (xy 105.946226 -282.279571) (xy 105.962225 -282.328811) (xy 105.970324 -282.379949)
			(xy 105.970832 -282.405836) (xy 105.970394 -282.431161) (xy 105.962657 -282.481217) (xy 105.947354 -282.5295)
			(xy 105.924846 -282.574874) (xy 105.895662 -282.616272) (xy 105.86049 -282.652718) (xy 105.820156 -282.683356)
			(xy 105.775612 -282.707464) (xy 105.727903 -282.724474) (xy 105.703116 -282.729686) (xy 105.680256 -282.734004)
			(xy 105.475024 -283.089096) (xy 105.482898 -283.111194) (xy 105.491535 -283.137539) (xy 105.500852 -283.192188)
			(xy 105.50144 -283.219906) (xy 105.500932 -283.245813) (xy 105.492826 -283.29699) (xy 105.476814 -283.346269)
			(xy 105.453291 -283.392436) (xy 105.422835 -283.434355) (xy 105.386197 -283.470993) (xy 105.344278 -283.501449)
			(xy 105.298111 -283.524972) (xy 105.248832 -283.540984) (xy 105.197655 -283.54909) (xy 105.145841 -283.54909)
			(xy 105.094664 -283.540984) (xy 105.045385 -283.524972) (xy 104.999218 -283.501449) (xy 104.957299 -283.470993)
			(xy 104.920661 -283.434355) (xy 104.890205 -283.392436) (xy 104.866682 -283.346269) (xy 104.85067 -283.29699)
			(xy 104.842564 -283.245813) (xy 104.842056 -283.219906) (xy 102.681237 -283.219906) (xy 102.681237 -283.245785)
			(xy 102.673139 -283.296919) (xy 102.657142 -283.346157) (xy 102.63364 -283.392286) (xy 102.603213 -283.434171)
			(xy 102.566608 -283.470781) (xy 102.524727 -283.501215) (xy 102.478601 -283.524723) (xy 102.429366 -283.540727)
			(xy 102.378233 -283.548833) (xy 102.352348 -283.549344) (xy 102.326836 -283.548851) (xy 102.276422 -283.540996)
			(xy 102.227819 -283.525467) (xy 102.18219 -283.502633) (xy 102.140624 -283.473042) (xy 102.104115 -283.437399)
			(xy 102.088442 -283.417264) (xy 101.676454 -283.417264) (xy 101.660739 -283.437366) (xy 101.624239 -283.473014)
			(xy 101.582683 -283.502612) (xy 101.537062 -283.525454) (xy 101.488467 -283.540995) (xy 101.438058 -283.548863)
			(xy 101.412548 -283.549344) (xy 101.386657 -283.548854) (xy 101.33551 -283.54076) (xy 101.28626 -283.524764)
			(xy 101.240119 -283.50126) (xy 101.198223 -283.470827) (xy 101.161604 -283.434214) (xy 101.131165 -283.392322)
			(xy 101.107654 -283.346184) (xy 101.091651 -283.296937) (xy 101.083549 -283.245791) (xy 99.862132 -283.245791)
			(xy 99.862132 -283.245813) (xy 99.854026 -283.29699) (xy 99.838014 -283.346269) (xy 99.814491 -283.392436)
			(xy 99.784035 -283.434355) (xy 99.747397 -283.470993) (xy 99.705478 -283.501449) (xy 99.659311 -283.524972)
			(xy 99.610032 -283.540984) (xy 99.558855 -283.54909) (xy 99.507041 -283.54909) (xy 99.455864 -283.540984)
			(xy 99.406585 -283.524972) (xy 99.360418 -283.501449) (xy 99.318499 -283.470993) (xy 99.281861 -283.434355)
			(xy 99.251405 -283.392436) (xy 99.227882 -283.346269) (xy 99.21187 -283.29699) (xy 99.203764 -283.245813)
			(xy 99.203256 -283.219906) (xy 97.04324 -283.219906) (xy 97.042732 -283.245813) (xy 97.034626 -283.29699)
			(xy 97.018614 -283.346269) (xy 96.995091 -283.392436) (xy 96.964635 -283.434355) (xy 96.927997 -283.470993)
			(xy 96.886078 -283.501449) (xy 96.839911 -283.524972) (xy 96.790632 -283.540984) (xy 96.739455 -283.54909)
			(xy 96.687641 -283.54909) (xy 96.636464 -283.540984) (xy 96.587185 -283.524972) (xy 96.541018 -283.501449)
			(xy 96.499099 -283.470993) (xy 96.462461 -283.434355) (xy 96.432005 -283.392436) (xy 96.408482 -283.346269)
			(xy 96.39247 -283.29699) (xy 96.384364 -283.245813) (xy 96.383856 -283.219906) (xy 96.384448 -283.192189)
			(xy 96.393773 -283.137542) (xy 96.402398 -283.111194) (xy 96.410272 -283.089096) (xy 96.205294 -282.734004)
			(xy 96.18218 -282.729686) (xy 96.15736 -282.724514) (xy 96.109579 -282.707563) (xy 96.064958 -282.683494)
			(xy 96.024551 -282.652875) (xy 95.989309 -282.616428) (xy 95.960065 -282.575014) (xy 95.937508 -282.52961)
			(xy 95.922171 -282.481287) (xy 95.914416 -282.431185) (xy 95.913956 -282.405836) (xy 95.633032 -282.405836)
			(xy 95.632524 -282.431723) (xy 95.624425 -282.482861) (xy 95.608426 -282.532101) (xy 95.58492 -282.578233)
			(xy 95.554488 -282.62012) (xy 95.517878 -282.65673) (xy 95.475991 -282.687162) (xy 95.429859 -282.710668)
			(xy 95.380619 -282.726667) (xy 95.329481 -282.734766) (xy 95.277707 -282.734766) (xy 95.226569 -282.726667)
			(xy 95.177329 -282.710668) (xy 95.131197 -282.687162) (xy 95.08931 -282.65673) (xy 95.0527 -282.62012)
			(xy 95.022268 -282.578233) (xy 94.998762 -282.532101) (xy 94.982763 -282.482861) (xy 94.974664 -282.431723)
			(xy 94.974156 -282.405836) (xy 93.75394 -282.405836) (xy 93.753432 -282.431743) (xy 93.745326 -282.48292)
			(xy 93.729314 -282.532199) (xy 93.705791 -282.578366) (xy 93.675335 -282.620285) (xy 93.638697 -282.656923)
			(xy 93.596778 -282.687379) (xy 93.550611 -282.710902) (xy 93.501332 -282.726914) (xy 93.450155 -282.73502)
			(xy 93.398341 -282.73502) (xy 93.347164 -282.726914) (xy 93.297885 -282.710902) (xy 93.251718 -282.687379)
			(xy 93.209799 -282.656923) (xy 93.173161 -282.620285) (xy 93.142705 -282.578366) (xy 93.119182 -282.532199)
			(xy 93.10317 -282.48292) (xy 93.095064 -282.431743) (xy 93.094556 -282.405836) (xy 88.114632 -282.405836)
			(xy 88.11411 -282.433545) (xy 88.10491 -282.488191) (xy 88.096344 -282.514548) (xy 88.08847 -282.536646)
			(xy 88.293702 -282.891738) (xy 88.316562 -282.896056) (xy 88.341357 -282.90128) (xy 88.389096 -282.918263)
			(xy 88.433673 -282.942351) (xy 88.47404 -282.972977) (xy 88.509244 -283.009419) (xy 88.538458 -283.050819)
			(xy 88.560992 -283.096202) (xy 88.576316 -283.144498) (xy 88.584068 -283.194571) (xy 88.584532 -283.219906)
			(xy 88.584024 -283.245787) (xy 92.625176 -283.245787) (xy 92.625176 -283.194013) (xy 92.633275 -283.142878)
			(xy 92.649273 -283.093638) (xy 92.672778 -283.047508) (xy 92.703209 -283.005622) (xy 92.739818 -282.969013)
			(xy 92.781703 -282.938581) (xy 92.827833 -282.915076) (xy 92.877072 -282.899076) (xy 92.928207 -282.890976)
			(xy 92.954094 -282.890468) (xy 92.979605 -282.890965) (xy 93.030018 -282.898824) (xy 93.078619 -282.914355)
			(xy 93.124247 -282.937187) (xy 93.165813 -282.966776) (xy 93.202325 -283.002415) (xy 93.218 -283.022548)
			(xy 93.629988 -283.022548) (xy 93.645654 -283.002407) (xy 93.682167 -282.966766) (xy 93.723734 -282.937174)
			(xy 93.769364 -282.91434) (xy 93.817967 -282.898806) (xy 93.868382 -282.890945) (xy 93.893894 -282.890468)
			(xy 93.919784 -282.890937) (xy 93.970927 -282.899036) (xy 94.020174 -282.915037) (xy 94.066311 -282.938544)
			(xy 94.108202 -282.968979) (xy 94.144817 -283.005593) (xy 94.175253 -283.047484) (xy 94.198761 -283.093621)
			(xy 94.214762 -283.142867) (xy 94.222863 -283.19401) (xy 94.222863 -283.24579) (xy 94.214762 -283.296933)
			(xy 94.198761 -283.346179) (xy 94.175253 -283.392316) (xy 94.144817 -283.434207) (xy 94.108202 -283.470821)
			(xy 94.066311 -283.501256) (xy 94.020174 -283.524763) (xy 93.970927 -283.540764) (xy 93.919784 -283.548863)
			(xy 93.893894 -283.549344) (xy 93.868381 -283.54889) (xy 93.817964 -283.541027) (xy 93.769361 -283.52549)
			(xy 93.723732 -283.502649) (xy 93.682168 -283.473051) (xy 93.64566 -283.437402) (xy 93.629988 -283.417264)
			(xy 93.218 -283.417264) (xy 93.202317 -283.437392) (xy 93.16581 -283.473038) (xy 93.124247 -283.502633)
			(xy 93.078621 -283.525471) (xy 93.03002 -283.541006) (xy 92.979606 -283.548867) (xy 92.954094 -283.549344)
			(xy 92.928207 -283.548824) (xy 92.877072 -283.540724) (xy 92.827833 -283.524724) (xy 92.781703 -283.501219)
			(xy 92.739818 -283.470787) (xy 92.703209 -283.434178) (xy 92.672778 -283.392292) (xy 92.649273 -283.346162)
			(xy 92.633275 -283.296922) (xy 92.625176 -283.245787) (xy 88.584024 -283.245787) (xy 88.584024 -283.245793)
			(xy 88.575925 -283.296931) (xy 88.559926 -283.346171) (xy 88.53642 -283.392303) (xy 88.505988 -283.43419)
			(xy 88.469378 -283.4708) (xy 88.427491 -283.501232) (xy 88.381359 -283.524738) (xy 88.332119 -283.540737)
			(xy 88.280981 -283.548836) (xy 88.229207 -283.548836) (xy 88.178069 -283.540737) (xy 88.128829 -283.524738)
			(xy 88.082697 -283.501232) (xy 88.04081 -283.4708) (xy 88.0042 -283.43419) (xy 87.973768 -283.392303)
			(xy 87.950262 -283.346171) (xy 87.934263 -283.296931) (xy 87.926164 -283.245793) (xy 87.925656 -283.219906)
			(xy 87.926189 -283.192198) (xy 87.935382 -283.137551) (xy 87.943944 -283.111194) (xy 87.951818 -283.089096)
			(xy 87.746586 -282.734004) (xy 87.723726 -282.729686) (xy 87.698938 -282.724431) (xy 87.651203 -282.70745)
			(xy 87.606628 -282.683364) (xy 87.566263 -282.652742) (xy 87.531059 -282.616304) (xy 87.501844 -282.574908)
			(xy 87.479308 -282.52953) (xy 87.463981 -282.481238) (xy 87.456223 -282.431169) (xy 87.455756 -282.405836)
			(xy 2.509012 -282.405836) (xy 2.509012 -284.033722) (xy 86.515956 -284.033722) (xy 86.516464 -284.007815)
			(xy 86.52457 -283.956638) (xy 86.540582 -283.907359) (xy 86.564105 -283.861192) (xy 86.594561 -283.819273)
			(xy 86.631199 -283.782635) (xy 86.673118 -283.752179) (xy 86.719285 -283.728656) (xy 86.768564 -283.712644)
			(xy 86.819741 -283.704538) (xy 86.871555 -283.704538) (xy 86.922732 -283.712644) (xy 86.972011 -283.728656)
			(xy 87.018178 -283.752179) (xy 87.060097 -283.782635) (xy 87.096735 -283.819273) (xy 87.127191 -283.861192)
			(xy 87.150714 -283.907359) (xy 87.166726 -283.956638) (xy 87.174832 -284.007815) (xy 87.17534 -284.033722)
			(xy 334.456024 -284.033722) (xy 334.456532 -284.007815) (xy 334.464638 -283.956638) (xy 334.48065 -283.907359)
			(xy 334.504173 -283.861192) (xy 334.534629 -283.819273) (xy 334.571267 -283.782635) (xy 334.613186 -283.752179)
			(xy 334.659353 -283.728656) (xy 334.708632 -283.712644) (xy 334.759809 -283.704538) (xy 334.811623 -283.704538)
			(xy 334.8628 -283.712644) (xy 334.912079 -283.728656) (xy 334.958246 -283.752179) (xy 335.000165 -283.782635)
			(xy 335.036803 -283.819273) (xy 335.067259 -283.861192) (xy 335.090782 -283.907359) (xy 335.106794 -283.956638)
			(xy 335.1149 -284.007815) (xy 335.115408 -284.033722) (xy 335.114819 -284.06144) (xy 335.105492 -284.116086)
			(xy 335.096866 -284.142434) (xy 335.088992 -284.164532) (xy 335.29397 -284.51937) (xy 335.31683 -284.523688)
			(xy 335.341643 -284.528833) (xy 335.389384 -284.545828) (xy 335.433962 -284.569927) (xy 335.474328 -284.600564)
			(xy 335.50953 -284.637016) (xy 335.538741 -284.678425) (xy 335.561271 -284.723817) (xy 335.576591 -284.772121)
			(xy 335.584339 -284.8222) (xy 335.5848 -284.847538) (xy 335.584292 -284.873425) (xy 335.576193 -284.924563)
			(xy 335.560194 -284.973803) (xy 335.536688 -285.019935) (xy 335.506256 -285.061822) (xy 335.469646 -285.098432)
			(xy 335.427759 -285.128864) (xy 335.381627 -285.15237) (xy 335.332387 -285.168369) (xy 335.281249 -285.176468)
			(xy 335.229475 -285.176468) (xy 335.178337 -285.168369) (xy 335.129097 -285.15237) (xy 335.082965 -285.128864)
			(xy 335.041078 -285.098432) (xy 335.004468 -285.061822) (xy 334.974036 -285.019935) (xy 334.95053 -284.973803)
			(xy 334.934531 -284.924563) (xy 334.926432 -284.873425) (xy 334.925924 -284.847538) (xy 334.926462 -284.81983)
			(xy 334.935651 -284.765183) (xy 334.944212 -284.738826) (xy 334.952086 -284.716728) (xy 334.747108 -284.36189)
			(xy 334.724248 -284.357572) (xy 334.699419 -284.352437) (xy 334.651638 -284.33548) (xy 334.607017 -284.311405)
			(xy 334.56661 -284.280781) (xy 334.531369 -284.24433) (xy 334.502126 -284.202912) (xy 334.479571 -284.157504)
			(xy 334.464236 -284.109178) (xy 334.456483 -284.059073) (xy 334.456024 -284.033722) (xy 87.17534 -284.033722)
			(xy 87.174755 -284.06144) (xy 87.165426 -284.116086) (xy 87.156798 -284.142434) (xy 87.148924 -284.164532)
			(xy 87.353902 -284.51937) (xy 87.376762 -284.523688) (xy 87.401564 -284.528882) (xy 87.449305 -284.545867)
			(xy 87.493884 -284.569958) (xy 87.534252 -284.600587) (xy 87.569457 -284.637033) (xy 87.598669 -284.678438)
			(xy 87.621201 -284.723825) (xy 87.636522 -284.772125) (xy 87.644271 -284.822202) (xy 87.644732 -284.847538)
			(xy 87.644224 -284.873425) (xy 87.636125 -284.924563) (xy 87.620126 -284.973803) (xy 87.59662 -285.019935)
			(xy 87.566188 -285.061822) (xy 87.529578 -285.098432) (xy 87.487691 -285.128864) (xy 87.441559 -285.15237)
			(xy 87.392319 -285.168369) (xy 87.341181 -285.176468) (xy 87.289407 -285.176468) (xy 87.238269 -285.168369)
			(xy 87.189029 -285.15237) (xy 87.142897 -285.128864) (xy 87.10101 -285.098432) (xy 87.0644 -285.061822)
			(xy 87.033968 -285.019935) (xy 87.010462 -284.973803) (xy 86.994463 -284.924563) (xy 86.986364 -284.873425)
			(xy 86.985856 -284.847538) (xy 86.986397 -284.81983) (xy 86.995584 -284.765184) (xy 87.004144 -284.738826)
			(xy 87.012018 -284.716728) (xy 86.80704 -284.36189) (xy 86.78418 -284.357572) (xy 86.759356 -284.352414)
			(xy 86.711575 -284.335461) (xy 86.666954 -284.311391) (xy 86.626545 -284.28077) (xy 86.591303 -284.244322)
			(xy 86.56206 -284.202906) (xy 86.539504 -284.1575) (xy 86.524169 -284.109175) (xy 86.516415 -284.059072)
			(xy 86.515956 -284.033722) (xy 2.509012 -284.033722) (xy 2.509012 -285.661354) (xy 89.335356 -285.661354)
			(xy 89.335864 -285.635467) (xy 89.343963 -285.584329) (xy 89.359962 -285.535089) (xy 89.383468 -285.488957)
			(xy 89.4139 -285.44707) (xy 89.45051 -285.41046) (xy 89.492397 -285.380028) (xy 89.538529 -285.356522)
			(xy 89.587769 -285.340523) (xy 89.638907 -285.332424) (xy 89.690681 -285.332424) (xy 89.741819 -285.340523)
			(xy 89.791059 -285.356522) (xy 89.837191 -285.380028) (xy 89.879078 -285.41046) (xy 89.915688 -285.44707)
			(xy 89.94612 -285.488957) (xy 89.969626 -285.535089) (xy 89.985625 -285.584329) (xy 89.993724 -285.635467)
			(xy 89.994232 -285.661354) (xy 90.275156 -285.661354) (xy 90.27559 -285.636007) (xy 90.28337 -285.585913)
			(xy 90.298725 -285.537599) (xy 90.321292 -285.492204) (xy 90.35054 -285.450798) (xy 90.385779 -285.414354)
			(xy 90.426181 -285.383733) (xy 90.470793 -285.359656) (xy 90.518564 -285.342688) (xy 90.54338 -285.337504)
			(xy 90.56624 -285.333186) (xy 90.771218 -284.978348) (xy 90.763344 -284.956504) (xy 90.754767 -284.930085)
			(xy 90.745569 -284.87531) (xy 90.745056 -284.847538) (xy 90.745564 -284.821651) (xy 90.753663 -284.770513)
			(xy 90.769662 -284.721273) (xy 90.793168 -284.675141) (xy 90.8236 -284.633254) (xy 90.86021 -284.596644)
			(xy 90.902097 -284.566212) (xy 90.948229 -284.542706) (xy 90.997469 -284.526707) (xy 91.048607 -284.518608)
			(xy 91.100381 -284.518608) (xy 91.151519 -284.526707) (xy 91.200759 -284.542706) (xy 91.246891 -284.566212)
			(xy 91.288778 -284.596644) (xy 91.325388 -284.633254) (xy 91.35582 -284.675141) (xy 91.379326 -284.721273)
			(xy 91.395325 -284.770513) (xy 91.403424 -284.821651) (xy 91.403932 -284.847538) (xy 91.403458 -284.872872)
			(xy 91.395701 -284.922944) (xy 91.380375 -284.971239) (xy 91.357841 -285.016622) (xy 91.32863 -285.058022)
			(xy 91.29343 -285.094467) (xy 91.253068 -285.125098) (xy 91.208495 -285.149194) (xy 91.160761 -285.166187)
			(xy 91.135962 -285.171388) (xy 91.113102 -285.175706) (xy 90.908124 -285.530544) (xy 90.915998 -285.552642)
			(xy 90.924622 -285.57899) (xy 90.933948 -285.633636) (xy 90.93454 -285.661354) (xy 91.214956 -285.661354)
			(xy 91.215464 -285.635447) (xy 91.22357 -285.58427) (xy 91.239582 -285.534991) (xy 91.263105 -285.488824)
			(xy 91.293561 -285.446905) (xy 91.330199 -285.410267) (xy 91.372118 -285.379811) (xy 91.418285 -285.356288)
			(xy 91.467564 -285.340276) (xy 91.518741 -285.33217) (xy 91.570555 -285.33217) (xy 91.621732 -285.340276)
			(xy 91.671011 -285.356288) (xy 91.717178 -285.379811) (xy 91.759097 -285.410267) (xy 91.795735 -285.446905)
			(xy 91.826191 -285.488824) (xy 91.849714 -285.534991) (xy 91.865726 -285.58427) (xy 91.873832 -285.635447)
			(xy 91.87434 -285.661354) (xy 92.154756 -285.661354) (xy 92.155232 -285.63602) (xy 92.16299 -285.585949)
			(xy 92.178317 -285.537654) (xy 92.20085 -285.492273) (xy 92.230061 -285.450872) (xy 92.265261 -285.414427)
			(xy 92.305622 -285.383796) (xy 92.350194 -285.3597) (xy 92.397927 -285.342705) (xy 92.422726 -285.337504)
			(xy 92.445586 -285.333186) (xy 92.650818 -284.97784) (xy 92.643198 -284.955996) (xy 92.634574 -284.929714)
			(xy 92.625259 -284.875193) (xy 92.624656 -284.847538) (xy 92.625164 -284.821631) (xy 92.63327 -284.770454)
			(xy 92.649282 -284.721175) (xy 92.672805 -284.675008) (xy 92.703261 -284.633089) (xy 92.739899 -284.596451)
			(xy 92.781818 -284.565995) (xy 92.827985 -284.542472) (xy 92.877264 -284.52646) (xy 92.928441 -284.518354)
			(xy 92.980255 -284.518354) (xy 93.031432 -284.52646) (xy 93.080711 -284.542472) (xy 93.126878 -284.565995)
			(xy 93.168797 -284.596451) (xy 93.205435 -284.633089) (xy 93.235891 -284.675008) (xy 93.259414 -284.721175)
			(xy 93.275426 -284.770454) (xy 93.283532 -284.821631) (xy 93.28404 -284.847538) (xy 93.283648 -284.872916)
			(xy 93.275873 -284.923072) (xy 93.260496 -284.971442) (xy 93.237881 -285.016882) (xy 93.208565 -285.058314)
			(xy 93.17324 -285.09476) (xy 93.132743 -285.125356) (xy 93.088033 -285.149379) (xy 93.040166 -285.166259)
			(xy 93.015308 -285.171388) (xy 92.992448 -285.175706) (xy 92.78747 -285.530544) (xy 92.795344 -285.552642)
			(xy 92.803916 -285.578997) (xy 92.813107 -285.633645) (xy 92.813632 -285.661354) (xy 93.094556 -285.661354)
			(xy 93.095064 -285.635467) (xy 93.103163 -285.584329) (xy 93.119162 -285.535089) (xy 93.142668 -285.488957)
			(xy 93.1731 -285.44707) (xy 93.20971 -285.41046) (xy 93.251597 -285.380028) (xy 93.297729 -285.356522)
			(xy 93.346969 -285.340523) (xy 93.398107 -285.332424) (xy 93.449881 -285.332424) (xy 93.501019 -285.340523)
			(xy 93.550259 -285.356522) (xy 93.596391 -285.380028) (xy 93.638278 -285.41046) (xy 93.674888 -285.44707)
			(xy 93.70532 -285.488957) (xy 93.728826 -285.535089) (xy 93.744825 -285.584329) (xy 93.752924 -285.635467)
			(xy 93.753432 -285.661354) (xy 94.034356 -285.661354) (xy 94.034832 -285.63602) (xy 94.04259 -285.585949)
			(xy 94.057917 -285.537654) (xy 94.08045 -285.492273) (xy 94.109661 -285.450872) (xy 94.144861 -285.414427)
			(xy 94.185222 -285.383796) (xy 94.229794 -285.3597) (xy 94.277527 -285.342705) (xy 94.302326 -285.337504)
			(xy 94.325186 -285.333186) (xy 94.530418 -284.97784) (xy 94.522798 -284.955996) (xy 94.514174 -284.929714)
			(xy 94.504859 -284.875193) (xy 94.504256 -284.847538) (xy 94.504764 -284.821631) (xy 94.51287 -284.770454)
			(xy 94.528882 -284.721175) (xy 94.552405 -284.675008) (xy 94.582861 -284.633089) (xy 94.619499 -284.596451)
			(xy 94.661418 -284.565995) (xy 94.707585 -284.542472) (xy 94.756864 -284.52646) (xy 94.808041 -284.518354)
			(xy 94.859855 -284.518354) (xy 94.911032 -284.52646) (xy 94.960311 -284.542472) (xy 95.006478 -284.565995)
			(xy 95.048397 -284.596451) (xy 95.085035 -284.633089) (xy 95.115491 -284.675008) (xy 95.139014 -284.721175)
			(xy 95.155026 -284.770454) (xy 95.163132 -284.821631) (xy 95.16364 -284.847538) (xy 95.163248 -284.872916)
			(xy 95.155473 -284.923072) (xy 95.140096 -284.971442) (xy 95.117481 -285.016882) (xy 95.088165 -285.058314)
			(xy 95.05284 -285.09476) (xy 95.012343 -285.125356) (xy 94.967633 -285.149379) (xy 94.919766 -285.166259)
			(xy 94.894908 -285.171388) (xy 94.872048 -285.175706) (xy 94.66707 -285.530544) (xy 94.674944 -285.552642)
			(xy 94.683516 -285.578997) (xy 94.692707 -285.633645) (xy 94.693232 -285.661354) (xy 94.974156 -285.661354)
			(xy 94.974664 -285.635467) (xy 94.982763 -285.584329) (xy 94.998762 -285.535089) (xy 95.022268 -285.488957)
			(xy 95.0527 -285.44707) (xy 95.08931 -285.41046) (xy 95.131197 -285.380028) (xy 95.177329 -285.356522)
			(xy 95.226569 -285.340523) (xy 95.277707 -285.332424) (xy 95.329481 -285.332424) (xy 95.380619 -285.340523)
			(xy 95.429859 -285.356522) (xy 95.475991 -285.380028) (xy 95.517878 -285.41046) (xy 95.554488 -285.44707)
			(xy 95.58492 -285.488957) (xy 95.608426 -285.535089) (xy 95.624425 -285.584329) (xy 95.632524 -285.635467)
			(xy 95.633032 -285.661354) (xy 95.913956 -285.661354) (xy 95.914432 -285.63602) (xy 95.92219 -285.585949)
			(xy 95.937517 -285.537654) (xy 95.96005 -285.492273) (xy 95.989261 -285.450872) (xy 96.024461 -285.414427)
			(xy 96.064822 -285.383796) (xy 96.109394 -285.3597) (xy 96.157127 -285.342705) (xy 96.181926 -285.337504)
			(xy 96.204786 -285.333186) (xy 96.410018 -284.97784) (xy 96.402398 -284.955996) (xy 96.393774 -284.929714)
			(xy 96.384459 -284.875193) (xy 96.383856 -284.847538) (xy 96.384364 -284.821631) (xy 96.39247 -284.770454)
			(xy 96.408482 -284.721175) (xy 96.432005 -284.675008) (xy 96.462461 -284.633089) (xy 96.499099 -284.596451)
			(xy 96.541018 -284.565995) (xy 96.587185 -284.542472) (xy 96.636464 -284.52646) (xy 96.687641 -284.518354)
			(xy 96.739455 -284.518354) (xy 96.790632 -284.52646) (xy 96.839911 -284.542472) (xy 96.886078 -284.565995)
			(xy 96.927997 -284.596451) (xy 96.964635 -284.633089) (xy 96.995091 -284.675008) (xy 97.018614 -284.721175)
			(xy 97.034626 -284.770454) (xy 97.042732 -284.821631) (xy 97.04324 -284.847538) (xy 97.042848 -284.872916)
			(xy 97.035073 -284.923072) (xy 97.019696 -284.971442) (xy 96.997081 -285.016882) (xy 96.967765 -285.058314)
			(xy 96.93244 -285.09476) (xy 96.891943 -285.125356) (xy 96.847233 -285.149379) (xy 96.799366 -285.166259)
			(xy 96.774508 -285.171388) (xy 96.751648 -285.175706) (xy 96.54667 -285.530544) (xy 96.554544 -285.552642)
			(xy 96.563116 -285.578997) (xy 96.572307 -285.633645) (xy 96.572832 -285.661354) (xy 96.853756 -285.661354)
			(xy 96.854264 -285.635467) (xy 96.862363 -285.584329) (xy 96.878362 -285.535089) (xy 96.901868 -285.488957)
			(xy 96.9323 -285.44707) (xy 96.96891 -285.41046) (xy 97.010797 -285.380028) (xy 97.056929 -285.356522)
			(xy 97.106169 -285.340523) (xy 97.157307 -285.332424) (xy 97.209081 -285.332424) (xy 97.260219 -285.340523)
			(xy 97.309459 -285.356522) (xy 97.355591 -285.380028) (xy 97.397478 -285.41046) (xy 97.434088 -285.44707)
			(xy 97.46452 -285.488957) (xy 97.488026 -285.535089) (xy 97.504025 -285.584329) (xy 97.512124 -285.635467)
			(xy 97.512632 -285.661354) (xy 97.793556 -285.661354) (xy 97.794032 -285.63602) (xy 97.80179 -285.585949)
			(xy 97.817117 -285.537654) (xy 97.83965 -285.492273) (xy 97.868861 -285.450872) (xy 97.904061 -285.414427)
			(xy 97.944422 -285.383796) (xy 97.988994 -285.3597) (xy 98.036727 -285.342705) (xy 98.061526 -285.337504)
			(xy 98.084386 -285.333186) (xy 98.289618 -284.97784) (xy 98.281998 -284.955996) (xy 98.273374 -284.929714)
			(xy 98.264059 -284.875193) (xy 98.263456 -284.847538) (xy 98.263964 -284.821631) (xy 98.27207 -284.770454)
			(xy 98.288082 -284.721175) (xy 98.311605 -284.675008) (xy 98.342061 -284.633089) (xy 98.378699 -284.596451)
			(xy 98.420618 -284.565995) (xy 98.466785 -284.542472) (xy 98.516064 -284.52646) (xy 98.567241 -284.518354)
			(xy 98.619055 -284.518354) (xy 98.670232 -284.52646) (xy 98.719511 -284.542472) (xy 98.765678 -284.565995)
			(xy 98.807597 -284.596451) (xy 98.844235 -284.633089) (xy 98.874691 -284.675008) (xy 98.898214 -284.721175)
			(xy 98.914226 -284.770454) (xy 98.922332 -284.821631) (xy 98.92284 -284.847538) (xy 98.922448 -284.872916)
			(xy 98.914673 -284.923072) (xy 98.899296 -284.971442) (xy 98.876681 -285.016882) (xy 98.847365 -285.058314)
			(xy 98.81204 -285.09476) (xy 98.771543 -285.125356) (xy 98.726833 -285.149379) (xy 98.678966 -285.166259)
			(xy 98.654108 -285.171388) (xy 98.631248 -285.175706) (xy 98.42627 -285.530544) (xy 98.434144 -285.552642)
			(xy 98.442716 -285.578997) (xy 98.451907 -285.633645) (xy 98.452432 -285.661354) (xy 98.733356 -285.661354)
			(xy 98.733864 -285.635467) (xy 98.741963 -285.584329) (xy 98.757962 -285.535089) (xy 98.781468 -285.488957)
			(xy 98.8119 -285.44707) (xy 98.84851 -285.41046) (xy 98.890397 -285.380028) (xy 98.936529 -285.356522)
			(xy 98.985769 -285.340523) (xy 99.036907 -285.332424) (xy 99.088681 -285.332424) (xy 99.139819 -285.340523)
			(xy 99.189059 -285.356522) (xy 99.235191 -285.380028) (xy 99.277078 -285.41046) (xy 99.313688 -285.44707)
			(xy 99.34412 -285.488957) (xy 99.367626 -285.535089) (xy 99.383625 -285.584329) (xy 99.391724 -285.635467)
			(xy 99.392232 -285.661354) (xy 99.673156 -285.661354) (xy 99.673632 -285.63602) (xy 99.68139 -285.585949)
			(xy 99.696717 -285.537654) (xy 99.71925 -285.492273) (xy 99.748461 -285.450872) (xy 99.783661 -285.414427)
			(xy 99.824022 -285.383796) (xy 99.868594 -285.3597) (xy 99.916327 -285.342705) (xy 99.941126 -285.337504)
			(xy 99.963986 -285.333186) (xy 100.169218 -284.97784) (xy 100.161598 -284.955996) (xy 100.152974 -284.929714)
			(xy 100.143659 -284.875193) (xy 100.143056 -284.847538) (xy 100.143564 -284.821631) (xy 100.15167 -284.770454)
			(xy 100.167682 -284.721175) (xy 100.191205 -284.675008) (xy 100.221661 -284.633089) (xy 100.258299 -284.596451)
			(xy 100.300218 -284.565995) (xy 100.346385 -284.542472) (xy 100.395664 -284.52646) (xy 100.446841 -284.518354)
			(xy 100.498655 -284.518354) (xy 100.549832 -284.52646) (xy 100.599111 -284.542472) (xy 100.645278 -284.565995)
			(xy 100.687197 -284.596451) (xy 100.723835 -284.633089) (xy 100.754291 -284.675008) (xy 100.777814 -284.721175)
			(xy 100.793826 -284.770454) (xy 100.801932 -284.821631) (xy 100.80244 -284.847538) (xy 100.802048 -284.872916)
			(xy 100.794273 -284.923072) (xy 100.778896 -284.971442) (xy 100.756281 -285.016882) (xy 100.726965 -285.058314)
			(xy 100.69164 -285.09476) (xy 100.651143 -285.125356) (xy 100.606433 -285.149379) (xy 100.558566 -285.166259)
			(xy 100.533708 -285.171388) (xy 100.510848 -285.175706) (xy 100.30587 -285.530544) (xy 100.313744 -285.552642)
			(xy 100.322316 -285.578997) (xy 100.331507 -285.633645) (xy 100.332032 -285.661354) (xy 100.612956 -285.661354)
			(xy 100.613464 -285.635467) (xy 100.621563 -285.584329) (xy 100.637562 -285.535089) (xy 100.661068 -285.488957)
			(xy 100.6915 -285.44707) (xy 100.72811 -285.41046) (xy 100.769997 -285.380028) (xy 100.816129 -285.356522)
			(xy 100.865369 -285.340523) (xy 100.916507 -285.332424) (xy 100.968281 -285.332424) (xy 101.019419 -285.340523)
			(xy 101.068659 -285.356522) (xy 101.114791 -285.380028) (xy 101.156678 -285.41046) (xy 101.193288 -285.44707)
			(xy 101.22372 -285.488957) (xy 101.247226 -285.535089) (xy 101.263225 -285.584329) (xy 101.271324 -285.635467)
			(xy 101.271832 -285.661354) (xy 101.552756 -285.661354) (xy 101.553232 -285.63602) (xy 101.56099 -285.585949)
			(xy 101.576317 -285.537654) (xy 101.59885 -285.492273) (xy 101.628061 -285.450872) (xy 101.663261 -285.414427)
			(xy 101.703622 -285.383796) (xy 101.748194 -285.3597) (xy 101.795927 -285.342705) (xy 101.820726 -285.337504)
			(xy 101.843586 -285.333186) (xy 102.048818 -284.97784) (xy 102.041198 -284.955996) (xy 102.032574 -284.929714)
			(xy 102.023259 -284.875193) (xy 102.022656 -284.847538) (xy 102.023164 -284.821631) (xy 102.03127 -284.770454)
			(xy 102.047282 -284.721175) (xy 102.070805 -284.675008) (xy 102.101261 -284.633089) (xy 102.137899 -284.596451)
			(xy 102.179818 -284.565995) (xy 102.225985 -284.542472) (xy 102.275264 -284.52646) (xy 102.326441 -284.518354)
			(xy 102.378255 -284.518354) (xy 102.429432 -284.52646) (xy 102.478711 -284.542472) (xy 102.524878 -284.565995)
			(xy 102.566797 -284.596451) (xy 102.603435 -284.633089) (xy 102.633891 -284.675008) (xy 102.657414 -284.721175)
			(xy 102.673426 -284.770454) (xy 102.681532 -284.821631) (xy 102.68204 -284.847538) (xy 102.681648 -284.872916)
			(xy 102.673873 -284.923072) (xy 102.658496 -284.971442) (xy 102.635881 -285.016882) (xy 102.606565 -285.058314)
			(xy 102.57124 -285.09476) (xy 102.530743 -285.125356) (xy 102.486033 -285.149379) (xy 102.438166 -285.166259)
			(xy 102.413308 -285.171388) (xy 102.390448 -285.175706) (xy 102.18547 -285.530544) (xy 102.193344 -285.552642)
			(xy 102.201916 -285.578997) (xy 102.211107 -285.633645) (xy 102.211632 -285.661354) (xy 102.492556 -285.661354)
			(xy 102.493064 -285.635467) (xy 102.501163 -285.584329) (xy 102.517162 -285.535089) (xy 102.540668 -285.488957)
			(xy 102.5711 -285.44707) (xy 102.60771 -285.41046) (xy 102.649597 -285.380028) (xy 102.695729 -285.356522)
			(xy 102.744969 -285.340523) (xy 102.796107 -285.332424) (xy 102.847881 -285.332424) (xy 102.899019 -285.340523)
			(xy 102.948259 -285.356522) (xy 102.994391 -285.380028) (xy 103.036278 -285.41046) (xy 103.072888 -285.44707)
			(xy 103.10332 -285.488957) (xy 103.126826 -285.535089) (xy 103.142825 -285.584329) (xy 103.150924 -285.635467)
			(xy 103.151432 -285.661354) (xy 103.432356 -285.661354) (xy 103.432832 -285.63602) (xy 103.44059 -285.585949)
			(xy 103.455917 -285.537654) (xy 103.47845 -285.492273) (xy 103.507661 -285.450872) (xy 103.542861 -285.414427)
			(xy 103.583222 -285.383796) (xy 103.627794 -285.3597) (xy 103.675527 -285.342705) (xy 103.700326 -285.337504)
			(xy 103.723186 -285.333186) (xy 103.928418 -284.97784) (xy 103.920798 -284.955996) (xy 103.912174 -284.929714)
			(xy 103.902859 -284.875193) (xy 103.902256 -284.847538) (xy 103.902764 -284.821631) (xy 103.91087 -284.770454)
			(xy 103.926882 -284.721175) (xy 103.950405 -284.675008) (xy 103.980861 -284.633089) (xy 104.017499 -284.596451)
			(xy 104.059418 -284.565995) (xy 104.105585 -284.542472) (xy 104.154864 -284.52646) (xy 104.206041 -284.518354)
			(xy 104.257855 -284.518354) (xy 104.309032 -284.52646) (xy 104.358311 -284.542472) (xy 104.404478 -284.565995)
			(xy 104.446397 -284.596451) (xy 104.483035 -284.633089) (xy 104.513491 -284.675008) (xy 104.537014 -284.721175)
			(xy 104.553026 -284.770454) (xy 104.561132 -284.821631) (xy 104.56164 -284.847538) (xy 118.939056 -284.847538)
			(xy 118.939564 -284.821631) (xy 118.94767 -284.770454) (xy 118.963682 -284.721175) (xy 118.987205 -284.675008)
			(xy 119.017661 -284.633089) (xy 119.054299 -284.596451) (xy 119.096218 -284.565995) (xy 119.142385 -284.542472)
			(xy 119.191664 -284.52646) (xy 119.242841 -284.518354) (xy 119.294655 -284.518354) (xy 119.345832 -284.52646)
			(xy 119.395111 -284.542472) (xy 119.441278 -284.565995) (xy 119.483197 -284.596451) (xy 119.519835 -284.633089)
			(xy 119.550291 -284.675008) (xy 119.573814 -284.721175) (xy 119.589826 -284.770454) (xy 119.597932 -284.821631)
			(xy 119.59844 -284.847538) (xy 120.818656 -284.847538) (xy 120.819164 -284.821631) (xy 120.82727 -284.770454)
			(xy 120.843282 -284.721175) (xy 120.866805 -284.675008) (xy 120.897261 -284.633089) (xy 120.933899 -284.596451)
			(xy 120.975818 -284.565995) (xy 121.021985 -284.542472) (xy 121.071264 -284.52646) (xy 121.122441 -284.518354)
			(xy 121.174255 -284.518354) (xy 121.225432 -284.52646) (xy 121.274711 -284.542472) (xy 121.320878 -284.565995)
			(xy 121.362797 -284.596451) (xy 121.399435 -284.633089) (xy 121.429891 -284.675008) (xy 121.453414 -284.721175)
			(xy 121.469426 -284.770454) (xy 121.477532 -284.821631) (xy 121.47804 -284.847538) (xy 122.698256 -284.847538)
			(xy 122.698764 -284.821631) (xy 122.70687 -284.770454) (xy 122.722882 -284.721175) (xy 122.746405 -284.675008)
			(xy 122.776861 -284.633089) (xy 122.813499 -284.596451) (xy 122.855418 -284.565995) (xy 122.901585 -284.542472)
			(xy 122.950864 -284.52646) (xy 123.002041 -284.518354) (xy 123.053855 -284.518354) (xy 123.105032 -284.52646)
			(xy 123.154311 -284.542472) (xy 123.200478 -284.565995) (xy 123.242397 -284.596451) (xy 123.279035 -284.633089)
			(xy 123.309491 -284.675008) (xy 123.333014 -284.721175) (xy 123.349026 -284.770454) (xy 123.357132 -284.821631)
			(xy 123.35764 -284.847538) (xy 124.577856 -284.847538) (xy 124.578364 -284.821631) (xy 124.58647 -284.770454)
			(xy 124.602482 -284.721175) (xy 124.626005 -284.675008) (xy 124.656461 -284.633089) (xy 124.693099 -284.596451)
			(xy 124.735018 -284.565995) (xy 124.781185 -284.542472) (xy 124.830464 -284.52646) (xy 124.881641 -284.518354)
			(xy 124.933455 -284.518354) (xy 124.984632 -284.52646) (xy 125.033911 -284.542472) (xy 125.080078 -284.565995)
			(xy 125.121997 -284.596451) (xy 125.158635 -284.633089) (xy 125.189091 -284.675008) (xy 125.212614 -284.721175)
			(xy 125.228626 -284.770454) (xy 125.236732 -284.821631) (xy 125.23724 -284.847538) (xy 126.457456 -284.847538)
			(xy 126.457964 -284.821631) (xy 126.46607 -284.770454) (xy 126.482082 -284.721175) (xy 126.505605 -284.675008)
			(xy 126.536061 -284.633089) (xy 126.572699 -284.596451) (xy 126.614618 -284.565995) (xy 126.660785 -284.542472)
			(xy 126.710064 -284.52646) (xy 126.761241 -284.518354) (xy 126.813055 -284.518354) (xy 126.864232 -284.52646)
			(xy 126.913511 -284.542472) (xy 126.959678 -284.565995) (xy 127.001597 -284.596451) (xy 127.038235 -284.633089)
			(xy 127.068691 -284.675008) (xy 127.092214 -284.721175) (xy 127.108226 -284.770454) (xy 127.116332 -284.821631)
			(xy 127.11684 -284.847538) (xy 128.337056 -284.847538) (xy 128.337564 -284.821631) (xy 128.34567 -284.770454)
			(xy 128.361682 -284.721175) (xy 128.385205 -284.675008) (xy 128.415661 -284.633089) (xy 128.452299 -284.596451)
			(xy 128.494218 -284.565995) (xy 128.540385 -284.542472) (xy 128.589664 -284.52646) (xy 128.640841 -284.518354)
			(xy 128.692655 -284.518354) (xy 128.743832 -284.52646) (xy 128.793111 -284.542472) (xy 128.839278 -284.565995)
			(xy 128.881197 -284.596451) (xy 128.917835 -284.633089) (xy 128.948291 -284.675008) (xy 128.971814 -284.721175)
			(xy 128.987826 -284.770454) (xy 128.995932 -284.821631) (xy 128.99644 -284.847538) (xy 130.216656 -284.847538)
			(xy 130.217164 -284.821631) (xy 130.22527 -284.770454) (xy 130.241282 -284.721175) (xy 130.264805 -284.675008)
			(xy 130.295261 -284.633089) (xy 130.331899 -284.596451) (xy 130.373818 -284.565995) (xy 130.419985 -284.542472)
			(xy 130.469264 -284.52646) (xy 130.520441 -284.518354) (xy 130.572255 -284.518354) (xy 130.623432 -284.52646)
			(xy 130.672711 -284.542472) (xy 130.718878 -284.565995) (xy 130.760797 -284.596451) (xy 130.797435 -284.633089)
			(xy 130.827891 -284.675008) (xy 130.851414 -284.721175) (xy 130.867426 -284.770454) (xy 130.875532 -284.821631)
			(xy 130.87604 -284.847538) (xy 132.096256 -284.847538) (xy 132.096764 -284.821631) (xy 132.10487 -284.770454)
			(xy 132.120882 -284.721175) (xy 132.144405 -284.675008) (xy 132.174861 -284.633089) (xy 132.211499 -284.596451)
			(xy 132.253418 -284.565995) (xy 132.299585 -284.542472) (xy 132.348864 -284.52646) (xy 132.400041 -284.518354)
			(xy 132.451855 -284.518354) (xy 132.503032 -284.52646) (xy 132.552311 -284.542472) (xy 132.598478 -284.565995)
			(xy 132.640397 -284.596451) (xy 132.677035 -284.633089) (xy 132.707491 -284.675008) (xy 132.731014 -284.721175)
			(xy 132.747026 -284.770454) (xy 132.755132 -284.821631) (xy 132.75564 -284.847538) (xy 132.755034 -284.875255)
			(xy 132.745719 -284.929901) (xy 132.737098 -284.95625) (xy 132.729224 -284.978348) (xy 132.934202 -285.333186)
			(xy 132.957062 -285.337504) (xy 132.981868 -285.342683) (xy 133.02961 -285.359669) (xy 133.07419 -285.383762)
			(xy 133.114558 -285.414393) (xy 133.149763 -285.450841) (xy 133.178975 -285.492247) (xy 133.201506 -285.537636)
			(xy 133.216825 -285.585939) (xy 133.224572 -285.636017) (xy 133.225032 -285.661354) (xy 133.224524 -285.687241)
			(xy 133.216425 -285.738379) (xy 133.200426 -285.787619) (xy 133.17692 -285.833751) (xy 133.146488 -285.875638)
			(xy 133.109878 -285.912248) (xy 133.067991 -285.94268) (xy 133.021859 -285.966186) (xy 132.972619 -285.982185)
			(xy 132.921481 -285.990284) (xy 132.869707 -285.990284) (xy 132.818569 -285.982185) (xy 132.769329 -285.966186)
			(xy 132.723197 -285.94268) (xy 132.68131 -285.912248) (xy 132.6447 -285.875638) (xy 132.614268 -285.833751)
			(xy 132.590762 -285.787619) (xy 132.574763 -285.738379) (xy 132.566664 -285.687241) (xy 132.566156 -285.661354)
			(xy 132.566701 -285.633647) (xy 132.575886 -285.579) (xy 132.584444 -285.552642) (xy 132.592318 -285.530544)
			(xy 132.38734 -285.175706) (xy 132.36448 -285.171388) (xy 132.33966 -285.166215) (xy 132.29188 -285.149263)
			(xy 132.247259 -285.125194) (xy 132.206851 -285.094575) (xy 132.171609 -285.058129) (xy 132.142365 -285.016715)
			(xy 132.119809 -284.971312) (xy 132.104472 -284.922989) (xy 132.096717 -284.872887) (xy 132.096256 -284.847538)
			(xy 130.87604 -284.847538) (xy 130.875434 -284.875255) (xy 130.866119 -284.929901) (xy 130.857498 -284.95625)
			(xy 130.849624 -284.978348) (xy 131.054602 -285.333186) (xy 131.077462 -285.337504) (xy 131.102268 -285.342683)
			(xy 131.15001 -285.359669) (xy 131.19459 -285.383762) (xy 131.234958 -285.414393) (xy 131.270163 -285.450841)
			(xy 131.299375 -285.492247) (xy 131.321906 -285.537636) (xy 131.337225 -285.585939) (xy 131.344972 -285.636017)
			(xy 131.345432 -285.661354) (xy 131.344924 -285.687241) (xy 131.336825 -285.738379) (xy 131.320826 -285.787619)
			(xy 131.29732 -285.833751) (xy 131.266888 -285.875638) (xy 131.230278 -285.912248) (xy 131.188391 -285.94268)
			(xy 131.142259 -285.966186) (xy 131.093019 -285.982185) (xy 131.041881 -285.990284) (xy 130.990107 -285.990284)
			(xy 130.938969 -285.982185) (xy 130.889729 -285.966186) (xy 130.843597 -285.94268) (xy 130.80171 -285.912248)
			(xy 130.7651 -285.875638) (xy 130.734668 -285.833751) (xy 130.711162 -285.787619) (xy 130.695163 -285.738379)
			(xy 130.687064 -285.687241) (xy 130.686556 -285.661354) (xy 130.687101 -285.633647) (xy 130.696286 -285.579)
			(xy 130.704844 -285.552642) (xy 130.712718 -285.530544) (xy 130.50774 -285.175706) (xy 130.48488 -285.171388)
			(xy 130.46006 -285.166215) (xy 130.41228 -285.149263) (xy 130.367659 -285.125194) (xy 130.327251 -285.094575)
			(xy 130.292009 -285.058129) (xy 130.262765 -285.016715) (xy 130.240209 -284.971312) (xy 130.224872 -284.922989)
			(xy 130.217117 -284.872887) (xy 130.216656 -284.847538) (xy 128.99644 -284.847538) (xy 128.995834 -284.875255)
			(xy 128.986519 -284.929901) (xy 128.977898 -284.95625) (xy 128.970024 -284.978348) (xy 129.175002 -285.333186)
			(xy 129.197862 -285.337504) (xy 129.222668 -285.342683) (xy 129.27041 -285.359669) (xy 129.31499 -285.383762)
			(xy 129.355358 -285.414393) (xy 129.390563 -285.450841) (xy 129.419775 -285.492247) (xy 129.442306 -285.537636)
			(xy 129.457625 -285.585939) (xy 129.465372 -285.636017) (xy 129.465832 -285.661354) (xy 129.465324 -285.687241)
			(xy 129.457225 -285.738379) (xy 129.441226 -285.787619) (xy 129.41772 -285.833751) (xy 129.387288 -285.875638)
			(xy 129.350678 -285.912248) (xy 129.308791 -285.94268) (xy 129.262659 -285.966186) (xy 129.213419 -285.982185)
			(xy 129.162281 -285.990284) (xy 129.110507 -285.990284) (xy 129.059369 -285.982185) (xy 129.010129 -285.966186)
			(xy 128.963997 -285.94268) (xy 128.92211 -285.912248) (xy 128.8855 -285.875638) (xy 128.855068 -285.833751)
			(xy 128.831562 -285.787619) (xy 128.815563 -285.738379) (xy 128.807464 -285.687241) (xy 128.806956 -285.661354)
			(xy 128.807501 -285.633647) (xy 128.816686 -285.579) (xy 128.825244 -285.552642) (xy 128.833118 -285.530544)
			(xy 128.62814 -285.175706) (xy 128.60528 -285.171388) (xy 128.58046 -285.166215) (xy 128.53268 -285.149263)
			(xy 128.488059 -285.125194) (xy 128.447651 -285.094575) (xy 128.412409 -285.058129) (xy 128.383165 -285.016715)
			(xy 128.360609 -284.971312) (xy 128.345272 -284.922989) (xy 128.337517 -284.872887) (xy 128.337056 -284.847538)
			(xy 127.11684 -284.847538) (xy 127.116234 -284.875255) (xy 127.106919 -284.929901) (xy 127.098298 -284.95625)
			(xy 127.090424 -284.978348) (xy 127.295402 -285.333186) (xy 127.318262 -285.337504) (xy 127.343068 -285.342683)
			(xy 127.39081 -285.359669) (xy 127.43539 -285.383762) (xy 127.475758 -285.414393) (xy 127.510963 -285.450841)
			(xy 127.540175 -285.492247) (xy 127.562706 -285.537636) (xy 127.578025 -285.585939) (xy 127.585772 -285.636017)
			(xy 127.586232 -285.661354) (xy 127.585724 -285.687241) (xy 127.577625 -285.738379) (xy 127.561626 -285.787619)
			(xy 127.53812 -285.833751) (xy 127.507688 -285.875638) (xy 127.471078 -285.912248) (xy 127.429191 -285.94268)
			(xy 127.383059 -285.966186) (xy 127.333819 -285.982185) (xy 127.282681 -285.990284) (xy 127.230907 -285.990284)
			(xy 127.179769 -285.982185) (xy 127.130529 -285.966186) (xy 127.084397 -285.94268) (xy 127.04251 -285.912248)
			(xy 127.0059 -285.875638) (xy 126.975468 -285.833751) (xy 126.951962 -285.787619) (xy 126.935963 -285.738379)
			(xy 126.927864 -285.687241) (xy 126.927356 -285.661354) (xy 126.927901 -285.633647) (xy 126.937086 -285.579)
			(xy 126.945644 -285.552642) (xy 126.953518 -285.530544) (xy 126.74854 -285.175706) (xy 126.72568 -285.171388)
			(xy 126.70086 -285.166215) (xy 126.65308 -285.149263) (xy 126.608459 -285.125194) (xy 126.568051 -285.094575)
			(xy 126.532809 -285.058129) (xy 126.503565 -285.016715) (xy 126.481009 -284.971312) (xy 126.465672 -284.922989)
			(xy 126.457917 -284.872887) (xy 126.457456 -284.847538) (xy 125.23724 -284.847538) (xy 125.236634 -284.875255)
			(xy 125.227319 -284.929901) (xy 125.218698 -284.95625) (xy 125.210824 -284.978348) (xy 125.415802 -285.333186)
			(xy 125.438662 -285.337504) (xy 125.463468 -285.342683) (xy 125.51121 -285.359669) (xy 125.55579 -285.383762)
			(xy 125.596158 -285.414393) (xy 125.631363 -285.450841) (xy 125.660575 -285.492247) (xy 125.683106 -285.537636)
			(xy 125.698425 -285.585939) (xy 125.706172 -285.636017) (xy 125.706632 -285.661354) (xy 125.706124 -285.687241)
			(xy 125.698025 -285.738379) (xy 125.682026 -285.787619) (xy 125.65852 -285.833751) (xy 125.628088 -285.875638)
			(xy 125.591478 -285.912248) (xy 125.549591 -285.94268) (xy 125.503459 -285.966186) (xy 125.454219 -285.982185)
			(xy 125.403081 -285.990284) (xy 125.351307 -285.990284) (xy 125.300169 -285.982185) (xy 125.250929 -285.966186)
			(xy 125.204797 -285.94268) (xy 125.16291 -285.912248) (xy 125.1263 -285.875638) (xy 125.095868 -285.833751)
			(xy 125.072362 -285.787619) (xy 125.056363 -285.738379) (xy 125.048264 -285.687241) (xy 125.047756 -285.661354)
			(xy 125.048301 -285.633647) (xy 125.057486 -285.579) (xy 125.066044 -285.552642) (xy 125.073918 -285.530544)
			(xy 124.86894 -285.175706) (xy 124.84608 -285.171388) (xy 124.82126 -285.166215) (xy 124.77348 -285.149263)
			(xy 124.728859 -285.125194) (xy 124.688451 -285.094575) (xy 124.653209 -285.058129) (xy 124.623965 -285.016715)
			(xy 124.601409 -284.971312) (xy 124.586072 -284.922989) (xy 124.578317 -284.872887) (xy 124.577856 -284.847538)
			(xy 123.35764 -284.847538) (xy 123.357034 -284.875255) (xy 123.347719 -284.929901) (xy 123.339098 -284.95625)
			(xy 123.331224 -284.978348) (xy 123.536202 -285.333186) (xy 123.559062 -285.337504) (xy 123.583868 -285.342683)
			(xy 123.63161 -285.359669) (xy 123.67619 -285.383762) (xy 123.716558 -285.414393) (xy 123.751763 -285.450841)
			(xy 123.780975 -285.492247) (xy 123.803506 -285.537636) (xy 123.818825 -285.585939) (xy 123.826572 -285.636017)
			(xy 123.827032 -285.661354) (xy 123.826524 -285.687241) (xy 123.818425 -285.738379) (xy 123.802426 -285.787619)
			(xy 123.77892 -285.833751) (xy 123.748488 -285.875638) (xy 123.711878 -285.912248) (xy 123.669991 -285.94268)
			(xy 123.623859 -285.966186) (xy 123.574619 -285.982185) (xy 123.523481 -285.990284) (xy 123.471707 -285.990284)
			(xy 123.420569 -285.982185) (xy 123.371329 -285.966186) (xy 123.325197 -285.94268) (xy 123.28331 -285.912248)
			(xy 123.2467 -285.875638) (xy 123.216268 -285.833751) (xy 123.192762 -285.787619) (xy 123.176763 -285.738379)
			(xy 123.168664 -285.687241) (xy 123.168156 -285.661354) (xy 123.168701 -285.633647) (xy 123.177886 -285.579)
			(xy 123.186444 -285.552642) (xy 123.194318 -285.530544) (xy 122.98934 -285.175706) (xy 122.96648 -285.171388)
			(xy 122.94166 -285.166215) (xy 122.89388 -285.149263) (xy 122.849259 -285.125194) (xy 122.808851 -285.094575)
			(xy 122.773609 -285.058129) (xy 122.744365 -285.016715) (xy 122.721809 -284.971312) (xy 122.706472 -284.922989)
			(xy 122.698717 -284.872887) (xy 122.698256 -284.847538) (xy 121.47804 -284.847538) (xy 121.477434 -284.875255)
			(xy 121.468119 -284.929901) (xy 121.459498 -284.95625) (xy 121.451624 -284.978348) (xy 121.656602 -285.333186)
			(xy 121.679462 -285.337504) (xy 121.704268 -285.342683) (xy 121.75201 -285.359669) (xy 121.79659 -285.383762)
			(xy 121.836958 -285.414393) (xy 121.872163 -285.450841) (xy 121.901375 -285.492247) (xy 121.923906 -285.537636)
			(xy 121.939225 -285.585939) (xy 121.946972 -285.636017) (xy 121.947432 -285.661354) (xy 121.946924 -285.687241)
			(xy 121.938825 -285.738379) (xy 121.922826 -285.787619) (xy 121.89932 -285.833751) (xy 121.868888 -285.875638)
			(xy 121.832278 -285.912248) (xy 121.790391 -285.94268) (xy 121.744259 -285.966186) (xy 121.695019 -285.982185)
			(xy 121.643881 -285.990284) (xy 121.592107 -285.990284) (xy 121.540969 -285.982185) (xy 121.491729 -285.966186)
			(xy 121.445597 -285.94268) (xy 121.40371 -285.912248) (xy 121.3671 -285.875638) (xy 121.336668 -285.833751)
			(xy 121.313162 -285.787619) (xy 121.297163 -285.738379) (xy 121.289064 -285.687241) (xy 121.288556 -285.661354)
			(xy 121.289101 -285.633647) (xy 121.298286 -285.579) (xy 121.306844 -285.552642) (xy 121.314718 -285.530544)
			(xy 121.10974 -285.175706) (xy 121.08688 -285.171388) (xy 121.06206 -285.166215) (xy 121.01428 -285.149263)
			(xy 120.969659 -285.125194) (xy 120.929251 -285.094575) (xy 120.894009 -285.058129) (xy 120.864765 -285.016715)
			(xy 120.842209 -284.971312) (xy 120.826872 -284.922989) (xy 120.819117 -284.872887) (xy 120.818656 -284.847538)
			(xy 119.59844 -284.847538) (xy 119.597834 -284.875255) (xy 119.588519 -284.929901) (xy 119.579898 -284.95625)
			(xy 119.572024 -284.978348) (xy 119.777002 -285.333186) (xy 119.799862 -285.337504) (xy 119.824668 -285.342683)
			(xy 119.87241 -285.359669) (xy 119.91699 -285.383762) (xy 119.957358 -285.414393) (xy 119.992563 -285.450841)
			(xy 120.021775 -285.492247) (xy 120.044306 -285.537636) (xy 120.059625 -285.585939) (xy 120.067372 -285.636017)
			(xy 120.067832 -285.661354) (xy 120.067324 -285.687241) (xy 120.059225 -285.738379) (xy 120.043226 -285.787619)
			(xy 120.01972 -285.833751) (xy 119.989288 -285.875638) (xy 119.952678 -285.912248) (xy 119.910791 -285.94268)
			(xy 119.864659 -285.966186) (xy 119.815419 -285.982185) (xy 119.764281 -285.990284) (xy 119.712507 -285.990284)
			(xy 119.661369 -285.982185) (xy 119.612129 -285.966186) (xy 119.565997 -285.94268) (xy 119.52411 -285.912248)
			(xy 119.4875 -285.875638) (xy 119.457068 -285.833751) (xy 119.433562 -285.787619) (xy 119.417563 -285.738379)
			(xy 119.409464 -285.687241) (xy 119.408956 -285.661354) (xy 119.409501 -285.633647) (xy 119.418686 -285.579)
			(xy 119.427244 -285.552642) (xy 119.435118 -285.530544) (xy 119.23014 -285.175706) (xy 119.20728 -285.171388)
			(xy 119.18246 -285.166215) (xy 119.13468 -285.149263) (xy 119.090059 -285.125194) (xy 119.049651 -285.094575)
			(xy 119.014409 -285.058129) (xy 118.985165 -285.016715) (xy 118.962609 -284.971312) (xy 118.947272 -284.922989)
			(xy 118.939517 -284.872887) (xy 118.939056 -284.847538) (xy 104.56164 -284.847538) (xy 104.561248 -284.872916)
			(xy 104.553473 -284.923072) (xy 104.538096 -284.971442) (xy 104.515481 -285.016882) (xy 104.486165 -285.058314)
			(xy 104.45084 -285.09476) (xy 104.410343 -285.125356) (xy 104.365633 -285.149379) (xy 104.317766 -285.166259)
			(xy 104.292908 -285.171388) (xy 104.270048 -285.175706) (xy 104.06507 -285.530544) (xy 104.072944 -285.552642)
			(xy 104.081516 -285.578997) (xy 104.090707 -285.633645) (xy 104.091232 -285.661354) (xy 104.090724 -285.687241)
			(xy 104.082625 -285.738379) (xy 104.066626 -285.787619) (xy 104.04312 -285.833751) (xy 104.012688 -285.875638)
			(xy 103.976078 -285.912248) (xy 103.934191 -285.94268) (xy 103.888059 -285.966186) (xy 103.838819 -285.982185)
			(xy 103.787681 -285.990284) (xy 103.735907 -285.990284) (xy 103.684769 -285.982185) (xy 103.635529 -285.966186)
			(xy 103.589397 -285.94268) (xy 103.54751 -285.912248) (xy 103.5109 -285.875638) (xy 103.480468 -285.833751)
			(xy 103.456962 -285.787619) (xy 103.440963 -285.738379) (xy 103.432864 -285.687241) (xy 103.432356 -285.661354)
			(xy 103.151432 -285.661354) (xy 103.151432 -285.661862) (xy 103.150853 -285.689379) (xy 103.141659 -285.74364)
			(xy 103.133144 -285.769812) (xy 103.125524 -285.79191) (xy 103.330756 -286.147256) (xy 103.353616 -286.151574)
			(xy 103.378427 -286.156786) (xy 103.426204 -286.173734) (xy 103.470823 -286.197799) (xy 103.51123 -286.228413)
			(xy 103.546472 -286.264855) (xy 103.575717 -286.306263) (xy 103.598276 -286.351662) (xy 103.613617 -286.399979)
			(xy 103.621377 -286.450077) (xy 103.62184 -286.475424) (xy 119.878856 -286.475424) (xy 119.879354 -286.450079)
			(xy 119.887123 -286.399987) (xy 119.902468 -286.351675) (xy 119.925026 -286.306281) (xy 119.954266 -286.264873)
			(xy 119.989499 -286.228429) (xy 120.029894 -286.197807) (xy 120.0745 -286.173728) (xy 120.122266 -286.156759)
			(xy 120.14708 -286.151574) (xy 120.16994 -286.147256) (xy 120.374918 -285.792164) (xy 120.367044 -285.77032)
			(xy 120.358471 -285.743899) (xy 120.34927 -285.689126) (xy 120.348756 -285.661354) (xy 120.349264 -285.635467)
			(xy 120.357363 -285.584329) (xy 120.373362 -285.535089) (xy 120.396868 -285.488957) (xy 120.4273 -285.44707)
			(xy 120.46391 -285.41046) (xy 120.505797 -285.380028) (xy 120.551929 -285.356522) (xy 120.601169 -285.340523)
			(xy 120.652307 -285.332424) (xy 120.704081 -285.332424) (xy 120.755219 -285.340523) (xy 120.804459 -285.356522)
			(xy 120.850591 -285.380028) (xy 120.892478 -285.41046) (xy 120.929088 -285.44707) (xy 120.95952 -285.488957)
			(xy 120.983026 -285.535089) (xy 120.999025 -285.584329) (xy 121.007124 -285.635467) (xy 121.007632 -285.661354)
			(xy 121.007172 -285.686689) (xy 120.999413 -285.736761) (xy 120.984085 -285.785057) (xy 120.961549 -285.830439)
			(xy 120.932336 -285.87184) (xy 120.897134 -285.908285) (xy 120.856771 -285.938915) (xy 120.812197 -285.963011)
			(xy 120.764462 -285.980004) (xy 120.739662 -285.985204) (xy 120.716802 -285.989522) (xy 120.511824 -286.344614)
			(xy 120.519698 -286.366458) (xy 120.528349 -286.392865) (xy 120.537666 -286.447642) (xy 120.53824 -286.475424)
			(xy 121.758456 -286.475424) (xy 121.758954 -286.450079) (xy 121.766723 -286.399987) (xy 121.782068 -286.351675)
			(xy 121.804626 -286.306281) (xy 121.833866 -286.264873) (xy 121.869099 -286.228429) (xy 121.909494 -286.197807)
			(xy 121.9541 -286.173728) (xy 122.001866 -286.156759) (xy 122.02668 -286.151574) (xy 122.04954 -286.147256)
			(xy 122.254518 -285.792164) (xy 122.246644 -285.77032) (xy 122.238071 -285.743899) (xy 122.22887 -285.689126)
			(xy 122.228356 -285.661354) (xy 122.228864 -285.635467) (xy 122.236963 -285.584329) (xy 122.252962 -285.535089)
			(xy 122.276468 -285.488957) (xy 122.3069 -285.44707) (xy 122.34351 -285.41046) (xy 122.385397 -285.380028)
			(xy 122.431529 -285.356522) (xy 122.480769 -285.340523) (xy 122.531907 -285.332424) (xy 122.583681 -285.332424)
			(xy 122.634819 -285.340523) (xy 122.684059 -285.356522) (xy 122.730191 -285.380028) (xy 122.772078 -285.41046)
			(xy 122.808688 -285.44707) (xy 122.83912 -285.488957) (xy 122.862626 -285.535089) (xy 122.878625 -285.584329)
			(xy 122.886724 -285.635467) (xy 122.887232 -285.661354) (xy 122.886772 -285.686689) (xy 122.879013 -285.736761)
			(xy 122.863685 -285.785057) (xy 122.841149 -285.830439) (xy 122.811936 -285.87184) (xy 122.776734 -285.908285)
			(xy 122.736371 -285.938915) (xy 122.691797 -285.963011) (xy 122.644062 -285.980004) (xy 122.619262 -285.985204)
			(xy 122.596402 -285.989522) (xy 122.391424 -286.344614) (xy 122.399298 -286.366458) (xy 122.407949 -286.392865)
			(xy 122.417266 -286.447642) (xy 122.41784 -286.475424) (xy 123.638056 -286.475424) (xy 123.638554 -286.450079)
			(xy 123.646323 -286.399987) (xy 123.661668 -286.351675) (xy 123.684226 -286.306281) (xy 123.713466 -286.264873)
			(xy 123.748699 -286.228429) (xy 123.789094 -286.197807) (xy 123.8337 -286.173728) (xy 123.881466 -286.156759)
			(xy 123.90628 -286.151574) (xy 123.92914 -286.147256) (xy 124.134118 -285.792164) (xy 124.126244 -285.77032)
			(xy 124.117671 -285.743899) (xy 124.10847 -285.689126) (xy 124.107956 -285.661354) (xy 124.108464 -285.635467)
			(xy 124.116563 -285.584329) (xy 124.132562 -285.535089) (xy 124.156068 -285.488957) (xy 124.1865 -285.44707)
			(xy 124.22311 -285.41046) (xy 124.264997 -285.380028) (xy 124.311129 -285.356522) (xy 124.360369 -285.340523)
			(xy 124.411507 -285.332424) (xy 124.463281 -285.332424) (xy 124.514419 -285.340523) (xy 124.563659 -285.356522)
			(xy 124.609791 -285.380028) (xy 124.651678 -285.41046) (xy 124.688288 -285.44707) (xy 124.71872 -285.488957)
			(xy 124.742226 -285.535089) (xy 124.758225 -285.584329) (xy 124.766324 -285.635467) (xy 124.766832 -285.661354)
			(xy 124.766372 -285.686689) (xy 124.758613 -285.736761) (xy 124.743285 -285.785057) (xy 124.720749 -285.830439)
			(xy 124.691536 -285.87184) (xy 124.656334 -285.908285) (xy 124.615971 -285.938915) (xy 124.571397 -285.963011)
			(xy 124.523662 -285.980004) (xy 124.498862 -285.985204) (xy 124.476002 -285.989522) (xy 124.271024 -286.344614)
			(xy 124.278898 -286.366458) (xy 124.287549 -286.392865) (xy 124.296866 -286.447642) (xy 124.29744 -286.475424)
			(xy 125.517656 -286.475424) (xy 125.518154 -286.450079) (xy 125.525923 -286.399987) (xy 125.541268 -286.351675)
			(xy 125.563826 -286.306281) (xy 125.593066 -286.264873) (xy 125.628299 -286.228429) (xy 125.668694 -286.197807)
			(xy 125.7133 -286.173728) (xy 125.761066 -286.156759) (xy 125.78588 -286.151574) (xy 125.80874 -286.147256)
			(xy 126.013718 -285.792164) (xy 126.005844 -285.77032) (xy 125.997271 -285.743899) (xy 125.98807 -285.689126)
			(xy 125.987556 -285.661354) (xy 125.988064 -285.635467) (xy 125.996163 -285.584329) (xy 126.012162 -285.535089)
			(xy 126.035668 -285.488957) (xy 126.0661 -285.44707) (xy 126.10271 -285.41046) (xy 126.144597 -285.380028)
			(xy 126.190729 -285.356522) (xy 126.239969 -285.340523) (xy 126.291107 -285.332424) (xy 126.342881 -285.332424)
			(xy 126.394019 -285.340523) (xy 126.443259 -285.356522) (xy 126.489391 -285.380028) (xy 126.531278 -285.41046)
			(xy 126.567888 -285.44707) (xy 126.59832 -285.488957) (xy 126.621826 -285.535089) (xy 126.637825 -285.584329)
			(xy 126.645924 -285.635467) (xy 126.646432 -285.661354) (xy 126.645972 -285.686689) (xy 126.638213 -285.736761)
			(xy 126.622885 -285.785057) (xy 126.600349 -285.830439) (xy 126.571136 -285.87184) (xy 126.535934 -285.908285)
			(xy 126.495571 -285.938915) (xy 126.450997 -285.963011) (xy 126.403262 -285.980004) (xy 126.378462 -285.985204)
			(xy 126.355602 -285.989522) (xy 126.150624 -286.344614) (xy 126.158498 -286.366458) (xy 126.167149 -286.392865)
			(xy 126.176466 -286.447642) (xy 126.17704 -286.475424) (xy 127.397256 -286.475424) (xy 127.397754 -286.450079)
			(xy 127.405523 -286.399987) (xy 127.420868 -286.351675) (xy 127.443426 -286.306281) (xy 127.472666 -286.264873)
			(xy 127.507899 -286.228429) (xy 127.548294 -286.197807) (xy 127.5929 -286.173728) (xy 127.640666 -286.156759)
			(xy 127.66548 -286.151574) (xy 127.68834 -286.147256) (xy 127.893318 -285.792164) (xy 127.885444 -285.77032)
			(xy 127.876871 -285.743899) (xy 127.86767 -285.689126) (xy 127.867156 -285.661354) (xy 127.867664 -285.635467)
			(xy 127.875763 -285.584329) (xy 127.891762 -285.535089) (xy 127.915268 -285.488957) (xy 127.9457 -285.44707)
			(xy 127.98231 -285.41046) (xy 128.024197 -285.380028) (xy 128.070329 -285.356522) (xy 128.119569 -285.340523)
			(xy 128.170707 -285.332424) (xy 128.222481 -285.332424) (xy 128.273619 -285.340523) (xy 128.322859 -285.356522)
			(xy 128.368991 -285.380028) (xy 128.410878 -285.41046) (xy 128.447488 -285.44707) (xy 128.47792 -285.488957)
			(xy 128.501426 -285.535089) (xy 128.517425 -285.584329) (xy 128.525524 -285.635467) (xy 128.526032 -285.661354)
			(xy 128.525572 -285.686689) (xy 128.517813 -285.736761) (xy 128.502485 -285.785057) (xy 128.479949 -285.830439)
			(xy 128.450736 -285.87184) (xy 128.415534 -285.908285) (xy 128.375171 -285.938915) (xy 128.330597 -285.963011)
			(xy 128.282862 -285.980004) (xy 128.258062 -285.985204) (xy 128.235202 -285.989522) (xy 128.030224 -286.344614)
			(xy 128.038098 -286.366458) (xy 128.046749 -286.392865) (xy 128.056066 -286.447642) (xy 128.05664 -286.475424)
			(xy 129.276856 -286.475424) (xy 129.277354 -286.450079) (xy 129.285123 -286.399987) (xy 129.300468 -286.351675)
			(xy 129.323026 -286.306281) (xy 129.352266 -286.264873) (xy 129.387499 -286.228429) (xy 129.427894 -286.197807)
			(xy 129.4725 -286.173728) (xy 129.520266 -286.156759) (xy 129.54508 -286.151574) (xy 129.56794 -286.147256)
			(xy 129.772918 -285.792164) (xy 129.765044 -285.77032) (xy 129.756471 -285.743899) (xy 129.74727 -285.689126)
			(xy 129.746756 -285.661354) (xy 129.747264 -285.635467) (xy 129.755363 -285.584329) (xy 129.771362 -285.535089)
			(xy 129.794868 -285.488957) (xy 129.8253 -285.44707) (xy 129.86191 -285.41046) (xy 129.903797 -285.380028)
			(xy 129.949929 -285.356522) (xy 129.999169 -285.340523) (xy 130.050307 -285.332424) (xy 130.102081 -285.332424)
			(xy 130.153219 -285.340523) (xy 130.202459 -285.356522) (xy 130.248591 -285.380028) (xy 130.290478 -285.41046)
			(xy 130.327088 -285.44707) (xy 130.35752 -285.488957) (xy 130.381026 -285.535089) (xy 130.397025 -285.584329)
			(xy 130.405124 -285.635467) (xy 130.405632 -285.661354) (xy 130.405172 -285.686689) (xy 130.397413 -285.736761)
			(xy 130.382085 -285.785057) (xy 130.359549 -285.830439) (xy 130.330336 -285.87184) (xy 130.295134 -285.908285)
			(xy 130.254771 -285.938915) (xy 130.210197 -285.963011) (xy 130.162462 -285.980004) (xy 130.137662 -285.985204)
			(xy 130.114802 -285.989522) (xy 129.909824 -286.344614) (xy 129.917698 -286.366458) (xy 129.926349 -286.392865)
			(xy 129.935666 -286.447642) (xy 129.93624 -286.475424) (xy 131.156456 -286.475424) (xy 131.156954 -286.450079)
			(xy 131.164723 -286.399987) (xy 131.180068 -286.351675) (xy 131.202626 -286.306281) (xy 131.231866 -286.264873)
			(xy 131.267099 -286.228429) (xy 131.307494 -286.197807) (xy 131.3521 -286.173728) (xy 131.399866 -286.156759)
			(xy 131.42468 -286.151574) (xy 131.44754 -286.147256) (xy 131.652518 -285.792164) (xy 131.644644 -285.77032)
			(xy 131.636071 -285.743899) (xy 131.62687 -285.689126) (xy 131.626356 -285.661354) (xy 131.626864 -285.635467)
			(xy 131.634963 -285.584329) (xy 131.650962 -285.535089) (xy 131.674468 -285.488957) (xy 131.7049 -285.44707)
			(xy 131.74151 -285.41046) (xy 131.783397 -285.380028) (xy 131.829529 -285.356522) (xy 131.878769 -285.340523)
			(xy 131.929907 -285.332424) (xy 131.981681 -285.332424) (xy 132.032819 -285.340523) (xy 132.082059 -285.356522)
			(xy 132.128191 -285.380028) (xy 132.170078 -285.41046) (xy 132.206688 -285.44707) (xy 132.23712 -285.488957)
			(xy 132.260626 -285.535089) (xy 132.276625 -285.584329) (xy 132.284724 -285.635467) (xy 132.285232 -285.661354)
			(xy 132.284772 -285.686689) (xy 132.277013 -285.736761) (xy 132.261685 -285.785057) (xy 132.239149 -285.830439)
			(xy 132.209936 -285.87184) (xy 132.174734 -285.908285) (xy 132.134371 -285.938915) (xy 132.089797 -285.963011)
			(xy 132.042062 -285.980004) (xy 132.017262 -285.985204) (xy 131.994402 -285.989522) (xy 131.789424 -286.344614)
			(xy 131.797298 -286.366458) (xy 131.805949 -286.392865) (xy 131.815266 -286.447642) (xy 131.81584 -286.475424)
			(xy 133.036056 -286.475424) (xy 133.036554 -286.450079) (xy 133.044323 -286.399987) (xy 133.059668 -286.351675)
			(xy 133.082226 -286.306281) (xy 133.111466 -286.264873) (xy 133.146699 -286.228429) (xy 133.187094 -286.197807)
			(xy 133.2317 -286.173728) (xy 133.279466 -286.156759) (xy 133.30428 -286.151574) (xy 133.32714 -286.147256)
			(xy 133.532118 -285.792164) (xy 133.524244 -285.77032) (xy 133.515671 -285.743899) (xy 133.50647 -285.689126)
			(xy 133.505956 -285.661354) (xy 133.506464 -285.635467) (xy 133.514563 -285.584329) (xy 133.530562 -285.535089)
			(xy 133.554068 -285.488957) (xy 133.5845 -285.44707) (xy 133.62111 -285.41046) (xy 133.662997 -285.380028)
			(xy 133.709129 -285.356522) (xy 133.758369 -285.340523) (xy 133.809507 -285.332424) (xy 133.861281 -285.332424)
			(xy 133.912419 -285.340523) (xy 133.961659 -285.356522) (xy 134.007791 -285.380028) (xy 134.049678 -285.41046)
			(xy 134.086288 -285.44707) (xy 134.11672 -285.488957) (xy 134.140226 -285.535089) (xy 134.156225 -285.584329)
			(xy 134.164324 -285.635467) (xy 134.164832 -285.661354) (xy 337.275424 -285.661354) (xy 337.275932 -285.635467)
			(xy 337.284031 -285.584329) (xy 337.30003 -285.535089) (xy 337.323536 -285.488957) (xy 337.353968 -285.44707)
			(xy 337.390578 -285.41046) (xy 337.432465 -285.380028) (xy 337.478597 -285.356522) (xy 337.527837 -285.340523)
			(xy 337.578975 -285.332424) (xy 337.630749 -285.332424) (xy 337.681887 -285.340523) (xy 337.731127 -285.356522)
			(xy 337.777259 -285.380028) (xy 337.819146 -285.41046) (xy 337.855756 -285.44707) (xy 337.886188 -285.488957)
			(xy 337.909694 -285.535089) (xy 337.925693 -285.584329) (xy 337.933792 -285.635467) (xy 337.9343 -285.661354)
			(xy 338.215224 -285.661354) (xy 338.215684 -285.636008) (xy 338.223463 -285.585916) (xy 338.238816 -285.537605)
			(xy 338.26138 -285.492212) (xy 338.290625 -285.450806) (xy 338.325861 -285.414363) (xy 338.366259 -285.383741)
			(xy 338.410867 -285.359661) (xy 338.458634 -285.34269) (xy 338.483448 -285.337504) (xy 338.506308 -285.333186)
			(xy 338.711286 -284.978348) (xy 338.703412 -284.956504) (xy 338.694834 -284.930085) (xy 338.685636 -284.87531)
			(xy 338.685124 -284.847538) (xy 338.685632 -284.821651) (xy 338.693731 -284.770513) (xy 338.70973 -284.721273)
			(xy 338.733236 -284.675141) (xy 338.763668 -284.633254) (xy 338.800278 -284.596644) (xy 338.842165 -284.566212)
			(xy 338.888297 -284.542706) (xy 338.937537 -284.526707) (xy 338.988675 -284.518608) (xy 339.040449 -284.518608)
			(xy 339.091587 -284.526707) (xy 339.140827 -284.542706) (xy 339.186959 -284.566212) (xy 339.228846 -284.596644)
			(xy 339.265456 -284.633254) (xy 339.295888 -284.675141) (xy 339.319394 -284.721273) (xy 339.335393 -284.770513)
			(xy 339.343492 -284.821651) (xy 339.344 -284.847538) (xy 339.343552 -284.872874) (xy 339.335794 -284.922948)
			(xy 339.320466 -284.971245) (xy 339.29793 -285.016629) (xy 339.268716 -285.058031) (xy 339.233511 -285.094476)
			(xy 339.193146 -285.125106) (xy 339.148569 -285.149199) (xy 339.100831 -285.16619) (xy 339.07603 -285.171388)
			(xy 339.05317 -285.175706) (xy 338.848192 -285.530544) (xy 338.856066 -285.552642) (xy 338.86469 -285.578991)
			(xy 338.874015 -285.633637) (xy 338.874608 -285.661354) (xy 339.155024 -285.661354) (xy 339.155532 -285.635447)
			(xy 339.163638 -285.58427) (xy 339.17965 -285.534991) (xy 339.203173 -285.488824) (xy 339.233629 -285.446905)
			(xy 339.270267 -285.410267) (xy 339.312186 -285.379811) (xy 339.358353 -285.356288) (xy 339.407632 -285.340276)
			(xy 339.458809 -285.33217) (xy 339.510623 -285.33217) (xy 339.5618 -285.340276) (xy 339.611079 -285.356288)
			(xy 339.657246 -285.379811) (xy 339.699165 -285.410267) (xy 339.735803 -285.446905) (xy 339.766259 -285.488824)
			(xy 339.789782 -285.534991) (xy 339.805794 -285.58427) (xy 339.8139 -285.635447) (xy 339.814408 -285.661354)
			(xy 340.094824 -285.661354) (xy 340.095245 -285.636017) (xy 340.103005 -285.585941) (xy 340.118335 -285.537642)
			(xy 340.140875 -285.492257) (xy 340.170092 -285.450854) (xy 340.2053 -285.41441) (xy 340.24567 -285.383781)
			(xy 340.29025 -285.359689) (xy 340.337992 -285.342701) (xy 340.362794 -285.337504) (xy 340.385654 -285.333186)
			(xy 340.590886 -284.97784) (xy 340.583266 -284.955996) (xy 340.574644 -284.929713) (xy 340.565327 -284.875193)
			(xy 340.564724 -284.847538) (xy 340.565232 -284.821631) (xy 340.573338 -284.770454) (xy 340.58935 -284.721175)
			(xy 340.612873 -284.675008) (xy 340.643329 -284.633089) (xy 340.679967 -284.596451) (xy 340.721886 -284.565995)
			(xy 340.768053 -284.542472) (xy 340.817332 -284.52646) (xy 340.868509 -284.518354) (xy 340.920323 -284.518354)
			(xy 340.9715 -284.52646) (xy 341.020779 -284.542472) (xy 341.066946 -284.565995) (xy 341.108865 -284.596451)
			(xy 341.145503 -284.633089) (xy 341.175959 -284.675008) (xy 341.199482 -284.721175) (xy 341.215494 -284.770454)
			(xy 341.2236 -284.821631) (xy 341.224108 -284.847538) (xy 341.223661 -284.872913) (xy 341.215887 -284.923064)
			(xy 341.200514 -284.97143) (xy 341.177905 -285.016866) (xy 341.148596 -285.058297) (xy 341.113279 -285.094742)
			(xy 341.072791 -285.125341) (xy 341.028089 -285.149367) (xy 340.980231 -285.166254) (xy 340.955376 -285.171388)
			(xy 340.932516 -285.175706) (xy 340.727538 -285.530544) (xy 340.735412 -285.552642) (xy 340.743983 -285.578997)
			(xy 340.753175 -285.633645) (xy 340.7537 -285.661354) (xy 341.034624 -285.661354) (xy 341.035132 -285.635467)
			(xy 341.043231 -285.584329) (xy 341.05923 -285.535089) (xy 341.082736 -285.488957) (xy 341.113168 -285.44707)
			(xy 341.149778 -285.41046) (xy 341.191665 -285.380028) (xy 341.237797 -285.356522) (xy 341.287037 -285.340523)
			(xy 341.338175 -285.332424) (xy 341.389949 -285.332424) (xy 341.441087 -285.340523) (xy 341.490327 -285.356522)
			(xy 341.536459 -285.380028) (xy 341.578346 -285.41046) (xy 341.614956 -285.44707) (xy 341.645388 -285.488957)
			(xy 341.668894 -285.535089) (xy 341.684893 -285.584329) (xy 341.692992 -285.635467) (xy 341.6935 -285.661354)
			(xy 341.974424 -285.661354) (xy 341.974845 -285.636017) (xy 341.982605 -285.585941) (xy 341.997935 -285.537642)
			(xy 342.020475 -285.492257) (xy 342.049692 -285.450854) (xy 342.0849 -285.41441) (xy 342.12527 -285.383781)
			(xy 342.16985 -285.359689) (xy 342.217592 -285.342701) (xy 342.242394 -285.337504) (xy 342.265254 -285.333186)
			(xy 342.470486 -284.97784) (xy 342.462866 -284.955996) (xy 342.454244 -284.929713) (xy 342.444927 -284.875193)
			(xy 342.444324 -284.847538) (xy 342.444832 -284.821631) (xy 342.452938 -284.770454) (xy 342.46895 -284.721175)
			(xy 342.492473 -284.675008) (xy 342.522929 -284.633089) (xy 342.559567 -284.596451) (xy 342.601486 -284.565995)
			(xy 342.647653 -284.542472) (xy 342.696932 -284.52646) (xy 342.748109 -284.518354) (xy 342.799923 -284.518354)
			(xy 342.8511 -284.52646) (xy 342.900379 -284.542472) (xy 342.946546 -284.565995) (xy 342.988465 -284.596451)
			(xy 343.025103 -284.633089) (xy 343.055559 -284.675008) (xy 343.079082 -284.721175) (xy 343.095094 -284.770454)
			(xy 343.1032 -284.821631) (xy 343.103708 -284.847538) (xy 343.103261 -284.872913) (xy 343.095487 -284.923064)
			(xy 343.080114 -284.97143) (xy 343.057505 -285.016866) (xy 343.028196 -285.058297) (xy 342.992879 -285.094742)
			(xy 342.952391 -285.125341) (xy 342.907689 -285.149367) (xy 342.859831 -285.166254) (xy 342.834976 -285.171388)
			(xy 342.812116 -285.175706) (xy 342.607138 -285.530544) (xy 342.615012 -285.552642) (xy 342.623583 -285.578997)
			(xy 342.632775 -285.633645) (xy 342.6333 -285.661354) (xy 342.914224 -285.661354) (xy 342.914732 -285.635467)
			(xy 342.922831 -285.584329) (xy 342.93883 -285.535089) (xy 342.962336 -285.488957) (xy 342.992768 -285.44707)
			(xy 343.029378 -285.41046) (xy 343.071265 -285.380028) (xy 343.117397 -285.356522) (xy 343.166637 -285.340523)
			(xy 343.217775 -285.332424) (xy 343.269549 -285.332424) (xy 343.320687 -285.340523) (xy 343.369927 -285.356522)
			(xy 343.416059 -285.380028) (xy 343.457946 -285.41046) (xy 343.494556 -285.44707) (xy 343.524988 -285.488957)
			(xy 343.548494 -285.535089) (xy 343.564493 -285.584329) (xy 343.572592 -285.635467) (xy 343.5731 -285.661354)
			(xy 343.854024 -285.661354) (xy 343.854445 -285.636017) (xy 343.862205 -285.585941) (xy 343.877535 -285.537642)
			(xy 343.900075 -285.492257) (xy 343.929292 -285.450854) (xy 343.9645 -285.41441) (xy 344.00487 -285.383781)
			(xy 344.04945 -285.359689) (xy 344.097192 -285.342701) (xy 344.121994 -285.337504) (xy 344.144854 -285.333186)
			(xy 344.350086 -284.97784) (xy 344.342466 -284.955996) (xy 344.333844 -284.929713) (xy 344.324527 -284.875193)
			(xy 344.323924 -284.847538) (xy 344.324432 -284.821631) (xy 344.332538 -284.770454) (xy 344.34855 -284.721175)
			(xy 344.372073 -284.675008) (xy 344.402529 -284.633089) (xy 344.439167 -284.596451) (xy 344.481086 -284.565995)
			(xy 344.527253 -284.542472) (xy 344.576532 -284.52646) (xy 344.627709 -284.518354) (xy 344.679523 -284.518354)
			(xy 344.7307 -284.52646) (xy 344.779979 -284.542472) (xy 344.826146 -284.565995) (xy 344.868065 -284.596451)
			(xy 344.904703 -284.633089) (xy 344.935159 -284.675008) (xy 344.958682 -284.721175) (xy 344.974694 -284.770454)
			(xy 344.9828 -284.821631) (xy 344.983308 -284.847538) (xy 344.982861 -284.872913) (xy 344.975087 -284.923064)
			(xy 344.959714 -284.97143) (xy 344.937105 -285.016866) (xy 344.907796 -285.058297) (xy 344.872479 -285.094742)
			(xy 344.831991 -285.125341) (xy 344.787289 -285.149367) (xy 344.739431 -285.166254) (xy 344.714576 -285.171388)
			(xy 344.691716 -285.175706) (xy 344.486738 -285.530544) (xy 344.494612 -285.552642) (xy 344.503183 -285.578997)
			(xy 344.512375 -285.633645) (xy 344.5129 -285.661354) (xy 344.793824 -285.661354) (xy 344.794332 -285.635467)
			(xy 344.802431 -285.584329) (xy 344.81843 -285.535089) (xy 344.841936 -285.488957) (xy 344.872368 -285.44707)
			(xy 344.908978 -285.41046) (xy 344.950865 -285.380028) (xy 344.996997 -285.356522) (xy 345.046237 -285.340523)
			(xy 345.097375 -285.332424) (xy 345.149149 -285.332424) (xy 345.200287 -285.340523) (xy 345.249527 -285.356522)
			(xy 345.295659 -285.380028) (xy 345.337546 -285.41046) (xy 345.374156 -285.44707) (xy 345.404588 -285.488957)
			(xy 345.428094 -285.535089) (xy 345.444093 -285.584329) (xy 345.452192 -285.635467) (xy 345.4527 -285.661354)
			(xy 345.733624 -285.661354) (xy 345.734045 -285.636017) (xy 345.741805 -285.585941) (xy 345.757135 -285.537642)
			(xy 345.779675 -285.492257) (xy 345.808892 -285.450854) (xy 345.8441 -285.41441) (xy 345.88447 -285.383781)
			(xy 345.92905 -285.359689) (xy 345.976792 -285.342701) (xy 346.001594 -285.337504) (xy 346.024454 -285.333186)
			(xy 346.229686 -284.97784) (xy 346.222066 -284.955996) (xy 346.213444 -284.929713) (xy 346.204127 -284.875193)
			(xy 346.203524 -284.847538) (xy 346.204032 -284.821631) (xy 346.212138 -284.770454) (xy 346.22815 -284.721175)
			(xy 346.251673 -284.675008) (xy 346.282129 -284.633089) (xy 346.318767 -284.596451) (xy 346.360686 -284.565995)
			(xy 346.406853 -284.542472) (xy 346.456132 -284.52646) (xy 346.507309 -284.518354) (xy 346.559123 -284.518354)
			(xy 346.6103 -284.52646) (xy 346.659579 -284.542472) (xy 346.705746 -284.565995) (xy 346.747665 -284.596451)
			(xy 346.784303 -284.633089) (xy 346.814759 -284.675008) (xy 346.838282 -284.721175) (xy 346.854294 -284.770454)
			(xy 346.8624 -284.821631) (xy 346.862908 -284.847538) (xy 346.862461 -284.872913) (xy 346.854687 -284.923064)
			(xy 346.839314 -284.97143) (xy 346.816705 -285.016866) (xy 346.787396 -285.058297) (xy 346.752079 -285.094742)
			(xy 346.711591 -285.125341) (xy 346.666889 -285.149367) (xy 346.619031 -285.166254) (xy 346.594176 -285.171388)
			(xy 346.571316 -285.175706) (xy 346.366338 -285.530544) (xy 346.374212 -285.552642) (xy 346.382783 -285.578997)
			(xy 346.391975 -285.633645) (xy 346.3925 -285.661354) (xy 346.673424 -285.661354) (xy 346.673932 -285.635467)
			(xy 346.682031 -285.584329) (xy 346.69803 -285.535089) (xy 346.721536 -285.488957) (xy 346.751968 -285.44707)
			(xy 346.788578 -285.41046) (xy 346.830465 -285.380028) (xy 346.876597 -285.356522) (xy 346.925837 -285.340523)
			(xy 346.976975 -285.332424) (xy 347.028749 -285.332424) (xy 347.079887 -285.340523) (xy 347.129127 -285.356522)
			(xy 347.175259 -285.380028) (xy 347.217146 -285.41046) (xy 347.253756 -285.44707) (xy 347.284188 -285.488957)
			(xy 347.307694 -285.535089) (xy 347.323693 -285.584329) (xy 347.331792 -285.635467) (xy 347.3323 -285.661354)
			(xy 347.613224 -285.661354) (xy 347.613645 -285.636017) (xy 347.621405 -285.585941) (xy 347.636735 -285.537642)
			(xy 347.659275 -285.492257) (xy 347.688492 -285.450854) (xy 347.7237 -285.41441) (xy 347.76407 -285.383781)
			(xy 347.80865 -285.359689) (xy 347.856392 -285.342701) (xy 347.881194 -285.337504) (xy 347.904054 -285.333186)
			(xy 348.109286 -284.97784) (xy 348.101666 -284.955996) (xy 348.093044 -284.929713) (xy 348.083727 -284.875193)
			(xy 348.083124 -284.847538) (xy 348.083632 -284.821631) (xy 348.091738 -284.770454) (xy 348.10775 -284.721175)
			(xy 348.131273 -284.675008) (xy 348.161729 -284.633089) (xy 348.198367 -284.596451) (xy 348.240286 -284.565995)
			(xy 348.286453 -284.542472) (xy 348.335732 -284.52646) (xy 348.386909 -284.518354) (xy 348.438723 -284.518354)
			(xy 348.4899 -284.52646) (xy 348.539179 -284.542472) (xy 348.585346 -284.565995) (xy 348.627265 -284.596451)
			(xy 348.663903 -284.633089) (xy 348.694359 -284.675008) (xy 348.717882 -284.721175) (xy 348.733894 -284.770454)
			(xy 348.742 -284.821631) (xy 348.742508 -284.847538) (xy 348.742061 -284.872913) (xy 348.734287 -284.923064)
			(xy 348.718914 -284.97143) (xy 348.696305 -285.016866) (xy 348.666996 -285.058297) (xy 348.631679 -285.094742)
			(xy 348.591191 -285.125341) (xy 348.546489 -285.149367) (xy 348.498631 -285.166254) (xy 348.473776 -285.171388)
			(xy 348.450916 -285.175706) (xy 348.245938 -285.530544) (xy 348.253812 -285.552642) (xy 348.262383 -285.578997)
			(xy 348.271575 -285.633645) (xy 348.2721 -285.661354) (xy 348.553024 -285.661354) (xy 348.553532 -285.635467)
			(xy 348.561631 -285.584329) (xy 348.57763 -285.535089) (xy 348.601136 -285.488957) (xy 348.631568 -285.44707)
			(xy 348.668178 -285.41046) (xy 348.710065 -285.380028) (xy 348.756197 -285.356522) (xy 348.805437 -285.340523)
			(xy 348.856575 -285.332424) (xy 348.908349 -285.332424) (xy 348.959487 -285.340523) (xy 349.008727 -285.356522)
			(xy 349.054859 -285.380028) (xy 349.096746 -285.41046) (xy 349.133356 -285.44707) (xy 349.163788 -285.488957)
			(xy 349.187294 -285.535089) (xy 349.203293 -285.584329) (xy 349.211392 -285.635467) (xy 349.2119 -285.661354)
			(xy 349.492824 -285.661354) (xy 349.493245 -285.636017) (xy 349.501005 -285.585941) (xy 349.516335 -285.537642)
			(xy 349.538875 -285.492257) (xy 349.568092 -285.450854) (xy 349.6033 -285.41441) (xy 349.64367 -285.383781)
			(xy 349.68825 -285.359689) (xy 349.735992 -285.342701) (xy 349.760794 -285.337504) (xy 349.783654 -285.333186)
			(xy 349.988886 -284.97784) (xy 349.981266 -284.955996) (xy 349.972644 -284.929713) (xy 349.963327 -284.875193)
			(xy 349.962724 -284.847538) (xy 349.963232 -284.821631) (xy 349.971338 -284.770454) (xy 349.98735 -284.721175)
			(xy 350.010873 -284.675008) (xy 350.041329 -284.633089) (xy 350.077967 -284.596451) (xy 350.119886 -284.565995)
			(xy 350.166053 -284.542472) (xy 350.215332 -284.52646) (xy 350.266509 -284.518354) (xy 350.318323 -284.518354)
			(xy 350.3695 -284.52646) (xy 350.418779 -284.542472) (xy 350.464946 -284.565995) (xy 350.506865 -284.596451)
			(xy 350.543503 -284.633089) (xy 350.573959 -284.675008) (xy 350.597482 -284.721175) (xy 350.613494 -284.770454)
			(xy 350.6216 -284.821631) (xy 350.622108 -284.847538) (xy 350.621661 -284.872913) (xy 350.613887 -284.923064)
			(xy 350.598514 -284.97143) (xy 350.575905 -285.016866) (xy 350.546596 -285.058297) (xy 350.511279 -285.094742)
			(xy 350.470791 -285.125341) (xy 350.426089 -285.149367) (xy 350.378231 -285.166254) (xy 350.353376 -285.171388)
			(xy 350.330516 -285.175706) (xy 350.125538 -285.530544) (xy 350.133412 -285.552642) (xy 350.141983 -285.578997)
			(xy 350.151175 -285.633645) (xy 350.1517 -285.661354) (xy 350.432624 -285.661354) (xy 350.433132 -285.635467)
			(xy 350.441231 -285.584329) (xy 350.45723 -285.535089) (xy 350.480736 -285.488957) (xy 350.511168 -285.44707)
			(xy 350.547778 -285.41046) (xy 350.589665 -285.380028) (xy 350.635797 -285.356522) (xy 350.685037 -285.340523)
			(xy 350.736175 -285.332424) (xy 350.787949 -285.332424) (xy 350.839087 -285.340523) (xy 350.888327 -285.356522)
			(xy 350.934459 -285.380028) (xy 350.976346 -285.41046) (xy 351.012956 -285.44707) (xy 351.043388 -285.488957)
			(xy 351.066894 -285.535089) (xy 351.082893 -285.584329) (xy 351.090992 -285.635467) (xy 351.0915 -285.661354)
			(xy 351.372424 -285.661354) (xy 351.372845 -285.636017) (xy 351.380605 -285.585941) (xy 351.395935 -285.537642)
			(xy 351.418475 -285.492257) (xy 351.447692 -285.450854) (xy 351.4829 -285.41441) (xy 351.52327 -285.383781)
			(xy 351.56785 -285.359689) (xy 351.615592 -285.342701) (xy 351.640394 -285.337504) (xy 351.663254 -285.333186)
			(xy 351.868486 -284.97784) (xy 351.860866 -284.955996) (xy 351.852244 -284.929713) (xy 351.842927 -284.875193)
			(xy 351.842324 -284.847538) (xy 351.842832 -284.821631) (xy 351.850938 -284.770454) (xy 351.86695 -284.721175)
			(xy 351.890473 -284.675008) (xy 351.920929 -284.633089) (xy 351.957567 -284.596451) (xy 351.999486 -284.565995)
			(xy 352.045653 -284.542472) (xy 352.094932 -284.52646) (xy 352.146109 -284.518354) (xy 352.197923 -284.518354)
			(xy 352.2491 -284.52646) (xy 352.298379 -284.542472) (xy 352.344546 -284.565995) (xy 352.386465 -284.596451)
			(xy 352.423103 -284.633089) (xy 352.453559 -284.675008) (xy 352.477082 -284.721175) (xy 352.493094 -284.770454)
			(xy 352.5012 -284.821631) (xy 352.501708 -284.847538) (xy 366.879124 -284.847538) (xy 366.879632 -284.821631)
			(xy 366.887738 -284.770454) (xy 366.90375 -284.721175) (xy 366.927273 -284.675008) (xy 366.957729 -284.633089)
			(xy 366.994367 -284.596451) (xy 367.036286 -284.565995) (xy 367.082453 -284.542472) (xy 367.131732 -284.52646)
			(xy 367.182909 -284.518354) (xy 367.234723 -284.518354) (xy 367.2859 -284.52646) (xy 367.335179 -284.542472)
			(xy 367.381346 -284.565995) (xy 367.423265 -284.596451) (xy 367.459903 -284.633089) (xy 367.490359 -284.675008)
			(xy 367.513882 -284.721175) (xy 367.529894 -284.770454) (xy 367.538 -284.821631) (xy 367.538508 -284.847538)
			(xy 368.758724 -284.847538) (xy 368.759232 -284.821631) (xy 368.767338 -284.770454) (xy 368.78335 -284.721175)
			(xy 368.806873 -284.675008) (xy 368.837329 -284.633089) (xy 368.873967 -284.596451) (xy 368.915886 -284.565995)
			(xy 368.962053 -284.542472) (xy 369.011332 -284.52646) (xy 369.062509 -284.518354) (xy 369.114323 -284.518354)
			(xy 369.1655 -284.52646) (xy 369.214779 -284.542472) (xy 369.260946 -284.565995) (xy 369.302865 -284.596451)
			(xy 369.339503 -284.633089) (xy 369.369959 -284.675008) (xy 369.393482 -284.721175) (xy 369.409494 -284.770454)
			(xy 369.4176 -284.821631) (xy 369.418108 -284.847538) (xy 370.638324 -284.847538) (xy 370.638832 -284.821631)
			(xy 370.646938 -284.770454) (xy 370.66295 -284.721175) (xy 370.686473 -284.675008) (xy 370.716929 -284.633089)
			(xy 370.753567 -284.596451) (xy 370.795486 -284.565995) (xy 370.841653 -284.542472) (xy 370.890932 -284.52646)
			(xy 370.942109 -284.518354) (xy 370.993923 -284.518354) (xy 371.0451 -284.52646) (xy 371.094379 -284.542472)
			(xy 371.140546 -284.565995) (xy 371.182465 -284.596451) (xy 371.219103 -284.633089) (xy 371.249559 -284.675008)
			(xy 371.273082 -284.721175) (xy 371.289094 -284.770454) (xy 371.2972 -284.821631) (xy 371.297708 -284.847538)
			(xy 372.517924 -284.847538) (xy 372.518432 -284.821631) (xy 372.526538 -284.770454) (xy 372.54255 -284.721175)
			(xy 372.566073 -284.675008) (xy 372.596529 -284.633089) (xy 372.633167 -284.596451) (xy 372.675086 -284.565995)
			(xy 372.721253 -284.542472) (xy 372.770532 -284.52646) (xy 372.821709 -284.518354) (xy 372.873523 -284.518354)
			(xy 372.9247 -284.52646) (xy 372.973979 -284.542472) (xy 373.020146 -284.565995) (xy 373.062065 -284.596451)
			(xy 373.098703 -284.633089) (xy 373.129159 -284.675008) (xy 373.152682 -284.721175) (xy 373.168694 -284.770454)
			(xy 373.1768 -284.821631) (xy 373.177308 -284.847538) (xy 374.397524 -284.847538) (xy 374.398032 -284.821631)
			(xy 374.406138 -284.770454) (xy 374.42215 -284.721175) (xy 374.445673 -284.675008) (xy 374.476129 -284.633089)
			(xy 374.512767 -284.596451) (xy 374.554686 -284.565995) (xy 374.600853 -284.542472) (xy 374.650132 -284.52646)
			(xy 374.701309 -284.518354) (xy 374.753123 -284.518354) (xy 374.8043 -284.52646) (xy 374.853579 -284.542472)
			(xy 374.899746 -284.565995) (xy 374.941665 -284.596451) (xy 374.978303 -284.633089) (xy 375.008759 -284.675008)
			(xy 375.032282 -284.721175) (xy 375.048294 -284.770454) (xy 375.0564 -284.821631) (xy 375.056908 -284.847538)
			(xy 376.277124 -284.847538) (xy 376.277632 -284.821631) (xy 376.285738 -284.770454) (xy 376.30175 -284.721175)
			(xy 376.325273 -284.675008) (xy 376.355729 -284.633089) (xy 376.392367 -284.596451) (xy 376.434286 -284.565995)
			(xy 376.480453 -284.542472) (xy 376.529732 -284.52646) (xy 376.580909 -284.518354) (xy 376.632723 -284.518354)
			(xy 376.6839 -284.52646) (xy 376.733179 -284.542472) (xy 376.779346 -284.565995) (xy 376.821265 -284.596451)
			(xy 376.857903 -284.633089) (xy 376.888359 -284.675008) (xy 376.911882 -284.721175) (xy 376.927894 -284.770454)
			(xy 376.936 -284.821631) (xy 376.936508 -284.847538) (xy 378.156724 -284.847538) (xy 378.157232 -284.821631)
			(xy 378.165338 -284.770454) (xy 378.18135 -284.721175) (xy 378.204873 -284.675008) (xy 378.235329 -284.633089)
			(xy 378.271967 -284.596451) (xy 378.313886 -284.565995) (xy 378.360053 -284.542472) (xy 378.409332 -284.52646)
			(xy 378.460509 -284.518354) (xy 378.512323 -284.518354) (xy 378.5635 -284.52646) (xy 378.612779 -284.542472)
			(xy 378.658946 -284.565995) (xy 378.700865 -284.596451) (xy 378.737503 -284.633089) (xy 378.767959 -284.675008)
			(xy 378.791482 -284.721175) (xy 378.807494 -284.770454) (xy 378.8156 -284.821631) (xy 378.816108 -284.847538)
			(xy 380.036324 -284.847538) (xy 380.036832 -284.821631) (xy 380.044938 -284.770454) (xy 380.06095 -284.721175)
			(xy 380.084473 -284.675008) (xy 380.114929 -284.633089) (xy 380.151567 -284.596451) (xy 380.193486 -284.565995)
			(xy 380.239653 -284.542472) (xy 380.288932 -284.52646) (xy 380.340109 -284.518354) (xy 380.391923 -284.518354)
			(xy 380.4431 -284.52646) (xy 380.492379 -284.542472) (xy 380.538546 -284.565995) (xy 380.580465 -284.596451)
			(xy 380.617103 -284.633089) (xy 380.647559 -284.675008) (xy 380.671082 -284.721175) (xy 380.687094 -284.770454)
			(xy 380.6952 -284.821631) (xy 380.695708 -284.847538) (xy 380.695098 -284.875255) (xy 380.685785 -284.929901)
			(xy 380.677166 -284.95625) (xy 380.669292 -284.978348) (xy 380.87427 -285.333186) (xy 380.89713 -285.337504)
			(xy 380.921947 -285.342634) (xy 380.969689 -285.35963) (xy 381.014267 -285.383731) (xy 381.054634 -285.414369)
			(xy 381.089836 -285.450823) (xy 381.119046 -285.492235) (xy 381.141576 -285.537628) (xy 381.156894 -285.585934)
			(xy 381.16464 -285.636016) (xy 381.1651 -285.661354) (xy 381.164592 -285.687241) (xy 381.156493 -285.738379)
			(xy 381.140494 -285.787619) (xy 381.116988 -285.833751) (xy 381.086556 -285.875638) (xy 381.049946 -285.912248)
			(xy 381.008059 -285.94268) (xy 380.961927 -285.966186) (xy 380.912687 -285.982185) (xy 380.861549 -285.990284)
			(xy 380.809775 -285.990284) (xy 380.758637 -285.982185) (xy 380.709397 -285.966186) (xy 380.663265 -285.94268)
			(xy 380.621378 -285.912248) (xy 380.584768 -285.875638) (xy 380.554336 -285.833751) (xy 380.53083 -285.787619)
			(xy 380.514831 -285.738379) (xy 380.506732 -285.687241) (xy 380.506224 -285.661354) (xy 380.506766 -285.633646)
			(xy 380.515953 -285.579) (xy 380.524512 -285.552642) (xy 380.532386 -285.530544) (xy 380.327408 -285.175706)
			(xy 380.304548 -285.171388) (xy 380.279723 -285.166238) (xy 380.231943 -285.149282) (xy 380.187323 -285.125209)
			(xy 380.146916 -285.094586) (xy 380.111675 -285.058137) (xy 380.082431 -285.016721) (xy 380.059876 -284.971315)
			(xy 380.044539 -284.922991) (xy 380.036785 -284.872888) (xy 380.036324 -284.847538) (xy 378.816108 -284.847538)
			(xy 378.815498 -284.875255) (xy 378.806185 -284.929901) (xy 378.797566 -284.95625) (xy 378.789692 -284.978348)
			(xy 378.99467 -285.333186) (xy 379.01753 -285.337504) (xy 379.042347 -285.342634) (xy 379.090089 -285.35963)
			(xy 379.134667 -285.383731) (xy 379.175034 -285.414369) (xy 379.210236 -285.450823) (xy 379.239446 -285.492235)
			(xy 379.261976 -285.537628) (xy 379.277294 -285.585934) (xy 379.28504 -285.636016) (xy 379.2855 -285.661354)
			(xy 379.284992 -285.687241) (xy 379.276893 -285.738379) (xy 379.260894 -285.787619) (xy 379.237388 -285.833751)
			(xy 379.206956 -285.875638) (xy 379.170346 -285.912248) (xy 379.128459 -285.94268) (xy 379.082327 -285.966186)
			(xy 379.033087 -285.982185) (xy 378.981949 -285.990284) (xy 378.930175 -285.990284) (xy 378.879037 -285.982185)
			(xy 378.829797 -285.966186) (xy 378.783665 -285.94268) (xy 378.741778 -285.912248) (xy 378.705168 -285.875638)
			(xy 378.674736 -285.833751) (xy 378.65123 -285.787619) (xy 378.635231 -285.738379) (xy 378.627132 -285.687241)
			(xy 378.626624 -285.661354) (xy 378.627166 -285.633646) (xy 378.636353 -285.579) (xy 378.644912 -285.552642)
			(xy 378.652786 -285.530544) (xy 378.447808 -285.175706) (xy 378.424948 -285.171388) (xy 378.400123 -285.166238)
			(xy 378.352343 -285.149282) (xy 378.307723 -285.125209) (xy 378.267316 -285.094586) (xy 378.232075 -285.058137)
			(xy 378.202831 -285.016721) (xy 378.180276 -284.971315) (xy 378.164939 -284.922991) (xy 378.157185 -284.872888)
			(xy 378.156724 -284.847538) (xy 376.936508 -284.847538) (xy 376.935898 -284.875255) (xy 376.926585 -284.929901)
			(xy 376.917966 -284.95625) (xy 376.910092 -284.978348) (xy 377.11507 -285.333186) (xy 377.13793 -285.337504)
			(xy 377.162747 -285.342634) (xy 377.210489 -285.35963) (xy 377.255067 -285.383731) (xy 377.295434 -285.414369)
			(xy 377.330636 -285.450823) (xy 377.359846 -285.492235) (xy 377.382376 -285.537628) (xy 377.397694 -285.585934)
			(xy 377.40544 -285.636016) (xy 377.4059 -285.661354) (xy 377.405392 -285.687241) (xy 377.397293 -285.738379)
			(xy 377.381294 -285.787619) (xy 377.357788 -285.833751) (xy 377.327356 -285.875638) (xy 377.290746 -285.912248)
			(xy 377.248859 -285.94268) (xy 377.202727 -285.966186) (xy 377.153487 -285.982185) (xy 377.102349 -285.990284)
			(xy 377.050575 -285.990284) (xy 376.999437 -285.982185) (xy 376.950197 -285.966186) (xy 376.904065 -285.94268)
			(xy 376.862178 -285.912248) (xy 376.825568 -285.875638) (xy 376.795136 -285.833751) (xy 376.77163 -285.787619)
			(xy 376.755631 -285.738379) (xy 376.747532 -285.687241) (xy 376.747024 -285.661354) (xy 376.747566 -285.633646)
			(xy 376.756753 -285.579) (xy 376.765312 -285.552642) (xy 376.773186 -285.530544) (xy 376.568208 -285.175706)
			(xy 376.545348 -285.171388) (xy 376.520523 -285.166238) (xy 376.472743 -285.149282) (xy 376.428123 -285.125209)
			(xy 376.387716 -285.094586) (xy 376.352475 -285.058137) (xy 376.323231 -285.016721) (xy 376.300676 -284.971315)
			(xy 376.285339 -284.922991) (xy 376.277585 -284.872888) (xy 376.277124 -284.847538) (xy 375.056908 -284.847538)
			(xy 375.056298 -284.875255) (xy 375.046985 -284.929901) (xy 375.038366 -284.95625) (xy 375.030492 -284.978348)
			(xy 375.23547 -285.333186) (xy 375.25833 -285.337504) (xy 375.283147 -285.342634) (xy 375.330889 -285.35963)
			(xy 375.375467 -285.383731) (xy 375.415834 -285.414369) (xy 375.451036 -285.450823) (xy 375.480246 -285.492235)
			(xy 375.502776 -285.537628) (xy 375.518094 -285.585934) (xy 375.52584 -285.636016) (xy 375.5263 -285.661354)
			(xy 375.525792 -285.687241) (xy 375.517693 -285.738379) (xy 375.501694 -285.787619) (xy 375.478188 -285.833751)
			(xy 375.447756 -285.875638) (xy 375.411146 -285.912248) (xy 375.369259 -285.94268) (xy 375.323127 -285.966186)
			(xy 375.273887 -285.982185) (xy 375.222749 -285.990284) (xy 375.170975 -285.990284) (xy 375.119837 -285.982185)
			(xy 375.070597 -285.966186) (xy 375.024465 -285.94268) (xy 374.982578 -285.912248) (xy 374.945968 -285.875638)
			(xy 374.915536 -285.833751) (xy 374.89203 -285.787619) (xy 374.876031 -285.738379) (xy 374.867932 -285.687241)
			(xy 374.867424 -285.661354) (xy 374.867966 -285.633646) (xy 374.877153 -285.579) (xy 374.885712 -285.552642)
			(xy 374.893586 -285.530544) (xy 374.688608 -285.175706) (xy 374.665748 -285.171388) (xy 374.640923 -285.166238)
			(xy 374.593143 -285.149282) (xy 374.548523 -285.125209) (xy 374.508116 -285.094586) (xy 374.472875 -285.058137)
			(xy 374.443631 -285.016721) (xy 374.421076 -284.971315) (xy 374.405739 -284.922991) (xy 374.397985 -284.872888)
			(xy 374.397524 -284.847538) (xy 373.177308 -284.847538) (xy 373.176698 -284.875255) (xy 373.167385 -284.929901)
			(xy 373.158766 -284.95625) (xy 373.150892 -284.978348) (xy 373.35587 -285.333186) (xy 373.37873 -285.337504)
			(xy 373.403547 -285.342634) (xy 373.451289 -285.35963) (xy 373.495867 -285.383731) (xy 373.536234 -285.414369)
			(xy 373.571436 -285.450823) (xy 373.600646 -285.492235) (xy 373.623176 -285.537628) (xy 373.638494 -285.585934)
			(xy 373.64624 -285.636016) (xy 373.6467 -285.661354) (xy 373.646192 -285.687241) (xy 373.638093 -285.738379)
			(xy 373.622094 -285.787619) (xy 373.598588 -285.833751) (xy 373.568156 -285.875638) (xy 373.531546 -285.912248)
			(xy 373.489659 -285.94268) (xy 373.443527 -285.966186) (xy 373.394287 -285.982185) (xy 373.343149 -285.990284)
			(xy 373.291375 -285.990284) (xy 373.240237 -285.982185) (xy 373.190997 -285.966186) (xy 373.144865 -285.94268)
			(xy 373.102978 -285.912248) (xy 373.066368 -285.875638) (xy 373.035936 -285.833751) (xy 373.01243 -285.787619)
			(xy 372.996431 -285.738379) (xy 372.988332 -285.687241) (xy 372.987824 -285.661354) (xy 372.988366 -285.633646)
			(xy 372.997553 -285.579) (xy 373.006112 -285.552642) (xy 373.013986 -285.530544) (xy 372.809008 -285.175706)
			(xy 372.786148 -285.171388) (xy 372.761323 -285.166238) (xy 372.713543 -285.149282) (xy 372.668923 -285.125209)
			(xy 372.628516 -285.094586) (xy 372.593275 -285.058137) (xy 372.564031 -285.016721) (xy 372.541476 -284.971315)
			(xy 372.526139 -284.922991) (xy 372.518385 -284.872888) (xy 372.517924 -284.847538) (xy 371.297708 -284.847538)
			(xy 371.297098 -284.875255) (xy 371.287785 -284.929901) (xy 371.279166 -284.95625) (xy 371.271292 -284.978348)
			(xy 371.47627 -285.333186) (xy 371.49913 -285.337504) (xy 371.523947 -285.342634) (xy 371.571689 -285.35963)
			(xy 371.616267 -285.383731) (xy 371.656634 -285.414369) (xy 371.691836 -285.450823) (xy 371.721046 -285.492235)
			(xy 371.743576 -285.537628) (xy 371.758894 -285.585934) (xy 371.76664 -285.636016) (xy 371.7671 -285.661354)
			(xy 371.766592 -285.687241) (xy 371.758493 -285.738379) (xy 371.742494 -285.787619) (xy 371.718988 -285.833751)
			(xy 371.688556 -285.875638) (xy 371.651946 -285.912248) (xy 371.610059 -285.94268) (xy 371.563927 -285.966186)
			(xy 371.514687 -285.982185) (xy 371.463549 -285.990284) (xy 371.411775 -285.990284) (xy 371.360637 -285.982185)
			(xy 371.311397 -285.966186) (xy 371.265265 -285.94268) (xy 371.223378 -285.912248) (xy 371.186768 -285.875638)
			(xy 371.156336 -285.833751) (xy 371.13283 -285.787619) (xy 371.116831 -285.738379) (xy 371.108732 -285.687241)
			(xy 371.108224 -285.661354) (xy 371.108766 -285.633646) (xy 371.117953 -285.579) (xy 371.126512 -285.552642)
			(xy 371.134386 -285.530544) (xy 370.929408 -285.175706) (xy 370.906548 -285.171388) (xy 370.881723 -285.166238)
			(xy 370.833943 -285.149282) (xy 370.789323 -285.125209) (xy 370.748916 -285.094586) (xy 370.713675 -285.058137)
			(xy 370.684431 -285.016721) (xy 370.661876 -284.971315) (xy 370.646539 -284.922991) (xy 370.638785 -284.872888)
			(xy 370.638324 -284.847538) (xy 369.418108 -284.847538) (xy 369.417498 -284.875255) (xy 369.408185 -284.929901)
			(xy 369.399566 -284.95625) (xy 369.391692 -284.978348) (xy 369.59667 -285.333186) (xy 369.61953 -285.337504)
			(xy 369.644347 -285.342634) (xy 369.692089 -285.35963) (xy 369.736667 -285.383731) (xy 369.777034 -285.414369)
			(xy 369.812236 -285.450823) (xy 369.841446 -285.492235) (xy 369.863976 -285.537628) (xy 369.879294 -285.585934)
			(xy 369.88704 -285.636016) (xy 369.8875 -285.661354) (xy 369.886992 -285.687241) (xy 369.878893 -285.738379)
			(xy 369.862894 -285.787619) (xy 369.839388 -285.833751) (xy 369.808956 -285.875638) (xy 369.772346 -285.912248)
			(xy 369.730459 -285.94268) (xy 369.684327 -285.966186) (xy 369.635087 -285.982185) (xy 369.583949 -285.990284)
			(xy 369.532175 -285.990284) (xy 369.481037 -285.982185) (xy 369.431797 -285.966186) (xy 369.385665 -285.94268)
			(xy 369.343778 -285.912248) (xy 369.307168 -285.875638) (xy 369.276736 -285.833751) (xy 369.25323 -285.787619)
			(xy 369.237231 -285.738379) (xy 369.229132 -285.687241) (xy 369.228624 -285.661354) (xy 369.229166 -285.633646)
			(xy 369.238353 -285.579) (xy 369.246912 -285.552642) (xy 369.254786 -285.530544) (xy 369.049808 -285.175706)
			(xy 369.026948 -285.171388) (xy 369.002123 -285.166238) (xy 368.954343 -285.149282) (xy 368.909723 -285.125209)
			(xy 368.869316 -285.094586) (xy 368.834075 -285.058137) (xy 368.804831 -285.016721) (xy 368.782276 -284.971315)
			(xy 368.766939 -284.922991) (xy 368.759185 -284.872888) (xy 368.758724 -284.847538) (xy 367.538508 -284.847538)
			(xy 367.537898 -284.875255) (xy 367.528585 -284.929901) (xy 367.519966 -284.95625) (xy 367.512092 -284.978348)
			(xy 367.71707 -285.333186) (xy 367.73993 -285.337504) (xy 367.764747 -285.342634) (xy 367.812489 -285.35963)
			(xy 367.857067 -285.383731) (xy 367.897434 -285.414369) (xy 367.932636 -285.450823) (xy 367.961846 -285.492235)
			(xy 367.984376 -285.537628) (xy 367.999694 -285.585934) (xy 368.00744 -285.636016) (xy 368.0079 -285.661354)
			(xy 368.007392 -285.687241) (xy 367.999293 -285.738379) (xy 367.983294 -285.787619) (xy 367.959788 -285.833751)
			(xy 367.929356 -285.875638) (xy 367.892746 -285.912248) (xy 367.850859 -285.94268) (xy 367.804727 -285.966186)
			(xy 367.755487 -285.982185) (xy 367.704349 -285.990284) (xy 367.652575 -285.990284) (xy 367.601437 -285.982185)
			(xy 367.552197 -285.966186) (xy 367.506065 -285.94268) (xy 367.464178 -285.912248) (xy 367.427568 -285.875638)
			(xy 367.397136 -285.833751) (xy 367.37363 -285.787619) (xy 367.357631 -285.738379) (xy 367.349532 -285.687241)
			(xy 367.349024 -285.661354) (xy 367.349566 -285.633646) (xy 367.358753 -285.579) (xy 367.367312 -285.552642)
			(xy 367.375186 -285.530544) (xy 367.170208 -285.175706) (xy 367.147348 -285.171388) (xy 367.122523 -285.166238)
			(xy 367.074743 -285.149282) (xy 367.030123 -285.125209) (xy 366.989716 -285.094586) (xy 366.954475 -285.058137)
			(xy 366.925231 -285.016721) (xy 366.902676 -284.971315) (xy 366.887339 -284.922991) (xy 366.879585 -284.872888)
			(xy 366.879124 -284.847538) (xy 352.501708 -284.847538) (xy 352.501261 -284.872913) (xy 352.493487 -284.923064)
			(xy 352.478114 -284.97143) (xy 352.455505 -285.016866) (xy 352.426196 -285.058297) (xy 352.390879 -285.094742)
			(xy 352.350391 -285.125341) (xy 352.305689 -285.149367) (xy 352.257831 -285.166254) (xy 352.232976 -285.171388)
			(xy 352.210116 -285.175706) (xy 352.005138 -285.530544) (xy 352.013012 -285.552642) (xy 352.021583 -285.578997)
			(xy 352.030775 -285.633645) (xy 352.0313 -285.661354) (xy 352.030792 -285.687241) (xy 352.022693 -285.738379)
			(xy 352.006694 -285.787619) (xy 351.983188 -285.833751) (xy 351.952756 -285.875638) (xy 351.916146 -285.912248)
			(xy 351.874259 -285.94268) (xy 351.828127 -285.966186) (xy 351.778887 -285.982185) (xy 351.727749 -285.990284)
			(xy 351.675975 -285.990284) (xy 351.624837 -285.982185) (xy 351.575597 -285.966186) (xy 351.529465 -285.94268)
			(xy 351.487578 -285.912248) (xy 351.450968 -285.875638) (xy 351.420536 -285.833751) (xy 351.39703 -285.787619)
			(xy 351.381031 -285.738379) (xy 351.372932 -285.687241) (xy 351.372424 -285.661354) (xy 351.0915 -285.661354)
			(xy 351.0915 -285.661862) (xy 351.090923 -285.689379) (xy 351.081728 -285.74364) (xy 351.073212 -285.769812)
			(xy 351.065592 -285.79191) (xy 351.270824 -286.147256) (xy 351.293684 -286.151574) (xy 351.318506 -286.156737)
			(xy 351.366283 -286.173695) (xy 351.410901 -286.197768) (xy 351.451306 -286.22839) (xy 351.486546 -286.264837)
			(xy 351.515789 -286.30625) (xy 351.538346 -286.351653) (xy 351.553685 -286.399975) (xy 351.561445 -286.450075)
			(xy 351.561908 -286.475424) (xy 367.818924 -286.475424) (xy 367.819448 -286.45008) (xy 367.827216 -286.399991)
			(xy 367.842559 -286.351681) (xy 367.865115 -286.306288) (xy 367.894351 -286.264882) (xy 367.92958 -286.228438)
			(xy 367.969972 -286.197814) (xy 368.014574 -286.173733) (xy 368.062336 -286.156761) (xy 368.087148 -286.151574)
			(xy 368.110008 -286.147256) (xy 368.314986 -285.792164) (xy 368.307112 -285.77032) (xy 368.298538 -285.7439)
			(xy 368.289338 -285.689126) (xy 368.288824 -285.661354) (xy 368.289332 -285.635467) (xy 368.297431 -285.584329)
			(xy 368.31343 -285.535089) (xy 368.336936 -285.488957) (xy 368.367368 -285.44707) (xy 368.403978 -285.41046)
			(xy 368.445865 -285.380028) (xy 368.491997 -285.356522) (xy 368.541237 -285.340523) (xy 368.592375 -285.332424)
			(xy 368.644149 -285.332424) (xy 368.695287 -285.340523) (xy 368.744527 -285.356522) (xy 368.790659 -285.380028)
			(xy 368.832546 -285.41046) (xy 368.869156 -285.44707) (xy 368.899588 -285.488957) (xy 368.923094 -285.535089)
			(xy 368.939093 -285.584329) (xy 368.947192 -285.635467) (xy 368.9477 -285.661354) (xy 368.947266 -285.68669)
			(xy 368.939506 -285.736765) (xy 368.924176 -285.785062) (xy 368.901638 -285.830446) (xy 368.872422 -285.871848)
			(xy 368.837216 -285.908293) (xy 368.796849 -285.938922) (xy 368.752271 -285.963016) (xy 368.704531 -285.980006)
			(xy 368.67973 -285.985204) (xy 368.65687 -285.989522) (xy 368.451892 -286.344614) (xy 368.459766 -286.366458)
			(xy 368.468419 -286.392864) (xy 368.477734 -286.447642) (xy 368.478308 -286.475424) (xy 369.698524 -286.475424)
			(xy 369.699048 -286.45008) (xy 369.706816 -286.399991) (xy 369.722159 -286.351681) (xy 369.744715 -286.306288)
			(xy 369.773951 -286.264882) (xy 369.80918 -286.228438) (xy 369.849572 -286.197814) (xy 369.894174 -286.173733)
			(xy 369.941936 -286.156761) (xy 369.966748 -286.151574) (xy 369.989608 -286.147256) (xy 370.194586 -285.792164)
			(xy 370.186712 -285.77032) (xy 370.178138 -285.7439) (xy 370.168938 -285.689126) (xy 370.168424 -285.661354)
			(xy 370.168932 -285.635467) (xy 370.177031 -285.584329) (xy 370.19303 -285.535089) (xy 370.216536 -285.488957)
			(xy 370.246968 -285.44707) (xy 370.283578 -285.41046) (xy 370.325465 -285.380028) (xy 370.371597 -285.356522)
			(xy 370.420837 -285.340523) (xy 370.471975 -285.332424) (xy 370.523749 -285.332424) (xy 370.574887 -285.340523)
			(xy 370.624127 -285.356522) (xy 370.670259 -285.380028) (xy 370.712146 -285.41046) (xy 370.748756 -285.44707)
			(xy 370.779188 -285.488957) (xy 370.802694 -285.535089) (xy 370.818693 -285.584329) (xy 370.826792 -285.635467)
			(xy 370.8273 -285.661354) (xy 370.826866 -285.68669) (xy 370.819106 -285.736765) (xy 370.803776 -285.785062)
			(xy 370.781238 -285.830446) (xy 370.752022 -285.871848) (xy 370.716816 -285.908293) (xy 370.676449 -285.938922)
			(xy 370.631871 -285.963016) (xy 370.584131 -285.980006) (xy 370.55933 -285.985204) (xy 370.53647 -285.989522)
			(xy 370.331492 -286.344614) (xy 370.339366 -286.366458) (xy 370.348019 -286.392864) (xy 370.357334 -286.447642)
			(xy 370.357908 -286.475424) (xy 371.578124 -286.475424) (xy 371.578648 -286.45008) (xy 371.586416 -286.399991)
			(xy 371.601759 -286.351681) (xy 371.624315 -286.306288) (xy 371.653551 -286.264882) (xy 371.68878 -286.228438)
			(xy 371.729172 -286.197814) (xy 371.773774 -286.173733) (xy 371.821536 -286.156761) (xy 371.846348 -286.151574)
			(xy 371.869208 -286.147256) (xy 372.074186 -285.792164) (xy 372.066312 -285.77032) (xy 372.057738 -285.7439)
			(xy 372.048538 -285.689126) (xy 372.048024 -285.661354) (xy 372.048532 -285.635467) (xy 372.056631 -285.584329)
			(xy 372.07263 -285.535089) (xy 372.096136 -285.488957) (xy 372.126568 -285.44707) (xy 372.163178 -285.41046)
			(xy 372.205065 -285.380028) (xy 372.251197 -285.356522) (xy 372.300437 -285.340523) (xy 372.351575 -285.332424)
			(xy 372.403349 -285.332424) (xy 372.454487 -285.340523) (xy 372.503727 -285.356522) (xy 372.549859 -285.380028)
			(xy 372.591746 -285.41046) (xy 372.628356 -285.44707) (xy 372.658788 -285.488957) (xy 372.682294 -285.535089)
			(xy 372.698293 -285.584329) (xy 372.706392 -285.635467) (xy 372.7069 -285.661354) (xy 372.706466 -285.68669)
			(xy 372.698706 -285.736765) (xy 372.683376 -285.785062) (xy 372.660838 -285.830446) (xy 372.631622 -285.871848)
			(xy 372.596416 -285.908293) (xy 372.556049 -285.938922) (xy 372.511471 -285.963016) (xy 372.463731 -285.980006)
			(xy 372.43893 -285.985204) (xy 372.41607 -285.989522) (xy 372.211092 -286.344614) (xy 372.218966 -286.366458)
			(xy 372.227619 -286.392864) (xy 372.236934 -286.447642) (xy 372.237508 -286.475424) (xy 373.457724 -286.475424)
			(xy 373.458248 -286.45008) (xy 373.466016 -286.399991) (xy 373.481359 -286.351681) (xy 373.503915 -286.306288)
			(xy 373.533151 -286.264882) (xy 373.56838 -286.228438) (xy 373.608772 -286.197814) (xy 373.653374 -286.173733)
			(xy 373.701136 -286.156761) (xy 373.725948 -286.151574) (xy 373.748808 -286.147256) (xy 373.953786 -285.792164)
			(xy 373.945912 -285.77032) (xy 373.937338 -285.7439) (xy 373.928138 -285.689126) (xy 373.927624 -285.661354)
			(xy 373.928132 -285.635467) (xy 373.936231 -285.584329) (xy 373.95223 -285.535089) (xy 373.975736 -285.488957)
			(xy 374.006168 -285.44707) (xy 374.042778 -285.41046) (xy 374.084665 -285.380028) (xy 374.130797 -285.356522)
			(xy 374.180037 -285.340523) (xy 374.231175 -285.332424) (xy 374.282949 -285.332424) (xy 374.334087 -285.340523)
			(xy 374.383327 -285.356522) (xy 374.429459 -285.380028) (xy 374.471346 -285.41046) (xy 374.507956 -285.44707)
			(xy 374.538388 -285.488957) (xy 374.561894 -285.535089) (xy 374.577893 -285.584329) (xy 374.585992 -285.635467)
			(xy 374.5865 -285.661354) (xy 374.586066 -285.68669) (xy 374.578306 -285.736765) (xy 374.562976 -285.785062)
			(xy 374.540438 -285.830446) (xy 374.511222 -285.871848) (xy 374.476016 -285.908293) (xy 374.435649 -285.938922)
			(xy 374.391071 -285.963016) (xy 374.343331 -285.980006) (xy 374.31853 -285.985204) (xy 374.29567 -285.989522)
			(xy 374.090692 -286.344614) (xy 374.098566 -286.366458) (xy 374.107219 -286.392864) (xy 374.116534 -286.447642)
			(xy 374.117108 -286.475424) (xy 375.337324 -286.475424) (xy 375.337848 -286.45008) (xy 375.345616 -286.399991)
			(xy 375.360959 -286.351681) (xy 375.383515 -286.306288) (xy 375.412751 -286.264882) (xy 375.44798 -286.228438)
			(xy 375.488372 -286.197814) (xy 375.532974 -286.173733) (xy 375.580736 -286.156761) (xy 375.605548 -286.151574)
			(xy 375.628408 -286.147256) (xy 375.833386 -285.792164) (xy 375.825512 -285.77032) (xy 375.816938 -285.7439)
			(xy 375.807738 -285.689126) (xy 375.807224 -285.661354) (xy 375.807732 -285.635467) (xy 375.815831 -285.584329)
			(xy 375.83183 -285.535089) (xy 375.855336 -285.488957) (xy 375.885768 -285.44707) (xy 375.922378 -285.41046)
			(xy 375.964265 -285.380028) (xy 376.010397 -285.356522) (xy 376.059637 -285.340523) (xy 376.110775 -285.332424)
			(xy 376.162549 -285.332424) (xy 376.213687 -285.340523) (xy 376.262927 -285.356522) (xy 376.309059 -285.380028)
			(xy 376.350946 -285.41046) (xy 376.387556 -285.44707) (xy 376.417988 -285.488957) (xy 376.441494 -285.535089)
			(xy 376.457493 -285.584329) (xy 376.465592 -285.635467) (xy 376.4661 -285.661354) (xy 376.465666 -285.68669)
			(xy 376.457906 -285.736765) (xy 376.442576 -285.785062) (xy 376.420038 -285.830446) (xy 376.390822 -285.871848)
			(xy 376.355616 -285.908293) (xy 376.315249 -285.938922) (xy 376.270671 -285.963016) (xy 376.222931 -285.980006)
			(xy 376.19813 -285.985204) (xy 376.17527 -285.989522) (xy 375.970292 -286.344614) (xy 375.978166 -286.366458)
			(xy 375.986819 -286.392864) (xy 375.996134 -286.447642) (xy 375.996708 -286.475424) (xy 377.216924 -286.475424)
			(xy 377.217448 -286.45008) (xy 377.225216 -286.399991) (xy 377.240559 -286.351681) (xy 377.263115 -286.306288)
			(xy 377.292351 -286.264882) (xy 377.32758 -286.228438) (xy 377.367972 -286.197814) (xy 377.412574 -286.173733)
			(xy 377.460336 -286.156761) (xy 377.485148 -286.151574) (xy 377.508008 -286.147256) (xy 377.712986 -285.792164)
			(xy 377.705112 -285.77032) (xy 377.696538 -285.7439) (xy 377.687338 -285.689126) (xy 377.686824 -285.661354)
			(xy 377.687332 -285.635467) (xy 377.695431 -285.584329) (xy 377.71143 -285.535089) (xy 377.734936 -285.488957)
			(xy 377.765368 -285.44707) (xy 377.801978 -285.41046) (xy 377.843865 -285.380028) (xy 377.889997 -285.356522)
			(xy 377.939237 -285.340523) (xy 377.990375 -285.332424) (xy 378.042149 -285.332424) (xy 378.093287 -285.340523)
			(xy 378.142527 -285.356522) (xy 378.188659 -285.380028) (xy 378.230546 -285.41046) (xy 378.267156 -285.44707)
			(xy 378.297588 -285.488957) (xy 378.321094 -285.535089) (xy 378.337093 -285.584329) (xy 378.345192 -285.635467)
			(xy 378.3457 -285.661354) (xy 378.345266 -285.68669) (xy 378.337506 -285.736765) (xy 378.322176 -285.785062)
			(xy 378.299638 -285.830446) (xy 378.270422 -285.871848) (xy 378.235216 -285.908293) (xy 378.194849 -285.938922)
			(xy 378.150271 -285.963016) (xy 378.102531 -285.980006) (xy 378.07773 -285.985204) (xy 378.05487 -285.989522)
			(xy 377.849892 -286.344614) (xy 377.857766 -286.366458) (xy 377.866419 -286.392864) (xy 377.875734 -286.447642)
			(xy 377.876308 -286.475424) (xy 379.096524 -286.475424) (xy 379.097048 -286.45008) (xy 379.104816 -286.399991)
			(xy 379.120159 -286.351681) (xy 379.142715 -286.306288) (xy 379.171951 -286.264882) (xy 379.20718 -286.228438)
			(xy 379.247572 -286.197814) (xy 379.292174 -286.173733) (xy 379.339936 -286.156761) (xy 379.364748 -286.151574)
			(xy 379.387608 -286.147256) (xy 379.592586 -285.792164) (xy 379.584712 -285.77032) (xy 379.576138 -285.7439)
			(xy 379.566938 -285.689126) (xy 379.566424 -285.661354) (xy 379.566932 -285.635467) (xy 379.575031 -285.584329)
			(xy 379.59103 -285.535089) (xy 379.614536 -285.488957) (xy 379.644968 -285.44707) (xy 379.681578 -285.41046)
			(xy 379.723465 -285.380028) (xy 379.769597 -285.356522) (xy 379.818837 -285.340523) (xy 379.869975 -285.332424)
			(xy 379.921749 -285.332424) (xy 379.972887 -285.340523) (xy 380.022127 -285.356522) (xy 380.068259 -285.380028)
			(xy 380.110146 -285.41046) (xy 380.146756 -285.44707) (xy 380.177188 -285.488957) (xy 380.200694 -285.535089)
			(xy 380.216693 -285.584329) (xy 380.224792 -285.635467) (xy 380.2253 -285.661354) (xy 380.224866 -285.68669)
			(xy 380.217106 -285.736765) (xy 380.201776 -285.785062) (xy 380.179238 -285.830446) (xy 380.150022 -285.871848)
			(xy 380.114816 -285.908293) (xy 380.074449 -285.938922) (xy 380.029871 -285.963016) (xy 379.982131 -285.980006)
			(xy 379.95733 -285.985204) (xy 379.93447 -285.989522) (xy 379.729492 -286.344614) (xy 379.737366 -286.366458)
			(xy 379.746019 -286.392864) (xy 379.755334 -286.447642) (xy 379.755908 -286.475424) (xy 380.976124 -286.475424)
			(xy 380.976648 -286.45008) (xy 380.984416 -286.399991) (xy 380.999759 -286.351681) (xy 381.022315 -286.306288)
			(xy 381.051551 -286.264882) (xy 381.08678 -286.228438) (xy 381.127172 -286.197814) (xy 381.171774 -286.173733)
			(xy 381.219536 -286.156761) (xy 381.244348 -286.151574) (xy 381.267208 -286.147256) (xy 381.472186 -285.792164)
			(xy 381.464312 -285.77032) (xy 381.455738 -285.7439) (xy 381.446538 -285.689126) (xy 381.446024 -285.661354)
			(xy 381.446532 -285.635467) (xy 381.454631 -285.584329) (xy 381.47063 -285.535089) (xy 381.494136 -285.488957)
			(xy 381.524568 -285.44707) (xy 381.561178 -285.41046) (xy 381.603065 -285.380028) (xy 381.649197 -285.356522)
			(xy 381.698437 -285.340523) (xy 381.749575 -285.332424) (xy 381.801349 -285.332424) (xy 381.852487 -285.340523)
			(xy 381.901727 -285.356522) (xy 381.947859 -285.380028) (xy 381.989746 -285.41046) (xy 382.026356 -285.44707)
			(xy 382.056788 -285.488957) (xy 382.080294 -285.535089) (xy 382.096293 -285.584329) (xy 382.104392 -285.635467)
			(xy 382.1049 -285.661354) (xy 382.104466 -285.68669) (xy 382.096706 -285.736765) (xy 382.081376 -285.785062)
			(xy 382.058838 -285.830446) (xy 382.029622 -285.871848) (xy 381.994416 -285.908293) (xy 381.954049 -285.938922)
			(xy 381.909471 -285.963016) (xy 381.861731 -285.980006) (xy 381.83693 -285.985204) (xy 381.81407 -285.989522)
			(xy 381.609092 -286.344614) (xy 381.616966 -286.366458) (xy 381.625619 -286.392864) (xy 381.634934 -286.447642)
			(xy 381.635508 -286.475424) (xy 381.635 -286.501331) (xy 381.626894 -286.552508) (xy 381.610882 -286.601787)
			(xy 381.587359 -286.647954) (xy 381.556903 -286.689873) (xy 381.520265 -286.726511) (xy 381.478346 -286.756967)
			(xy 381.432179 -286.78049) (xy 381.3829 -286.796502) (xy 381.331723 -286.804608) (xy 381.279909 -286.804608)
			(xy 381.228732 -286.796502) (xy 381.179453 -286.78049) (xy 381.133286 -286.756967) (xy 381.091367 -286.726511)
			(xy 381.054729 -286.689873) (xy 381.024273 -286.647954) (xy 381.00075 -286.601787) (xy 380.984738 -286.552508)
			(xy 380.976632 -286.501331) (xy 380.976124 -286.475424) (xy 379.755908 -286.475424) (xy 379.7554 -286.501331)
			(xy 379.747294 -286.552508) (xy 379.731282 -286.601787) (xy 379.707759 -286.647954) (xy 379.677303 -286.689873)
			(xy 379.640665 -286.726511) (xy 379.598746 -286.756967) (xy 379.552579 -286.78049) (xy 379.5033 -286.796502)
			(xy 379.452123 -286.804608) (xy 379.400309 -286.804608) (xy 379.349132 -286.796502) (xy 379.299853 -286.78049)
			(xy 379.253686 -286.756967) (xy 379.211767 -286.726511) (xy 379.175129 -286.689873) (xy 379.144673 -286.647954)
			(xy 379.12115 -286.601787) (xy 379.105138 -286.552508) (xy 379.097032 -286.501331) (xy 379.096524 -286.475424)
			(xy 377.876308 -286.475424) (xy 377.8758 -286.501331) (xy 377.867694 -286.552508) (xy 377.851682 -286.601787)
			(xy 377.828159 -286.647954) (xy 377.797703 -286.689873) (xy 377.761065 -286.726511) (xy 377.719146 -286.756967)
			(xy 377.672979 -286.78049) (xy 377.6237 -286.796502) (xy 377.572523 -286.804608) (xy 377.520709 -286.804608)
			(xy 377.469532 -286.796502) (xy 377.420253 -286.78049) (xy 377.374086 -286.756967) (xy 377.332167 -286.726511)
			(xy 377.295529 -286.689873) (xy 377.265073 -286.647954) (xy 377.24155 -286.601787) (xy 377.225538 -286.552508)
			(xy 377.217432 -286.501331) (xy 377.216924 -286.475424) (xy 375.996708 -286.475424) (xy 375.9962 -286.501331)
			(xy 375.988094 -286.552508) (xy 375.972082 -286.601787) (xy 375.948559 -286.647954) (xy 375.918103 -286.689873)
			(xy 375.881465 -286.726511) (xy 375.839546 -286.756967) (xy 375.793379 -286.78049) (xy 375.7441 -286.796502)
			(xy 375.692923 -286.804608) (xy 375.641109 -286.804608) (xy 375.589932 -286.796502) (xy 375.540653 -286.78049)
			(xy 375.494486 -286.756967) (xy 375.452567 -286.726511) (xy 375.415929 -286.689873) (xy 375.385473 -286.647954)
			(xy 375.36195 -286.601787) (xy 375.345938 -286.552508) (xy 375.337832 -286.501331) (xy 375.337324 -286.475424)
			(xy 374.117108 -286.475424) (xy 374.1166 -286.501331) (xy 374.108494 -286.552508) (xy 374.092482 -286.601787)
			(xy 374.068959 -286.647954) (xy 374.038503 -286.689873) (xy 374.001865 -286.726511) (xy 373.959946 -286.756967)
			(xy 373.913779 -286.78049) (xy 373.8645 -286.796502) (xy 373.813323 -286.804608) (xy 373.761509 -286.804608)
			(xy 373.710332 -286.796502) (xy 373.661053 -286.78049) (xy 373.614886 -286.756967) (xy 373.572967 -286.726511)
			(xy 373.536329 -286.689873) (xy 373.505873 -286.647954) (xy 373.48235 -286.601787) (xy 373.466338 -286.552508)
			(xy 373.458232 -286.501331) (xy 373.457724 -286.475424) (xy 372.237508 -286.475424) (xy 372.237 -286.501331)
			(xy 372.228894 -286.552508) (xy 372.212882 -286.601787) (xy 372.189359 -286.647954) (xy 372.158903 -286.689873)
			(xy 372.122265 -286.726511) (xy 372.080346 -286.756967) (xy 372.034179 -286.78049) (xy 371.9849 -286.796502)
			(xy 371.933723 -286.804608) (xy 371.881909 -286.804608) (xy 371.830732 -286.796502) (xy 371.781453 -286.78049)
			(xy 371.735286 -286.756967) (xy 371.693367 -286.726511) (xy 371.656729 -286.689873) (xy 371.626273 -286.647954)
			(xy 371.60275 -286.601787) (xy 371.586738 -286.552508) (xy 371.578632 -286.501331) (xy 371.578124 -286.475424)
			(xy 370.357908 -286.475424) (xy 370.3574 -286.501331) (xy 370.349294 -286.552508) (xy 370.333282 -286.601787)
			(xy 370.309759 -286.647954) (xy 370.279303 -286.689873) (xy 370.242665 -286.726511) (xy 370.200746 -286.756967)
			(xy 370.154579 -286.78049) (xy 370.1053 -286.796502) (xy 370.054123 -286.804608) (xy 370.002309 -286.804608)
			(xy 369.951132 -286.796502) (xy 369.901853 -286.78049) (xy 369.855686 -286.756967) (xy 369.813767 -286.726511)
			(xy 369.777129 -286.689873) (xy 369.746673 -286.647954) (xy 369.72315 -286.601787) (xy 369.707138 -286.552508)
			(xy 369.699032 -286.501331) (xy 369.698524 -286.475424) (xy 368.478308 -286.475424) (xy 368.4778 -286.501331)
			(xy 368.469694 -286.552508) (xy 368.453682 -286.601787) (xy 368.430159 -286.647954) (xy 368.399703 -286.689873)
			(xy 368.363065 -286.726511) (xy 368.321146 -286.756967) (xy 368.274979 -286.78049) (xy 368.2257 -286.796502)
			(xy 368.174523 -286.804608) (xy 368.122709 -286.804608) (xy 368.071532 -286.796502) (xy 368.022253 -286.78049)
			(xy 367.976086 -286.756967) (xy 367.934167 -286.726511) (xy 367.897529 -286.689873) (xy 367.867073 -286.647954)
			(xy 367.84355 -286.601787) (xy 367.827538 -286.552508) (xy 367.819432 -286.501331) (xy 367.818924 -286.475424)
			(xy 351.561908 -286.475424) (xy 351.5614 -286.501331) (xy 351.553294 -286.552508) (xy 351.537282 -286.601787)
			(xy 351.513759 -286.647954) (xy 351.483303 -286.689873) (xy 351.446665 -286.726511) (xy 351.404746 -286.756967)
			(xy 351.358579 -286.78049) (xy 351.3093 -286.796502) (xy 351.258123 -286.804608) (xy 351.206309 -286.804608)
			(xy 351.155132 -286.796502) (xy 351.105853 -286.78049) (xy 351.059686 -286.756967) (xy 351.017767 -286.726511)
			(xy 350.981129 -286.689873) (xy 350.950673 -286.647954) (xy 350.92715 -286.601787) (xy 350.911138 -286.552508)
			(xy 350.903032 -286.501331) (xy 350.902524 -286.475424) (xy 350.903123 -286.447707) (xy 350.912443 -286.39306)
			(xy 350.921066 -286.366712) (xy 350.92894 -286.344614) (xy 350.723962 -285.989522) (xy 350.700848 -285.985204)
			(xy 350.676027 -285.980039) (xy 350.628247 -285.963084) (xy 350.583628 -285.939012) (xy 350.543222 -285.908392)
			(xy 350.507981 -285.871945) (xy 350.478737 -285.830531) (xy 350.45618 -285.785127) (xy 350.440843 -285.736804)
			(xy 350.433086 -285.686703) (xy 350.432624 -285.661354) (xy 350.1517 -285.661354) (xy 350.151192 -285.687241)
			(xy 350.143093 -285.738379) (xy 350.127094 -285.787619) (xy 350.103588 -285.833751) (xy 350.073156 -285.875638)
			(xy 350.036546 -285.912248) (xy 349.994659 -285.94268) (xy 349.948527 -285.966186) (xy 349.899287 -285.982185)
			(xy 349.848149 -285.990284) (xy 349.796375 -285.990284) (xy 349.745237 -285.982185) (xy 349.695997 -285.966186)
			(xy 349.649865 -285.94268) (xy 349.607978 -285.912248) (xy 349.571368 -285.875638) (xy 349.540936 -285.833751)
			(xy 349.51743 -285.787619) (xy 349.501431 -285.738379) (xy 349.493332 -285.687241) (xy 349.492824 -285.661354)
			(xy 349.2119 -285.661354) (xy 349.2119 -285.661862) (xy 349.211323 -285.689379) (xy 349.202128 -285.74364)
			(xy 349.193612 -285.769812) (xy 349.185992 -285.79191) (xy 349.391224 -286.147256) (xy 349.414084 -286.151574)
			(xy 349.438906 -286.156737) (xy 349.486683 -286.173695) (xy 349.531301 -286.197768) (xy 349.571706 -286.22839)
			(xy 349.606946 -286.264837) (xy 349.636189 -286.30625) (xy 349.658746 -286.351653) (xy 349.674085 -286.399975)
			(xy 349.681845 -286.450075) (xy 349.682308 -286.475424) (xy 349.6818 -286.501331) (xy 349.673694 -286.552508)
			(xy 349.657682 -286.601787) (xy 349.634159 -286.647954) (xy 349.603703 -286.689873) (xy 349.567065 -286.726511)
			(xy 349.525146 -286.756967) (xy 349.478979 -286.78049) (xy 349.4297 -286.796502) (xy 349.378523 -286.804608)
			(xy 349.326709 -286.804608) (xy 349.275532 -286.796502) (xy 349.226253 -286.78049) (xy 349.180086 -286.756967)
			(xy 349.138167 -286.726511) (xy 349.101529 -286.689873) (xy 349.071073 -286.647954) (xy 349.04755 -286.601787)
			(xy 349.031538 -286.552508) (xy 349.023432 -286.501331) (xy 349.022924 -286.475424) (xy 349.023523 -286.447707)
			(xy 349.032843 -286.39306) (xy 349.041466 -286.366712) (xy 349.04934 -286.344614) (xy 348.844362 -285.989522)
			(xy 348.821248 -285.985204) (xy 348.796427 -285.980039) (xy 348.748647 -285.963084) (xy 348.704028 -285.939012)
			(xy 348.663622 -285.908392) (xy 348.628381 -285.871945) (xy 348.599137 -285.830531) (xy 348.57658 -285.785127)
			(xy 348.561243 -285.736804) (xy 348.553486 -285.686703) (xy 348.553024 -285.661354) (xy 348.2721 -285.661354)
			(xy 348.271592 -285.687241) (xy 348.263493 -285.738379) (xy 348.247494 -285.787619) (xy 348.223988 -285.833751)
			(xy 348.193556 -285.875638) (xy 348.156946 -285.912248) (xy 348.115059 -285.94268) (xy 348.068927 -285.966186)
			(xy 348.019687 -285.982185) (xy 347.968549 -285.990284) (xy 347.916775 -285.990284) (xy 347.865637 -285.982185)
			(xy 347.816397 -285.966186) (xy 347.770265 -285.94268) (xy 347.728378 -285.912248) (xy 347.691768 -285.875638)
			(xy 347.661336 -285.833751) (xy 347.63783 -285.787619) (xy 347.621831 -285.738379) (xy 347.613732 -285.687241)
			(xy 347.613224 -285.661354) (xy 347.3323 -285.661354) (xy 347.3323 -285.661862) (xy 347.331723 -285.689379)
			(xy 347.322528 -285.74364) (xy 347.314012 -285.769812) (xy 347.306392 -285.79191) (xy 347.511624 -286.147256)
			(xy 347.534484 -286.151574) (xy 347.559306 -286.156737) (xy 347.607083 -286.173695) (xy 347.651701 -286.197768)
			(xy 347.692106 -286.22839) (xy 347.727346 -286.264837) (xy 347.756589 -286.30625) (xy 347.779146 -286.351653)
			(xy 347.794485 -286.399975) (xy 347.802245 -286.450075) (xy 347.802708 -286.475424) (xy 347.8022 -286.501331)
			(xy 347.794094 -286.552508) (xy 347.778082 -286.601787) (xy 347.754559 -286.647954) (xy 347.724103 -286.689873)
			(xy 347.687465 -286.726511) (xy 347.645546 -286.756967) (xy 347.599379 -286.78049) (xy 347.5501 -286.796502)
			(xy 347.498923 -286.804608) (xy 347.447109 -286.804608) (xy 347.395932 -286.796502) (xy 347.346653 -286.78049)
			(xy 347.300486 -286.756967) (xy 347.258567 -286.726511) (xy 347.221929 -286.689873) (xy 347.191473 -286.647954)
			(xy 347.16795 -286.601787) (xy 347.151938 -286.552508) (xy 347.143832 -286.501331) (xy 347.143324 -286.475424)
			(xy 347.143923 -286.447707) (xy 347.153243 -286.39306) (xy 347.161866 -286.366712) (xy 347.16974 -286.344614)
			(xy 346.964762 -285.989522) (xy 346.941648 -285.985204) (xy 346.916827 -285.980039) (xy 346.869047 -285.963084)
			(xy 346.824428 -285.939012) (xy 346.784022 -285.908392) (xy 346.748781 -285.871945) (xy 346.719537 -285.830531)
			(xy 346.69698 -285.785127) (xy 346.681643 -285.736804) (xy 346.673886 -285.686703) (xy 346.673424 -285.661354)
			(xy 346.3925 -285.661354) (xy 346.391992 -285.687241) (xy 346.383893 -285.738379) (xy 346.367894 -285.787619)
			(xy 346.344388 -285.833751) (xy 346.313956 -285.875638) (xy 346.277346 -285.912248) (xy 346.235459 -285.94268)
			(xy 346.189327 -285.966186) (xy 346.140087 -285.982185) (xy 346.088949 -285.990284) (xy 346.037175 -285.990284)
			(xy 345.986037 -285.982185) (xy 345.936797 -285.966186) (xy 345.890665 -285.94268) (xy 345.848778 -285.912248)
			(xy 345.812168 -285.875638) (xy 345.781736 -285.833751) (xy 345.75823 -285.787619) (xy 345.742231 -285.738379)
			(xy 345.734132 -285.687241) (xy 345.733624 -285.661354) (xy 345.4527 -285.661354) (xy 345.4527 -285.661862)
			(xy 345.452123 -285.689379) (xy 345.442928 -285.74364) (xy 345.434412 -285.769812) (xy 345.426792 -285.79191)
			(xy 345.632024 -286.147256) (xy 345.654884 -286.151574) (xy 345.679706 -286.156737) (xy 345.727483 -286.173695)
			(xy 345.772101 -286.197768) (xy 345.812506 -286.22839) (xy 345.847746 -286.264837) (xy 345.876989 -286.30625)
			(xy 345.899546 -286.351653) (xy 345.914885 -286.399975) (xy 345.922645 -286.450075) (xy 345.923108 -286.475424)
			(xy 345.9226 -286.501331) (xy 345.914494 -286.552508) (xy 345.898482 -286.601787) (xy 345.874959 -286.647954)
			(xy 345.844503 -286.689873) (xy 345.807865 -286.726511) (xy 345.765946 -286.756967) (xy 345.719779 -286.78049)
			(xy 345.6705 -286.796502) (xy 345.619323 -286.804608) (xy 345.567509 -286.804608) (xy 345.516332 -286.796502)
			(xy 345.467053 -286.78049) (xy 345.420886 -286.756967) (xy 345.378967 -286.726511) (xy 345.342329 -286.689873)
			(xy 345.311873 -286.647954) (xy 345.28835 -286.601787) (xy 345.272338 -286.552508) (xy 345.264232 -286.501331)
			(xy 345.263724 -286.475424) (xy 345.264323 -286.447707) (xy 345.273643 -286.39306) (xy 345.282266 -286.366712)
			(xy 345.29014 -286.344614) (xy 345.085162 -285.989522) (xy 345.062048 -285.985204) (xy 345.037227 -285.980039)
			(xy 344.989447 -285.963084) (xy 344.944828 -285.939012) (xy 344.904422 -285.908392) (xy 344.869181 -285.871945)
			(xy 344.839937 -285.830531) (xy 344.81738 -285.785127) (xy 344.802043 -285.736804) (xy 344.794286 -285.686703)
			(xy 344.793824 -285.661354) (xy 344.5129 -285.661354) (xy 344.512392 -285.687241) (xy 344.504293 -285.738379)
			(xy 344.488294 -285.787619) (xy 344.464788 -285.833751) (xy 344.434356 -285.875638) (xy 344.397746 -285.912248)
			(xy 344.355859 -285.94268) (xy 344.309727 -285.966186) (xy 344.260487 -285.982185) (xy 344.209349 -285.990284)
			(xy 344.157575 -285.990284) (xy 344.106437 -285.982185) (xy 344.057197 -285.966186) (xy 344.011065 -285.94268)
			(xy 343.969178 -285.912248) (xy 343.932568 -285.875638) (xy 343.902136 -285.833751) (xy 343.87863 -285.787619)
			(xy 343.862631 -285.738379) (xy 343.854532 -285.687241) (xy 343.854024 -285.661354) (xy 343.5731 -285.661354)
			(xy 343.5731 -285.661862) (xy 343.572523 -285.689379) (xy 343.563328 -285.74364) (xy 343.554812 -285.769812)
			(xy 343.547192 -285.79191) (xy 343.752424 -286.147256) (xy 343.775284 -286.151574) (xy 343.800106 -286.156737)
			(xy 343.847883 -286.173695) (xy 343.892501 -286.197768) (xy 343.932906 -286.22839) (xy 343.968146 -286.264837)
			(xy 343.997389 -286.30625) (xy 344.019946 -286.351653) (xy 344.035285 -286.399975) (xy 344.043045 -286.450075)
			(xy 344.043508 -286.475424) (xy 344.043 -286.501331) (xy 344.034894 -286.552508) (xy 344.018882 -286.601787)
			(xy 343.995359 -286.647954) (xy 343.964903 -286.689873) (xy 343.928265 -286.726511) (xy 343.886346 -286.756967)
			(xy 343.840179 -286.78049) (xy 343.7909 -286.796502) (xy 343.739723 -286.804608) (xy 343.687909 -286.804608)
			(xy 343.636732 -286.796502) (xy 343.587453 -286.78049) (xy 343.541286 -286.756967) (xy 343.499367 -286.726511)
			(xy 343.462729 -286.689873) (xy 343.432273 -286.647954) (xy 343.40875 -286.601787) (xy 343.392738 -286.552508)
			(xy 343.384632 -286.501331) (xy 343.384124 -286.475424) (xy 343.384723 -286.447707) (xy 343.394043 -286.39306)
			(xy 343.402666 -286.366712) (xy 343.41054 -286.344614) (xy 343.205562 -285.989522) (xy 343.182448 -285.985204)
			(xy 343.157627 -285.980039) (xy 343.109847 -285.963084) (xy 343.065228 -285.939012) (xy 343.024822 -285.908392)
			(xy 342.989581 -285.871945) (xy 342.960337 -285.830531) (xy 342.93778 -285.785127) (xy 342.922443 -285.736804)
			(xy 342.914686 -285.686703) (xy 342.914224 -285.661354) (xy 342.6333 -285.661354) (xy 342.632792 -285.687241)
			(xy 342.624693 -285.738379) (xy 342.608694 -285.787619) (xy 342.585188 -285.833751) (xy 342.554756 -285.875638)
			(xy 342.518146 -285.912248) (xy 342.476259 -285.94268) (xy 342.430127 -285.966186) (xy 342.380887 -285.982185)
			(xy 342.329749 -285.990284) (xy 342.277975 -285.990284) (xy 342.226837 -285.982185) (xy 342.177597 -285.966186)
			(xy 342.131465 -285.94268) (xy 342.089578 -285.912248) (xy 342.052968 -285.875638) (xy 342.022536 -285.833751)
			(xy 341.99903 -285.787619) (xy 341.983031 -285.738379) (xy 341.974932 -285.687241) (xy 341.974424 -285.661354)
			(xy 341.6935 -285.661354) (xy 341.6935 -285.661862) (xy 341.692923 -285.689379) (xy 341.683728 -285.74364)
			(xy 341.675212 -285.769812) (xy 341.667592 -285.79191) (xy 341.872824 -286.147256) (xy 341.895684 -286.151574)
			(xy 341.920506 -286.156737) (xy 341.968283 -286.173695) (xy 342.012901 -286.197768) (xy 342.053306 -286.22839)
			(xy 342.088546 -286.264837) (xy 342.117789 -286.30625) (xy 342.140346 -286.351653) (xy 342.155685 -286.399975)
			(xy 342.163445 -286.450075) (xy 342.163908 -286.475424) (xy 342.1634 -286.501331) (xy 342.155294 -286.552508)
			(xy 342.139282 -286.601787) (xy 342.115759 -286.647954) (xy 342.085303 -286.689873) (xy 342.048665 -286.726511)
			(xy 342.006746 -286.756967) (xy 341.960579 -286.78049) (xy 341.9113 -286.796502) (xy 341.860123 -286.804608)
			(xy 341.808309 -286.804608) (xy 341.757132 -286.796502) (xy 341.707853 -286.78049) (xy 341.661686 -286.756967)
			(xy 341.619767 -286.726511) (xy 341.583129 -286.689873) (xy 341.552673 -286.647954) (xy 341.52915 -286.601787)
			(xy 341.513138 -286.552508) (xy 341.505032 -286.501331) (xy 341.504524 -286.475424) (xy 341.505123 -286.447707)
			(xy 341.514443 -286.39306) (xy 341.523066 -286.366712) (xy 341.53094 -286.344614) (xy 341.325962 -285.989522)
			(xy 341.302848 -285.985204) (xy 341.278027 -285.980039) (xy 341.230247 -285.963084) (xy 341.185628 -285.939012)
			(xy 341.145222 -285.908392) (xy 341.109981 -285.871945) (xy 341.080737 -285.830531) (xy 341.05818 -285.785127)
			(xy 341.042843 -285.736804) (xy 341.035086 -285.686703) (xy 341.034624 -285.661354) (xy 340.7537 -285.661354)
			(xy 340.753192 -285.687241) (xy 340.745093 -285.738379) (xy 340.729094 -285.787619) (xy 340.705588 -285.833751)
			(xy 340.675156 -285.875638) (xy 340.638546 -285.912248) (xy 340.596659 -285.94268) (xy 340.550527 -285.966186)
			(xy 340.501287 -285.982185) (xy 340.450149 -285.990284) (xy 340.398375 -285.990284) (xy 340.347237 -285.982185)
			(xy 340.297997 -285.966186) (xy 340.251865 -285.94268) (xy 340.209978 -285.912248) (xy 340.173368 -285.875638)
			(xy 340.142936 -285.833751) (xy 340.11943 -285.787619) (xy 340.103431 -285.738379) (xy 340.095332 -285.687241)
			(xy 340.094824 -285.661354) (xy 339.814408 -285.661354) (xy 339.813802 -285.689071) (xy 339.804487 -285.743717)
			(xy 339.795866 -285.770066) (xy 339.787992 -285.792164) (xy 339.993224 -286.147256) (xy 340.016084 -286.151574)
			(xy 340.040906 -286.156737) (xy 340.088683 -286.173695) (xy 340.133301 -286.197768) (xy 340.173706 -286.22839)
			(xy 340.208946 -286.264837) (xy 340.238189 -286.30625) (xy 340.260746 -286.351653) (xy 340.276085 -286.399975)
			(xy 340.283845 -286.450075) (xy 340.284308 -286.475424) (xy 340.2838 -286.501331) (xy 340.275694 -286.552508)
			(xy 340.259682 -286.601787) (xy 340.236159 -286.647954) (xy 340.205703 -286.689873) (xy 340.169065 -286.726511)
			(xy 340.127146 -286.756967) (xy 340.080979 -286.78049) (xy 340.0317 -286.796502) (xy 339.980523 -286.804608)
			(xy 339.928709 -286.804608) (xy 339.877532 -286.796502) (xy 339.828253 -286.78049) (xy 339.782086 -286.756967)
			(xy 339.740167 -286.726511) (xy 339.703529 -286.689873) (xy 339.673073 -286.647954) (xy 339.64955 -286.601787)
			(xy 339.633538 -286.552508) (xy 339.625432 -286.501331) (xy 339.624924 -286.475424) (xy 339.625523 -286.447707)
			(xy 339.634843 -286.39306) (xy 339.643466 -286.366712) (xy 339.65134 -286.344614) (xy 339.446108 -285.989522)
			(xy 339.423248 -285.985204) (xy 339.398427 -285.980039) (xy 339.350647 -285.963084) (xy 339.306028 -285.939012)
			(xy 339.265622 -285.908392) (xy 339.230381 -285.871945) (xy 339.201137 -285.830531) (xy 339.17858 -285.785127)
			(xy 339.163243 -285.736804) (xy 339.155486 -285.686703) (xy 339.155024 -285.661354) (xy 338.874608 -285.661354)
			(xy 338.8741 -285.687261) (xy 338.865994 -285.738438) (xy 338.849982 -285.787717) (xy 338.826459 -285.833884)
			(xy 338.796003 -285.875803) (xy 338.759365 -285.912441) (xy 338.717446 -285.942897) (xy 338.671279 -285.96642)
			(xy 338.622 -285.982432) (xy 338.570823 -285.990538) (xy 338.519009 -285.990538) (xy 338.467832 -285.982432)
			(xy 338.418553 -285.96642) (xy 338.372386 -285.942897) (xy 338.330467 -285.912441) (xy 338.293829 -285.875803)
			(xy 338.263373 -285.833884) (xy 338.23985 -285.787717) (xy 338.223838 -285.738438) (xy 338.215732 -285.687261)
			(xy 338.215224 -285.661354) (xy 337.9343 -285.661354) (xy 337.933759 -285.689062) (xy 337.924571 -285.743708)
			(xy 337.916012 -285.770066) (xy 337.908138 -285.792164) (xy 338.11337 -286.147256) (xy 338.13623 -286.151574)
			(xy 338.16104 -286.156732) (xy 338.20878 -286.173726) (xy 338.253357 -286.197824) (xy 338.293722 -286.228459)
			(xy 338.328925 -286.264909) (xy 338.358136 -286.306317) (xy 338.380667 -286.351707) (xy 338.395988 -286.400009)
			(xy 338.403738 -286.450087) (xy 338.4042 -286.475424) (xy 338.403692 -286.501311) (xy 338.395593 -286.552449)
			(xy 338.379594 -286.601689) (xy 338.356088 -286.647821) (xy 338.325656 -286.689708) (xy 338.289046 -286.726318)
			(xy 338.247159 -286.75675) (xy 338.201027 -286.780256) (xy 338.151787 -286.796255) (xy 338.100649 -286.804354)
			(xy 338.048875 -286.804354) (xy 337.997737 -286.796255) (xy 337.948497 -286.780256) (xy 337.902365 -286.75675)
			(xy 337.860478 -286.726318) (xy 337.823868 -286.689708) (xy 337.793436 -286.647821) (xy 337.76993 -286.601689)
			(xy 337.753931 -286.552449) (xy 337.745832 -286.501311) (xy 337.745324 -286.475424) (xy 337.745858 -286.447716)
			(xy 337.75505 -286.393069) (xy 337.763612 -286.366712) (xy 337.771486 -286.344614) (xy 337.566254 -285.989522)
			(xy 337.543394 -285.985204) (xy 337.518583 -285.980049) (xy 337.470842 -285.963057) (xy 337.426263 -285.93896)
			(xy 337.385896 -285.908325) (xy 337.350693 -285.871874) (xy 337.321482 -285.830466) (xy 337.298951 -285.785075)
			(xy 337.283632 -285.736771) (xy 337.275885 -285.686692) (xy 337.275424 -285.661354) (xy 134.164832 -285.661354)
			(xy 134.164372 -285.686689) (xy 134.156613 -285.736761) (xy 134.141285 -285.785057) (xy 134.118749 -285.830439)
			(xy 134.089536 -285.87184) (xy 134.054334 -285.908285) (xy 134.013971 -285.938915) (xy 133.969397 -285.963011)
			(xy 133.921662 -285.980004) (xy 133.896862 -285.985204) (xy 133.874002 -285.989522) (xy 133.669024 -286.344614)
			(xy 133.676898 -286.366458) (xy 133.685549 -286.392865) (xy 133.694866 -286.447642) (xy 133.69544 -286.475424)
			(xy 333.986124 -286.475424) (xy 333.986632 -286.449537) (xy 333.994731 -286.398399) (xy 334.01073 -286.349159)
			(xy 334.034236 -286.303027) (xy 334.064668 -286.26114) (xy 334.101278 -286.22453) (xy 334.143165 -286.194098)
			(xy 334.189297 -286.170592) (xy 334.238537 -286.154593) (xy 334.289675 -286.146494) (xy 334.341449 -286.146494)
			(xy 334.392587 -286.154593) (xy 334.441827 -286.170592) (xy 334.487959 -286.194098) (xy 334.529846 -286.22453)
			(xy 334.566456 -286.26114) (xy 334.596888 -286.303027) (xy 334.620394 -286.349159) (xy 334.636393 -286.398399)
			(xy 334.644492 -286.449537) (xy 334.645 -286.475424) (xy 334.644476 -286.503132) (xy 334.635277 -286.557779)
			(xy 334.626712 -286.584136) (xy 334.619092 -286.60598) (xy 334.82407 -286.961072) (xy 334.84693 -286.96539)
			(xy 334.871744 -286.970533) (xy 334.919484 -286.987528) (xy 334.964063 -287.011628) (xy 335.004428 -287.042264)
			(xy 335.039631 -287.078717) (xy 335.068841 -287.120126) (xy 335.091372 -287.165518) (xy 335.106691 -287.213822)
			(xy 335.114439 -287.263902) (xy 335.1149 -287.28924) (xy 335.114392 -287.315127) (xy 335.106293 -287.366265)
			(xy 335.090294 -287.415505) (xy 335.066788 -287.461637) (xy 335.036356 -287.503524) (xy 334.999746 -287.540134)
			(xy 334.957859 -287.570566) (xy 334.911727 -287.594072) (xy 334.862487 -287.610071) (xy 334.811349 -287.61817)
			(xy 334.759575 -287.61817) (xy 334.708437 -287.610071) (xy 334.659197 -287.594072) (xy 334.613065 -287.570566)
			(xy 334.571178 -287.540134) (xy 334.534568 -287.503524) (xy 334.504136 -287.461637) (xy 334.48063 -287.415505)
			(xy 334.464631 -287.366265) (xy 334.456532 -287.315127) (xy 334.456024 -287.28924) (xy 334.456562 -287.261532)
			(xy 334.465751 -287.206885) (xy 334.474312 -287.180528) (xy 334.481932 -287.158684) (xy 334.276954 -286.803592)
			(xy 334.254094 -286.799274) (xy 334.229299 -286.794053) (xy 334.181562 -286.777067) (xy 334.136987 -286.752976)
			(xy 334.096622 -286.722349) (xy 334.061419 -286.685906) (xy 334.032206 -286.644507) (xy 334.009672 -286.599125)
			(xy 333.994346 -286.55083) (xy 333.98659 -286.500758) (xy 333.986124 -286.475424) (xy 133.69544 -286.475424)
			(xy 133.694932 -286.501331) (xy 133.686826 -286.552508) (xy 133.670814 -286.601787) (xy 133.647291 -286.647954)
			(xy 133.616835 -286.689873) (xy 133.580197 -286.726511) (xy 133.538278 -286.756967) (xy 133.492111 -286.78049)
			(xy 133.442832 -286.796502) (xy 133.391655 -286.804608) (xy 133.339841 -286.804608) (xy 133.288664 -286.796502)
			(xy 133.239385 -286.78049) (xy 133.193218 -286.756967) (xy 133.151299 -286.726511) (xy 133.114661 -286.689873)
			(xy 133.084205 -286.647954) (xy 133.060682 -286.601787) (xy 133.04467 -286.552508) (xy 133.036564 -286.501331)
			(xy 133.036056 -286.475424) (xy 131.81584 -286.475424) (xy 131.815332 -286.501331) (xy 131.807226 -286.552508)
			(xy 131.791214 -286.601787) (xy 131.767691 -286.647954) (xy 131.737235 -286.689873) (xy 131.700597 -286.726511)
			(xy 131.658678 -286.756967) (xy 131.612511 -286.78049) (xy 131.563232 -286.796502) (xy 131.512055 -286.804608)
			(xy 131.460241 -286.804608) (xy 131.409064 -286.796502) (xy 131.359785 -286.78049) (xy 131.313618 -286.756967)
			(xy 131.271699 -286.726511) (xy 131.235061 -286.689873) (xy 131.204605 -286.647954) (xy 131.181082 -286.601787)
			(xy 131.16507 -286.552508) (xy 131.156964 -286.501331) (xy 131.156456 -286.475424) (xy 129.93624 -286.475424)
			(xy 129.935732 -286.501331) (xy 129.927626 -286.552508) (xy 129.911614 -286.601787) (xy 129.888091 -286.647954)
			(xy 129.857635 -286.689873) (xy 129.820997 -286.726511) (xy 129.779078 -286.756967) (xy 129.732911 -286.78049)
			(xy 129.683632 -286.796502) (xy 129.632455 -286.804608) (xy 129.580641 -286.804608) (xy 129.529464 -286.796502)
			(xy 129.480185 -286.78049) (xy 129.434018 -286.756967) (xy 129.392099 -286.726511) (xy 129.355461 -286.689873)
			(xy 129.325005 -286.647954) (xy 129.301482 -286.601787) (xy 129.28547 -286.552508) (xy 129.277364 -286.501331)
			(xy 129.276856 -286.475424) (xy 128.05664 -286.475424) (xy 128.056132 -286.501331) (xy 128.048026 -286.552508)
			(xy 128.032014 -286.601787) (xy 128.008491 -286.647954) (xy 127.978035 -286.689873) (xy 127.941397 -286.726511)
			(xy 127.899478 -286.756967) (xy 127.853311 -286.78049) (xy 127.804032 -286.796502) (xy 127.752855 -286.804608)
			(xy 127.701041 -286.804608) (xy 127.649864 -286.796502) (xy 127.600585 -286.78049) (xy 127.554418 -286.756967)
			(xy 127.512499 -286.726511) (xy 127.475861 -286.689873) (xy 127.445405 -286.647954) (xy 127.421882 -286.601787)
			(xy 127.40587 -286.552508) (xy 127.397764 -286.501331) (xy 127.397256 -286.475424) (xy 126.17704 -286.475424)
			(xy 126.176532 -286.501331) (xy 126.168426 -286.552508) (xy 126.152414 -286.601787) (xy 126.128891 -286.647954)
			(xy 126.098435 -286.689873) (xy 126.061797 -286.726511) (xy 126.019878 -286.756967) (xy 125.973711 -286.78049)
			(xy 125.924432 -286.796502) (xy 125.873255 -286.804608) (xy 125.821441 -286.804608) (xy 125.770264 -286.796502)
			(xy 125.720985 -286.78049) (xy 125.674818 -286.756967) (xy 125.632899 -286.726511) (xy 125.596261 -286.689873)
			(xy 125.565805 -286.647954) (xy 125.542282 -286.601787) (xy 125.52627 -286.552508) (xy 125.518164 -286.501331)
			(xy 125.517656 -286.475424) (xy 124.29744 -286.475424) (xy 124.296932 -286.501331) (xy 124.288826 -286.552508)
			(xy 124.272814 -286.601787) (xy 124.249291 -286.647954) (xy 124.218835 -286.689873) (xy 124.182197 -286.726511)
			(xy 124.140278 -286.756967) (xy 124.094111 -286.78049) (xy 124.044832 -286.796502) (xy 123.993655 -286.804608)
			(xy 123.941841 -286.804608) (xy 123.890664 -286.796502) (xy 123.841385 -286.78049) (xy 123.795218 -286.756967)
			(xy 123.753299 -286.726511) (xy 123.716661 -286.689873) (xy 123.686205 -286.647954) (xy 123.662682 -286.601787)
			(xy 123.64667 -286.552508) (xy 123.638564 -286.501331) (xy 123.638056 -286.475424) (xy 122.41784 -286.475424)
			(xy 122.417332 -286.501331) (xy 122.409226 -286.552508) (xy 122.393214 -286.601787) (xy 122.369691 -286.647954)
			(xy 122.339235 -286.689873) (xy 122.302597 -286.726511) (xy 122.260678 -286.756967) (xy 122.214511 -286.78049)
			(xy 122.165232 -286.796502) (xy 122.114055 -286.804608) (xy 122.062241 -286.804608) (xy 122.011064 -286.796502)
			(xy 121.961785 -286.78049) (xy 121.915618 -286.756967) (xy 121.873699 -286.726511) (xy 121.837061 -286.689873)
			(xy 121.806605 -286.647954) (xy 121.783082 -286.601787) (xy 121.76707 -286.552508) (xy 121.758964 -286.501331)
			(xy 121.758456 -286.475424) (xy 120.53824 -286.475424) (xy 120.537732 -286.501331) (xy 120.529626 -286.552508)
			(xy 120.513614 -286.601787) (xy 120.490091 -286.647954) (xy 120.459635 -286.689873) (xy 120.422997 -286.726511)
			(xy 120.381078 -286.756967) (xy 120.334911 -286.78049) (xy 120.285632 -286.796502) (xy 120.234455 -286.804608)
			(xy 120.182641 -286.804608) (xy 120.131464 -286.796502) (xy 120.082185 -286.78049) (xy 120.036018 -286.756967)
			(xy 119.994099 -286.726511) (xy 119.957461 -286.689873) (xy 119.927005 -286.647954) (xy 119.903482 -286.601787)
			(xy 119.88747 -286.552508) (xy 119.879364 -286.501331) (xy 119.878856 -286.475424) (xy 103.62184 -286.475424)
			(xy 103.621332 -286.501331) (xy 103.613226 -286.552508) (xy 103.597214 -286.601787) (xy 103.573691 -286.647954)
			(xy 103.543235 -286.689873) (xy 103.506597 -286.726511) (xy 103.464678 -286.756967) (xy 103.418511 -286.78049)
			(xy 103.369232 -286.796502) (xy 103.318055 -286.804608) (xy 103.266241 -286.804608) (xy 103.215064 -286.796502)
			(xy 103.165785 -286.78049) (xy 103.119618 -286.756967) (xy 103.077699 -286.726511) (xy 103.041061 -286.689873)
			(xy 103.010605 -286.647954) (xy 102.987082 -286.601787) (xy 102.97107 -286.552508) (xy 102.962964 -286.501331)
			(xy 102.962456 -286.475424) (xy 102.963053 -286.447707) (xy 102.972374 -286.39306) (xy 102.980998 -286.366712)
			(xy 102.988872 -286.344614) (xy 102.783894 -285.989522) (xy 102.76078 -285.985204) (xy 102.735964 -285.980016)
			(xy 102.688184 -285.963065) (xy 102.643565 -285.938998) (xy 102.603157 -285.908381) (xy 102.567916 -285.871936)
			(xy 102.538671 -285.830525) (xy 102.516113 -285.785123) (xy 102.500775 -285.736802) (xy 102.493018 -285.686702)
			(xy 102.492556 -285.661354) (xy 102.211632 -285.661354) (xy 102.211124 -285.687241) (xy 102.203025 -285.738379)
			(xy 102.187026 -285.787619) (xy 102.16352 -285.833751) (xy 102.133088 -285.875638) (xy 102.096478 -285.912248)
			(xy 102.054591 -285.94268) (xy 102.008459 -285.966186) (xy 101.959219 -285.982185) (xy 101.908081 -285.990284)
			(xy 101.856307 -285.990284) (xy 101.805169 -285.982185) (xy 101.755929 -285.966186) (xy 101.709797 -285.94268)
			(xy 101.66791 -285.912248) (xy 101.6313 -285.875638) (xy 101.600868 -285.833751) (xy 101.577362 -285.787619)
			(xy 101.561363 -285.738379) (xy 101.553264 -285.687241) (xy 101.552756 -285.661354) (xy 101.271832 -285.661354)
			(xy 101.271832 -285.661862) (xy 101.271253 -285.689379) (xy 101.262059 -285.74364) (xy 101.253544 -285.769812)
			(xy 101.245924 -285.79191) (xy 101.451156 -286.147256) (xy 101.474016 -286.151574) (xy 101.498827 -286.156786)
			(xy 101.546604 -286.173734) (xy 101.591223 -286.197799) (xy 101.63163 -286.228413) (xy 101.666872 -286.264855)
			(xy 101.696117 -286.306263) (xy 101.718676 -286.351662) (xy 101.734017 -286.399979) (xy 101.741777 -286.450077)
			(xy 101.74224 -286.475424) (xy 101.741732 -286.501331) (xy 101.733626 -286.552508) (xy 101.717614 -286.601787)
			(xy 101.694091 -286.647954) (xy 101.663635 -286.689873) (xy 101.626997 -286.726511) (xy 101.585078 -286.756967)
			(xy 101.538911 -286.78049) (xy 101.489632 -286.796502) (xy 101.438455 -286.804608) (xy 101.386641 -286.804608)
			(xy 101.335464 -286.796502) (xy 101.286185 -286.78049) (xy 101.240018 -286.756967) (xy 101.198099 -286.726511)
			(xy 101.161461 -286.689873) (xy 101.131005 -286.647954) (xy 101.107482 -286.601787) (xy 101.09147 -286.552508)
			(xy 101.083364 -286.501331) (xy 101.082856 -286.475424) (xy 101.083453 -286.447707) (xy 101.092774 -286.39306)
			(xy 101.101398 -286.366712) (xy 101.109272 -286.344614) (xy 100.904294 -285.989522) (xy 100.88118 -285.985204)
			(xy 100.856364 -285.980016) (xy 100.808584 -285.963065) (xy 100.763965 -285.938998) (xy 100.723557 -285.908381)
			(xy 100.688316 -285.871936) (xy 100.659071 -285.830525) (xy 100.636513 -285.785123) (xy 100.621175 -285.736802)
			(xy 100.613418 -285.686702) (xy 100.612956 -285.661354) (xy 100.332032 -285.661354) (xy 100.331524 -285.687241)
			(xy 100.323425 -285.738379) (xy 100.307426 -285.787619) (xy 100.28392 -285.833751) (xy 100.253488 -285.875638)
			(xy 100.216878 -285.912248) (xy 100.174991 -285.94268) (xy 100.128859 -285.966186) (xy 100.079619 -285.982185)
			(xy 100.028481 -285.990284) (xy 99.976707 -285.990284) (xy 99.925569 -285.982185) (xy 99.876329 -285.966186)
			(xy 99.830197 -285.94268) (xy 99.78831 -285.912248) (xy 99.7517 -285.875638) (xy 99.721268 -285.833751)
			(xy 99.697762 -285.787619) (xy 99.681763 -285.738379) (xy 99.673664 -285.687241) (xy 99.673156 -285.661354)
			(xy 99.392232 -285.661354) (xy 99.392232 -285.661862) (xy 99.391653 -285.689379) (xy 99.382459 -285.74364)
			(xy 99.373944 -285.769812) (xy 99.366324 -285.79191) (xy 99.571556 -286.147256) (xy 99.594416 -286.151574)
			(xy 99.619227 -286.156786) (xy 99.667004 -286.173734) (xy 99.711623 -286.197799) (xy 99.75203 -286.228413)
			(xy 99.787272 -286.264855) (xy 99.816517 -286.306263) (xy 99.839076 -286.351662) (xy 99.854417 -286.399979)
			(xy 99.862177 -286.450077) (xy 99.86264 -286.475424) (xy 99.862132 -286.501331) (xy 99.854026 -286.552508)
			(xy 99.838014 -286.601787) (xy 99.814491 -286.647954) (xy 99.784035 -286.689873) (xy 99.747397 -286.726511)
			(xy 99.705478 -286.756967) (xy 99.659311 -286.78049) (xy 99.610032 -286.796502) (xy 99.558855 -286.804608)
			(xy 99.507041 -286.804608) (xy 99.455864 -286.796502) (xy 99.406585 -286.78049) (xy 99.360418 -286.756967)
			(xy 99.318499 -286.726511) (xy 99.281861 -286.689873) (xy 99.251405 -286.647954) (xy 99.227882 -286.601787)
			(xy 99.21187 -286.552508) (xy 99.203764 -286.501331) (xy 99.203256 -286.475424) (xy 99.203853 -286.447707)
			(xy 99.213174 -286.39306) (xy 99.221798 -286.366712) (xy 99.229672 -286.344614) (xy 99.024694 -285.989522)
			(xy 99.00158 -285.985204) (xy 98.976764 -285.980016) (xy 98.928984 -285.963065) (xy 98.884365 -285.938998)
			(xy 98.843957 -285.908381) (xy 98.808716 -285.871936) (xy 98.779471 -285.830525) (xy 98.756913 -285.785123)
			(xy 98.741575 -285.736802) (xy 98.733818 -285.686702) (xy 98.733356 -285.661354) (xy 98.452432 -285.661354)
			(xy 98.451924 -285.687241) (xy 98.443825 -285.738379) (xy 98.427826 -285.787619) (xy 98.40432 -285.833751)
			(xy 98.373888 -285.875638) (xy 98.337278 -285.912248) (xy 98.295391 -285.94268) (xy 98.249259 -285.966186)
			(xy 98.200019 -285.982185) (xy 98.148881 -285.990284) (xy 98.097107 -285.990284) (xy 98.045969 -285.982185)
			(xy 97.996729 -285.966186) (xy 97.950597 -285.94268) (xy 97.90871 -285.912248) (xy 97.8721 -285.875638)
			(xy 97.841668 -285.833751) (xy 97.818162 -285.787619) (xy 97.802163 -285.738379) (xy 97.794064 -285.687241)
			(xy 97.793556 -285.661354) (xy 97.512632 -285.661354) (xy 97.512632 -285.661862) (xy 97.512053 -285.689379)
			(xy 97.502859 -285.74364) (xy 97.494344 -285.769812) (xy 97.486724 -285.79191) (xy 97.691956 -286.147256)
			(xy 97.714816 -286.151574) (xy 97.739627 -286.156786) (xy 97.787404 -286.173734) (xy 97.832023 -286.197799)
			(xy 97.87243 -286.228413) (xy 97.907672 -286.264855) (xy 97.936917 -286.306263) (xy 97.959476 -286.351662)
			(xy 97.974817 -286.399979) (xy 97.982577 -286.450077) (xy 97.98304 -286.475424) (xy 97.982532 -286.501331)
			(xy 97.974426 -286.552508) (xy 97.958414 -286.601787) (xy 97.934891 -286.647954) (xy 97.904435 -286.689873)
			(xy 97.867797 -286.726511) (xy 97.825878 -286.756967) (xy 97.779711 -286.78049) (xy 97.730432 -286.796502)
			(xy 97.679255 -286.804608) (xy 97.627441 -286.804608) (xy 97.576264 -286.796502) (xy 97.526985 -286.78049)
			(xy 97.480818 -286.756967) (xy 97.438899 -286.726511) (xy 97.402261 -286.689873) (xy 97.371805 -286.647954)
			(xy 97.348282 -286.601787) (xy 97.33227 -286.552508) (xy 97.324164 -286.501331) (xy 97.323656 -286.475424)
			(xy 97.324253 -286.447707) (xy 97.333574 -286.39306) (xy 97.342198 -286.366712) (xy 97.350072 -286.344614)
			(xy 97.145094 -285.989522) (xy 97.12198 -285.985204) (xy 97.097164 -285.980016) (xy 97.049384 -285.963065)
			(xy 97.004765 -285.938998) (xy 96.964357 -285.908381) (xy 96.929116 -285.871936) (xy 96.899871 -285.830525)
			(xy 96.877313 -285.785123) (xy 96.861975 -285.736802) (xy 96.854218 -285.686702) (xy 96.853756 -285.661354)
			(xy 96.572832 -285.661354) (xy 96.572324 -285.687241) (xy 96.564225 -285.738379) (xy 96.548226 -285.787619)
			(xy 96.52472 -285.833751) (xy 96.494288 -285.875638) (xy 96.457678 -285.912248) (xy 96.415791 -285.94268)
			(xy 96.369659 -285.966186) (xy 96.320419 -285.982185) (xy 96.269281 -285.990284) (xy 96.217507 -285.990284)
			(xy 96.166369 -285.982185) (xy 96.117129 -285.966186) (xy 96.070997 -285.94268) (xy 96.02911 -285.912248)
			(xy 95.9925 -285.875638) (xy 95.962068 -285.833751) (xy 95.938562 -285.787619) (xy 95.922563 -285.738379)
			(xy 95.914464 -285.687241) (xy 95.913956 -285.661354) (xy 95.633032 -285.661354) (xy 95.633032 -285.661862)
			(xy 95.632453 -285.689379) (xy 95.623259 -285.74364) (xy 95.614744 -285.769812) (xy 95.607124 -285.79191)
			(xy 95.812356 -286.147256) (xy 95.835216 -286.151574) (xy 95.860027 -286.156786) (xy 95.907804 -286.173734)
			(xy 95.952423 -286.197799) (xy 95.99283 -286.228413) (xy 96.028072 -286.264855) (xy 96.057317 -286.306263)
			(xy 96.079876 -286.351662) (xy 96.095217 -286.399979) (xy 96.102977 -286.450077) (xy 96.10344 -286.475424)
			(xy 96.102932 -286.501331) (xy 96.094826 -286.552508) (xy 96.078814 -286.601787) (xy 96.055291 -286.647954)
			(xy 96.024835 -286.689873) (xy 95.988197 -286.726511) (xy 95.946278 -286.756967) (xy 95.900111 -286.78049)
			(xy 95.850832 -286.796502) (xy 95.799655 -286.804608) (xy 95.747841 -286.804608) (xy 95.696664 -286.796502)
			(xy 95.647385 -286.78049) (xy 95.601218 -286.756967) (xy 95.559299 -286.726511) (xy 95.522661 -286.689873)
			(xy 95.492205 -286.647954) (xy 95.468682 -286.601787) (xy 95.45267 -286.552508) (xy 95.444564 -286.501331)
			(xy 95.444056 -286.475424) (xy 95.444653 -286.447707) (xy 95.453974 -286.39306) (xy 95.462598 -286.366712)
			(xy 95.470472 -286.344614) (xy 95.265494 -285.989522) (xy 95.24238 -285.985204) (xy 95.217564 -285.980016)
			(xy 95.169784 -285.963065) (xy 95.125165 -285.938998) (xy 95.084757 -285.908381) (xy 95.049516 -285.871936)
			(xy 95.020271 -285.830525) (xy 94.997713 -285.785123) (xy 94.982375 -285.736802) (xy 94.974618 -285.686702)
			(xy 94.974156 -285.661354) (xy 94.693232 -285.661354) (xy 94.692724 -285.687241) (xy 94.684625 -285.738379)
			(xy 94.668626 -285.787619) (xy 94.64512 -285.833751) (xy 94.614688 -285.875638) (xy 94.578078 -285.912248)
			(xy 94.536191 -285.94268) (xy 94.490059 -285.966186) (xy 94.440819 -285.982185) (xy 94.389681 -285.990284)
			(xy 94.337907 -285.990284) (xy 94.286769 -285.982185) (xy 94.237529 -285.966186) (xy 94.191397 -285.94268)
			(xy 94.14951 -285.912248) (xy 94.1129 -285.875638) (xy 94.082468 -285.833751) (xy 94.058962 -285.787619)
			(xy 94.042963 -285.738379) (xy 94.034864 -285.687241) (xy 94.034356 -285.661354) (xy 93.753432 -285.661354)
			(xy 93.753432 -285.661862) (xy 93.752853 -285.689379) (xy 93.743659 -285.74364) (xy 93.735144 -285.769812)
			(xy 93.727524 -285.79191) (xy 93.932756 -286.147256) (xy 93.955616 -286.151574) (xy 93.980427 -286.156786)
			(xy 94.028204 -286.173734) (xy 94.072823 -286.197799) (xy 94.11323 -286.228413) (xy 94.148472 -286.264855)
			(xy 94.177717 -286.306263) (xy 94.200276 -286.351662) (xy 94.215617 -286.399979) (xy 94.223377 -286.450077)
			(xy 94.22384 -286.475424) (xy 94.223332 -286.501331) (xy 94.215226 -286.552508) (xy 94.199214 -286.601787)
			(xy 94.175691 -286.647954) (xy 94.145235 -286.689873) (xy 94.108597 -286.726511) (xy 94.066678 -286.756967)
			(xy 94.020511 -286.78049) (xy 93.971232 -286.796502) (xy 93.920055 -286.804608) (xy 93.868241 -286.804608)
			(xy 93.817064 -286.796502) (xy 93.767785 -286.78049) (xy 93.721618 -286.756967) (xy 93.679699 -286.726511)
			(xy 93.643061 -286.689873) (xy 93.612605 -286.647954) (xy 93.589082 -286.601787) (xy 93.57307 -286.552508)
			(xy 93.564964 -286.501331) (xy 93.564456 -286.475424) (xy 93.565053 -286.447707) (xy 93.574374 -286.39306)
			(xy 93.582998 -286.366712) (xy 93.590872 -286.344614) (xy 93.385894 -285.989522) (xy 93.36278 -285.985204)
			(xy 93.337964 -285.980016) (xy 93.290184 -285.963065) (xy 93.245565 -285.938998) (xy 93.205157 -285.908381)
			(xy 93.169916 -285.871936) (xy 93.140671 -285.830525) (xy 93.118113 -285.785123) (xy 93.102775 -285.736802)
			(xy 93.095018 -285.686702) (xy 93.094556 -285.661354) (xy 92.813632 -285.661354) (xy 92.813124 -285.687241)
			(xy 92.805025 -285.738379) (xy 92.789026 -285.787619) (xy 92.76552 -285.833751) (xy 92.735088 -285.875638)
			(xy 92.698478 -285.912248) (xy 92.656591 -285.94268) (xy 92.610459 -285.966186) (xy 92.561219 -285.982185)
			(xy 92.510081 -285.990284) (xy 92.458307 -285.990284) (xy 92.407169 -285.982185) (xy 92.357929 -285.966186)
			(xy 92.311797 -285.94268) (xy 92.26991 -285.912248) (xy 92.2333 -285.875638) (xy 92.202868 -285.833751)
			(xy 92.179362 -285.787619) (xy 92.163363 -285.738379) (xy 92.155264 -285.687241) (xy 92.154756 -285.661354)
			(xy 91.87434 -285.661354) (xy 91.873738 -285.689071) (xy 91.86442 -285.743718) (xy 91.855798 -285.770066)
			(xy 91.847924 -285.792164) (xy 92.053156 -286.147256) (xy 92.076016 -286.151574) (xy 92.100827 -286.156786)
			(xy 92.148604 -286.173734) (xy 92.193223 -286.197799) (xy 92.23363 -286.228413) (xy 92.268872 -286.264855)
			(xy 92.298117 -286.306263) (xy 92.320676 -286.351662) (xy 92.336017 -286.399979) (xy 92.343777 -286.450077)
			(xy 92.34424 -286.475424) (xy 92.343732 -286.501331) (xy 92.335626 -286.552508) (xy 92.319614 -286.601787)
			(xy 92.296091 -286.647954) (xy 92.265635 -286.689873) (xy 92.228997 -286.726511) (xy 92.187078 -286.756967)
			(xy 92.140911 -286.78049) (xy 92.091632 -286.796502) (xy 92.040455 -286.804608) (xy 91.988641 -286.804608)
			(xy 91.937464 -286.796502) (xy 91.888185 -286.78049) (xy 91.842018 -286.756967) (xy 91.800099 -286.726511)
			(xy 91.763461 -286.689873) (xy 91.733005 -286.647954) (xy 91.709482 -286.601787) (xy 91.69347 -286.552508)
			(xy 91.685364 -286.501331) (xy 91.684856 -286.475424) (xy 91.685453 -286.447707) (xy 91.694774 -286.39306)
			(xy 91.703398 -286.366712) (xy 91.711272 -286.344614) (xy 91.50604 -285.989522) (xy 91.48318 -285.985204)
			(xy 91.458364 -285.980016) (xy 91.410584 -285.963065) (xy 91.365965 -285.938998) (xy 91.325557 -285.908381)
			(xy 91.290316 -285.871936) (xy 91.261071 -285.830525) (xy 91.238513 -285.785123) (xy 91.223175 -285.736802)
			(xy 91.215418 -285.686702) (xy 91.214956 -285.661354) (xy 90.93454 -285.661354) (xy 90.934032 -285.687261)
			(xy 90.925926 -285.738438) (xy 90.909914 -285.787717) (xy 90.886391 -285.833884) (xy 90.855935 -285.875803)
			(xy 90.819297 -285.912441) (xy 90.777378 -285.942897) (xy 90.731211 -285.96642) (xy 90.681932 -285.982432)
			(xy 90.630755 -285.990538) (xy 90.578941 -285.990538) (xy 90.527764 -285.982432) (xy 90.478485 -285.96642)
			(xy 90.432318 -285.942897) (xy 90.390399 -285.912441) (xy 90.353761 -285.875803) (xy 90.323305 -285.833884)
			(xy 90.299782 -285.787717) (xy 90.28377 -285.738438) (xy 90.275664 -285.687261) (xy 90.275156 -285.661354)
			(xy 89.994232 -285.661354) (xy 89.993689 -285.689062) (xy 89.984503 -285.743708) (xy 89.975944 -285.770066)
			(xy 89.96807 -285.792164) (xy 90.173302 -286.147256) (xy 90.196162 -286.151574) (xy 90.220961 -286.156781)
			(xy 90.268701 -286.173765) (xy 90.31328 -286.197855) (xy 90.353647 -286.228483) (xy 90.388851 -286.264927)
			(xy 90.418064 -286.30633) (xy 90.440597 -286.351715) (xy 90.455919 -286.400014) (xy 90.46367 -286.450088)
			(xy 90.464132 -286.475424) (xy 90.463624 -286.501311) (xy 90.455525 -286.552449) (xy 90.439526 -286.601689)
			(xy 90.41602 -286.647821) (xy 90.385588 -286.689708) (xy 90.348978 -286.726318) (xy 90.307091 -286.75675)
			(xy 90.260959 -286.780256) (xy 90.211719 -286.796255) (xy 90.160581 -286.804354) (xy 90.108807 -286.804354)
			(xy 90.057669 -286.796255) (xy 90.008429 -286.780256) (xy 89.962297 -286.75675) (xy 89.92041 -286.726318)
			(xy 89.8838 -286.689708) (xy 89.853368 -286.647821) (xy 89.829862 -286.601689) (xy 89.813863 -286.552449)
			(xy 89.805764 -286.501311) (xy 89.805256 -286.475424) (xy 89.805793 -286.447716) (xy 89.814983 -286.393069)
			(xy 89.823544 -286.366712) (xy 89.831418 -286.344614) (xy 89.626186 -285.989522) (xy 89.603326 -285.985204)
			(xy 89.57852 -285.980026) (xy 89.530779 -285.963039) (xy 89.486199 -285.938946) (xy 89.445832 -285.908314)
			(xy 89.410627 -285.871866) (xy 89.381416 -285.83046) (xy 89.358884 -285.785071) (xy 89.343564 -285.736769)
			(xy 89.335817 -285.686691) (xy 89.335356 -285.661354) (xy 2.509012 -285.661354) (xy 2.509012 -286.475424)
			(xy 86.046056 -286.475424) (xy 86.046564 -286.449537) (xy 86.054663 -286.398399) (xy 86.070662 -286.349159)
			(xy 86.094168 -286.303027) (xy 86.1246 -286.26114) (xy 86.16121 -286.22453) (xy 86.203097 -286.194098)
			(xy 86.249229 -286.170592) (xy 86.298469 -286.154593) (xy 86.349607 -286.146494) (xy 86.401381 -286.146494)
			(xy 86.452519 -286.154593) (xy 86.501759 -286.170592) (xy 86.547891 -286.194098) (xy 86.589778 -286.22453)
			(xy 86.626388 -286.26114) (xy 86.65682 -286.303027) (xy 86.680326 -286.349159) (xy 86.696325 -286.398399)
			(xy 86.704424 -286.449537) (xy 86.704932 -286.475424) (xy 86.704407 -286.503132) (xy 86.695209 -286.557779)
			(xy 86.686644 -286.584136) (xy 86.679024 -286.60598) (xy 86.884002 -286.961072) (xy 86.906862 -286.96539)
			(xy 86.931665 -286.970582) (xy 86.979406 -286.987567) (xy 87.023985 -287.011659) (xy 87.064353 -287.042288)
			(xy 87.099557 -287.078734) (xy 87.12877 -287.120139) (xy 87.151302 -287.165526) (xy 87.166622 -287.213827)
			(xy 87.174371 -287.263904) (xy 87.174832 -287.28924) (xy 87.174324 -287.315127) (xy 87.166225 -287.366265)
			(xy 87.150226 -287.415505) (xy 87.12672 -287.461637) (xy 87.096288 -287.503524) (xy 87.059678 -287.540134)
			(xy 87.017791 -287.570566) (xy 86.971659 -287.594072) (xy 86.922419 -287.610071) (xy 86.871281 -287.61817)
			(xy 86.819507 -287.61817) (xy 86.768369 -287.610071) (xy 86.719129 -287.594072) (xy 86.672997 -287.570566)
			(xy 86.63111 -287.540134) (xy 86.5945 -287.503524) (xy 86.564068 -287.461637) (xy 86.540562 -287.415505)
			(xy 86.524563 -287.366265) (xy 86.516464 -287.315127) (xy 86.515956 -287.28924) (xy 86.516497 -287.261532)
			(xy 86.525685 -287.206886) (xy 86.534244 -287.180528) (xy 86.541864 -287.158684) (xy 86.336886 -286.803592)
			(xy 86.314026 -286.799274) (xy 86.289236 -286.79403) (xy 86.241499 -286.777048) (xy 86.196923 -286.752961)
			(xy 86.156558 -286.722338) (xy 86.121354 -286.685898) (xy 86.09214 -286.644501) (xy 86.069605 -286.599121)
			(xy 86.054278 -286.550828) (xy 86.046522 -286.500758) (xy 86.046056 -286.475424) (xy 2.509012 -286.475424)
			(xy 2.509012 -288.917126) (xy 88.395556 -288.917126) (xy 88.396056 -288.891781) (xy 88.403825 -288.84169)
			(xy 88.419169 -288.793377) (xy 88.441727 -288.747983) (xy 88.470967 -288.706576) (xy 88.506199 -288.670131)
			(xy 88.546595 -288.639509) (xy 88.591201 -288.61543) (xy 88.638966 -288.598461) (xy 88.66378 -288.593276)
			(xy 88.68664 -288.588958) (xy 88.891618 -288.233866) (xy 88.883744 -288.212022) (xy 88.875171 -288.185601)
			(xy 88.86597 -288.130828) (xy 88.865456 -288.103056) (xy 88.865964 -288.077169) (xy 88.874063 -288.026031)
			(xy 88.890062 -287.976791) (xy 88.913568 -287.930659) (xy 88.944 -287.888772) (xy 88.98061 -287.852162)
			(xy 89.022497 -287.82173) (xy 89.068629 -287.798224) (xy 89.117869 -287.782225) (xy 89.169007 -287.774126)
			(xy 89.220781 -287.774126) (xy 89.271919 -287.782225) (xy 89.321159 -287.798224) (xy 89.367291 -287.82173)
			(xy 89.409178 -287.852162) (xy 89.445788 -287.888772) (xy 89.47622 -287.930659) (xy 89.499726 -287.976791)
			(xy 89.515725 -288.026031) (xy 89.523824 -288.077169) (xy 89.524332 -288.103056) (xy 89.523874 -288.128391)
			(xy 89.516115 -288.178463) (xy 89.500786 -288.226759) (xy 89.47825 -288.272141) (xy 89.449037 -288.313542)
			(xy 89.413835 -288.349987) (xy 89.373471 -288.380617) (xy 89.328897 -288.404713) (xy 89.281162 -288.421706)
			(xy 89.256362 -288.426906) (xy 89.233502 -288.431224) (xy 89.028524 -288.786316) (xy 89.036398 -288.80816)
			(xy 89.045049 -288.834567) (xy 89.054366 -288.889344) (xy 89.05494 -288.917126) (xy 90.275156 -288.917126)
			(xy 90.275656 -288.891781) (xy 90.283425 -288.84169) (xy 90.298769 -288.793377) (xy 90.321327 -288.747983)
			(xy 90.350567 -288.706576) (xy 90.385799 -288.670131) (xy 90.426195 -288.639509) (xy 90.470801 -288.61543)
			(xy 90.518566 -288.598461) (xy 90.54338 -288.593276) (xy 90.56624 -288.588958) (xy 90.771218 -288.233866)
			(xy 90.763344 -288.212022) (xy 90.754771 -288.185601) (xy 90.74557 -288.130828) (xy 90.745056 -288.103056)
			(xy 90.745564 -288.077169) (xy 90.753663 -288.026031) (xy 90.769662 -287.976791) (xy 90.793168 -287.930659)
			(xy 90.8236 -287.888772) (xy 90.86021 -287.852162) (xy 90.902097 -287.82173) (xy 90.948229 -287.798224)
			(xy 90.997469 -287.782225) (xy 91.048607 -287.774126) (xy 91.100381 -287.774126) (xy 91.151519 -287.782225)
			(xy 91.200759 -287.798224) (xy 91.246891 -287.82173) (xy 91.288778 -287.852162) (xy 91.325388 -287.888772)
			(xy 91.35582 -287.930659) (xy 91.379326 -287.976791) (xy 91.395325 -288.026031) (xy 91.403424 -288.077169)
			(xy 91.403932 -288.103056) (xy 91.403474 -288.128391) (xy 91.395715 -288.178463) (xy 91.380386 -288.226759)
			(xy 91.35785 -288.272141) (xy 91.328637 -288.313542) (xy 91.293435 -288.349987) (xy 91.253071 -288.380617)
			(xy 91.208497 -288.404713) (xy 91.160762 -288.421706) (xy 91.135962 -288.426906) (xy 91.113102 -288.431224)
			(xy 90.908124 -288.786316) (xy 90.915998 -288.80816) (xy 90.924649 -288.834567) (xy 90.933966 -288.889344)
			(xy 90.93454 -288.917126) (xy 91.214956 -288.917126) (xy 91.215464 -288.891219) (xy 91.22357 -288.840042)
			(xy 91.239582 -288.790763) (xy 91.263105 -288.744596) (xy 91.293561 -288.702677) (xy 91.330199 -288.666039)
			(xy 91.372118 -288.635583) (xy 91.418285 -288.61206) (xy 91.467564 -288.596048) (xy 91.518741 -288.587942)
			(xy 91.570555 -288.587942) (xy 91.621732 -288.596048) (xy 91.671011 -288.61206) (xy 91.717178 -288.635583)
			(xy 91.759097 -288.666039) (xy 91.795735 -288.702677) (xy 91.826191 -288.744596) (xy 91.849714 -288.790763)
			(xy 91.865726 -288.840042) (xy 91.873832 -288.891219) (xy 91.87434 -288.917126) (xy 92.154756 -288.917126)
			(xy 92.155256 -288.891781) (xy 92.163025 -288.84169) (xy 92.178369 -288.793377) (xy 92.200927 -288.747983)
			(xy 92.230167 -288.706576) (xy 92.265399 -288.670131) (xy 92.305795 -288.639509) (xy 92.350401 -288.61543)
			(xy 92.398166 -288.598461) (xy 92.42298 -288.593276) (xy 92.44584 -288.588958) (xy 92.651072 -288.233866)
			(xy 92.643198 -288.211768) (xy 92.634576 -288.185419) (xy 92.625249 -288.130773) (xy 92.624656 -288.103056)
			(xy 92.625164 -288.077149) (xy 92.63327 -288.025972) (xy 92.649282 -287.976693) (xy 92.672805 -287.930526)
			(xy 92.703261 -287.888607) (xy 92.739899 -287.851969) (xy 92.781818 -287.821513) (xy 92.827985 -287.79799)
			(xy 92.877264 -287.781978) (xy 92.928441 -287.773872) (xy 92.980255 -287.773872) (xy 93.031432 -287.781978)
			(xy 93.080711 -287.79799) (xy 93.126878 -287.821513) (xy 93.168797 -287.851969) (xy 93.205435 -287.888607)
			(xy 93.235891 -287.930526) (xy 93.259414 -287.976693) (xy 93.275426 -288.025972) (xy 93.283532 -288.077149)
			(xy 93.28404 -288.103056) (xy 93.283618 -288.128404) (xy 93.275836 -288.178499) (xy 93.26048 -288.226813)
			(xy 93.237912 -288.272208) (xy 93.208662 -288.313614) (xy 93.173421 -288.350057) (xy 93.133018 -288.380678)
			(xy 93.088405 -288.404755) (xy 93.040632 -288.421722) (xy 93.015816 -288.426906) (xy 92.992956 -288.431224)
			(xy 92.787724 -288.786316) (xy 92.795598 -288.808414) (xy 92.80424 -288.834757) (xy 92.813554 -288.889407)
			(xy 92.81414 -288.917126) (xy 93.094556 -288.917126) (xy 93.095064 -288.891219) (xy 93.10317 -288.840042)
			(xy 93.119182 -288.790763) (xy 93.142705 -288.744596) (xy 93.173161 -288.702677) (xy 93.209799 -288.666039)
			(xy 93.251718 -288.635583) (xy 93.297885 -288.61206) (xy 93.347164 -288.596048) (xy 93.398341 -288.587942)
			(xy 93.450155 -288.587942) (xy 93.501332 -288.596048) (xy 93.550611 -288.61206) (xy 93.596778 -288.635583)
			(xy 93.638697 -288.666039) (xy 93.675335 -288.702677) (xy 93.705791 -288.744596) (xy 93.729314 -288.790763)
			(xy 93.745326 -288.840042) (xy 93.753432 -288.891219) (xy 93.75394 -288.917126) (xy 94.034356 -288.917126)
			(xy 94.034856 -288.891781) (xy 94.042625 -288.84169) (xy 94.057969 -288.793377) (xy 94.080527 -288.747983)
			(xy 94.109767 -288.706576) (xy 94.144999 -288.670131) (xy 94.185395 -288.639509) (xy 94.230001 -288.61543)
			(xy 94.277766 -288.598461) (xy 94.30258 -288.593276) (xy 94.32544 -288.588958) (xy 94.530672 -288.233866)
			(xy 94.522798 -288.211768) (xy 94.514176 -288.185419) (xy 94.504849 -288.130773) (xy 94.504256 -288.103056)
			(xy 94.504764 -288.077149) (xy 94.51287 -288.025972) (xy 94.528882 -287.976693) (xy 94.552405 -287.930526)
			(xy 94.582861 -287.888607) (xy 94.619499 -287.851969) (xy 94.661418 -287.821513) (xy 94.707585 -287.79799)
			(xy 94.756864 -287.781978) (xy 94.808041 -287.773872) (xy 94.859855 -287.773872) (xy 94.911032 -287.781978)
			(xy 94.960311 -287.79799) (xy 95.006478 -287.821513) (xy 95.048397 -287.851969) (xy 95.085035 -287.888607)
			(xy 95.115491 -287.930526) (xy 95.139014 -287.976693) (xy 95.155026 -288.025972) (xy 95.163132 -288.077149)
			(xy 95.16364 -288.103056) (xy 95.163218 -288.128404) (xy 95.155436 -288.178499) (xy 95.14008 -288.226813)
			(xy 95.117512 -288.272208) (xy 95.088262 -288.313614) (xy 95.053021 -288.350057) (xy 95.012618 -288.380678)
			(xy 94.968005 -288.404755) (xy 94.920232 -288.421722) (xy 94.895416 -288.426906) (xy 94.872556 -288.431224)
			(xy 94.667324 -288.786316) (xy 94.675198 -288.808414) (xy 94.68384 -288.834757) (xy 94.693154 -288.889407)
			(xy 94.69374 -288.917126) (xy 94.974156 -288.917126) (xy 94.974664 -288.891219) (xy 94.98277 -288.840042)
			(xy 94.998782 -288.790763) (xy 95.022305 -288.744596) (xy 95.052761 -288.702677) (xy 95.089399 -288.666039)
			(xy 95.131318 -288.635583) (xy 95.177485 -288.61206) (xy 95.226764 -288.596048) (xy 95.277941 -288.587942)
			(xy 95.329755 -288.587942) (xy 95.380932 -288.596048) (xy 95.430211 -288.61206) (xy 95.476378 -288.635583)
			(xy 95.518297 -288.666039) (xy 95.554935 -288.702677) (xy 95.585391 -288.744596) (xy 95.608914 -288.790763)
			(xy 95.624926 -288.840042) (xy 95.633032 -288.891219) (xy 95.63354 -288.917126) (xy 95.913956 -288.917126)
			(xy 95.914456 -288.891781) (xy 95.922225 -288.84169) (xy 95.937569 -288.793377) (xy 95.960127 -288.747983)
			(xy 95.989367 -288.706576) (xy 96.024599 -288.670131) (xy 96.064995 -288.639509) (xy 96.109601 -288.61543)
			(xy 96.157366 -288.598461) (xy 96.18218 -288.593276) (xy 96.20504 -288.588958) (xy 96.410272 -288.233866)
			(xy 96.402398 -288.211768) (xy 96.393776 -288.185419) (xy 96.384449 -288.130773) (xy 96.383856 -288.103056)
			(xy 96.384364 -288.077149) (xy 96.39247 -288.025972) (xy 96.408482 -287.976693) (xy 96.432005 -287.930526)
			(xy 96.462461 -287.888607) (xy 96.499099 -287.851969) (xy 96.541018 -287.821513) (xy 96.587185 -287.79799)
			(xy 96.636464 -287.781978) (xy 96.687641 -287.773872) (xy 96.739455 -287.773872) (xy 96.790632 -287.781978)
			(xy 96.839911 -287.79799) (xy 96.886078 -287.821513) (xy 96.927997 -287.851969) (xy 96.964635 -287.888607)
			(xy 96.995091 -287.930526) (xy 97.018614 -287.976693) (xy 97.034626 -288.025972) (xy 97.042732 -288.077149)
			(xy 97.04324 -288.103056) (xy 97.042818 -288.128404) (xy 97.035036 -288.178499) (xy 97.01968 -288.226813)
			(xy 96.997112 -288.272208) (xy 96.967862 -288.313614) (xy 96.932621 -288.350057) (xy 96.892218 -288.380678)
			(xy 96.847605 -288.404755) (xy 96.799832 -288.421722) (xy 96.775016 -288.426906) (xy 96.752156 -288.431224)
			(xy 96.546924 -288.786316) (xy 96.554798 -288.808414) (xy 96.56344 -288.834757) (xy 96.572754 -288.889407)
			(xy 96.57334 -288.917126) (xy 96.853756 -288.917126) (xy 96.854264 -288.891219) (xy 96.86237 -288.840042)
			(xy 96.878382 -288.790763) (xy 96.901905 -288.744596) (xy 96.932361 -288.702677) (xy 96.968999 -288.666039)
			(xy 97.010918 -288.635583) (xy 97.057085 -288.61206) (xy 97.106364 -288.596048) (xy 97.157541 -288.587942)
			(xy 97.209355 -288.587942) (xy 97.260532 -288.596048) (xy 97.309811 -288.61206) (xy 97.355978 -288.635583)
			(xy 97.397897 -288.666039) (xy 97.434535 -288.702677) (xy 97.464991 -288.744596) (xy 97.488514 -288.790763)
			(xy 97.504526 -288.840042) (xy 97.512632 -288.891219) (xy 97.51314 -288.917126) (xy 97.793556 -288.917126)
			(xy 97.794056 -288.891781) (xy 97.801825 -288.84169) (xy 97.817169 -288.793377) (xy 97.839727 -288.747983)
			(xy 97.868967 -288.706576) (xy 97.904199 -288.670131) (xy 97.944595 -288.639509) (xy 97.989201 -288.61543)
			(xy 98.036966 -288.598461) (xy 98.06178 -288.593276) (xy 98.08464 -288.588958) (xy 98.289872 -288.233866)
			(xy 98.281998 -288.211768) (xy 98.273376 -288.185419) (xy 98.264049 -288.130773) (xy 98.263456 -288.103056)
			(xy 98.263964 -288.077149) (xy 98.27207 -288.025972) (xy 98.288082 -287.976693) (xy 98.311605 -287.930526)
			(xy 98.342061 -287.888607) (xy 98.378699 -287.851969) (xy 98.420618 -287.821513) (xy 98.466785 -287.79799)
			(xy 98.516064 -287.781978) (xy 98.567241 -287.773872) (xy 98.619055 -287.773872) (xy 98.670232 -287.781978)
			(xy 98.719511 -287.79799) (xy 98.765678 -287.821513) (xy 98.807597 -287.851969) (xy 98.844235 -287.888607)
			(xy 98.874691 -287.930526) (xy 98.898214 -287.976693) (xy 98.914226 -288.025972) (xy 98.922332 -288.077149)
			(xy 98.92284 -288.103056) (xy 98.922418 -288.128404) (xy 98.914636 -288.178499) (xy 98.89928 -288.226813)
			(xy 98.876712 -288.272208) (xy 98.847462 -288.313614) (xy 98.812221 -288.350057) (xy 98.771818 -288.380678)
			(xy 98.727205 -288.404755) (xy 98.679432 -288.421722) (xy 98.654616 -288.426906) (xy 98.631756 -288.431224)
			(xy 98.426524 -288.786316) (xy 98.434398 -288.808414) (xy 98.44304 -288.834757) (xy 98.452354 -288.889407)
			(xy 98.45294 -288.917126) (xy 98.733356 -288.917126) (xy 98.733864 -288.891219) (xy 98.74197 -288.840042)
			(xy 98.757982 -288.790763) (xy 98.781505 -288.744596) (xy 98.811961 -288.702677) (xy 98.848599 -288.666039)
			(xy 98.890518 -288.635583) (xy 98.936685 -288.61206) (xy 98.985964 -288.596048) (xy 99.037141 -288.587942)
			(xy 99.088955 -288.587942) (xy 99.140132 -288.596048) (xy 99.189411 -288.61206) (xy 99.235578 -288.635583)
			(xy 99.277497 -288.666039) (xy 99.314135 -288.702677) (xy 99.344591 -288.744596) (xy 99.368114 -288.790763)
			(xy 99.384126 -288.840042) (xy 99.392232 -288.891219) (xy 99.39274 -288.917126) (xy 99.673156 -288.917126)
			(xy 99.673656 -288.891781) (xy 99.681425 -288.84169) (xy 99.696769 -288.793377) (xy 99.719327 -288.747983)
			(xy 99.748567 -288.706576) (xy 99.783799 -288.670131) (xy 99.824195 -288.639509) (xy 99.868801 -288.61543)
			(xy 99.916566 -288.598461) (xy 99.94138 -288.593276) (xy 99.96424 -288.588958) (xy 100.169472 -288.233866)
			(xy 100.161598 -288.211768) (xy 100.152976 -288.185419) (xy 100.143649 -288.130773) (xy 100.143056 -288.103056)
			(xy 100.143564 -288.077149) (xy 100.15167 -288.025972) (xy 100.167682 -287.976693) (xy 100.191205 -287.930526)
			(xy 100.221661 -287.888607) (xy 100.258299 -287.851969) (xy 100.300218 -287.821513) (xy 100.346385 -287.79799)
			(xy 100.395664 -287.781978) (xy 100.446841 -287.773872) (xy 100.498655 -287.773872) (xy 100.549832 -287.781978)
			(xy 100.599111 -287.79799) (xy 100.645278 -287.821513) (xy 100.687197 -287.851969) (xy 100.723835 -287.888607)
			(xy 100.754291 -287.930526) (xy 100.777814 -287.976693) (xy 100.793826 -288.025972) (xy 100.801932 -288.077149)
			(xy 100.80244 -288.103056) (xy 100.802018 -288.128404) (xy 100.794236 -288.178499) (xy 100.77888 -288.226813)
			(xy 100.756312 -288.272208) (xy 100.727062 -288.313614) (xy 100.691821 -288.350057) (xy 100.651418 -288.380678)
			(xy 100.606805 -288.404755) (xy 100.559032 -288.421722) (xy 100.534216 -288.426906) (xy 100.511356 -288.431224)
			(xy 100.306124 -288.786316) (xy 100.313998 -288.808414) (xy 100.32264 -288.834757) (xy 100.331954 -288.889407)
			(xy 100.33254 -288.917126) (xy 100.612956 -288.917126) (xy 100.613464 -288.891219) (xy 100.62157 -288.840042)
			(xy 100.637582 -288.790763) (xy 100.661105 -288.744596) (xy 100.691561 -288.702677) (xy 100.728199 -288.666039)
			(xy 100.770118 -288.635583) (xy 100.816285 -288.61206) (xy 100.865564 -288.596048) (xy 100.916741 -288.587942)
			(xy 100.968555 -288.587942) (xy 101.019732 -288.596048) (xy 101.069011 -288.61206) (xy 101.115178 -288.635583)
			(xy 101.157097 -288.666039) (xy 101.193735 -288.702677) (xy 101.224191 -288.744596) (xy 101.247714 -288.790763)
			(xy 101.263726 -288.840042) (xy 101.271832 -288.891219) (xy 101.27234 -288.917126) (xy 101.552756 -288.917126)
			(xy 101.553256 -288.891781) (xy 101.561025 -288.84169) (xy 101.576369 -288.793377) (xy 101.598927 -288.747983)
			(xy 101.628167 -288.706576) (xy 101.663399 -288.670131) (xy 101.703795 -288.639509) (xy 101.748401 -288.61543)
			(xy 101.796166 -288.598461) (xy 101.82098 -288.593276) (xy 101.84384 -288.588958) (xy 102.049072 -288.233866)
			(xy 102.041198 -288.211768) (xy 102.032576 -288.185419) (xy 102.023249 -288.130773) (xy 102.022656 -288.103056)
			(xy 102.023164 -288.077149) (xy 102.03127 -288.025972) (xy 102.047282 -287.976693) (xy 102.070805 -287.930526)
			(xy 102.101261 -287.888607) (xy 102.137899 -287.851969) (xy 102.179818 -287.821513) (xy 102.225985 -287.79799)
			(xy 102.275264 -287.781978) (xy 102.326441 -287.773872) (xy 102.378255 -287.773872) (xy 102.429432 -287.781978)
			(xy 102.478711 -287.79799) (xy 102.524878 -287.821513) (xy 102.566797 -287.851969) (xy 102.603435 -287.888607)
			(xy 102.633891 -287.930526) (xy 102.657414 -287.976693) (xy 102.673426 -288.025972) (xy 102.681532 -288.077149)
			(xy 102.68204 -288.103056) (xy 102.681618 -288.128404) (xy 102.673836 -288.178499) (xy 102.65848 -288.226813)
			(xy 102.635912 -288.272208) (xy 102.606662 -288.313614) (xy 102.571421 -288.350057) (xy 102.531018 -288.380678)
			(xy 102.486405 -288.404755) (xy 102.438632 -288.421722) (xy 102.413816 -288.426906) (xy 102.390956 -288.431224)
			(xy 102.185724 -288.786316) (xy 102.193598 -288.808414) (xy 102.20224 -288.834757) (xy 102.211554 -288.889407)
			(xy 102.21214 -288.917126) (xy 102.492556 -288.917126) (xy 102.493064 -288.891219) (xy 102.50117 -288.840042)
			(xy 102.517182 -288.790763) (xy 102.540705 -288.744596) (xy 102.571161 -288.702677) (xy 102.607799 -288.666039)
			(xy 102.649718 -288.635583) (xy 102.695885 -288.61206) (xy 102.745164 -288.596048) (xy 102.796341 -288.587942)
			(xy 102.848155 -288.587942) (xy 102.899332 -288.596048) (xy 102.948611 -288.61206) (xy 102.994778 -288.635583)
			(xy 103.036697 -288.666039) (xy 103.073335 -288.702677) (xy 103.103791 -288.744596) (xy 103.127314 -288.790763)
			(xy 103.143326 -288.840042) (xy 103.151432 -288.891219) (xy 103.15194 -288.917126) (xy 103.432356 -288.917126)
			(xy 103.432856 -288.891781) (xy 103.440625 -288.84169) (xy 103.455969 -288.793377) (xy 103.478527 -288.747983)
			(xy 103.507767 -288.706576) (xy 103.542999 -288.670131) (xy 103.583395 -288.639509) (xy 103.628001 -288.61543)
			(xy 103.675766 -288.598461) (xy 103.70058 -288.593276) (xy 103.72344 -288.588958) (xy 103.928672 -288.233866)
			(xy 103.920798 -288.211768) (xy 103.912176 -288.185419) (xy 103.902849 -288.130773) (xy 103.902256 -288.103056)
			(xy 103.902764 -288.077149) (xy 103.91087 -288.025972) (xy 103.926882 -287.976693) (xy 103.950405 -287.930526)
			(xy 103.980861 -287.888607) (xy 104.017499 -287.851969) (xy 104.059418 -287.821513) (xy 104.105585 -287.79799)
			(xy 104.154864 -287.781978) (xy 104.206041 -287.773872) (xy 104.257855 -287.773872) (xy 104.309032 -287.781978)
			(xy 104.358311 -287.79799) (xy 104.404478 -287.821513) (xy 104.446397 -287.851969) (xy 104.483035 -287.888607)
			(xy 104.513491 -287.930526) (xy 104.537014 -287.976693) (xy 104.553026 -288.025972) (xy 104.561132 -288.077149)
			(xy 104.56164 -288.103056) (xy 120.818656 -288.103056) (xy 120.819164 -288.077149) (xy 120.82727 -288.025972)
			(xy 120.843282 -287.976693) (xy 120.866805 -287.930526) (xy 120.897261 -287.888607) (xy 120.933899 -287.851969)
			(xy 120.975818 -287.821513) (xy 121.021985 -287.79799) (xy 121.071264 -287.781978) (xy 121.122441 -287.773872)
			(xy 121.174255 -287.773872) (xy 121.225432 -287.781978) (xy 121.274711 -287.79799) (xy 121.320878 -287.821513)
			(xy 121.362797 -287.851969) (xy 121.399435 -287.888607) (xy 121.429891 -287.930526) (xy 121.453414 -287.976693)
			(xy 121.469426 -288.025972) (xy 121.477532 -288.077149) (xy 121.47804 -288.103056) (xy 122.698256 -288.103056)
			(xy 122.698764 -288.077149) (xy 122.70687 -288.025972) (xy 122.722882 -287.976693) (xy 122.746405 -287.930526)
			(xy 122.776861 -287.888607) (xy 122.813499 -287.851969) (xy 122.855418 -287.821513) (xy 122.901585 -287.79799)
			(xy 122.950864 -287.781978) (xy 123.002041 -287.773872) (xy 123.053855 -287.773872) (xy 123.105032 -287.781978)
			(xy 123.154311 -287.79799) (xy 123.200478 -287.821513) (xy 123.242397 -287.851969) (xy 123.279035 -287.888607)
			(xy 123.309491 -287.930526) (xy 123.333014 -287.976693) (xy 123.349026 -288.025972) (xy 123.357132 -288.077149)
			(xy 123.35764 -288.103056) (xy 124.577856 -288.103056) (xy 124.578364 -288.077149) (xy 124.58647 -288.025972)
			(xy 124.602482 -287.976693) (xy 124.626005 -287.930526) (xy 124.656461 -287.888607) (xy 124.693099 -287.851969)
			(xy 124.735018 -287.821513) (xy 124.781185 -287.79799) (xy 124.830464 -287.781978) (xy 124.881641 -287.773872)
			(xy 124.933455 -287.773872) (xy 124.984632 -287.781978) (xy 125.033911 -287.79799) (xy 125.080078 -287.821513)
			(xy 125.121997 -287.851969) (xy 125.158635 -287.888607) (xy 125.189091 -287.930526) (xy 125.212614 -287.976693)
			(xy 125.228626 -288.025972) (xy 125.236732 -288.077149) (xy 125.23724 -288.103056) (xy 126.457456 -288.103056)
			(xy 126.457964 -288.077149) (xy 126.46607 -288.025972) (xy 126.482082 -287.976693) (xy 126.505605 -287.930526)
			(xy 126.536061 -287.888607) (xy 126.572699 -287.851969) (xy 126.614618 -287.821513) (xy 126.660785 -287.79799)
			(xy 126.710064 -287.781978) (xy 126.761241 -287.773872) (xy 126.813055 -287.773872) (xy 126.864232 -287.781978)
			(xy 126.913511 -287.79799) (xy 126.959678 -287.821513) (xy 127.001597 -287.851969) (xy 127.038235 -287.888607)
			(xy 127.068691 -287.930526) (xy 127.092214 -287.976693) (xy 127.108226 -288.025972) (xy 127.116332 -288.077149)
			(xy 127.11684 -288.103056) (xy 128.337056 -288.103056) (xy 128.337564 -288.077149) (xy 128.34567 -288.025972)
			(xy 128.361682 -287.976693) (xy 128.385205 -287.930526) (xy 128.415661 -287.888607) (xy 128.452299 -287.851969)
			(xy 128.494218 -287.821513) (xy 128.540385 -287.79799) (xy 128.589664 -287.781978) (xy 128.640841 -287.773872)
			(xy 128.692655 -287.773872) (xy 128.743832 -287.781978) (xy 128.793111 -287.79799) (xy 128.839278 -287.821513)
			(xy 128.881197 -287.851969) (xy 128.917835 -287.888607) (xy 128.948291 -287.930526) (xy 128.971814 -287.976693)
			(xy 128.987826 -288.025972) (xy 128.995932 -288.077149) (xy 128.99644 -288.103056) (xy 130.216656 -288.103056)
			(xy 130.217164 -288.077149) (xy 130.22527 -288.025972) (xy 130.241282 -287.976693) (xy 130.264805 -287.930526)
			(xy 130.295261 -287.888607) (xy 130.331899 -287.851969) (xy 130.373818 -287.821513) (xy 130.419985 -287.79799)
			(xy 130.469264 -287.781978) (xy 130.520441 -287.773872) (xy 130.572255 -287.773872) (xy 130.623432 -287.781978)
			(xy 130.672711 -287.79799) (xy 130.718878 -287.821513) (xy 130.760797 -287.851969) (xy 130.797435 -287.888607)
			(xy 130.827891 -287.930526) (xy 130.851414 -287.976693) (xy 130.867426 -288.025972) (xy 130.875532 -288.077149)
			(xy 130.87604 -288.103056) (xy 132.096256 -288.103056) (xy 132.096764 -288.077149) (xy 132.10487 -288.025972)
			(xy 132.120882 -287.976693) (xy 132.144405 -287.930526) (xy 132.174861 -287.888607) (xy 132.211499 -287.851969)
			(xy 132.253418 -287.821513) (xy 132.299585 -287.79799) (xy 132.348864 -287.781978) (xy 132.400041 -287.773872)
			(xy 132.451855 -287.773872) (xy 132.503032 -287.781978) (xy 132.552311 -287.79799) (xy 132.598478 -287.821513)
			(xy 132.640397 -287.851969) (xy 132.677035 -287.888607) (xy 132.707491 -287.930526) (xy 132.731014 -287.976693)
			(xy 132.747026 -288.025972) (xy 132.755132 -288.077149) (xy 132.75564 -288.103056) (xy 134.915656 -288.103056)
			(xy 134.916164 -288.077149) (xy 134.92427 -288.025972) (xy 134.940282 -287.976693) (xy 134.963805 -287.930526)
			(xy 134.994261 -287.888607) (xy 135.030899 -287.851969) (xy 135.072818 -287.821513) (xy 135.118985 -287.79799)
			(xy 135.168264 -287.781978) (xy 135.219441 -287.773872) (xy 135.271255 -287.773872) (xy 135.322432 -287.781978)
			(xy 135.371711 -287.79799) (xy 135.417878 -287.821513) (xy 135.459797 -287.851969) (xy 135.496435 -287.888607)
			(xy 135.526891 -287.930526) (xy 135.550414 -287.976693) (xy 135.566426 -288.025972) (xy 135.574532 -288.077149)
			(xy 135.57504 -288.103056) (xy 135.574438 -288.130773) (xy 135.56512 -288.18542) (xy 135.556498 -288.211768)
			(xy 135.548624 -288.233866) (xy 135.753856 -288.588958) (xy 135.776716 -288.593276) (xy 135.801527 -288.598486)
			(xy 135.849305 -288.615434) (xy 135.893924 -288.6395) (xy 135.934331 -288.670114) (xy 135.969573 -288.706556)
			(xy 135.998818 -288.747964) (xy 136.021377 -288.793363) (xy 136.036717 -288.841681) (xy 136.044477 -288.891779)
			(xy 136.04494 -288.917126) (xy 336.335624 -288.917126) (xy 336.336149 -288.891782) (xy 336.343918 -288.841693)
			(xy 336.359261 -288.793383) (xy 336.381816 -288.74799) (xy 336.411052 -288.706584) (xy 336.446281 -288.67014)
			(xy 336.486672 -288.639516) (xy 336.531274 -288.615435) (xy 336.579036 -288.598463) (xy 336.603848 -288.593276)
			(xy 336.626708 -288.588958) (xy 336.831686 -288.233866) (xy 336.823812 -288.212022) (xy 336.815238 -288.185602)
			(xy 336.806038 -288.130828) (xy 336.805524 -288.103056) (xy 336.806032 -288.077169) (xy 336.814131 -288.026031)
			(xy 336.83013 -287.976791) (xy 336.853636 -287.930659) (xy 336.884068 -287.888772) (xy 336.920678 -287.852162)
			(xy 336.962565 -287.82173) (xy 337.008697 -287.798224) (xy 337.057937 -287.782225) (xy 337.109075 -287.774126)
			(xy 337.160849 -287.774126) (xy 337.211987 -287.782225) (xy 337.261227 -287.798224) (xy 337.307359 -287.82173)
			(xy 337.349246 -287.852162) (xy 337.385856 -287.888772) (xy 337.416288 -287.930659) (xy 337.439794 -287.976791)
			(xy 337.455793 -288.026031) (xy 337.463892 -288.077169) (xy 337.4644 -288.103056) (xy 337.463968 -288.128392)
			(xy 337.456207 -288.178467) (xy 337.440877 -288.226765) (xy 337.418339 -288.272149) (xy 337.389123 -288.31355)
			(xy 337.353916 -288.349995) (xy 337.313549 -288.380624) (xy 337.268971 -288.404718) (xy 337.221232 -288.421708)
			(xy 337.19643 -288.426906) (xy 337.17357 -288.431224) (xy 336.968592 -288.786316) (xy 336.976466 -288.80816)
			(xy 336.985119 -288.834566) (xy 336.994435 -288.889344) (xy 336.995008 -288.917126) (xy 338.215224 -288.917126)
			(xy 338.215749 -288.891782) (xy 338.223518 -288.841693) (xy 338.238861 -288.793383) (xy 338.261416 -288.74799)
			(xy 338.290652 -288.706584) (xy 338.325881 -288.67014) (xy 338.366272 -288.639516) (xy 338.410874 -288.615435)
			(xy 338.458636 -288.598463) (xy 338.483448 -288.593276) (xy 338.506308 -288.588958) (xy 338.711286 -288.233866)
			(xy 338.703412 -288.212022) (xy 338.694838 -288.185602) (xy 338.685638 -288.130828) (xy 338.685124 -288.103056)
			(xy 338.685632 -288.077169) (xy 338.693731 -288.026031) (xy 338.70973 -287.976791) (xy 338.733236 -287.930659)
			(xy 338.763668 -287.888772) (xy 338.800278 -287.852162) (xy 338.842165 -287.82173) (xy 338.888297 -287.798224)
			(xy 338.937537 -287.782225) (xy 338.988675 -287.774126) (xy 339.040449 -287.774126) (xy 339.091587 -287.782225)
			(xy 339.140827 -287.798224) (xy 339.186959 -287.82173) (xy 339.228846 -287.852162) (xy 339.265456 -287.888772)
			(xy 339.295888 -287.930659) (xy 339.319394 -287.976791) (xy 339.335393 -288.026031) (xy 339.343492 -288.077169)
			(xy 339.344 -288.103056) (xy 339.343568 -288.128392) (xy 339.335807 -288.178467) (xy 339.320477 -288.226765)
			(xy 339.297939 -288.272149) (xy 339.268723 -288.31355) (xy 339.233516 -288.349995) (xy 339.193149 -288.380624)
			(xy 339.148571 -288.404718) (xy 339.100832 -288.421708) (xy 339.07603 -288.426906) (xy 339.05317 -288.431224)
			(xy 338.848192 -288.786316) (xy 338.856066 -288.80816) (xy 338.864719 -288.834566) (xy 338.874035 -288.889344)
			(xy 338.874608 -288.917126) (xy 339.155024 -288.917126) (xy 339.155532 -288.891219) (xy 339.163638 -288.840042)
			(xy 339.17965 -288.790763) (xy 339.203173 -288.744596) (xy 339.233629 -288.702677) (xy 339.270267 -288.666039)
			(xy 339.312186 -288.635583) (xy 339.358353 -288.61206) (xy 339.407632 -288.596048) (xy 339.458809 -288.587942)
			(xy 339.510623 -288.587942) (xy 339.5618 -288.596048) (xy 339.611079 -288.61206) (xy 339.657246 -288.635583)
			(xy 339.699165 -288.666039) (xy 339.735803 -288.702677) (xy 339.766259 -288.744596) (xy 339.789782 -288.790763)
			(xy 339.805794 -288.840042) (xy 339.8139 -288.891219) (xy 339.814408 -288.917126) (xy 340.094824 -288.917126)
			(xy 340.095349 -288.891782) (xy 340.103118 -288.841693) (xy 340.118461 -288.793383) (xy 340.141016 -288.74799)
			(xy 340.170252 -288.706584) (xy 340.205481 -288.67014) (xy 340.245872 -288.639516) (xy 340.290474 -288.615435)
			(xy 340.338236 -288.598463) (xy 340.363048 -288.593276) (xy 340.385908 -288.588958) (xy 340.59114 -288.233866)
			(xy 340.583266 -288.211768) (xy 340.574642 -288.185419) (xy 340.565317 -288.130773) (xy 340.564724 -288.103056)
			(xy 340.565232 -288.077149) (xy 340.573338 -288.025972) (xy 340.58935 -287.976693) (xy 340.612873 -287.930526)
			(xy 340.643329 -287.888607) (xy 340.679967 -287.851969) (xy 340.721886 -287.821513) (xy 340.768053 -287.79799)
			(xy 340.817332 -287.781978) (xy 340.868509 -287.773872) (xy 340.920323 -287.773872) (xy 340.9715 -287.781978)
			(xy 341.020779 -287.79799) (xy 341.066946 -287.821513) (xy 341.108865 -287.851969) (xy 341.145503 -287.888607)
			(xy 341.175959 -287.930526) (xy 341.199482 -287.976693) (xy 341.215494 -288.025972) (xy 341.2236 -288.077149)
			(xy 341.224108 -288.103056) (xy 341.223631 -288.128401) (xy 341.215851 -288.178491) (xy 341.200499 -288.2268)
			(xy 341.177936 -288.272192) (xy 341.148694 -288.313597) (xy 341.11346 -288.35004) (xy 341.073065 -288.380663)
			(xy 341.028461 -288.404744) (xy 340.980697 -288.421718) (xy 340.955884 -288.426906) (xy 340.933024 -288.431224)
			(xy 340.727792 -288.786316) (xy 340.735666 -288.808414) (xy 340.744307 -288.834758) (xy 340.753621 -288.889407)
			(xy 340.754208 -288.917126) (xy 341.034624 -288.917126) (xy 341.035132 -288.891219) (xy 341.043238 -288.840042)
			(xy 341.05925 -288.790763) (xy 341.082773 -288.744596) (xy 341.113229 -288.702677) (xy 341.149867 -288.666039)
			(xy 341.191786 -288.635583) (xy 341.237953 -288.61206) (xy 341.287232 -288.596048) (xy 341.338409 -288.587942)
			(xy 341.390223 -288.587942) (xy 341.4414 -288.596048) (xy 341.490679 -288.61206) (xy 341.536846 -288.635583)
			(xy 341.578765 -288.666039) (xy 341.615403 -288.702677) (xy 341.645859 -288.744596) (xy 341.669382 -288.790763)
			(xy 341.685394 -288.840042) (xy 341.6935 -288.891219) (xy 341.694008 -288.917126) (xy 341.974424 -288.917126)
			(xy 341.974949 -288.891782) (xy 341.982718 -288.841693) (xy 341.998061 -288.793383) (xy 342.020616 -288.74799)
			(xy 342.049852 -288.706584) (xy 342.085081 -288.67014) (xy 342.125472 -288.639516) (xy 342.170074 -288.615435)
			(xy 342.217836 -288.598463) (xy 342.242648 -288.593276) (xy 342.265508 -288.588958) (xy 342.47074 -288.233866)
			(xy 342.462866 -288.211768) (xy 342.454242 -288.185419) (xy 342.444917 -288.130773) (xy 342.444324 -288.103056)
			(xy 342.444832 -288.077149) (xy 342.452938 -288.025972) (xy 342.46895 -287.976693) (xy 342.492473 -287.930526)
			(xy 342.522929 -287.888607) (xy 342.559567 -287.851969) (xy 342.601486 -287.821513) (xy 342.647653 -287.79799)
			(xy 342.696932 -287.781978) (xy 342.748109 -287.773872) (xy 342.799923 -287.773872) (xy 342.8511 -287.781978)
			(xy 342.900379 -287.79799) (xy 342.946546 -287.821513) (xy 342.988465 -287.851969) (xy 343.025103 -287.888607)
			(xy 343.055559 -287.930526) (xy 343.079082 -287.976693) (xy 343.095094 -288.025972) (xy 343.1032 -288.077149)
			(xy 343.103708 -288.103056) (xy 343.103231 -288.128401) (xy 343.095451 -288.178491) (xy 343.080099 -288.2268)
			(xy 343.057536 -288.272192) (xy 343.028294 -288.313597) (xy 342.99306 -288.35004) (xy 342.952665 -288.380663)
			(xy 342.908061 -288.404744) (xy 342.860297 -288.421718) (xy 342.835484 -288.426906) (xy 342.812624 -288.431224)
			(xy 342.607392 -288.786316) (xy 342.615266 -288.808414) (xy 342.623907 -288.834758) (xy 342.633221 -288.889407)
			(xy 342.633808 -288.917126) (xy 342.914224 -288.917126) (xy 342.914732 -288.891219) (xy 342.922838 -288.840042)
			(xy 342.93885 -288.790763) (xy 342.962373 -288.744596) (xy 342.992829 -288.702677) (xy 343.029467 -288.666039)
			(xy 343.071386 -288.635583) (xy 343.117553 -288.61206) (xy 343.166832 -288.596048) (xy 343.218009 -288.587942)
			(xy 343.269823 -288.587942) (xy 343.321 -288.596048) (xy 343.370279 -288.61206) (xy 343.416446 -288.635583)
			(xy 343.458365 -288.666039) (xy 343.495003 -288.702677) (xy 343.525459 -288.744596) (xy 343.548982 -288.790763)
			(xy 343.564994 -288.840042) (xy 343.5731 -288.891219) (xy 343.573608 -288.917126) (xy 343.854024 -288.917126)
			(xy 343.854549 -288.891782) (xy 343.862318 -288.841693) (xy 343.877661 -288.793383) (xy 343.900216 -288.74799)
			(xy 343.929452 -288.706584) (xy 343.964681 -288.67014) (xy 344.005072 -288.639516) (xy 344.049674 -288.615435)
			(xy 344.097436 -288.598463) (xy 344.122248 -288.593276) (xy 344.145108 -288.588958) (xy 344.35034 -288.233866)
			(xy 344.342466 -288.211768) (xy 344.333842 -288.185419) (xy 344.324517 -288.130773) (xy 344.323924 -288.103056)
			(xy 344.324432 -288.077149) (xy 344.332538 -288.025972) (xy 344.34855 -287.976693) (xy 344.372073 -287.930526)
			(xy 344.402529 -287.888607) (xy 344.439167 -287.851969) (xy 344.481086 -287.821513) (xy 344.527253 -287.79799)
			(xy 344.576532 -287.781978) (xy 344.627709 -287.773872) (xy 344.679523 -287.773872) (xy 344.7307 -287.781978)
			(xy 344.779979 -287.79799) (xy 344.826146 -287.821513) (xy 344.868065 -287.851969) (xy 344.904703 -287.888607)
			(xy 344.935159 -287.930526) (xy 344.958682 -287.976693) (xy 344.974694 -288.025972) (xy 344.9828 -288.077149)
			(xy 344.983308 -288.103056) (xy 344.982831 -288.128401) (xy 344.975051 -288.178491) (xy 344.959699 -288.2268)
			(xy 344.937136 -288.272192) (xy 344.907894 -288.313597) (xy 344.87266 -288.35004) (xy 344.832265 -288.380663)
			(xy 344.787661 -288.404744) (xy 344.739897 -288.421718) (xy 344.715084 -288.426906) (xy 344.692224 -288.431224)
			(xy 344.486992 -288.786316) (xy 344.494866 -288.808414) (xy 344.503507 -288.834758) (xy 344.512821 -288.889407)
			(xy 344.513408 -288.917126) (xy 344.793824 -288.917126) (xy 344.794332 -288.891219) (xy 344.802438 -288.840042)
			(xy 344.81845 -288.790763) (xy 344.841973 -288.744596) (xy 344.872429 -288.702677) (xy 344.909067 -288.666039)
			(xy 344.950986 -288.635583) (xy 344.997153 -288.61206) (xy 345.046432 -288.596048) (xy 345.097609 -288.587942)
			(xy 345.149423 -288.587942) (xy 345.2006 -288.596048) (xy 345.249879 -288.61206) (xy 345.296046 -288.635583)
			(xy 345.337965 -288.666039) (xy 345.374603 -288.702677) (xy 345.405059 -288.744596) (xy 345.428582 -288.790763)
			(xy 345.444594 -288.840042) (xy 345.4527 -288.891219) (xy 345.453208 -288.917126) (xy 345.733624 -288.917126)
			(xy 345.734149 -288.891782) (xy 345.741918 -288.841693) (xy 345.757261 -288.793383) (xy 345.779816 -288.74799)
			(xy 345.809052 -288.706584) (xy 345.844281 -288.67014) (xy 345.884672 -288.639516) (xy 345.929274 -288.615435)
			(xy 345.977036 -288.598463) (xy 346.001848 -288.593276) (xy 346.024708 -288.588958) (xy 346.22994 -288.233866)
			(xy 346.222066 -288.211768) (xy 346.213442 -288.185419) (xy 346.204117 -288.130773) (xy 346.203524 -288.103056)
			(xy 346.204032 -288.077149) (xy 346.212138 -288.025972) (xy 346.22815 -287.976693) (xy 346.251673 -287.930526)
			(xy 346.282129 -287.888607) (xy 346.318767 -287.851969) (xy 346.360686 -287.821513) (xy 346.406853 -287.79799)
			(xy 346.456132 -287.781978) (xy 346.507309 -287.773872) (xy 346.559123 -287.773872) (xy 346.6103 -287.781978)
			(xy 346.659579 -287.79799) (xy 346.705746 -287.821513) (xy 346.747665 -287.851969) (xy 346.784303 -287.888607)
			(xy 346.814759 -287.930526) (xy 346.838282 -287.976693) (xy 346.854294 -288.025972) (xy 346.8624 -288.077149)
			(xy 346.862908 -288.103056) (xy 346.862431 -288.128401) (xy 346.854651 -288.178491) (xy 346.839299 -288.2268)
			(xy 346.816736 -288.272192) (xy 346.787494 -288.313597) (xy 346.75226 -288.35004) (xy 346.711865 -288.380663)
			(xy 346.667261 -288.404744) (xy 346.619497 -288.421718) (xy 346.594684 -288.426906) (xy 346.571824 -288.431224)
			(xy 346.366592 -288.786316) (xy 346.374466 -288.808414) (xy 346.383107 -288.834758) (xy 346.392421 -288.889407)
			(xy 346.393008 -288.917126) (xy 346.673424 -288.917126) (xy 346.673932 -288.891219) (xy 346.682038 -288.840042)
			(xy 346.69805 -288.790763) (xy 346.721573 -288.744596) (xy 346.752029 -288.702677) (xy 346.788667 -288.666039)
			(xy 346.830586 -288.635583) (xy 346.876753 -288.61206) (xy 346.926032 -288.596048) (xy 346.977209 -288.587942)
			(xy 347.029023 -288.587942) (xy 347.0802 -288.596048) (xy 347.129479 -288.61206) (xy 347.175646 -288.635583)
			(xy 347.217565 -288.666039) (xy 347.254203 -288.702677) (xy 347.284659 -288.744596) (xy 347.308182 -288.790763)
			(xy 347.324194 -288.840042) (xy 347.3323 -288.891219) (xy 347.332808 -288.917126) (xy 347.613224 -288.917126)
			(xy 347.613749 -288.891782) (xy 347.621518 -288.841693) (xy 347.636861 -288.793383) (xy 347.659416 -288.74799)
			(xy 347.688652 -288.706584) (xy 347.723881 -288.67014) (xy 347.764272 -288.639516) (xy 347.808874 -288.615435)
			(xy 347.856636 -288.598463) (xy 347.881448 -288.593276) (xy 347.904308 -288.588958) (xy 348.10954 -288.233866)
			(xy 348.101666 -288.211768) (xy 348.093042 -288.185419) (xy 348.083717 -288.130773) (xy 348.083124 -288.103056)
			(xy 348.083632 -288.077149) (xy 348.091738 -288.025972) (xy 348.10775 -287.976693) (xy 348.131273 -287.930526)
			(xy 348.161729 -287.888607) (xy 348.198367 -287.851969) (xy 348.240286 -287.821513) (xy 348.286453 -287.79799)
			(xy 348.335732 -287.781978) (xy 348.386909 -287.773872) (xy 348.438723 -287.773872) (xy 348.4899 -287.781978)
			(xy 348.539179 -287.79799) (xy 348.585346 -287.821513) (xy 348.627265 -287.851969) (xy 348.663903 -287.888607)
			(xy 348.694359 -287.930526) (xy 348.717882 -287.976693) (xy 348.733894 -288.025972) (xy 348.742 -288.077149)
			(xy 348.742508 -288.103056) (xy 348.742031 -288.128401) (xy 348.734251 -288.178491) (xy 348.718899 -288.2268)
			(xy 348.696336 -288.272192) (xy 348.667094 -288.313597) (xy 348.63186 -288.35004) (xy 348.591465 -288.380663)
			(xy 348.546861 -288.404744) (xy 348.499097 -288.421718) (xy 348.474284 -288.426906) (xy 348.451424 -288.431224)
			(xy 348.246192 -288.786316) (xy 348.254066 -288.808414) (xy 348.262707 -288.834758) (xy 348.272021 -288.889407)
			(xy 348.272608 -288.917126) (xy 348.553024 -288.917126) (xy 348.553532 -288.891219) (xy 348.561638 -288.840042)
			(xy 348.57765 -288.790763) (xy 348.601173 -288.744596) (xy 348.631629 -288.702677) (xy 348.668267 -288.666039)
			(xy 348.710186 -288.635583) (xy 348.756353 -288.61206) (xy 348.805632 -288.596048) (xy 348.856809 -288.587942)
			(xy 348.908623 -288.587942) (xy 348.9598 -288.596048) (xy 349.009079 -288.61206) (xy 349.055246 -288.635583)
			(xy 349.097165 -288.666039) (xy 349.133803 -288.702677) (xy 349.164259 -288.744596) (xy 349.187782 -288.790763)
			(xy 349.203794 -288.840042) (xy 349.2119 -288.891219) (xy 349.212408 -288.917126) (xy 349.492824 -288.917126)
			(xy 349.493349 -288.891782) (xy 349.501118 -288.841693) (xy 349.516461 -288.793383) (xy 349.539016 -288.74799)
			(xy 349.568252 -288.706584) (xy 349.603481 -288.67014) (xy 349.643872 -288.639516) (xy 349.688474 -288.615435)
			(xy 349.736236 -288.598463) (xy 349.761048 -288.593276) (xy 349.783908 -288.588958) (xy 349.98914 -288.233866)
			(xy 349.981266 -288.211768) (xy 349.972642 -288.185419) (xy 349.963317 -288.130773) (xy 349.962724 -288.103056)
			(xy 349.963232 -288.077149) (xy 349.971338 -288.025972) (xy 349.98735 -287.976693) (xy 350.010873 -287.930526)
			(xy 350.041329 -287.888607) (xy 350.077967 -287.851969) (xy 350.119886 -287.821513) (xy 350.166053 -287.79799)
			(xy 350.215332 -287.781978) (xy 350.266509 -287.773872) (xy 350.318323 -287.773872) (xy 350.3695 -287.781978)
			(xy 350.418779 -287.79799) (xy 350.464946 -287.821513) (xy 350.506865 -287.851969) (xy 350.543503 -287.888607)
			(xy 350.573959 -287.930526) (xy 350.597482 -287.976693) (xy 350.613494 -288.025972) (xy 350.6216 -288.077149)
			(xy 350.622108 -288.103056) (xy 350.621631 -288.128401) (xy 350.613851 -288.178491) (xy 350.598499 -288.2268)
			(xy 350.575936 -288.272192) (xy 350.546694 -288.313597) (xy 350.51146 -288.35004) (xy 350.471065 -288.380663)
			(xy 350.426461 -288.404744) (xy 350.378697 -288.421718) (xy 350.353884 -288.426906) (xy 350.331024 -288.431224)
			(xy 350.125792 -288.786316) (xy 350.133666 -288.808414) (xy 350.142307 -288.834758) (xy 350.151621 -288.889407)
			(xy 350.152208 -288.917126) (xy 350.432624 -288.917126) (xy 350.433132 -288.891219) (xy 350.441238 -288.840042)
			(xy 350.45725 -288.790763) (xy 350.480773 -288.744596) (xy 350.511229 -288.702677) (xy 350.547867 -288.666039)
			(xy 350.589786 -288.635583) (xy 350.635953 -288.61206) (xy 350.685232 -288.596048) (xy 350.736409 -288.587942)
			(xy 350.788223 -288.587942) (xy 350.8394 -288.596048) (xy 350.888679 -288.61206) (xy 350.934846 -288.635583)
			(xy 350.976765 -288.666039) (xy 351.013403 -288.702677) (xy 351.043859 -288.744596) (xy 351.067382 -288.790763)
			(xy 351.083394 -288.840042) (xy 351.0915 -288.891219) (xy 351.092008 -288.917126) (xy 351.372424 -288.917126)
			(xy 351.372949 -288.891782) (xy 351.380718 -288.841693) (xy 351.396061 -288.793383) (xy 351.418616 -288.74799)
			(xy 351.447852 -288.706584) (xy 351.483081 -288.67014) (xy 351.523472 -288.639516) (xy 351.568074 -288.615435)
			(xy 351.615836 -288.598463) (xy 351.640648 -288.593276) (xy 351.663508 -288.588958) (xy 351.86874 -288.233866)
			(xy 351.860866 -288.211768) (xy 351.852242 -288.185419) (xy 351.842917 -288.130773) (xy 351.842324 -288.103056)
			(xy 351.842832 -288.077149) (xy 351.850938 -288.025972) (xy 351.86695 -287.976693) (xy 351.890473 -287.930526)
			(xy 351.920929 -287.888607) (xy 351.957567 -287.851969) (xy 351.999486 -287.821513) (xy 352.045653 -287.79799)
			(xy 352.094932 -287.781978) (xy 352.146109 -287.773872) (xy 352.197923 -287.773872) (xy 352.2491 -287.781978)
			(xy 352.298379 -287.79799) (xy 352.344546 -287.821513) (xy 352.386465 -287.851969) (xy 352.423103 -287.888607)
			(xy 352.453559 -287.930526) (xy 352.477082 -287.976693) (xy 352.493094 -288.025972) (xy 352.5012 -288.077149)
			(xy 352.501708 -288.103056) (xy 368.758724 -288.103056) (xy 368.759232 -288.077149) (xy 368.767338 -288.025972)
			(xy 368.78335 -287.976693) (xy 368.806873 -287.930526) (xy 368.837329 -287.888607) (xy 368.873967 -287.851969)
			(xy 368.915886 -287.821513) (xy 368.962053 -287.79799) (xy 369.011332 -287.781978) (xy 369.062509 -287.773872)
			(xy 369.114323 -287.773872) (xy 369.1655 -287.781978) (xy 369.214779 -287.79799) (xy 369.260946 -287.821513)
			(xy 369.302865 -287.851969) (xy 369.339503 -287.888607) (xy 369.369959 -287.930526) (xy 369.393482 -287.976693)
			(xy 369.409494 -288.025972) (xy 369.4176 -288.077149) (xy 369.418108 -288.103056) (xy 370.638324 -288.103056)
			(xy 370.638832 -288.077149) (xy 370.646938 -288.025972) (xy 370.66295 -287.976693) (xy 370.686473 -287.930526)
			(xy 370.716929 -287.888607) (xy 370.753567 -287.851969) (xy 370.795486 -287.821513) (xy 370.841653 -287.79799)
			(xy 370.890932 -287.781978) (xy 370.942109 -287.773872) (xy 370.993923 -287.773872) (xy 371.0451 -287.781978)
			(xy 371.094379 -287.79799) (xy 371.140546 -287.821513) (xy 371.182465 -287.851969) (xy 371.219103 -287.888607)
			(xy 371.249559 -287.930526) (xy 371.273082 -287.976693) (xy 371.289094 -288.025972) (xy 371.2972 -288.077149)
			(xy 371.297708 -288.103056) (xy 372.517924 -288.103056) (xy 372.518432 -288.077149) (xy 372.526538 -288.025972)
			(xy 372.54255 -287.976693) (xy 372.566073 -287.930526) (xy 372.596529 -287.888607) (xy 372.633167 -287.851969)
			(xy 372.675086 -287.821513) (xy 372.721253 -287.79799) (xy 372.770532 -287.781978) (xy 372.821709 -287.773872)
			(xy 372.873523 -287.773872) (xy 372.9247 -287.781978) (xy 372.973979 -287.79799) (xy 373.020146 -287.821513)
			(xy 373.062065 -287.851969) (xy 373.098703 -287.888607) (xy 373.129159 -287.930526) (xy 373.152682 -287.976693)
			(xy 373.168694 -288.025972) (xy 373.1768 -288.077149) (xy 373.177308 -288.103056) (xy 374.397524 -288.103056)
			(xy 374.398032 -288.077149) (xy 374.406138 -288.025972) (xy 374.42215 -287.976693) (xy 374.445673 -287.930526)
			(xy 374.476129 -287.888607) (xy 374.512767 -287.851969) (xy 374.554686 -287.821513) (xy 374.600853 -287.79799)
			(xy 374.650132 -287.781978) (xy 374.701309 -287.773872) (xy 374.753123 -287.773872) (xy 374.8043 -287.781978)
			(xy 374.853579 -287.79799) (xy 374.899746 -287.821513) (xy 374.941665 -287.851969) (xy 374.978303 -287.888607)
			(xy 375.008759 -287.930526) (xy 375.032282 -287.976693) (xy 375.048294 -288.025972) (xy 375.0564 -288.077149)
			(xy 375.056908 -288.103056) (xy 376.277124 -288.103056) (xy 376.277632 -288.077149) (xy 376.285738 -288.025972)
			(xy 376.30175 -287.976693) (xy 376.325273 -287.930526) (xy 376.355729 -287.888607) (xy 376.392367 -287.851969)
			(xy 376.434286 -287.821513) (xy 376.480453 -287.79799) (xy 376.529732 -287.781978) (xy 376.580909 -287.773872)
			(xy 376.632723 -287.773872) (xy 376.6839 -287.781978) (xy 376.733179 -287.79799) (xy 376.779346 -287.821513)
			(xy 376.821265 -287.851969) (xy 376.857903 -287.888607) (xy 376.888359 -287.930526) (xy 376.911882 -287.976693)
			(xy 376.927894 -288.025972) (xy 376.936 -288.077149) (xy 376.936508 -288.103056) (xy 378.156724 -288.103056)
			(xy 378.157232 -288.077149) (xy 378.165338 -288.025972) (xy 378.18135 -287.976693) (xy 378.204873 -287.930526)
			(xy 378.235329 -287.888607) (xy 378.271967 -287.851969) (xy 378.313886 -287.821513) (xy 378.360053 -287.79799)
			(xy 378.409332 -287.781978) (xy 378.460509 -287.773872) (xy 378.512323 -287.773872) (xy 378.5635 -287.781978)
			(xy 378.612779 -287.79799) (xy 378.658946 -287.821513) (xy 378.700865 -287.851969) (xy 378.737503 -287.888607)
			(xy 378.767959 -287.930526) (xy 378.791482 -287.976693) (xy 378.807494 -288.025972) (xy 378.8156 -288.077149)
			(xy 378.816108 -288.103056) (xy 380.036324 -288.103056) (xy 380.036832 -288.077149) (xy 380.044938 -288.025972)
			(xy 380.06095 -287.976693) (xy 380.084473 -287.930526) (xy 380.114929 -287.888607) (xy 380.151567 -287.851969)
			(xy 380.193486 -287.821513) (xy 380.239653 -287.79799) (xy 380.288932 -287.781978) (xy 380.340109 -287.773872)
			(xy 380.391923 -287.773872) (xy 380.4431 -287.781978) (xy 380.492379 -287.79799) (xy 380.538546 -287.821513)
			(xy 380.580465 -287.851969) (xy 380.617103 -287.888607) (xy 380.647559 -287.930526) (xy 380.671082 -287.976693)
			(xy 380.687094 -288.025972) (xy 380.6952 -288.077149) (xy 380.695708 -288.103056) (xy 382.855724 -288.103056)
			(xy 382.856232 -288.077149) (xy 382.864338 -288.025972) (xy 382.88035 -287.976693) (xy 382.903873 -287.930526)
			(xy 382.934329 -287.888607) (xy 382.970967 -287.851969) (xy 383.012886 -287.821513) (xy 383.059053 -287.79799)
			(xy 383.108332 -287.781978) (xy 383.159509 -287.773872) (xy 383.211323 -287.773872) (xy 383.2625 -287.781978)
			(xy 383.311779 -287.79799) (xy 383.357946 -287.821513) (xy 383.399865 -287.851969) (xy 383.436503 -287.888607)
			(xy 383.466959 -287.930526) (xy 383.490482 -287.976693) (xy 383.506494 -288.025972) (xy 383.5146 -288.077149)
			(xy 383.515108 -288.103056) (xy 383.514503 -288.130773) (xy 383.505187 -288.185419) (xy 383.496566 -288.211768)
			(xy 383.488692 -288.233866) (xy 383.693924 -288.588958) (xy 383.716784 -288.593276) (xy 383.741606 -288.598437)
			(xy 383.789384 -288.615395) (xy 383.834001 -288.639469) (xy 383.874406 -288.67009) (xy 383.909646 -288.706538)
			(xy 383.93889 -288.747952) (xy 383.961447 -288.793355) (xy 383.976786 -288.841676) (xy 383.984545 -288.891777)
			(xy 383.985008 -288.917126) (xy 383.9845 -288.943033) (xy 383.976394 -288.99421) (xy 383.960382 -289.043489)
			(xy 383.936859 -289.089656) (xy 383.906403 -289.131575) (xy 383.869765 -289.168213) (xy 383.827846 -289.198669)
			(xy 383.781679 -289.222192) (xy 383.7324 -289.238204) (xy 383.681223 -289.24631) (xy 383.629409 -289.24631)
			(xy 383.578232 -289.238204) (xy 383.528953 -289.222192) (xy 383.482786 -289.198669) (xy 383.440867 -289.168213)
			(xy 383.404229 -289.131575) (xy 383.373773 -289.089656) (xy 383.35025 -289.043489) (xy 383.334238 -288.99421)
			(xy 383.326132 -288.943033) (xy 383.325624 -288.917126) (xy 383.326223 -288.889409) (xy 383.335543 -288.834762)
			(xy 383.344166 -288.808414) (xy 383.35204 -288.786316) (xy 383.146808 -288.431224) (xy 383.123948 -288.426906)
			(xy 383.099127 -288.421739) (xy 383.051348 -288.404784) (xy 383.006729 -288.380713) (xy 382.966322 -288.350092)
			(xy 382.931082 -288.313646) (xy 382.901838 -288.272232) (xy 382.879281 -288.226828) (xy 382.863943 -288.178506)
			(xy 382.856186 -288.128405) (xy 382.855724 -288.103056) (xy 380.695708 -288.103056) (xy 380.695103 -288.130773)
			(xy 380.685787 -288.185419) (xy 380.677166 -288.211768) (xy 380.669546 -288.233866) (xy 380.874524 -288.588958)
			(xy 380.897384 -288.593276) (xy 380.922206 -288.598437) (xy 380.969984 -288.615395) (xy 381.014601 -288.639469)
			(xy 381.055006 -288.67009) (xy 381.090246 -288.706538) (xy 381.11949 -288.747952) (xy 381.142047 -288.793355)
			(xy 381.157386 -288.841676) (xy 381.165145 -288.891777) (xy 381.165608 -288.917126) (xy 381.1651 -288.943033)
			(xy 381.156994 -288.99421) (xy 381.140982 -289.043489) (xy 381.117459 -289.089656) (xy 381.087003 -289.131575)
			(xy 381.050365 -289.168213) (xy 381.008446 -289.198669) (xy 380.962279 -289.222192) (xy 380.913 -289.238204)
			(xy 380.861823 -289.24631) (xy 380.810009 -289.24631) (xy 380.758832 -289.238204) (xy 380.709553 -289.222192)
			(xy 380.663386 -289.198669) (xy 380.621467 -289.168213) (xy 380.584829 -289.131575) (xy 380.554373 -289.089656)
			(xy 380.53085 -289.043489) (xy 380.514838 -288.99421) (xy 380.506732 -288.943033) (xy 380.506224 -288.917126)
			(xy 380.506823 -288.889409) (xy 380.516143 -288.834762) (xy 380.524766 -288.808414) (xy 380.53264 -288.786316)
			(xy 380.327662 -288.431224) (xy 380.304802 -288.426906) (xy 380.279961 -288.421779) (xy 380.232152 -288.40484)
			(xy 380.187502 -288.380778) (xy 380.147063 -288.350162) (xy 380.111791 -288.313713) (xy 380.082517 -288.272293)
			(xy 380.059933 -288.226877) (xy 380.044571 -288.178538) (xy 380.036794 -288.128417) (xy 380.036324 -288.103056)
			(xy 378.816108 -288.103056) (xy 378.815503 -288.130773) (xy 378.806187 -288.185419) (xy 378.797566 -288.211768)
			(xy 378.789946 -288.233866) (xy 378.994924 -288.588958) (xy 379.017784 -288.593276) (xy 379.042606 -288.598437)
			(xy 379.090384 -288.615395) (xy 379.135001 -288.639469) (xy 379.175406 -288.67009) (xy 379.210646 -288.706538)
			(xy 379.23989 -288.747952) (xy 379.262447 -288.793355) (xy 379.277786 -288.841676) (xy 379.285545 -288.891777)
			(xy 379.286008 -288.917126) (xy 379.2855 -288.943033) (xy 379.277394 -288.99421) (xy 379.261382 -289.043489)
			(xy 379.237859 -289.089656) (xy 379.207403 -289.131575) (xy 379.170765 -289.168213) (xy 379.128846 -289.198669)
			(xy 379.082679 -289.222192) (xy 379.0334 -289.238204) (xy 378.982223 -289.24631) (xy 378.930409 -289.24631)
			(xy 378.879232 -289.238204) (xy 378.829953 -289.222192) (xy 378.783786 -289.198669) (xy 378.741867 -289.168213)
			(xy 378.705229 -289.131575) (xy 378.674773 -289.089656) (xy 378.65125 -289.043489) (xy 378.635238 -288.99421)
			(xy 378.627132 -288.943033) (xy 378.626624 -288.917126) (xy 378.627223 -288.889409) (xy 378.636543 -288.834762)
			(xy 378.645166 -288.808414) (xy 378.65304 -288.786316) (xy 378.448062 -288.431224) (xy 378.425202 -288.426906)
			(xy 378.400361 -288.421779) (xy 378.352552 -288.40484) (xy 378.307902 -288.380778) (xy 378.267463 -288.350162)
			(xy 378.232191 -288.313713) (xy 378.202917 -288.272293) (xy 378.180333 -288.226877) (xy 378.164971 -288.178538)
			(xy 378.157194 -288.128417) (xy 378.156724 -288.103056) (xy 376.936508 -288.103056) (xy 376.935903 -288.130773)
			(xy 376.926587 -288.185419) (xy 376.917966 -288.211768) (xy 376.910346 -288.233866) (xy 377.115324 -288.588958)
			(xy 377.138184 -288.593276) (xy 377.163006 -288.598437) (xy 377.210784 -288.615395) (xy 377.255401 -288.639469)
			(xy 377.295806 -288.67009) (xy 377.331046 -288.706538) (xy 377.36029 -288.747952) (xy 377.382847 -288.793355)
			(xy 377.398186 -288.841676) (xy 377.405945 -288.891777) (xy 377.406408 -288.917126) (xy 377.4059 -288.943033)
			(xy 377.397794 -288.99421) (xy 377.381782 -289.043489) (xy 377.358259 -289.089656) (xy 377.327803 -289.131575)
			(xy 377.291165 -289.168213) (xy 377.249246 -289.198669) (xy 377.203079 -289.222192) (xy 377.1538 -289.238204)
			(xy 377.102623 -289.24631) (xy 377.050809 -289.24631) (xy 376.999632 -289.238204) (xy 376.950353 -289.222192)
			(xy 376.904186 -289.198669) (xy 376.862267 -289.168213) (xy 376.825629 -289.131575) (xy 376.795173 -289.089656)
			(xy 376.77165 -289.043489) (xy 376.755638 -288.99421) (xy 376.747532 -288.943033) (xy 376.747024 -288.917126)
			(xy 376.747623 -288.889409) (xy 376.756943 -288.834762) (xy 376.765566 -288.808414) (xy 376.77344 -288.786316)
			(xy 376.568462 -288.431224) (xy 376.545602 -288.426906) (xy 376.520761 -288.421779) (xy 376.472952 -288.40484)
			(xy 376.428302 -288.380778) (xy 376.387863 -288.350162) (xy 376.352591 -288.313713) (xy 376.323317 -288.272293)
			(xy 376.300733 -288.226877) (xy 376.285371 -288.178538) (xy 376.277594 -288.128417) (xy 376.277124 -288.103056)
			(xy 375.056908 -288.103056) (xy 375.056303 -288.130773) (xy 375.046987 -288.185419) (xy 375.038366 -288.211768)
			(xy 375.030746 -288.233866) (xy 375.235724 -288.588958) (xy 375.258584 -288.593276) (xy 375.283406 -288.598437)
			(xy 375.331184 -288.615395) (xy 375.375801 -288.639469) (xy 375.416206 -288.67009) (xy 375.451446 -288.706538)
			(xy 375.48069 -288.747952) (xy 375.503247 -288.793355) (xy 375.518586 -288.841676) (xy 375.526345 -288.891777)
			(xy 375.526808 -288.917126) (xy 375.5263 -288.943033) (xy 375.518194 -288.99421) (xy 375.502182 -289.043489)
			(xy 375.478659 -289.089656) (xy 375.448203 -289.131575) (xy 375.411565 -289.168213) (xy 375.369646 -289.198669)
			(xy 375.323479 -289.222192) (xy 375.2742 -289.238204) (xy 375.223023 -289.24631) (xy 375.171209 -289.24631)
			(xy 375.120032 -289.238204) (xy 375.070753 -289.222192) (xy 375.024586 -289.198669) (xy 374.982667 -289.168213)
			(xy 374.946029 -289.131575) (xy 374.915573 -289.089656) (xy 374.89205 -289.043489) (xy 374.876038 -288.99421)
			(xy 374.867932 -288.943033) (xy 374.867424 -288.917126) (xy 374.868023 -288.889409) (xy 374.877343 -288.834762)
			(xy 374.885966 -288.808414) (xy 374.89384 -288.786316) (xy 374.688862 -288.431224) (xy 374.666002 -288.426906)
			(xy 374.641161 -288.421779) (xy 374.593352 -288.40484) (xy 374.548702 -288.380778) (xy 374.508263 -288.350162)
			(xy 374.472991 -288.313713) (xy 374.443717 -288.272293) (xy 374.421133 -288.226877) (xy 374.405771 -288.178538)
			(xy 374.397994 -288.128417) (xy 374.397524 -288.103056) (xy 373.177308 -288.103056) (xy 373.176703 -288.130773)
			(xy 373.167387 -288.185419) (xy 373.158766 -288.211768) (xy 373.151146 -288.233866) (xy 373.356124 -288.588958)
			(xy 373.378984 -288.593276) (xy 373.403806 -288.598437) (xy 373.451584 -288.615395) (xy 373.496201 -288.639469)
			(xy 373.536606 -288.67009) (xy 373.571846 -288.706538) (xy 373.60109 -288.747952) (xy 373.623647 -288.793355)
			(xy 373.638986 -288.841676) (xy 373.646745 -288.891777) (xy 373.647208 -288.917126) (xy 373.6467 -288.943033)
			(xy 373.638594 -288.99421) (xy 373.622582 -289.043489) (xy 373.599059 -289.089656) (xy 373.568603 -289.131575)
			(xy 373.531965 -289.168213) (xy 373.490046 -289.198669) (xy 373.443879 -289.222192) (xy 373.3946 -289.238204)
			(xy 373.343423 -289.24631) (xy 373.291609 -289.24631) (xy 373.240432 -289.238204) (xy 373.191153 -289.222192)
			(xy 373.144986 -289.198669) (xy 373.103067 -289.168213) (xy 373.066429 -289.131575) (xy 373.035973 -289.089656)
			(xy 373.01245 -289.043489) (xy 372.996438 -288.99421) (xy 372.988332 -288.943033) (xy 372.987824 -288.917126)
			(xy 372.988423 -288.889409) (xy 372.997743 -288.834762) (xy 373.006366 -288.808414) (xy 373.01424 -288.786316)
			(xy 372.809262 -288.431224) (xy 372.786402 -288.426906) (xy 372.761561 -288.421779) (xy 372.713752 -288.40484)
			(xy 372.669102 -288.380778) (xy 372.628663 -288.350162) (xy 372.593391 -288.313713) (xy 372.564117 -288.272293)
			(xy 372.541533 -288.226877) (xy 372.526171 -288.178538) (xy 372.518394 -288.128417) (xy 372.517924 -288.103056)
			(xy 371.297708 -288.103056) (xy 371.297103 -288.130773) (xy 371.287787 -288.185419) (xy 371.279166 -288.211768)
			(xy 371.271546 -288.233866) (xy 371.476524 -288.588958) (xy 371.499384 -288.593276) (xy 371.524206 -288.598437)
			(xy 371.571984 -288.615395) (xy 371.616601 -288.639469) (xy 371.657006 -288.67009) (xy 371.692246 -288.706538)
			(xy 371.72149 -288.747952) (xy 371.744047 -288.793355) (xy 371.759386 -288.841676) (xy 371.767145 -288.891777)
			(xy 371.767608 -288.917126) (xy 371.7671 -288.943033) (xy 371.758994 -288.99421) (xy 371.742982 -289.043489)
			(xy 371.719459 -289.089656) (xy 371.689003 -289.131575) (xy 371.652365 -289.168213) (xy 371.610446 -289.198669)
			(xy 371.564279 -289.222192) (xy 371.515 -289.238204) (xy 371.463823 -289.24631) (xy 371.412009 -289.24631)
			(xy 371.360832 -289.238204) (xy 371.311553 -289.222192) (xy 371.265386 -289.198669) (xy 371.223467 -289.168213)
			(xy 371.186829 -289.131575) (xy 371.156373 -289.089656) (xy 371.13285 -289.043489) (xy 371.116838 -288.99421)
			(xy 371.108732 -288.943033) (xy 371.108224 -288.917126) (xy 371.108823 -288.889409) (xy 371.118143 -288.834762)
			(xy 371.126766 -288.808414) (xy 371.13464 -288.786316) (xy 370.929662 -288.431224) (xy 370.906802 -288.426906)
			(xy 370.881961 -288.421779) (xy 370.834152 -288.40484) (xy 370.789502 -288.380778) (xy 370.749063 -288.350162)
			(xy 370.713791 -288.313713) (xy 370.684517 -288.272293) (xy 370.661933 -288.226877) (xy 370.646571 -288.178538)
			(xy 370.638794 -288.128417) (xy 370.638324 -288.103056) (xy 369.418108 -288.103056) (xy 369.417503 -288.130773)
			(xy 369.408187 -288.185419) (xy 369.399566 -288.211768) (xy 369.391692 -288.233866) (xy 369.596924 -288.588958)
			(xy 369.619784 -288.593276) (xy 369.644606 -288.598437) (xy 369.692384 -288.615395) (xy 369.737001 -288.639469)
			(xy 369.777406 -288.67009) (xy 369.812646 -288.706538) (xy 369.84189 -288.747952) (xy 369.864447 -288.793355)
			(xy 369.879786 -288.841676) (xy 369.887545 -288.891777) (xy 369.888008 -288.917126) (xy 369.8875 -288.943033)
			(xy 369.879394 -288.99421) (xy 369.863382 -289.043489) (xy 369.839859 -289.089656) (xy 369.809403 -289.131575)
			(xy 369.772765 -289.168213) (xy 369.730846 -289.198669) (xy 369.684679 -289.222192) (xy 369.6354 -289.238204)
			(xy 369.584223 -289.24631) (xy 369.532409 -289.24631) (xy 369.481232 -289.238204) (xy 369.431953 -289.222192)
			(xy 369.385786 -289.198669) (xy 369.343867 -289.168213) (xy 369.307229 -289.131575) (xy 369.276773 -289.089656)
			(xy 369.25325 -289.043489) (xy 369.237238 -288.99421) (xy 369.229132 -288.943033) (xy 369.228624 -288.917126)
			(xy 369.229223 -288.889409) (xy 369.238543 -288.834762) (xy 369.247166 -288.808414) (xy 369.25504 -288.786316)
			(xy 369.049808 -288.431224) (xy 369.026948 -288.426906) (xy 369.002127 -288.421739) (xy 368.954348 -288.404784)
			(xy 368.909729 -288.380713) (xy 368.869322 -288.350092) (xy 368.834082 -288.313646) (xy 368.804838 -288.272232)
			(xy 368.782281 -288.226828) (xy 368.766943 -288.178506) (xy 368.759186 -288.128405) (xy 368.758724 -288.103056)
			(xy 352.501708 -288.103056) (xy 352.501231 -288.128401) (xy 352.493451 -288.178491) (xy 352.478099 -288.2268)
			(xy 352.455536 -288.272192) (xy 352.426294 -288.313597) (xy 352.39106 -288.35004) (xy 352.350665 -288.380663)
			(xy 352.306061 -288.404744) (xy 352.258297 -288.421718) (xy 352.233484 -288.426906) (xy 352.210624 -288.431224)
			(xy 352.005392 -288.786316) (xy 352.013266 -288.808414) (xy 352.021907 -288.834758) (xy 352.031221 -288.889407)
			(xy 352.031808 -288.917126) (xy 352.0313 -288.943033) (xy 352.023194 -288.99421) (xy 352.007182 -289.043489)
			(xy 351.983659 -289.089656) (xy 351.953203 -289.131575) (xy 351.916565 -289.168213) (xy 351.874646 -289.198669)
			(xy 351.828479 -289.222192) (xy 351.7792 -289.238204) (xy 351.728023 -289.24631) (xy 351.676209 -289.24631)
			(xy 351.625032 -289.238204) (xy 351.575753 -289.222192) (xy 351.529586 -289.198669) (xy 351.487667 -289.168213)
			(xy 351.451029 -289.131575) (xy 351.420573 -289.089656) (xy 351.39705 -289.043489) (xy 351.381038 -288.99421)
			(xy 351.372932 -288.943033) (xy 351.372424 -288.917126) (xy 351.092008 -288.917126) (xy 351.091589 -288.940067)
			(xy 351.08516 -288.985498) (xy 351.072513 -289.029604) (xy 351.06356 -289.05073) (xy 351.053654 -289.073336)
			(xy 351.267522 -289.478466) (xy 351.291652 -289.483038) (xy 351.316573 -289.488138) (xy 351.364584 -289.504939)
			(xy 351.409443 -289.528919) (xy 351.450084 -289.559507) (xy 351.485541 -289.595978) (xy 351.514973 -289.637465)
			(xy 351.537679 -289.682981) (xy 351.553121 -289.731446) (xy 351.560931 -289.781709) (xy 351.5614 -289.807142)
			(xy 367.818924 -289.807142) (xy 367.819411 -289.781712) (xy 367.827244 -289.73146) (xy 367.842699 -289.683005)
			(xy 367.86541 -289.637498) (xy 367.894839 -289.596018) (xy 367.930287 -289.559547) (xy 367.970914 -289.528951)
			(xy 368.015757 -289.504956) (xy 368.063753 -289.48813) (xy 368.088672 -289.483038) (xy 368.112802 -289.478466)
			(xy 368.327178 -289.073082) (xy 368.317272 -289.050476) (xy 368.308309 -289.029398) (xy 368.295664 -288.985377)
			(xy 368.289249 -288.940026) (xy 368.288824 -288.917126) (xy 368.289332 -288.891219) (xy 368.297438 -288.840042)
			(xy 368.31345 -288.790763) (xy 368.336973 -288.744596) (xy 368.367429 -288.702677) (xy 368.404067 -288.666039)
			(xy 368.445986 -288.635583) (xy 368.492153 -288.61206) (xy 368.541432 -288.596048) (xy 368.592609 -288.587942)
			(xy 368.644423 -288.587942) (xy 368.6956 -288.596048) (xy 368.744879 -288.61206) (xy 368.791046 -288.635583)
			(xy 368.832965 -288.666039) (xy 368.869603 -288.702677) (xy 368.900059 -288.744596) (xy 368.923582 -288.790763)
			(xy 368.939594 -288.840042) (xy 368.9477 -288.891219) (xy 368.948208 -288.917126) (xy 368.947753 -288.942575)
			(xy 368.939949 -288.992871) (xy 368.924499 -289.041367) (xy 368.901771 -289.086909) (xy 368.872307 -289.128411)
			(xy 368.836809 -289.164887) (xy 368.796121 -289.195466) (xy 368.751213 -289.21942) (xy 368.703153 -289.23618)
			(xy 368.678206 -289.24123) (xy 368.654076 -289.245802) (xy 368.4397 -289.651186) (xy 368.449606 -289.673792)
			(xy 368.458528 -289.694877) (xy 368.471078 -289.738907) (xy 368.47741 -289.78425) (xy 368.4778 -289.807142)
			(xy 369.698524 -289.807142) (xy 369.699011 -289.781712) (xy 369.706844 -289.73146) (xy 369.722299 -289.683005)
			(xy 369.74501 -289.637498) (xy 369.774439 -289.596018) (xy 369.809887 -289.559547) (xy 369.850514 -289.528951)
			(xy 369.895357 -289.504956) (xy 369.943353 -289.48813) (xy 369.968272 -289.483038) (xy 369.992402 -289.478466)
			(xy 370.206778 -289.073082) (xy 370.196872 -289.050476) (xy 370.187909 -289.029398) (xy 370.175264 -288.985377)
			(xy 370.168849 -288.940026) (xy 370.168424 -288.917126) (xy 370.168932 -288.891219) (xy 370.177038 -288.840042)
			(xy 370.19305 -288.790763) (xy 370.216573 -288.744596) (xy 370.247029 -288.702677) (xy 370.283667 -288.666039)
			(xy 370.325586 -288.635583) (xy 370.371753 -288.61206) (xy 370.421032 -288.596048) (xy 370.472209 -288.587942)
			(xy 370.524023 -288.587942) (xy 370.5752 -288.596048) (xy 370.624479 -288.61206) (xy 370.670646 -288.635583)
			(xy 370.712565 -288.666039) (xy 370.749203 -288.702677) (xy 370.779659 -288.744596) (xy 370.803182 -288.790763)
			(xy 370.819194 -288.840042) (xy 370.8273 -288.891219) (xy 370.827808 -288.917126) (xy 370.827353 -288.942575)
			(xy 370.819549 -288.992871) (xy 370.804099 -289.041367) (xy 370.781371 -289.086909) (xy 370.751907 -289.128411)
			(xy 370.716409 -289.164887) (xy 370.675721 -289.195466) (xy 370.630813 -289.21942) (xy 370.582753 -289.23618)
			(xy 370.557806 -289.24123) (xy 370.533676 -289.245802) (xy 370.3193 -289.651186) (xy 370.329206 -289.673792)
			(xy 370.338128 -289.694877) (xy 370.350678 -289.738907) (xy 370.35701 -289.78425) (xy 370.3574 -289.807142)
			(xy 371.578124 -289.807142) (xy 371.578611 -289.781712) (xy 371.586444 -289.73146) (xy 371.601899 -289.683005)
			(xy 371.62461 -289.637498) (xy 371.654039 -289.596018) (xy 371.689487 -289.559547) (xy 371.730114 -289.528951)
			(xy 371.774957 -289.504956) (xy 371.822953 -289.48813) (xy 371.847872 -289.483038) (xy 371.872002 -289.478466)
			(xy 372.086378 -289.073082) (xy 372.076472 -289.050476) (xy 372.067509 -289.029398) (xy 372.054864 -288.985377)
			(xy 372.048449 -288.940026) (xy 372.048024 -288.917126) (xy 372.048532 -288.891219) (xy 372.056638 -288.840042)
			(xy 372.07265 -288.790763) (xy 372.096173 -288.744596) (xy 372.126629 -288.702677) (xy 372.163267 -288.666039)
			(xy 372.205186 -288.635583) (xy 372.251353 -288.61206) (xy 372.300632 -288.596048) (xy 372.351809 -288.587942)
			(xy 372.403623 -288.587942) (xy 372.4548 -288.596048) (xy 372.504079 -288.61206) (xy 372.550246 -288.635583)
			(xy 372.592165 -288.666039) (xy 372.628803 -288.702677) (xy 372.659259 -288.744596) (xy 372.682782 -288.790763)
			(xy 372.698794 -288.840042) (xy 372.7069 -288.891219) (xy 372.707408 -288.917126) (xy 372.706953 -288.942575)
			(xy 372.699149 -288.992871) (xy 372.683699 -289.041367) (xy 372.660971 -289.086909) (xy 372.631507 -289.128411)
			(xy 372.596009 -289.164887) (xy 372.555321 -289.195466) (xy 372.510413 -289.21942) (xy 372.462353 -289.23618)
			(xy 372.437406 -289.24123) (xy 372.413276 -289.245802) (xy 372.1989 -289.651186) (xy 372.208806 -289.673792)
			(xy 372.217728 -289.694877) (xy 372.230278 -289.738907) (xy 372.23661 -289.78425) (xy 372.237 -289.807142)
			(xy 373.457724 -289.807142) (xy 373.458211 -289.781712) (xy 373.466044 -289.73146) (xy 373.481499 -289.683005)
			(xy 373.50421 -289.637498) (xy 373.533639 -289.596018) (xy 373.569087 -289.559547) (xy 373.609714 -289.528951)
			(xy 373.654557 -289.504956) (xy 373.702553 -289.48813) (xy 373.727472 -289.483038) (xy 373.751602 -289.478466)
			(xy 373.965978 -289.073082) (xy 373.956072 -289.050476) (xy 373.947109 -289.029398) (xy 373.934464 -288.985377)
			(xy 373.928049 -288.940026) (xy 373.927624 -288.917126) (xy 373.928132 -288.891219) (xy 373.936238 -288.840042)
			(xy 373.95225 -288.790763) (xy 373.975773 -288.744596) (xy 374.006229 -288.702677) (xy 374.042867 -288.666039)
			(xy 374.084786 -288.635583) (xy 374.130953 -288.61206) (xy 374.180232 -288.596048) (xy 374.231409 -288.587942)
			(xy 374.283223 -288.587942) (xy 374.3344 -288.596048) (xy 374.383679 -288.61206) (xy 374.429846 -288.635583)
			(xy 374.471765 -288.666039) (xy 374.508403 -288.702677) (xy 374.538859 -288.744596) (xy 374.562382 -288.790763)
			(xy 374.578394 -288.840042) (xy 374.5865 -288.891219) (xy 374.587008 -288.917126) (xy 374.586553 -288.942575)
			(xy 374.578749 -288.992871) (xy 374.563299 -289.041367) (xy 374.540571 -289.086909) (xy 374.511107 -289.128411)
			(xy 374.475609 -289.164887) (xy 374.434921 -289.195466) (xy 374.390013 -289.21942) (xy 374.341953 -289.23618)
			(xy 374.317006 -289.24123) (xy 374.292876 -289.245802) (xy 374.0785 -289.651186) (xy 374.088406 -289.673792)
			(xy 374.097328 -289.694877) (xy 374.109878 -289.738907) (xy 374.11621 -289.78425) (xy 374.1166 -289.807142)
			(xy 375.337324 -289.807142) (xy 375.337811 -289.781712) (xy 375.345644 -289.73146) (xy 375.361099 -289.683005)
			(xy 375.38381 -289.637498) (xy 375.413239 -289.596018) (xy 375.448687 -289.559547) (xy 375.489314 -289.528951)
			(xy 375.534157 -289.504956) (xy 375.582153 -289.48813) (xy 375.607072 -289.483038) (xy 375.631202 -289.478466)
			(xy 375.845578 -289.073082) (xy 375.835672 -289.050476) (xy 375.826709 -289.029398) (xy 375.814064 -288.985377)
			(xy 375.807649 -288.940026) (xy 375.807224 -288.917126) (xy 375.807732 -288.891219) (xy 375.815838 -288.840042)
			(xy 375.83185 -288.790763) (xy 375.855373 -288.744596) (xy 375.885829 -288.702677) (xy 375.922467 -288.666039)
			(xy 375.964386 -288.635583) (xy 376.010553 -288.61206) (xy 376.059832 -288.596048) (xy 376.111009 -288.587942)
			(xy 376.162823 -288.587942) (xy 376.214 -288.596048) (xy 376.263279 -288.61206) (xy 376.309446 -288.635583)
			(xy 376.351365 -288.666039) (xy 376.388003 -288.702677) (xy 376.418459 -288.744596) (xy 376.441982 -288.790763)
			(xy 376.457994 -288.840042) (xy 376.4661 -288.891219) (xy 376.466608 -288.917126) (xy 376.466153 -288.942575)
			(xy 376.458349 -288.992871) (xy 376.442899 -289.041367) (xy 376.420171 -289.086909) (xy 376.390707 -289.128411)
			(xy 376.355209 -289.164887) (xy 376.314521 -289.195466) (xy 376.269613 -289.21942) (xy 376.221553 -289.23618)
			(xy 376.196606 -289.24123) (xy 376.172476 -289.245802) (xy 375.9581 -289.651186) (xy 375.968006 -289.673792)
			(xy 375.976928 -289.694877) (xy 375.989478 -289.738907) (xy 375.99581 -289.78425) (xy 375.9962 -289.807142)
			(xy 377.216924 -289.807142) (xy 377.217411 -289.781712) (xy 377.225244 -289.73146) (xy 377.240699 -289.683005)
			(xy 377.26341 -289.637498) (xy 377.292839 -289.596018) (xy 377.328287 -289.559547) (xy 377.368914 -289.528951)
			(xy 377.413757 -289.504956) (xy 377.461753 -289.48813) (xy 377.486672 -289.483038) (xy 377.510802 -289.478466)
			(xy 377.725178 -289.073082) (xy 377.715272 -289.050476) (xy 377.706309 -289.029398) (xy 377.693664 -288.985377)
			(xy 377.687249 -288.940026) (xy 377.686824 -288.917126) (xy 377.687332 -288.891219) (xy 377.695438 -288.840042)
			(xy 377.71145 -288.790763) (xy 377.734973 -288.744596) (xy 377.765429 -288.702677) (xy 377.802067 -288.666039)
			(xy 377.843986 -288.635583) (xy 377.890153 -288.61206) (xy 377.939432 -288.596048) (xy 377.990609 -288.587942)
			(xy 378.042423 -288.587942) (xy 378.0936 -288.596048) (xy 378.142879 -288.61206) (xy 378.189046 -288.635583)
			(xy 378.230965 -288.666039) (xy 378.267603 -288.702677) (xy 378.298059 -288.744596) (xy 378.321582 -288.790763)
			(xy 378.337594 -288.840042) (xy 378.3457 -288.891219) (xy 378.346208 -288.917126) (xy 378.345753 -288.942575)
			(xy 378.337949 -288.992871) (xy 378.322499 -289.041367) (xy 378.299771 -289.086909) (xy 378.270307 -289.128411)
			(xy 378.234809 -289.164887) (xy 378.194121 -289.195466) (xy 378.149213 -289.21942) (xy 378.101153 -289.23618)
			(xy 378.076206 -289.24123) (xy 378.052076 -289.245802) (xy 377.8377 -289.651186) (xy 377.847606 -289.673792)
			(xy 377.856528 -289.694877) (xy 377.869078 -289.738907) (xy 377.87541 -289.78425) (xy 377.8758 -289.807142)
			(xy 379.096524 -289.807142) (xy 379.097011 -289.781712) (xy 379.104844 -289.73146) (xy 379.120299 -289.683005)
			(xy 379.14301 -289.637498) (xy 379.172439 -289.596018) (xy 379.207887 -289.559547) (xy 379.248514 -289.528951)
			(xy 379.293357 -289.504956) (xy 379.341353 -289.48813) (xy 379.366272 -289.483038) (xy 379.390402 -289.478466)
			(xy 379.604778 -289.073082) (xy 379.594872 -289.050476) (xy 379.585909 -289.029398) (xy 379.573264 -288.985377)
			(xy 379.566849 -288.940026) (xy 379.566424 -288.917126) (xy 379.566932 -288.891219) (xy 379.575038 -288.840042)
			(xy 379.59105 -288.790763) (xy 379.614573 -288.744596) (xy 379.645029 -288.702677) (xy 379.681667 -288.666039)
			(xy 379.723586 -288.635583) (xy 379.769753 -288.61206) (xy 379.819032 -288.596048) (xy 379.870209 -288.587942)
			(xy 379.922023 -288.587942) (xy 379.9732 -288.596048) (xy 380.022479 -288.61206) (xy 380.068646 -288.635583)
			(xy 380.110565 -288.666039) (xy 380.147203 -288.702677) (xy 380.177659 -288.744596) (xy 380.201182 -288.790763)
			(xy 380.217194 -288.840042) (xy 380.2253 -288.891219) (xy 380.225808 -288.917126) (xy 380.225353 -288.942575)
			(xy 380.217549 -288.992871) (xy 380.202099 -289.041367) (xy 380.179371 -289.086909) (xy 380.149907 -289.128411)
			(xy 380.114409 -289.164887) (xy 380.073721 -289.195466) (xy 380.028813 -289.21942) (xy 379.980753 -289.23618)
			(xy 379.955806 -289.24123) (xy 379.931676 -289.245802) (xy 379.7173 -289.651186) (xy 379.727206 -289.673792)
			(xy 379.736128 -289.694877) (xy 379.748678 -289.738907) (xy 379.75501 -289.78425) (xy 379.7554 -289.807142)
			(xy 380.976124 -289.807142) (xy 380.976611 -289.781712) (xy 380.984444 -289.73146) (xy 380.999899 -289.683005)
			(xy 381.02261 -289.637498) (xy 381.052039 -289.596018) (xy 381.087487 -289.559547) (xy 381.128114 -289.528951)
			(xy 381.172957 -289.504956) (xy 381.220953 -289.48813) (xy 381.245872 -289.483038) (xy 381.270002 -289.478466)
			(xy 381.484378 -289.073082) (xy 381.474472 -289.050476) (xy 381.465509 -289.029398) (xy 381.452864 -288.985377)
			(xy 381.446449 -288.940026) (xy 381.446024 -288.917126) (xy 381.446532 -288.891219) (xy 381.454638 -288.840042)
			(xy 381.47065 -288.790763) (xy 381.494173 -288.744596) (xy 381.524629 -288.702677) (xy 381.561267 -288.666039)
			(xy 381.603186 -288.635583) (xy 381.649353 -288.61206) (xy 381.698632 -288.596048) (xy 381.749809 -288.587942)
			(xy 381.801623 -288.587942) (xy 381.8528 -288.596048) (xy 381.902079 -288.61206) (xy 381.948246 -288.635583)
			(xy 381.990165 -288.666039) (xy 382.026803 -288.702677) (xy 382.057259 -288.744596) (xy 382.080782 -288.790763)
			(xy 382.096794 -288.840042) (xy 382.1049 -288.891219) (xy 382.105408 -288.917126) (xy 382.104953 -288.942575)
			(xy 382.097149 -288.992871) (xy 382.081699 -289.041367) (xy 382.058971 -289.086909) (xy 382.029507 -289.128411)
			(xy 381.994009 -289.164887) (xy 381.953321 -289.195466) (xy 381.908413 -289.21942) (xy 381.860353 -289.23618)
			(xy 381.835406 -289.24123) (xy 381.811276 -289.245802) (xy 381.5969 -289.651186) (xy 381.606806 -289.673792)
			(xy 381.615728 -289.694877) (xy 381.628278 -289.738907) (xy 381.63461 -289.78425) (xy 381.635 -289.807142)
			(xy 381.634492 -289.833029) (xy 381.626393 -289.884167) (xy 381.610394 -289.933407) (xy 381.586888 -289.979539)
			(xy 381.556456 -290.021426) (xy 381.519846 -290.058036) (xy 381.477959 -290.088468) (xy 381.431827 -290.111974)
			(xy 381.382587 -290.127973) (xy 381.331449 -290.136072) (xy 381.279675 -290.136072) (xy 381.228537 -290.127973)
			(xy 381.179297 -290.111974) (xy 381.133165 -290.088468) (xy 381.091278 -290.058036) (xy 381.054668 -290.021426)
			(xy 381.024236 -289.979539) (xy 381.00073 -289.933407) (xy 380.984731 -289.884167) (xy 380.976632 -289.833029)
			(xy 380.976124 -289.807142) (xy 379.7554 -289.807142) (xy 379.754892 -289.833029) (xy 379.746793 -289.884167)
			(xy 379.730794 -289.933407) (xy 379.707288 -289.979539) (xy 379.676856 -290.021426) (xy 379.640246 -290.058036)
			(xy 379.598359 -290.088468) (xy 379.552227 -290.111974) (xy 379.502987 -290.127973) (xy 379.451849 -290.136072)
			(xy 379.400075 -290.136072) (xy 379.348937 -290.127973) (xy 379.299697 -290.111974) (xy 379.253565 -290.088468)
			(xy 379.211678 -290.058036) (xy 379.175068 -290.021426) (xy 379.144636 -289.979539) (xy 379.12113 -289.933407)
			(xy 379.105131 -289.884167) (xy 379.097032 -289.833029) (xy 379.096524 -289.807142) (xy 377.8758 -289.807142)
			(xy 377.875292 -289.833029) (xy 377.867193 -289.884167) (xy 377.851194 -289.933407) (xy 377.827688 -289.979539)
			(xy 377.797256 -290.021426) (xy 377.760646 -290.058036) (xy 377.718759 -290.088468) (xy 377.672627 -290.111974)
			(xy 377.623387 -290.127973) (xy 377.572249 -290.136072) (xy 377.520475 -290.136072) (xy 377.469337 -290.127973)
			(xy 377.420097 -290.111974) (xy 377.373965 -290.088468) (xy 377.332078 -290.058036) (xy 377.295468 -290.021426)
			(xy 377.265036 -289.979539) (xy 377.24153 -289.933407) (xy 377.225531 -289.884167) (xy 377.217432 -289.833029)
			(xy 377.216924 -289.807142) (xy 375.9962 -289.807142) (xy 375.995692 -289.833029) (xy 375.987593 -289.884167)
			(xy 375.971594 -289.933407) (xy 375.948088 -289.979539) (xy 375.917656 -290.021426) (xy 375.881046 -290.058036)
			(xy 375.839159 -290.088468) (xy 375.793027 -290.111974) (xy 375.743787 -290.127973) (xy 375.692649 -290.136072)
			(xy 375.640875 -290.136072) (xy 375.589737 -290.127973) (xy 375.540497 -290.111974) (xy 375.494365 -290.088468)
			(xy 375.452478 -290.058036) (xy 375.415868 -290.021426) (xy 375.385436 -289.979539) (xy 375.36193 -289.933407)
			(xy 375.345931 -289.884167) (xy 375.337832 -289.833029) (xy 375.337324 -289.807142) (xy 374.1166 -289.807142)
			(xy 374.116092 -289.833029) (xy 374.107993 -289.884167) (xy 374.091994 -289.933407) (xy 374.068488 -289.979539)
			(xy 374.038056 -290.021426) (xy 374.001446 -290.058036) (xy 373.959559 -290.088468) (xy 373.913427 -290.111974)
			(xy 373.864187 -290.127973) (xy 373.813049 -290.136072) (xy 373.761275 -290.136072) (xy 373.710137 -290.127973)
			(xy 373.660897 -290.111974) (xy 373.614765 -290.088468) (xy 373.572878 -290.058036) (xy 373.536268 -290.021426)
			(xy 373.505836 -289.979539) (xy 373.48233 -289.933407) (xy 373.466331 -289.884167) (xy 373.458232 -289.833029)
			(xy 373.457724 -289.807142) (xy 372.237 -289.807142) (xy 372.236492 -289.833029) (xy 372.228393 -289.884167)
			(xy 372.212394 -289.933407) (xy 372.188888 -289.979539) (xy 372.158456 -290.021426) (xy 372.121846 -290.058036)
			(xy 372.079959 -290.088468) (xy 372.033827 -290.111974) (xy 371.984587 -290.127973) (xy 371.933449 -290.136072)
			(xy 371.881675 -290.136072) (xy 371.830537 -290.127973) (xy 371.781297 -290.111974) (xy 371.735165 -290.088468)
			(xy 371.693278 -290.058036) (xy 371.656668 -290.021426) (xy 371.626236 -289.979539) (xy 371.60273 -289.933407)
			(xy 371.586731 -289.884167) (xy 371.578632 -289.833029) (xy 371.578124 -289.807142) (xy 370.3574 -289.807142)
			(xy 370.356892 -289.833029) (xy 370.348793 -289.884167) (xy 370.332794 -289.933407) (xy 370.309288 -289.979539)
			(xy 370.278856 -290.021426) (xy 370.242246 -290.058036) (xy 370.200359 -290.088468) (xy 370.154227 -290.111974)
			(xy 370.104987 -290.127973) (xy 370.053849 -290.136072) (xy 370.002075 -290.136072) (xy 369.950937 -290.127973)
			(xy 369.901697 -290.111974) (xy 369.855565 -290.088468) (xy 369.813678 -290.058036) (xy 369.777068 -290.021426)
			(xy 369.746636 -289.979539) (xy 369.72313 -289.933407) (xy 369.707131 -289.884167) (xy 369.699032 -289.833029)
			(xy 369.698524 -289.807142) (xy 368.4778 -289.807142) (xy 368.477292 -289.833029) (xy 368.469193 -289.884167)
			(xy 368.453194 -289.933407) (xy 368.429688 -289.979539) (xy 368.399256 -290.021426) (xy 368.362646 -290.058036)
			(xy 368.320759 -290.088468) (xy 368.274627 -290.111974) (xy 368.225387 -290.127973) (xy 368.174249 -290.136072)
			(xy 368.122475 -290.136072) (xy 368.071337 -290.127973) (xy 368.022097 -290.111974) (xy 367.975965 -290.088468)
			(xy 367.934078 -290.058036) (xy 367.897468 -290.021426) (xy 367.867036 -289.979539) (xy 367.84353 -289.933407)
			(xy 367.827531 -289.884167) (xy 367.819432 -289.833029) (xy 367.818924 -289.807142) (xy 351.5614 -289.807142)
			(xy 351.560892 -289.833029) (xy 351.552793 -289.884167) (xy 351.536794 -289.933407) (xy 351.513288 -289.979539)
			(xy 351.482856 -290.021426) (xy 351.446246 -290.058036) (xy 351.404359 -290.088468) (xy 351.358227 -290.111974)
			(xy 351.308987 -290.127973) (xy 351.257849 -290.136072) (xy 351.206075 -290.136072) (xy 351.154937 -290.127973)
			(xy 351.105697 -290.111974) (xy 351.059565 -290.088468) (xy 351.017678 -290.058036) (xy 350.981068 -290.021426)
			(xy 350.950636 -289.979539) (xy 350.92713 -289.933407) (xy 350.911131 -289.884167) (xy 350.903032 -289.833029)
			(xy 350.902524 -289.807142) (xy 350.902524 -289.806634) (xy 350.902922 -289.783785) (xy 350.909275 -289.738531)
			(xy 350.921824 -289.694589) (xy 350.930718 -289.673538) (xy 350.940624 -289.650932) (xy 350.726756 -289.245802)
			(xy 350.702626 -289.24123) (xy 350.677682 -289.236182) (xy 350.629639 -289.219398) (xy 350.584746 -289.195428)
			(xy 350.544072 -289.164843) (xy 350.508582 -289.128369) (xy 350.479121 -289.086873) (xy 350.456389 -289.041341)
			(xy 350.440925 -288.992857) (xy 350.433099 -288.942571) (xy 350.432624 -288.917126) (xy 350.152208 -288.917126)
			(xy 350.1517 -288.943033) (xy 350.143594 -288.99421) (xy 350.127582 -289.043489) (xy 350.104059 -289.089656)
			(xy 350.073603 -289.131575) (xy 350.036965 -289.168213) (xy 349.995046 -289.198669) (xy 349.948879 -289.222192)
			(xy 349.8996 -289.238204) (xy 349.848423 -289.24631) (xy 349.796609 -289.24631) (xy 349.745432 -289.238204)
			(xy 349.696153 -289.222192) (xy 349.649986 -289.198669) (xy 349.608067 -289.168213) (xy 349.571429 -289.131575)
			(xy 349.540973 -289.089656) (xy 349.51745 -289.043489) (xy 349.501438 -288.99421) (xy 349.493332 -288.943033)
			(xy 349.492824 -288.917126) (xy 349.212408 -288.917126) (xy 349.211989 -288.940067) (xy 349.20556 -288.985498)
			(xy 349.192913 -289.029604) (xy 349.18396 -289.05073) (xy 349.174054 -289.073336) (xy 349.387922 -289.478466)
			(xy 349.412052 -289.483038) (xy 349.436973 -289.488138) (xy 349.484984 -289.504939) (xy 349.529843 -289.528919)
			(xy 349.570484 -289.559507) (xy 349.605941 -289.595978) (xy 349.635373 -289.637465) (xy 349.658079 -289.682981)
			(xy 349.673521 -289.731446) (xy 349.681331 -289.781709) (xy 349.6818 -289.807142) (xy 349.681292 -289.833029)
			(xy 349.673193 -289.884167) (xy 349.657194 -289.933407) (xy 349.633688 -289.979539) (xy 349.603256 -290.021426)
			(xy 349.566646 -290.058036) (xy 349.524759 -290.088468) (xy 349.478627 -290.111974) (xy 349.429387 -290.127973)
			(xy 349.378249 -290.136072) (xy 349.326475 -290.136072) (xy 349.275337 -290.127973) (xy 349.226097 -290.111974)
			(xy 349.179965 -290.088468) (xy 349.138078 -290.058036) (xy 349.101468 -290.021426) (xy 349.071036 -289.979539)
			(xy 349.04753 -289.933407) (xy 349.031531 -289.884167) (xy 349.023432 -289.833029) (xy 349.022924 -289.807142)
			(xy 349.022924 -289.806634) (xy 349.023322 -289.783785) (xy 349.029675 -289.738531) (xy 349.042224 -289.694589)
			(xy 349.051118 -289.673538) (xy 349.061024 -289.650932) (xy 348.847156 -289.245802) (xy 348.823026 -289.24123)
			(xy 348.798082 -289.236182) (xy 348.750039 -289.219398) (xy 348.705146 -289.195428) (xy 348.664472 -289.164843)
			(xy 348.628982 -289.128369) (xy 348.599521 -289.086873) (xy 348.576789 -289.041341) (xy 348.561325 -288.992857)
			(xy 348.553499 -288.942571) (xy 348.553024 -288.917126) (xy 348.272608 -288.917126) (xy 348.2721 -288.943033)
			(xy 348.263994 -288.99421) (xy 348.247982 -289.043489) (xy 348.224459 -289.089656) (xy 348.194003 -289.131575)
			(xy 348.157365 -289.168213) (xy 348.115446 -289.198669) (xy 348.069279 -289.222192) (xy 348.02 -289.238204)
			(xy 347.968823 -289.24631) (xy 347.917009 -289.24631) (xy 347.865832 -289.238204) (xy 347.816553 -289.222192)
			(xy 347.770386 -289.198669) (xy 347.728467 -289.168213) (xy 347.691829 -289.131575) (xy 347.661373 -289.089656)
			(xy 347.63785 -289.043489) (xy 347.621838 -288.99421) (xy 347.613732 -288.943033) (xy 347.613224 -288.917126)
			(xy 347.332808 -288.917126) (xy 347.332389 -288.940067) (xy 347.32596 -288.985498) (xy 347.313313 -289.029604)
			(xy 347.30436 -289.05073) (xy 347.294454 -289.073336) (xy 347.508322 -289.478466) (xy 347.532452 -289.483038)
			(xy 347.557373 -289.488138) (xy 347.605384 -289.504939) (xy 347.650243 -289.528919) (xy 347.690884 -289.559507)
			(xy 347.726341 -289.595978) (xy 347.755773 -289.637465) (xy 347.778479 -289.682981) (xy 347.793921 -289.731446)
			(xy 347.801731 -289.781709) (xy 347.8022 -289.807142) (xy 347.801692 -289.833029) (xy 347.793593 -289.884167)
			(xy 347.777594 -289.933407) (xy 347.754088 -289.979539) (xy 347.723656 -290.021426) (xy 347.687046 -290.058036)
			(xy 347.645159 -290.088468) (xy 347.599027 -290.111974) (xy 347.549787 -290.127973) (xy 347.498649 -290.136072)
			(xy 347.446875 -290.136072) (xy 347.395737 -290.127973) (xy 347.346497 -290.111974) (xy 347.300365 -290.088468)
			(xy 347.258478 -290.058036) (xy 347.221868 -290.021426) (xy 347.191436 -289.979539) (xy 347.16793 -289.933407)
			(xy 347.151931 -289.884167) (xy 347.143832 -289.833029) (xy 347.143324 -289.807142) (xy 347.143324 -289.806634)
			(xy 347.143722 -289.783785) (xy 347.150075 -289.738531) (xy 347.162624 -289.694589) (xy 347.171518 -289.673538)
			(xy 347.181424 -289.650932) (xy 346.967556 -289.245802) (xy 346.943426 -289.24123) (xy 346.918482 -289.236182)
			(xy 346.870439 -289.219398) (xy 346.825546 -289.195428) (xy 346.784872 -289.164843) (xy 346.749382 -289.128369)
			(xy 346.719921 -289.086873) (xy 346.697189 -289.041341) (xy 346.681725 -288.992857) (xy 346.673899 -288.942571)
			(xy 346.673424 -288.917126) (xy 346.393008 -288.917126) (xy 346.3925 -288.943033) (xy 346.384394 -288.99421)
			(xy 346.368382 -289.043489) (xy 346.344859 -289.089656) (xy 346.314403 -289.131575) (xy 346.277765 -289.168213)
			(xy 346.235846 -289.198669) (xy 346.189679 -289.222192) (xy 346.1404 -289.238204) (xy 346.089223 -289.24631)
			(xy 346.037409 -289.24631) (xy 345.986232 -289.238204) (xy 345.936953 -289.222192) (xy 345.890786 -289.198669)
			(xy 345.848867 -289.168213) (xy 345.812229 -289.131575) (xy 345.781773 -289.089656) (xy 345.75825 -289.043489)
			(xy 345.742238 -288.99421) (xy 345.734132 -288.943033) (xy 345.733624 -288.917126) (xy 345.453208 -288.917126)
			(xy 345.452789 -288.940067) (xy 345.44636 -288.985498) (xy 345.433713 -289.029604) (xy 345.42476 -289.05073)
			(xy 345.414854 -289.073336) (xy 345.628722 -289.478466) (xy 345.652852 -289.483038) (xy 345.677773 -289.488138)
			(xy 345.725784 -289.504939) (xy 345.770643 -289.528919) (xy 345.811284 -289.559507) (xy 345.846741 -289.595978)
			(xy 345.876173 -289.637465) (xy 345.898879 -289.682981) (xy 345.914321 -289.731446) (xy 345.922131 -289.781709)
			(xy 345.9226 -289.807142) (xy 345.922092 -289.833029) (xy 345.913993 -289.884167) (xy 345.897994 -289.933407)
			(xy 345.874488 -289.979539) (xy 345.844056 -290.021426) (xy 345.807446 -290.058036) (xy 345.765559 -290.088468)
			(xy 345.719427 -290.111974) (xy 345.670187 -290.127973) (xy 345.619049 -290.136072) (xy 345.567275 -290.136072)
			(xy 345.516137 -290.127973) (xy 345.466897 -290.111974) (xy 345.420765 -290.088468) (xy 345.378878 -290.058036)
			(xy 345.342268 -290.021426) (xy 345.311836 -289.979539) (xy 345.28833 -289.933407) (xy 345.272331 -289.884167)
			(xy 345.264232 -289.833029) (xy 345.263724 -289.807142) (xy 345.263724 -289.806634) (xy 345.264122 -289.783785)
			(xy 345.270475 -289.738531) (xy 345.283024 -289.694589) (xy 345.291918 -289.673538) (xy 345.301824 -289.650932)
			(xy 345.087956 -289.245802) (xy 345.063826 -289.24123) (xy 345.038882 -289.236182) (xy 344.990839 -289.219398)
			(xy 344.945946 -289.195428) (xy 344.905272 -289.164843) (xy 344.869782 -289.128369) (xy 344.840321 -289.086873)
			(xy 344.817589 -289.041341) (xy 344.802125 -288.992857) (xy 344.794299 -288.942571) (xy 344.793824 -288.917126)
			(xy 344.513408 -288.917126) (xy 344.5129 -288.943033) (xy 344.504794 -288.99421) (xy 344.488782 -289.043489)
			(xy 344.465259 -289.089656) (xy 344.434803 -289.131575) (xy 344.398165 -289.168213) (xy 344.356246 -289.198669)
			(xy 344.310079 -289.222192) (xy 344.2608 -289.238204) (xy 344.209623 -289.24631) (xy 344.157809 -289.24631)
			(xy 344.106632 -289.238204) (xy 344.057353 -289.222192) (xy 344.011186 -289.198669) (xy 343.969267 -289.168213)
			(xy 343.932629 -289.131575) (xy 343.902173 -289.089656) (xy 343.87865 -289.043489) (xy 343.862638 -288.99421)
			(xy 343.854532 -288.943033) (xy 343.854024 -288.917126) (xy 343.573608 -288.917126) (xy 343.573189 -288.940067)
			(xy 343.56676 -288.985498) (xy 343.554113 -289.029604) (xy 343.54516 -289.05073) (xy 343.535254 -289.073336)
			(xy 343.749122 -289.478466) (xy 343.773252 -289.483038) (xy 343.798173 -289.488138) (xy 343.846184 -289.504939)
			(xy 343.891043 -289.528919) (xy 343.931684 -289.559507) (xy 343.967141 -289.595978) (xy 343.996573 -289.637465)
			(xy 344.019279 -289.682981) (xy 344.034721 -289.731446) (xy 344.042531 -289.781709) (xy 344.043 -289.807142)
			(xy 344.042492 -289.833029) (xy 344.034393 -289.884167) (xy 344.018394 -289.933407) (xy 343.994888 -289.979539)
			(xy 343.964456 -290.021426) (xy 343.927846 -290.058036) (xy 343.885959 -290.088468) (xy 343.839827 -290.111974)
			(xy 343.790587 -290.127973) (xy 343.739449 -290.136072) (xy 343.687675 -290.136072) (xy 343.636537 -290.127973)
			(xy 343.587297 -290.111974) (xy 343.541165 -290.088468) (xy 343.499278 -290.058036) (xy 343.462668 -290.021426)
			(xy 343.432236 -289.979539) (xy 343.40873 -289.933407) (xy 343.392731 -289.884167) (xy 343.384632 -289.833029)
			(xy 343.384124 -289.807142) (xy 343.384124 -289.806634) (xy 343.384522 -289.783785) (xy 343.390875 -289.738531)
			(xy 343.403424 -289.694589) (xy 343.412318 -289.673538) (xy 343.422224 -289.650932) (xy 343.208356 -289.245802)
			(xy 343.184226 -289.24123) (xy 343.159282 -289.236182) (xy 343.111239 -289.219398) (xy 343.066346 -289.195428)
			(xy 343.025672 -289.164843) (xy 342.990182 -289.128369) (xy 342.960721 -289.086873) (xy 342.937989 -289.041341)
			(xy 342.922525 -288.992857) (xy 342.914699 -288.942571) (xy 342.914224 -288.917126) (xy 342.633808 -288.917126)
			(xy 342.6333 -288.943033) (xy 342.625194 -288.99421) (xy 342.609182 -289.043489) (xy 342.585659 -289.089656)
			(xy 342.555203 -289.131575) (xy 342.518565 -289.168213) (xy 342.476646 -289.198669) (xy 342.430479 -289.222192)
			(xy 342.3812 -289.238204) (xy 342.330023 -289.24631) (xy 342.278209 -289.24631) (xy 342.227032 -289.238204)
			(xy 342.177753 -289.222192) (xy 342.131586 -289.198669) (xy 342.089667 -289.168213) (xy 342.053029 -289.131575)
			(xy 342.022573 -289.089656) (xy 341.99905 -289.043489) (xy 341.983038 -288.99421) (xy 341.974932 -288.943033)
			(xy 341.974424 -288.917126) (xy 341.694008 -288.917126) (xy 341.693589 -288.940067) (xy 341.68716 -288.985498)
			(xy 341.674513 -289.029604) (xy 341.66556 -289.05073) (xy 341.655654 -289.073336) (xy 341.869522 -289.478466)
			(xy 341.893652 -289.483038) (xy 341.918573 -289.488138) (xy 341.966584 -289.504939) (xy 342.011443 -289.528919)
			(xy 342.052084 -289.559507) (xy 342.087541 -289.595978) (xy 342.116973 -289.637465) (xy 342.139679 -289.682981)
			(xy 342.155121 -289.731446) (xy 342.162931 -289.781709) (xy 342.1634 -289.807142) (xy 342.162892 -289.833029)
			(xy 342.154793 -289.884167) (xy 342.138794 -289.933407) (xy 342.115288 -289.979539) (xy 342.084856 -290.021426)
			(xy 342.048246 -290.058036) (xy 342.006359 -290.088468) (xy 341.960227 -290.111974) (xy 341.910987 -290.127973)
			(xy 341.859849 -290.136072) (xy 341.808075 -290.136072) (xy 341.756937 -290.127973) (xy 341.707697 -290.111974)
			(xy 341.661565 -290.088468) (xy 341.619678 -290.058036) (xy 341.583068 -290.021426) (xy 341.552636 -289.979539)
			(xy 341.52913 -289.933407) (xy 341.513131 -289.884167) (xy 341.505032 -289.833029) (xy 341.504524 -289.807142)
			(xy 341.504524 -289.806634) (xy 341.504922 -289.783785) (xy 341.511275 -289.738531) (xy 341.523824 -289.694589)
			(xy 341.532718 -289.673538) (xy 341.542624 -289.650932) (xy 341.328756 -289.245802) (xy 341.304626 -289.24123)
			(xy 341.279682 -289.236182) (xy 341.231639 -289.219398) (xy 341.186746 -289.195428) (xy 341.146072 -289.164843)
			(xy 341.110582 -289.128369) (xy 341.081121 -289.086873) (xy 341.058389 -289.041341) (xy 341.042925 -288.992857)
			(xy 341.035099 -288.942571) (xy 341.034624 -288.917126) (xy 340.754208 -288.917126) (xy 340.7537 -288.943033)
			(xy 340.745594 -288.99421) (xy 340.729582 -289.043489) (xy 340.706059 -289.089656) (xy 340.675603 -289.131575)
			(xy 340.638965 -289.168213) (xy 340.597046 -289.198669) (xy 340.550879 -289.222192) (xy 340.5016 -289.238204)
			(xy 340.450423 -289.24631) (xy 340.398609 -289.24631) (xy 340.347432 -289.238204) (xy 340.298153 -289.222192)
			(xy 340.251986 -289.198669) (xy 340.210067 -289.168213) (xy 340.173429 -289.131575) (xy 340.142973 -289.089656)
			(xy 340.11945 -289.043489) (xy 340.103438 -288.99421) (xy 340.095332 -288.943033) (xy 340.094824 -288.917126)
			(xy 339.814408 -288.917126) (xy 339.813989 -288.940067) (xy 339.80756 -288.985498) (xy 339.794913 -289.029604)
			(xy 339.78596 -289.05073) (xy 339.776054 -289.073336) (xy 339.989922 -289.478466) (xy 340.014052 -289.483038)
			(xy 340.038973 -289.488138) (xy 340.086984 -289.504939) (xy 340.131843 -289.528919) (xy 340.172484 -289.559507)
			(xy 340.207941 -289.595978) (xy 340.237373 -289.637465) (xy 340.260079 -289.682981) (xy 340.275521 -289.731446)
			(xy 340.283331 -289.781709) (xy 340.2838 -289.807142) (xy 340.283292 -289.833029) (xy 340.275193 -289.884167)
			(xy 340.259194 -289.933407) (xy 340.235688 -289.979539) (xy 340.205256 -290.021426) (xy 340.168646 -290.058036)
			(xy 340.126759 -290.088468) (xy 340.080627 -290.111974) (xy 340.031387 -290.127973) (xy 339.980249 -290.136072)
			(xy 339.928475 -290.136072) (xy 339.877337 -290.127973) (xy 339.828097 -290.111974) (xy 339.781965 -290.088468)
			(xy 339.740078 -290.058036) (xy 339.703468 -290.021426) (xy 339.673036 -289.979539) (xy 339.64953 -289.933407)
			(xy 339.633531 -289.884167) (xy 339.625432 -289.833029) (xy 339.624924 -289.807142) (xy 339.624924 -289.806634)
			(xy 339.625322 -289.783785) (xy 339.631675 -289.738531) (xy 339.644224 -289.694589) (xy 339.653118 -289.673538)
			(xy 339.663024 -289.650932) (xy 339.449156 -289.245802) (xy 339.425026 -289.24123) (xy 339.400082 -289.236182)
			(xy 339.352039 -289.219398) (xy 339.307146 -289.195428) (xy 339.266472 -289.164843) (xy 339.230982 -289.128369)
			(xy 339.201521 -289.086873) (xy 339.178789 -289.041341) (xy 339.163325 -288.992857) (xy 339.155499 -288.942571)
			(xy 339.155024 -288.917126) (xy 338.874608 -288.917126) (xy 338.8741 -288.943033) (xy 338.865994 -288.99421)
			(xy 338.849982 -289.043489) (xy 338.826459 -289.089656) (xy 338.796003 -289.131575) (xy 338.759365 -289.168213)
			(xy 338.717446 -289.198669) (xy 338.671279 -289.222192) (xy 338.622 -289.238204) (xy 338.570823 -289.24631)
			(xy 338.519009 -289.24631) (xy 338.467832 -289.238204) (xy 338.418553 -289.222192) (xy 338.372386 -289.198669)
			(xy 338.330467 -289.168213) (xy 338.293829 -289.131575) (xy 338.263373 -289.089656) (xy 338.23985 -289.043489)
			(xy 338.223838 -288.99421) (xy 338.215732 -288.943033) (xy 338.215224 -288.917126) (xy 336.995008 -288.917126)
			(xy 336.9945 -288.943033) (xy 336.986394 -288.99421) (xy 336.970382 -289.043489) (xy 336.946859 -289.089656)
			(xy 336.916403 -289.131575) (xy 336.879765 -289.168213) (xy 336.837846 -289.198669) (xy 336.791679 -289.222192)
			(xy 336.7424 -289.238204) (xy 336.691223 -289.24631) (xy 336.639409 -289.24631) (xy 336.588232 -289.238204)
			(xy 336.538953 -289.222192) (xy 336.492786 -289.198669) (xy 336.450867 -289.168213) (xy 336.414229 -289.131575)
			(xy 336.383773 -289.089656) (xy 336.36025 -289.043489) (xy 336.344238 -288.99421) (xy 336.336132 -288.943033)
			(xy 336.335624 -288.917126) (xy 136.04494 -288.917126) (xy 136.044432 -288.943033) (xy 136.036326 -288.99421)
			(xy 136.020314 -289.043489) (xy 135.996791 -289.089656) (xy 135.966335 -289.131575) (xy 135.929697 -289.168213)
			(xy 135.887778 -289.198669) (xy 135.841611 -289.222192) (xy 135.792332 -289.238204) (xy 135.741155 -289.24631)
			(xy 135.689341 -289.24631) (xy 135.638164 -289.238204) (xy 135.588885 -289.222192) (xy 135.542718 -289.198669)
			(xy 135.500799 -289.168213) (xy 135.464161 -289.131575) (xy 135.433705 -289.089656) (xy 135.410182 -289.043489)
			(xy 135.39417 -288.99421) (xy 135.386064 -288.943033) (xy 135.385556 -288.917126) (xy 135.386153 -288.889409)
			(xy 135.395474 -288.834762) (xy 135.404098 -288.808414) (xy 135.411972 -288.786316) (xy 135.20674 -288.431224)
			(xy 135.18388 -288.426906) (xy 135.159064 -288.421716) (xy 135.111285 -288.404766) (xy 135.066665 -288.380698)
			(xy 135.026258 -288.350081) (xy 134.991016 -288.313637) (xy 134.961772 -288.272226) (xy 134.939214 -288.226825)
			(xy 134.923875 -288.178504) (xy 134.916118 -288.128404) (xy 134.915656 -288.103056) (xy 132.75564 -288.103056)
			(xy 132.755038 -288.130773) (xy 132.74572 -288.18542) (xy 132.737098 -288.211768) (xy 132.729478 -288.233866)
			(xy 132.934456 -288.588958) (xy 132.957316 -288.593276) (xy 132.982127 -288.598486) (xy 133.029905 -288.615434)
			(xy 133.074524 -288.6395) (xy 133.114931 -288.670114) (xy 133.150173 -288.706556) (xy 133.179418 -288.747964)
			(xy 133.201977 -288.793363) (xy 133.217317 -288.841681) (xy 133.225077 -288.891779) (xy 133.22554 -288.917126)
			(xy 133.225032 -288.943033) (xy 133.216926 -288.99421) (xy 133.200914 -289.043489) (xy 133.177391 -289.089656)
			(xy 133.146935 -289.131575) (xy 133.110297 -289.168213) (xy 133.068378 -289.198669) (xy 133.022211 -289.222192)
			(xy 132.972932 -289.238204) (xy 132.921755 -289.24631) (xy 132.869941 -289.24631) (xy 132.818764 -289.238204)
			(xy 132.769485 -289.222192) (xy 132.723318 -289.198669) (xy 132.681399 -289.168213) (xy 132.644761 -289.131575)
			(xy 132.614305 -289.089656) (xy 132.590782 -289.043489) (xy 132.57477 -288.99421) (xy 132.566664 -288.943033)
			(xy 132.566156 -288.917126) (xy 132.566753 -288.889409) (xy 132.576074 -288.834762) (xy 132.584698 -288.808414)
			(xy 132.592572 -288.786316) (xy 132.387594 -288.431224) (xy 132.364734 -288.426906) (xy 132.339899 -288.421756)
			(xy 132.292089 -288.404821) (xy 132.247438 -288.380764) (xy 132.206999 -288.350151) (xy 132.171726 -288.313705)
			(xy 132.142451 -288.272287) (xy 132.119866 -288.226873) (xy 132.104504 -288.178536) (xy 132.096726 -288.128416)
			(xy 132.096256 -288.103056) (xy 130.87604 -288.103056) (xy 130.875438 -288.130773) (xy 130.86612 -288.18542)
			(xy 130.857498 -288.211768) (xy 130.849878 -288.233866) (xy 131.054856 -288.588958) (xy 131.077716 -288.593276)
			(xy 131.102527 -288.598486) (xy 131.150305 -288.615434) (xy 131.194924 -288.6395) (xy 131.235331 -288.670114)
			(xy 131.270573 -288.706556) (xy 131.299818 -288.747964) (xy 131.322377 -288.793363) (xy 131.337717 -288.841681)
			(xy 131.345477 -288.891779) (xy 131.34594 -288.917126) (xy 131.345432 -288.943033) (xy 131.337326 -288.99421)
			(xy 131.321314 -289.043489) (xy 131.297791 -289.089656) (xy 131.267335 -289.131575) (xy 131.230697 -289.168213)
			(xy 131.188778 -289.198669) (xy 131.142611 -289.222192) (xy 131.093332 -289.238204) (xy 131.042155 -289.24631)
			(xy 130.990341 -289.24631) (xy 130.939164 -289.238204) (xy 130.889885 -289.222192) (xy 130.843718 -289.198669)
			(xy 130.801799 -289.168213) (xy 130.765161 -289.131575) (xy 130.734705 -289.089656) (xy 130.711182 -289.043489)
			(xy 130.69517 -288.99421) (xy 130.687064 -288.943033) (xy 130.686556 -288.917126) (xy 130.687153 -288.889409)
			(xy 130.696474 -288.834762) (xy 130.705098 -288.808414) (xy 130.712972 -288.786316) (xy 130.507994 -288.431224)
			(xy 130.485134 -288.426906) (xy 130.460299 -288.421756) (xy 130.412489 -288.404821) (xy 130.367838 -288.380764)
			(xy 130.327399 -288.350151) (xy 130.292126 -288.313705) (xy 130.262851 -288.272287) (xy 130.240266 -288.226873)
			(xy 130.224904 -288.178536) (xy 130.217126 -288.128416) (xy 130.216656 -288.103056) (xy 128.99644 -288.103056)
			(xy 128.995838 -288.130773) (xy 128.98652 -288.18542) (xy 128.977898 -288.211768) (xy 128.970278 -288.233866)
			(xy 129.175256 -288.588958) (xy 129.198116 -288.593276) (xy 129.222927 -288.598486) (xy 129.270705 -288.615434)
			(xy 129.315324 -288.6395) (xy 129.355731 -288.670114) (xy 129.390973 -288.706556) (xy 129.420218 -288.747964)
			(xy 129.442777 -288.793363) (xy 129.458117 -288.841681) (xy 129.465877 -288.891779) (xy 129.46634 -288.917126)
			(xy 129.465832 -288.943033) (xy 129.457726 -288.99421) (xy 129.441714 -289.043489) (xy 129.418191 -289.089656)
			(xy 129.387735 -289.131575) (xy 129.351097 -289.168213) (xy 129.309178 -289.198669) (xy 129.263011 -289.222192)
			(xy 129.213732 -289.238204) (xy 129.162555 -289.24631) (xy 129.110741 -289.24631) (xy 129.059564 -289.238204)
			(xy 129.010285 -289.222192) (xy 128.964118 -289.198669) (xy 128.922199 -289.168213) (xy 128.885561 -289.131575)
			(xy 128.855105 -289.089656) (xy 128.831582 -289.043489) (xy 128.81557 -288.99421) (xy 128.807464 -288.943033)
			(xy 128.806956 -288.917126) (xy 128.807553 -288.889409) (xy 128.816874 -288.834762) (xy 128.825498 -288.808414)
			(xy 128.833372 -288.786316) (xy 128.628394 -288.431224) (xy 128.605534 -288.426906) (xy 128.580699 -288.421756)
			(xy 128.532889 -288.404821) (xy 128.488238 -288.380764) (xy 128.447799 -288.350151) (xy 128.412526 -288.313705)
			(xy 128.383251 -288.272287) (xy 128.360666 -288.226873) (xy 128.345304 -288.178536) (xy 128.337526 -288.128416)
			(xy 128.337056 -288.103056) (xy 127.11684 -288.103056) (xy 127.116238 -288.130773) (xy 127.10692 -288.18542)
			(xy 127.098298 -288.211768) (xy 127.090678 -288.233866) (xy 127.295656 -288.588958) (xy 127.318516 -288.593276)
			(xy 127.343327 -288.598486) (xy 127.391105 -288.615434) (xy 127.435724 -288.6395) (xy 127.476131 -288.670114)
			(xy 127.511373 -288.706556) (xy 127.540618 -288.747964) (xy 127.563177 -288.793363) (xy 127.578517 -288.841681)
			(xy 127.586277 -288.891779) (xy 127.58674 -288.917126) (xy 127.586232 -288.943033) (xy 127.578126 -288.99421)
			(xy 127.562114 -289.043489) (xy 127.538591 -289.089656) (xy 127.508135 -289.131575) (xy 127.471497 -289.168213)
			(xy 127.429578 -289.198669) (xy 127.383411 -289.222192) (xy 127.334132 -289.238204) (xy 127.282955 -289.24631)
			(xy 127.231141 -289.24631) (xy 127.179964 -289.238204) (xy 127.130685 -289.222192) (xy 127.084518 -289.198669)
			(xy 127.042599 -289.168213) (xy 127.005961 -289.131575) (xy 126.975505 -289.089656) (xy 126.951982 -289.043489)
			(xy 126.93597 -288.99421) (xy 126.927864 -288.943033) (xy 126.927356 -288.917126) (xy 126.927953 -288.889409)
			(xy 126.937274 -288.834762) (xy 126.945898 -288.808414) (xy 126.953772 -288.786316) (xy 126.748794 -288.431224)
			(xy 126.725934 -288.426906) (xy 126.701099 -288.421756) (xy 126.653289 -288.404821) (xy 126.608638 -288.380764)
			(xy 126.568199 -288.350151) (xy 126.532926 -288.313705) (xy 126.503651 -288.272287) (xy 126.481066 -288.226873)
			(xy 126.465704 -288.178536) (xy 126.457926 -288.128416) (xy 126.457456 -288.103056) (xy 125.23724 -288.103056)
			(xy 125.236638 -288.130773) (xy 125.22732 -288.18542) (xy 125.218698 -288.211768) (xy 125.211078 -288.233866)
			(xy 125.416056 -288.588958) (xy 125.438916 -288.593276) (xy 125.463727 -288.598486) (xy 125.511505 -288.615434)
			(xy 125.556124 -288.6395) (xy 125.596531 -288.670114) (xy 125.631773 -288.706556) (xy 125.661018 -288.747964)
			(xy 125.683577 -288.793363) (xy 125.698917 -288.841681) (xy 125.706677 -288.891779) (xy 125.70714 -288.917126)
			(xy 125.706632 -288.943033) (xy 125.698526 -288.99421) (xy 125.682514 -289.043489) (xy 125.658991 -289.089656)
			(xy 125.628535 -289.131575) (xy 125.591897 -289.168213) (xy 125.549978 -289.198669) (xy 125.503811 -289.222192)
			(xy 125.454532 -289.238204) (xy 125.403355 -289.24631) (xy 125.351541 -289.24631) (xy 125.300364 -289.238204)
			(xy 125.251085 -289.222192) (xy 125.204918 -289.198669) (xy 125.162999 -289.168213) (xy 125.126361 -289.131575)
			(xy 125.095905 -289.089656) (xy 125.072382 -289.043489) (xy 125.05637 -288.99421) (xy 125.048264 -288.943033)
			(xy 125.047756 -288.917126) (xy 125.048353 -288.889409) (xy 125.057674 -288.834762) (xy 125.066298 -288.808414)
			(xy 125.074172 -288.786316) (xy 124.869194 -288.431224) (xy 124.846334 -288.426906) (xy 124.821499 -288.421756)
			(xy 124.773689 -288.404821) (xy 124.729038 -288.380764) (xy 124.688599 -288.350151) (xy 124.653326 -288.313705)
			(xy 124.624051 -288.272287) (xy 124.601466 -288.226873) (xy 124.586104 -288.178536) (xy 124.578326 -288.128416)
			(xy 124.577856 -288.103056) (xy 123.35764 -288.103056) (xy 123.357038 -288.130773) (xy 123.34772 -288.18542)
			(xy 123.339098 -288.211768) (xy 123.331478 -288.233866) (xy 123.536456 -288.588958) (xy 123.559316 -288.593276)
			(xy 123.584127 -288.598486) (xy 123.631905 -288.615434) (xy 123.676524 -288.6395) (xy 123.716931 -288.670114)
			(xy 123.752173 -288.706556) (xy 123.781418 -288.747964) (xy 123.803977 -288.793363) (xy 123.819317 -288.841681)
			(xy 123.827077 -288.891779) (xy 123.82754 -288.917126) (xy 123.827032 -288.943033) (xy 123.818926 -288.99421)
			(xy 123.802914 -289.043489) (xy 123.779391 -289.089656) (xy 123.748935 -289.131575) (xy 123.712297 -289.168213)
			(xy 123.670378 -289.198669) (xy 123.624211 -289.222192) (xy 123.574932 -289.238204) (xy 123.523755 -289.24631)
			(xy 123.471941 -289.24631) (xy 123.420764 -289.238204) (xy 123.371485 -289.222192) (xy 123.325318 -289.198669)
			(xy 123.283399 -289.168213) (xy 123.246761 -289.131575) (xy 123.216305 -289.089656) (xy 123.192782 -289.043489)
			(xy 123.17677 -288.99421) (xy 123.168664 -288.943033) (xy 123.168156 -288.917126) (xy 123.168753 -288.889409)
			(xy 123.178074 -288.834762) (xy 123.186698 -288.808414) (xy 123.194572 -288.786316) (xy 122.989594 -288.431224)
			(xy 122.966734 -288.426906) (xy 122.941899 -288.421756) (xy 122.894089 -288.404821) (xy 122.849438 -288.380764)
			(xy 122.808999 -288.350151) (xy 122.773726 -288.313705) (xy 122.744451 -288.272287) (xy 122.721866 -288.226873)
			(xy 122.706504 -288.178536) (xy 122.698726 -288.128416) (xy 122.698256 -288.103056) (xy 121.47804 -288.103056)
			(xy 121.477438 -288.130773) (xy 121.46812 -288.18542) (xy 121.459498 -288.211768) (xy 121.451624 -288.233866)
			(xy 121.656856 -288.588958) (xy 121.679716 -288.593276) (xy 121.704527 -288.598486) (xy 121.752305 -288.615434)
			(xy 121.796924 -288.6395) (xy 121.837331 -288.670114) (xy 121.872573 -288.706556) (xy 121.901818 -288.747964)
			(xy 121.924377 -288.793363) (xy 121.939717 -288.841681) (xy 121.947477 -288.891779) (xy 121.94794 -288.917126)
			(xy 121.947432 -288.943033) (xy 121.939326 -288.99421) (xy 121.923314 -289.043489) (xy 121.899791 -289.089656)
			(xy 121.869335 -289.131575) (xy 121.832697 -289.168213) (xy 121.790778 -289.198669) (xy 121.744611 -289.222192)
			(xy 121.695332 -289.238204) (xy 121.644155 -289.24631) (xy 121.592341 -289.24631) (xy 121.541164 -289.238204)
			(xy 121.491885 -289.222192) (xy 121.445718 -289.198669) (xy 121.403799 -289.168213) (xy 121.367161 -289.131575)
			(xy 121.336705 -289.089656) (xy 121.313182 -289.043489) (xy 121.29717 -288.99421) (xy 121.289064 -288.943033)
			(xy 121.288556 -288.917126) (xy 121.289153 -288.889409) (xy 121.298474 -288.834762) (xy 121.307098 -288.808414)
			(xy 121.314972 -288.786316) (xy 121.10974 -288.431224) (xy 121.08688 -288.426906) (xy 121.062064 -288.421716)
			(xy 121.014285 -288.404766) (xy 120.969665 -288.380698) (xy 120.929258 -288.350081) (xy 120.894016 -288.313637)
			(xy 120.864772 -288.272226) (xy 120.842214 -288.226825) (xy 120.826875 -288.178504) (xy 120.819118 -288.128404)
			(xy 120.818656 -288.103056) (xy 104.56164 -288.103056) (xy 104.561218 -288.128404) (xy 104.553436 -288.178499)
			(xy 104.53808 -288.226813) (xy 104.515512 -288.272208) (xy 104.486262 -288.313614) (xy 104.451021 -288.350057)
			(xy 104.410618 -288.380678) (xy 104.366005 -288.404755) (xy 104.318232 -288.421722) (xy 104.293416 -288.426906)
			(xy 104.270556 -288.431224) (xy 104.065324 -288.786316) (xy 104.073198 -288.808414) (xy 104.08184 -288.834757)
			(xy 104.091154 -288.889407) (xy 104.09174 -288.917126) (xy 104.091232 -288.943033) (xy 104.083126 -288.99421)
			(xy 104.067114 -289.043489) (xy 104.043591 -289.089656) (xy 104.013135 -289.131575) (xy 103.976497 -289.168213)
			(xy 103.934578 -289.198669) (xy 103.888411 -289.222192) (xy 103.839132 -289.238204) (xy 103.787955 -289.24631)
			(xy 103.736141 -289.24631) (xy 103.684964 -289.238204) (xy 103.635685 -289.222192) (xy 103.589518 -289.198669)
			(xy 103.547599 -289.168213) (xy 103.510961 -289.131575) (xy 103.480505 -289.089656) (xy 103.456982 -289.043489)
			(xy 103.44097 -288.99421) (xy 103.432864 -288.943033) (xy 103.432356 -288.917126) (xy 103.15194 -288.917126)
			(xy 103.151518 -288.940067) (xy 103.14509 -288.985498) (xy 103.132444 -289.029604) (xy 103.123492 -289.05073)
			(xy 103.113586 -289.073336) (xy 103.327454 -289.478466) (xy 103.351584 -289.483038) (xy 103.37651 -289.488115)
			(xy 103.424521 -289.50492) (xy 103.469379 -289.528904) (xy 103.510019 -289.559496) (xy 103.545476 -289.59597)
			(xy 103.574906 -289.637459) (xy 103.597612 -289.682977) (xy 103.613053 -289.731444) (xy 103.620863 -289.781708)
			(xy 103.621332 -289.807142) (xy 119.878856 -289.807142) (xy 119.879399 -289.781715) (xy 119.887229 -289.731468)
			(xy 119.90268 -289.683018) (xy 119.925386 -289.637514) (xy 119.954808 -289.596036) (xy 119.990248 -289.559565)
			(xy 120.030867 -289.528967) (xy 120.075701 -289.504967) (xy 120.123688 -289.488134) (xy 120.148604 -289.483038)
			(xy 120.172734 -289.478466) (xy 120.38711 -289.073082) (xy 120.377204 -289.050476) (xy 120.368243 -289.029398)
			(xy 120.355596 -288.985377) (xy 120.349182 -288.940026) (xy 120.348756 -288.917126) (xy 120.349264 -288.891219)
			(xy 120.35737 -288.840042) (xy 120.373382 -288.790763) (xy 120.396905 -288.744596) (xy 120.427361 -288.702677)
			(xy 120.463999 -288.666039) (xy 120.505918 -288.635583) (xy 120.552085 -288.61206) (xy 120.601364 -288.596048)
			(xy 120.652541 -288.587942) (xy 120.704355 -288.587942) (xy 120.755532 -288.596048) (xy 120.804811 -288.61206)
			(xy 120.850978 -288.635583) (xy 120.892897 -288.666039) (xy 120.929535 -288.702677) (xy 120.959991 -288.744596)
			(xy 120.983514 -288.790763) (xy 120.999526 -288.840042) (xy 121.007632 -288.891219) (xy 121.00814 -288.917126)
			(xy 121.007659 -288.942574) (xy 120.999856 -288.992867) (xy 120.984408 -289.041361) (xy 120.961683 -289.086901)
			(xy 120.932222 -289.128403) (xy 120.896727 -289.164878) (xy 120.856043 -289.195458) (xy 120.811139 -289.219415)
			(xy 120.763084 -289.236178) (xy 120.738138 -289.24123) (xy 120.714008 -289.245802) (xy 120.499632 -289.651186)
			(xy 120.509538 -289.673792) (xy 120.518456 -289.694878) (xy 120.531008 -289.738907) (xy 120.537342 -289.78425)
			(xy 120.537732 -289.807142) (xy 121.758456 -289.807142) (xy 121.758999 -289.781715) (xy 121.766829 -289.731468)
			(xy 121.78228 -289.683018) (xy 121.804986 -289.637514) (xy 121.834408 -289.596036) (xy 121.869848 -289.559565)
			(xy 121.910467 -289.528967) (xy 121.955301 -289.504967) (xy 122.003288 -289.488134) (xy 122.028204 -289.483038)
			(xy 122.052334 -289.478466) (xy 122.26671 -289.073082) (xy 122.256804 -289.050476) (xy 122.247843 -289.029398)
			(xy 122.235196 -288.985377) (xy 122.228782 -288.940026) (xy 122.228356 -288.917126) (xy 122.228864 -288.891219)
			(xy 122.23697 -288.840042) (xy 122.252982 -288.790763) (xy 122.276505 -288.744596) (xy 122.306961 -288.702677)
			(xy 122.343599 -288.666039) (xy 122.385518 -288.635583) (xy 122.431685 -288.61206) (xy 122.480964 -288.596048)
			(xy 122.532141 -288.587942) (xy 122.583955 -288.587942) (xy 122.635132 -288.596048) (xy 122.684411 -288.61206)
			(xy 122.730578 -288.635583) (xy 122.772497 -288.666039) (xy 122.809135 -288.702677) (xy 122.839591 -288.744596)
			(xy 122.863114 -288.790763) (xy 122.879126 -288.840042) (xy 122.887232 -288.891219) (xy 122.88774 -288.917126)
			(xy 122.887259 -288.942574) (xy 122.879456 -288.992867) (xy 122.864008 -289.041361) (xy 122.841283 -289.086901)
			(xy 122.811822 -289.128403) (xy 122.776327 -289.164878) (xy 122.735643 -289.195458) (xy 122.690739 -289.219415)
			(xy 122.642684 -289.236178) (xy 122.617738 -289.24123) (xy 122.593608 -289.245802) (xy 122.379232 -289.651186)
			(xy 122.389138 -289.673792) (xy 122.398056 -289.694878) (xy 122.410608 -289.738907) (xy 122.416942 -289.78425)
			(xy 122.417332 -289.807142) (xy 123.638056 -289.807142) (xy 123.638599 -289.781715) (xy 123.646429 -289.731468)
			(xy 123.66188 -289.683018) (xy 123.684586 -289.637514) (xy 123.714008 -289.596036) (xy 123.749448 -289.559565)
			(xy 123.790067 -289.528967) (xy 123.834901 -289.504967) (xy 123.882888 -289.488134) (xy 123.907804 -289.483038)
			(xy 123.931934 -289.478466) (xy 124.14631 -289.073082) (xy 124.136404 -289.050476) (xy 124.127443 -289.029398)
			(xy 124.114796 -288.985377) (xy 124.108382 -288.940026) (xy 124.107956 -288.917126) (xy 124.108464 -288.891219)
			(xy 124.11657 -288.840042) (xy 124.132582 -288.790763) (xy 124.156105 -288.744596) (xy 124.186561 -288.702677)
			(xy 124.223199 -288.666039) (xy 124.265118 -288.635583) (xy 124.311285 -288.61206) (xy 124.360564 -288.596048)
			(xy 124.411741 -288.587942) (xy 124.463555 -288.587942) (xy 124.514732 -288.596048) (xy 124.564011 -288.61206)
			(xy 124.610178 -288.635583) (xy 124.652097 -288.666039) (xy 124.688735 -288.702677) (xy 124.719191 -288.744596)
			(xy 124.742714 -288.790763) (xy 124.758726 -288.840042) (xy 124.766832 -288.891219) (xy 124.76734 -288.917126)
			(xy 124.766859 -288.942574) (xy 124.759056 -288.992867) (xy 124.743608 -289.041361) (xy 124.720883 -289.086901)
			(xy 124.691422 -289.128403) (xy 124.655927 -289.164878) (xy 124.615243 -289.195458) (xy 124.570339 -289.219415)
			(xy 124.522284 -289.236178) (xy 124.497338 -289.24123) (xy 124.473208 -289.245802) (xy 124.258832 -289.651186)
			(xy 124.268738 -289.673792) (xy 124.277656 -289.694878) (xy 124.290208 -289.738907) (xy 124.296542 -289.78425)
			(xy 124.296932 -289.807142) (xy 125.517656 -289.807142) (xy 125.518199 -289.781715) (xy 125.526029 -289.731468)
			(xy 125.54148 -289.683018) (xy 125.564186 -289.637514) (xy 125.593608 -289.596036) (xy 125.629048 -289.559565)
			(xy 125.669667 -289.528967) (xy 125.714501 -289.504967) (xy 125.762488 -289.488134) (xy 125.787404 -289.483038)
			(xy 125.811534 -289.478466) (xy 126.02591 -289.073082) (xy 126.016004 -289.050476) (xy 126.007043 -289.029398)
			(xy 125.994396 -288.985377) (xy 125.987982 -288.940026) (xy 125.987556 -288.917126) (xy 125.988064 -288.891219)
			(xy 125.99617 -288.840042) (xy 126.012182 -288.790763) (xy 126.035705 -288.744596) (xy 126.066161 -288.702677)
			(xy 126.102799 -288.666039) (xy 126.144718 -288.635583) (xy 126.190885 -288.61206) (xy 126.240164 -288.596048)
			(xy 126.291341 -288.587942) (xy 126.343155 -288.587942) (xy 126.394332 -288.596048) (xy 126.443611 -288.61206)
			(xy 126.489778 -288.635583) (xy 126.531697 -288.666039) (xy 126.568335 -288.702677) (xy 126.598791 -288.744596)
			(xy 126.622314 -288.790763) (xy 126.638326 -288.840042) (xy 126.646432 -288.891219) (xy 126.64694 -288.917126)
			(xy 126.646459 -288.942574) (xy 126.638656 -288.992867) (xy 126.623208 -289.041361) (xy 126.600483 -289.086901)
			(xy 126.571022 -289.128403) (xy 126.535527 -289.164878) (xy 126.494843 -289.195458) (xy 126.449939 -289.219415)
			(xy 126.401884 -289.236178) (xy 126.376938 -289.24123) (xy 126.352808 -289.245802) (xy 126.138432 -289.651186)
			(xy 126.148338 -289.673792) (xy 126.157256 -289.694878) (xy 126.169808 -289.738907) (xy 126.176142 -289.78425)
			(xy 126.176532 -289.807142) (xy 127.397256 -289.807142) (xy 127.397799 -289.781715) (xy 127.405629 -289.731468)
			(xy 127.42108 -289.683018) (xy 127.443786 -289.637514) (xy 127.473208 -289.596036) (xy 127.508648 -289.559565)
			(xy 127.549267 -289.528967) (xy 127.594101 -289.504967) (xy 127.642088 -289.488134) (xy 127.667004 -289.483038)
			(xy 127.691134 -289.478466) (xy 127.90551 -289.073082) (xy 127.895604 -289.050476) (xy 127.886643 -289.029398)
			(xy 127.873996 -288.985377) (xy 127.867582 -288.940026) (xy 127.867156 -288.917126) (xy 127.867664 -288.891219)
			(xy 127.87577 -288.840042) (xy 127.891782 -288.790763) (xy 127.915305 -288.744596) (xy 127.945761 -288.702677)
			(xy 127.982399 -288.666039) (xy 128.024318 -288.635583) (xy 128.070485 -288.61206) (xy 128.119764 -288.596048)
			(xy 128.170941 -288.587942) (xy 128.222755 -288.587942) (xy 128.273932 -288.596048) (xy 128.323211 -288.61206)
			(xy 128.369378 -288.635583) (xy 128.411297 -288.666039) (xy 128.447935 -288.702677) (xy 128.478391 -288.744596)
			(xy 128.501914 -288.790763) (xy 128.517926 -288.840042) (xy 128.526032 -288.891219) (xy 128.52654 -288.917126)
			(xy 128.526059 -288.942574) (xy 128.518256 -288.992867) (xy 128.502808 -289.041361) (xy 128.480083 -289.086901)
			(xy 128.450622 -289.128403) (xy 128.415127 -289.164878) (xy 128.374443 -289.195458) (xy 128.329539 -289.219415)
			(xy 128.281484 -289.236178) (xy 128.256538 -289.24123) (xy 128.232408 -289.245802) (xy 128.018032 -289.651186)
			(xy 128.027938 -289.673792) (xy 128.036856 -289.694878) (xy 128.049408 -289.738907) (xy 128.055742 -289.78425)
			(xy 128.056132 -289.807142) (xy 129.276856 -289.807142) (xy 129.277399 -289.781715) (xy 129.285229 -289.731468)
			(xy 129.30068 -289.683018) (xy 129.323386 -289.637514) (xy 129.352808 -289.596036) (xy 129.388248 -289.559565)
			(xy 129.428867 -289.528967) (xy 129.473701 -289.504967) (xy 129.521688 -289.488134) (xy 129.546604 -289.483038)
			(xy 129.570734 -289.478466) (xy 129.78511 -289.073082) (xy 129.775204 -289.050476) (xy 129.766243 -289.029398)
			(xy 129.753596 -288.985377) (xy 129.747182 -288.940026) (xy 129.746756 -288.917126) (xy 129.747264 -288.891219)
			(xy 129.75537 -288.840042) (xy 129.771382 -288.790763) (xy 129.794905 -288.744596) (xy 129.825361 -288.702677)
			(xy 129.861999 -288.666039) (xy 129.903918 -288.635583) (xy 129.950085 -288.61206) (xy 129.999364 -288.596048)
			(xy 130.050541 -288.587942) (xy 130.102355 -288.587942) (xy 130.153532 -288.596048) (xy 130.202811 -288.61206)
			(xy 130.248978 -288.635583) (xy 130.290897 -288.666039) (xy 130.327535 -288.702677) (xy 130.357991 -288.744596)
			(xy 130.381514 -288.790763) (xy 130.397526 -288.840042) (xy 130.405632 -288.891219) (xy 130.40614 -288.917126)
			(xy 130.405659 -288.942574) (xy 130.397856 -288.992867) (xy 130.382408 -289.041361) (xy 130.359683 -289.086901)
			(xy 130.330222 -289.128403) (xy 130.294727 -289.164878) (xy 130.254043 -289.195458) (xy 130.209139 -289.219415)
			(xy 130.161084 -289.236178) (xy 130.136138 -289.24123) (xy 130.112008 -289.245802) (xy 129.897632 -289.651186)
			(xy 129.907538 -289.673792) (xy 129.916456 -289.694878) (xy 129.929008 -289.738907) (xy 129.935342 -289.78425)
			(xy 129.935732 -289.807142) (xy 131.156456 -289.807142) (xy 131.156999 -289.781715) (xy 131.164829 -289.731468)
			(xy 131.18028 -289.683018) (xy 131.202986 -289.637514) (xy 131.232408 -289.596036) (xy 131.267848 -289.559565)
			(xy 131.308467 -289.528967) (xy 131.353301 -289.504967) (xy 131.401288 -289.488134) (xy 131.426204 -289.483038)
			(xy 131.450334 -289.478466) (xy 131.66471 -289.073082) (xy 131.654804 -289.050476) (xy 131.645843 -289.029398)
			(xy 131.633196 -288.985377) (xy 131.626782 -288.940026) (xy 131.626356 -288.917126) (xy 131.626864 -288.891219)
			(xy 131.63497 -288.840042) (xy 131.650982 -288.790763) (xy 131.674505 -288.744596) (xy 131.704961 -288.702677)
			(xy 131.741599 -288.666039) (xy 131.783518 -288.635583) (xy 131.829685 -288.61206) (xy 131.878964 -288.596048)
			(xy 131.930141 -288.587942) (xy 131.981955 -288.587942) (xy 132.033132 -288.596048) (xy 132.082411 -288.61206)
			(xy 132.128578 -288.635583) (xy 132.170497 -288.666039) (xy 132.207135 -288.702677) (xy 132.237591 -288.744596)
			(xy 132.261114 -288.790763) (xy 132.277126 -288.840042) (xy 132.285232 -288.891219) (xy 132.28574 -288.917126)
			(xy 132.285259 -288.942574) (xy 132.277456 -288.992867) (xy 132.262008 -289.041361) (xy 132.239283 -289.086901)
			(xy 132.209822 -289.128403) (xy 132.174327 -289.164878) (xy 132.133643 -289.195458) (xy 132.088739 -289.219415)
			(xy 132.040684 -289.236178) (xy 132.015738 -289.24123) (xy 131.991608 -289.245802) (xy 131.777232 -289.651186)
			(xy 131.787138 -289.673792) (xy 131.796056 -289.694878) (xy 131.808608 -289.738907) (xy 131.814942 -289.78425)
			(xy 131.815332 -289.807142) (xy 133.036056 -289.807142) (xy 133.036599 -289.781715) (xy 133.044429 -289.731468)
			(xy 133.05988 -289.683018) (xy 133.082586 -289.637514) (xy 133.112008 -289.596036) (xy 133.147448 -289.559565)
			(xy 133.188067 -289.528967) (xy 133.232901 -289.504967) (xy 133.280888 -289.488134) (xy 133.305804 -289.483038)
			(xy 133.329934 -289.478466) (xy 133.54431 -289.073082) (xy 133.534404 -289.050476) (xy 133.525443 -289.029398)
			(xy 133.512796 -288.985377) (xy 133.506382 -288.940026) (xy 133.505956 -288.917126) (xy 133.506464 -288.891219)
			(xy 133.51457 -288.840042) (xy 133.530582 -288.790763) (xy 133.554105 -288.744596) (xy 133.584561 -288.702677)
			(xy 133.621199 -288.666039) (xy 133.663118 -288.635583) (xy 133.709285 -288.61206) (xy 133.758564 -288.596048)
			(xy 133.809741 -288.587942) (xy 133.861555 -288.587942) (xy 133.912732 -288.596048) (xy 133.962011 -288.61206)
			(xy 134.008178 -288.635583) (xy 134.050097 -288.666039) (xy 134.086735 -288.702677) (xy 134.117191 -288.744596)
			(xy 134.140714 -288.790763) (xy 134.156726 -288.840042) (xy 134.164832 -288.891219) (xy 134.16534 -288.917126)
			(xy 134.164859 -288.942574) (xy 134.157056 -288.992867) (xy 134.141608 -289.041361) (xy 134.118883 -289.086901)
			(xy 134.089422 -289.128403) (xy 134.053927 -289.164878) (xy 134.013243 -289.195458) (xy 133.968339 -289.219415)
			(xy 133.920284 -289.236178) (xy 133.895338 -289.24123) (xy 133.871208 -289.245802) (xy 133.656832 -289.651186)
			(xy 133.666738 -289.673792) (xy 133.675656 -289.694878) (xy 133.688208 -289.738907) (xy 133.694542 -289.78425)
			(xy 133.694932 -289.807142) (xy 133.694424 -289.833029) (xy 133.686325 -289.884167) (xy 133.670326 -289.933407)
			(xy 133.64682 -289.979539) (xy 133.616388 -290.021426) (xy 133.579778 -290.058036) (xy 133.537891 -290.088468)
			(xy 133.491759 -290.111974) (xy 133.442519 -290.127973) (xy 133.391381 -290.136072) (xy 133.339607 -290.136072)
			(xy 133.288469 -290.127973) (xy 133.239229 -290.111974) (xy 133.193097 -290.088468) (xy 133.15121 -290.058036)
			(xy 133.1146 -290.021426) (xy 133.084168 -289.979539) (xy 133.060662 -289.933407) (xy 133.044663 -289.884167)
			(xy 133.036564 -289.833029) (xy 133.036056 -289.807142) (xy 131.815332 -289.807142) (xy 131.814824 -289.833029)
			(xy 131.806725 -289.884167) (xy 131.790726 -289.933407) (xy 131.76722 -289.979539) (xy 131.736788 -290.021426)
			(xy 131.700178 -290.058036) (xy 131.658291 -290.088468) (xy 131.612159 -290.111974) (xy 131.562919 -290.127973)
			(xy 131.511781 -290.136072) (xy 131.460007 -290.136072) (xy 131.408869 -290.127973) (xy 131.359629 -290.111974)
			(xy 131.313497 -290.088468) (xy 131.27161 -290.058036) (xy 131.235 -290.021426) (xy 131.204568 -289.979539)
			(xy 131.181062 -289.933407) (xy 131.165063 -289.884167) (xy 131.156964 -289.833029) (xy 131.156456 -289.807142)
			(xy 129.935732 -289.807142) (xy 129.935224 -289.833029) (xy 129.927125 -289.884167) (xy 129.911126 -289.933407)
			(xy 129.88762 -289.979539) (xy 129.857188 -290.021426) (xy 129.820578 -290.058036) (xy 129.778691 -290.088468)
			(xy 129.732559 -290.111974) (xy 129.683319 -290.127973) (xy 129.632181 -290.136072) (xy 129.580407 -290.136072)
			(xy 129.529269 -290.127973) (xy 129.480029 -290.111974) (xy 129.433897 -290.088468) (xy 129.39201 -290.058036)
			(xy 129.3554 -290.021426) (xy 129.324968 -289.979539) (xy 129.301462 -289.933407) (xy 129.285463 -289.884167)
			(xy 129.277364 -289.833029) (xy 129.276856 -289.807142) (xy 128.056132 -289.807142) (xy 128.055624 -289.833029)
			(xy 128.047525 -289.884167) (xy 128.031526 -289.933407) (xy 128.00802 -289.979539) (xy 127.977588 -290.021426)
			(xy 127.940978 -290.058036) (xy 127.899091 -290.088468) (xy 127.852959 -290.111974) (xy 127.803719 -290.127973)
			(xy 127.752581 -290.136072) (xy 127.700807 -290.136072) (xy 127.649669 -290.127973) (xy 127.600429 -290.111974)
			(xy 127.554297 -290.088468) (xy 127.51241 -290.058036) (xy 127.4758 -290.021426) (xy 127.445368 -289.979539)
			(xy 127.421862 -289.933407) (xy 127.405863 -289.884167) (xy 127.397764 -289.833029) (xy 127.397256 -289.807142)
			(xy 126.176532 -289.807142) (xy 126.176024 -289.833029) (xy 126.167925 -289.884167) (xy 126.151926 -289.933407)
			(xy 126.12842 -289.979539) (xy 126.097988 -290.021426) (xy 126.061378 -290.058036) (xy 126.019491 -290.088468)
			(xy 125.973359 -290.111974) (xy 125.924119 -290.127973) (xy 125.872981 -290.136072) (xy 125.821207 -290.136072)
			(xy 125.770069 -290.127973) (xy 125.720829 -290.111974) (xy 125.674697 -290.088468) (xy 125.63281 -290.058036)
			(xy 125.5962 -290.021426) (xy 125.565768 -289.979539) (xy 125.542262 -289.933407) (xy 125.526263 -289.884167)
			(xy 125.518164 -289.833029) (xy 125.517656 -289.807142) (xy 124.296932 -289.807142) (xy 124.296424 -289.833029)
			(xy 124.288325 -289.884167) (xy 124.272326 -289.933407) (xy 124.24882 -289.979539) (xy 124.218388 -290.021426)
			(xy 124.181778 -290.058036) (xy 124.139891 -290.088468) (xy 124.093759 -290.111974) (xy 124.044519 -290.127973)
			(xy 123.993381 -290.136072) (xy 123.941607 -290.136072) (xy 123.890469 -290.127973) (xy 123.841229 -290.111974)
			(xy 123.795097 -290.088468) (xy 123.75321 -290.058036) (xy 123.7166 -290.021426) (xy 123.686168 -289.979539)
			(xy 123.662662 -289.933407) (xy 123.646663 -289.884167) (xy 123.638564 -289.833029) (xy 123.638056 -289.807142)
			(xy 122.417332 -289.807142) (xy 122.416824 -289.833029) (xy 122.408725 -289.884167) (xy 122.392726 -289.933407)
			(xy 122.36922 -289.979539) (xy 122.338788 -290.021426) (xy 122.302178 -290.058036) (xy 122.260291 -290.088468)
			(xy 122.214159 -290.111974) (xy 122.164919 -290.127973) (xy 122.113781 -290.136072) (xy 122.062007 -290.136072)
			(xy 122.010869 -290.127973) (xy 121.961629 -290.111974) (xy 121.915497 -290.088468) (xy 121.87361 -290.058036)
			(xy 121.837 -290.021426) (xy 121.806568 -289.979539) (xy 121.783062 -289.933407) (xy 121.767063 -289.884167)
			(xy 121.758964 -289.833029) (xy 121.758456 -289.807142) (xy 120.537732 -289.807142) (xy 120.537224 -289.833029)
			(xy 120.529125 -289.884167) (xy 120.513126 -289.933407) (xy 120.48962 -289.979539) (xy 120.459188 -290.021426)
			(xy 120.422578 -290.058036) (xy 120.380691 -290.088468) (xy 120.334559 -290.111974) (xy 120.285319 -290.127973)
			(xy 120.234181 -290.136072) (xy 120.182407 -290.136072) (xy 120.131269 -290.127973) (xy 120.082029 -290.111974)
			(xy 120.035897 -290.088468) (xy 119.99401 -290.058036) (xy 119.9574 -290.021426) (xy 119.926968 -289.979539)
			(xy 119.903462 -289.933407) (xy 119.887463 -289.884167) (xy 119.879364 -289.833029) (xy 119.878856 -289.807142)
			(xy 103.621332 -289.807142) (xy 103.620824 -289.833029) (xy 103.612725 -289.884167) (xy 103.596726 -289.933407)
			(xy 103.57322 -289.979539) (xy 103.542788 -290.021426) (xy 103.506178 -290.058036) (xy 103.464291 -290.088468)
			(xy 103.418159 -290.111974) (xy 103.368919 -290.127973) (xy 103.317781 -290.136072) (xy 103.266007 -290.136072)
			(xy 103.214869 -290.127973) (xy 103.165629 -290.111974) (xy 103.119497 -290.088468) (xy 103.07761 -290.058036)
			(xy 103.041 -290.021426) (xy 103.010568 -289.979539) (xy 102.987062 -289.933407) (xy 102.971063 -289.884167)
			(xy 102.962964 -289.833029) (xy 102.962456 -289.807142) (xy 102.962456 -289.806634) (xy 102.962859 -289.783785)
			(xy 102.969212 -289.738531) (xy 102.981758 -289.694589) (xy 102.99065 -289.673538) (xy 103.000556 -289.650932)
			(xy 102.786688 -289.245802) (xy 102.762558 -289.24123) (xy 102.737619 -289.236158) (xy 102.689576 -289.219379)
			(xy 102.644683 -289.195414) (xy 102.604007 -289.164832) (xy 102.568517 -289.12836) (xy 102.539055 -289.086867)
			(xy 102.516322 -289.041337) (xy 102.500858 -288.992854) (xy 102.493031 -288.942571) (xy 102.492556 -288.917126)
			(xy 102.21214 -288.917126) (xy 102.211632 -288.943033) (xy 102.203526 -288.99421) (xy 102.187514 -289.043489)
			(xy 102.163991 -289.089656) (xy 102.133535 -289.131575) (xy 102.096897 -289.168213) (xy 102.054978 -289.198669)
			(xy 102.008811 -289.222192) (xy 101.959532 -289.238204) (xy 101.908355 -289.24631) (xy 101.856541 -289.24631)
			(xy 101.805364 -289.238204) (xy 101.756085 -289.222192) (xy 101.709918 -289.198669) (xy 101.667999 -289.168213)
			(xy 101.631361 -289.131575) (xy 101.600905 -289.089656) (xy 101.577382 -289.043489) (xy 101.56137 -288.99421)
			(xy 101.553264 -288.943033) (xy 101.552756 -288.917126) (xy 101.27234 -288.917126) (xy 101.271918 -288.940067)
			(xy 101.26549 -288.985498) (xy 101.252844 -289.029604) (xy 101.243892 -289.05073) (xy 101.233986 -289.073336)
			(xy 101.447854 -289.478466) (xy 101.471984 -289.483038) (xy 101.49691 -289.488115) (xy 101.544921 -289.50492)
			(xy 101.589779 -289.528904) (xy 101.630419 -289.559496) (xy 101.665876 -289.59597) (xy 101.695306 -289.637459)
			(xy 101.718012 -289.682977) (xy 101.733453 -289.731444) (xy 101.741263 -289.781708) (xy 101.741732 -289.807142)
			(xy 101.741224 -289.833029) (xy 101.733125 -289.884167) (xy 101.717126 -289.933407) (xy 101.69362 -289.979539)
			(xy 101.663188 -290.021426) (xy 101.626578 -290.058036) (xy 101.584691 -290.088468) (xy 101.538559 -290.111974)
			(xy 101.489319 -290.127973) (xy 101.438181 -290.136072) (xy 101.386407 -290.136072) (xy 101.335269 -290.127973)
			(xy 101.286029 -290.111974) (xy 101.239897 -290.088468) (xy 101.19801 -290.058036) (xy 101.1614 -290.021426)
			(xy 101.130968 -289.979539) (xy 101.107462 -289.933407) (xy 101.091463 -289.884167) (xy 101.083364 -289.833029)
			(xy 101.082856 -289.807142) (xy 101.082856 -289.806634) (xy 101.083259 -289.783785) (xy 101.089612 -289.738531)
			(xy 101.102158 -289.694589) (xy 101.11105 -289.673538) (xy 101.120956 -289.650932) (xy 100.907088 -289.245802)
			(xy 100.882958 -289.24123) (xy 100.858019 -289.236158) (xy 100.809976 -289.219379) (xy 100.765083 -289.195414)
			(xy 100.724407 -289.164832) (xy 100.688917 -289.12836) (xy 100.659455 -289.086867) (xy 100.636722 -289.041337)
			(xy 100.621258 -288.992854) (xy 100.613431 -288.942571) (xy 100.612956 -288.917126) (xy 100.33254 -288.917126)
			(xy 100.332032 -288.943033) (xy 100.323926 -288.99421) (xy 100.307914 -289.043489) (xy 100.284391 -289.089656)
			(xy 100.253935 -289.131575) (xy 100.217297 -289.168213) (xy 100.175378 -289.198669) (xy 100.129211 -289.222192)
			(xy 100.079932 -289.238204) (xy 100.028755 -289.24631) (xy 99.976941 -289.24631) (xy 99.925764 -289.238204)
			(xy 99.876485 -289.222192) (xy 99.830318 -289.198669) (xy 99.788399 -289.168213) (xy 99.751761 -289.131575)
			(xy 99.721305 -289.089656) (xy 99.697782 -289.043489) (xy 99.68177 -288.99421) (xy 99.673664 -288.943033)
			(xy 99.673156 -288.917126) (xy 99.39274 -288.917126) (xy 99.392318 -288.940067) (xy 99.38589 -288.985498)
			(xy 99.373244 -289.029604) (xy 99.364292 -289.05073) (xy 99.354386 -289.073336) (xy 99.568254 -289.478466)
			(xy 99.592384 -289.483038) (xy 99.61731 -289.488115) (xy 99.665321 -289.50492) (xy 99.710179 -289.528904)
			(xy 99.750819 -289.559496) (xy 99.786276 -289.59597) (xy 99.815706 -289.637459) (xy 99.838412 -289.682977)
			(xy 99.853853 -289.731444) (xy 99.861663 -289.781708) (xy 99.862132 -289.807142) (xy 99.861624 -289.833029)
			(xy 99.853525 -289.884167) (xy 99.837526 -289.933407) (xy 99.81402 -289.979539) (xy 99.783588 -290.021426)
			(xy 99.746978 -290.058036) (xy 99.705091 -290.088468) (xy 99.658959 -290.111974) (xy 99.609719 -290.127973)
			(xy 99.558581 -290.136072) (xy 99.506807 -290.136072) (xy 99.455669 -290.127973) (xy 99.406429 -290.111974)
			(xy 99.360297 -290.088468) (xy 99.31841 -290.058036) (xy 99.2818 -290.021426) (xy 99.251368 -289.979539)
			(xy 99.227862 -289.933407) (xy 99.211863 -289.884167) (xy 99.203764 -289.833029) (xy 99.203256 -289.807142)
			(xy 99.203256 -289.806634) (xy 99.203659 -289.783785) (xy 99.210012 -289.738531) (xy 99.222558 -289.694589)
			(xy 99.23145 -289.673538) (xy 99.241356 -289.650932) (xy 99.027488 -289.245802) (xy 99.003358 -289.24123)
			(xy 98.978419 -289.236158) (xy 98.930376 -289.219379) (xy 98.885483 -289.195414) (xy 98.844807 -289.164832)
			(xy 98.809317 -289.12836) (xy 98.779855 -289.086867) (xy 98.757122 -289.041337) (xy 98.741658 -288.992854)
			(xy 98.733831 -288.942571) (xy 98.733356 -288.917126) (xy 98.45294 -288.917126) (xy 98.452432 -288.943033)
			(xy 98.444326 -288.99421) (xy 98.428314 -289.043489) (xy 98.404791 -289.089656) (xy 98.374335 -289.131575)
			(xy 98.337697 -289.168213) (xy 98.295778 -289.198669) (xy 98.249611 -289.222192) (xy 98.200332 -289.238204)
			(xy 98.149155 -289.24631) (xy 98.097341 -289.24631) (xy 98.046164 -289.238204) (xy 97.996885 -289.222192)
			(xy 97.950718 -289.198669) (xy 97.908799 -289.168213) (xy 97.872161 -289.131575) (xy 97.841705 -289.089656)
			(xy 97.818182 -289.043489) (xy 97.80217 -288.99421) (xy 97.794064 -288.943033) (xy 97.793556 -288.917126)
			(xy 97.51314 -288.917126) (xy 97.512718 -288.940067) (xy 97.50629 -288.985498) (xy 97.493644 -289.029604)
			(xy 97.484692 -289.05073) (xy 97.474786 -289.073336) (xy 97.688654 -289.478466) (xy 97.712784 -289.483038)
			(xy 97.73771 -289.488115) (xy 97.785721 -289.50492) (xy 97.830579 -289.528904) (xy 97.871219 -289.559496)
			(xy 97.906676 -289.59597) (xy 97.936106 -289.637459) (xy 97.958812 -289.682977) (xy 97.974253 -289.731444)
			(xy 97.982063 -289.781708) (xy 97.982532 -289.807142) (xy 97.982024 -289.833029) (xy 97.973925 -289.884167)
			(xy 97.957926 -289.933407) (xy 97.93442 -289.979539) (xy 97.903988 -290.021426) (xy 97.867378 -290.058036)
			(xy 97.825491 -290.088468) (xy 97.779359 -290.111974) (xy 97.730119 -290.127973) (xy 97.678981 -290.136072)
			(xy 97.627207 -290.136072) (xy 97.576069 -290.127973) (xy 97.526829 -290.111974) (xy 97.480697 -290.088468)
			(xy 97.43881 -290.058036) (xy 97.4022 -290.021426) (xy 97.371768 -289.979539) (xy 97.348262 -289.933407)
			(xy 97.332263 -289.884167) (xy 97.324164 -289.833029) (xy 97.323656 -289.807142) (xy 97.323656 -289.806634)
			(xy 97.324059 -289.783785) (xy 97.330412 -289.738531) (xy 97.342958 -289.694589) (xy 97.35185 -289.673538)
			(xy 97.361756 -289.650932) (xy 97.147888 -289.245802) (xy 97.123758 -289.24123) (xy 97.098819 -289.236158)
			(xy 97.050776 -289.219379) (xy 97.005883 -289.195414) (xy 96.965207 -289.164832) (xy 96.929717 -289.12836)
			(xy 96.900255 -289.086867) (xy 96.877522 -289.041337) (xy 96.862058 -288.992854) (xy 96.854231 -288.942571)
			(xy 96.853756 -288.917126) (xy 96.57334 -288.917126) (xy 96.572832 -288.943033) (xy 96.564726 -288.99421)
			(xy 96.548714 -289.043489) (xy 96.525191 -289.089656) (xy 96.494735 -289.131575) (xy 96.458097 -289.168213)
			(xy 96.416178 -289.198669) (xy 96.370011 -289.222192) (xy 96.320732 -289.238204) (xy 96.269555 -289.24631)
			(xy 96.217741 -289.24631) (xy 96.166564 -289.238204) (xy 96.117285 -289.222192) (xy 96.071118 -289.198669)
			(xy 96.029199 -289.168213) (xy 95.992561 -289.131575) (xy 95.962105 -289.089656) (xy 95.938582 -289.043489)
			(xy 95.92257 -288.99421) (xy 95.914464 -288.943033) (xy 95.913956 -288.917126) (xy 95.63354 -288.917126)
			(xy 95.633118 -288.940067) (xy 95.62669 -288.985498) (xy 95.614044 -289.029604) (xy 95.605092 -289.05073)
			(xy 95.595186 -289.073336) (xy 95.809054 -289.478466) (xy 95.833184 -289.483038) (xy 95.85811 -289.488115)
			(xy 95.906121 -289.50492) (xy 95.950979 -289.528904) (xy 95.991619 -289.559496) (xy 96.027076 -289.59597)
			(xy 96.056506 -289.637459) (xy 96.079212 -289.682977) (xy 96.094653 -289.731444) (xy 96.102463 -289.781708)
			(xy 96.102932 -289.807142) (xy 96.102424 -289.833029) (xy 96.094325 -289.884167) (xy 96.078326 -289.933407)
			(xy 96.05482 -289.979539) (xy 96.024388 -290.021426) (xy 95.987778 -290.058036) (xy 95.945891 -290.088468)
			(xy 95.899759 -290.111974) (xy 95.850519 -290.127973) (xy 95.799381 -290.136072) (xy 95.747607 -290.136072)
			(xy 95.696469 -290.127973) (xy 95.647229 -290.111974) (xy 95.601097 -290.088468) (xy 95.55921 -290.058036)
			(xy 95.5226 -290.021426) (xy 95.492168 -289.979539) (xy 95.468662 -289.933407) (xy 95.452663 -289.884167)
			(xy 95.444564 -289.833029) (xy 95.444056 -289.807142) (xy 95.444056 -289.806634) (xy 95.444459 -289.783785)
			(xy 95.450812 -289.738531) (xy 95.463358 -289.694589) (xy 95.47225 -289.673538) (xy 95.482156 -289.650932)
			(xy 95.268288 -289.245802) (xy 95.244158 -289.24123) (xy 95.219219 -289.236158) (xy 95.171176 -289.219379)
			(xy 95.126283 -289.195414) (xy 95.085607 -289.164832) (xy 95.050117 -289.12836) (xy 95.020655 -289.086867)
			(xy 94.997922 -289.041337) (xy 94.982458 -288.992854) (xy 94.974631 -288.942571) (xy 94.974156 -288.917126)
			(xy 94.69374 -288.917126) (xy 94.693232 -288.943033) (xy 94.685126 -288.99421) (xy 94.669114 -289.043489)
			(xy 94.645591 -289.089656) (xy 94.615135 -289.131575) (xy 94.578497 -289.168213) (xy 94.536578 -289.198669)
			(xy 94.490411 -289.222192) (xy 94.441132 -289.238204) (xy 94.389955 -289.24631) (xy 94.338141 -289.24631)
			(xy 94.286964 -289.238204) (xy 94.237685 -289.222192) (xy 94.191518 -289.198669) (xy 94.149599 -289.168213)
			(xy 94.112961 -289.131575) (xy 94.082505 -289.089656) (xy 94.058982 -289.043489) (xy 94.04297 -288.99421)
			(xy 94.034864 -288.943033) (xy 94.034356 -288.917126) (xy 93.75394 -288.917126) (xy 93.753518 -288.940067)
			(xy 93.74709 -288.985498) (xy 93.734444 -289.029604) (xy 93.725492 -289.05073) (xy 93.715586 -289.073336)
			(xy 93.929454 -289.478466) (xy 93.953584 -289.483038) (xy 93.97851 -289.488115) (xy 94.026521 -289.50492)
			(xy 94.071379 -289.528904) (xy 94.112019 -289.559496) (xy 94.147476 -289.59597) (xy 94.176906 -289.637459)
			(xy 94.199612 -289.682977) (xy 94.215053 -289.731444) (xy 94.222863 -289.781708) (xy 94.223332 -289.807142)
			(xy 94.222824 -289.833029) (xy 94.214725 -289.884167) (xy 94.198726 -289.933407) (xy 94.17522 -289.979539)
			(xy 94.144788 -290.021426) (xy 94.108178 -290.058036) (xy 94.066291 -290.088468) (xy 94.020159 -290.111974)
			(xy 93.970919 -290.127973) (xy 93.919781 -290.136072) (xy 93.868007 -290.136072) (xy 93.816869 -290.127973)
			(xy 93.767629 -290.111974) (xy 93.721497 -290.088468) (xy 93.67961 -290.058036) (xy 93.643 -290.021426)
			(xy 93.612568 -289.979539) (xy 93.589062 -289.933407) (xy 93.573063 -289.884167) (xy 93.564964 -289.833029)
			(xy 93.564456 -289.807142) (xy 93.564456 -289.806634) (xy 93.564859 -289.783785) (xy 93.571212 -289.738531)
			(xy 93.583758 -289.694589) (xy 93.59265 -289.673538) (xy 93.602556 -289.650932) (xy 93.388688 -289.245802)
			(xy 93.364558 -289.24123) (xy 93.339619 -289.236158) (xy 93.291576 -289.219379) (xy 93.246683 -289.195414)
			(xy 93.206007 -289.164832) (xy 93.170517 -289.12836) (xy 93.141055 -289.086867) (xy 93.118322 -289.041337)
			(xy 93.102858 -288.992854) (xy 93.095031 -288.942571) (xy 93.094556 -288.917126) (xy 92.81414 -288.917126)
			(xy 92.813632 -288.943033) (xy 92.805526 -288.99421) (xy 92.789514 -289.043489) (xy 92.765991 -289.089656)
			(xy 92.735535 -289.131575) (xy 92.698897 -289.168213) (xy 92.656978 -289.198669) (xy 92.610811 -289.222192)
			(xy 92.561532 -289.238204) (xy 92.510355 -289.24631) (xy 92.458541 -289.24631) (xy 92.407364 -289.238204)
			(xy 92.358085 -289.222192) (xy 92.311918 -289.198669) (xy 92.269999 -289.168213) (xy 92.233361 -289.131575)
			(xy 92.202905 -289.089656) (xy 92.179382 -289.043489) (xy 92.16337 -288.99421) (xy 92.155264 -288.943033)
			(xy 92.154756 -288.917126) (xy 91.87434 -288.917126) (xy 91.873918 -288.940067) (xy 91.86749 -288.985498)
			(xy 91.854844 -289.029604) (xy 91.845892 -289.05073) (xy 91.835986 -289.073336) (xy 92.049854 -289.478466)
			(xy 92.073984 -289.483038) (xy 92.09891 -289.488115) (xy 92.146921 -289.50492) (xy 92.191779 -289.528904)
			(xy 92.232419 -289.559496) (xy 92.267876 -289.59597) (xy 92.297306 -289.637459) (xy 92.320012 -289.682977)
			(xy 92.335453 -289.731444) (xy 92.343263 -289.781708) (xy 92.343732 -289.807142) (xy 92.343224 -289.833029)
			(xy 92.335125 -289.884167) (xy 92.319126 -289.933407) (xy 92.29562 -289.979539) (xy 92.265188 -290.021426)
			(xy 92.228578 -290.058036) (xy 92.186691 -290.088468) (xy 92.140559 -290.111974) (xy 92.091319 -290.127973)
			(xy 92.040181 -290.136072) (xy 91.988407 -290.136072) (xy 91.937269 -290.127973) (xy 91.888029 -290.111974)
			(xy 91.841897 -290.088468) (xy 91.80001 -290.058036) (xy 91.7634 -290.021426) (xy 91.732968 -289.979539)
			(xy 91.709462 -289.933407) (xy 91.693463 -289.884167) (xy 91.685364 -289.833029) (xy 91.684856 -289.807142)
			(xy 91.684856 -289.806634) (xy 91.685259 -289.783785) (xy 91.691612 -289.738531) (xy 91.704158 -289.694589)
			(xy 91.71305 -289.673538) (xy 91.722956 -289.650932) (xy 91.509088 -289.245802) (xy 91.484958 -289.24123)
			(xy 91.460019 -289.236158) (xy 91.411976 -289.219379) (xy 91.367083 -289.195414) (xy 91.326407 -289.164832)
			(xy 91.290917 -289.12836) (xy 91.261455 -289.086867) (xy 91.238722 -289.041337) (xy 91.223258 -288.992854)
			(xy 91.215431 -288.942571) (xy 91.214956 -288.917126) (xy 90.93454 -288.917126) (xy 90.934032 -288.943033)
			(xy 90.925926 -288.99421) (xy 90.909914 -289.043489) (xy 90.886391 -289.089656) (xy 90.855935 -289.131575)
			(xy 90.819297 -289.168213) (xy 90.777378 -289.198669) (xy 90.731211 -289.222192) (xy 90.681932 -289.238204)
			(xy 90.630755 -289.24631) (xy 90.578941 -289.24631) (xy 90.527764 -289.238204) (xy 90.478485 -289.222192)
			(xy 90.432318 -289.198669) (xy 90.390399 -289.168213) (xy 90.353761 -289.131575) (xy 90.323305 -289.089656)
			(xy 90.299782 -289.043489) (xy 90.28377 -288.99421) (xy 90.275664 -288.943033) (xy 90.275156 -288.917126)
			(xy 89.05494 -288.917126) (xy 89.054432 -288.943033) (xy 89.046326 -288.99421) (xy 89.030314 -289.043489)
			(xy 89.006791 -289.089656) (xy 88.976335 -289.131575) (xy 88.939697 -289.168213) (xy 88.897778 -289.198669)
			(xy 88.851611 -289.222192) (xy 88.802332 -289.238204) (xy 88.751155 -289.24631) (xy 88.699341 -289.24631)
			(xy 88.648164 -289.238204) (xy 88.598885 -289.222192) (xy 88.552718 -289.198669) (xy 88.510799 -289.168213)
			(xy 88.474161 -289.131575) (xy 88.443705 -289.089656) (xy 88.420182 -289.043489) (xy 88.40417 -288.99421)
			(xy 88.396064 -288.943033) (xy 88.395556 -288.917126) (xy 2.509012 -288.917126) (xy 2.509012 -297.515026)
			(xy 88.21548 -297.515026) (xy 88.219461 -297.382006) (xy 88.23139 -297.249461) (xy 88.251225 -297.117868)
			(xy 88.278894 -296.987696) (xy 88.314298 -296.859411) (xy 88.357311 -296.733474) (xy 88.407778 -296.610335)
			(xy 88.465519 -296.490434) (xy 88.530328 -296.374201) (xy 88.601972 -296.262051) (xy 88.680194 -296.154387)
			(xy 88.764715 -296.051594) (xy 88.855233 -295.954039) (xy 88.951422 -295.862073) (xy 89.05294 -295.776023)
			(xy 89.159421 -295.696199) (xy 89.270486 -295.622886) (xy 89.385737 -295.556346) (xy 89.504761 -295.496817)
			(xy 89.627132 -295.444513) (xy 89.752411 -295.399621) (xy 89.880152 -295.362302) (xy 90.009895 -295.332689)
			(xy 90.141177 -295.310888) (xy 90.273528 -295.296978) (xy 90.406474 -295.291007) (xy 90.539539 -295.292998)
			(xy 90.672247 -295.302943) (xy 90.804123 -295.320807) (xy 90.934694 -295.346525) (xy 91.063494 -295.380006)
			(xy 91.19006 -295.42113) (xy 91.313941 -295.46975) (xy 91.434692 -295.525691) (xy 91.551882 -295.588753)
			(xy 91.665091 -295.658711) (xy 91.773913 -295.735315) (xy 91.877959 -295.818289) (xy 91.976857 -295.907337)
			(xy 92.070252 -296.00214) (xy 92.15781 -296.102358) (xy 92.239219 -296.207634) (xy 92.314185 -296.31759)
			(xy 92.382442 -296.431832) (xy 92.443744 -296.549952) (xy 92.497873 -296.671527) (xy 92.544634 -296.796121)
			(xy 92.58386 -296.923289) (xy 92.61541 -297.052575) (xy 92.639173 -297.183516) (xy 92.655062 -297.315644)
			(xy 92.66302 -297.448486) (xy 92.663518 -297.515026) (xy 131.195582 -297.515026) (xy 131.199563 -297.382006)
			(xy 131.211492 -297.249461) (xy 131.231327 -297.117868) (xy 131.258996 -296.987696) (xy 131.2944 -296.859411)
			(xy 131.337413 -296.733474) (xy 131.38788 -296.610335) (xy 131.445621 -296.490434) (xy 131.51043 -296.374201)
			(xy 131.582074 -296.262051) (xy 131.660296 -296.154387) (xy 131.744817 -296.051594) (xy 131.835335 -295.954039)
			(xy 131.931524 -295.862073) (xy 132.033042 -295.776023) (xy 132.139523 -295.696199) (xy 132.250588 -295.622886)
			(xy 132.365839 -295.556346) (xy 132.484863 -295.496817) (xy 132.607234 -295.444513) (xy 132.732513 -295.399621)
			(xy 132.860254 -295.362302) (xy 132.989997 -295.332689) (xy 133.121279 -295.310888) (xy 133.25363 -295.296978)
			(xy 133.386576 -295.291007) (xy 133.519641 -295.292998) (xy 133.652349 -295.302943) (xy 133.784225 -295.320807)
			(xy 133.914796 -295.346525) (xy 134.043596 -295.380006) (xy 134.170162 -295.42113) (xy 134.294043 -295.46975)
			(xy 134.414794 -295.525691) (xy 134.531984 -295.588753) (xy 134.645193 -295.658711) (xy 134.754015 -295.735315)
			(xy 134.858061 -295.818289) (xy 134.956959 -295.907337) (xy 135.050354 -296.00214) (xy 135.137912 -296.102358)
			(xy 135.219321 -296.207634) (xy 135.294287 -296.31759) (xy 135.362544 -296.431832) (xy 135.423846 -296.549952)
			(xy 135.477975 -296.671527) (xy 135.524736 -296.796121) (xy 135.563962 -296.923289) (xy 135.595512 -297.052575)
			(xy 135.619275 -297.183516) (xy 135.635164 -297.315644) (xy 135.643122 -297.448486) (xy 135.64362 -297.515026)
			(xy 336.155548 -297.515026) (xy 336.159529 -297.382006) (xy 336.171458 -297.249461) (xy 336.191293 -297.117868)
			(xy 336.218962 -296.987696) (xy 336.254366 -296.859411) (xy 336.297379 -296.733474) (xy 336.347846 -296.610335)
			(xy 336.405587 -296.490434) (xy 336.470396 -296.374201) (xy 336.54204 -296.262051) (xy 336.620262 -296.154387)
			(xy 336.704783 -296.051594) (xy 336.795301 -295.954039) (xy 336.89149 -295.862073) (xy 336.993008 -295.776023)
			(xy 337.099489 -295.696199) (xy 337.210554 -295.622886) (xy 337.325805 -295.556346) (xy 337.444829 -295.496817)
			(xy 337.5672 -295.444513) (xy 337.692479 -295.399621) (xy 337.82022 -295.362302) (xy 337.949963 -295.332689)
			(xy 338.081245 -295.310888) (xy 338.213596 -295.296978) (xy 338.346542 -295.291007) (xy 338.479607 -295.292998)
			(xy 338.612315 -295.302943) (xy 338.744191 -295.320807) (xy 338.874762 -295.346525) (xy 339.003562 -295.380006)
			(xy 339.130128 -295.42113) (xy 339.254009 -295.46975) (xy 339.37476 -295.525691) (xy 339.49195 -295.588753)
			(xy 339.605159 -295.658711) (xy 339.713981 -295.735315) (xy 339.818027 -295.818289) (xy 339.916925 -295.907337)
			(xy 340.01032 -296.00214) (xy 340.097878 -296.102358) (xy 340.179287 -296.207634) (xy 340.254253 -296.31759)
			(xy 340.32251 -296.431832) (xy 340.383812 -296.549952) (xy 340.437941 -296.671527) (xy 340.484702 -296.796121)
			(xy 340.523928 -296.923289) (xy 340.555478 -297.052575) (xy 340.579241 -297.183516) (xy 340.59513 -297.315644)
			(xy 340.603088 -297.448486) (xy 340.603586 -297.515026) (xy 379.13565 -297.515026) (xy 379.139631 -297.382006)
			(xy 379.15156 -297.249461) (xy 379.171395 -297.117868) (xy 379.199064 -296.987696) (xy 379.234468 -296.859411)
			(xy 379.277481 -296.733474) (xy 379.327948 -296.610335) (xy 379.385689 -296.490434) (xy 379.450498 -296.374201)
			(xy 379.522142 -296.262051) (xy 379.600364 -296.154387) (xy 379.684885 -296.051594) (xy 379.775403 -295.954039)
			(xy 379.871592 -295.862073) (xy 379.97311 -295.776023) (xy 380.079591 -295.696199) (xy 380.190656 -295.622886)
			(xy 380.305907 -295.556346) (xy 380.424931 -295.496817) (xy 380.547302 -295.444513) (xy 380.672581 -295.399621)
			(xy 380.800322 -295.362302) (xy 380.930065 -295.332689) (xy 381.061347 -295.310888) (xy 381.193698 -295.296978)
			(xy 381.326644 -295.291007) (xy 381.459709 -295.292998) (xy 381.592417 -295.302943) (xy 381.724293 -295.320807)
			(xy 381.854864 -295.346525) (xy 381.983664 -295.380006) (xy 382.11023 -295.42113) (xy 382.234111 -295.46975)
			(xy 382.354862 -295.525691) (xy 382.472052 -295.588753) (xy 382.585261 -295.658711) (xy 382.694083 -295.735315)
			(xy 382.798129 -295.818289) (xy 382.897027 -295.907337) (xy 382.990422 -296.00214) (xy 383.07798 -296.102358)
			(xy 383.159389 -296.207634) (xy 383.234355 -296.31759) (xy 383.302612 -296.431832) (xy 383.363914 -296.549952)
			(xy 383.418043 -296.671527) (xy 383.464804 -296.796121) (xy 383.50403 -296.923289) (xy 383.53558 -297.052575)
			(xy 383.559343 -297.183516) (xy 383.575232 -297.315644) (xy 383.58319 -297.448486) (xy 383.583688 -297.515026)
			(xy 383.58319 -297.581566) (xy 383.575232 -297.714408) (xy 383.559343 -297.846536) (xy 383.53558 -297.977477)
			(xy 383.50403 -298.106763) (xy 383.464804 -298.233931) (xy 383.418043 -298.358525) (xy 383.363914 -298.4801)
			(xy 383.302612 -298.59822) (xy 383.234355 -298.712462) (xy 383.159389 -298.822418) (xy 383.07798 -298.927694)
			(xy 382.990422 -299.027912) (xy 382.897027 -299.122715) (xy 382.798129 -299.211763) (xy 382.694083 -299.294737)
			(xy 382.585261 -299.371341) (xy 382.472052 -299.441299) (xy 382.354862 -299.504361) (xy 382.234111 -299.560302)
			(xy 382.11023 -299.608922) (xy 381.983664 -299.650046) (xy 381.854864 -299.683527) (xy 381.724293 -299.709245)
			(xy 381.592417 -299.727109) (xy 381.459709 -299.737054) (xy 381.326644 -299.739045) (xy 381.193698 -299.733074)
			(xy 381.061347 -299.719164) (xy 380.930065 -299.697363) (xy 380.800322 -299.66775) (xy 380.672581 -299.630431)
			(xy 380.547302 -299.585539) (xy 380.424931 -299.533235) (xy 380.305907 -299.473706) (xy 380.190656 -299.407166)
			(xy 380.079591 -299.333853) (xy 379.97311 -299.254029) (xy 379.871592 -299.167979) (xy 379.775403 -299.076013)
			(xy 379.684885 -298.978458) (xy 379.600364 -298.875665) (xy 379.522142 -298.768001) (xy 379.450498 -298.655851)
			(xy 379.385689 -298.539618) (xy 379.327948 -298.419717) (xy 379.277481 -298.296578) (xy 379.234468 -298.170641)
			(xy 379.199064 -298.042356) (xy 379.171395 -297.912184) (xy 379.15156 -297.780591) (xy 379.139631 -297.648046)
			(xy 379.13565 -297.515026) (xy 340.603586 -297.515026) (xy 340.603088 -297.581566) (xy 340.59513 -297.714408)
			(xy 340.579241 -297.846536) (xy 340.555478 -297.977477) (xy 340.523928 -298.106763) (xy 340.484702 -298.233931)
			(xy 340.437941 -298.358525) (xy 340.383812 -298.4801) (xy 340.32251 -298.59822) (xy 340.254253 -298.712462)
			(xy 340.179287 -298.822418) (xy 340.097878 -298.927694) (xy 340.01032 -299.027912) (xy 339.916925 -299.122715)
			(xy 339.818027 -299.211763) (xy 339.713981 -299.294737) (xy 339.605159 -299.371341) (xy 339.49195 -299.441299)
			(xy 339.37476 -299.504361) (xy 339.254009 -299.560302) (xy 339.130128 -299.608922) (xy 339.003562 -299.650046)
			(xy 338.874762 -299.683527) (xy 338.744191 -299.709245) (xy 338.612315 -299.727109) (xy 338.479607 -299.737054)
			(xy 338.346542 -299.739045) (xy 338.213596 -299.733074) (xy 338.081245 -299.719164) (xy 337.949963 -299.697363)
			(xy 337.82022 -299.66775) (xy 337.692479 -299.630431) (xy 337.5672 -299.585539) (xy 337.444829 -299.533235)
			(xy 337.325805 -299.473706) (xy 337.210554 -299.407166) (xy 337.099489 -299.333853) (xy 336.993008 -299.254029)
			(xy 336.89149 -299.167979) (xy 336.795301 -299.076013) (xy 336.704783 -298.978458) (xy 336.620262 -298.875665)
			(xy 336.54204 -298.768001) (xy 336.470396 -298.655851) (xy 336.405587 -298.539618) (xy 336.347846 -298.419717)
			(xy 336.297379 -298.296578) (xy 336.254366 -298.170641) (xy 336.218962 -298.042356) (xy 336.191293 -297.912184)
			(xy 336.171458 -297.780591) (xy 336.159529 -297.648046) (xy 336.155548 -297.515026) (xy 135.64362 -297.515026)
			(xy 135.643122 -297.581566) (xy 135.635164 -297.714408) (xy 135.619275 -297.846536) (xy 135.595512 -297.977477)
			(xy 135.563962 -298.106763) (xy 135.524736 -298.233931) (xy 135.477975 -298.358525) (xy 135.423846 -298.4801)
			(xy 135.362544 -298.59822) (xy 135.294287 -298.712462) (xy 135.219321 -298.822418) (xy 135.137912 -298.927694)
			(xy 135.050354 -299.027912) (xy 134.956959 -299.122715) (xy 134.858061 -299.211763) (xy 134.754015 -299.294737)
			(xy 134.645193 -299.371341) (xy 134.531984 -299.441299) (xy 134.414794 -299.504361) (xy 134.294043 -299.560302)
			(xy 134.170162 -299.608922) (xy 134.043596 -299.650046) (xy 133.914796 -299.683527) (xy 133.784225 -299.709245)
			(xy 133.652349 -299.727109) (xy 133.519641 -299.737054) (xy 133.386576 -299.739045) (xy 133.25363 -299.733074)
			(xy 133.121279 -299.719164) (xy 132.989997 -299.697363) (xy 132.860254 -299.66775) (xy 132.732513 -299.630431)
			(xy 132.607234 -299.585539) (xy 132.484863 -299.533235) (xy 132.365839 -299.473706) (xy 132.250588 -299.407166)
			(xy 132.139523 -299.333853) (xy 132.033042 -299.254029) (xy 131.931524 -299.167979) (xy 131.835335 -299.076013)
			(xy 131.744817 -298.978458) (xy 131.660296 -298.875665) (xy 131.582074 -298.768001) (xy 131.51043 -298.655851)
			(xy 131.445621 -298.539618) (xy 131.38788 -298.419717) (xy 131.337413 -298.296578) (xy 131.2944 -298.170641)
			(xy 131.258996 -298.042356) (xy 131.231327 -297.912184) (xy 131.211492 -297.780591) (xy 131.199563 -297.648046)
			(xy 131.195582 -297.515026) (xy 92.663518 -297.515026) (xy 92.66302 -297.581566) (xy 92.655062 -297.714408)
			(xy 92.639173 -297.846536) (xy 92.61541 -297.977477) (xy 92.58386 -298.106763) (xy 92.544634 -298.233931)
			(xy 92.497873 -298.358525) (xy 92.443744 -298.4801) (xy 92.382442 -298.59822) (xy 92.314185 -298.712462)
			(xy 92.239219 -298.822418) (xy 92.15781 -298.927694) (xy 92.070252 -299.027912) (xy 91.976857 -299.122715)
			(xy 91.877959 -299.211763) (xy 91.773913 -299.294737) (xy 91.665091 -299.371341) (xy 91.551882 -299.441299)
			(xy 91.434692 -299.504361) (xy 91.313941 -299.560302) (xy 91.19006 -299.608922) (xy 91.063494 -299.650046)
			(xy 90.934694 -299.683527) (xy 90.804123 -299.709245) (xy 90.672247 -299.727109) (xy 90.539539 -299.737054)
			(xy 90.406474 -299.739045) (xy 90.273528 -299.733074) (xy 90.141177 -299.719164) (xy 90.009895 -299.697363)
			(xy 89.880152 -299.66775) (xy 89.752411 -299.630431) (xy 89.627132 -299.585539) (xy 89.504761 -299.533235)
			(xy 89.385737 -299.473706) (xy 89.270486 -299.407166) (xy 89.159421 -299.333853) (xy 89.05294 -299.254029)
			(xy 88.951422 -299.167979) (xy 88.855233 -299.076013) (xy 88.764715 -298.978458) (xy 88.680194 -298.875665)
			(xy 88.601972 -298.768001) (xy 88.530328 -298.655851) (xy 88.465519 -298.539618) (xy 88.407778 -298.419717)
			(xy 88.357311 -298.296578) (xy 88.314298 -298.170641) (xy 88.278894 -298.042356) (xy 88.251225 -297.912184)
			(xy 88.23139 -297.780591) (xy 88.219461 -297.648046) (xy 88.21548 -297.515026) (xy 2.509012 -297.515026)
			(xy 2.509012 -360.76382) (xy 4.226823 -360.76382) (xy 4.230819 -360.553934) (xy 4.242804 -360.344352)
			(xy 4.262758 -360.135378) (xy 4.290654 -359.927316) (xy 4.326451 -359.720466) (xy 4.370096 -359.515129)
			(xy 4.421528 -359.311603) (xy 4.48067 -359.110182) (xy 4.547438 -358.911159) (xy 4.621734 -358.714822)
			(xy 4.703452 -358.521456) (xy 4.792471 -358.331341) (xy 4.888664 -358.144753) (xy 4.991891 -357.961962)
			(xy 5.102002 -357.783234) (xy 5.218837 -357.608827) (xy 5.342227 -357.438995) (xy 5.471994 -357.273983)
			(xy 5.607948 -357.114032) (xy 5.749894 -356.959372) (xy 5.897624 -356.810228) (xy 6.050926 -356.666817)
			(xy 6.209576 -356.529346) (xy 6.373345 -356.398014) (xy 6.541995 -356.273013) (xy 6.715281 -356.154522)
			(xy 6.892953 -356.042715) (xy 7.074753 -355.937753) (xy 7.260417 -355.839788) (xy 7.449675 -355.748963)
			(xy 7.642255 -355.665409) (xy 7.837876 -355.589246) (xy 8.036254 -355.520587) (xy 8.237103 -355.45953)
			(xy 8.44013 -355.406163) (xy 8.645043 -355.360565) (xy 8.851542 -355.3228) (xy 9.059329 -355.292925)
			(xy 9.268104 -355.270982) (xy 9.477562 -355.257003) (xy 9.687401 -355.251008) (xy 9.897315 -355.253007)
			(xy 10.107002 -355.262995) (xy 10.316156 -355.28096) (xy 10.524474 -355.306874) (xy 10.731655 -355.340699)
			(xy 10.937399 -355.382388) (xy 11.141405 -355.43188) (xy 11.34338 -355.489102) (xy 11.54303 -355.553972)
			(xy 11.740065 -355.626396) (xy 11.934201 -355.706269) (xy 12.125154 -355.793475) (xy 12.31265 -355.887887)
			(xy 12.496415 -355.989369) (xy 12.676183 -356.097773) (xy 12.851694 -356.212943) (xy 13.022693 -356.334711)
			(xy 13.188933 -356.4629) (xy 13.350172 -356.597326) (xy 13.506176 -356.737793) (xy 13.656719 -356.884097)
			(xy 13.801583 -357.036026) (xy 13.940558 -357.19336) (xy 14.073443 -357.355871) (xy 14.200044 -357.523324)
			(xy 14.320179 -357.695474) (xy 14.433673 -357.872074) (xy 14.540361 -358.052866) (xy 14.640088 -358.237589)
			(xy 14.732711 -358.425975) (xy 14.818095 -358.61775) (xy 14.896116 -358.812637) (xy 14.966661 -359.010353)
			(xy 15.029628 -359.210611) (xy 15.084925 -359.413121) (xy 15.132472 -359.61759) (xy 15.1722 -359.823721)
			(xy 15.204052 -360.031214) (xy 15.227982 -360.23977) (xy 15.243954 -360.449086) (xy 15.251946 -360.658858)
			(xy 15.252446 -360.76382) (xy 15.251946 -360.868782) (xy 15.243954 -361.078554) (xy 15.239789 -361.133136)
			(xy 121.446286 -361.133136) (xy 121.450375 -361.077254) (xy 121.462558 -361.022564) (xy 121.482574 -360.97023)
			(xy 121.509997 -360.921368) (xy 121.544242 -360.87702) (xy 121.584578 -360.83813) (xy 121.630148 -360.805528)
			(xy 121.679979 -360.779909) (xy 121.733009 -360.761817) (xy 121.788107 -360.75164) (xy 121.844101 -360.749594)
			(xy 121.899796 -360.755722) (xy 121.930771 -360.76382) (xy 211.161635 -360.76382) (xy 211.16566 -360.621628)
			(xy 211.177723 -360.479892) (xy 211.197786 -360.339066) (xy 211.225784 -360.1996) (xy 211.261628 -360.061941)
			(xy 211.305202 -359.926531) (xy 211.356367 -359.793803) (xy 211.41496 -359.664182) (xy 211.480791 -359.538084)
			(xy 211.553652 -359.415912) (xy 211.633307 -359.298058) (xy 211.719503 -359.184899) (xy 211.811962 -359.076797)
			(xy 211.91039 -358.9741) (xy 212.014469 -358.877136) (xy 212.123868 -358.786216) (xy 212.238236 -358.70163)
			(xy 212.357205 -358.62365) (xy 212.480396 -358.552526) (xy 212.607413 -358.488485) (xy 212.73785 -358.431733)
			(xy 212.871289 -358.382451) (xy 213.007302 -358.340797) (xy 213.145454 -358.306905) (xy 213.285303 -358.280884)
			(xy 213.426399 -358.262816) (xy 213.568291 -358.252759) (xy 213.710526 -358.250746) (xy 213.852646 -358.256783)
			(xy 213.994197 -358.270851) (xy 214.134726 -358.292905) (xy 214.273781 -358.322874) (xy 214.410919 -358.360662)
			(xy 214.545699 -358.406148) (xy 214.67769 -358.459186) (xy 214.806469 -358.519607) (xy 214.931623 -358.587216)
			(xy 215.052751 -358.661798) (xy 215.169467 -358.743114) (xy 215.281395 -358.830902) (xy 215.388177 -358.924882)
			(xy 215.489471 -359.024752) (xy 215.584952 -359.130194) (xy 215.674316 -359.240868) (xy 215.757274 -359.356421)
			(xy 215.833563 -359.476482) (xy 215.902937 -359.600667) (xy 215.965174 -359.728578) (xy 216.020075 -359.859805)
			(xy 216.067463 -359.993928) (xy 216.107188 -360.130517) (xy 216.139121 -360.269135) (xy 216.163162 -360.409337)
			(xy 216.179231 -360.550675) (xy 216.187279 -360.692696) (xy 216.187782 -360.76382) (xy 255.611635 -360.76382)
			(xy 255.61566 -360.621628) (xy 255.627723 -360.479892) (xy 255.647786 -360.339066) (xy 255.675784 -360.1996)
			(xy 255.711628 -360.061941) (xy 255.755202 -359.926531) (xy 255.806367 -359.793803) (xy 255.86496 -359.664182)
			(xy 255.930791 -359.538084) (xy 256.003652 -359.415912) (xy 256.083307 -359.298058) (xy 256.169503 -359.184899)
			(xy 256.261962 -359.076797) (xy 256.36039 -358.9741) (xy 256.464469 -358.877136) (xy 256.573868 -358.786216)
			(xy 256.688236 -358.70163) (xy 256.807205 -358.62365) (xy 256.930396 -358.552526) (xy 257.057413 -358.488485)
			(xy 257.18785 -358.431733) (xy 257.321289 -358.382451) (xy 257.457302 -358.340797) (xy 257.595454 -358.306905)
			(xy 257.735303 -358.280884) (xy 257.876399 -358.262816) (xy 258.018291 -358.252759) (xy 258.160526 -358.250746)
			(xy 258.302646 -358.256783) (xy 258.444197 -358.270851) (xy 258.584726 -358.292905) (xy 258.723781 -358.322874)
			(xy 258.860919 -358.360662) (xy 258.995699 -358.406148) (xy 259.12769 -358.459186) (xy 259.256469 -358.519607)
			(xy 259.381623 -358.587216) (xy 259.502751 -358.661798) (xy 259.619467 -358.743114) (xy 259.731395 -358.830902)
			(xy 259.838177 -358.924882) (xy 259.939471 -359.024752) (xy 260.034952 -359.130194) (xy 260.124316 -359.240868)
			(xy 260.207274 -359.356421) (xy 260.283563 -359.476482) (xy 260.352937 -359.600667) (xy 260.415174 -359.728578)
			(xy 260.470075 -359.859805) (xy 260.517463 -359.993928) (xy 260.557188 -360.130517) (xy 260.589121 -360.269135)
			(xy 260.613162 -360.409337) (xy 260.629231 -360.550675) (xy 260.637279 -360.692696) (xy 260.637782 -360.76382)
			(xy 260.637279 -360.834944) (xy 260.629231 -360.976965) (xy 260.613162 -361.118303) (xy 260.610619 -361.133136)
			(xy 369.3861 -361.133136) (xy 369.390189 -361.077254) (xy 369.402372 -361.022564) (xy 369.422388 -360.97023)
			(xy 369.449811 -360.921368) (xy 369.484056 -360.87702) (xy 369.524392 -360.83813) (xy 369.569962 -360.805528)
			(xy 369.619793 -360.779909) (xy 369.672823 -360.761817) (xy 369.727921 -360.75164) (xy 369.783915 -360.749594)
			(xy 369.83961 -360.755722) (xy 369.870585 -360.76382) (xy 456.565771 -360.76382) (xy 456.569767 -360.553934)
			(xy 456.581752 -360.344352) (xy 456.601706 -360.135378) (xy 456.629602 -359.927316) (xy 456.665399 -359.720466)
			(xy 456.709044 -359.515129) (xy 456.760476 -359.311603) (xy 456.819618 -359.110182) (xy 456.886386 -358.911159)
			(xy 456.960682 -358.714822) (xy 457.0424 -358.521456) (xy 457.131419 -358.331341) (xy 457.227612 -358.144753)
			(xy 457.330839 -357.961962) (xy 457.44095 -357.783234) (xy 457.557785 -357.608827) (xy 457.681175 -357.438995)
			(xy 457.810942 -357.273983) (xy 457.946896 -357.114032) (xy 458.088842 -356.959372) (xy 458.236572 -356.810228)
			(xy 458.389874 -356.666817) (xy 458.548524 -356.529346) (xy 458.712293 -356.398014) (xy 458.880943 -356.273013)
			(xy 459.054229 -356.154522) (xy 459.231901 -356.042715) (xy 459.413701 -355.937753) (xy 459.599365 -355.839788)
			(xy 459.788623 -355.748963) (xy 459.981203 -355.665409) (xy 460.176824 -355.589246) (xy 460.375202 -355.520587)
			(xy 460.576051 -355.45953) (xy 460.779078 -355.406163) (xy 460.983991 -355.360565) (xy 461.19049 -355.3228)
			(xy 461.398277 -355.292925) (xy 461.607052 -355.270982) (xy 461.81651 -355.257003) (xy 462.026349 -355.251008)
			(xy 462.236263 -355.253007) (xy 462.44595 -355.262995) (xy 462.655104 -355.28096) (xy 462.863422 -355.306874)
			(xy 463.070603 -355.340699) (xy 463.276347 -355.382388) (xy 463.480353 -355.43188) (xy 463.682328 -355.489102)
			(xy 463.881978 -355.553972) (xy 464.079013 -355.626396) (xy 464.273149 -355.706269) (xy 464.464102 -355.793475)
			(xy 464.651598 -355.887887) (xy 464.835363 -355.989369) (xy 465.015131 -356.097773) (xy 465.190642 -356.212943)
			(xy 465.361641 -356.334711) (xy 465.527881 -356.4629) (xy 465.68912 -356.597326) (xy 465.845124 -356.737793)
			(xy 465.995667 -356.884097) (xy 466.140531 -357.036026) (xy 466.279506 -357.19336) (xy 466.412391 -357.355871)
			(xy 466.538992 -357.523324) (xy 466.659127 -357.695474) (xy 466.772621 -357.872074) (xy 466.879309 -358.052866)
			(xy 466.979036 -358.237589) (xy 467.071659 -358.425975) (xy 467.157043 -358.61775) (xy 467.235064 -358.812637)
			(xy 467.305609 -359.010353) (xy 467.368576 -359.210611) (xy 467.423873 -359.413121) (xy 467.47142 -359.61759)
			(xy 467.511148 -359.823721) (xy 467.543 -360.031214) (xy 467.56693 -360.23977) (xy 467.582902 -360.449086)
			(xy 467.590894 -360.658858) (xy 467.591394 -360.76382) (xy 467.590894 -360.868782) (xy 467.582902 -361.078554)
			(xy 467.56693 -361.28787) (xy 467.543 -361.496426) (xy 467.511148 -361.703919) (xy 467.47142 -361.91005)
			(xy 467.423873 -362.114519) (xy 467.368576 -362.317029) (xy 467.305609 -362.517287) (xy 467.235064 -362.715003)
			(xy 467.157043 -362.90989) (xy 467.071659 -363.101665) (xy 466.979036 -363.290051) (xy 466.879309 -363.474774)
			(xy 466.772621 -363.655566) (xy 466.659127 -363.832166) (xy 466.538992 -364.004316) (xy 466.412391 -364.171769)
			(xy 466.279506 -364.33428) (xy 466.140531 -364.491614) (xy 465.995667 -364.643543) (xy 465.845124 -364.789847)
			(xy 465.68912 -364.930314) (xy 465.527881 -365.06474) (xy 465.361641 -365.192929) (xy 465.190642 -365.314697)
			(xy 465.015131 -365.429867) (xy 464.835363 -365.538271) (xy 464.651598 -365.639753) (xy 464.464102 -365.734165)
			(xy 464.273149 -365.821371) (xy 464.079013 -365.901244) (xy 463.881978 -365.973668) (xy 463.682328 -366.038538)
			(xy 463.480353 -366.09576) (xy 463.276347 -366.145252) (xy 463.070603 -366.186941) (xy 462.863422 -366.220766)
			(xy 462.655104 -366.24668) (xy 462.44595 -366.264645) (xy 462.236263 -366.274633) (xy 462.026349 -366.276632)
			(xy 461.81651 -366.270637) (xy 461.607052 -366.256658) (xy 461.398277 -366.234715) (xy 461.19049 -366.20484)
			(xy 460.983991 -366.167075) (xy 460.779078 -366.121477) (xy 460.576051 -366.06811) (xy 460.375202 -366.007053)
			(xy 460.176824 -365.938394) (xy 459.981203 -365.862231) (xy 459.788623 -365.778677) (xy 459.599365 -365.687852)
			(xy 459.413701 -365.589887) (xy 459.231901 -365.484925) (xy 459.054229 -365.373118) (xy 458.880943 -365.254627)
			(xy 458.712293 -365.129626) (xy 458.548524 -364.998294) (xy 458.389874 -364.860823) (xy 458.236572 -364.717412)
			(xy 458.088842 -364.568268) (xy 457.946896 -364.413608) (xy 457.810942 -364.253657) (xy 457.681175 -364.088645)
			(xy 457.557785 -363.918813) (xy 457.44095 -363.744406) (xy 457.330839 -363.565678) (xy 457.227612 -363.382887)
			(xy 457.131419 -363.196299) (xy 457.0424 -363.006184) (xy 456.960682 -362.812818) (xy 456.886386 -362.616481)
			(xy 456.819618 -362.417458) (xy 456.760476 -362.216037) (xy 456.709044 -362.012511) (xy 456.665399 -361.807174)
			(xy 456.629602 -361.600324) (xy 456.601706 -361.392262) (xy 456.581752 -361.183288) (xy 456.569767 -360.973706)
			(xy 456.565771 -360.76382) (xy 369.870585 -360.76382) (xy 369.893819 -360.769894) (xy 369.945387 -360.791808)
			(xy 369.993215 -360.820997) (xy 370.036283 -360.856838) (xy 370.073673 -360.898568) (xy 370.104589 -360.945298)
			(xy 370.128372 -360.996031) (xy 370.144514 -361.049687) (xy 370.152673 -361.105121) (xy 370.153184 -361.133136)
			(xy 370.152673 -361.161151) (xy 370.144514 -361.216585) (xy 370.128372 -361.270241) (xy 370.104589 -361.320974)
			(xy 370.073673 -361.367704) (xy 370.036283 -361.409434) (xy 369.993215 -361.445275) (xy 369.945387 -361.474464)
			(xy 369.893819 -361.496378) (xy 369.83961 -361.51055) (xy 369.783915 -361.516678) (xy 369.727921 -361.514632)
			(xy 369.672823 -361.504455) (xy 369.619793 -361.486363) (xy 369.569962 -361.460744) (xy 369.524392 -361.428142)
			(xy 369.484056 -361.389252) (xy 369.449811 -361.344904) (xy 369.422388 -361.296042) (xy 369.402372 -361.243708)
			(xy 369.390189 -361.189018) (xy 369.3861 -361.133136) (xy 260.610619 -361.133136) (xy 260.589121 -361.258505)
			(xy 260.557188 -361.397123) (xy 260.517463 -361.533712) (xy 260.470075 -361.667835) (xy 260.415174 -361.799062)
			(xy 260.352937 -361.926973) (xy 260.283563 -362.051158) (xy 260.207274 -362.171219) (xy 260.124316 -362.286772)
			(xy 260.034952 -362.397446) (xy 259.939471 -362.502888) (xy 259.838177 -362.602758) (xy 259.731395 -362.696738)
			(xy 259.619467 -362.784526) (xy 259.502751 -362.865842) (xy 259.381623 -362.940424) (xy 259.256469 -363.008033)
			(xy 259.12769 -363.068454) (xy 258.995699 -363.121492) (xy 258.860919 -363.166978) (xy 258.723781 -363.204766)
			(xy 258.584726 -363.234735) (xy 258.444197 -363.256789) (xy 258.302646 -363.270857) (xy 258.160526 -363.276894)
			(xy 258.018291 -363.274881) (xy 257.876399 -363.264824) (xy 257.735303 -363.246756) (xy 257.595454 -363.220735)
			(xy 257.457302 -363.186843) (xy 257.321289 -363.145189) (xy 257.18785 -363.095907) (xy 257.057413 -363.039155)
			(xy 256.930396 -362.975114) (xy 256.807205 -362.90399) (xy 256.688236 -362.82601) (xy 256.573868 -362.741424)
			(xy 256.464469 -362.650504) (xy 256.36039 -362.55354) (xy 256.261962 -362.450843) (xy 256.169503 -362.342741)
			(xy 256.083307 -362.229582) (xy 256.003652 -362.111728) (xy 255.930791 -361.989556) (xy 255.86496 -361.863458)
			(xy 255.806367 -361.733837) (xy 255.755202 -361.601109) (xy 255.711628 -361.465699) (xy 255.675784 -361.32804)
			(xy 255.647786 -361.188574) (xy 255.627723 -361.047748) (xy 255.61566 -360.906012) (xy 255.611635 -360.76382)
			(xy 216.187782 -360.76382) (xy 216.187279 -360.834944) (xy 216.179231 -360.976965) (xy 216.163162 -361.118303)
			(xy 216.139121 -361.258505) (xy 216.107188 -361.397123) (xy 216.067463 -361.533712) (xy 216.020075 -361.667835)
			(xy 215.965174 -361.799062) (xy 215.902937 -361.926973) (xy 215.833563 -362.051158) (xy 215.757274 -362.171219)
			(xy 215.674316 -362.286772) (xy 215.584952 -362.397446) (xy 215.489471 -362.502888) (xy 215.388177 -362.602758)
			(xy 215.281395 -362.696738) (xy 215.169467 -362.784526) (xy 215.052751 -362.865842) (xy 214.931623 -362.940424)
			(xy 214.806469 -363.008033) (xy 214.67769 -363.068454) (xy 214.545699 -363.121492) (xy 214.410919 -363.166978)
			(xy 214.273781 -363.204766) (xy 214.134726 -363.234735) (xy 213.994197 -363.256789) (xy 213.852646 -363.270857)
			(xy 213.710526 -363.276894) (xy 213.568291 -363.274881) (xy 213.426399 -363.264824) (xy 213.285303 -363.246756)
			(xy 213.145454 -363.220735) (xy 213.007302 -363.186843) (xy 212.871289 -363.145189) (xy 212.73785 -363.095907)
			(xy 212.607413 -363.039155) (xy 212.480396 -362.975114) (xy 212.357205 -362.90399) (xy 212.238236 -362.82601)
			(xy 212.123868 -362.741424) (xy 212.014469 -362.650504) (xy 211.91039 -362.55354) (xy 211.811962 -362.450843)
			(xy 211.719503 -362.342741) (xy 211.633307 -362.229582) (xy 211.553652 -362.111728) (xy 211.480791 -361.989556)
			(xy 211.41496 -361.863458) (xy 211.356367 -361.733837) (xy 211.305202 -361.601109) (xy 211.261628 -361.465699)
			(xy 211.225784 -361.32804) (xy 211.197786 -361.188574) (xy 211.177723 -361.047748) (xy 211.16566 -360.906012)
			(xy 211.161635 -360.76382) (xy 121.930771 -360.76382) (xy 121.954005 -360.769894) (xy 122.005573 -360.791808)
			(xy 122.053401 -360.820997) (xy 122.096469 -360.856838) (xy 122.133859 -360.898568) (xy 122.164775 -360.945298)
			(xy 122.188558 -360.996031) (xy 122.2047 -361.049687) (xy 122.212859 -361.105121) (xy 122.21337 -361.133136)
			(xy 122.212859 -361.161151) (xy 122.2047 -361.216585) (xy 122.188558 -361.270241) (xy 122.164775 -361.320974)
			(xy 122.133859 -361.367704) (xy 122.096469 -361.409434) (xy 122.053401 -361.445275) (xy 122.005573 -361.474464)
			(xy 121.954005 -361.496378) (xy 121.899796 -361.51055) (xy 121.844101 -361.516678) (xy 121.788107 -361.514632)
			(xy 121.733009 -361.504455) (xy 121.679979 -361.486363) (xy 121.630148 -361.460744) (xy 121.584578 -361.428142)
			(xy 121.544242 -361.389252) (xy 121.509997 -361.344904) (xy 121.482574 -361.296042) (xy 121.462558 -361.243708)
			(xy 121.450375 -361.189018) (xy 121.446286 -361.133136) (xy 15.239789 -361.133136) (xy 15.227982 -361.28787)
			(xy 15.204052 -361.496426) (xy 15.1722 -361.703919) (xy 15.132472 -361.91005) (xy 15.084925 -362.114519)
			(xy 15.029628 -362.317029) (xy 14.966661 -362.517287) (xy 14.896116 -362.715003) (xy 14.818095 -362.90989)
			(xy 14.732711 -363.101665) (xy 14.640088 -363.290051) (xy 14.540361 -363.474774) (xy 14.433673 -363.655566)
			(xy 14.320179 -363.832166) (xy 14.200044 -364.004316) (xy 14.073443 -364.171769) (xy 13.940558 -364.33428)
			(xy 13.801583 -364.491614) (xy 13.656719 -364.643543) (xy 13.506176 -364.789847) (xy 13.350172 -364.930314)
			(xy 13.188933 -365.06474) (xy 13.022693 -365.192929) (xy 12.851694 -365.314697) (xy 12.676183 -365.429867)
			(xy 12.496415 -365.538271) (xy 12.31265 -365.639753) (xy 12.125154 -365.734165) (xy 11.934201 -365.821371)
			(xy 11.740065 -365.901244) (xy 11.54303 -365.973668) (xy 11.34338 -366.038538) (xy 11.141405 -366.09576)
			(xy 10.937399 -366.145252) (xy 10.731655 -366.186941) (xy 10.524474 -366.220766) (xy 10.316156 -366.24668)
			(xy 10.107002 -366.264645) (xy 9.897315 -366.274633) (xy 9.687401 -366.276632) (xy 9.477562 -366.270637)
			(xy 9.268104 -366.256658) (xy 9.059329 -366.234715) (xy 8.851542 -366.20484) (xy 8.645043 -366.167075)
			(xy 8.44013 -366.121477) (xy 8.237103 -366.06811) (xy 8.036254 -366.007053) (xy 7.837876 -365.938394)
			(xy 7.642255 -365.862231) (xy 7.449675 -365.778677) (xy 7.260417 -365.687852) (xy 7.074753 -365.589887)
			(xy 6.892953 -365.484925) (xy 6.715281 -365.373118) (xy 6.541995 -365.254627) (xy 6.373345 -365.129626)
			(xy 6.209576 -364.998294) (xy 6.050926 -364.860823) (xy 5.897624 -364.717412) (xy 5.749894 -364.568268)
			(xy 5.607948 -364.413608) (xy 5.471994 -364.253657) (xy 5.342227 -364.088645) (xy 5.218837 -363.918813)
			(xy 5.102002 -363.744406) (xy 4.991891 -363.565678) (xy 4.888664 -363.382887) (xy 4.792471 -363.196299)
			(xy 4.703452 -363.006184) (xy 4.621734 -362.812818) (xy 4.547438 -362.616481) (xy 4.48067 -362.417458)
			(xy 4.421528 -362.216037) (xy 4.370096 -362.012511) (xy 4.326451 -361.807174) (xy 4.290654 -361.600324)
			(xy 4.262758 -361.392262) (xy 4.242804 -361.183288) (xy 4.230819 -360.973706) (xy 4.226823 -360.76382)
			(xy 2.509012 -360.76382) (xy 2.509012 -383.932484) (xy 8.539215 -383.932484) (xy 8.539215 -383.803344)
			(xy 8.547165 -383.674449) (xy 8.563035 -383.546289) (xy 8.586764 -383.419348) (xy 8.618263 -383.294109)
			(xy 8.657412 -383.171046) (xy 8.704063 -383.050627) (xy 8.758038 -382.933308) (xy 8.819133 -382.819534)
			(xy 8.887116 -382.709737) (xy 8.96173 -382.604334) (xy 9.042691 -382.503724) (xy 9.129691 -382.408289)
			(xy 9.222402 -382.31839) (xy 9.320472 -382.234369) (xy 9.423527 -382.156545) (xy 9.531178 -382.085213)
			(xy 9.643017 -382.020643) (xy 9.758618 -381.963081) (xy 9.877543 -381.912744) (xy 9.999342 -381.869824)
			(xy 10.123552 -381.834483) (xy 10.249701 -381.806856) (xy 10.377313 -381.787047) (xy 10.505902 -381.775131)
			(xy 10.63498 -381.771155) (xy 10.764058 -381.775131) (xy 10.892647 -381.787047) (xy 11.020259 -381.806856)
			(xy 11.146408 -381.834483) (xy 11.270618 -381.869824) (xy 11.392417 -381.912744) (xy 11.511342 -381.963081)
			(xy 11.626943 -382.020643) (xy 11.738782 -382.085213) (xy 11.846433 -382.156545) (xy 11.949488 -382.234369)
			(xy 12.047558 -382.31839) (xy 12.140269 -382.408289) (xy 12.227269 -382.503724) (xy 12.30823 -382.604334)
			(xy 12.382844 -382.709737) (xy 12.450827 -382.819534) (xy 12.505341 -382.921052) (xy 19.016679 -382.921052)
			(xy 19.016679 -382.866548) (xy 19.024437 -382.812598) (xy 19.039793 -382.760301) (xy 19.062436 -382.710722)
			(xy 19.091904 -382.664871) (xy 19.127599 -382.62368) (xy 19.168792 -382.587989) (xy 19.214645 -382.558523)
			(xy 19.264226 -382.535884) (xy 19.316523 -382.520531) (xy 19.370474 -382.512778) (xy 19.397726 -382.512316)
			(xy 20.261326 -382.512316) (xy 20.288578 -382.512756) (xy 20.342526 -382.520516) (xy 20.394821 -382.535874)
			(xy 20.444398 -382.558518) (xy 20.490248 -382.587987) (xy 20.531438 -382.623681) (xy 20.567129 -382.664873)
			(xy 20.596594 -382.710725) (xy 20.619235 -382.760303) (xy 20.63459 -382.812599) (xy 20.642346 -382.866548)
			(xy 20.642346 -382.921052) (xy 20.636681 -382.960459) (xy 22.291788 -382.960459) (xy 22.291788 -382.905921)
			(xy 22.29955 -382.851938) (xy 22.314915 -382.79961) (xy 22.337571 -382.75) (xy 22.367056 -382.70412)
			(xy 22.40277 -382.662903) (xy 22.443987 -382.627188) (xy 22.489867 -382.597702) (xy 22.539476 -382.575046)
			(xy 22.591804 -382.559681) (xy 22.645787 -382.551919) (xy 22.673056 -382.551432) (xy 23.536656 -382.551432)
			(xy 23.563927 -382.551887) (xy 23.617915 -382.559649) (xy 23.670249 -382.575015) (xy 23.719863 -382.597673)
			(xy 23.765748 -382.62716) (xy 23.806969 -382.662878) (xy 23.842687 -382.704099) (xy 23.872175 -382.749983)
			(xy 23.894834 -382.799597) (xy 23.9102 -382.851931) (xy 23.917962 -382.905919) (xy 23.917962 -382.960461)
			(xy 23.9102 -383.014449) (xy 23.894834 -383.066783) (xy 23.872175 -383.116397) (xy 23.842687 -383.162281)
			(xy 23.806969 -383.203502) (xy 23.765748 -383.23922) (xy 23.719863 -383.268707) (xy 23.670249 -383.291365)
			(xy 23.617915 -383.306731) (xy 23.563927 -383.314493) (xy 23.536656 -383.314956) (xy 22.673056 -383.314956)
			(xy 22.645787 -383.314461) (xy 22.591804 -383.306699) (xy 22.539476 -383.291334) (xy 22.489867 -383.268678)
			(xy 22.443987 -383.239192) (xy 22.40277 -383.203477) (xy 22.367056 -383.16226) (xy 22.337571 -383.11638)
			(xy 22.314915 -383.06677) (xy 22.29955 -383.014442) (xy 22.291788 -382.960459) (xy 20.636681 -382.960459)
			(xy 20.63459 -382.975001) (xy 20.619235 -383.027297) (xy 20.596594 -383.076875) (xy 20.567129 -383.122727)
			(xy 20.531438 -383.163919) (xy 20.490248 -383.199613) (xy 20.444398 -383.229082) (xy 20.394821 -383.251726)
			(xy 20.342526 -383.267084) (xy 20.288578 -383.274844) (xy 20.261326 -383.275332) (xy 19.397726 -383.275332)
			(xy 19.370474 -383.274822) (xy 19.316523 -383.267069) (xy 19.264226 -383.251716) (xy 19.214645 -383.229077)
			(xy 19.168792 -383.199611) (xy 19.127599 -383.16392) (xy 19.091904 -383.122729) (xy 19.062436 -383.076878)
			(xy 19.039793 -383.027299) (xy 19.024437 -382.975002) (xy 19.016679 -382.921052) (xy 12.505341 -382.921052)
			(xy 12.511922 -382.933308) (xy 12.565897 -383.050627) (xy 12.612548 -383.171046) (xy 12.651697 -383.294109)
			(xy 12.683196 -383.419348) (xy 12.706925 -383.546289) (xy 12.722795 -383.674449) (xy 12.730745 -383.803344)
			(xy 12.731242 -383.867914) (xy 12.730745 -383.932484) (xy 12.722795 -384.061379) (xy 12.706925 -384.189539)
			(xy 12.683196 -384.31648) (xy 12.651697 -384.441719) (xy 12.612548 -384.564782) (xy 12.565897 -384.685201)
			(xy 12.511922 -384.80252) (xy 12.450827 -384.916294) (xy 12.382844 -385.026091) (xy 12.30823 -385.131494)
			(xy 12.227269 -385.232104) (xy 12.140269 -385.327539) (xy 12.047558 -385.417438) (xy 11.949488 -385.501459)
			(xy 11.846433 -385.579283) (xy 11.738782 -385.650615) (xy 11.626943 -385.715185) (xy 11.511342 -385.772747)
			(xy 11.483943 -385.784344) (xy 19.460972 -385.784344) (xy 19.460972 -384.920744) (xy 19.461458 -384.893493)
			(xy 19.469214 -384.839545) (xy 19.484569 -384.78725) (xy 19.507211 -384.737673) (xy 19.536677 -384.691823)
			(xy 19.572368 -384.650632) (xy 19.613559 -384.614941) (xy 19.659409 -384.585475) (xy 19.708986 -384.562833)
			(xy 19.761281 -384.547478) (xy 19.815229 -384.539722) (xy 19.869731 -384.539722) (xy 19.923679 -384.547478)
			(xy 19.975974 -384.562833) (xy 20.025551 -384.585475) (xy 20.071401 -384.614941) (xy 20.112592 -384.650632)
			(xy 20.148283 -384.691823) (xy 20.177749 -384.737673) (xy 20.200391 -384.78725) (xy 20.215746 -384.839545)
			(xy 20.223502 -384.893493) (xy 20.223988 -384.920744) (xy 20.223988 -385.784344) (xy 20.22353 -385.809998)
			(xy 22.731984 -385.809998) (xy 22.731984 -384.946398) (xy 22.73247 -384.919147) (xy 22.740226 -384.865199)
			(xy 22.755581 -384.812904) (xy 22.778223 -384.763327) (xy 22.807689 -384.717477) (xy 22.84338 -384.676286)
			(xy 22.884571 -384.640595) (xy 22.930421 -384.611129) (xy 22.979998 -384.588487) (xy 23.032293 -384.573132)
			(xy 23.086241 -384.565376) (xy 23.140743 -384.565376) (xy 23.194691 -384.573132) (xy 23.246986 -384.588487)
			(xy 23.296563 -384.611129) (xy 23.342413 -384.640595) (xy 23.383604 -384.676286) (xy 23.419295 -384.717477)
			(xy 23.448761 -384.763327) (xy 23.471403 -384.812904) (xy 23.486758 -384.865199) (xy 23.494514 -384.919147)
			(xy 23.495 -384.946398) (xy 23.495 -385.440249) (xy 36.585674 -385.440249) (xy 36.585674 -385.385751)
			(xy 36.593429 -385.331807) (xy 36.608782 -385.279515) (xy 36.63142 -385.229941) (xy 36.660882 -385.184092)
			(xy 36.696569 -385.142903) (xy 36.737753 -385.107211) (xy 36.783598 -385.077743) (xy 36.83317 -385.055099)
			(xy 36.88546 -385.039739) (xy 36.939403 -385.031977) (xy 36.966652 -385.031488) (xy 37.830252 -385.031488)
			(xy 37.857507 -385.031956) (xy 37.911462 -385.039707) (xy 37.963765 -385.055059) (xy 38.013351 -385.077699)
			(xy 38.05921 -385.107165) (xy 38.100408 -385.142858) (xy 38.136106 -385.184052) (xy 38.165578 -385.229907)
			(xy 38.188224 -385.27949) (xy 38.203582 -385.331791) (xy 38.211341 -385.385745) (xy 38.211341 -385.440255)
			(xy 38.203582 -385.494209) (xy 38.188224 -385.54651) (xy 38.165578 -385.596093) (xy 38.16123 -385.602858)
			(xy 41.455211 -385.602858) (xy 41.455211 -385.548342) (xy 41.46297 -385.494381) (xy 41.47833 -385.442074)
			(xy 41.500978 -385.392486) (xy 41.530453 -385.346625) (xy 41.566155 -385.305427) (xy 41.607357 -385.269729)
			(xy 41.653221 -385.240259) (xy 41.702812 -385.217616) (xy 41.755121 -385.202261) (xy 41.809082 -385.194508)
			(xy 41.83634 -385.194048) (xy 42.69994 -385.194048) (xy 42.727186 -385.194625) (xy 42.781123 -385.202385)
			(xy 42.833407 -385.217742) (xy 42.882974 -385.240383) (xy 42.928814 -385.269847) (xy 42.969994 -385.305534)
			(xy 43.005677 -385.346718) (xy 43.035136 -385.392562) (xy 43.057772 -385.44213) (xy 43.073123 -385.494416)
			(xy 43.080878 -385.548354) (xy 43.080878 -385.602846) (xy 43.073123 -385.656784) (xy 43.057772 -385.70907)
			(xy 43.035136 -385.758638) (xy 43.005677 -385.804482) (xy 42.969994 -385.845666) (xy 42.928814 -385.881353)
			(xy 42.882974 -385.910817) (xy 42.833407 -385.933458) (xy 42.781123 -385.948815) (xy 42.727186 -385.956575)
			(xy 42.69994 -385.957064) (xy 41.83634 -385.957064) (xy 41.809082 -385.956692) (xy 41.755121 -385.948939)
			(xy 41.702812 -385.933584) (xy 41.653221 -385.910941) (xy 41.607357 -385.881471) (xy 41.566155 -385.845773)
			(xy 41.530453 -385.804575) (xy 41.500978 -385.758714) (xy 41.47833 -385.709126) (xy 41.46297 -385.656819)
			(xy 41.455211 -385.602858) (xy 38.16123 -385.602858) (xy 38.136106 -385.641948) (xy 38.100408 -385.683142)
			(xy 38.05921 -385.718835) (xy 38.013351 -385.748301) (xy 37.963765 -385.770941) (xy 37.911462 -385.786293)
			(xy 37.857507 -385.794044) (xy 37.830252 -385.794504) (xy 36.966652 -385.794504) (xy 36.939403 -385.794023)
			(xy 36.88546 -385.786261) (xy 36.83317 -385.770901) (xy 36.783598 -385.748257) (xy 36.737753 -385.718789)
			(xy 36.696569 -385.683097) (xy 36.660882 -385.641908) (xy 36.63142 -385.596059) (xy 36.608782 -385.546485)
			(xy 36.593429 -385.494193) (xy 36.585674 -385.440249) (xy 23.495 -385.440249) (xy 23.495 -385.809998)
			(xy 23.494514 -385.837249) (xy 23.486758 -385.891197) (xy 23.471403 -385.943492) (xy 23.448761 -385.993069)
			(xy 23.419295 -386.038919) (xy 23.383604 -386.08011) (xy 23.342413 -386.115801) (xy 23.296563 -386.145267)
			(xy 23.246986 -386.167909) (xy 23.194691 -386.183264) (xy 23.140743 -386.19102) (xy 23.086241 -386.19102)
			(xy 23.032293 -386.183264) (xy 22.979998 -386.167909) (xy 22.930421 -386.145267) (xy 22.884571 -386.115801)
			(xy 22.84338 -386.08011) (xy 22.807689 -386.038919) (xy 22.778223 -385.993069) (xy 22.755581 -385.943492)
			(xy 22.740226 -385.891197) (xy 22.73247 -385.837249) (xy 22.731984 -385.809998) (xy 20.22353 -385.809998)
			(xy 20.223502 -385.811595) (xy 20.215746 -385.865543) (xy 20.200391 -385.917838) (xy 20.177749 -385.967415)
			(xy 20.148283 -386.013265) (xy 20.112592 -386.054456) (xy 20.071401 -386.090147) (xy 20.025551 -386.119613)
			(xy 19.975974 -386.142255) (xy 19.923679 -386.15761) (xy 19.869731 -386.165366) (xy 19.815229 -386.165366)
			(xy 19.761281 -386.15761) (xy 19.708986 -386.142255) (xy 19.659409 -386.119613) (xy 19.613559 -386.090147)
			(xy 19.572368 -386.054456) (xy 19.536677 -386.013265) (xy 19.507211 -385.967415) (xy 19.484569 -385.917838)
			(xy 19.469214 -385.865543) (xy 19.461458 -385.811595) (xy 19.460972 -385.784344) (xy 11.483943 -385.784344)
			(xy 11.392417 -385.823084) (xy 11.270618 -385.866004) (xy 11.146408 -385.901345) (xy 11.020259 -385.928972)
			(xy 10.892647 -385.948781) (xy 10.764058 -385.960697) (xy 10.63498 -385.964674) (xy 10.505902 -385.960697)
			(xy 10.377313 -385.948781) (xy 10.249701 -385.928972) (xy 10.123552 -385.901345) (xy 9.999342 -385.866004)
			(xy 9.877543 -385.823084) (xy 9.758618 -385.772747) (xy 9.643017 -385.715185) (xy 9.531178 -385.650615)
			(xy 9.423527 -385.579283) (xy 9.320472 -385.501459) (xy 9.222402 -385.417438) (xy 9.129691 -385.327539)
			(xy 9.042691 -385.232104) (xy 8.96173 -385.131494) (xy 8.887116 -385.026091) (xy 8.819133 -384.916294)
			(xy 8.758038 -384.80252) (xy 8.704063 -384.685201) (xy 8.657412 -384.564782) (xy 8.618263 -384.441719)
			(xy 8.586764 -384.31648) (xy 8.563035 -384.189539) (xy 8.547165 -384.061379) (xy 8.539215 -383.932484)
			(xy 2.509012 -383.932484) (xy 2.509012 -389.402275) (xy 286.566098 -389.402275) (xy 286.566098 -389.317529)
			(xy 286.574154 -389.233168) (xy 286.590192 -389.149954) (xy 286.614067 -389.068641) (xy 286.645564 -388.989966)
			(xy 286.684397 -388.914642) (xy 286.730213 -388.843349) (xy 286.7826 -388.776735) (xy 286.84108 -388.715402)
			(xy 286.905127 -388.659906) (xy 286.974158 -388.610748) (xy 287.04755 -388.568376) (xy 287.124637 -388.533171)
			(xy 287.204721 -388.505454) (xy 287.287078 -388.485474) (xy 287.370961 -388.473414) (xy 287.45561 -388.469382)
			(xy 287.540259 -388.473414) (xy 287.624142 -388.485474) (xy 287.706499 -388.505454) (xy 287.786583 -388.533171)
			(xy 287.86367 -388.568376) (xy 287.937062 -388.610748) (xy 288.006093 -388.659906) (xy 288.07014 -388.715402)
			(xy 288.12862 -388.776735) (xy 288.181007 -388.843349) (xy 288.226823 -388.914642) (xy 288.265656 -388.989966)
			(xy 288.297153 -389.068641) (xy 288.321028 -389.149954) (xy 288.337066 -389.233168) (xy 288.345122 -389.317529)
			(xy 288.345626 -389.359902) (xy 288.345122 -389.402275) (xy 297.615098 -389.402275) (xy 297.615098 -389.317529)
			(xy 297.623154 -389.233168) (xy 297.639192 -389.149954) (xy 297.663067 -389.068641) (xy 297.694564 -388.989966)
			(xy 297.733397 -388.914642) (xy 297.779213 -388.843349) (xy 297.8316 -388.776735) (xy 297.89008 -388.715402)
			(xy 297.954127 -388.659906) (xy 298.023158 -388.610748) (xy 298.09655 -388.568376) (xy 298.173637 -388.533171)
			(xy 298.253721 -388.505454) (xy 298.336078 -388.485474) (xy 298.419961 -388.473414) (xy 298.50461 -388.469382)
			(xy 298.589259 -388.473414) (xy 298.673142 -388.485474) (xy 298.755499 -388.505454) (xy 298.835583 -388.533171)
			(xy 298.91267 -388.568376) (xy 298.986062 -388.610748) (xy 299.055093 -388.659906) (xy 299.11914 -388.715402)
			(xy 299.17762 -388.776735) (xy 299.230007 -388.843349) (xy 299.275823 -388.914642) (xy 299.314656 -388.989966)
			(xy 299.346153 -389.068641) (xy 299.370028 -389.149954) (xy 299.386066 -389.233168) (xy 299.394122 -389.317529)
			(xy 299.394626 -389.359902) (xy 299.394122 -389.402275) (xy 299.386066 -389.486636) (xy 299.370028 -389.56985)
			(xy 299.346153 -389.651163) (xy 299.314656 -389.729838) (xy 299.275823 -389.805162) (xy 299.230007 -389.876455)
			(xy 299.17762 -389.943069) (xy 299.11914 -390.004402) (xy 299.055093 -390.059898) (xy 298.986062 -390.109056)
			(xy 298.91267 -390.151428) (xy 298.835583 -390.186633) (xy 298.755499 -390.21435) (xy 298.673142 -390.23433)
			(xy 298.589259 -390.24639) (xy 298.50461 -390.250423) (xy 298.419961 -390.24639) (xy 298.336078 -390.23433)
			(xy 298.253721 -390.21435) (xy 298.173637 -390.186633) (xy 298.09655 -390.151428) (xy 298.023158 -390.109056)
			(xy 297.954127 -390.059898) (xy 297.89008 -390.004402) (xy 297.8316 -389.943069) (xy 297.779213 -389.876455)
			(xy 297.733397 -389.805162) (xy 297.694564 -389.729838) (xy 297.663067 -389.651163) (xy 297.639192 -389.56985)
			(xy 297.623154 -389.486636) (xy 297.615098 -389.402275) (xy 288.345122 -389.402275) (xy 288.337066 -389.486636)
			(xy 288.321028 -389.56985) (xy 288.297153 -389.651163) (xy 288.265656 -389.729838) (xy 288.226823 -389.805162)
			(xy 288.181007 -389.876455) (xy 288.12862 -389.943069) (xy 288.07014 -390.004402) (xy 288.006093 -390.059898)
			(xy 287.937062 -390.109056) (xy 287.86367 -390.151428) (xy 287.786583 -390.186633) (xy 287.706499 -390.21435)
			(xy 287.624142 -390.23433) (xy 287.540259 -390.24639) (xy 287.45561 -390.250423) (xy 287.370961 -390.24639)
			(xy 287.287078 -390.23433) (xy 287.204721 -390.21435) (xy 287.124637 -390.186633) (xy 287.04755 -390.151428)
			(xy 286.974158 -390.109056) (xy 286.905127 -390.059898) (xy 286.84108 -390.004402) (xy 286.7826 -389.943069)
			(xy 286.730213 -389.876455) (xy 286.684397 -389.805162) (xy 286.645564 -389.729838) (xy 286.614067 -389.651163)
			(xy 286.590192 -389.56985) (xy 286.574154 -389.486636) (xy 286.566098 -389.402275) (xy 2.509012 -389.402275)
			(xy 2.509012 -390.74852) (xy 289.828732 -390.74852) (xy 289.829157 -390.717787) (xy 289.836564 -390.656768)
			(xy 289.851272 -390.597088) (xy 289.873068 -390.539615) (xy 289.901633 -390.485189) (xy 289.93655 -390.434604)
			(xy 289.97731 -390.388596) (xy 290.023319 -390.347837) (xy 290.073907 -390.312922) (xy 290.128334 -390.28436)
			(xy 290.185807 -390.262566) (xy 290.245488 -390.24786) (xy 290.306507 -390.240455) (xy 290.33724 -390.240012)
			(xy 290.369283 -390.240508) (xy 290.432859 -390.248584) (xy 290.494917 -390.264579) (xy 290.554476 -390.288239)
			(xy 290.610594 -390.31919) (xy 290.662381 -390.356941) (xy 290.709019 -390.400896) (xy 290.749768 -390.450359)
			(xy 290.783985 -390.504546) (xy 290.811128 -390.562601) (xy 290.830767 -390.623604) (xy 290.842591 -390.686591)
			(xy 290.844986 -390.718548) (xy 290.846452 -390.733661) (xy 290.857061 -390.762093) (xy 290.875562 -390.786147)
			(xy 290.900318 -390.803698) (xy 290.929141 -390.813192) (xy 290.9443 -390.814052) (xy 290.977155 -390.815239)
			(xy 291.042167 -390.825028) (xy 291.105376 -390.843112) (xy 291.165728 -390.86919) (xy 291.222216 -390.902827)
			(xy 291.2739 -390.943462) (xy 291.319917 -390.990417) (xy 291.359501 -391.04291) (xy 291.391992 -391.100065)
			(xy 291.416847 -391.160931) (xy 291.433653 -391.224491) (xy 291.442129 -391.289688) (xy 291.442648 -391.32256)
			(xy 291.442106 -391.353289) (xy 291.434703 -391.414298) (xy 291.42 -391.473971) (xy 291.398212 -391.531436)
			(xy 291.369656 -391.585856) (xy 291.334748 -391.636437) (xy 291.293998 -391.682441) (xy 291.248 -391.723199)
			(xy 291.197424 -391.758114) (xy 291.143009 -391.786679) (xy 291.085547 -391.808477) (xy 291.025877 -391.823189)
			(xy 290.964869 -391.830602) (xy 290.93414 -391.831068) (xy 290.902098 -391.830516) (xy 290.838523 -391.822449)
			(xy 290.776465 -391.806463) (xy 290.716905 -391.78281) (xy 290.660787 -391.751866) (xy 290.608999 -391.71412)
			(xy 290.56236 -391.670169) (xy 290.521609 -391.620711) (xy 290.487392 -391.566526) (xy 290.460249 -391.508474)
			(xy 290.440611 -391.447473) (xy 290.428788 -391.384488) (xy 290.426394 -391.352532) (xy 290.424962 -391.337414)
			(xy 290.414346 -391.308979) (xy 290.395837 -391.284924) (xy 290.371072 -391.267376) (xy 290.342242 -391.257886)
			(xy 290.32708 -391.257028) (xy 290.294229 -391.25578) (xy 290.229223 -391.24599) (xy 290.166019 -391.227907)
			(xy 290.105673 -391.201832) (xy 290.049188 -391.1682) (xy 289.997507 -391.127571) (xy 289.95149 -391.080623)
			(xy 289.911906 -391.028137) (xy 289.879413 -390.97099) (xy 289.854553 -390.910132) (xy 289.837741 -390.846579)
			(xy 289.829256 -390.78139) (xy 289.828732 -390.74852) (xy 2.509012 -390.74852) (xy 2.509012 -394.8085)
			(xy 243.179528 -394.8085) (xy 243.183558 -394.723892) (xy 243.195613 -394.640051) (xy 243.215583 -394.557735)
			(xy 243.243287 -394.47769) (xy 243.278475 -394.400641) (xy 243.320827 -394.327286) (xy 243.36996 -394.258289)
			(xy 243.42543 -394.194274) (xy 243.486733 -394.135823) (xy 243.553315 -394.083463) (xy 243.624573 -394.03767)
			(xy 243.699861 -393.998857) (xy 243.778498 -393.967377) (xy 243.859771 -393.943515) (xy 243.942944 -393.927486)
			(xy 244.027264 -393.919435) (xy 244.069616 -393.918948) (xy 244.11084 -393.919417) (xy 244.192933 -393.927053)
			(xy 244.273968 -393.94225) (xy 244.35325 -393.964876) (xy 244.430099 -393.994739) (xy 244.503857 -394.031582)
			(xy 244.573891 -394.075088) (xy 244.639601 -394.124886) (xy 244.670326 -394.152374) (xy 244.677558 -394.158461)
			(xy 244.695171 -394.165287) (xy 244.714061 -394.165287) (xy 244.731674 -394.158461) (xy 244.738906 -394.152374)
			(xy 244.769639 -394.124894) (xy 244.835341 -394.075085) (xy 244.905371 -394.03157) (xy 244.979128 -393.994723)
			(xy 245.055977 -393.964858) (xy 245.13526 -393.942233) (xy 245.216297 -393.927041) (xy 245.298392 -393.919413)
			(xy 245.339616 -393.918948) (xy 245.380184 -393.919416) (xy 245.460981 -393.926807) (xy 245.54077 -393.941524)
			(xy 245.618888 -393.963447) (xy 245.694684 -393.992392) (xy 245.767529 -394.02812) (xy 245.836818 -394.070333)
			(xy 245.901975 -394.118681) (xy 245.962458 -394.172761) (xy 246.017765 -394.232125) (xy 246.067436 -394.296278)
			(xy 246.111059 -394.364689) (xy 246.130064 -394.400532) (xy 246.157157 -394.401367) (xy 246.21073 -394.409598)
			(xy 246.262601 -394.42532) (xy 246.31173 -394.448214) (xy 246.357129 -394.477824) (xy 246.397887 -394.513553)
			(xy 246.433186 -394.554684) (xy 246.462317 -394.600391) (xy 246.484695 -394.649758) (xy 246.499871 -394.701791)
			(xy 246.507539 -394.755447) (xy 246.508016 -394.782548) (xy 246.507582 -394.8085) (xy 249.114543 -394.8085)
			(xy 249.118574 -394.723896) (xy 249.130628 -394.640058) (xy 249.150596 -394.557746) (xy 249.178298 -394.477704)
			(xy 249.213483 -394.400658) (xy 249.255833 -394.327305) (xy 249.304963 -394.25831) (xy 249.360429 -394.194298)
			(xy 249.421729 -394.135847) (xy 249.488307 -394.083488) (xy 249.55956 -394.037695) (xy 249.634844 -393.998882)
			(xy 249.713476 -393.967401) (xy 249.794745 -393.943537) (xy 249.877914 -393.927506) (xy 249.96223 -393.919453)
			(xy 250.00458 -393.918948) (xy 250.045803 -393.919439) (xy 250.127896 -393.927072) (xy 250.20893 -393.942266)
			(xy 250.288212 -393.964889) (xy 250.365061 -393.994749) (xy 250.438819 -394.031588) (xy 250.508854 -394.075092)
			(xy 250.574564 -394.124887) (xy 250.60529 -394.152374) (xy 250.612522 -394.158461) (xy 250.630135 -394.165287)
			(xy 250.649025 -394.165287) (xy 250.666638 -394.158461) (xy 250.67387 -394.152374) (xy 250.704576 -394.124863)
			(xy 250.770283 -394.075057) (xy 250.840317 -394.031545) (xy 250.914078 -393.994701) (xy 250.990931 -393.96484)
			(xy 251.070218 -393.942219) (xy 251.151257 -393.927032) (xy 251.233355 -393.91941) (xy 251.27458 -393.918948)
			(xy 251.315219 -393.919386) (xy 251.396157 -393.926808) (xy 251.47608 -393.941582) (xy 251.554323 -393.963585)
			(xy 251.630232 -393.992634) (xy 251.703174 -394.028487) (xy 251.772542 -394.070844) (xy 251.837756 -394.119353)
			(xy 251.898274 -394.173608) (xy 251.95359 -394.233158) (xy 252.003243 -394.297505) (xy 252.046819 -394.366114)
			(xy 252.06579 -394.402056) (xy 252.086364 -394.401548) (xy 252.113582 -394.401996) (xy 252.167464 -394.409739)
			(xy 252.219695 -394.425073) (xy 252.269213 -394.447684) (xy 252.315007 -394.477114) (xy 252.356147 -394.512762)
			(xy 252.391793 -394.553902) (xy 252.421221 -394.599698) (xy 252.443832 -394.649216) (xy 252.459163 -394.701448)
			(xy 252.466905 -394.75533) (xy 252.467364 -394.782548) (xy 252.466916 -394.8085) (xy 255.049428 -394.8085)
			(xy 255.053459 -394.723891) (xy 255.065514 -394.640048) (xy 255.085484 -394.55773) (xy 255.11319 -394.477684)
			(xy 255.148379 -394.400634) (xy 255.190732 -394.327277) (xy 255.239868 -394.258279) (xy 255.295339 -394.194265)
			(xy 255.356645 -394.135813) (xy 255.423229 -394.083453) (xy 255.494489 -394.03766) (xy 255.56978 -393.998849)
			(xy 255.648419 -393.96737) (xy 255.729694 -393.943509) (xy 255.812869 -393.927482) (xy 255.897191 -393.919434)
			(xy 255.939544 -393.918948) (xy 255.980768 -393.919399) (xy 256.062862 -393.927038) (xy 256.143897 -393.942237)
			(xy 256.223179 -393.964866) (xy 256.300029 -393.994731) (xy 256.373786 -394.031576) (xy 256.44382 -394.075085)
			(xy 256.509529 -394.124885) (xy 256.540254 -394.152374) (xy 256.547486 -394.158461) (xy 256.565099 -394.165287)
			(xy 256.583989 -394.165287) (xy 256.601602 -394.158461) (xy 256.608834 -394.152374) (xy 256.639555 -394.12488)
			(xy 256.70526 -394.075073) (xy 256.775292 -394.031559) (xy 256.849049 -393.994713) (xy 256.925901 -393.96485)
			(xy 257.005185 -393.942227) (xy 257.086223 -393.927037) (xy 257.168319 -393.919412) (xy 257.209544 -393.918948)
			(xy 257.250365 -393.919407) (xy 257.331665 -393.926876) (xy 257.411938 -393.941765) (xy 257.490509 -393.963948)
			(xy 257.566715 -393.993239) (xy 257.639917 -394.029392) (xy 257.709496 -394.072102) (xy 257.774868 -394.121009)
			(xy 257.835483 -394.175702) (xy 257.890829 -394.235721) (xy 257.940442 -394.300559) (xy 257.983902 -394.369672)
			(xy 258.002786 -394.405866) (xy 258.01873 -394.403337) (xy 258.050905 -394.400664) (xy 258.067048 -394.400532)
			(xy 258.094337 -394.400926) (xy 258.148358 -394.408699) (xy 258.200723 -394.424081) (xy 258.250366 -394.446758)
			(xy 258.296278 -394.476268) (xy 258.337522 -394.512012) (xy 258.37326 -394.553261) (xy 258.402765 -394.599176)
			(xy 258.425436 -394.648822) (xy 258.440811 -394.701189) (xy 258.448577 -394.755211) (xy 258.448577 -394.8085)
			(xy 260.984428 -394.8085) (xy 260.988458 -394.723893) (xy 261.000513 -394.640052) (xy 261.020483 -394.557736)
			(xy 261.048186 -394.477692) (xy 261.083374 -394.400643) (xy 261.125725 -394.327288) (xy 261.174858 -394.258291)
			(xy 261.230327 -394.194277) (xy 261.29163 -394.135826) (xy 261.358212 -394.083466) (xy 261.429469 -394.037672)
			(xy 261.504756 -393.99886) (xy 261.583392 -393.967379) (xy 261.664664 -393.943516) (xy 261.747837 -393.927487)
			(xy 261.832156 -393.919436) (xy 261.874508 -393.918948) (xy 261.915732 -393.919422) (xy 261.997825 -393.927057)
			(xy 262.078859 -393.942253) (xy 262.158141 -393.964879) (xy 262.234991 -393.994741) (xy 262.308749 -394.031583)
			(xy 262.378783 -394.075089) (xy 262.444493 -394.124886) (xy 262.475218 -394.152374) (xy 262.48245 -394.158461)
			(xy 262.500063 -394.165287) (xy 262.518953 -394.165287) (xy 262.536566 -394.158461) (xy 262.543798 -394.152374)
			(xy 262.574534 -394.124897) (xy 262.640236 -394.075089) (xy 262.710266 -394.031574) (xy 262.784021 -393.994725)
			(xy 262.86087 -393.96486) (xy 262.940153 -393.942234) (xy 263.021189 -393.927042) (xy 263.103284 -393.919413)
			(xy 263.144508 -393.918948) (xy 263.185239 -393.919443) (xy 263.26636 -393.9269) (xy 263.346458 -393.941743)
			(xy 263.424865 -393.963847) (xy 263.500922 -393.993026) (xy 263.573993 -394.029037) (xy 263.643465 -394.071577)
			(xy 263.708758 -394.120291) (xy 263.769323 -394.174771) (xy 263.824654 -394.234559) (xy 263.874287 -394.299155)
			(xy 263.917806 -394.368019) (xy 263.936734 -394.404088) (xy 263.947933 -394.402872) (xy 263.970427 -394.401601)
			(xy 263.981692 -394.401548) (xy 264.008912 -394.401914) (xy 264.062799 -394.409661) (xy 264.115035 -394.424998)
			(xy 264.164556 -394.447612) (xy 264.210355 -394.477045) (xy 264.251499 -394.512695) (xy 264.287151 -394.553838)
			(xy 264.316584 -394.599637) (xy 264.3392 -394.649158) (xy 264.354537 -394.701393) (xy 264.362285 -394.75528)
			(xy 264.362285 -394.8085) (xy 266.919443 -394.8085) (xy 266.923474 -394.723896) (xy 266.935527 -394.640059)
			(xy 266.955496 -394.557747) (xy 266.983198 -394.477706) (xy 267.018382 -394.40066) (xy 267.060731 -394.327308)
			(xy 267.109861 -394.258313) (xy 267.165326 -394.194301) (xy 267.226625 -394.13585) (xy 267.293203 -394.083491)
			(xy 267.364456 -394.037698) (xy 267.439739 -393.998885) (xy 267.51837 -393.967403) (xy 267.599638 -393.943538)
			(xy 267.682807 -393.927507) (xy 267.767122 -393.919453) (xy 267.809472 -393.918948) (xy 267.850695 -393.919444)
			(xy 267.932787 -393.927077) (xy 268.013822 -393.942269) (xy 268.093103 -393.964892) (xy 268.169953 -393.994751)
			(xy 268.243711 -394.03159) (xy 268.313746 -394.075093) (xy 268.379456 -394.124888) (xy 268.410182 -394.152374)
			(xy 268.417414 -394.158461) (xy 268.435027 -394.165287) (xy 268.453917 -394.165287) (xy 268.47153 -394.158461)
			(xy 268.478762 -394.152374) (xy 268.509471 -394.124866) (xy 268.575178 -394.07506) (xy 268.645212 -394.031548)
			(xy 268.718971 -393.994703) (xy 268.795824 -393.964842) (xy 268.87511 -393.942221) (xy 268.95615 -393.927033)
			(xy 269.038247 -393.91941) (xy 269.079472 -393.918948) (xy 269.120039 -393.919454) (xy 269.200835 -393.92684)
			(xy 269.280624 -393.941554) (xy 269.35874 -393.963472) (xy 269.434536 -393.992414) (xy 269.507381 -394.028138)
			(xy 269.576671 -394.070348) (xy 269.641828 -394.118693) (xy 269.702312 -394.17277) (xy 269.757619 -394.232131)
			(xy 269.807291 -394.296282) (xy 269.850914 -394.36469) (xy 269.86992 -394.400532) (xy 269.897015 -394.401316)
			(xy 269.95059 -394.409555) (xy 270.002462 -394.425283) (xy 270.051591 -394.448184) (xy 270.096989 -394.477799)
			(xy 270.137747 -394.513533) (xy 270.173045 -394.554669) (xy 270.202175 -394.60038) (xy 270.224552 -394.64975)
			(xy 270.239727 -394.701787) (xy 270.247395 -394.755446) (xy 270.247872 -394.782548) (xy 270.24739 -394.8085)
			(xy 272.854328 -394.8085) (xy 272.858359 -394.723891) (xy 272.870414 -394.640048) (xy 272.890384 -394.557731)
			(xy 272.918089 -394.477686) (xy 272.953277 -394.400636) (xy 272.995631 -394.32728) (xy 273.044766 -394.258282)
			(xy 273.100237 -394.194267) (xy 273.161542 -394.135816) (xy 273.228125 -394.083456) (xy 273.299385 -394.037663)
			(xy 273.374675 -393.998851) (xy 273.453313 -393.967372) (xy 273.534587 -393.943511) (xy 273.617762 -393.927483)
			(xy 273.702084 -393.919434) (xy 273.744436 -393.918948) (xy 273.78566 -393.919404) (xy 273.867754 -393.927042)
			(xy 273.948789 -393.942241) (xy 274.028071 -393.964869) (xy 274.10492 -393.994734) (xy 274.178678 -394.031578)
			(xy 274.248712 -394.075086) (xy 274.314421 -394.124886) (xy 274.345146 -394.152374) (xy 274.352378 -394.158461)
			(xy 274.369991 -394.165287) (xy 274.388881 -394.165287) (xy 274.406494 -394.158461) (xy 274.413726 -394.152374)
			(xy 274.44445 -394.124884) (xy 274.510154 -394.075076) (xy 274.580186 -394.031562) (xy 274.653943 -393.994716)
			(xy 274.730794 -393.964852) (xy 274.810078 -393.942228) (xy 274.891116 -393.927038) (xy 274.973211 -393.919412)
			(xy 275.014436 -393.918948) (xy 275.055004 -393.9194) (xy 275.135802 -393.926792) (xy 275.215592 -393.941511)
			(xy 275.293709 -393.963435) (xy 275.369506 -393.992382) (xy 275.442351 -394.028112) (xy 275.51164 -394.070326)
			(xy 275.576797 -394.118675) (xy 275.63728 -394.172757) (xy 275.692586 -394.232122) (xy 275.742257 -394.296277)
			(xy 275.785879 -394.364688) (xy 275.804884 -394.400532) (xy 275.831978 -394.401349) (xy 275.885551 -394.409583)
			(xy 275.937423 -394.425306) (xy 275.986552 -394.448204) (xy 276.031951 -394.477815) (xy 276.072709 -394.513546)
			(xy 276.108007 -394.554678) (xy 276.137138 -394.600387) (xy 276.159515 -394.649755) (xy 276.174691 -394.70179)
			(xy 276.182359 -394.755447) (xy 276.182836 -394.782548) (xy 276.182385 -394.808456) (xy 278.916892 -394.808456)
			(xy 278.917356 -394.766262) (xy 278.925335 -394.682252) (xy 278.941234 -394.599376) (xy 278.964912 -394.518378)
			(xy 278.996156 -394.439987) (xy 279.034684 -394.364908) (xy 279.08015 -394.293815) (xy 279.132146 -394.227349)
			(xy 279.190203 -394.166106) (xy 279.2538 -394.110638) (xy 279.322365 -394.061443) (xy 279.395282 -394.018964)
			(xy 279.471894 -393.983582) (xy 279.551513 -393.955615) (xy 279.633423 -393.935316) (xy 279.675082 -393.9286)
			(xy 279.689459 -393.925944) (xy 279.715949 -393.913606) (xy 279.737852 -393.894262) (xy 279.753368 -393.869499)
			(xy 279.761223 -393.841352) (xy 279.760772 -393.812133) (xy 279.75687 -393.798044) (xy 279.744165 -393.755179)
			(xy 279.726399 -393.667554) (xy 279.717507 -393.578589) (xy 279.716992 -393.533884) (xy 279.717496 -393.491536)
			(xy 279.725547 -393.407222) (xy 279.741576 -393.324056) (xy 279.765437 -393.242789) (xy 279.796916 -393.164159)
			(xy 279.835727 -393.088878) (xy 279.881517 -393.017626) (xy 279.933873 -392.95105) (xy 279.992321 -392.889752)
			(xy 280.056331 -392.834287) (xy 280.125323 -392.785158) (xy 280.198673 -392.742809) (xy 280.275716 -392.707625)
			(xy 280.355755 -392.679923) (xy 280.438064 -392.659955) (xy 280.521899 -392.647902) (xy 280.6065 -392.643872)
			(xy 280.691101 -392.647902) (xy 280.774936 -392.659955) (xy 280.857245 -392.679923) (xy 280.937284 -392.707625)
			(xy 281.014327 -392.742809) (xy 281.087677 -392.785158) (xy 281.156669 -392.834287) (xy 281.220679 -392.889752)
			(xy 281.279127 -392.95105) (xy 281.331483 -393.017626) (xy 281.377273 -393.088878) (xy 281.416084 -393.164159)
			(xy 281.447563 -393.242789) (xy 281.471424 -393.324056) (xy 281.487453 -393.407222) (xy 281.495504 -393.491536)
			(xy 281.496008 -393.533884) (xy 281.495487 -393.576077) (xy 281.487514 -393.660085) (xy 281.47162 -393.74296)
			(xy 281.461756 -393.776708) (xy 289.471608 -393.776708) (xy 289.471608 -393.776454) (xy 289.47211 -393.744493)
			(xy 289.480121 -393.681075) (xy 289.496018 -393.619161) (xy 289.51955 -393.559728) (xy 289.550344 -393.503713)
			(xy 289.587917 -393.451998) (xy 289.631674 -393.405401) (xy 289.680927 -393.364656) (xy 289.734898 -393.330405)
			(xy 289.792737 -393.303188) (xy 289.85353 -393.283435) (xy 289.91632 -393.271457) (xy 289.980116 -393.267444)
			(xy 290.043912 -393.271457) (xy 290.106702 -393.283435) (xy 290.167495 -393.303188) (xy 290.225334 -393.330405)
			(xy 290.279305 -393.364656) (xy 290.328558 -393.405401) (xy 290.372315 -393.451998) (xy 290.409888 -393.503713)
			(xy 290.440682 -393.559728) (xy 290.464214 -393.619161) (xy 290.480111 -393.681075) (xy 290.488122 -393.744493)
			(xy 290.488624 -393.776454) (xy 290.488624 -393.7765) (xy 291.470768 -393.7765) (xy 291.474784 -393.712663)
			(xy 291.48677 -393.649832) (xy 291.506536 -393.589) (xy 291.533771 -393.531124) (xy 291.568045 -393.477118)
			(xy 291.608817 -393.427834) (xy 291.655445 -393.384049) (xy 291.707193 -393.346453) (xy 291.763245 -393.315639)
			(xy 291.822717 -393.292094) (xy 291.884671 -393.276188) (xy 291.94813 -393.268172) (xy 291.980112 -393.267692)
			(xy 292.010658 -393.268138) (xy 292.071311 -393.275449) (xy 292.13065 -393.289975) (xy 292.187822 -393.311508)
			(xy 292.242001 -393.339737) (xy 292.292406 -393.374254) (xy 292.338312 -393.414564) (xy 292.379057 -393.460084)
			(xy 292.396926 -393.484862) (xy 292.405296 -393.496027) (xy 292.426903 -393.51367) (xy 292.452477 -393.52481)
			(xy 292.480111 -393.528618) (xy 292.507745 -393.52481) (xy 292.533319 -393.51367) (xy 292.554926 -393.496027)
			(xy 292.563296 -393.484862) (xy 292.582389 -393.458454) (xy 292.626241 -393.410247) (xy 292.675892 -393.368039)
			(xy 292.730528 -393.332518) (xy 292.789254 -393.304269) (xy 292.851108 -393.283754) (xy 292.915076 -393.271309)
			(xy 292.98011 -393.267138) (xy 293.045144 -393.271309) (xy 293.109112 -393.283754) (xy 293.170966 -393.304269)
			(xy 293.229692 -393.332518) (xy 293.284328 -393.368039) (xy 293.333979 -393.410247) (xy 293.377831 -393.458454)
			(xy 293.396924 -393.484862) (xy 293.405294 -393.496027) (xy 293.426901 -393.51367) (xy 293.452475 -393.52481)
			(xy 293.480109 -393.528618) (xy 293.507743 -393.52481) (xy 293.533317 -393.51367) (xy 293.554924 -393.496027)
			(xy 293.563294 -393.484862) (xy 293.582387 -393.458454) (xy 293.626239 -393.410247) (xy 293.67589 -393.368039)
			(xy 293.730526 -393.332518) (xy 293.789252 -393.304269) (xy 293.851106 -393.283754) (xy 293.915074 -393.271309)
			(xy 293.980108 -393.267138) (xy 294.045142 -393.271309) (xy 294.10911 -393.283754) (xy 294.170964 -393.304269)
			(xy 294.22969 -393.332518) (xy 294.284326 -393.368039) (xy 294.333977 -393.410247) (xy 294.377829 -393.458454)
			(xy 294.396922 -393.484862) (xy 294.405292 -393.496027) (xy 294.426899 -393.51367) (xy 294.452473 -393.52481)
			(xy 294.480107 -393.528618) (xy 294.507741 -393.52481) (xy 294.533315 -393.51367) (xy 294.554922 -393.496027)
			(xy 294.563292 -393.484862) (xy 294.582385 -393.458454) (xy 294.626237 -393.410247) (xy 294.675888 -393.368039)
			(xy 294.730524 -393.332518) (xy 294.78925 -393.304269) (xy 294.851104 -393.283754) (xy 294.915072 -393.271309)
			(xy 294.980106 -393.267138) (xy 295.04514 -393.271309) (xy 295.109108 -393.283754) (xy 295.170962 -393.304269)
			(xy 295.229688 -393.332518) (xy 295.284324 -393.368039) (xy 295.333975 -393.410247) (xy 295.377827 -393.458454)
			(xy 295.39692 -393.484862) (xy 295.40529 -393.496027) (xy 295.426897 -393.51367) (xy 295.452471 -393.52481)
			(xy 295.480105 -393.528618) (xy 295.507739 -393.52481) (xy 295.533313 -393.51367) (xy 295.55492 -393.496027)
			(xy 295.56329 -393.484862) (xy 295.582383 -393.458454) (xy 295.626235 -393.410247) (xy 295.675886 -393.368039)
			(xy 295.730522 -393.332518) (xy 295.789248 -393.304269) (xy 295.851102 -393.283754) (xy 295.91507 -393.271309)
			(xy 295.980104 -393.267138) (xy 296.045138 -393.271309) (xy 296.109106 -393.283754) (xy 296.17096 -393.304269)
			(xy 296.229686 -393.332518) (xy 296.284322 -393.368039) (xy 296.333973 -393.410247) (xy 296.377825 -393.458454)
			(xy 296.396918 -393.484862) (xy 296.405288 -393.496027) (xy 296.426895 -393.51367) (xy 296.452469 -393.52481)
			(xy 296.480103 -393.528618) (xy 296.507737 -393.52481) (xy 296.533311 -393.51367) (xy 296.554918 -393.496027)
			(xy 296.563288 -393.484862) (xy 296.581151 -393.46008) (xy 296.621903 -393.414568) (xy 296.667813 -393.374265)
			(xy 296.71822 -393.339752) (xy 296.772399 -393.311525) (xy 296.829568 -393.289992) (xy 296.888906 -393.275462)
			(xy 296.949557 -393.268144) (xy 296.980102 -393.267692) (xy 297.012076 -393.268286) (xy 297.07552 -393.276301)
			(xy 297.137459 -393.292204) (xy 297.196916 -393.315745) (xy 297.252954 -393.346553) (xy 297.304689 -393.384141)
			(xy 297.351305 -393.427916) (xy 297.392067 -393.477189) (xy 297.426332 -393.531182) (xy 297.45356 -393.589044)
			(xy 297.473321 -393.649863) (xy 297.485304 -393.712678) (xy 297.489319 -393.7765) (xy 297.485304 -393.840322)
			(xy 297.473321 -393.903137) (xy 297.45356 -393.963956) (xy 297.426332 -394.021818) (xy 297.392067 -394.075811)
			(xy 297.351305 -394.125084) (xy 297.304689 -394.168859) (xy 297.252954 -394.206447) (xy 297.196916 -394.237255)
			(xy 297.137459 -394.260796) (xy 297.07552 -394.276699) (xy 297.012076 -394.284714) (xy 296.980102 -394.285216)
			(xy 296.949556 -394.284756) (xy 296.888904 -394.277447) (xy 296.829565 -394.262922) (xy 296.772394 -394.241392)
			(xy 296.718215 -394.213165) (xy 296.667809 -394.178649) (xy 296.621903 -394.138341) (xy 296.581158 -394.092823)
			(xy 296.563288 -394.068046) (xy 296.554946 -394.056837) (xy 296.53336 -394.03911) (xy 296.507771 -394.027912)
			(xy 296.480103 -394.024083) (xy 296.452435 -394.027912) (xy 296.426846 -394.03911) (xy 296.40526 -394.056837)
			(xy 296.396918 -394.068046) (xy 296.377825 -394.094454) (xy 296.333973 -394.142661) (xy 296.284322 -394.184869)
			(xy 296.229686 -394.22039) (xy 296.17096 -394.248639) (xy 296.109106 -394.269154) (xy 296.045138 -394.281599)
			(xy 295.980104 -394.28577) (xy 295.91507 -394.281599) (xy 295.851102 -394.269154) (xy 295.789248 -394.248639)
			(xy 295.730522 -394.22039) (xy 295.675886 -394.184869) (xy 295.626235 -394.142661) (xy 295.582383 -394.094454)
			(xy 295.56329 -394.068046) (xy 295.554948 -394.056837) (xy 295.533362 -394.03911) (xy 295.507773 -394.027912)
			(xy 295.480105 -394.024083) (xy 295.452437 -394.027912) (xy 295.426848 -394.03911) (xy 295.405262 -394.056837)
			(xy 295.39692 -394.068046) (xy 295.377827 -394.094454) (xy 295.333975 -394.142661) (xy 295.284324 -394.184869)
			(xy 295.229688 -394.22039) (xy 295.170962 -394.248639) (xy 295.109108 -394.269154) (xy 295.04514 -394.281599)
			(xy 294.980106 -394.28577) (xy 294.915072 -394.281599) (xy 294.851104 -394.269154) (xy 294.78925 -394.248639)
			(xy 294.730524 -394.22039) (xy 294.675888 -394.184869) (xy 294.626237 -394.142661) (xy 294.582385 -394.094454)
			(xy 294.563292 -394.068046) (xy 294.55495 -394.056837) (xy 294.533364 -394.03911) (xy 294.507775 -394.027912)
			(xy 294.480107 -394.024083) (xy 294.452439 -394.027912) (xy 294.42685 -394.03911) (xy 294.405264 -394.056837)
			(xy 294.396922 -394.068046) (xy 294.377829 -394.094454) (xy 294.333977 -394.142661) (xy 294.284326 -394.184869)
			(xy 294.22969 -394.22039) (xy 294.170964 -394.248639) (xy 294.10911 -394.269154) (xy 294.045142 -394.281599)
			(xy 293.980108 -394.28577) (xy 293.915074 -394.281599) (xy 293.851106 -394.269154) (xy 293.789252 -394.248639)
			(xy 293.730526 -394.22039) (xy 293.67589 -394.184869) (xy 293.626239 -394.142661) (xy 293.582387 -394.094454)
			(xy 293.563294 -394.068046) (xy 293.554952 -394.056837) (xy 293.533366 -394.03911) (xy 293.507777 -394.027912)
			(xy 293.480109 -394.024083) (xy 293.452441 -394.027912) (xy 293.426852 -394.03911) (xy 293.405266 -394.056837)
			(xy 293.396924 -394.068046) (xy 293.377831 -394.094454) (xy 293.333979 -394.142661) (xy 293.284328 -394.184869)
			(xy 293.229692 -394.22039) (xy 293.170966 -394.248639) (xy 293.109112 -394.269154) (xy 293.045144 -394.281599)
			(xy 292.98011 -394.28577) (xy 292.915076 -394.281599) (xy 292.851108 -394.269154) (xy 292.789254 -394.248639)
			(xy 292.730528 -394.22039) (xy 292.675892 -394.184869) (xy 292.626241 -394.142661) (xy 292.582389 -394.094454)
			(xy 292.563296 -394.068046) (xy 292.554954 -394.056837) (xy 292.533368 -394.03911) (xy 292.507779 -394.027912)
			(xy 292.480111 -394.024083) (xy 292.452443 -394.027912) (xy 292.426854 -394.03911) (xy 292.405268 -394.056837)
			(xy 292.396926 -394.068046) (xy 292.379057 -394.092823) (xy 292.338306 -394.138335) (xy 292.292396 -394.178638)
			(xy 292.24199 -394.213151) (xy 292.187812 -394.241378) (xy 292.130644 -394.262913) (xy 292.071307 -394.277444)
			(xy 292.010657 -394.284763) (xy 291.980112 -394.285216) (xy 291.94813 -394.284828) (xy 291.884671 -394.276812)
			(xy 291.822717 -394.260906) (xy 291.763245 -394.237361) (xy 291.707193 -394.206547) (xy 291.655445 -394.168951)
			(xy 291.608817 -394.125166) (xy 291.568045 -394.075882) (xy 291.533771 -394.021876) (xy 291.506536 -393.964)
			(xy 291.48677 -393.903168) (xy 291.474784 -393.840337) (xy 291.470768 -393.7765) (xy 290.488624 -393.7765)
			(xy 290.488624 -393.776962) (xy 290.488202 -393.806564) (xy 290.481324 -393.865367) (xy 290.467658 -393.922971)
			(xy 290.447389 -393.978597) (xy 290.420792 -394.03149) (xy 290.388226 -394.080932) (xy 290.369498 -394.10386)
			(xy 290.389588 -394.127178) (xy 290.424612 -394.17779) (xy 290.453267 -394.232263) (xy 290.475133 -394.289797)
			(xy 290.48989 -394.349552) (xy 290.497321 -394.410651) (xy 290.497768 -394.441426) (xy 290.497768 -394.44168)
			(xy 290.497266 -394.473641) (xy 290.489255 -394.537059) (xy 290.473358 -394.598973) (xy 290.449826 -394.658406)
			(xy 290.419032 -394.714421) (xy 290.381459 -394.766136) (xy 290.337702 -394.812733) (xy 290.288449 -394.853478)
			(xy 290.234478 -394.887729) (xy 290.176639 -394.914946) (xy 290.115846 -394.934699) (xy 290.053056 -394.946677)
			(xy 289.98926 -394.950691) (xy 289.925464 -394.946677) (xy 289.862674 -394.934699) (xy 289.801881 -394.914946)
			(xy 289.744042 -394.887729) (xy 289.690071 -394.853478) (xy 289.640818 -394.812733) (xy 289.597061 -394.766136)
			(xy 289.559488 -394.714421) (xy 289.528694 -394.658406) (xy 289.505162 -394.598973) (xy 289.489265 -394.537059)
			(xy 289.481254 -394.473641) (xy 289.480752 -394.44168) (xy 289.480752 -394.441172) (xy 289.481141 -394.411569)
			(xy 289.488026 -394.352765) (xy 289.501699 -394.29516) (xy 289.521974 -394.239535) (xy 289.548577 -394.186643)
			(xy 289.581148 -394.137202) (xy 289.599878 -394.114274) (xy 289.579769 -394.090972) (xy 289.544745 -394.040357)
			(xy 289.516091 -393.985882) (xy 289.494228 -393.928344) (xy 289.479476 -393.868586) (xy 289.472051 -393.807484)
			(xy 289.471608 -393.776708) (xy 281.461756 -393.776708) (xy 281.447947 -393.823957) (xy 281.416708 -393.902348)
			(xy 281.378185 -393.977427) (xy 281.332723 -394.04852) (xy 281.280732 -394.114986) (xy 281.222678 -394.176229)
			(xy 281.159084 -394.231698) (xy 281.090523 -394.280894) (xy 281.017609 -394.323374) (xy 280.941 -394.358757)
			(xy 280.861383 -394.386724) (xy 280.779476 -394.407024) (xy 280.737818 -394.41374) (xy 280.72343 -394.416347)
			(xy 280.696933 -394.428691) (xy 280.675026 -394.448046) (xy 280.659511 -394.472819) (xy 280.651661 -394.500977)
			(xy 280.652122 -394.530204) (xy 280.65603 -394.544296) (xy 280.668744 -394.587158) (xy 280.686507 -394.674785)
			(xy 280.695395 -394.763751) (xy 280.695908 -394.808456) (xy 280.695404 -394.850804) (xy 280.687353 -394.935118)
			(xy 280.671324 -395.018284) (xy 280.647463 -395.099551) (xy 280.615984 -395.178181) (xy 280.577173 -395.253462)
			(xy 280.531383 -395.324714) (xy 280.479027 -395.39129) (xy 280.420579 -395.452588) (xy 280.356569 -395.508053)
			(xy 280.287577 -395.557182) (xy 280.214227 -395.599531) (xy 280.137184 -395.634715) (xy 280.057145 -395.662417)
			(xy 279.974836 -395.682385) (xy 279.891001 -395.694438) (xy 279.8064 -395.698469) (xy 279.721799 -395.694438)
			(xy 279.637964 -395.682385) (xy 279.555655 -395.662417) (xy 279.475616 -395.634715) (xy 279.398573 -395.599531)
			(xy 279.325223 -395.557182) (xy 279.256231 -395.508053) (xy 279.192221 -395.452588) (xy 279.133773 -395.39129)
			(xy 279.081417 -395.324714) (xy 279.035627 -395.253462) (xy 278.996816 -395.178181) (xy 278.965337 -395.099551)
			(xy 278.941476 -395.018284) (xy 278.925447 -394.935118) (xy 278.917396 -394.850804) (xy 278.916892 -394.808456)
			(xy 276.182385 -394.808456) (xy 276.182339 -394.81111) (xy 276.173854 -394.867601) (xy 276.157051 -394.922198)
			(xy 276.132304 -394.973684) (xy 276.100165 -395.02091) (xy 276.061351 -395.062822) (xy 276.016728 -395.098487)
			(xy 275.967291 -395.127109) (xy 275.914142 -395.148048) (xy 275.858468 -395.160839) (xy 275.83003 -395.163548)
			(xy 275.812369 -395.202766) (xy 275.770577 -395.277947) (xy 275.721724 -395.348744) (xy 275.666266 -395.414494)
			(xy 275.60472 -395.474584) (xy 275.537661 -395.528453) (xy 275.465716 -395.575598) (xy 275.389556 -395.615578)
			(xy 275.309893 -395.648021) (xy 275.22747 -395.672622) (xy 275.143058 -395.689153) (xy 275.057444 -395.697459)
			(xy 275.014436 -395.697964) (xy 274.973213 -395.69746) (xy 274.891121 -395.689828) (xy 274.810087 -395.674636)
			(xy 274.730806 -395.652015) (xy 274.653956 -395.622157) (xy 274.580198 -395.585319) (xy 274.510163 -395.541817)
			(xy 274.444452 -395.492024) (xy 274.413726 -395.464538) (xy 274.406494 -395.458451) (xy 274.388881 -395.451625)
			(xy 274.369991 -395.451625) (xy 274.352378 -395.458451) (xy 274.345146 -395.464538) (xy 274.314435 -395.492044)
			(xy 274.248729 -395.54185) (xy 274.178695 -395.585362) (xy 274.104936 -395.622207) (xy 274.028083 -395.652068)
			(xy 273.948797 -395.67469) (xy 273.867758 -395.689878) (xy 273.785661 -395.697501) (xy 273.744436 -395.697964)
			(xy 273.702084 -395.697566) (xy 273.617762 -395.689517) (xy 273.534587 -395.673489) (xy 273.453313 -395.649628)
			(xy 273.374675 -395.618149) (xy 273.299385 -395.579337) (xy 273.228125 -395.533544) (xy 273.161542 -395.481184)
			(xy 273.100237 -395.422733) (xy 273.044766 -395.358718) (xy 272.995631 -395.28972) (xy 272.953277 -395.216364)
			(xy 272.918089 -395.139314) (xy 272.890384 -395.059269) (xy 272.870414 -394.976952) (xy 272.858359 -394.893109)
			(xy 272.854328 -394.8085) (xy 270.24739 -394.8085) (xy 270.247342 -394.811109) (xy 270.238858 -394.867596)
			(xy 270.222057 -394.922191) (xy 270.197312 -394.973674) (xy 270.165177 -395.020899) (xy 270.126367 -395.062811)
			(xy 270.081748 -395.098476) (xy 270.032316 -395.127099) (xy 269.979172 -395.148042) (xy 269.923503 -395.160836)
			(xy 269.895066 -395.163548) (xy 269.877376 -395.202752) (xy 269.835586 -395.277933) (xy 269.786736 -395.348729)
			(xy 269.73128 -395.414479) (xy 269.669737 -395.474569) (xy 269.602681 -395.528439) (xy 269.530739 -395.575585)
			(xy 269.454582 -395.615566) (xy 269.374921 -395.648011) (xy 269.292501 -395.672615) (xy 269.208091 -395.689148)
			(xy 269.122479 -395.697457) (xy 269.079472 -395.697964) (xy 269.038248 -395.6975) (xy 268.956155 -395.689862)
			(xy 268.87512 -395.674665) (xy 268.795838 -395.652037) (xy 268.718989 -395.622174) (xy 268.645231 -395.585331)
			(xy 268.575197 -395.541824) (xy 268.509487 -395.492026) (xy 268.478762 -395.464538) (xy 268.47153 -395.458451)
			(xy 268.453917 -395.451625) (xy 268.435027 -395.451625) (xy 268.417414 -395.458451) (xy 268.410182 -395.464538)
			(xy 268.379456 -395.492026) (xy 268.313752 -395.541834) (xy 268.243721 -395.585348) (xy 268.169964 -395.622194)
			(xy 268.093113 -395.652058) (xy 268.013829 -395.674682) (xy 267.932792 -395.689873) (xy 267.850696 -395.6975)
			(xy 267.809472 -395.697964) (xy 267.767122 -395.697547) (xy 267.682807 -395.689493) (xy 267.599638 -395.673462)
			(xy 267.51837 -395.649597) (xy 267.439739 -395.618115) (xy 267.364456 -395.579302) (xy 267.293203 -395.533509)
			(xy 267.226625 -395.48115) (xy 267.165326 -395.422699) (xy 267.109861 -395.358687) (xy 267.060731 -395.289692)
			(xy 267.018382 -395.21634) (xy 266.983198 -395.139294) (xy 266.955496 -395.059253) (xy 266.935527 -394.976941)
			(xy 266.923474 -394.893104) (xy 266.919443 -394.8085) (xy 264.362285 -394.8085) (xy 264.362285 -394.80972)
			(xy 264.354537 -394.863607) (xy 264.3392 -394.915842) (xy 264.316584 -394.965363) (xy 264.287151 -395.011162)
			(xy 264.251499 -395.052305) (xy 264.210355 -395.087955) (xy 264.164556 -395.117388) (xy 264.115035 -395.140002)
			(xy 264.062799 -395.155339) (xy 264.008912 -395.163086) (xy 263.981692 -395.163548) (xy 263.960356 -395.16304)
			(xy 263.942674 -395.202274) (xy 263.9009 -395.277517) (xy 263.852055 -395.348375) (xy 263.796597 -395.414185)
			(xy 263.735042 -395.474332) (xy 263.667968 -395.528254) (xy 263.596 -395.575447) (xy 263.519811 -395.61547)
			(xy 263.440113 -395.647949) (xy 263.357652 -395.67258) (xy 263.273197 -395.689134) (xy 263.187539 -395.697455)
			(xy 263.144508 -395.697964) (xy 263.103285 -395.697477) (xy 263.021192 -395.689843) (xy 262.940158 -395.674649)
			(xy 262.860876 -395.652025) (xy 262.784027 -395.622164) (xy 262.710269 -395.585324) (xy 262.640234 -395.54182)
			(xy 262.574524 -395.492025) (xy 262.543798 -395.464538) (xy 262.536566 -395.458451) (xy 262.518953 -395.451625)
			(xy 262.500063 -395.451625) (xy 262.48245 -395.458451) (xy 262.475218 -395.464538) (xy 262.444477 -395.492009)
			(xy 262.378775 -395.541818) (xy 262.308747 -395.585333) (xy 262.234992 -395.622182) (xy 262.158144 -395.652048)
			(xy 262.078861 -395.674675) (xy 261.997826 -395.689868) (xy 261.915732 -395.697498) (xy 261.874508 -395.697964)
			(xy 261.832156 -395.697564) (xy 261.747837 -395.689513) (xy 261.664664 -395.673484) (xy 261.583392 -395.649621)
			(xy 261.504756 -395.61814) (xy 261.429469 -395.579328) (xy 261.358212 -395.533534) (xy 261.29163 -395.481174)
			(xy 261.230327 -395.422723) (xy 261.174858 -395.358709) (xy 261.125725 -395.289712) (xy 261.083374 -395.216357)
			(xy 261.048186 -395.139308) (xy 261.020483 -395.059264) (xy 261.000513 -394.976948) (xy 260.988458 -394.893107)
			(xy 260.984428 -394.8085) (xy 258.448577 -394.8085) (xy 258.448577 -394.809789) (xy 258.440811 -394.863811)
			(xy 258.425436 -394.916178) (xy 258.402765 -394.965824) (xy 258.37326 -395.011739) (xy 258.337522 -395.052988)
			(xy 258.296278 -395.088732) (xy 258.250366 -395.118242) (xy 258.200723 -395.140919) (xy 258.148358 -395.156301)
			(xy 258.094337 -395.164074) (xy 258.067048 -395.164564) (xy 258.056676 -395.164479) (xy 258.035964 -395.163337)
			(xy 258.025646 -395.162278) (xy 258.008 -395.201564) (xy 257.966267 -395.276906) (xy 257.917448 -395.347861)
			(xy 257.861999 -395.413765) (xy 257.80044 -395.474001) (xy 257.733346 -395.528004) (xy 257.661347 -395.575269)
			(xy 257.585116 -395.615354) (xy 257.505368 -395.647883) (xy 257.422848 -395.672551) (xy 257.338331 -395.689127)
			(xy 257.252608 -395.697456) (xy 257.209544 -395.697964) (xy 257.168321 -395.697455) (xy 257.08623 -395.689824)
			(xy 257.005196 -395.674633) (xy 256.925914 -395.652012) (xy 256.849065 -395.622155) (xy 256.775306 -395.585317)
			(xy 256.705271 -395.541816) (xy 256.63956 -395.492023) (xy 256.608834 -395.464538) (xy 256.601602 -395.458451)
			(xy 256.583989 -395.451625) (xy 256.565099 -395.451625) (xy 256.547486 -395.458451) (xy 256.540254 -395.464538)
			(xy 256.50954 -395.49204) (xy 256.443834 -395.541846) (xy 256.373801 -395.585359) (xy 256.300042 -395.622204)
			(xy 256.22319 -395.652066) (xy 256.143904 -395.674688) (xy 256.062865 -395.689877) (xy 255.980769 -395.697501)
			(xy 255.939544 -395.697964) (xy 255.897191 -395.697566) (xy 255.812869 -395.689518) (xy 255.729694 -395.673491)
			(xy 255.648419 -395.64963) (xy 255.56978 -395.618151) (xy 255.494489 -395.57934) (xy 255.423229 -395.533547)
			(xy 255.356645 -395.481187) (xy 255.295339 -395.422735) (xy 255.239868 -395.358721) (xy 255.190732 -395.289723)
			(xy 255.148379 -395.216366) (xy 255.11319 -395.139316) (xy 255.085484 -395.05927) (xy 255.065514 -394.976952)
			(xy 255.053459 -394.893109) (xy 255.049428 -394.8085) (xy 252.466916 -394.8085) (xy 252.466897 -394.809592)
			(xy 252.459254 -394.863136) (xy 252.444116 -394.915061) (xy 252.421785 -394.964324) (xy 252.392711 -395.009932)
			(xy 252.357479 -395.05097) (xy 252.316797 -395.086613) (xy 252.271483 -395.116143) (xy 252.222447 -395.138967)
			(xy 252.170677 -395.154627) (xy 252.117212 -395.162807) (xy 252.090174 -395.163548) (xy 252.072477 -395.202749)
			(xy 252.030688 -395.27793) (xy 251.981838 -395.348725) (xy 251.926383 -395.414475) (xy 251.864841 -395.474566)
			(xy 251.797785 -395.528436) (xy 251.725844 -395.575582) (xy 251.649687 -395.615564) (xy 251.570027 -395.648009)
			(xy 251.487608 -395.672613) (xy 251.403198 -395.689147) (xy 251.317587 -395.697457) (xy 251.27458 -395.697964)
			(xy 251.233356 -395.697495) (xy 251.151263 -395.689858) (xy 251.070228 -395.674661) (xy 250.990947 -395.652035)
			(xy 250.914097 -395.622172) (xy 250.840339 -395.58533) (xy 250.770305 -395.541823) (xy 250.704595 -395.492026)
			(xy 250.67387 -395.464538) (xy 250.666638 -395.458451) (xy 250.649025 -395.451625) (xy 250.630135 -395.451625)
			(xy 250.612522 -395.458451) (xy 250.60529 -395.464538) (xy 250.574561 -395.492023) (xy 250.508857 -395.54183)
			(xy 250.438827 -395.585344) (xy 250.36507 -395.622192) (xy 250.28822 -395.652056) (xy 250.208936 -395.67468)
			(xy 250.127899 -395.689872) (xy 250.045804 -395.697499) (xy 250.00458 -395.697964) (xy 249.96223 -395.697547)
			(xy 249.877914 -395.689494) (xy 249.794745 -395.673463) (xy 249.713476 -395.649599) (xy 249.634844 -395.618118)
			(xy 249.55956 -395.579305) (xy 249.488307 -395.533512) (xy 249.421729 -395.481153) (xy 249.360429 -395.422702)
			(xy 249.304963 -395.35869) (xy 249.255833 -395.289695) (xy 249.213483 -395.216342) (xy 249.178298 -395.139296)
			(xy 249.150596 -395.059254) (xy 249.130628 -394.976942) (xy 249.118574 -394.893104) (xy 249.114543 -394.8085)
			(xy 246.507582 -394.8085) (xy 246.507538 -394.811111) (xy 246.499052 -394.867604) (xy 246.482248 -394.922202)
			(xy 246.457499 -394.973689) (xy 246.425358 -395.020916) (xy 246.386542 -395.062829) (xy 246.341916 -395.098493)
			(xy 246.292476 -395.127114) (xy 246.239326 -395.148052) (xy 246.183649 -395.16084) (xy 246.15521 -395.163548)
			(xy 246.137565 -395.202774) (xy 246.095772 -395.277955) (xy 246.046918 -395.348752) (xy 245.991458 -395.414502)
			(xy 245.929911 -395.474592) (xy 245.86285 -395.528461) (xy 245.790904 -395.575605) (xy 245.714742 -395.615585)
			(xy 245.635078 -395.648026) (xy 245.552653 -395.672626) (xy 245.46824 -395.689156) (xy 245.382624 -395.69746)
			(xy 245.339616 -395.697964) (xy 245.298393 -395.697472) (xy 245.216301 -395.689839) (xy 245.135266 -395.674645)
			(xy 245.055985 -395.652022) (xy 244.979135 -395.622162) (xy 244.905377 -395.585323) (xy 244.835342 -395.541819)
			(xy 244.769632 -395.492024) (xy 244.738906 -395.464538) (xy 244.731674 -395.458451) (xy 244.714061 -395.451625)
			(xy 244.695171 -395.451625) (xy 244.677558 -395.458451) (xy 244.670326 -395.464538) (xy 244.639624 -395.492053)
			(xy 244.573916 -395.541859) (xy 244.503881 -395.58537) (xy 244.43012 -395.622214) (xy 244.353266 -395.652074)
			(xy 244.273979 -395.674694) (xy 244.192939 -395.68988) (xy 244.110841 -395.697502) (xy 244.069616 -395.697964)
			(xy 244.027264 -395.697565) (xy 243.942944 -395.689514) (xy 243.859771 -395.673485) (xy 243.778498 -395.649623)
			(xy 243.699861 -395.618143) (xy 243.624573 -395.57933) (xy 243.553315 -395.533537) (xy 243.486733 -395.481177)
			(xy 243.42543 -395.422726) (xy 243.36996 -395.358711) (xy 243.320827 -395.289714) (xy 243.278475 -395.216359)
			(xy 243.243287 -395.13931) (xy 243.215583 -395.059265) (xy 243.195613 -394.976949) (xy 243.183558 -394.893108)
			(xy 243.179528 -394.8085) (xy 2.509012 -394.8085) (xy 2.509012 -396.842996) (xy 18.90268 -396.842996)
			(xy 18.90268 -395.979396) (xy 18.903166 -395.952145) (xy 18.910922 -395.898197) (xy 18.926277 -395.845902)
			(xy 18.948919 -395.796325) (xy 18.978385 -395.750475) (xy 19.014076 -395.709284) (xy 19.055267 -395.673593)
			(xy 19.101117 -395.644127) (xy 19.150694 -395.621485) (xy 19.202989 -395.60613) (xy 19.256937 -395.598374)
			(xy 19.311439 -395.598374) (xy 19.365387 -395.60613) (xy 19.417682 -395.621485) (xy 19.467259 -395.644127)
			(xy 19.513109 -395.673593) (xy 19.5543 -395.709284) (xy 19.589991 -395.750475) (xy 19.601933 -395.769057)
			(xy 288.471858 -395.769057) (xy 288.471858 -395.705103) (xy 288.479873 -395.641653) (xy 288.495778 -395.579708)
			(xy 288.519321 -395.520246) (xy 288.550131 -395.464202) (xy 288.587723 -395.412462) (xy 288.631502 -395.365842)
			(xy 288.68078 -395.325076) (xy 288.734778 -395.290808) (xy 288.792645 -395.263577) (xy 288.853469 -395.243814)
			(xy 288.91629 -395.231831) (xy 288.980118 -395.227815) (xy 289.043946 -395.231831) (xy 289.106767 -395.243814)
			(xy 289.167591 -395.263577) (xy 289.225458 -395.290808) (xy 289.279456 -395.325076) (xy 289.328734 -395.365842)
			(xy 289.372513 -395.412462) (xy 289.410105 -395.464202) (xy 289.440915 -395.520246) (xy 289.464458 -395.579708)
			(xy 289.480363 -395.641653) (xy 289.488378 -395.705103) (xy 289.48888 -395.73708) (xy 289.488378 -395.769057)
			(xy 289.480363 -395.832507) (xy 289.464458 -395.894452) (xy 289.440915 -395.953914) (xy 289.410105 -396.009958)
			(xy 289.372513 -396.061698) (xy 289.328734 -396.108318) (xy 289.279456 -396.149084) (xy 289.225458 -396.183352)
			(xy 289.167591 -396.210583) (xy 289.106767 -396.230346) (xy 289.043946 -396.242329) (xy 288.980118 -396.246345)
			(xy 288.91629 -396.242329) (xy 288.853469 -396.230346) (xy 288.792645 -396.210583) (xy 288.734778 -396.183352)
			(xy 288.68078 -396.149084) (xy 288.631502 -396.108318) (xy 288.587723 -396.061698) (xy 288.550131 -396.009958)
			(xy 288.519321 -395.953914) (xy 288.495778 -395.894452) (xy 288.479873 -395.832507) (xy 288.471858 -395.769057)
			(xy 19.601933 -395.769057) (xy 19.619457 -395.796325) (xy 19.642099 -395.845902) (xy 19.657454 -395.898197)
			(xy 19.66521 -395.952145) (xy 19.665696 -395.979396) (xy 19.665696 -396.842996) (xy 19.66521 -396.870247)
			(xy 19.657454 -396.924195) (xy 19.642099 -396.97649) (xy 19.619457 -397.026067) (xy 19.589991 -397.071917)
			(xy 19.5543 -397.113108) (xy 19.513109 -397.148799) (xy 19.467259 -397.178265) (xy 19.417682 -397.200907)
			(xy 19.365387 -397.216262) (xy 19.311439 -397.224018) (xy 19.256937 -397.224018) (xy 19.202989 -397.216262)
			(xy 19.150694 -397.200907) (xy 19.101117 -397.178265) (xy 19.055267 -397.148799) (xy 19.014076 -397.113108)
			(xy 18.978385 -397.071917) (xy 18.948919 -397.026067) (xy 18.926277 -396.97649) (xy 18.910922 -396.924195)
			(xy 18.903166 -396.870247) (xy 18.90268 -396.842996) (xy 2.509012 -396.842996) (xy 2.509012 -397.606012)
			(xy 24.954992 -397.606012) (xy 24.954992 -396.742412) (xy 24.955478 -396.715161) (xy 24.963234 -396.661213)
			(xy 24.978589 -396.608918) (xy 25.001231 -396.559341) (xy 25.030697 -396.513491) (xy 25.066388 -396.4723)
			(xy 25.107579 -396.436609) (xy 25.153429 -396.407143) (xy 25.203006 -396.384501) (xy 25.255301 -396.369146)
			(xy 25.309249 -396.36139) (xy 25.363751 -396.36139) (xy 25.417699 -396.369146) (xy 25.469994 -396.384501)
			(xy 25.519571 -396.407143) (xy 25.565421 -396.436609) (xy 25.606612 -396.4723) (xy 25.642303 -396.513491)
			(xy 25.671769 -396.559341) (xy 25.694411 -396.608918) (xy 25.709766 -396.661213) (xy 25.717522 -396.715161)
			(xy 25.718008 -396.742412) (xy 25.718008 -397.606012) (xy 25.717522 -397.633263) (xy 25.709766 -397.687211)
			(xy 25.694411 -397.739506) (xy 25.671769 -397.789083) (xy 25.642303 -397.834933) (xy 25.606612 -397.876124)
			(xy 25.565421 -397.911815) (xy 25.519571 -397.941281) (xy 25.469994 -397.963923) (xy 25.417699 -397.979278)
			(xy 25.363751 -397.987034) (xy 25.309249 -397.987034) (xy 25.255301 -397.979278) (xy 25.203006 -397.963923)
			(xy 25.153429 -397.941281) (xy 25.107579 -397.911815) (xy 25.066388 -397.876124) (xy 25.030697 -397.834933)
			(xy 25.001231 -397.789083) (xy 24.978589 -397.739506) (xy 24.963234 -397.687211) (xy 24.955478 -397.633263)
			(xy 24.954992 -397.606012) (xy 2.509012 -397.606012) (xy 2.509012 -398.68657) (xy 36.781952 -398.68657)
			(xy 36.781952 -398.63203) (xy 36.789714 -398.578046) (xy 36.805081 -398.525717) (xy 36.827739 -398.476107)
			(xy 36.857227 -398.430227) (xy 36.892945 -398.389011) (xy 36.934165 -398.353298) (xy 36.980049 -398.323816)
			(xy 37.029662 -398.301164) (xy 37.081993 -398.285804) (xy 37.135978 -398.278048) (xy 37.163248 -398.277588)
			(xy 38.026848 -398.277588) (xy 38.054119 -398.277978) (xy 38.108104 -398.285746) (xy 38.160435 -398.301118)
			(xy 38.210045 -398.323779) (xy 38.255926 -398.353271) (xy 38.297144 -398.38899) (xy 38.332858 -398.430212)
			(xy 38.362344 -398.476097) (xy 38.384999 -398.52571) (xy 38.400364 -398.578043) (xy 38.408126 -398.632029)
			(xy 38.408126 -398.686571) (xy 38.400364 -398.740557) (xy 38.384999 -398.79289) (xy 38.38214 -398.799152)
			(xy 42.10455 -398.799152) (xy 42.10455 -398.744648) (xy 42.112306 -398.6907) (xy 42.12766 -398.638404)
			(xy 42.150301 -398.588826) (xy 42.179766 -398.542974) (xy 42.215456 -398.501781) (xy 42.256645 -398.466087)
			(xy 42.302494 -398.436618) (xy 42.35207 -398.413973) (xy 42.404365 -398.398614) (xy 42.458312 -398.390852)
			(xy 42.485564 -398.390364) (xy 43.349164 -398.390364) (xy 43.376417 -398.390881) (xy 43.430367 -398.398633)
			(xy 43.482666 -398.413985) (xy 43.532247 -398.436624) (xy 43.578101 -398.466088) (xy 43.619295 -398.50178)
			(xy 43.65499 -398.54297) (xy 43.684459 -398.588822) (xy 43.707103 -398.638401) (xy 43.722459 -398.690697)
			(xy 43.730217 -398.744648) (xy 43.730217 -398.799152) (xy 43.722459 -398.853103) (xy 43.707103 -398.9054)
			(xy 43.684459 -398.954978) (xy 43.65499 -399.00083) (xy 43.619295 -399.04202) (xy 43.578101 -399.077712)
			(xy 43.532247 -399.107176) (xy 43.482666 -399.129815) (xy 43.430367 -399.145167) (xy 43.376417 -399.152919)
			(xy 43.349164 -399.15338) (xy 42.485564 -399.15338) (xy 42.458312 -399.152948) (xy 42.404365 -399.145186)
			(xy 42.35207 -399.129827) (xy 42.302494 -399.107182) (xy 42.256645 -399.077713) (xy 42.215456 -399.042019)
			(xy 42.179766 -399.000826) (xy 42.150301 -398.954974) (xy 42.12766 -398.905396) (xy 42.112306 -398.8531)
			(xy 42.10455 -398.799152) (xy 38.38214 -398.799152) (xy 38.362344 -398.842503) (xy 38.332858 -398.888388)
			(xy 38.297144 -398.92961) (xy 38.255926 -398.965329) (xy 38.210045 -398.994821) (xy 38.160435 -399.017482)
			(xy 38.108104 -399.032854) (xy 38.054119 -399.040622) (xy 38.026848 -399.041112) (xy 37.163248 -399.041112)
			(xy 37.135978 -399.040552) (xy 37.081993 -399.032796) (xy 37.029662 -399.017436) (xy 36.980049 -398.994784)
			(xy 36.934165 -398.965302) (xy 36.892945 -398.929589) (xy 36.857227 -398.888373) (xy 36.827739 -398.842493)
			(xy 36.805081 -398.792883) (xy 36.789714 -398.740554) (xy 36.781952 -398.68657) (xy 2.509012 -398.68657)
			(xy 2.509012 -399.443249) (xy 18.470394 -399.443249) (xy 18.470394 -399.388751) (xy 18.47815 -399.334808)
			(xy 18.493503 -399.282518) (xy 18.516141 -399.232945) (xy 18.545603 -399.187098) (xy 18.58129 -399.14591)
			(xy 18.622475 -399.11022) (xy 18.66832 -399.080754) (xy 18.717892 -399.058112) (xy 18.770181 -399.042756)
			(xy 18.824123 -399.034996) (xy 18.851372 -399.034508) (xy 19.714972 -399.034508) (xy 19.742227 -399.034937)
			(xy 19.796184 -399.042691) (xy 19.848487 -399.058045) (xy 19.898073 -399.080687) (xy 19.943931 -399.110156)
			(xy 19.985129 -399.145851) (xy 20.020827 -399.187046) (xy 20.050299 -399.232903) (xy 20.072945 -399.282487)
			(xy 20.088303 -399.334789) (xy 20.096061 -399.388745) (xy 20.096061 -399.443255) (xy 20.088303 -399.497211)
			(xy 20.072945 -399.549513) (xy 20.050299 -399.599097) (xy 20.020828 -399.644954) (xy 19.985129 -399.686149)
			(xy 19.943931 -399.721844) (xy 19.898073 -399.751313) (xy 19.848487 -399.773955) (xy 19.796184 -399.789309)
			(xy 19.742227 -399.797063) (xy 19.714972 -399.797524) (xy 18.851372 -399.797524) (xy 18.824123 -399.797004)
			(xy 18.770181 -399.789244) (xy 18.717892 -399.773888) (xy 18.66832 -399.751246) (xy 18.622475 -399.72178)
			(xy 18.58129 -399.68609) (xy 18.545603 -399.644902) (xy 18.516141 -399.599055) (xy 18.493503 -399.549482)
			(xy 18.47815 -399.497192) (xy 18.470394 -399.443249) (xy 2.509012 -399.443249) (xy 2.509012 -400.459248)
			(xy 25.590794 -400.459248) (xy 25.590794 -400.404752) (xy 25.598549 -400.350811) (xy 25.613901 -400.298522)
			(xy 25.636538 -400.24895) (xy 25.665999 -400.203104) (xy 25.701684 -400.161916) (xy 25.742867 -400.126226)
			(xy 25.788709 -400.09676) (xy 25.838279 -400.074117) (xy 25.890566 -400.058759) (xy 25.944506 -400.050997)
			(xy 25.971754 -400.050508) (xy 26.835354 -400.050508) (xy 26.86261 -400.050936) (xy 26.916568 -400.058688)
			(xy 26.968874 -400.07404) (xy 27.018462 -400.096681) (xy 27.064323 -400.126149) (xy 27.105523 -400.161845)
			(xy 27.141223 -400.20304) (xy 27.170697 -400.248897) (xy 27.193343 -400.298483) (xy 27.208702 -400.350787)
			(xy 27.216461 -400.404744) (xy 27.216461 -400.459256) (xy 27.208702 -400.513213) (xy 27.193343 -400.565517)
			(xy 27.170697 -400.615103) (xy 27.141223 -400.66096) (xy 27.105523 -400.702155) (xy 27.064323 -400.737851)
			(xy 27.018462 -400.767319) (xy 26.968874 -400.78996) (xy 26.916568 -400.805312) (xy 26.86261 -400.813064)
			(xy 26.835354 -400.813524) (xy 25.971754 -400.813524) (xy 25.944506 -400.813003) (xy 25.890566 -400.805241)
			(xy 25.838279 -400.789883) (xy 25.788709 -400.76724) (xy 25.742867 -400.737774) (xy 25.701684 -400.702084)
			(xy 25.665999 -400.660896) (xy 25.636538 -400.61505) (xy 25.613901 -400.565478) (xy 25.598549 -400.513189)
			(xy 25.590794 -400.459248) (xy 2.509012 -400.459248) (xy 2.509012 -400.885453) (xy 47.598783 -400.885453)
			(xy 47.598783 -400.830947) (xy 47.606541 -400.776997) (xy 47.621898 -400.7247) (xy 47.644541 -400.675121)
			(xy 47.674011 -400.629269) (xy 47.709706 -400.588079) (xy 47.7509 -400.552388) (xy 47.796754 -400.522923)
			(xy 47.846336 -400.500284) (xy 47.898634 -400.484933) (xy 47.952585 -400.477181) (xy 47.979838 -400.47672)
			(xy 48.843438 -400.47672) (xy 48.870689 -400.477152) (xy 48.924637 -400.484914) (xy 48.976931 -400.500273)
			(xy 49.026507 -400.522918) (xy 49.072356 -400.552388) (xy 49.113545 -400.588082) (xy 49.149235 -400.629274)
			(xy 49.1787 -400.675126) (xy 49.20134 -400.724705) (xy 49.216694 -400.777) (xy 49.22445 -400.830948)
			(xy 49.22445 -400.885448) (xy 50.662106 -400.885448) (xy 50.662106 -400.830952) (xy 50.669862 -400.77701)
			(xy 50.685214 -400.724721) (xy 50.707852 -400.675149) (xy 50.737314 -400.629303) (xy 50.773001 -400.588116)
			(xy 50.814185 -400.552427) (xy 50.86003 -400.522963) (xy 50.9096 -400.500322) (xy 50.961888 -400.484966)
			(xy 51.01583 -400.477208) (xy 51.043078 -400.47672) (xy 51.906678 -400.47672) (xy 51.933934 -400.477125)
			(xy 51.987891 -400.48488) (xy 52.040196 -400.500236) (xy 52.089782 -400.522879) (xy 52.135642 -400.552348)
			(xy 52.17684 -400.588045) (xy 52.212539 -400.629241) (xy 52.242011 -400.675098) (xy 52.264657 -400.724684)
			(xy 52.280015 -400.776987) (xy 52.287773 -400.830944) (xy 52.287773 -400.885452) (xy 53.725283 -400.885452)
			(xy 53.725283 -400.830948) (xy 53.73304 -400.777) (xy 53.748396 -400.724704) (xy 53.771038 -400.675127)
			(xy 53.800506 -400.629276) (xy 53.836199 -400.588086) (xy 53.87739 -400.552395) (xy 53.923242 -400.52293)
			(xy 53.972821 -400.50029) (xy 54.025117 -400.484936) (xy 54.079066 -400.477182) (xy 54.106318 -400.47672)
			(xy 54.969918 -400.47672) (xy 54.99717 -400.477151) (xy 55.05112 -400.48491) (xy 55.103417 -400.500268)
			(xy 55.152995 -400.522912) (xy 55.198847 -400.552381) (xy 55.240038 -400.588075) (xy 55.27573 -400.629268)
			(xy 55.305197 -400.675121) (xy 55.327838 -400.7247) (xy 55.343194 -400.776997) (xy 55.35095 -400.830948)
			(xy 55.35095 -400.885447) (xy 56.788606 -400.885447) (xy 56.788606 -400.830953) (xy 56.796361 -400.777013)
			(xy 56.811713 -400.724725) (xy 56.834349 -400.675154) (xy 56.863809 -400.629309) (xy 56.899494 -400.588123)
			(xy 56.940676 -400.552435) (xy 56.986518 -400.522969) (xy 57.036086 -400.500327) (xy 57.088372 -400.48497)
			(xy 57.142311 -400.477209) (xy 57.169558 -400.47672) (xy 58.033158 -400.47672) (xy 58.060415 -400.477124)
			(xy 58.114374 -400.484877) (xy 58.166681 -400.50023) (xy 58.21627 -400.522872) (xy 58.262132 -400.552341)
			(xy 58.303333 -400.588037) (xy 58.339034 -400.629234) (xy 58.368508 -400.675093) (xy 58.391155 -400.724679)
			(xy 58.406514 -400.776985) (xy 58.414273 -400.830943) (xy 58.414273 -400.885449) (xy 59.851806 -400.885449)
			(xy 59.851806 -400.830951) (xy 59.859562 -400.777007) (xy 59.874916 -400.724717) (xy 59.897555 -400.675143)
			(xy 59.927019 -400.629296) (xy 59.962708 -400.588109) (xy 60.003895 -400.55242) (xy 60.049742 -400.522956)
			(xy 60.099315 -400.500317) (xy 60.151605 -400.484963) (xy 60.205549 -400.477206) (xy 60.232798 -400.47672)
			(xy 61.096398 -400.47672) (xy 61.123653 -400.477127) (xy 61.177608 -400.484884) (xy 61.22991 -400.500241)
			(xy 61.279494 -400.522885) (xy 61.325351 -400.552355) (xy 61.366547 -400.588052) (xy 61.402243 -400.629247)
			(xy 61.431714 -400.675104) (xy 61.454358 -400.724688) (xy 61.469715 -400.77699) (xy 61.477473 -400.830945)
			(xy 61.477473 -400.885453) (xy 62.914983 -400.885453) (xy 62.914983 -400.830947) (xy 62.922741 -400.776997)
			(xy 62.938098 -400.7247) (xy 62.960741 -400.675121) (xy 62.990211 -400.629269) (xy 63.025906 -400.588079)
			(xy 63.0671 -400.552388) (xy 63.112954 -400.522923) (xy 63.162536 -400.500284) (xy 63.214834 -400.484933)
			(xy 63.268785 -400.477181) (xy 63.296038 -400.47672) (xy 64.159638 -400.47672) (xy 64.186889 -400.477152)
			(xy 64.240837 -400.484914) (xy 64.293131 -400.500273) (xy 64.342707 -400.522918) (xy 64.388556 -400.552388)
			(xy 64.429745 -400.588082) (xy 64.465435 -400.629274) (xy 64.4949 -400.675126) (xy 64.51754 -400.724705)
			(xy 64.532894 -400.777) (xy 64.54065 -400.830948) (xy 64.54065 -400.885448) (xy 65.978306 -400.885448)
			(xy 65.978306 -400.830952) (xy 65.986062 -400.77701) (xy 66.001414 -400.724721) (xy 66.024052 -400.675149)
			(xy 66.053514 -400.629303) (xy 66.089201 -400.588116) (xy 66.130385 -400.552427) (xy 66.17623 -400.522963)
			(xy 66.2258 -400.500322) (xy 66.278088 -400.484966) (xy 66.33203 -400.477208) (xy 66.359278 -400.47672)
			(xy 67.222878 -400.47672) (xy 67.250134 -400.477125) (xy 67.304091 -400.48488) (xy 67.356396 -400.500236)
			(xy 67.405982 -400.522879) (xy 67.451842 -400.552348) (xy 67.49304 -400.588045) (xy 67.528739 -400.629241)
			(xy 67.558211 -400.675098) (xy 67.580857 -400.724684) (xy 67.596215 -400.776987) (xy 67.603973 -400.830944)
			(xy 67.603973 -400.885452) (xy 69.041483 -400.885452) (xy 69.041483 -400.830948) (xy 69.04924 -400.777)
			(xy 69.064596 -400.724704) (xy 69.087238 -400.675127) (xy 69.116706 -400.629276) (xy 69.152399 -400.588086)
			(xy 69.19359 -400.552395) (xy 69.239442 -400.52293) (xy 69.289021 -400.50029) (xy 69.341317 -400.484936)
			(xy 69.395266 -400.477182) (xy 69.422518 -400.47672) (xy 70.286118 -400.47672) (xy 70.31337 -400.477151)
			(xy 70.36732 -400.48491) (xy 70.419617 -400.500268) (xy 70.469195 -400.522912) (xy 70.515047 -400.552381)
			(xy 70.556238 -400.588075) (xy 70.59193 -400.629268) (xy 70.621397 -400.675121) (xy 70.644038 -400.7247)
			(xy 70.659394 -400.776997) (xy 70.66715 -400.830948) (xy 70.66715 -400.885447) (xy 72.104806 -400.885447)
			(xy 72.104806 -400.830953) (xy 72.112561 -400.777013) (xy 72.127913 -400.724725) (xy 72.150549 -400.675154)
			(xy 72.180009 -400.629309) (xy 72.215694 -400.588123) (xy 72.256876 -400.552435) (xy 72.302718 -400.522969)
			(xy 72.352286 -400.500327) (xy 72.404572 -400.48497) (xy 72.458511 -400.477209) (xy 72.485758 -400.47672)
			(xy 73.349358 -400.47672) (xy 73.376615 -400.477124) (xy 73.430574 -400.484877) (xy 73.482881 -400.50023)
			(xy 73.53247 -400.522872) (xy 73.578332 -400.552341) (xy 73.619533 -400.588037) (xy 73.655234 -400.629234)
			(xy 73.684708 -400.675093) (xy 73.707355 -400.724679) (xy 73.722714 -400.776985) (xy 73.730473 -400.830943)
			(xy 73.730473 -400.885449) (xy 75.168006 -400.885449) (xy 75.168006 -400.830951) (xy 75.175762 -400.777007)
			(xy 75.191116 -400.724717) (xy 75.213755 -400.675143) (xy 75.243219 -400.629296) (xy 75.278908 -400.588109)
			(xy 75.320095 -400.55242) (xy 75.365942 -400.522956) (xy 75.415515 -400.500317) (xy 75.467805 -400.484963)
			(xy 75.521749 -400.477206) (xy 75.548998 -400.47672) (xy 76.412598 -400.47672) (xy 76.439853 -400.477127)
			(xy 76.493808 -400.484884) (xy 76.54611 -400.500241) (xy 76.595694 -400.522885) (xy 76.641551 -400.552355)
			(xy 76.682747 -400.588052) (xy 76.718443 -400.629247) (xy 76.747914 -400.675104) (xy 76.770558 -400.724688)
			(xy 76.785915 -400.77699) (xy 76.793673 -400.830945) (xy 76.793673 -400.885453) (xy 78.231183 -400.885453)
			(xy 78.231183 -400.830947) (xy 78.238941 -400.776997) (xy 78.254298 -400.7247) (xy 78.276941 -400.675121)
			(xy 78.306411 -400.629269) (xy 78.342106 -400.588079) (xy 78.3833 -400.552388) (xy 78.429154 -400.522923)
			(xy 78.478736 -400.500284) (xy 78.531034 -400.484933) (xy 78.584985 -400.477181) (xy 78.612238 -400.47672)
			(xy 79.475838 -400.47672) (xy 79.503089 -400.477152) (xy 79.557037 -400.484914) (xy 79.609331 -400.500273)
			(xy 79.658907 -400.522918) (xy 79.704756 -400.552388) (xy 79.745945 -400.588082) (xy 79.781635 -400.629274)
			(xy 79.8111 -400.675126) (xy 79.83374 -400.724705) (xy 79.849094 -400.777) (xy 79.85685 -400.830948)
			(xy 79.85685 -400.885448) (xy 81.294506 -400.885448) (xy 81.294506 -400.830952) (xy 81.302262 -400.77701)
			(xy 81.317614 -400.724721) (xy 81.340252 -400.675149) (xy 81.369714 -400.629303) (xy 81.405401 -400.588116)
			(xy 81.446585 -400.552427) (xy 81.49243 -400.522963) (xy 81.542 -400.500322) (xy 81.594288 -400.484966)
			(xy 81.64823 -400.477208) (xy 81.675478 -400.47672) (xy 82.539078 -400.47672) (xy 82.566334 -400.477125)
			(xy 82.620291 -400.48488) (xy 82.672596 -400.500236) (xy 82.722182 -400.522879) (xy 82.768042 -400.552348)
			(xy 82.80924 -400.588045) (xy 82.844939 -400.629241) (xy 82.874411 -400.675098) (xy 82.897057 -400.724684)
			(xy 82.912415 -400.776987) (xy 82.920173 -400.830944) (xy 82.920173 -400.885452) (xy 84.357683 -400.885452)
			(xy 84.357683 -400.830948) (xy 84.36544 -400.777) (xy 84.380796 -400.724704) (xy 84.403438 -400.675127)
			(xy 84.432906 -400.629276) (xy 84.468599 -400.588086) (xy 84.50979 -400.552395) (xy 84.555642 -400.52293)
			(xy 84.605221 -400.50029) (xy 84.657517 -400.484936) (xy 84.711466 -400.477182) (xy 84.738718 -400.47672)
			(xy 85.602318 -400.47672) (xy 85.62957 -400.477151) (xy 85.68352 -400.48491) (xy 85.735817 -400.500268)
			(xy 85.785395 -400.522912) (xy 85.831247 -400.552381) (xy 85.872438 -400.588075) (xy 85.90813 -400.629268)
			(xy 85.937597 -400.675121) (xy 85.960238 -400.7247) (xy 85.975594 -400.776997) (xy 85.98335 -400.830948)
			(xy 85.98335 -400.885447) (xy 87.421006 -400.885447) (xy 87.421006 -400.830953) (xy 87.428761 -400.777013)
			(xy 87.444113 -400.724725) (xy 87.466749 -400.675154) (xy 87.496209 -400.629309) (xy 87.531894 -400.588123)
			(xy 87.573076 -400.552435) (xy 87.618918 -400.522969) (xy 87.668486 -400.500327) (xy 87.720772 -400.48497)
			(xy 87.774711 -400.477209) (xy 87.801958 -400.47672) (xy 88.665558 -400.47672) (xy 88.692815 -400.477124)
			(xy 88.746774 -400.484877) (xy 88.799081 -400.50023) (xy 88.84867 -400.522872) (xy 88.894532 -400.552341)
			(xy 88.935733 -400.588037) (xy 88.971434 -400.629234) (xy 89.000908 -400.675093) (xy 89.023555 -400.724679)
			(xy 89.038914 -400.776985) (xy 89.046673 -400.830943) (xy 89.046673 -400.885449) (xy 90.484206 -400.885449)
			(xy 90.484206 -400.830951) (xy 90.491962 -400.777007) (xy 90.507316 -400.724717) (xy 90.529955 -400.675143)
			(xy 90.559419 -400.629296) (xy 90.595108 -400.588109) (xy 90.636295 -400.55242) (xy 90.682142 -400.522956)
			(xy 90.731715 -400.500317) (xy 90.784005 -400.484963) (xy 90.837949 -400.477206) (xy 90.865198 -400.47672)
			(xy 91.728798 -400.47672) (xy 91.756053 -400.477127) (xy 91.810008 -400.484884) (xy 91.86231 -400.500241)
			(xy 91.911894 -400.522885) (xy 91.957751 -400.552355) (xy 91.998947 -400.588052) (xy 92.034643 -400.629247)
			(xy 92.064114 -400.675104) (xy 92.086758 -400.724688) (xy 92.102115 -400.77699) (xy 92.109873 -400.830945)
			(xy 92.109873 -400.885453) (xy 93.547383 -400.885453) (xy 93.547383 -400.830947) (xy 93.555141 -400.776997)
			(xy 93.570498 -400.7247) (xy 93.593141 -400.675121) (xy 93.622611 -400.629269) (xy 93.658306 -400.588079)
			(xy 93.6995 -400.552388) (xy 93.745354 -400.522923) (xy 93.794936 -400.500284) (xy 93.847234 -400.484933)
			(xy 93.901185 -400.477181) (xy 93.928438 -400.47672) (xy 94.792038 -400.47672) (xy 94.819289 -400.477152)
			(xy 94.873237 -400.484914) (xy 94.925531 -400.500273) (xy 94.975107 -400.522918) (xy 95.020956 -400.552388)
			(xy 95.062145 -400.588082) (xy 95.097835 -400.629274) (xy 95.1273 -400.675126) (xy 95.14994 -400.724705)
			(xy 95.165294 -400.777) (xy 95.17305 -400.830948) (xy 95.17305 -400.885447) (xy 119.774006 -400.885447)
			(xy 119.774006 -400.830953) (xy 119.781761 -400.777013) (xy 119.797112 -400.724726) (xy 119.819749 -400.675156)
			(xy 119.849208 -400.629311) (xy 119.884892 -400.588125) (xy 119.926074 -400.552436) (xy 119.971915 -400.522971)
			(xy 120.021483 -400.500329) (xy 120.073768 -400.484971) (xy 120.127707 -400.477209) (xy 120.154954 -400.47672)
			(xy 121.018554 -400.47672) (xy 121.045811 -400.477124) (xy 121.099771 -400.484876) (xy 121.152078 -400.500229)
			(xy 121.201668 -400.522871) (xy 121.24753 -400.55234) (xy 121.288731 -400.588036) (xy 121.324433 -400.629233)
			(xy 121.353907 -400.675092) (xy 121.376555 -400.724679) (xy 121.391914 -400.776984) (xy 121.399673 -400.830943)
			(xy 121.399673 -400.885449) (xy 122.837206 -400.885449) (xy 122.837206 -400.830951) (xy 122.844962 -400.777008)
			(xy 122.860316 -400.724717) (xy 122.882955 -400.675144) (xy 122.912418 -400.629298) (xy 122.948106 -400.588111)
			(xy 122.989293 -400.552422) (xy 123.035139 -400.522958) (xy 123.084712 -400.500318) (xy 123.137002 -400.484963)
			(xy 123.190945 -400.477207) (xy 123.218194 -400.47672) (xy 124.081794 -400.47672) (xy 124.109049 -400.477127)
			(xy 124.163005 -400.484883) (xy 124.215307 -400.50024) (xy 124.264892 -400.522884) (xy 124.310749 -400.552354)
			(xy 124.351946 -400.58805) (xy 124.387643 -400.629246) (xy 124.417113 -400.675103) (xy 124.439758 -400.724687)
			(xy 124.455115 -400.776989) (xy 124.462873 -400.830945) (xy 124.462873 -400.885452) (xy 125.900383 -400.885452)
			(xy 125.900383 -400.830948) (xy 125.908141 -400.776998) (xy 125.923497 -400.724701) (xy 125.946141 -400.675122)
			(xy 125.97561 -400.629271) (xy 126.011304 -400.58808) (xy 126.052498 -400.552389) (xy 126.098352 -400.522924)
			(xy 126.147933 -400.500285) (xy 126.200231 -400.484933) (xy 126.254182 -400.477181) (xy 126.281434 -400.47672)
			(xy 127.145034 -400.47672) (xy 127.172286 -400.477152) (xy 127.226234 -400.484913) (xy 127.278528 -400.500272)
			(xy 127.328105 -400.522917) (xy 127.373954 -400.552386) (xy 127.415143 -400.588081) (xy 127.450834 -400.629273)
			(xy 127.480299 -400.675125) (xy 127.50294 -400.724704) (xy 127.518294 -400.777) (xy 127.52605 -400.830948)
			(xy 127.52605 -400.885448) (xy 128.963706 -400.885448) (xy 128.963706 -400.830952) (xy 128.971461 -400.777011)
			(xy 128.986814 -400.724722) (xy 129.009452 -400.67515) (xy 129.038913 -400.629304) (xy 129.074599 -400.588118)
			(xy 129.115783 -400.552429) (xy 129.161627 -400.522964) (xy 129.211197 -400.500323) (xy 129.263485 -400.484967)
			(xy 129.317426 -400.477208) (xy 129.344674 -400.47672) (xy 130.208274 -400.47672) (xy 130.23553 -400.477125)
			(xy 130.289488 -400.48488) (xy 130.341793 -400.500235) (xy 130.39138 -400.522877) (xy 130.43724 -400.552347)
			(xy 130.478438 -400.588043) (xy 130.514138 -400.62924) (xy 130.54361 -400.675097) (xy 130.566256 -400.724683)
			(xy 130.581615 -400.776987) (xy 130.589373 -400.830944) (xy 130.589373 -400.885451) (xy 132.026883 -400.885451)
			(xy 132.026883 -400.830949) (xy 132.03464 -400.777) (xy 132.049996 -400.724705) (xy 132.072638 -400.675128)
			(xy 132.102105 -400.629277) (xy 132.137797 -400.588087) (xy 132.178989 -400.552396) (xy 132.22484 -400.522931)
			(xy 132.274418 -400.500291) (xy 132.326714 -400.484937) (xy 132.380662 -400.477182) (xy 132.407914 -400.47672)
			(xy 133.271514 -400.47672) (xy 133.298767 -400.477151) (xy 133.352717 -400.48491) (xy 133.405014 -400.500267)
			(xy 133.454593 -400.522911) (xy 133.500445 -400.552379) (xy 133.541636 -400.588074) (xy 133.577329 -400.629266)
			(xy 133.606796 -400.67512) (xy 133.629438 -400.724699) (xy 133.644793 -400.776997) (xy 133.65255 -400.830947)
			(xy 133.65255 -400.885447) (xy 135.090206 -400.885447) (xy 135.090206 -400.830953) (xy 135.097961 -400.777013)
			(xy 135.113312 -400.724726) (xy 135.135949 -400.675156) (xy 135.165408 -400.629311) (xy 135.201092 -400.588125)
			(xy 135.242274 -400.552436) (xy 135.288115 -400.522971) (xy 135.337683 -400.500329) (xy 135.389968 -400.484971)
			(xy 135.443907 -400.477209) (xy 135.471154 -400.47672) (xy 136.334754 -400.47672) (xy 136.362011 -400.477124)
			(xy 136.415971 -400.484876) (xy 136.468278 -400.500229) (xy 136.517868 -400.522871) (xy 136.56373 -400.55234)
			(xy 136.604931 -400.588036) (xy 136.640633 -400.629233) (xy 136.670107 -400.675092) (xy 136.692755 -400.724679)
			(xy 136.708114 -400.776984) (xy 136.715873 -400.830943) (xy 136.715873 -400.885449) (xy 138.153406 -400.885449)
			(xy 138.153406 -400.830951) (xy 138.161162 -400.777008) (xy 138.176516 -400.724717) (xy 138.199155 -400.675144)
			(xy 138.228618 -400.629298) (xy 138.264306 -400.588111) (xy 138.305493 -400.552422) (xy 138.351339 -400.522958)
			(xy 138.400912 -400.500318) (xy 138.453202 -400.484963) (xy 138.507145 -400.477207) (xy 138.534394 -400.47672)
			(xy 139.397994 -400.47672) (xy 139.425249 -400.477127) (xy 139.479205 -400.484883) (xy 139.531507 -400.50024)
			(xy 139.581092 -400.522884) (xy 139.626949 -400.552354) (xy 139.668146 -400.58805) (xy 139.703843 -400.629246)
			(xy 139.733313 -400.675103) (xy 139.755958 -400.724687) (xy 139.771315 -400.776989) (xy 139.779073 -400.830945)
			(xy 139.779073 -400.885452) (xy 141.216583 -400.885452) (xy 141.216583 -400.830948) (xy 141.224341 -400.776998)
			(xy 141.239697 -400.724701) (xy 141.262341 -400.675122) (xy 141.29181 -400.629271) (xy 141.327504 -400.58808)
			(xy 141.368698 -400.552389) (xy 141.414552 -400.522924) (xy 141.464133 -400.500285) (xy 141.516431 -400.484933)
			(xy 141.570382 -400.477181) (xy 141.597634 -400.47672) (xy 142.461234 -400.47672) (xy 142.488486 -400.477152)
			(xy 142.542434 -400.484913) (xy 142.594728 -400.500272) (xy 142.644305 -400.522917) (xy 142.690154 -400.552386)
			(xy 142.731343 -400.588081) (xy 142.767034 -400.629273) (xy 142.796499 -400.675125) (xy 142.81914 -400.724704)
			(xy 142.834494 -400.777) (xy 142.84225 -400.830948) (xy 142.84225 -400.885448) (xy 144.279906 -400.885448)
			(xy 144.279906 -400.830952) (xy 144.287661 -400.777011) (xy 144.303014 -400.724722) (xy 144.325652 -400.67515)
			(xy 144.355113 -400.629304) (xy 144.390799 -400.588118) (xy 144.431983 -400.552429) (xy 144.477827 -400.522964)
			(xy 144.527397 -400.500323) (xy 144.579685 -400.484967) (xy 144.633626 -400.477208) (xy 144.660874 -400.47672)
			(xy 145.524474 -400.47672) (xy 145.55173 -400.477125) (xy 145.605688 -400.48488) (xy 145.657993 -400.500235)
			(xy 145.70758 -400.522877) (xy 145.75344 -400.552347) (xy 145.794638 -400.588043) (xy 145.830338 -400.62924)
			(xy 145.85981 -400.675097) (xy 145.882456 -400.724683) (xy 145.897815 -400.776987) (xy 145.905573 -400.830944)
			(xy 145.905573 -400.885451) (xy 147.343083 -400.885451) (xy 147.343083 -400.830949) (xy 147.35084 -400.777)
			(xy 147.366196 -400.724705) (xy 147.388838 -400.675128) (xy 147.418305 -400.629277) (xy 147.453997 -400.588087)
			(xy 147.495189 -400.552396) (xy 147.54104 -400.522931) (xy 147.590618 -400.500291) (xy 147.642914 -400.484937)
			(xy 147.696862 -400.477182) (xy 147.724114 -400.47672) (xy 148.587714 -400.47672) (xy 148.614967 -400.477151)
			(xy 148.668917 -400.48491) (xy 148.721214 -400.500267) (xy 148.770793 -400.522911) (xy 148.816645 -400.552379)
			(xy 148.857836 -400.588074) (xy 148.893529 -400.629266) (xy 148.922996 -400.67512) (xy 148.945638 -400.724699)
			(xy 148.960993 -400.776997) (xy 148.96875 -400.830947) (xy 148.96875 -400.885447) (xy 150.406406 -400.885447)
			(xy 150.406406 -400.830953) (xy 150.414161 -400.777013) (xy 150.429512 -400.724726) (xy 150.452149 -400.675156)
			(xy 150.481608 -400.629311) (xy 150.517292 -400.588125) (xy 150.558474 -400.552436) (xy 150.604315 -400.522971)
			(xy 150.653883 -400.500329) (xy 150.706168 -400.484971) (xy 150.760107 -400.477209) (xy 150.787354 -400.47672)
			(xy 151.650954 -400.47672) (xy 151.678211 -400.477124) (xy 151.732171 -400.484876) (xy 151.784478 -400.500229)
			(xy 151.834068 -400.522871) (xy 151.87993 -400.55234) (xy 151.921131 -400.588036) (xy 151.956833 -400.629233)
			(xy 151.986307 -400.675092) (xy 152.008955 -400.724679) (xy 152.024314 -400.776984) (xy 152.032073 -400.830943)
			(xy 152.032073 -400.885449) (xy 153.469606 -400.885449) (xy 153.469606 -400.830951) (xy 153.477362 -400.777008)
			(xy 153.492716 -400.724717) (xy 153.515355 -400.675144) (xy 153.544818 -400.629298) (xy 153.580506 -400.588111)
			(xy 153.621693 -400.552422) (xy 153.667539 -400.522958) (xy 153.717112 -400.500318) (xy 153.769402 -400.484963)
			(xy 153.823345 -400.477207) (xy 153.850594 -400.47672) (xy 154.714194 -400.47672) (xy 154.741449 -400.477127)
			(xy 154.795405 -400.484883) (xy 154.847707 -400.50024) (xy 154.897292 -400.522884) (xy 154.943149 -400.552354)
			(xy 154.984346 -400.58805) (xy 155.020043 -400.629246) (xy 155.049513 -400.675103) (xy 155.072158 -400.724687)
			(xy 155.087515 -400.776989) (xy 155.095273 -400.830945) (xy 155.095273 -400.885452) (xy 156.532783 -400.885452)
			(xy 156.532783 -400.830948) (xy 156.540541 -400.776998) (xy 156.555897 -400.724701) (xy 156.578541 -400.675122)
			(xy 156.60801 -400.629271) (xy 156.643704 -400.58808) (xy 156.684898 -400.552389) (xy 156.730752 -400.522924)
			(xy 156.780333 -400.500285) (xy 156.832631 -400.484933) (xy 156.886582 -400.477181) (xy 156.913834 -400.47672)
			(xy 157.777434 -400.47672) (xy 157.804686 -400.477152) (xy 157.858634 -400.484913) (xy 157.910928 -400.500272)
			(xy 157.960505 -400.522917) (xy 158.006354 -400.552386) (xy 158.047543 -400.588081) (xy 158.083234 -400.629273)
			(xy 158.112699 -400.675125) (xy 158.13534 -400.724704) (xy 158.150694 -400.777) (xy 158.15845 -400.830948)
			(xy 158.15845 -400.885448) (xy 159.596106 -400.885448) (xy 159.596106 -400.830952) (xy 159.603861 -400.777011)
			(xy 159.619214 -400.724722) (xy 159.641852 -400.67515) (xy 159.671313 -400.629304) (xy 159.706999 -400.588118)
			(xy 159.748183 -400.552429) (xy 159.794027 -400.522964) (xy 159.843597 -400.500323) (xy 159.895885 -400.484967)
			(xy 159.949826 -400.477208) (xy 159.977074 -400.47672) (xy 160.840674 -400.47672) (xy 160.86793 -400.477125)
			(xy 160.921888 -400.48488) (xy 160.974193 -400.500235) (xy 161.02378 -400.522877) (xy 161.06964 -400.552347)
			(xy 161.110838 -400.588043) (xy 161.146538 -400.62924) (xy 161.17601 -400.675097) (xy 161.198656 -400.724683)
			(xy 161.214015 -400.776987) (xy 161.221773 -400.830944) (xy 161.221773 -400.885451) (xy 162.659283 -400.885451)
			(xy 162.659283 -400.830949) (xy 162.66704 -400.777) (xy 162.682396 -400.724705) (xy 162.705038 -400.675128)
			(xy 162.734505 -400.629277) (xy 162.770197 -400.588087) (xy 162.811389 -400.552396) (xy 162.85724 -400.522931)
			(xy 162.906818 -400.500291) (xy 162.959114 -400.484937) (xy 163.013062 -400.477182) (xy 163.040314 -400.47672)
			(xy 163.903914 -400.47672) (xy 163.931167 -400.477151) (xy 163.985117 -400.48491) (xy 164.037414 -400.500267)
			(xy 164.086993 -400.522911) (xy 164.132845 -400.552379) (xy 164.174036 -400.588074) (xy 164.209729 -400.629266)
			(xy 164.239196 -400.67512) (xy 164.261838 -400.724699) (xy 164.277193 -400.776997) (xy 164.28495 -400.830947)
			(xy 164.28495 -400.885447) (xy 165.722606 -400.885447) (xy 165.722606 -400.830953) (xy 165.730361 -400.777013)
			(xy 165.745712 -400.724726) (xy 165.768349 -400.675156) (xy 165.797808 -400.629311) (xy 165.833492 -400.588125)
			(xy 165.874674 -400.552436) (xy 165.920515 -400.522971) (xy 165.970083 -400.500329) (xy 166.022368 -400.484971)
			(xy 166.076307 -400.477209) (xy 166.103554 -400.47672) (xy 166.967154 -400.47672) (xy 166.994411 -400.477124)
			(xy 167.048371 -400.484876) (xy 167.100678 -400.500229) (xy 167.150268 -400.522871) (xy 167.19613 -400.55234)
			(xy 167.237331 -400.588036) (xy 167.273033 -400.629233) (xy 167.302507 -400.675092) (xy 167.325155 -400.724679)
			(xy 167.340514 -400.776984) (xy 167.348273 -400.830943) (xy 167.348273 -400.885457) (xy 167.340514 -400.939416)
			(xy 167.325155 -400.991721) (xy 167.302507 -401.041308) (xy 167.273033 -401.087167) (xy 167.237331 -401.128364)
			(xy 167.19613 -401.16406) (xy 167.150268 -401.193529) (xy 167.100678 -401.216171) (xy 167.048371 -401.231524)
			(xy 166.994411 -401.239276) (xy 166.967154 -401.239736) (xy 166.103554 -401.239736) (xy 166.076307 -401.239191)
			(xy 166.022368 -401.231429) (xy 165.970083 -401.216071) (xy 165.920515 -401.193429) (xy 165.874674 -401.163964)
			(xy 165.833492 -401.128275) (xy 165.797808 -401.087089) (xy 165.768349 -401.041244) (xy 165.745712 -400.991674)
			(xy 165.730361 -400.939387) (xy 165.722606 -400.885447) (xy 164.28495 -400.885447) (xy 164.28495 -400.885453)
			(xy 164.277193 -400.939403) (xy 164.261838 -400.991701) (xy 164.239196 -401.04128) (xy 164.209729 -401.087134)
			(xy 164.174036 -401.128326) (xy 164.132845 -401.164021) (xy 164.086993 -401.193489) (xy 164.037414 -401.216133)
			(xy 163.985117 -401.23149) (xy 163.931167 -401.239249) (xy 163.903914 -401.239736) (xy 163.040314 -401.239736)
			(xy 163.013062 -401.239218) (xy 162.959114 -401.231463) (xy 162.906818 -401.216109) (xy 162.85724 -401.193469)
			(xy 162.811389 -401.164004) (xy 162.770197 -401.128313) (xy 162.734505 -401.087123) (xy 162.705038 -401.041272)
			(xy 162.682396 -400.991695) (xy 162.66704 -400.9394) (xy 162.659283 -400.885451) (xy 161.221773 -400.885451)
			(xy 161.221773 -400.885456) (xy 161.214015 -400.939413) (xy 161.198656 -400.991717) (xy 161.17601 -401.041303)
			(xy 161.146538 -401.08716) (xy 161.110838 -401.128357) (xy 161.06964 -401.164053) (xy 161.02378 -401.193523)
			(xy 160.974193 -401.216165) (xy 160.921888 -401.23152) (xy 160.86793 -401.239275) (xy 160.840674 -401.239736)
			(xy 159.977074 -401.239736) (xy 159.949826 -401.239192) (xy 159.895885 -401.231433) (xy 159.843597 -401.216077)
			(xy 159.794027 -401.193436) (xy 159.748183 -401.163971) (xy 159.706999 -401.128282) (xy 159.671313 -401.087096)
			(xy 159.641852 -401.04125) (xy 159.619214 -400.991678) (xy 159.603861 -400.939389) (xy 159.596106 -400.885448)
			(xy 158.15845 -400.885448) (xy 158.15845 -400.885452) (xy 158.150694 -400.9394) (xy 158.13534 -400.991696)
			(xy 158.112699 -401.041275) (xy 158.083234 -401.087127) (xy 158.047543 -401.128319) (xy 158.006354 -401.164014)
			(xy 157.960505 -401.193483) (xy 157.910928 -401.216128) (xy 157.858634 -401.231487) (xy 157.804686 -401.239248)
			(xy 157.777434 -401.239736) (xy 156.913834 -401.239736) (xy 156.886582 -401.239219) (xy 156.832631 -401.231467)
			(xy 156.780333 -401.216115) (xy 156.730752 -401.193476) (xy 156.684898 -401.164011) (xy 156.643704 -401.12832)
			(xy 156.60801 -401.087129) (xy 156.578541 -401.041278) (xy 156.555897 -400.991699) (xy 156.540541 -400.939402)
			(xy 156.532783 -400.885452) (xy 155.095273 -400.885452) (xy 155.095273 -400.885455) (xy 155.087515 -400.939411)
			(xy 155.072158 -400.991713) (xy 155.049513 -401.041297) (xy 155.020043 -401.087154) (xy 154.984346 -401.12835)
			(xy 154.943149 -401.164046) (xy 154.897292 -401.193516) (xy 154.847707 -401.21616) (xy 154.795405 -401.231517)
			(xy 154.741449 -401.239273) (xy 154.714194 -401.239736) (xy 153.850594 -401.239736) (xy 153.823345 -401.239193)
			(xy 153.769402 -401.231437) (xy 153.717112 -401.216082) (xy 153.667539 -401.193442) (xy 153.621693 -401.163978)
			(xy 153.580506 -401.128289) (xy 153.544818 -401.087102) (xy 153.515355 -401.041256) (xy 153.492716 -400.991683)
			(xy 153.477362 -400.939392) (xy 153.469606 -400.885449) (xy 152.032073 -400.885449) (xy 152.032073 -400.885457)
			(xy 152.024314 -400.939416) (xy 152.008955 -400.991721) (xy 151.986307 -401.041308) (xy 151.956833 -401.087167)
			(xy 151.921131 -401.128364) (xy 151.87993 -401.16406) (xy 151.834068 -401.193529) (xy 151.784478 -401.216171)
			(xy 151.732171 -401.231524) (xy 151.678211 -401.239276) (xy 151.650954 -401.239736) (xy 150.787354 -401.239736)
			(xy 150.760107 -401.239191) (xy 150.706168 -401.231429) (xy 150.653883 -401.216071) (xy 150.604315 -401.193429)
			(xy 150.558474 -401.163964) (xy 150.517292 -401.128275) (xy 150.481608 -401.087089) (xy 150.452149 -401.041244)
			(xy 150.429512 -400.991674) (xy 150.414161 -400.939387) (xy 150.406406 -400.885447) (xy 148.96875 -400.885447)
			(xy 148.96875 -400.885453) (xy 148.960993 -400.939403) (xy 148.945638 -400.991701) (xy 148.922996 -401.04128)
			(xy 148.893529 -401.087134) (xy 148.857836 -401.128326) (xy 148.816645 -401.164021) (xy 148.770793 -401.193489)
			(xy 148.721214 -401.216133) (xy 148.668917 -401.23149) (xy 148.614967 -401.239249) (xy 148.587714 -401.239736)
			(xy 147.724114 -401.239736) (xy 147.696862 -401.239218) (xy 147.642914 -401.231463) (xy 147.590618 -401.216109)
			(xy 147.54104 -401.193469) (xy 147.495189 -401.164004) (xy 147.453997 -401.128313) (xy 147.418305 -401.087123)
			(xy 147.388838 -401.041272) (xy 147.366196 -400.991695) (xy 147.35084 -400.9394) (xy 147.343083 -400.885451)
			(xy 145.905573 -400.885451) (xy 145.905573 -400.885456) (xy 145.897815 -400.939413) (xy 145.882456 -400.991717)
			(xy 145.85981 -401.041303) (xy 145.830338 -401.08716) (xy 145.794638 -401.128357) (xy 145.75344 -401.164053)
			(xy 145.70758 -401.193523) (xy 145.657993 -401.216165) (xy 145.605688 -401.23152) (xy 145.55173 -401.239275)
			(xy 145.524474 -401.239736) (xy 144.660874 -401.239736) (xy 144.633626 -401.239192) (xy 144.579685 -401.231433)
			(xy 144.527397 -401.216077) (xy 144.477827 -401.193436) (xy 144.431983 -401.163971) (xy 144.390799 -401.128282)
			(xy 144.355113 -401.087096) (xy 144.325652 -401.04125) (xy 144.303014 -400.991678) (xy 144.287661 -400.939389)
			(xy 144.279906 -400.885448) (xy 142.84225 -400.885448) (xy 142.84225 -400.885452) (xy 142.834494 -400.9394)
			(xy 142.81914 -400.991696) (xy 142.796499 -401.041275) (xy 142.767034 -401.087127) (xy 142.731343 -401.128319)
			(xy 142.690154 -401.164014) (xy 142.644305 -401.193483) (xy 142.594728 -401.216128) (xy 142.542434 -401.231487)
			(xy 142.488486 -401.239248) (xy 142.461234 -401.239736) (xy 141.597634 -401.239736) (xy 141.570382 -401.239219)
			(xy 141.516431 -401.231467) (xy 141.464133 -401.216115) (xy 141.414552 -401.193476) (xy 141.368698 -401.164011)
			(xy 141.327504 -401.12832) (xy 141.29181 -401.087129) (xy 141.262341 -401.041278) (xy 141.239697 -400.991699)
			(xy 141.224341 -400.939402) (xy 141.216583 -400.885452) (xy 139.779073 -400.885452) (xy 139.779073 -400.885455)
			(xy 139.771315 -400.939411) (xy 139.755958 -400.991713) (xy 139.733313 -401.041297) (xy 139.703843 -401.087154)
			(xy 139.668146 -401.12835) (xy 139.626949 -401.164046) (xy 139.581092 -401.193516) (xy 139.531507 -401.21616)
			(xy 139.479205 -401.231517) (xy 139.425249 -401.239273) (xy 139.397994 -401.239736) (xy 138.534394 -401.239736)
			(xy 138.507145 -401.239193) (xy 138.453202 -401.231437) (xy 138.400912 -401.216082) (xy 138.351339 -401.193442)
			(xy 138.305493 -401.163978) (xy 138.264306 -401.128289) (xy 138.228618 -401.087102) (xy 138.199155 -401.041256)
			(xy 138.176516 -400.991683) (xy 138.161162 -400.939392) (xy 138.153406 -400.885449) (xy 136.715873 -400.885449)
			(xy 136.715873 -400.885457) (xy 136.708114 -400.939416) (xy 136.692755 -400.991721) (xy 136.670107 -401.041308)
			(xy 136.640633 -401.087167) (xy 136.604931 -401.128364) (xy 136.56373 -401.16406) (xy 136.517868 -401.193529)
			(xy 136.468278 -401.216171) (xy 136.415971 -401.231524) (xy 136.362011 -401.239276) (xy 136.334754 -401.239736)
			(xy 135.471154 -401.239736) (xy 135.443907 -401.239191) (xy 135.389968 -401.231429) (xy 135.337683 -401.216071)
			(xy 135.288115 -401.193429) (xy 135.242274 -401.163964) (xy 135.201092 -401.128275) (xy 135.165408 -401.087089)
			(xy 135.135949 -401.041244) (xy 135.113312 -400.991674) (xy 135.097961 -400.939387) (xy 135.090206 -400.885447)
			(xy 133.65255 -400.885447) (xy 133.65255 -400.885453) (xy 133.644793 -400.939403) (xy 133.629438 -400.991701)
			(xy 133.606796 -401.04128) (xy 133.577329 -401.087134) (xy 133.541636 -401.128326) (xy 133.500445 -401.164021)
			(xy 133.454593 -401.193489) (xy 133.405014 -401.216133) (xy 133.352717 -401.23149) (xy 133.298767 -401.239249)
			(xy 133.271514 -401.239736) (xy 132.407914 -401.239736) (xy 132.380662 -401.239218) (xy 132.326714 -401.231463)
			(xy 132.274418 -401.216109) (xy 132.22484 -401.193469) (xy 132.178989 -401.164004) (xy 132.137797 -401.128313)
			(xy 132.102105 -401.087123) (xy 132.072638 -401.041272) (xy 132.049996 -400.991695) (xy 132.03464 -400.9394)
			(xy 132.026883 -400.885451) (xy 130.589373 -400.885451) (xy 130.589373 -400.885456) (xy 130.581615 -400.939413)
			(xy 130.566256 -400.991717) (xy 130.54361 -401.041303) (xy 130.514138 -401.08716) (xy 130.478438 -401.128357)
			(xy 130.43724 -401.164053) (xy 130.39138 -401.193523) (xy 130.341793 -401.216165) (xy 130.289488 -401.23152)
			(xy 130.23553 -401.239275) (xy 130.208274 -401.239736) (xy 129.344674 -401.239736) (xy 129.317426 -401.239192)
			(xy 129.263485 -401.231433) (xy 129.211197 -401.216077) (xy 129.161627 -401.193436) (xy 129.115783 -401.163971)
			(xy 129.074599 -401.128282) (xy 129.038913 -401.087096) (xy 129.009452 -401.04125) (xy 128.986814 -400.991678)
			(xy 128.971461 -400.939389) (xy 128.963706 -400.885448) (xy 127.52605 -400.885448) (xy 127.52605 -400.885452)
			(xy 127.518294 -400.9394) (xy 127.50294 -400.991696) (xy 127.480299 -401.041275) (xy 127.450834 -401.087127)
			(xy 127.415143 -401.128319) (xy 127.373954 -401.164014) (xy 127.328105 -401.193483) (xy 127.278528 -401.216128)
			(xy 127.226234 -401.231487) (xy 127.172286 -401.239248) (xy 127.145034 -401.239736) (xy 126.281434 -401.239736)
			(xy 126.254182 -401.239219) (xy 126.200231 -401.231467) (xy 126.147933 -401.216115) (xy 126.098352 -401.193476)
			(xy 126.052498 -401.164011) (xy 126.011304 -401.12832) (xy 125.97561 -401.087129) (xy 125.946141 -401.041278)
			(xy 125.923497 -400.991699) (xy 125.908141 -400.939402) (xy 125.900383 -400.885452) (xy 124.462873 -400.885452)
			(xy 124.462873 -400.885455) (xy 124.455115 -400.939411) (xy 124.439758 -400.991713) (xy 124.417113 -401.041297)
			(xy 124.387643 -401.087154) (xy 124.351946 -401.12835) (xy 124.310749 -401.164046) (xy 124.264892 -401.193516)
			(xy 124.215307 -401.21616) (xy 124.163005 -401.231517) (xy 124.109049 -401.239273) (xy 124.081794 -401.239736)
			(xy 123.218194 -401.239736) (xy 123.190945 -401.239193) (xy 123.137002 -401.231437) (xy 123.084712 -401.216082)
			(xy 123.035139 -401.193442) (xy 122.989293 -401.163978) (xy 122.948106 -401.128289) (xy 122.912418 -401.087102)
			(xy 122.882955 -401.041256) (xy 122.860316 -400.991683) (xy 122.844962 -400.939392) (xy 122.837206 -400.885449)
			(xy 121.399673 -400.885449) (xy 121.399673 -400.885457) (xy 121.391914 -400.939416) (xy 121.376555 -400.991721)
			(xy 121.353907 -401.041308) (xy 121.324433 -401.087167) (xy 121.288731 -401.128364) (xy 121.24753 -401.16406)
			(xy 121.201668 -401.193529) (xy 121.152078 -401.216171) (xy 121.099771 -401.231524) (xy 121.045811 -401.239276)
			(xy 121.018554 -401.239736) (xy 120.154954 -401.239736) (xy 120.127707 -401.239191) (xy 120.073768 -401.231429)
			(xy 120.021483 -401.216071) (xy 119.971915 -401.193429) (xy 119.926074 -401.163964) (xy 119.884892 -401.128275)
			(xy 119.849208 -401.087089) (xy 119.819749 -401.041244) (xy 119.797112 -400.991674) (xy 119.781761 -400.939387)
			(xy 119.774006 -400.885447) (xy 95.17305 -400.885447) (xy 95.17305 -400.885452) (xy 95.165294 -400.9394)
			(xy 95.14994 -400.991695) (xy 95.1273 -401.041274) (xy 95.097835 -401.087126) (xy 95.062145 -401.128318)
			(xy 95.020956 -401.164012) (xy 94.975107 -401.193482) (xy 94.925531 -401.216127) (xy 94.873237 -401.231486)
			(xy 94.819289 -401.239248) (xy 94.792038 -401.239736) (xy 93.928438 -401.239736) (xy 93.901185 -401.239219)
			(xy 93.847234 -401.231467) (xy 93.794936 -401.216116) (xy 93.745354 -401.193477) (xy 93.6995 -401.164012)
			(xy 93.658306 -401.128321) (xy 93.622611 -401.087131) (xy 93.593141 -401.041279) (xy 93.570498 -400.9917)
			(xy 93.555141 -400.939403) (xy 93.547383 -400.885453) (xy 92.109873 -400.885453) (xy 92.109873 -400.885455)
			(xy 92.102115 -400.93941) (xy 92.086758 -400.991712) (xy 92.064114 -401.041296) (xy 92.034643 -401.087153)
			(xy 91.998947 -401.128348) (xy 91.957751 -401.164045) (xy 91.911894 -401.193515) (xy 91.86231 -401.216159)
			(xy 91.810008 -401.231516) (xy 91.756053 -401.239273) (xy 91.728798 -401.239736) (xy 90.865198 -401.239736)
			(xy 90.837949 -401.239194) (xy 90.784005 -401.231437) (xy 90.731715 -401.216083) (xy 90.682142 -401.193444)
			(xy 90.636295 -401.16398) (xy 90.595108 -401.128291) (xy 90.559419 -401.087104) (xy 90.529955 -401.041257)
			(xy 90.507316 -400.991683) (xy 90.491962 -400.939393) (xy 90.484206 -400.885449) (xy 89.046673 -400.885449)
			(xy 89.046673 -400.885457) (xy 89.038914 -400.939415) (xy 89.023555 -400.991721) (xy 89.000908 -401.041307)
			(xy 88.971434 -401.087166) (xy 88.935733 -401.128363) (xy 88.894532 -401.164059) (xy 88.84867 -401.193528)
			(xy 88.799081 -401.21617) (xy 88.746774 -401.231523) (xy 88.692815 -401.239276) (xy 88.665558 -401.239736)
			(xy 87.801958 -401.239736) (xy 87.774711 -401.239191) (xy 87.720772 -401.23143) (xy 87.668486 -401.216073)
			(xy 87.618918 -401.193431) (xy 87.573076 -401.163965) (xy 87.531894 -401.128277) (xy 87.496209 -401.087091)
			(xy 87.466749 -401.041246) (xy 87.444113 -400.991675) (xy 87.428761 -400.939387) (xy 87.421006 -400.885447)
			(xy 85.98335 -400.885447) (xy 85.98335 -400.885452) (xy 85.975594 -400.939403) (xy 85.960238 -400.9917)
			(xy 85.937597 -401.041279) (xy 85.90813 -401.087132) (xy 85.872438 -401.128325) (xy 85.831247 -401.164019)
			(xy 85.785395 -401.193488) (xy 85.735817 -401.216132) (xy 85.68352 -401.23149) (xy 85.62957 -401.239249)
			(xy 85.602318 -401.239736) (xy 84.738718 -401.239736) (xy 84.711466 -401.239218) (xy 84.657517 -401.231464)
			(xy 84.605221 -401.21611) (xy 84.555642 -401.19347) (xy 84.50979 -401.164005) (xy 84.468599 -401.128314)
			(xy 84.432906 -401.087124) (xy 84.403438 -401.041273) (xy 84.380796 -400.991696) (xy 84.36544 -400.9394)
			(xy 84.357683 -400.885452) (xy 82.920173 -400.885452) (xy 82.920173 -400.885456) (xy 82.912415 -400.939413)
			(xy 82.897057 -400.991716) (xy 82.874411 -401.041302) (xy 82.844939 -401.087159) (xy 82.80924 -401.128355)
			(xy 82.768042 -401.164052) (xy 82.722182 -401.193521) (xy 82.672596 -401.216164) (xy 82.620291 -401.23152)
			(xy 82.566334 -401.239275) (xy 82.539078 -401.239736) (xy 81.675478 -401.239736) (xy 81.64823 -401.239192)
			(xy 81.594288 -401.231434) (xy 81.542 -401.216078) (xy 81.49243 -401.193437) (xy 81.446585 -401.163973)
			(xy 81.405401 -401.128284) (xy 81.369714 -401.087097) (xy 81.340252 -401.041251) (xy 81.317614 -400.991679)
			(xy 81.302262 -400.93939) (xy 81.294506 -400.885448) (xy 79.85685 -400.885448) (xy 79.85685 -400.885452)
			(xy 79.849094 -400.9394) (xy 79.83374 -400.991695) (xy 79.8111 -401.041274) (xy 79.781635 -401.087126)
			(xy 79.745945 -401.128318) (xy 79.704756 -401.164012) (xy 79.658907 -401.193482) (xy 79.609331 -401.216127)
			(xy 79.557037 -401.231486) (xy 79.503089 -401.239248) (xy 79.475838 -401.239736) (xy 78.612238 -401.239736)
			(xy 78.584985 -401.239219) (xy 78.531034 -401.231467) (xy 78.478736 -401.216116) (xy 78.429154 -401.193477)
			(xy 78.3833 -401.164012) (xy 78.342106 -401.128321) (xy 78.306411 -401.087131) (xy 78.276941 -401.041279)
			(xy 78.254298 -400.9917) (xy 78.238941 -400.939403) (xy 78.231183 -400.885453) (xy 76.793673 -400.885453)
			(xy 76.793673 -400.885455) (xy 76.785915 -400.93941) (xy 76.770558 -400.991712) (xy 76.747914 -401.041296)
			(xy 76.718443 -401.087153) (xy 76.682747 -401.128348) (xy 76.641551 -401.164045) (xy 76.595694 -401.193515)
			(xy 76.54611 -401.216159) (xy 76.493808 -401.231516) (xy 76.439853 -401.239273) (xy 76.412598 -401.239736)
			(xy 75.548998 -401.239736) (xy 75.521749 -401.239194) (xy 75.467805 -401.231437) (xy 75.415515 -401.216083)
			(xy 75.365942 -401.193444) (xy 75.320095 -401.16398) (xy 75.278908 -401.128291) (xy 75.243219 -401.087104)
			(xy 75.213755 -401.041257) (xy 75.191116 -400.991683) (xy 75.175762 -400.939393) (xy 75.168006 -400.885449)
			(xy 73.730473 -400.885449) (xy 73.730473 -400.885457) (xy 73.722714 -400.939415) (xy 73.707355 -400.991721)
			(xy 73.684708 -401.041307) (xy 73.655234 -401.087166) (xy 73.619533 -401.128363) (xy 73.578332 -401.164059)
			(xy 73.53247 -401.193528) (xy 73.482881 -401.21617) (xy 73.430574 -401.231523) (xy 73.376615 -401.239276)
			(xy 73.349358 -401.239736) (xy 72.485758 -401.239736) (xy 72.458511 -401.239191) (xy 72.404572 -401.23143)
			(xy 72.352286 -401.216073) (xy 72.302718 -401.193431) (xy 72.256876 -401.163965) (xy 72.215694 -401.128277)
			(xy 72.180009 -401.087091) (xy 72.150549 -401.041246) (xy 72.127913 -400.991675) (xy 72.112561 -400.939387)
			(xy 72.104806 -400.885447) (xy 70.66715 -400.885447) (xy 70.66715 -400.885452) (xy 70.659394 -400.939403)
			(xy 70.644038 -400.9917) (xy 70.621397 -401.041279) (xy 70.59193 -401.087132) (xy 70.556238 -401.128325)
			(xy 70.515047 -401.164019) (xy 70.469195 -401.193488) (xy 70.419617 -401.216132) (xy 70.36732 -401.23149)
			(xy 70.31337 -401.239249) (xy 70.286118 -401.239736) (xy 69.422518 -401.239736) (xy 69.395266 -401.239218)
			(xy 69.341317 -401.231464) (xy 69.289021 -401.21611) (xy 69.239442 -401.19347) (xy 69.19359 -401.164005)
			(xy 69.152399 -401.128314) (xy 69.116706 -401.087124) (xy 69.087238 -401.041273) (xy 69.064596 -400.991696)
			(xy 69.04924 -400.9394) (xy 69.041483 -400.885452) (xy 67.603973 -400.885452) (xy 67.603973 -400.885456)
			(xy 67.596215 -400.939413) (xy 67.580857 -400.991716) (xy 67.558211 -401.041302) (xy 67.528739 -401.087159)
			(xy 67.49304 -401.128355) (xy 67.451842 -401.164052) (xy 67.405982 -401.193521) (xy 67.356396 -401.216164)
			(xy 67.304091 -401.23152) (xy 67.250134 -401.239275) (xy 67.222878 -401.239736) (xy 66.359278 -401.239736)
			(xy 66.33203 -401.239192) (xy 66.278088 -401.231434) (xy 66.2258 -401.216078) (xy 66.17623 -401.193437)
			(xy 66.130385 -401.163973) (xy 66.089201 -401.128284) (xy 66.053514 -401.087097) (xy 66.024052 -401.041251)
			(xy 66.001414 -400.991679) (xy 65.986062 -400.93939) (xy 65.978306 -400.885448) (xy 64.54065 -400.885448)
			(xy 64.54065 -400.885452) (xy 64.532894 -400.9394) (xy 64.51754 -400.991695) (xy 64.4949 -401.041274)
			(xy 64.465435 -401.087126) (xy 64.429745 -401.128318) (xy 64.388556 -401.164012) (xy 64.342707 -401.193482)
			(xy 64.293131 -401.216127) (xy 64.240837 -401.231486) (xy 64.186889 -401.239248) (xy 64.159638 -401.239736)
			(xy 63.296038 -401.239736) (xy 63.268785 -401.239219) (xy 63.214834 -401.231467) (xy 63.162536 -401.216116)
			(xy 63.112954 -401.193477) (xy 63.0671 -401.164012) (xy 63.025906 -401.128321) (xy 62.990211 -401.087131)
			(xy 62.960741 -401.041279) (xy 62.938098 -400.9917) (xy 62.922741 -400.939403) (xy 62.914983 -400.885453)
			(xy 61.477473 -400.885453) (xy 61.477473 -400.885455) (xy 61.469715 -400.93941) (xy 61.454358 -400.991712)
			(xy 61.431714 -401.041296) (xy 61.402243 -401.087153) (xy 61.366547 -401.128348) (xy 61.325351 -401.164045)
			(xy 61.279494 -401.193515) (xy 61.22991 -401.216159) (xy 61.177608 -401.231516) (xy 61.123653 -401.239273)
			(xy 61.096398 -401.239736) (xy 60.232798 -401.239736) (xy 60.205549 -401.239194) (xy 60.151605 -401.231437)
			(xy 60.099315 -401.216083) (xy 60.049742 -401.193444) (xy 60.003895 -401.16398) (xy 59.962708 -401.128291)
			(xy 59.927019 -401.087104) (xy 59.897555 -401.041257) (xy 59.874916 -400.991683) (xy 59.859562 -400.939393)
			(xy 59.851806 -400.885449) (xy 58.414273 -400.885449) (xy 58.414273 -400.885457) (xy 58.406514 -400.939415)
			(xy 58.391155 -400.991721) (xy 58.368508 -401.041307) (xy 58.339034 -401.087166) (xy 58.303333 -401.128363)
			(xy 58.262132 -401.164059) (xy 58.21627 -401.193528) (xy 58.166681 -401.21617) (xy 58.114374 -401.231523)
			(xy 58.060415 -401.239276) (xy 58.033158 -401.239736) (xy 57.169558 -401.239736) (xy 57.142311 -401.239191)
			(xy 57.088372 -401.23143) (xy 57.036086 -401.216073) (xy 56.986518 -401.193431) (xy 56.940676 -401.163965)
			(xy 56.899494 -401.128277) (xy 56.863809 -401.087091) (xy 56.834349 -401.041246) (xy 56.811713 -400.991675)
			(xy 56.796361 -400.939387) (xy 56.788606 -400.885447) (xy 55.35095 -400.885447) (xy 55.35095 -400.885452)
			(xy 55.343194 -400.939403) (xy 55.327838 -400.9917) (xy 55.305197 -401.041279) (xy 55.27573 -401.087132)
			(xy 55.240038 -401.128325) (xy 55.198847 -401.164019) (xy 55.152995 -401.193488) (xy 55.103417 -401.216132)
			(xy 55.05112 -401.23149) (xy 54.99717 -401.239249) (xy 54.969918 -401.239736) (xy 54.106318 -401.239736)
			(xy 54.079066 -401.239218) (xy 54.025117 -401.231464) (xy 53.972821 -401.21611) (xy 53.923242 -401.19347)
			(xy 53.87739 -401.164005) (xy 53.836199 -401.128314) (xy 53.800506 -401.087124) (xy 53.771038 -401.041273)
			(xy 53.748396 -400.991696) (xy 53.73304 -400.9394) (xy 53.725283 -400.885452) (xy 52.287773 -400.885452)
			(xy 52.287773 -400.885456) (xy 52.280015 -400.939413) (xy 52.264657 -400.991716) (xy 52.242011 -401.041302)
			(xy 52.212539 -401.087159) (xy 52.17684 -401.128355) (xy 52.135642 -401.164052) (xy 52.089782 -401.193521)
			(xy 52.040196 -401.216164) (xy 51.987891 -401.23152) (xy 51.933934 -401.239275) (xy 51.906678 -401.239736)
			(xy 51.043078 -401.239736) (xy 51.01583 -401.239192) (xy 50.961888 -401.231434) (xy 50.9096 -401.216078)
			(xy 50.86003 -401.193437) (xy 50.814185 -401.163973) (xy 50.773001 -401.128284) (xy 50.737314 -401.087097)
			(xy 50.707852 -401.041251) (xy 50.685214 -400.991679) (xy 50.669862 -400.93939) (xy 50.662106 -400.885448)
			(xy 49.22445 -400.885448) (xy 49.22445 -400.885452) (xy 49.216694 -400.9394) (xy 49.20134 -400.991695)
			(xy 49.1787 -401.041274) (xy 49.149235 -401.087126) (xy 49.113545 -401.128318) (xy 49.072356 -401.164012)
			(xy 49.026507 -401.193482) (xy 48.976931 -401.216127) (xy 48.924637 -401.231486) (xy 48.870689 -401.239248)
			(xy 48.843438 -401.239736) (xy 47.979838 -401.239736) (xy 47.952585 -401.239219) (xy 47.898634 -401.231467)
			(xy 47.846336 -401.216116) (xy 47.796754 -401.193477) (xy 47.7509 -401.164012) (xy 47.709706 -401.128321)
			(xy 47.674011 -401.087131) (xy 47.644541 -401.041279) (xy 47.621898 -400.9917) (xy 47.606541 -400.939403)
			(xy 47.598783 -400.885453) (xy 2.509012 -400.885453) (xy 2.509012 -402.10994) (xy 239.42294 -402.10994)
			(xy 239.42294 -397.53286) (xy 239.423521 -397.5079) (xy 239.433246 -397.458937) (xy 239.452353 -397.412819)
			(xy 239.480105 -397.371324) (xy 239.497362 -397.353282) (xy 239.885982 -396.964662) (xy 239.904032 -396.947415)
			(xy 239.945531 -396.919673) (xy 239.991645 -396.900562) (xy 240.040601 -396.890815) (xy 240.06556 -396.89024)
			(xy 280.24074 -396.89024) (xy 280.2657 -396.890821) (xy 280.314663 -396.900546) (xy 280.360781 -396.919653)
			(xy 280.402276 -396.947405) (xy 280.420318 -396.964662) (xy 280.689558 -397.233902) (xy 280.706818 -397.25194)
			(xy 280.734556 -397.293444) (xy 280.753664 -397.339561) (xy 280.763407 -397.38852) (xy 280.76398 -397.41348)
			(xy 280.76398 -398.65534) (xy 457.185003 -398.65534) (xy 457.185003 -398.5262) (xy 457.192953 -398.397305)
			(xy 457.208823 -398.269145) (xy 457.232552 -398.142204) (xy 457.264051 -398.016965) (xy 457.3032 -397.893902)
			(xy 457.349851 -397.773483) (xy 457.403826 -397.656164) (xy 457.464921 -397.54239) (xy 457.532904 -397.432593)
			(xy 457.607518 -397.32719) (xy 457.688479 -397.22658) (xy 457.775479 -397.131145) (xy 457.86819 -397.041246)
			(xy 457.96626 -396.957225) (xy 458.069315 -396.879401) (xy 458.176966 -396.808069) (xy 458.288805 -396.743499)
			(xy 458.404406 -396.685937) (xy 458.523331 -396.6356) (xy 458.64513 -396.59268) (xy 458.76934 -396.557339)
			(xy 458.895489 -396.529712) (xy 459.023101 -396.509903) (xy 459.15169 -396.497987) (xy 459.280768 -396.494011)
			(xy 459.409846 -396.497987) (xy 459.538435 -396.509903) (xy 459.666047 -396.529712) (xy 459.792196 -396.557339)
			(xy 459.916406 -396.59268) (xy 460.038205 -396.6356) (xy 460.15713 -396.685937) (xy 460.272731 -396.743499)
			(xy 460.38457 -396.808069) (xy 460.492221 -396.879401) (xy 460.595276 -396.957225) (xy 460.693346 -397.041246)
			(xy 460.786057 -397.131145) (xy 460.873057 -397.22658) (xy 460.954018 -397.32719) (xy 461.028632 -397.432593)
			(xy 461.096615 -397.54239) (xy 461.15771 -397.656164) (xy 461.211685 -397.773483) (xy 461.258336 -397.893902)
			(xy 461.297485 -398.016965) (xy 461.328984 -398.142204) (xy 461.352713 -398.269145) (xy 461.368583 -398.397305)
			(xy 461.376533 -398.5262) (xy 461.37703 -398.59077) (xy 461.376533 -398.65534) (xy 461.368583 -398.784235)
			(xy 461.352713 -398.912395) (xy 461.328984 -399.039336) (xy 461.297485 -399.164575) (xy 461.258336 -399.287638)
			(xy 461.211685 -399.408057) (xy 461.15771 -399.525376) (xy 461.096615 -399.63915) (xy 461.028632 -399.748947)
			(xy 460.954018 -399.85435) (xy 460.873057 -399.95496) (xy 460.786057 -400.050395) (xy 460.693346 -400.140294)
			(xy 460.595276 -400.224315) (xy 460.492221 -400.302139) (xy 460.38457 -400.373471) (xy 460.272731 -400.438041)
			(xy 460.15713 -400.495603) (xy 460.038205 -400.54594) (xy 459.916406 -400.58886) (xy 459.792196 -400.624201)
			(xy 459.666047 -400.651828) (xy 459.538435 -400.671637) (xy 459.409846 -400.683553) (xy 459.280768 -400.68753)
			(xy 459.15169 -400.683553) (xy 459.023101 -400.671637) (xy 458.895489 -400.651828) (xy 458.76934 -400.624201)
			(xy 458.64513 -400.58886) (xy 458.523331 -400.54594) (xy 458.404406 -400.495603) (xy 458.288805 -400.438041)
			(xy 458.176966 -400.373471) (xy 458.069315 -400.302139) (xy 457.96626 -400.224315) (xy 457.86819 -400.140294)
			(xy 457.775479 -400.050395) (xy 457.688479 -399.95496) (xy 457.607518 -399.85435) (xy 457.532904 -399.748947)
			(xy 457.464921 -399.63915) (xy 457.403826 -399.525376) (xy 457.349851 -399.408057) (xy 457.3032 -399.287638)
			(xy 457.264051 -399.164575) (xy 457.232552 -399.039336) (xy 457.208823 -398.912395) (xy 457.192953 -398.784235)
			(xy 457.185003 -398.65534) (xy 280.76398 -398.65534) (xy 280.76398 -399.9835) (xy 289.606441 -399.9835)
			(xy 289.610455 -399.919698) (xy 289.622434 -399.856902) (xy 289.642189 -399.796103) (xy 289.669408 -399.73826)
			(xy 289.703662 -399.684283) (xy 289.744411 -399.635026) (xy 289.791013 -399.591264) (xy 289.842731 -399.553688)
			(xy 289.898752 -399.52289) (xy 289.958191 -399.499357) (xy 290.02011 -399.483458) (xy 290.083534 -399.475446)
			(xy 290.115498 -399.474944) (xy 290.115752 -399.474944) (xy 290.147498 -399.475464) (xy 290.210494 -399.483393)
			(xy 290.272014 -399.499096) (xy 290.331102 -399.52233) (xy 290.386842 -399.552733) (xy 290.438367 -399.589834)
			(xy 290.461954 -399.611088) (xy 290.469217 -399.617272) (xy 290.486967 -399.624223) (xy 290.506029 -399.624223)
			(xy 290.523779 -399.617272) (xy 290.531042 -399.611088) (xy 290.554631 -399.589832) (xy 290.60614 -399.5527)
			(xy 290.661874 -399.522276) (xy 290.720965 -399.499035) (xy 290.782492 -399.483338) (xy 290.845495 -399.475431)
			(xy 290.877244 -399.474944) (xy 290.877498 -399.474944) (xy 290.909457 -399.475521) (xy 290.972872 -399.483532)
			(xy 291.034783 -399.499427) (xy 291.094213 -399.522957) (xy 291.150226 -399.55375) (xy 291.201937 -399.591321)
			(xy 291.248532 -399.635076) (xy 291.289276 -399.684326) (xy 291.323525 -399.738295) (xy 291.350741 -399.79613)
			(xy 291.370493 -399.856921) (xy 291.38247 -399.919707) (xy 291.386484 -399.9835) (xy 292.146441 -399.9835)
			(xy 292.150455 -399.919698) (xy 292.162434 -399.856902) (xy 292.182189 -399.796103) (xy 292.209408 -399.73826)
			(xy 292.243662 -399.684283) (xy 292.284411 -399.635026) (xy 292.331013 -399.591264) (xy 292.382731 -399.553688)
			(xy 292.438752 -399.52289) (xy 292.498191 -399.499357) (xy 292.56011 -399.483458) (xy 292.623534 -399.475446)
			(xy 292.655498 -399.474944) (xy 292.655752 -399.474944) (xy 292.687498 -399.475464) (xy 292.750494 -399.483393)
			(xy 292.812014 -399.499096) (xy 292.871102 -399.52233) (xy 292.926842 -399.552733) (xy 292.978367 -399.589834)
			(xy 293.001954 -399.611088) (xy 293.009217 -399.617272) (xy 293.026967 -399.624223) (xy 293.046029 -399.624223)
			(xy 293.063779 -399.617272) (xy 293.071042 -399.611088) (xy 293.094631 -399.589832) (xy 293.14614 -399.5527)
			(xy 293.201874 -399.522276) (xy 293.260965 -399.499035) (xy 293.322492 -399.483338) (xy 293.385495 -399.475431)
			(xy 293.417244 -399.474944) (xy 293.417498 -399.474944) (xy 293.449457 -399.475521) (xy 293.512872 -399.483532)
			(xy 293.574783 -399.499427) (xy 293.634213 -399.522957) (xy 293.690226 -399.55375) (xy 293.741937 -399.591321)
			(xy 293.788532 -399.635076) (xy 293.829276 -399.684326) (xy 293.863525 -399.738295) (xy 293.890741 -399.79613)
			(xy 293.910493 -399.856921) (xy 293.92247 -399.919707) (xy 293.926484 -399.9835) (xy 294.53602 -399.9835)
			(xy 294.540035 -399.919693) (xy 294.552015 -399.856892) (xy 294.571773 -399.796089) (xy 294.598995 -399.738241)
			(xy 294.633253 -399.684261) (xy 294.674007 -399.635001) (xy 294.720613 -399.591237) (xy 294.772338 -399.55366)
			(xy 294.828364 -399.522862) (xy 294.887809 -399.499329) (xy 294.949734 -399.483433) (xy 295.013163 -399.475423)
			(xy 295.04513 -399.474944) (xy 295.045384 -399.474944) (xy 295.077131 -399.475444) (xy 295.140127 -399.483377)
			(xy 295.201647 -399.499084) (xy 295.260736 -399.522322) (xy 295.316476 -399.552728) (xy 295.368 -399.589832)
			(xy 295.391586 -399.611088) (xy 295.398849 -399.617272) (xy 295.416599 -399.624223) (xy 295.435661 -399.624223)
			(xy 295.453411 -399.617272) (xy 295.460674 -399.611088) (xy 295.48425 -399.589817) (xy 295.535761 -399.552686)
			(xy 295.591498 -399.522265) (xy 295.650592 -399.499026) (xy 295.712121 -399.483332) (xy 295.775126 -399.475429)
			(xy 295.806876 -399.474944) (xy 295.80713 -399.474944) (xy 295.839087 -399.475544) (xy 295.902496 -399.483558)
			(xy 295.964401 -399.499455) (xy 296.023825 -399.522986) (xy 296.079832 -399.553779) (xy 296.131538 -399.591348)
			(xy 296.178128 -399.635102) (xy 296.218866 -399.684349) (xy 296.253112 -399.738314) (xy 296.280324 -399.796145)
			(xy 296.300074 -399.856931) (xy 296.312049 -399.919712) (xy 296.316063 -399.9835) (xy 297.07602 -399.9835)
			(xy 297.080035 -399.919693) (xy 297.092015 -399.856892) (xy 297.111773 -399.796089) (xy 297.138995 -399.738241)
			(xy 297.173253 -399.684261) (xy 297.214007 -399.635001) (xy 297.260613 -399.591237) (xy 297.312338 -399.55366)
			(xy 297.368364 -399.522862) (xy 297.427809 -399.499329) (xy 297.489734 -399.483433) (xy 297.553163 -399.475423)
			(xy 297.58513 -399.474944) (xy 297.585384 -399.474944) (xy 297.617131 -399.475444) (xy 297.680127 -399.483377)
			(xy 297.741647 -399.499084) (xy 297.800736 -399.522322) (xy 297.856476 -399.552728) (xy 297.908 -399.589832)
			(xy 297.931586 -399.611088) (xy 297.938849 -399.617272) (xy 297.956599 -399.624223) (xy 297.975661 -399.624223)
			(xy 297.993411 -399.617272) (xy 298.000674 -399.611088) (xy 298.02425 -399.589817) (xy 298.075761 -399.552686)
			(xy 298.131498 -399.522265) (xy 298.190592 -399.499026) (xy 298.252121 -399.483332) (xy 298.315126 -399.475429)
			(xy 298.346876 -399.474944) (xy 298.34713 -399.474944) (xy 298.379087 -399.475544) (xy 298.442496 -399.483558)
			(xy 298.504401 -399.499455) (xy 298.563825 -399.522986) (xy 298.619832 -399.553779) (xy 298.671538 -399.591348)
			(xy 298.718128 -399.635102) (xy 298.758866 -399.684349) (xy 298.793112 -399.738314) (xy 298.820324 -399.796145)
			(xy 298.840074 -399.856931) (xy 298.852049 -399.919712) (xy 298.856063 -399.9835) (xy 298.852049 -400.047288)
			(xy 298.840074 -400.110069) (xy 298.820324 -400.170855) (xy 298.793112 -400.228686) (xy 298.758866 -400.282651)
			(xy 298.718128 -400.331898) (xy 298.671538 -400.375652) (xy 298.619832 -400.413221) (xy 298.563825 -400.444014)
			(xy 298.504401 -400.467545) (xy 298.442496 -400.483442) (xy 298.379087 -400.491456) (xy 298.34713 -400.49196)
			(xy 298.346876 -400.49196) (xy 298.315131 -400.491422) (xy 298.252136 -400.483497) (xy 298.190616 -400.467797)
			(xy 298.131527 -400.444566) (xy 298.075787 -400.414166) (xy 298.024261 -400.377069) (xy 298.000674 -400.355816)
			(xy 297.993411 -400.349632) (xy 297.975661 -400.342681) (xy 297.956599 -400.342681) (xy 297.938849 -400.349632)
			(xy 297.931586 -400.355816) (xy 297.908028 -400.377107) (xy 297.856512 -400.414235) (xy 297.800771 -400.444654)
			(xy 297.741674 -400.467889) (xy 297.680142 -400.483579) (xy 297.617135 -400.491478) (xy 297.585384 -400.49196)
			(xy 297.58513 -400.49196) (xy 297.553163 -400.491577) (xy 297.489734 -400.483567) (xy 297.427809 -400.467671)
			(xy 297.368364 -400.444138) (xy 297.312338 -400.41334) (xy 297.260613 -400.375763) (xy 297.214007 -400.331999)
			(xy 297.173253 -400.282739) (xy 297.138995 -400.228759) (xy 297.111773 -400.170911) (xy 297.092015 -400.110108)
			(xy 297.080035 -400.047307) (xy 297.07602 -399.9835) (xy 296.316063 -399.9835) (xy 296.312049 -400.047288)
			(xy 296.300074 -400.110069) (xy 296.280324 -400.170855) (xy 296.253112 -400.228686) (xy 296.218866 -400.282651)
			(xy 296.178128 -400.331898) (xy 296.131538 -400.375652) (xy 296.079832 -400.413221) (xy 296.023825 -400.444014)
			(xy 295.964401 -400.467545) (xy 295.902496 -400.483442) (xy 295.839087 -400.491456) (xy 295.80713 -400.49196)
			(xy 295.806876 -400.49196) (xy 295.775131 -400.491422) (xy 295.712136 -400.483497) (xy 295.650616 -400.467797)
			(xy 295.591527 -400.444566) (xy 295.535787 -400.414166) (xy 295.484261 -400.377069) (xy 295.460674 -400.355816)
			(xy 295.453411 -400.349632) (xy 295.435661 -400.342681) (xy 295.416599 -400.342681) (xy 295.398849 -400.349632)
			(xy 295.391586 -400.355816) (xy 295.368028 -400.377107) (xy 295.316512 -400.414235) (xy 295.260771 -400.444654)
			(xy 295.201674 -400.467889) (xy 295.140142 -400.483579) (xy 295.077135 -400.491478) (xy 295.045384 -400.49196)
			(xy 295.04513 -400.49196) (xy 295.013163 -400.491577) (xy 294.949734 -400.483567) (xy 294.887809 -400.467671)
			(xy 294.828364 -400.444138) (xy 294.772338 -400.41334) (xy 294.720613 -400.375763) (xy 294.674007 -400.331999)
			(xy 294.633253 -400.282739) (xy 294.598995 -400.228759) (xy 294.571773 -400.170911) (xy 294.552015 -400.110108)
			(xy 294.540035 -400.047307) (xy 294.53602 -399.9835) (xy 293.926484 -399.9835) (xy 293.92247 -400.047293)
			(xy 293.910493 -400.110079) (xy 293.890741 -400.17087) (xy 293.863525 -400.228705) (xy 293.829276 -400.282674)
			(xy 293.788532 -400.331924) (xy 293.741937 -400.375679) (xy 293.690226 -400.41325) (xy 293.634213 -400.444043)
			(xy 293.574783 -400.467573) (xy 293.512872 -400.483468) (xy 293.449457 -400.491479) (xy 293.417498 -400.49196)
			(xy 293.417244 -400.49196) (xy 293.385498 -400.491442) (xy 293.322502 -400.483512) (xy 293.260982 -400.467809)
			(xy 293.201894 -400.444575) (xy 293.146154 -400.414171) (xy 293.094629 -400.37707) (xy 293.071042 -400.355816)
			(xy 293.063779 -400.349632) (xy 293.046029 -400.342681) (xy 293.026967 -400.342681) (xy 293.009217 -400.349632)
			(xy 293.001954 -400.355816) (xy 292.978367 -400.377074) (xy 292.926858 -400.414206) (xy 292.871123 -400.44463)
			(xy 292.812032 -400.467871) (xy 292.750504 -400.483567) (xy 292.687501 -400.491474) (xy 292.655752 -400.49196)
			(xy 292.655498 -400.49196) (xy 292.623534 -400.491554) (xy 292.56011 -400.483542) (xy 292.498191 -400.467643)
			(xy 292.438752 -400.44411) (xy 292.382731 -400.413312) (xy 292.331013 -400.375736) (xy 292.284411 -400.331974)
			(xy 292.243662 -400.282717) (xy 292.209408 -400.22874) (xy 292.182189 -400.170897) (xy 292.162434 -400.110098)
			(xy 292.150455 -400.047302) (xy 292.146441 -399.9835) (xy 291.386484 -399.9835) (xy 291.38247 -400.047293)
			(xy 291.370493 -400.110079) (xy 291.350741 -400.17087) (xy 291.323525 -400.228705) (xy 291.289276 -400.282674)
			(xy 291.248532 -400.331924) (xy 291.201937 -400.375679) (xy 291.150226 -400.41325) (xy 291.094213 -400.444043)
			(xy 291.034783 -400.467573) (xy 290.972872 -400.483468) (xy 290.909457 -400.491479) (xy 290.877498 -400.49196)
			(xy 290.877244 -400.49196) (xy 290.845498 -400.491442) (xy 290.782502 -400.483512) (xy 290.720982 -400.467809)
			(xy 290.661894 -400.444575) (xy 290.606154 -400.414171) (xy 290.554629 -400.37707) (xy 290.531042 -400.355816)
			(xy 290.523779 -400.349632) (xy 290.506029 -400.342681) (xy 290.486967 -400.342681) (xy 290.469217 -400.349632)
			(xy 290.461954 -400.355816) (xy 290.438367 -400.377074) (xy 290.386858 -400.414206) (xy 290.331123 -400.44463)
			(xy 290.272032 -400.467871) (xy 290.210504 -400.483567) (xy 290.147501 -400.491474) (xy 290.115752 -400.49196)
			(xy 290.115498 -400.49196) (xy 290.083534 -400.491554) (xy 290.02011 -400.483542) (xy 289.958191 -400.467643)
			(xy 289.898752 -400.44411) (xy 289.842731 -400.413312) (xy 289.791013 -400.375736) (xy 289.744411 -400.331974)
			(xy 289.703662 -400.282717) (xy 289.669408 -400.22874) (xy 289.642189 -400.170897) (xy 289.622434 -400.110098)
			(xy 289.610455 -400.047302) (xy 289.606441 -399.9835) (xy 280.76398 -399.9835) (xy 280.76398 -400.885449)
			(xy 303.599106 -400.885449) (xy 303.599106 -400.830951) (xy 303.606862 -400.777009) (xy 303.622215 -400.724719)
			(xy 303.644854 -400.675146) (xy 303.674317 -400.6293) (xy 303.710004 -400.588113) (xy 303.75119 -400.552424)
			(xy 303.797036 -400.52296) (xy 303.846608 -400.500319) (xy 303.898897 -400.484964) (xy 303.952839 -400.477207)
			(xy 303.980088 -400.47672) (xy 304.843688 -400.47672) (xy 304.870943 -400.477126) (xy 304.9249 -400.484882)
			(xy 304.977203 -400.500238) (xy 305.026788 -400.522882) (xy 305.072646 -400.552352) (xy 305.113843 -400.588048)
			(xy 305.149541 -400.629244) (xy 305.179012 -400.675101) (xy 305.201657 -400.724686) (xy 305.217015 -400.776989)
			(xy 305.224773 -400.830945) (xy 305.224773 -400.885452) (xy 306.662283 -400.885452) (xy 306.662283 -400.830948)
			(xy 306.67004 -400.776998) (xy 306.685397 -400.724702) (xy 306.70804 -400.675124) (xy 306.737508 -400.629273)
			(xy 306.773202 -400.588082) (xy 306.814395 -400.552391) (xy 306.860248 -400.522926) (xy 306.909828 -400.500287)
			(xy 306.962126 -400.484935) (xy 307.016076 -400.477181) (xy 307.043328 -400.47672) (xy 307.906928 -400.47672)
			(xy 307.93418 -400.477152) (xy 307.988129 -400.484912) (xy 308.040424 -400.500271) (xy 308.090001 -400.522915)
			(xy 308.135851 -400.552384) (xy 308.177041 -400.588079) (xy 308.212732 -400.629271) (xy 308.242198 -400.675123)
			(xy 308.264839 -400.724702) (xy 308.280194 -400.776999) (xy 308.28795 -400.830948) (xy 308.28795 -400.885448)
			(xy 309.725606 -400.885448) (xy 309.725606 -400.830952) (xy 309.733361 -400.777011) (xy 309.748714 -400.724723)
			(xy 309.771351 -400.675152) (xy 309.800812 -400.629306) (xy 309.836497 -400.58812) (xy 309.877681 -400.552431)
			(xy 309.923524 -400.522966) (xy 309.973093 -400.500325) (xy 310.02538 -400.484968) (xy 310.07932 -400.477208)
			(xy 310.106568 -400.47672) (xy 310.970168 -400.47672) (xy 310.997424 -400.477125) (xy 311.051383 -400.484879)
			(xy 311.103688 -400.500233) (xy 311.153276 -400.522875) (xy 311.199137 -400.552345) (xy 311.240336 -400.588041)
			(xy 311.276036 -400.629238) (xy 311.305509 -400.675096) (xy 311.328156 -400.724682) (xy 311.343515 -400.776986)
			(xy 311.351273 -400.830944) (xy 311.351273 -400.885451) (xy 312.788783 -400.885451) (xy 312.788783 -400.830949)
			(xy 312.79654 -400.777001) (xy 312.811895 -400.724706) (xy 312.834537 -400.675129) (xy 312.864003 -400.629279)
			(xy 312.899695 -400.588089) (xy 312.940886 -400.552398) (xy 312.986736 -400.522933) (xy 313.036314 -400.500292)
			(xy 313.088609 -400.484938) (xy 313.142557 -400.477183) (xy 313.169808 -400.47672) (xy 314.033408 -400.47672)
			(xy 314.060661 -400.47715) (xy 314.114612 -400.484908) (xy 314.166909 -400.500265) (xy 314.216489 -400.522909)
			(xy 314.262342 -400.552377) (xy 314.303534 -400.588071) (xy 314.339228 -400.629264) (xy 314.368695 -400.675118)
			(xy 314.391337 -400.724698) (xy 314.406693 -400.776996) (xy 314.41445 -400.830947) (xy 314.41445 -400.885453)
			(xy 315.851983 -400.885453) (xy 315.851983 -400.830947) (xy 315.859741 -400.776996) (xy 315.875098 -400.724698)
			(xy 315.897743 -400.675118) (xy 315.927213 -400.629266) (xy 315.962909 -400.588075) (xy 316.004105 -400.552384)
			(xy 316.04996 -400.52292) (xy 316.099543 -400.500282) (xy 316.151843 -400.484931) (xy 316.205795 -400.47718)
			(xy 316.233048 -400.47672) (xy 317.096648 -400.47672) (xy 317.123899 -400.477153) (xy 317.177846 -400.484916)
			(xy 317.230138 -400.500276) (xy 317.279713 -400.522922) (xy 317.325561 -400.552391) (xy 317.366748 -400.588086)
			(xy 317.402437 -400.629278) (xy 317.431901 -400.675129) (xy 317.454541 -400.724707) (xy 317.469894 -400.777001)
			(xy 317.47765 -400.830949) (xy 317.47765 -400.885449) (xy 318.915306 -400.885449) (xy 318.915306 -400.830951)
			(xy 318.923062 -400.777009) (xy 318.938415 -400.724719) (xy 318.961054 -400.675146) (xy 318.990517 -400.6293)
			(xy 319.026204 -400.588113) (xy 319.06739 -400.552424) (xy 319.113236 -400.52296) (xy 319.162808 -400.500319)
			(xy 319.215097 -400.484964) (xy 319.269039 -400.477207) (xy 319.296288 -400.47672) (xy 320.159888 -400.47672)
			(xy 320.187143 -400.477126) (xy 320.2411 -400.484882) (xy 320.293403 -400.500238) (xy 320.342988 -400.522882)
			(xy 320.388846 -400.552352) (xy 320.430043 -400.588048) (xy 320.465741 -400.629244) (xy 320.495212 -400.675101)
			(xy 320.517857 -400.724686) (xy 320.533215 -400.776989) (xy 320.540973 -400.830945) (xy 320.540973 -400.885452)
			(xy 321.978483 -400.885452) (xy 321.978483 -400.830948) (xy 321.98624 -400.776998) (xy 322.001597 -400.724702)
			(xy 322.02424 -400.675124) (xy 322.053708 -400.629273) (xy 322.089402 -400.588082) (xy 322.130595 -400.552391)
			(xy 322.176448 -400.522926) (xy 322.226028 -400.500287) (xy 322.278326 -400.484935) (xy 322.332276 -400.477181)
			(xy 322.359528 -400.47672) (xy 323.223128 -400.47672) (xy 323.25038 -400.477152) (xy 323.304329 -400.484912)
			(xy 323.356624 -400.500271) (xy 323.406201 -400.522915) (xy 323.452051 -400.552384) (xy 323.493241 -400.588079)
			(xy 323.528932 -400.629271) (xy 323.558398 -400.675123) (xy 323.581039 -400.724702) (xy 323.596394 -400.776999)
			(xy 323.60415 -400.830948) (xy 323.60415 -400.885448) (xy 325.041806 -400.885448) (xy 325.041806 -400.830952)
			(xy 325.049561 -400.777011) (xy 325.064914 -400.724723) (xy 325.087551 -400.675152) (xy 325.117012 -400.629306)
			(xy 325.152697 -400.58812) (xy 325.193881 -400.552431) (xy 325.239724 -400.522966) (xy 325.289293 -400.500325)
			(xy 325.34158 -400.484968) (xy 325.39552 -400.477208) (xy 325.422768 -400.47672) (xy 326.286368 -400.47672)
			(xy 326.313624 -400.477125) (xy 326.367583 -400.484879) (xy 326.419888 -400.500233) (xy 326.469476 -400.522875)
			(xy 326.515337 -400.552345) (xy 326.556536 -400.588041) (xy 326.592236 -400.629238) (xy 326.621709 -400.675096)
			(xy 326.644356 -400.724682) (xy 326.659715 -400.776986) (xy 326.667473 -400.830944) (xy 326.667473 -400.885451)
			(xy 328.104983 -400.885451) (xy 328.104983 -400.830949) (xy 328.11274 -400.777001) (xy 328.128095 -400.724706)
			(xy 328.150737 -400.675129) (xy 328.180203 -400.629279) (xy 328.215895 -400.588089) (xy 328.257086 -400.552398)
			(xy 328.302936 -400.522933) (xy 328.352514 -400.500292) (xy 328.404809 -400.484938) (xy 328.458757 -400.477183)
			(xy 328.486008 -400.47672) (xy 329.349608 -400.47672) (xy 329.376861 -400.47715) (xy 329.430812 -400.484908)
			(xy 329.483109 -400.500265) (xy 329.532689 -400.522909) (xy 329.578542 -400.552377) (xy 329.619734 -400.588071)
			(xy 329.655428 -400.629264) (xy 329.684895 -400.675118) (xy 329.707537 -400.724698) (xy 329.722893 -400.776996)
			(xy 329.73065 -400.830947) (xy 329.73065 -400.885453) (xy 331.168183 -400.885453) (xy 331.168183 -400.830947)
			(xy 331.175941 -400.776996) (xy 331.191298 -400.724698) (xy 331.213943 -400.675118) (xy 331.243413 -400.629266)
			(xy 331.279109 -400.588075) (xy 331.320305 -400.552384) (xy 331.36616 -400.52292) (xy 331.415743 -400.500282)
			(xy 331.468043 -400.484931) (xy 331.521995 -400.47718) (xy 331.549248 -400.47672) (xy 332.412848 -400.47672)
			(xy 332.440099 -400.477153) (xy 332.494046 -400.484916) (xy 332.546338 -400.500276) (xy 332.595913 -400.522922)
			(xy 332.641761 -400.552391) (xy 332.682948 -400.588086) (xy 332.718637 -400.629278) (xy 332.748101 -400.675129)
			(xy 332.770741 -400.724707) (xy 332.786094 -400.777001) (xy 332.79385 -400.830949) (xy 332.79385 -400.885449)
			(xy 334.231506 -400.885449) (xy 334.231506 -400.830951) (xy 334.239262 -400.777009) (xy 334.254615 -400.724719)
			(xy 334.277254 -400.675146) (xy 334.306717 -400.6293) (xy 334.342404 -400.588113) (xy 334.38359 -400.552424)
			(xy 334.429436 -400.52296) (xy 334.479008 -400.500319) (xy 334.531297 -400.484964) (xy 334.585239 -400.477207)
			(xy 334.612488 -400.47672) (xy 335.476088 -400.47672) (xy 335.503343 -400.477126) (xy 335.5573 -400.484882)
			(xy 335.609603 -400.500238) (xy 335.659188 -400.522882) (xy 335.705046 -400.552352) (xy 335.746243 -400.588048)
			(xy 335.781941 -400.629244) (xy 335.811412 -400.675101) (xy 335.834057 -400.724686) (xy 335.849415 -400.776989)
			(xy 335.857173 -400.830945) (xy 335.857173 -400.885452) (xy 337.294683 -400.885452) (xy 337.294683 -400.830948)
			(xy 337.30244 -400.776998) (xy 337.317797 -400.724702) (xy 337.34044 -400.675124) (xy 337.369908 -400.629273)
			(xy 337.405602 -400.588082) (xy 337.446795 -400.552391) (xy 337.492648 -400.522926) (xy 337.542228 -400.500287)
			(xy 337.594526 -400.484935) (xy 337.648476 -400.477181) (xy 337.675728 -400.47672) (xy 338.539328 -400.47672)
			(xy 338.56658 -400.477152) (xy 338.620529 -400.484912) (xy 338.672824 -400.500271) (xy 338.722401 -400.522915)
			(xy 338.768251 -400.552384) (xy 338.809441 -400.588079) (xy 338.845132 -400.629271) (xy 338.874598 -400.675123)
			(xy 338.897239 -400.724702) (xy 338.912594 -400.776999) (xy 338.92035 -400.830948) (xy 338.92035 -400.885448)
			(xy 340.358006 -400.885448) (xy 340.358006 -400.830952) (xy 340.365761 -400.777011) (xy 340.381114 -400.724723)
			(xy 340.403751 -400.675152) (xy 340.433212 -400.629306) (xy 340.468897 -400.58812) (xy 340.510081 -400.552431)
			(xy 340.555924 -400.522966) (xy 340.605493 -400.500325) (xy 340.65778 -400.484968) (xy 340.71172 -400.477208)
			(xy 340.738968 -400.47672) (xy 341.602568 -400.47672) (xy 341.629824 -400.477125) (xy 341.683783 -400.484879)
			(xy 341.736088 -400.500233) (xy 341.785676 -400.522875) (xy 341.831537 -400.552345) (xy 341.872736 -400.588041)
			(xy 341.908436 -400.629238) (xy 341.937909 -400.675096) (xy 341.960556 -400.724682) (xy 341.975915 -400.776986)
			(xy 341.983673 -400.830944) (xy 341.983673 -400.885451) (xy 343.421183 -400.885451) (xy 343.421183 -400.830949)
			(xy 343.42894 -400.777001) (xy 343.444295 -400.724706) (xy 343.466937 -400.675129) (xy 343.496403 -400.629279)
			(xy 343.532095 -400.588089) (xy 343.573286 -400.552398) (xy 343.619136 -400.522933) (xy 343.668714 -400.500292)
			(xy 343.721009 -400.484938) (xy 343.774957 -400.477183) (xy 343.802208 -400.47672) (xy 344.665808 -400.47672)
			(xy 344.693061 -400.47715) (xy 344.747012 -400.484908) (xy 344.799309 -400.500265) (xy 344.848889 -400.522909)
			(xy 344.894742 -400.552377) (xy 344.935934 -400.588071) (xy 344.971628 -400.629264) (xy 345.001095 -400.675118)
			(xy 345.023737 -400.724698) (xy 345.039093 -400.776996) (xy 345.04685 -400.830947) (xy 345.04685 -400.885453)
			(xy 346.484383 -400.885453) (xy 346.484383 -400.830947) (xy 346.492141 -400.776996) (xy 346.507498 -400.724698)
			(xy 346.530143 -400.675118) (xy 346.559613 -400.629266) (xy 346.595309 -400.588075) (xy 346.636505 -400.552384)
			(xy 346.68236 -400.52292) (xy 346.731943 -400.500282) (xy 346.784243 -400.484931) (xy 346.838195 -400.47718)
			(xy 346.865448 -400.47672) (xy 347.729048 -400.47672) (xy 347.756299 -400.477153) (xy 347.810246 -400.484916)
			(xy 347.862538 -400.500276) (xy 347.912113 -400.522922) (xy 347.957961 -400.552391) (xy 347.999148 -400.588086)
			(xy 348.034837 -400.629278) (xy 348.064301 -400.675129) (xy 348.086941 -400.724707) (xy 348.102294 -400.777001)
			(xy 348.11005 -400.830949) (xy 348.11005 -400.885449) (xy 349.547706 -400.885449) (xy 349.547706 -400.830951)
			(xy 349.555462 -400.777009) (xy 349.570815 -400.724719) (xy 349.593454 -400.675146) (xy 349.622917 -400.6293)
			(xy 349.658604 -400.588113) (xy 349.69979 -400.552424) (xy 349.745636 -400.52296) (xy 349.795208 -400.500319)
			(xy 349.847497 -400.484964) (xy 349.901439 -400.477207) (xy 349.928688 -400.47672) (xy 350.792288 -400.47672)
			(xy 350.819543 -400.477126) (xy 350.8735 -400.484882) (xy 350.925803 -400.500238) (xy 350.975388 -400.522882)
			(xy 351.021246 -400.552352) (xy 351.062443 -400.588048) (xy 351.098141 -400.629244) (xy 351.127612 -400.675101)
			(xy 351.150257 -400.724686) (xy 351.165615 -400.776989) (xy 351.173373 -400.830945) (xy 351.173373 -400.885452)
			(xy 371.041883 -400.885452) (xy 371.041883 -400.830948) (xy 371.049641 -400.776998) (xy 371.064997 -400.724702)
			(xy 371.08764 -400.675123) (xy 371.117109 -400.629272) (xy 371.152803 -400.588082) (xy 371.193996 -400.552391)
			(xy 371.23985 -400.522926) (xy 371.28943 -400.500286) (xy 371.341728 -400.484934) (xy 371.395678 -400.477181)
			(xy 371.42293 -400.47672) (xy 372.28653 -400.47672) (xy 372.313782 -400.477152) (xy 372.36773 -400.484912)
			(xy 372.420025 -400.500271) (xy 372.469602 -400.522916) (xy 372.515452 -400.552385) (xy 372.556642 -400.588079)
			(xy 372.592333 -400.629272) (xy 372.621799 -400.675124) (xy 372.644439 -400.724703) (xy 372.659794 -400.776999)
			(xy 372.66755 -400.830948) (xy 372.66755 -400.885448) (xy 374.105206 -400.885448) (xy 374.105206 -400.830952)
			(xy 374.112961 -400.777011) (xy 374.128314 -400.724723) (xy 374.150951 -400.675151) (xy 374.180412 -400.629306)
			(xy 374.216098 -400.588119) (xy 374.257281 -400.55243) (xy 374.303125 -400.522965) (xy 374.352694 -400.500324)
			(xy 374.404982 -400.484968) (xy 374.458922 -400.477208) (xy 374.48617 -400.47672) (xy 375.34977 -400.47672)
			(xy 375.377026 -400.477125) (xy 375.430984 -400.484879) (xy 375.48329 -400.500234) (xy 375.532877 -400.522876)
			(xy 375.578738 -400.552345) (xy 375.619937 -400.588042) (xy 375.655637 -400.629238) (xy 375.68511 -400.675096)
			(xy 375.707756 -400.724682) (xy 375.723115 -400.776986) (xy 375.730873 -400.830944) (xy 375.730873 -400.885451)
			(xy 377.168383 -400.885451) (xy 377.168383 -400.830949) (xy 377.17614 -400.777001) (xy 377.191495 -400.724706)
			(xy 377.214137 -400.675129) (xy 377.243604 -400.629279) (xy 377.279296 -400.588089) (xy 377.320487 -400.552398)
			(xy 377.366338 -400.522932) (xy 377.415915 -400.500292) (xy 377.468211 -400.484938) (xy 377.522159 -400.477183)
			(xy 377.54941 -400.47672) (xy 378.41301 -400.47672) (xy 378.440263 -400.477151) (xy 378.494213 -400.484909)
			(xy 378.546511 -400.500266) (xy 378.59609 -400.522909) (xy 378.641943 -400.552378) (xy 378.683135 -400.588072)
			(xy 378.718828 -400.629265) (xy 378.748296 -400.675118) (xy 378.770938 -400.724699) (xy 378.786293 -400.776996)
			(xy 378.79405 -400.830947) (xy 378.79405 -400.885447) (xy 380.231706 -400.885447) (xy 380.231706 -400.830953)
			(xy 380.239461 -400.777014) (xy 380.254812 -400.724727) (xy 380.277448 -400.675157) (xy 380.306907 -400.629312)
			(xy 380.342591 -400.588126) (xy 380.383772 -400.552437) (xy 380.429613 -400.522972) (xy 380.47918 -400.50033)
			(xy 380.531465 -400.484971) (xy 380.585403 -400.47721) (xy 380.61265 -400.47672) (xy 381.47625 -400.47672)
			(xy 381.503507 -400.477124) (xy 381.557468 -400.484875) (xy 381.609775 -400.500228) (xy 381.659365 -400.522869)
			(xy 381.705228 -400.552338) (xy 381.74643 -400.588035) (xy 381.782132 -400.629232) (xy 381.811607 -400.675091)
			(xy 381.834254 -400.724678) (xy 381.849614 -400.776983) (xy 381.857373 -400.830943) (xy 381.857373 -400.885449)
			(xy 383.294906 -400.885449) (xy 383.294906 -400.830951) (xy 383.302662 -400.777008) (xy 383.318015 -400.724718)
			(xy 383.340654 -400.675145) (xy 383.370117 -400.629299) (xy 383.405805 -400.588112) (xy 383.446991 -400.552423)
			(xy 383.492837 -400.522959) (xy 383.542409 -400.500319) (xy 383.594699 -400.484964) (xy 383.648641 -400.477207)
			(xy 383.67589 -400.47672) (xy 384.53949 -400.47672) (xy 384.566745 -400.477126) (xy 384.620701 -400.484883)
			(xy 384.673004 -400.500239) (xy 384.722589 -400.522883) (xy 384.768447 -400.552352) (xy 384.809644 -400.588049)
			(xy 384.845342 -400.629245) (xy 384.874813 -400.675102) (xy 384.897458 -400.724686) (xy 384.912815 -400.776989)
			(xy 384.920573 -400.830945) (xy 384.920573 -400.885452) (xy 386.358083 -400.885452) (xy 386.358083 -400.830948)
			(xy 386.365841 -400.776998) (xy 386.381197 -400.724702) (xy 386.40384 -400.675123) (xy 386.433309 -400.629272)
			(xy 386.469003 -400.588082) (xy 386.510196 -400.552391) (xy 386.55605 -400.522926) (xy 386.60563 -400.500286)
			(xy 386.657928 -400.484934) (xy 386.711878 -400.477181) (xy 386.73913 -400.47672) (xy 387.60273 -400.47672)
			(xy 387.629982 -400.477152) (xy 387.68393 -400.484912) (xy 387.736225 -400.500271) (xy 387.785802 -400.522916)
			(xy 387.831652 -400.552385) (xy 387.872842 -400.588079) (xy 387.908533 -400.629272) (xy 387.937999 -400.675124)
			(xy 387.960639 -400.724703) (xy 387.975994 -400.776999) (xy 387.98375 -400.830948) (xy 387.98375 -400.885448)
			(xy 389.421406 -400.885448) (xy 389.421406 -400.830952) (xy 389.429161 -400.777011) (xy 389.444514 -400.724723)
			(xy 389.467151 -400.675151) (xy 389.496612 -400.629306) (xy 389.532298 -400.588119) (xy 389.573481 -400.55243)
			(xy 389.619325 -400.522965) (xy 389.668894 -400.500324) (xy 389.721182 -400.484968) (xy 389.775122 -400.477208)
			(xy 389.80237 -400.47672) (xy 390.66597 -400.47672) (xy 390.693226 -400.477125) (xy 390.747184 -400.484879)
			(xy 390.79949 -400.500234) (xy 390.849077 -400.522876) (xy 390.894938 -400.552345) (xy 390.936137 -400.588042)
			(xy 390.971837 -400.629238) (xy 391.00131 -400.675096) (xy 391.023956 -400.724682) (xy 391.039315 -400.776986)
			(xy 391.047073 -400.830944) (xy 391.047073 -400.885451) (xy 392.484583 -400.885451) (xy 392.484583 -400.830949)
			(xy 392.49234 -400.777001) (xy 392.507695 -400.724706) (xy 392.530337 -400.675129) (xy 392.559804 -400.629279)
			(xy 392.595496 -400.588089) (xy 392.636687 -400.552398) (xy 392.682538 -400.522932) (xy 392.732115 -400.500292)
			(xy 392.784411 -400.484938) (xy 392.838359 -400.477183) (xy 392.86561 -400.47672) (xy 393.72921 -400.47672)
			(xy 393.756463 -400.477151) (xy 393.810413 -400.484909) (xy 393.862711 -400.500266) (xy 393.91229 -400.522909)
			(xy 393.958143 -400.552378) (xy 393.999335 -400.588072) (xy 394.035028 -400.629265) (xy 394.064496 -400.675118)
			(xy 394.087138 -400.724699) (xy 394.102493 -400.776996) (xy 394.11025 -400.830947) (xy 394.11025 -400.885447)
			(xy 395.547906 -400.885447) (xy 395.547906 -400.830953) (xy 395.555661 -400.777014) (xy 395.571012 -400.724727)
			(xy 395.593648 -400.675157) (xy 395.623107 -400.629312) (xy 395.658791 -400.588126) (xy 395.699972 -400.552437)
			(xy 395.745813 -400.522972) (xy 395.79538 -400.50033) (xy 395.847665 -400.484971) (xy 395.901603 -400.47721)
			(xy 395.92885 -400.47672) (xy 396.79245 -400.47672) (xy 396.819707 -400.477124) (xy 396.873668 -400.484875)
			(xy 396.925975 -400.500228) (xy 396.975565 -400.522869) (xy 397.021428 -400.552338) (xy 397.06263 -400.588035)
			(xy 397.098332 -400.629232) (xy 397.127807 -400.675091) (xy 397.150454 -400.724678) (xy 397.165814 -400.776983)
			(xy 397.173573 -400.830943) (xy 397.173573 -400.885449) (xy 398.611106 -400.885449) (xy 398.611106 -400.830951)
			(xy 398.618862 -400.777008) (xy 398.634215 -400.724718) (xy 398.656854 -400.675145) (xy 398.686317 -400.629299)
			(xy 398.722005 -400.588112) (xy 398.763191 -400.552423) (xy 398.809037 -400.522959) (xy 398.858609 -400.500319)
			(xy 398.910899 -400.484964) (xy 398.964841 -400.477207) (xy 398.99209 -400.47672) (xy 399.85569 -400.47672)
			(xy 399.882945 -400.477126) (xy 399.936901 -400.484883) (xy 399.989204 -400.500239) (xy 400.038789 -400.522883)
			(xy 400.084647 -400.552352) (xy 400.125844 -400.588049) (xy 400.161542 -400.629245) (xy 400.191013 -400.675102)
			(xy 400.213658 -400.724686) (xy 400.229015 -400.776989) (xy 400.236773 -400.830945) (xy 400.236773 -400.885452)
			(xy 401.674283 -400.885452) (xy 401.674283 -400.830948) (xy 401.682041 -400.776998) (xy 401.697397 -400.724702)
			(xy 401.72004 -400.675123) (xy 401.749509 -400.629272) (xy 401.785203 -400.588082) (xy 401.826396 -400.552391)
			(xy 401.87225 -400.522926) (xy 401.92183 -400.500286) (xy 401.974128 -400.484934) (xy 402.028078 -400.477181)
			(xy 402.05533 -400.47672) (xy 402.91893 -400.47672) (xy 402.946182 -400.477152) (xy 403.00013 -400.484912)
			(xy 403.052425 -400.500271) (xy 403.102002 -400.522916) (xy 403.147852 -400.552385) (xy 403.189042 -400.588079)
			(xy 403.224733 -400.629272) (xy 403.254199 -400.675124) (xy 403.276839 -400.724703) (xy 403.292194 -400.776999)
			(xy 403.29995 -400.830948) (xy 403.29995 -400.885448) (xy 404.737606 -400.885448) (xy 404.737606 -400.830952)
			(xy 404.745361 -400.777011) (xy 404.760714 -400.724723) (xy 404.783351 -400.675151) (xy 404.812812 -400.629306)
			(xy 404.848498 -400.588119) (xy 404.889681 -400.55243) (xy 404.935525 -400.522965) (xy 404.985094 -400.500324)
			(xy 405.037382 -400.484968) (xy 405.091322 -400.477208) (xy 405.11857 -400.47672) (xy 405.98217 -400.47672)
			(xy 406.009426 -400.477125) (xy 406.063384 -400.484879) (xy 406.11569 -400.500234) (xy 406.165277 -400.522876)
			(xy 406.211138 -400.552345) (xy 406.252337 -400.588042) (xy 406.288037 -400.629238) (xy 406.31751 -400.675096)
			(xy 406.340156 -400.724682) (xy 406.355515 -400.776986) (xy 406.363273 -400.830944) (xy 406.363273 -400.885451)
			(xy 407.800783 -400.885451) (xy 407.800783 -400.830949) (xy 407.80854 -400.777001) (xy 407.823895 -400.724706)
			(xy 407.846537 -400.675129) (xy 407.876004 -400.629279) (xy 407.911696 -400.588089) (xy 407.952887 -400.552398)
			(xy 407.998738 -400.522932) (xy 408.048315 -400.500292) (xy 408.100611 -400.484938) (xy 408.154559 -400.477183)
			(xy 408.18181 -400.47672) (xy 409.04541 -400.47672) (xy 409.072663 -400.477151) (xy 409.126613 -400.484909)
			(xy 409.178911 -400.500266) (xy 409.22849 -400.522909) (xy 409.274343 -400.552378) (xy 409.315535 -400.588072)
			(xy 409.351228 -400.629265) (xy 409.380696 -400.675118) (xy 409.403338 -400.724699) (xy 409.418693 -400.776996)
			(xy 409.42645 -400.830947) (xy 409.42645 -400.885447) (xy 410.864106 -400.885447) (xy 410.864106 -400.830953)
			(xy 410.871861 -400.777014) (xy 410.887212 -400.724727) (xy 410.909848 -400.675157) (xy 410.939307 -400.629312)
			(xy 410.974991 -400.588126) (xy 411.016172 -400.552437) (xy 411.062013 -400.522972) (xy 411.11158 -400.50033)
			(xy 411.163865 -400.484971) (xy 411.217803 -400.47721) (xy 411.24505 -400.47672) (xy 412.10865 -400.47672)
			(xy 412.135907 -400.477124) (xy 412.189868 -400.484875) (xy 412.242175 -400.500228) (xy 412.291765 -400.522869)
			(xy 412.337628 -400.552338) (xy 412.37883 -400.588035) (xy 412.414532 -400.629232) (xy 412.444007 -400.675091)
			(xy 412.466654 -400.724678) (xy 412.482014 -400.776983) (xy 412.489773 -400.830943) (xy 412.489773 -400.885449)
			(xy 413.927306 -400.885449) (xy 413.927306 -400.830951) (xy 413.935062 -400.777008) (xy 413.950415 -400.724718)
			(xy 413.973054 -400.675145) (xy 414.002517 -400.629299) (xy 414.038205 -400.588112) (xy 414.079391 -400.552423)
			(xy 414.125237 -400.522959) (xy 414.174809 -400.500319) (xy 414.227099 -400.484964) (xy 414.281041 -400.477207)
			(xy 414.30829 -400.47672) (xy 415.17189 -400.47672) (xy 415.199145 -400.477126) (xy 415.253101 -400.484883)
			(xy 415.305404 -400.500239) (xy 415.354989 -400.522883) (xy 415.400847 -400.552352) (xy 415.442044 -400.588049)
			(xy 415.477742 -400.629245) (xy 415.507213 -400.675102) (xy 415.529858 -400.724686) (xy 415.545215 -400.776989)
			(xy 415.552973 -400.830945) (xy 415.552973 -400.885452) (xy 416.990483 -400.885452) (xy 416.990483 -400.830948)
			(xy 416.998241 -400.776998) (xy 417.013597 -400.724702) (xy 417.03624 -400.675123) (xy 417.065709 -400.629272)
			(xy 417.101403 -400.588082) (xy 417.142596 -400.552391) (xy 417.18845 -400.522926) (xy 417.23803 -400.500286)
			(xy 417.290328 -400.484934) (xy 417.344278 -400.477181) (xy 417.37153 -400.47672) (xy 418.23513 -400.47672)
			(xy 418.262382 -400.477152) (xy 418.31633 -400.484912) (xy 418.368625 -400.500271) (xy 418.418202 -400.522916)
			(xy 418.464052 -400.552385) (xy 418.505242 -400.588079) (xy 418.540933 -400.629272) (xy 418.570399 -400.675124)
			(xy 418.593039 -400.724703) (xy 418.608394 -400.776999) (xy 418.61615 -400.830948) (xy 418.61615 -400.885452)
			(xy 418.608394 -400.939401) (xy 418.593039 -400.991697) (xy 418.570399 -401.041276) (xy 418.540933 -401.087128)
			(xy 418.505242 -401.128321) (xy 418.464052 -401.164015) (xy 418.418202 -401.193484) (xy 418.368625 -401.216129)
			(xy 418.31633 -401.231488) (xy 418.262382 -401.239248) (xy 418.23513 -401.239736) (xy 417.37153 -401.239736)
			(xy 417.344278 -401.239219) (xy 417.290328 -401.231466) (xy 417.23803 -401.216114) (xy 417.18845 -401.193474)
			(xy 417.142596 -401.164009) (xy 417.101403 -401.128318) (xy 417.065709 -401.087128) (xy 417.03624 -401.041277)
			(xy 417.013597 -400.991698) (xy 416.998241 -400.939402) (xy 416.990483 -400.885452) (xy 415.552973 -400.885452)
			(xy 415.552973 -400.885455) (xy 415.545215 -400.939411) (xy 415.529858 -400.991714) (xy 415.507213 -401.041298)
			(xy 415.477742 -401.087155) (xy 415.442044 -401.128351) (xy 415.400847 -401.164048) (xy 415.354989 -401.193517)
			(xy 415.305404 -401.216161) (xy 415.253101 -401.231517) (xy 415.199145 -401.239274) (xy 415.17189 -401.239736)
			(xy 414.30829 -401.239736) (xy 414.281041 -401.239193) (xy 414.227099 -401.231436) (xy 414.174809 -401.216081)
			(xy 414.125237 -401.193441) (xy 414.079391 -401.163977) (xy 414.038205 -401.128288) (xy 414.002517 -401.087101)
			(xy 413.973054 -401.041255) (xy 413.950415 -400.991682) (xy 413.935062 -400.939392) (xy 413.927306 -400.885449)
			(xy 412.489773 -400.885449) (xy 412.489773 -400.885457) (xy 412.482014 -400.939416) (xy 412.466654 -400.991722)
			(xy 412.444007 -401.041309) (xy 412.414532 -401.087168) (xy 412.37883 -401.128365) (xy 412.337628 -401.164062)
			(xy 412.291765 -401.193531) (xy 412.242175 -401.216172) (xy 412.189868 -401.231525) (xy 412.135907 -401.239276)
			(xy 412.10865 -401.239736) (xy 411.24505 -401.239736) (xy 411.217803 -401.23919) (xy 411.163865 -401.231429)
			(xy 411.11158 -401.21607) (xy 411.062013 -401.193428) (xy 411.016172 -401.163963) (xy 410.974991 -401.128274)
			(xy 410.939307 -401.087088) (xy 410.909848 -401.041243) (xy 410.887212 -400.991673) (xy 410.871861 -400.939386)
			(xy 410.864106 -400.885447) (xy 409.42645 -400.885447) (xy 409.42645 -400.885453) (xy 409.418693 -400.939404)
			(xy 409.403338 -400.991701) (xy 409.380696 -401.041282) (xy 409.351228 -401.087135) (xy 409.315535 -401.128328)
			(xy 409.274343 -401.164022) (xy 409.22849 -401.193491) (xy 409.178911 -401.216134) (xy 409.126613 -401.231491)
			(xy 409.072663 -401.239249) (xy 409.04541 -401.239736) (xy 408.18181 -401.239736) (xy 408.154559 -401.239217)
			(xy 408.100611 -401.231462) (xy 408.048315 -401.216108) (xy 407.998738 -401.193468) (xy 407.952887 -401.164002)
			(xy 407.911696 -401.128311) (xy 407.876004 -401.087121) (xy 407.846537 -401.041271) (xy 407.823895 -400.991694)
			(xy 407.80854 -400.939399) (xy 407.800783 -400.885451) (xy 406.363273 -400.885451) (xy 406.363273 -400.885456)
			(xy 406.355515 -400.939414) (xy 406.340156 -400.991718) (xy 406.31751 -401.041304) (xy 406.288037 -401.087162)
			(xy 406.252337 -401.128358) (xy 406.211138 -401.164055) (xy 406.165277 -401.193524) (xy 406.11569 -401.216166)
			(xy 406.063384 -401.231521) (xy 406.009426 -401.239275) (xy 405.98217 -401.239736) (xy 405.11857 -401.239736)
			(xy 405.091322 -401.239192) (xy 405.037382 -401.231432) (xy 404.985094 -401.216076) (xy 404.935525 -401.193435)
			(xy 404.889682 -401.16397) (xy 404.848498 -401.128281) (xy 404.812812 -401.087094) (xy 404.783351 -401.041249)
			(xy 404.760714 -400.991677) (xy 404.745361 -400.939389) (xy 404.737606 -400.885448) (xy 403.29995 -400.885448)
			(xy 403.29995 -400.885452) (xy 403.292194 -400.939401) (xy 403.276839 -400.991697) (xy 403.254199 -401.041276)
			(xy 403.224733 -401.087128) (xy 403.189042 -401.128321) (xy 403.147852 -401.164015) (xy 403.102002 -401.193484)
			(xy 403.052425 -401.216129) (xy 403.00013 -401.231488) (xy 402.946182 -401.239248) (xy 402.91893 -401.239736)
			(xy 402.05533 -401.239736) (xy 402.028078 -401.239219) (xy 401.974128 -401.231466) (xy 401.92183 -401.216114)
			(xy 401.87225 -401.193474) (xy 401.826396 -401.164009) (xy 401.785203 -401.128318) (xy 401.749509 -401.087128)
			(xy 401.72004 -401.041277) (xy 401.697397 -400.991698) (xy 401.682041 -400.939402) (xy 401.674283 -400.885452)
			(xy 400.236773 -400.885452) (xy 400.236773 -400.885455) (xy 400.229015 -400.939411) (xy 400.213658 -400.991714)
			(xy 400.191013 -401.041298) (xy 400.161542 -401.087155) (xy 400.125844 -401.128351) (xy 400.084647 -401.164048)
			(xy 400.038789 -401.193517) (xy 399.989204 -401.216161) (xy 399.936901 -401.231517) (xy 399.882945 -401.239274)
			(xy 399.85569 -401.239736) (xy 398.99209 -401.239736) (xy 398.964841 -401.239193) (xy 398.910899 -401.231436)
			(xy 398.858609 -401.216081) (xy 398.809037 -401.193441) (xy 398.763191 -401.163977) (xy 398.722005 -401.128288)
			(xy 398.686317 -401.087101) (xy 398.656854 -401.041255) (xy 398.634215 -400.991682) (xy 398.618862 -400.939392)
			(xy 398.611106 -400.885449) (xy 397.173573 -400.885449) (xy 397.173573 -400.885457) (xy 397.165814 -400.939416)
			(xy 397.150454 -400.991722) (xy 397.127807 -401.041309) (xy 397.098332 -401.087168) (xy 397.06263 -401.128365)
			(xy 397.021428 -401.164062) (xy 396.975565 -401.193531) (xy 396.925975 -401.216172) (xy 396.873668 -401.231525)
			(xy 396.819707 -401.239276) (xy 396.79245 -401.239736) (xy 395.92885 -401.239736) (xy 395.901603 -401.23919)
			(xy 395.847665 -401.231429) (xy 395.79538 -401.21607) (xy 395.745813 -401.193428) (xy 395.699972 -401.163963)
			(xy 395.658791 -401.128274) (xy 395.623107 -401.087088) (xy 395.593648 -401.041243) (xy 395.571012 -400.991673)
			(xy 395.555661 -400.939386) (xy 395.547906 -400.885447) (xy 394.11025 -400.885447) (xy 394.11025 -400.885453)
			(xy 394.102493 -400.939404) (xy 394.087138 -400.991701) (xy 394.064496 -401.041282) (xy 394.035028 -401.087135)
			(xy 393.999335 -401.128328) (xy 393.958143 -401.164022) (xy 393.91229 -401.193491) (xy 393.862711 -401.216134)
			(xy 393.810413 -401.231491) (xy 393.756463 -401.239249) (xy 393.72921 -401.239736) (xy 392.86561 -401.239736)
			(xy 392.838359 -401.239217) (xy 392.784411 -401.231462) (xy 392.732115 -401.216108) (xy 392.682538 -401.193468)
			(xy 392.636687 -401.164002) (xy 392.595496 -401.128311) (xy 392.559804 -401.087121) (xy 392.530337 -401.041271)
			(xy 392.507695 -400.991694) (xy 392.49234 -400.939399) (xy 392.484583 -400.885451) (xy 391.047073 -400.885451)
			(xy 391.047073 -400.885456) (xy 391.039315 -400.939414) (xy 391.023956 -400.991718) (xy 391.00131 -401.041304)
			(xy 390.971837 -401.087162) (xy 390.936137 -401.128358) (xy 390.894938 -401.164055) (xy 390.849077 -401.193524)
			(xy 390.79949 -401.216166) (xy 390.747184 -401.231521) (xy 390.693226 -401.239275) (xy 390.66597 -401.239736)
			(xy 389.80237 -401.239736) (xy 389.775122 -401.239192) (xy 389.721182 -401.231432) (xy 389.668894 -401.216076)
			(xy 389.619325 -401.193435) (xy 389.573482 -401.16397) (xy 389.532298 -401.128281) (xy 389.496612 -401.087094)
			(xy 389.467151 -401.041249) (xy 389.444514 -400.991677) (xy 389.429161 -400.939389) (xy 389.421406 -400.885448)
			(xy 387.98375 -400.885448) (xy 387.98375 -400.885452) (xy 387.975994 -400.939401) (xy 387.960639 -400.991697)
			(xy 387.937999 -401.041276) (xy 387.908533 -401.087128) (xy 387.872842 -401.128321) (xy 387.831652 -401.164015)
			(xy 387.785802 -401.193484) (xy 387.736225 -401.216129) (xy 387.68393 -401.231488) (xy 387.629982 -401.239248)
			(xy 387.60273 -401.239736) (xy 386.73913 -401.239736) (xy 386.711878 -401.239219) (xy 386.657928 -401.231466)
			(xy 386.60563 -401.216114) (xy 386.55605 -401.193474) (xy 386.510196 -401.164009) (xy 386.469003 -401.128318)
			(xy 386.433309 -401.087128) (xy 386.40384 -401.041277) (xy 386.381197 -400.991698) (xy 386.365841 -400.939402)
			(xy 386.358083 -400.885452) (xy 384.920573 -400.885452) (xy 384.920573 -400.885455) (xy 384.912815 -400.939411)
			(xy 384.897458 -400.991714) (xy 384.874813 -401.041298) (xy 384.845342 -401.087155) (xy 384.809644 -401.128351)
			(xy 384.768447 -401.164048) (xy 384.722589 -401.193517) (xy 384.673004 -401.216161) (xy 384.620701 -401.231517)
			(xy 384.566745 -401.239274) (xy 384.53949 -401.239736) (xy 383.67589 -401.239736) (xy 383.648641 -401.239193)
			(xy 383.594699 -401.231436) (xy 383.542409 -401.216081) (xy 383.492837 -401.193441) (xy 383.446991 -401.163977)
			(xy 383.405805 -401.128288) (xy 383.370117 -401.087101) (xy 383.340654 -401.041255) (xy 383.318015 -400.991682)
			(xy 383.302662 -400.939392) (xy 383.294906 -400.885449) (xy 381.857373 -400.885449) (xy 381.857373 -400.885457)
			(xy 381.849614 -400.939416) (xy 381.834254 -400.991722) (xy 381.811607 -401.041309) (xy 381.782132 -401.087168)
			(xy 381.74643 -401.128365) (xy 381.705228 -401.164062) (xy 381.659365 -401.193531) (xy 381.609775 -401.216172)
			(xy 381.557468 -401.231525) (xy 381.503507 -401.239276) (xy 381.47625 -401.239736) (xy 380.61265 -401.239736)
			(xy 380.585403 -401.23919) (xy 380.531465 -401.231429) (xy 380.47918 -401.21607) (xy 380.429613 -401.193428)
			(xy 380.383772 -401.163963) (xy 380.342591 -401.128274) (xy 380.306907 -401.087088) (xy 380.277448 -401.041243)
			(xy 380.254812 -400.991673) (xy 380.239461 -400.939386) (xy 380.231706 -400.885447) (xy 378.79405 -400.885447)
			(xy 378.79405 -400.885453) (xy 378.786293 -400.939404) (xy 378.770938 -400.991701) (xy 378.748296 -401.041282)
			(xy 378.718828 -401.087135) (xy 378.683135 -401.128328) (xy 378.641943 -401.164022) (xy 378.59609 -401.193491)
			(xy 378.546511 -401.216134) (xy 378.494213 -401.231491) (xy 378.440263 -401.239249) (xy 378.41301 -401.239736)
			(xy 377.54941 -401.239736) (xy 377.522159 -401.239217) (xy 377.468211 -401.231462) (xy 377.415915 -401.216108)
			(xy 377.366338 -401.193468) (xy 377.320487 -401.164002) (xy 377.279296 -401.128311) (xy 377.243604 -401.087121)
			(xy 377.214137 -401.041271) (xy 377.191495 -400.991694) (xy 377.17614 -400.939399) (xy 377.168383 -400.885451)
			(xy 375.730873 -400.885451) (xy 375.730873 -400.885456) (xy 375.723115 -400.939414) (xy 375.707756 -400.991718)
			(xy 375.68511 -401.041304) (xy 375.655637 -401.087162) (xy 375.619937 -401.128358) (xy 375.578738 -401.164055)
			(xy 375.532877 -401.193524) (xy 375.48329 -401.216166) (xy 375.430984 -401.231521) (xy 375.377026 -401.239275)
			(xy 375.34977 -401.239736) (xy 374.48617 -401.239736) (xy 374.458922 -401.239192) (xy 374.404982 -401.231432)
			(xy 374.352694 -401.216076) (xy 374.303125 -401.193435) (xy 374.257282 -401.16397) (xy 374.216098 -401.128281)
			(xy 374.180412 -401.087094) (xy 374.150951 -401.041249) (xy 374.128314 -400.991677) (xy 374.112961 -400.939389)
			(xy 374.105206 -400.885448) (xy 372.66755 -400.885448) (xy 372.66755 -400.885452) (xy 372.659794 -400.939401)
			(xy 372.644439 -400.991697) (xy 372.621799 -401.041276) (xy 372.592333 -401.087128) (xy 372.556642 -401.128321)
			(xy 372.515452 -401.164015) (xy 372.469602 -401.193484) (xy 372.420025 -401.216129) (xy 372.36773 -401.231488)
			(xy 372.313782 -401.239248) (xy 372.28653 -401.239736) (xy 371.42293 -401.239736) (xy 371.395678 -401.239219)
			(xy 371.341728 -401.231466) (xy 371.28943 -401.216114) (xy 371.23985 -401.193474) (xy 371.193996 -401.164009)
			(xy 371.152803 -401.128318) (xy 371.117109 -401.087128) (xy 371.08764 -401.041277) (xy 371.064997 -400.991698)
			(xy 371.049641 -400.939402) (xy 371.041883 -400.885452) (xy 351.173373 -400.885452) (xy 351.173373 -400.885455)
			(xy 351.165615 -400.939411) (xy 351.150257 -400.991714) (xy 351.127612 -401.041299) (xy 351.098141 -401.087156)
			(xy 351.062443 -401.128352) (xy 351.021246 -401.164048) (xy 350.975388 -401.193518) (xy 350.925803 -401.216162)
			(xy 350.8735 -401.231518) (xy 350.819543 -401.239274) (xy 350.792288 -401.239736) (xy 349.928688 -401.239736)
			(xy 349.901439 -401.239193) (xy 349.847497 -401.231436) (xy 349.795208 -401.216081) (xy 349.745636 -401.19344)
			(xy 349.69979 -401.163976) (xy 349.658604 -401.128287) (xy 349.622917 -401.0871) (xy 349.593454 -401.041254)
			(xy 349.570815 -400.991681) (xy 349.555462 -400.939391) (xy 349.547706 -400.885449) (xy 348.11005 -400.885449)
			(xy 348.11005 -400.885451) (xy 348.102294 -400.939399) (xy 348.086941 -400.991693) (xy 348.064301 -401.041271)
			(xy 348.034837 -401.087122) (xy 347.999148 -401.128314) (xy 347.957961 -401.164009) (xy 347.912113 -401.193478)
			(xy 347.862538 -401.216124) (xy 347.810245 -401.231484) (xy 347.756299 -401.239247) (xy 347.729048 -401.239736)
			(xy 346.865448 -401.239736) (xy 346.838195 -401.23922) (xy 346.784243 -401.231469) (xy 346.731943 -401.216118)
			(xy 346.68236 -401.19348) (xy 346.636505 -401.164016) (xy 346.595309 -401.128325) (xy 346.559613 -401.087134)
			(xy 346.530143 -401.041282) (xy 346.507498 -400.991702) (xy 346.492141 -400.939404) (xy 346.484383 -400.885453)
			(xy 345.04685 -400.885453) (xy 345.039093 -400.939404) (xy 345.023737 -400.991702) (xy 345.001095 -401.041282)
			(xy 344.971628 -401.087136) (xy 344.935934 -401.128329) (xy 344.894742 -401.164023) (xy 344.848889 -401.193491)
			(xy 344.799309 -401.216135) (xy 344.747012 -401.231492) (xy 344.693061 -401.23925) (xy 344.665808 -401.239736)
			(xy 343.802208 -401.239736) (xy 343.774957 -401.239217) (xy 343.721009 -401.231462) (xy 343.668714 -401.216108)
			(xy 343.619136 -401.193467) (xy 343.573286 -401.164002) (xy 343.532095 -401.128311) (xy 343.496403 -401.087121)
			(xy 343.466937 -401.041271) (xy 343.444295 -400.991694) (xy 343.42894 -400.939399) (xy 343.421183 -400.885451)
			(xy 341.983673 -400.885451) (xy 341.983673 -400.885456) (xy 341.975915 -400.939414) (xy 341.960556 -400.991718)
			(xy 341.937909 -401.041304) (xy 341.908436 -401.087162) (xy 341.872736 -401.128359) (xy 341.831537 -401.164055)
			(xy 341.785676 -401.193525) (xy 341.736088 -401.216167) (xy 341.683783 -401.231521) (xy 341.629824 -401.239275)
			(xy 341.602568 -401.239736) (xy 340.738968 -401.239736) (xy 340.71172 -401.239192) (xy 340.65778 -401.231432)
			(xy 340.605493 -401.216075) (xy 340.555924 -401.193434) (xy 340.510081 -401.163969) (xy 340.468897 -401.12828)
			(xy 340.433212 -401.087094) (xy 340.403751 -401.041248) (xy 340.381114 -400.991677) (xy 340.365761 -400.939389)
			(xy 340.358006 -400.885448) (xy 338.92035 -400.885448) (xy 338.92035 -400.885452) (xy 338.912594 -400.939401)
			(xy 338.897239 -400.991698) (xy 338.874598 -401.041277) (xy 338.845132 -401.087129) (xy 338.809441 -401.128321)
			(xy 338.768251 -401.164016) (xy 338.722401 -401.193485) (xy 338.672824 -401.216129) (xy 338.620529 -401.231488)
			(xy 338.56658 -401.239248) (xy 338.539328 -401.239736) (xy 337.675728 -401.239736) (xy 337.648476 -401.239219)
			(xy 337.594526 -401.231465) (xy 337.542228 -401.216113) (xy 337.492648 -401.193474) (xy 337.446795 -401.164009)
			(xy 337.405602 -401.128318) (xy 337.369908 -401.087127) (xy 337.34044 -401.041276) (xy 337.317797 -400.991698)
			(xy 337.30244 -400.939402) (xy 337.294683 -400.885452) (xy 335.857173 -400.885452) (xy 335.857173 -400.885455)
			(xy 335.849415 -400.939411) (xy 335.834057 -400.991714) (xy 335.811412 -401.041299) (xy 335.781941 -401.087156)
			(xy 335.746243 -401.128352) (xy 335.705046 -401.164048) (xy 335.659188 -401.193518) (xy 335.609603 -401.216162)
			(xy 335.5573 -401.231518) (xy 335.503343 -401.239274) (xy 335.476088 -401.239736) (xy 334.612488 -401.239736)
			(xy 334.585239 -401.239193) (xy 334.531297 -401.231436) (xy 334.479008 -401.216081) (xy 334.429436 -401.19344)
			(xy 334.38359 -401.163976) (xy 334.342404 -401.128287) (xy 334.306717 -401.0871) (xy 334.277254 -401.041254)
			(xy 334.254615 -400.991681) (xy 334.239262 -400.939391) (xy 334.231506 -400.885449) (xy 332.79385 -400.885449)
			(xy 332.79385 -400.885451) (xy 332.786094 -400.939399) (xy 332.770741 -400.991693) (xy 332.748101 -401.041271)
			(xy 332.718637 -401.087122) (xy 332.682948 -401.128314) (xy 332.641761 -401.164009) (xy 332.595913 -401.193478)
			(xy 332.546338 -401.216124) (xy 332.494045 -401.231484) (xy 332.440099 -401.239247) (xy 332.412848 -401.239736)
			(xy 331.549248 -401.239736) (xy 331.521995 -401.23922) (xy 331.468043 -401.231469) (xy 331.415743 -401.216118)
			(xy 331.36616 -401.19348) (xy 331.320305 -401.164016) (xy 331.279109 -401.128325) (xy 331.243413 -401.087134)
			(xy 331.213943 -401.041282) (xy 331.191298 -400.991702) (xy 331.175941 -400.939404) (xy 331.168183 -400.885453)
			(xy 329.73065 -400.885453) (xy 329.722893 -400.939404) (xy 329.707537 -400.991702) (xy 329.684895 -401.041282)
			(xy 329.655428 -401.087136) (xy 329.619734 -401.128329) (xy 329.578542 -401.164023) (xy 329.532689 -401.193491)
			(xy 329.483109 -401.216135) (xy 329.430812 -401.231492) (xy 329.376861 -401.23925) (xy 329.349608 -401.239736)
			(xy 328.486008 -401.239736) (xy 328.458757 -401.239217) (xy 328.404809 -401.231462) (xy 328.352514 -401.216108)
			(xy 328.302936 -401.193467) (xy 328.257086 -401.164002) (xy 328.215895 -401.128311) (xy 328.180203 -401.087121)
			(xy 328.150737 -401.041271) (xy 328.128095 -400.991694) (xy 328.11274 -400.939399) (xy 328.104983 -400.885451)
			(xy 326.667473 -400.885451) (xy 326.667473 -400.885456) (xy 326.659715 -400.939414) (xy 326.644356 -400.991718)
			(xy 326.621709 -401.041304) (xy 326.592236 -401.087162) (xy 326.556536 -401.128359) (xy 326.515337 -401.164055)
			(xy 326.469476 -401.193525) (xy 326.419888 -401.216167) (xy 326.367583 -401.231521) (xy 326.313624 -401.239275)
			(xy 326.286368 -401.239736) (xy 325.422768 -401.239736) (xy 325.39552 -401.239192) (xy 325.34158 -401.231432)
			(xy 325.289293 -401.216075) (xy 325.239724 -401.193434) (xy 325.193881 -401.163969) (xy 325.152697 -401.12828)
			(xy 325.117012 -401.087094) (xy 325.087551 -401.041248) (xy 325.064914 -400.991677) (xy 325.049561 -400.939389)
			(xy 325.041806 -400.885448) (xy 323.60415 -400.885448) (xy 323.60415 -400.885452) (xy 323.596394 -400.939401)
			(xy 323.581039 -400.991698) (xy 323.558398 -401.041277) (xy 323.528932 -401.087129) (xy 323.493241 -401.128321)
			(xy 323.452051 -401.164016) (xy 323.406201 -401.193485) (xy 323.356624 -401.216129) (xy 323.304329 -401.231488)
			(xy 323.25038 -401.239248) (xy 323.223128 -401.239736) (xy 322.359528 -401.239736) (xy 322.332276 -401.239219)
			(xy 322.278326 -401.231465) (xy 322.226028 -401.216113) (xy 322.176448 -401.193474) (xy 322.130595 -401.164009)
			(xy 322.089402 -401.128318) (xy 322.053708 -401.087127) (xy 322.02424 -401.041276) (xy 322.001597 -400.991698)
			(xy 321.98624 -400.939402) (xy 321.978483 -400.885452) (xy 320.540973 -400.885452) (xy 320.540973 -400.885455)
			(xy 320.533215 -400.939411) (xy 320.517857 -400.991714) (xy 320.495212 -401.041299) (xy 320.465741 -401.087156)
			(xy 320.430043 -401.128352) (xy 320.388846 -401.164048) (xy 320.342988 -401.193518) (xy 320.293403 -401.216162)
			(xy 320.2411 -401.231518) (xy 320.187143 -401.239274) (xy 320.159888 -401.239736) (xy 319.296288 -401.239736)
			(xy 319.269039 -401.239193) (xy 319.215097 -401.231436) (xy 319.162808 -401.216081) (xy 319.113236 -401.19344)
			(xy 319.06739 -401.163976) (xy 319.026204 -401.128287) (xy 318.990517 -401.0871) (xy 318.961054 -401.041254)
			(xy 318.938415 -400.991681) (xy 318.923062 -400.939391) (xy 318.915306 -400.885449) (xy 317.47765 -400.885449)
			(xy 317.47765 -400.885451) (xy 317.469894 -400.939399) (xy 317.454541 -400.991693) (xy 317.431901 -401.041271)
			(xy 317.402437 -401.087122) (xy 317.366748 -401.128314) (xy 317.325561 -401.164009) (xy 317.279713 -401.193478)
			(xy 317.230138 -401.216124) (xy 317.177845 -401.231484) (xy 317.123899 -401.239247) (xy 317.096648 -401.239736)
			(xy 316.233048 -401.239736) (xy 316.205795 -401.23922) (xy 316.151843 -401.231469) (xy 316.099543 -401.216118)
			(xy 316.04996 -401.19348) (xy 316.004105 -401.164016) (xy 315.962909 -401.128325) (xy 315.927213 -401.087134)
			(xy 315.897743 -401.041282) (xy 315.875098 -400.991702) (xy 315.859741 -400.939404) (xy 315.851983 -400.885453)
			(xy 314.41445 -400.885453) (xy 314.406693 -400.939404) (xy 314.391337 -400.991702) (xy 314.368695 -401.041282)
			(xy 314.339228 -401.087136) (xy 314.303534 -401.128329) (xy 314.262342 -401.164023) (xy 314.216489 -401.193491)
			(xy 314.166909 -401.216135) (xy 314.114612 -401.231492) (xy 314.060661 -401.23925) (xy 314.033408 -401.239736)
			(xy 313.169808 -401.239736) (xy 313.142557 -401.239217) (xy 313.088609 -401.231462) (xy 313.036314 -401.216108)
			(xy 312.986736 -401.193467) (xy 312.940886 -401.164002) (xy 312.899695 -401.128311) (xy 312.864003 -401.087121)
			(xy 312.834537 -401.041271) (xy 312.811895 -400.991694) (xy 312.79654 -400.939399) (xy 312.788783 -400.885451)
			(xy 311.351273 -400.885451) (xy 311.351273 -400.885456) (xy 311.343515 -400.939414) (xy 311.328156 -400.991718)
			(xy 311.305509 -401.041304) (xy 311.276036 -401.087162) (xy 311.240336 -401.128359) (xy 311.199137 -401.164055)
			(xy 311.153276 -401.193525) (xy 311.103688 -401.216167) (xy 311.051383 -401.231521) (xy 310.997424 -401.239275)
			(xy 310.970168 -401.239736) (xy 310.106568 -401.239736) (xy 310.07932 -401.239192) (xy 310.02538 -401.231432)
			(xy 309.973093 -401.216075) (xy 309.923524 -401.193434) (xy 309.877681 -401.163969) (xy 309.836497 -401.12828)
			(xy 309.800812 -401.087094) (xy 309.771351 -401.041248) (xy 309.748714 -400.991677) (xy 309.733361 -400.939389)
			(xy 309.725606 -400.885448) (xy 308.28795 -400.885448) (xy 308.28795 -400.885452) (xy 308.280194 -400.939401)
			(xy 308.264839 -400.991698) (xy 308.242198 -401.041277) (xy 308.212732 -401.087129) (xy 308.177041 -401.128321)
			(xy 308.135851 -401.164016) (xy 308.090001 -401.193485) (xy 308.040424 -401.216129) (xy 307.988129 -401.231488)
			(xy 307.93418 -401.239248) (xy 307.906928 -401.239736) (xy 307.043328 -401.239736) (xy 307.016076 -401.239219)
			(xy 306.962126 -401.231465) (xy 306.909828 -401.216113) (xy 306.860248 -401.193474) (xy 306.814395 -401.164009)
			(xy 306.773202 -401.128318) (xy 306.737508 -401.087127) (xy 306.70804 -401.041276) (xy 306.685397 -400.991698)
			(xy 306.67004 -400.939402) (xy 306.662283 -400.885452) (xy 305.224773 -400.885452) (xy 305.224773 -400.885455)
			(xy 305.217015 -400.939411) (xy 305.201657 -400.991714) (xy 305.179012 -401.041299) (xy 305.149541 -401.087156)
			(xy 305.113843 -401.128352) (xy 305.072646 -401.164048) (xy 305.026788 -401.193518) (xy 304.977203 -401.216162)
			(xy 304.9249 -401.231518) (xy 304.870943 -401.239274) (xy 304.843688 -401.239736) (xy 303.980088 -401.239736)
			(xy 303.952839 -401.239193) (xy 303.898897 -401.231436) (xy 303.846608 -401.216081) (xy 303.797036 -401.19344)
			(xy 303.75119 -401.163976) (xy 303.710004 -401.128287) (xy 303.674317 -401.0871) (xy 303.644854 -401.041254)
			(xy 303.622215 -400.991681) (xy 303.606862 -400.939391) (xy 303.599106 -400.885449) (xy 280.76398 -400.885449)
			(xy 280.76398 -402.0155) (xy 287.066441 -402.0155) (xy 287.070455 -401.951698) (xy 287.082434 -401.888902)
			(xy 287.102189 -401.828103) (xy 287.129408 -401.77026) (xy 287.163662 -401.716283) (xy 287.204411 -401.667026)
			(xy 287.251013 -401.623264) (xy 287.302731 -401.585688) (xy 287.358752 -401.55489) (xy 287.418191 -401.531357)
			(xy 287.48011 -401.515458) (xy 287.543534 -401.507446) (xy 287.575498 -401.506944) (xy 287.575752 -401.506944)
			(xy 287.607498 -401.507464) (xy 287.670494 -401.515393) (xy 287.732014 -401.531096) (xy 287.791102 -401.55433)
			(xy 287.846842 -401.584733) (xy 287.898367 -401.621834) (xy 287.921954 -401.643088) (xy 287.929217 -401.649272)
			(xy 287.946967 -401.656223) (xy 287.966029 -401.656223) (xy 287.983779 -401.649272) (xy 287.991042 -401.643088)
			(xy 288.014631 -401.621832) (xy 288.06614 -401.5847) (xy 288.121874 -401.554276) (xy 288.180965 -401.531035)
			(xy 288.242492 -401.515338) (xy 288.305495 -401.507431) (xy 288.337244 -401.506944) (xy 288.337498 -401.506944)
			(xy 288.369457 -401.507521) (xy 288.432872 -401.515532) (xy 288.494783 -401.531427) (xy 288.554213 -401.554957)
			(xy 288.610226 -401.58575) (xy 288.661937 -401.623321) (xy 288.708532 -401.667076) (xy 288.749276 -401.716326)
			(xy 288.783525 -401.770295) (xy 288.810741 -401.82813) (xy 288.830493 -401.888921) (xy 288.84247 -401.951707)
			(xy 288.846484 -402.0155) (xy 289.606441 -402.0155) (xy 289.610455 -401.951698) (xy 289.622434 -401.888902)
			(xy 289.642189 -401.828103) (xy 289.669408 -401.77026) (xy 289.703662 -401.716283) (xy 289.744411 -401.667026)
			(xy 289.791013 -401.623264) (xy 289.842731 -401.585688) (xy 289.898752 -401.55489) (xy 289.958191 -401.531357)
			(xy 290.02011 -401.515458) (xy 290.083534 -401.507446) (xy 290.115498 -401.506944) (xy 290.115752 -401.506944)
			(xy 290.147498 -401.507464) (xy 290.210494 -401.515393) (xy 290.272014 -401.531096) (xy 290.331102 -401.55433)
			(xy 290.386842 -401.584733) (xy 290.438367 -401.621834) (xy 290.461954 -401.643088) (xy 290.469217 -401.649272)
			(xy 290.486967 -401.656223) (xy 290.506029 -401.656223) (xy 290.523779 -401.649272) (xy 290.531042 -401.643088)
			(xy 290.554631 -401.621832) (xy 290.60614 -401.5847) (xy 290.661874 -401.554276) (xy 290.720965 -401.531035)
			(xy 290.782492 -401.515338) (xy 290.845495 -401.507431) (xy 290.877244 -401.506944) (xy 290.877498 -401.506944)
			(xy 290.909457 -401.507521) (xy 290.972872 -401.515532) (xy 291.034783 -401.531427) (xy 291.094213 -401.554957)
			(xy 291.150226 -401.58575) (xy 291.201937 -401.623321) (xy 291.248532 -401.667076) (xy 291.289276 -401.716326)
			(xy 291.323525 -401.770295) (xy 291.350741 -401.82813) (xy 291.370493 -401.888921) (xy 291.38247 -401.951707)
			(xy 291.386484 -402.0155) (xy 292.146441 -402.0155) (xy 292.150455 -401.951698) (xy 292.162434 -401.888902)
			(xy 292.182189 -401.828103) (xy 292.209408 -401.77026) (xy 292.243662 -401.716283) (xy 292.284411 -401.667026)
			(xy 292.331013 -401.623264) (xy 292.382731 -401.585688) (xy 292.438752 -401.55489) (xy 292.498191 -401.531357)
			(xy 292.56011 -401.515458) (xy 292.623534 -401.507446) (xy 292.655498 -401.506944) (xy 292.655752 -401.506944)
			(xy 292.687498 -401.507464) (xy 292.750494 -401.515393) (xy 292.812014 -401.531096) (xy 292.871102 -401.55433)
			(xy 292.926842 -401.584733) (xy 292.978367 -401.621834) (xy 293.001954 -401.643088) (xy 293.009217 -401.649272)
			(xy 293.026967 -401.656223) (xy 293.046029 -401.656223) (xy 293.063779 -401.649272) (xy 293.071042 -401.643088)
			(xy 293.094631 -401.621832) (xy 293.14614 -401.5847) (xy 293.201874 -401.554276) (xy 293.260965 -401.531035)
			(xy 293.322492 -401.515338) (xy 293.385495 -401.507431) (xy 293.417244 -401.506944) (xy 293.417498 -401.506944)
			(xy 293.449457 -401.507521) (xy 293.512872 -401.515532) (xy 293.574783 -401.531427) (xy 293.634213 -401.554957)
			(xy 293.690226 -401.58575) (xy 293.741937 -401.623321) (xy 293.788532 -401.667076) (xy 293.829276 -401.716326)
			(xy 293.863525 -401.770295) (xy 293.890741 -401.82813) (xy 293.910493 -401.888921) (xy 293.92247 -401.951707)
			(xy 293.926484 -402.0155) (xy 294.53602 -402.0155) (xy 294.540035 -401.951693) (xy 294.552015 -401.888892)
			(xy 294.571773 -401.828089) (xy 294.598995 -401.770241) (xy 294.633253 -401.716261) (xy 294.674007 -401.667001)
			(xy 294.720613 -401.623237) (xy 294.772338 -401.58566) (xy 294.828364 -401.554862) (xy 294.887809 -401.531329)
			(xy 294.949734 -401.515433) (xy 295.013163 -401.507423) (xy 295.04513 -401.506944) (xy 295.045384 -401.506944)
			(xy 295.077131 -401.507444) (xy 295.140127 -401.515377) (xy 295.201647 -401.531084) (xy 295.260736 -401.554322)
			(xy 295.316476 -401.584728) (xy 295.368 -401.621832) (xy 295.391586 -401.643088) (xy 295.398849 -401.649272)
			(xy 295.416599 -401.656223) (xy 295.435661 -401.656223) (xy 295.453411 -401.649272) (xy 295.460674 -401.643088)
			(xy 295.48425 -401.621817) (xy 295.535761 -401.584686) (xy 295.591498 -401.554265) (xy 295.650592 -401.531026)
			(xy 295.712121 -401.515332) (xy 295.775126 -401.507429) (xy 295.806876 -401.506944) (xy 295.80713 -401.506944)
			(xy 295.839087 -401.507544) (xy 295.902496 -401.515558) (xy 295.964401 -401.531455) (xy 296.023825 -401.554986)
			(xy 296.079832 -401.585779) (xy 296.131538 -401.623348) (xy 296.178128 -401.667102) (xy 296.218866 -401.716349)
			(xy 296.253112 -401.770314) (xy 296.280324 -401.828145) (xy 296.300074 -401.888931) (xy 296.312049 -401.951712)
			(xy 296.316063 -402.0155) (xy 297.07602 -402.0155) (xy 297.080035 -401.951693) (xy 297.092015 -401.888892)
			(xy 297.111773 -401.828089) (xy 297.138995 -401.770241) (xy 297.173253 -401.716261) (xy 297.214007 -401.667001)
			(xy 297.260613 -401.623237) (xy 297.312338 -401.58566) (xy 297.368364 -401.554862) (xy 297.427809 -401.531329)
			(xy 297.489734 -401.515433) (xy 297.553163 -401.507423) (xy 297.58513 -401.506944) (xy 297.585384 -401.506944)
			(xy 297.617131 -401.507444) (xy 297.680127 -401.515377) (xy 297.741647 -401.531084) (xy 297.800736 -401.554322)
			(xy 297.856476 -401.584728) (xy 297.908 -401.621832) (xy 297.931586 -401.643088) (xy 297.938849 -401.649272)
			(xy 297.956599 -401.656223) (xy 297.975661 -401.656223) (xy 297.993411 -401.649272) (xy 298.000674 -401.643088)
			(xy 298.02425 -401.621817) (xy 298.075761 -401.584686) (xy 298.131498 -401.554265) (xy 298.190592 -401.531026)
			(xy 298.252121 -401.515332) (xy 298.315126 -401.507429) (xy 298.346876 -401.506944) (xy 298.34713 -401.506944)
			(xy 298.379087 -401.507544) (xy 298.442496 -401.515558) (xy 298.504401 -401.531455) (xy 298.563825 -401.554986)
			(xy 298.619832 -401.585779) (xy 298.671538 -401.623348) (xy 298.718128 -401.667102) (xy 298.758866 -401.716349)
			(xy 298.793112 -401.770314) (xy 298.820324 -401.828145) (xy 298.840074 -401.888931) (xy 298.852049 -401.951712)
			(xy 298.856063 -402.0155) (xy 298.852049 -402.079288) (xy 298.840074 -402.142069) (xy 298.820324 -402.202855)
			(xy 298.793112 -402.260686) (xy 298.758866 -402.314651) (xy 298.718128 -402.363898) (xy 298.671538 -402.407652)
			(xy 298.619832 -402.445221) (xy 298.563825 -402.476014) (xy 298.504401 -402.499545) (xy 298.442496 -402.515442)
			(xy 298.379087 -402.523456) (xy 298.34713 -402.52396) (xy 298.346876 -402.52396) (xy 298.315131 -402.523422)
			(xy 298.252136 -402.515497) (xy 298.190616 -402.499797) (xy 298.131527 -402.476566) (xy 298.075787 -402.446166)
			(xy 298.024261 -402.409069) (xy 298.000674 -402.387816) (xy 297.993411 -402.381632) (xy 297.975661 -402.374681)
			(xy 297.956599 -402.374681) (xy 297.938849 -402.381632) (xy 297.931586 -402.387816) (xy 297.908028 -402.409107)
			(xy 297.856512 -402.446235) (xy 297.800771 -402.476654) (xy 297.741674 -402.499889) (xy 297.680142 -402.515579)
			(xy 297.617135 -402.523478) (xy 297.585384 -402.52396) (xy 297.58513 -402.52396) (xy 297.553163 -402.523577)
			(xy 297.489734 -402.515567) (xy 297.427809 -402.499671) (xy 297.368364 -402.476138) (xy 297.312338 -402.44534)
			(xy 297.260613 -402.407763) (xy 297.214007 -402.363999) (xy 297.173253 -402.314739) (xy 297.138995 -402.260759)
			(xy 297.111773 -402.202911) (xy 297.092015 -402.142108) (xy 297.080035 -402.079307) (xy 297.07602 -402.0155)
			(xy 296.316063 -402.0155) (xy 296.312049 -402.079288) (xy 296.300074 -402.142069) (xy 296.280324 -402.202855)
			(xy 296.253112 -402.260686) (xy 296.218866 -402.314651) (xy 296.178128 -402.363898) (xy 296.131538 -402.407652)
			(xy 296.079832 -402.445221) (xy 296.023825 -402.476014) (xy 295.964401 -402.499545) (xy 295.902496 -402.515442)
			(xy 295.839087 -402.523456) (xy 295.80713 -402.52396) (xy 295.806876 -402.52396) (xy 295.775131 -402.523422)
			(xy 295.712136 -402.515497) (xy 295.650616 -402.499797) (xy 295.591527 -402.476566) (xy 295.535787 -402.446166)
			(xy 295.484261 -402.409069) (xy 295.460674 -402.387816) (xy 295.453411 -402.381632) (xy 295.435661 -402.374681)
			(xy 295.416599 -402.374681) (xy 295.398849 -402.381632) (xy 295.391586 -402.387816) (xy 295.368028 -402.409107)
			(xy 295.316512 -402.446235) (xy 295.260771 -402.476654) (xy 295.201674 -402.499889) (xy 295.140142 -402.515579)
			(xy 295.077135 -402.523478) (xy 295.045384 -402.52396) (xy 295.04513 -402.52396) (xy 295.013163 -402.523577)
			(xy 294.949734 -402.515567) (xy 294.887809 -402.499671) (xy 294.828364 -402.476138) (xy 294.772338 -402.44534)
			(xy 294.720613 -402.407763) (xy 294.674007 -402.363999) (xy 294.633253 -402.314739) (xy 294.598995 -402.260759)
			(xy 294.571773 -402.202911) (xy 294.552015 -402.142108) (xy 294.540035 -402.079307) (xy 294.53602 -402.0155)
			(xy 293.926484 -402.0155) (xy 293.92247 -402.079293) (xy 293.910493 -402.142079) (xy 293.890741 -402.20287)
			(xy 293.863525 -402.260705) (xy 293.829276 -402.314674) (xy 293.788532 -402.363924) (xy 293.741937 -402.407679)
			(xy 293.690226 -402.44525) (xy 293.634213 -402.476043) (xy 293.574783 -402.499573) (xy 293.512872 -402.515468)
			(xy 293.449457 -402.523479) (xy 293.417498 -402.52396) (xy 293.417244 -402.52396) (xy 293.385498 -402.523442)
			(xy 293.322502 -402.515512) (xy 293.260982 -402.499809) (xy 293.201894 -402.476575) (xy 293.146154 -402.446171)
			(xy 293.094629 -402.40907) (xy 293.071042 -402.387816) (xy 293.063779 -402.381632) (xy 293.046029 -402.374681)
			(xy 293.026967 -402.374681) (xy 293.009217 -402.381632) (xy 293.001954 -402.387816) (xy 292.978367 -402.409074)
			(xy 292.926858 -402.446206) (xy 292.871123 -402.47663) (xy 292.812032 -402.499871) (xy 292.750504 -402.515567)
			(xy 292.687501 -402.523474) (xy 292.655752 -402.52396) (xy 292.655498 -402.52396) (xy 292.623534 -402.523554)
			(xy 292.56011 -402.515542) (xy 292.498191 -402.499643) (xy 292.438752 -402.47611) (xy 292.382731 -402.445312)
			(xy 292.331013 -402.407736) (xy 292.284411 -402.363974) (xy 292.243662 -402.314717) (xy 292.209408 -402.26074)
			(xy 292.182189 -402.202897) (xy 292.162434 -402.142098) (xy 292.150455 -402.079302) (xy 292.146441 -402.0155)
			(xy 291.386484 -402.0155) (xy 291.38247 -402.079293) (xy 291.370493 -402.142079) (xy 291.350741 -402.20287)
			(xy 291.323525 -402.260705) (xy 291.289276 -402.314674) (xy 291.248532 -402.363924) (xy 291.201937 -402.407679)
			(xy 291.150226 -402.44525) (xy 291.094213 -402.476043) (xy 291.034783 -402.499573) (xy 290.972872 -402.515468)
			(xy 290.909457 -402.523479) (xy 290.877498 -402.52396) (xy 290.877244 -402.52396) (xy 290.845498 -402.523442)
			(xy 290.782502 -402.515512) (xy 290.720982 -402.499809) (xy 290.661894 -402.476575) (xy 290.606154 -402.446171)
			(xy 290.554629 -402.40907) (xy 290.531042 -402.387816) (xy 290.523779 -402.381632) (xy 290.506029 -402.374681)
			(xy 290.486967 -402.374681) (xy 290.469217 -402.381632) (xy 290.461954 -402.387816) (xy 290.438367 -402.409074)
			(xy 290.386858 -402.446206) (xy 290.331123 -402.47663) (xy 290.272032 -402.499871) (xy 290.210504 -402.515567)
			(xy 290.147501 -402.523474) (xy 290.115752 -402.52396) (xy 290.115498 -402.52396) (xy 290.083534 -402.523554)
			(xy 290.02011 -402.515542) (xy 289.958191 -402.499643) (xy 289.898752 -402.47611) (xy 289.842731 -402.445312)
			(xy 289.791013 -402.407736) (xy 289.744411 -402.363974) (xy 289.703662 -402.314717) (xy 289.669408 -402.26074)
			(xy 289.642189 -402.202897) (xy 289.622434 -402.142098) (xy 289.610455 -402.079302) (xy 289.606441 -402.0155)
			(xy 288.846484 -402.0155) (xy 288.84247 -402.079293) (xy 288.830493 -402.142079) (xy 288.810741 -402.20287)
			(xy 288.783525 -402.260705) (xy 288.749276 -402.314674) (xy 288.708532 -402.363924) (xy 288.661937 -402.407679)
			(xy 288.610226 -402.44525) (xy 288.554213 -402.476043) (xy 288.494783 -402.499573) (xy 288.432872 -402.515468)
			(xy 288.369457 -402.523479) (xy 288.337498 -402.52396) (xy 288.337244 -402.52396) (xy 288.305498 -402.523442)
			(xy 288.242502 -402.515512) (xy 288.180982 -402.499809) (xy 288.121894 -402.476575) (xy 288.066154 -402.446171)
			(xy 288.014629 -402.40907) (xy 287.991042 -402.387816) (xy 287.983779 -402.381632) (xy 287.966029 -402.374681)
			(xy 287.946967 -402.374681) (xy 287.929217 -402.381632) (xy 287.921954 -402.387816) (xy 287.898367 -402.409074)
			(xy 287.846858 -402.446206) (xy 287.791123 -402.47663) (xy 287.732032 -402.499871) (xy 287.670504 -402.515567)
			(xy 287.607501 -402.523474) (xy 287.575752 -402.52396) (xy 287.575498 -402.52396) (xy 287.543534 -402.523554)
			(xy 287.48011 -402.515542) (xy 287.418191 -402.499643) (xy 287.358752 -402.47611) (xy 287.302731 -402.445312)
			(xy 287.251013 -402.407736) (xy 287.204411 -402.363974) (xy 287.163662 -402.314717) (xy 287.129408 -402.26074)
			(xy 287.102189 -402.202897) (xy 287.082434 -402.142098) (xy 287.070455 -402.079302) (xy 287.066441 -402.0155)
			(xy 280.76398 -402.0155) (xy 280.76398 -402.1074) (xy 280.76343 -402.132362) (xy 280.753694 -402.181326)
			(xy 280.734578 -402.227444) (xy 280.706818 -402.268937) (xy 280.689558 -402.286978) (xy 280.501598 -402.474938)
			(xy 280.483557 -402.492195) (xy 280.442055 -402.519934) (xy 280.395938 -402.539043) (xy 280.346979 -402.548787)
			(xy 280.32202 -402.54936) (xy 239.86236 -402.54936) (xy 239.8374 -402.548779) (xy 239.788437 -402.539054)
			(xy 239.742319 -402.519947) (xy 239.700824 -402.492195) (xy 239.682782 -402.474938) (xy 239.497362 -402.289518)
			(xy 239.480115 -402.271468) (xy 239.452373 -402.229969) (xy 239.433262 -402.183855) (xy 239.423515 -402.134899)
			(xy 239.42294 -402.10994) (xy 2.509012 -402.10994) (xy 2.509012 -402.656674) (xy 98.152872 -402.656674)
			(xy 98.152872 -402.602126) (xy 98.160635 -402.548133) (xy 98.176003 -402.495795) (xy 98.198664 -402.446176)
			(xy 98.228156 -402.400288) (xy 98.263878 -402.359064) (xy 98.305104 -402.323344) (xy 98.350994 -402.293855)
			(xy 98.400613 -402.271196) (xy 98.452953 -402.255831) (xy 98.506946 -402.24807) (xy 98.53422 -402.247608)
			(xy 99.39782 -402.247608) (xy 99.425086 -402.248156) (xy 99.479063 -402.255919) (xy 99.531387 -402.271285)
			(xy 99.58099 -402.293941) (xy 99.626865 -402.323425) (xy 99.668077 -402.359137) (xy 99.703787 -402.400351)
			(xy 99.733269 -402.446227) (xy 99.755922 -402.495832) (xy 99.771285 -402.548156) (xy 99.779046 -402.602134)
			(xy 99.779046 -402.656666) (xy 99.771285 -402.710644) (xy 99.755922 -402.762968) (xy 99.733269 -402.812573)
			(xy 99.703787 -402.858449) (xy 99.668077 -402.899663) (xy 99.626865 -402.935375) (xy 99.58099 -402.964859)
			(xy 99.531387 -402.987515) (xy 99.479063 -403.002881) (xy 99.425086 -403.010644) (xy 99.39782 -403.011132)
			(xy 98.53422 -403.011132) (xy 98.506946 -403.01073) (xy 98.452953 -403.002969) (xy 98.400613 -402.987604)
			(xy 98.350994 -402.964945) (xy 98.305104 -402.935456) (xy 98.263878 -402.899736) (xy 98.228156 -402.858512)
			(xy 98.198664 -402.812624) (xy 98.176003 -402.763005) (xy 98.160635 -402.710667) (xy 98.152872 -402.656674)
			(xy 2.509012 -402.656674) (xy 2.509012 -403.371812) (xy 2.5095 -403.425034) (xy 2.517117 -403.531207)
			(xy 2.532283 -403.636566) (xy 2.554922 -403.740575) (xy 2.584919 -403.842706) (xy 2.610452 -403.911156)
			(xy 47.598731 -403.911156) (xy 47.598731 -403.856644) (xy 47.606489 -403.802686) (xy 47.621848 -403.750382)
			(xy 47.644495 -403.700796) (xy 47.673969 -403.654938) (xy 47.709669 -403.613742) (xy 47.750868 -403.578046)
			(xy 47.796729 -403.548577) (xy 47.846317 -403.525935) (xy 47.898623 -403.510581) (xy 47.952582 -403.502828)
			(xy 47.979838 -403.502368) (xy 48.843438 -403.502368) (xy 48.870686 -403.502905) (xy 48.924626 -403.510665)
			(xy 48.976913 -403.526023) (xy 49.026482 -403.548665) (xy 49.072325 -403.57813) (xy 49.113508 -403.613819)
			(xy 49.149193 -403.655006) (xy 49.178654 -403.700851) (xy 49.201291 -403.750423) (xy 49.216643 -403.802711)
			(xy 49.224398 -403.856652) (xy 49.224398 -403.911148) (xy 49.224397 -403.911152) (xy 50.662054 -403.911152)
			(xy 50.662054 -403.856648) (xy 50.66981 -403.802699) (xy 50.685165 -403.750403) (xy 50.707806 -403.700824)
			(xy 50.737272 -403.654971) (xy 50.772964 -403.613779) (xy 50.814154 -403.578085) (xy 50.860004 -403.548617)
			(xy 50.909582 -403.525973) (xy 50.961877 -403.510615) (xy 51.015826 -403.502855) (xy 51.043078 -403.502368)
			(xy 51.906678 -403.502368) (xy 51.93393 -403.502878) (xy 51.98788 -403.510632) (xy 52.040177 -403.525985)
			(xy 52.089757 -403.548625) (xy 52.13561 -403.57809) (xy 52.176803 -403.613782) (xy 52.212497 -403.654972)
			(xy 52.241965 -403.700824) (xy 52.264607 -403.750402) (xy 52.279964 -403.802698) (xy 52.287721 -403.856648)
			(xy 52.287721 -403.911152) (xy 52.287721 -403.911155) (xy 53.725231 -403.911155) (xy 53.725231 -403.856645)
			(xy 53.732989 -403.802689) (xy 53.748347 -403.750386) (xy 53.770992 -403.700801) (xy 53.800464 -403.654945)
			(xy 53.836162 -403.613749) (xy 53.877359 -403.578053) (xy 53.923217 -403.548583) (xy 53.972803 -403.525941)
			(xy 54.025106 -403.510585) (xy 54.079063 -403.50283) (xy 54.106318 -403.502368) (xy 54.969918 -403.502368)
			(xy 54.997167 -403.502903) (xy 55.051109 -403.510662) (xy 55.103398 -403.526017) (xy 55.15297 -403.548658)
			(xy 55.198815 -403.578123) (xy 55.240001 -403.613812) (xy 55.275688 -403.654999) (xy 55.305151 -403.700846)
			(xy 55.327789 -403.750419) (xy 55.343142 -403.802709) (xy 55.350898 -403.856651) (xy 55.350898 -403.911149)
			(xy 55.350898 -403.911151) (xy 56.788554 -403.911151) (xy 56.788554 -403.856649) (xy 56.79631 -403.802702)
			(xy 56.811664 -403.750407) (xy 56.834303 -403.700829) (xy 56.863767 -403.654978) (xy 56.899457 -403.613786)
			(xy 56.940644 -403.578093) (xy 56.986492 -403.548623) (xy 57.036067 -403.525978) (xy 57.08836 -403.510619)
			(xy 57.142307 -403.502857) (xy 57.169558 -403.502368) (xy 58.033158 -403.502368) (xy 58.060411 -403.502876)
			(xy 58.114363 -403.510628) (xy 58.166663 -403.525979) (xy 58.216245 -403.548618) (xy 58.262101 -403.578083)
			(xy 58.303296 -403.613775) (xy 58.338992 -403.654966) (xy 58.368462 -403.700818) (xy 58.391106 -403.750398)
			(xy 58.406463 -403.802696) (xy 58.414221 -403.856647) (xy 58.414221 -403.911153) (xy 59.851754 -403.911153)
			(xy 59.851754 -403.856647) (xy 59.859511 -403.802696) (xy 59.874867 -403.750398) (xy 59.897509 -403.700818)
			(xy 59.926977 -403.654965) (xy 59.962671 -403.613772) (xy 60.003863 -403.578078) (xy 60.049716 -403.54861)
			(xy 60.099296 -403.525967) (xy 60.151594 -403.510611) (xy 60.205545 -403.502854) (xy 60.232798 -403.502368)
			(xy 61.096398 -403.502368) (xy 61.123649 -403.502879) (xy 61.177597 -403.510635) (xy 61.229892 -403.52599)
			(xy 61.279469 -403.548631) (xy 61.32532 -403.578097) (xy 61.36651 -403.613789) (xy 61.402201 -403.654979)
			(xy 61.431668 -403.700829) (xy 61.454309 -403.750406) (xy 61.469664 -403.802701) (xy 61.477421 -403.856649)
			(xy 61.477421 -403.911151) (xy 61.47742 -403.911156) (xy 62.914931 -403.911156) (xy 62.914931 -403.856644)
			(xy 62.922689 -403.802686) (xy 62.938048 -403.750382) (xy 62.960695 -403.700796) (xy 62.990169 -403.654938)
			(xy 63.025869 -403.613742) (xy 63.067068 -403.578046) (xy 63.112929 -403.548577) (xy 63.162517 -403.525935)
			(xy 63.214823 -403.510581) (xy 63.268782 -403.502828) (xy 63.296038 -403.502368) (xy 64.159638 -403.502368)
			(xy 64.186886 -403.502905) (xy 64.240826 -403.510665) (xy 64.293113 -403.526023) (xy 64.342682 -403.548665)
			(xy 64.388525 -403.57813) (xy 64.429708 -403.613819) (xy 64.465393 -403.655006) (xy 64.494854 -403.700851)
			(xy 64.517491 -403.750423) (xy 64.532843 -403.802711) (xy 64.540598 -403.856652) (xy 64.540598 -403.911148)
			(xy 64.540597 -403.911152) (xy 65.978254 -403.911152) (xy 65.978254 -403.856648) (xy 65.98601 -403.802699)
			(xy 66.001365 -403.750403) (xy 66.024006 -403.700824) (xy 66.053472 -403.654971) (xy 66.089164 -403.613779)
			(xy 66.130354 -403.578085) (xy 66.176204 -403.548617) (xy 66.225782 -403.525973) (xy 66.278077 -403.510615)
			(xy 66.332026 -403.502855) (xy 66.359278 -403.502368) (xy 67.222878 -403.502368) (xy 67.25013 -403.502878)
			(xy 67.30408 -403.510632) (xy 67.356377 -403.525985) (xy 67.405957 -403.548625) (xy 67.45181 -403.57809)
			(xy 67.493003 -403.613782) (xy 67.528697 -403.654972) (xy 67.558165 -403.700824) (xy 67.580807 -403.750402)
			(xy 67.596164 -403.802698) (xy 67.603921 -403.856648) (xy 67.603921 -403.911152) (xy 67.603921 -403.911155)
			(xy 69.041431 -403.911155) (xy 69.041431 -403.856645) (xy 69.049189 -403.802689) (xy 69.064547 -403.750386)
			(xy 69.087192 -403.700801) (xy 69.116664 -403.654945) (xy 69.152362 -403.613749) (xy 69.193559 -403.578053)
			(xy 69.239417 -403.548583) (xy 69.289003 -403.525941) (xy 69.341306 -403.510585) (xy 69.395263 -403.50283)
			(xy 69.422518 -403.502368) (xy 70.286118 -403.502368) (xy 70.313367 -403.502903) (xy 70.367309 -403.510662)
			(xy 70.419598 -403.526017) (xy 70.46917 -403.548658) (xy 70.515015 -403.578123) (xy 70.556201 -403.613812)
			(xy 70.591888 -403.654999) (xy 70.621351 -403.700846) (xy 70.643989 -403.750419) (xy 70.659342 -403.802709)
			(xy 70.667098 -403.856651) (xy 70.667098 -403.911149) (xy 70.667098 -403.911151) (xy 72.104754 -403.911151)
			(xy 72.104754 -403.856649) (xy 72.11251 -403.802702) (xy 72.127864 -403.750407) (xy 72.150503 -403.700829)
			(xy 72.179967 -403.654978) (xy 72.215657 -403.613786) (xy 72.256844 -403.578093) (xy 72.302692 -403.548623)
			(xy 72.352267 -403.525978) (xy 72.40456 -403.510619) (xy 72.458507 -403.502857) (xy 72.485758 -403.502368)
			(xy 73.349358 -403.502368) (xy 73.376611 -403.502876) (xy 73.430563 -403.510628) (xy 73.482863 -403.525979)
			(xy 73.532445 -403.548618) (xy 73.578301 -403.578083) (xy 73.619496 -403.613775) (xy 73.655192 -403.654966)
			(xy 73.684662 -403.700818) (xy 73.707306 -403.750398) (xy 73.722663 -403.802696) (xy 73.730421 -403.856647)
			(xy 73.730421 -403.911153) (xy 75.167954 -403.911153) (xy 75.167954 -403.856647) (xy 75.175711 -403.802696)
			(xy 75.191067 -403.750398) (xy 75.213709 -403.700818) (xy 75.243177 -403.654965) (xy 75.278871 -403.613772)
			(xy 75.320063 -403.578078) (xy 75.365916 -403.54861) (xy 75.415496 -403.525967) (xy 75.467794 -403.510611)
			(xy 75.521745 -403.502854) (xy 75.548998 -403.502368) (xy 76.412598 -403.502368) (xy 76.439849 -403.502879)
			(xy 76.493797 -403.510635) (xy 76.546092 -403.52599) (xy 76.595669 -403.548631) (xy 76.64152 -403.578097)
			(xy 76.68271 -403.613789) (xy 76.718401 -403.654979) (xy 76.747868 -403.700829) (xy 76.770509 -403.750406)
			(xy 76.785864 -403.802701) (xy 76.793621 -403.856649) (xy 76.793621 -403.911151) (xy 76.79362 -403.911156)
			(xy 78.231131 -403.911156) (xy 78.231131 -403.856644) (xy 78.238889 -403.802686) (xy 78.254248 -403.750382)
			(xy 78.276895 -403.700796) (xy 78.306369 -403.654938) (xy 78.342069 -403.613742) (xy 78.383268 -403.578046)
			(xy 78.429129 -403.548577) (xy 78.478717 -403.525935) (xy 78.531023 -403.510581) (xy 78.584982 -403.502828)
			(xy 78.612238 -403.502368) (xy 79.475838 -403.502368) (xy 79.503086 -403.502905) (xy 79.557026 -403.510665)
			(xy 79.609313 -403.526023) (xy 79.658882 -403.548665) (xy 79.704725 -403.57813) (xy 79.745908 -403.613819)
			(xy 79.781593 -403.655006) (xy 79.811054 -403.700851) (xy 79.833691 -403.750423) (xy 79.849043 -403.802711)
			(xy 79.856798 -403.856652) (xy 79.856798 -403.911148) (xy 79.856797 -403.911152) (xy 81.294454 -403.911152)
			(xy 81.294454 -403.856648) (xy 81.30221 -403.802699) (xy 81.317565 -403.750403) (xy 81.340206 -403.700824)
			(xy 81.369672 -403.654971) (xy 81.405364 -403.613779) (xy 81.446554 -403.578085) (xy 81.492404 -403.548617)
			(xy 81.541982 -403.525973) (xy 81.594277 -403.510615) (xy 81.648226 -403.502855) (xy 81.675478 -403.502368)
			(xy 82.539078 -403.502368) (xy 82.56633 -403.502878) (xy 82.62028 -403.510632) (xy 82.672577 -403.525985)
			(xy 82.722157 -403.548625) (xy 82.76801 -403.57809) (xy 82.809203 -403.613782) (xy 82.844897 -403.654972)
			(xy 82.874365 -403.700824) (xy 82.897007 -403.750402) (xy 82.912364 -403.802698) (xy 82.920121 -403.856648)
			(xy 82.920121 -403.911152) (xy 82.920121 -403.911155) (xy 84.357631 -403.911155) (xy 84.357631 -403.856645)
			(xy 84.365389 -403.802689) (xy 84.380747 -403.750386) (xy 84.403392 -403.700801) (xy 84.432864 -403.654945)
			(xy 84.468562 -403.613749) (xy 84.509759 -403.578053) (xy 84.555617 -403.548583) (xy 84.605203 -403.525941)
			(xy 84.657506 -403.510585) (xy 84.711463 -403.50283) (xy 84.738718 -403.502368) (xy 85.602318 -403.502368)
			(xy 85.629567 -403.502903) (xy 85.683509 -403.510662) (xy 85.735798 -403.526017) (xy 85.78537 -403.548658)
			(xy 85.831215 -403.578123) (xy 85.872401 -403.613812) (xy 85.908088 -403.654999) (xy 85.937551 -403.700846)
			(xy 85.960189 -403.750419) (xy 85.975542 -403.802709) (xy 85.983298 -403.856651) (xy 85.983298 -403.911149)
			(xy 85.983298 -403.911151) (xy 87.420954 -403.911151) (xy 87.420954 -403.856649) (xy 87.42871 -403.802702)
			(xy 87.444064 -403.750407) (xy 87.466703 -403.700829) (xy 87.496167 -403.654978) (xy 87.531857 -403.613786)
			(xy 87.573044 -403.578093) (xy 87.618892 -403.548623) (xy 87.668467 -403.525978) (xy 87.72076 -403.510619)
			(xy 87.774707 -403.502857) (xy 87.801958 -403.502368) (xy 88.665558 -403.502368) (xy 88.692811 -403.502876)
			(xy 88.746763 -403.510628) (xy 88.799063 -403.525979) (xy 88.848645 -403.548618) (xy 88.894501 -403.578083)
			(xy 88.935696 -403.613775) (xy 88.971392 -403.654966) (xy 89.000862 -403.700818) (xy 89.023506 -403.750398)
			(xy 89.038863 -403.802696) (xy 89.046621 -403.856647) (xy 89.046621 -403.911153) (xy 90.484154 -403.911153)
			(xy 90.484154 -403.856647) (xy 90.491911 -403.802696) (xy 90.507267 -403.750398) (xy 90.529909 -403.700818)
			(xy 90.559377 -403.654965) (xy 90.595071 -403.613772) (xy 90.636263 -403.578078) (xy 90.682116 -403.54861)
			(xy 90.731696 -403.525967) (xy 90.783994 -403.510611) (xy 90.837945 -403.502854) (xy 90.865198 -403.502368)
			(xy 91.728798 -403.502368) (xy 91.756049 -403.502879) (xy 91.809997 -403.510635) (xy 91.862292 -403.52599)
			(xy 91.911869 -403.548631) (xy 91.95772 -403.578097) (xy 91.99891 -403.613789) (xy 92.034601 -403.654979)
			(xy 92.064068 -403.700829) (xy 92.086709 -403.750406) (xy 92.102064 -403.802701) (xy 92.109821 -403.856649)
			(xy 92.109821 -403.911151) (xy 92.10982 -403.911156) (xy 93.547331 -403.911156) (xy 93.547331 -403.856644)
			(xy 93.555089 -403.802686) (xy 93.570448 -403.750382) (xy 93.593095 -403.700796) (xy 93.622569 -403.654938)
			(xy 93.658269 -403.613742) (xy 93.699468 -403.578046) (xy 93.745329 -403.548577) (xy 93.794917 -403.525935)
			(xy 93.847223 -403.510581) (xy 93.901182 -403.502828) (xy 93.928438 -403.502368) (xy 94.792038 -403.502368)
			(xy 94.819286 -403.502905) (xy 94.873226 -403.510665) (xy 94.925513 -403.526023) (xy 94.975082 -403.548665)
			(xy 95.020925 -403.57813) (xy 95.062108 -403.613819) (xy 95.097793 -403.655006) (xy 95.127254 -403.700851)
			(xy 95.149891 -403.750423) (xy 95.165243 -403.802711) (xy 95.172998 -403.856652) (xy 95.172998 -403.911148)
			(xy 95.172998 -403.911151) (xy 119.773954 -403.911151) (xy 119.773954 -403.856649) (xy 119.78171 -403.802702)
			(xy 119.797063 -403.750408) (xy 119.819702 -403.70083) (xy 119.849166 -403.654979) (xy 119.884855 -403.613788)
			(xy 119.926042 -403.578094) (xy 119.97189 -403.548625) (xy 120.021465 -403.525979) (xy 120.073757 -403.510619)
			(xy 120.127703 -403.502857) (xy 120.154954 -403.502368) (xy 121.018554 -403.502368) (xy 121.045807 -403.502876)
			(xy 121.09976 -403.510627) (xy 121.15206 -403.525978) (xy 121.201643 -403.548617) (xy 121.247499 -403.578082)
			(xy 121.288694 -403.613773) (xy 121.324391 -403.654964) (xy 121.353861 -403.700817) (xy 121.376506 -403.750397)
			(xy 121.391863 -403.802695) (xy 121.399621 -403.856647) (xy 121.399621 -403.911153) (xy 122.837154 -403.911153)
			(xy 122.837154 -403.856647) (xy 122.844911 -403.802697) (xy 122.860266 -403.750399) (xy 122.882909 -403.700819)
			(xy 122.912376 -403.654966) (xy 122.948069 -403.613774) (xy 122.989261 -403.57808) (xy 123.035114 -403.548611)
			(xy 123.084694 -403.525969) (xy 123.136991 -403.510612) (xy 123.190941 -403.502854) (xy 123.218194 -403.502368)
			(xy 124.081794 -403.502368) (xy 124.109045 -403.502879) (xy 124.162994 -403.510635) (xy 124.215289 -403.525989)
			(xy 124.264867 -403.54863) (xy 124.310718 -403.578096) (xy 124.351908 -403.613787) (xy 124.3876 -403.654978)
			(xy 124.417067 -403.700828) (xy 124.439709 -403.750406) (xy 124.455064 -403.802701) (xy 124.462821 -403.856649)
			(xy 124.462821 -403.911151) (xy 124.46282 -403.911156) (xy 125.900331 -403.911156) (xy 125.900331 -403.856644)
			(xy 125.908089 -403.802686) (xy 125.923448 -403.750383) (xy 125.946095 -403.700797) (xy 125.975568 -403.654939)
			(xy 126.011267 -403.613743) (xy 126.052467 -403.578047) (xy 126.098327 -403.548578) (xy 126.147914 -403.525936)
			(xy 126.20022 -403.510582) (xy 126.254178 -403.502829) (xy 126.281434 -403.502368) (xy 127.145034 -403.502368)
			(xy 127.172282 -403.502905) (xy 127.226223 -403.510664) (xy 127.27851 -403.526022) (xy 127.32808 -403.548663)
			(xy 127.373923 -403.578129) (xy 127.415106 -403.613818) (xy 127.450792 -403.655004) (xy 127.480253 -403.70085)
			(xy 127.50289 -403.750422) (xy 127.518243 -403.802711) (xy 127.525998 -403.856652) (xy 127.525998 -403.911148)
			(xy 127.525997 -403.911152) (xy 128.963654 -403.911152) (xy 128.963654 -403.856648) (xy 128.97141 -403.802699)
			(xy 128.986765 -403.750403) (xy 129.009406 -403.700825) (xy 129.038871 -403.654973) (xy 129.074562 -403.613781)
			(xy 129.115752 -403.578087) (xy 129.161602 -403.548618) (xy 129.211179 -403.525974) (xy 129.263474 -403.510616)
			(xy 129.317422 -403.502856) (xy 129.344674 -403.502368) (xy 130.208274 -403.502368) (xy 130.235526 -403.502878)
			(xy 130.289477 -403.510631) (xy 130.341774 -403.525984) (xy 130.391355 -403.548623) (xy 130.437208 -403.578089)
			(xy 130.478401 -403.61378) (xy 130.514096 -403.654971) (xy 130.543564 -403.700822) (xy 130.566207 -403.750401)
			(xy 130.581563 -403.802698) (xy 130.589321 -403.856648) (xy 130.589321 -403.911152) (xy 130.589321 -403.911155)
			(xy 132.026831 -403.911155) (xy 132.026831 -403.856645) (xy 132.034589 -403.802689) (xy 132.049946 -403.750387)
			(xy 132.072591 -403.700803) (xy 132.102063 -403.654946) (xy 132.13776 -403.61375) (xy 132.178957 -403.578054)
			(xy 132.224815 -403.548585) (xy 132.2744 -403.525942) (xy 132.326703 -403.510586) (xy 132.380659 -403.50283)
			(xy 132.407914 -403.502368) (xy 133.271514 -403.502368) (xy 133.298763 -403.502903) (xy 133.352706 -403.510661)
			(xy 133.404995 -403.526016) (xy 133.454568 -403.548657) (xy 133.500413 -403.578121) (xy 133.541599 -403.613811)
			(xy 133.577287 -403.654998) (xy 133.60675 -403.700845) (xy 133.629389 -403.750418) (xy 133.644742 -403.802708)
			(xy 133.652498 -403.856651) (xy 133.652498 -403.911149) (xy 133.652498 -403.911151) (xy 135.090154 -403.911151)
			(xy 135.090154 -403.856649) (xy 135.09791 -403.802702) (xy 135.113263 -403.750408) (xy 135.135902 -403.70083)
			(xy 135.165366 -403.654979) (xy 135.201055 -403.613788) (xy 135.242242 -403.578094) (xy 135.28809 -403.548625)
			(xy 135.337665 -403.525979) (xy 135.389957 -403.510619) (xy 135.443903 -403.502857) (xy 135.471154 -403.502368)
			(xy 136.334754 -403.502368) (xy 136.362007 -403.502876) (xy 136.41596 -403.510627) (xy 136.46826 -403.525978)
			(xy 136.517843 -403.548617) (xy 136.563699 -403.578082) (xy 136.604894 -403.613773) (xy 136.640591 -403.654964)
			(xy 136.670061 -403.700817) (xy 136.692706 -403.750397) (xy 136.708063 -403.802695) (xy 136.715821 -403.856647)
			(xy 136.715821 -403.911153) (xy 138.153354 -403.911153) (xy 138.153354 -403.856647) (xy 138.161111 -403.802697)
			(xy 138.176466 -403.750399) (xy 138.199109 -403.700819) (xy 138.228576 -403.654966) (xy 138.264269 -403.613774)
			(xy 138.305461 -403.57808) (xy 138.351314 -403.548611) (xy 138.400894 -403.525969) (xy 138.453191 -403.510612)
			(xy 138.507141 -403.502854) (xy 138.534394 -403.502368) (xy 139.397994 -403.502368) (xy 139.425245 -403.502879)
			(xy 139.479194 -403.510635) (xy 139.531489 -403.525989) (xy 139.581067 -403.54863) (xy 139.626918 -403.578096)
			(xy 139.668108 -403.613787) (xy 139.7038 -403.654978) (xy 139.733267 -403.700828) (xy 139.755909 -403.750406)
			(xy 139.771264 -403.802701) (xy 139.779021 -403.856649) (xy 139.779021 -403.911151) (xy 139.77902 -403.911156)
			(xy 141.216531 -403.911156) (xy 141.216531 -403.856644) (xy 141.224289 -403.802686) (xy 141.239648 -403.750383)
			(xy 141.262295 -403.700797) (xy 141.291768 -403.654939) (xy 141.327467 -403.613743) (xy 141.368667 -403.578047)
			(xy 141.414527 -403.548578) (xy 141.464114 -403.525936) (xy 141.51642 -403.510582) (xy 141.570378 -403.502829)
			(xy 141.597634 -403.502368) (xy 142.461234 -403.502368) (xy 142.488482 -403.502905) (xy 142.542423 -403.510664)
			(xy 142.59471 -403.526022) (xy 142.64428 -403.548663) (xy 142.690123 -403.578129) (xy 142.731306 -403.613818)
			(xy 142.766992 -403.655004) (xy 142.796453 -403.70085) (xy 142.81909 -403.750422) (xy 142.834443 -403.802711)
			(xy 142.842198 -403.856652) (xy 142.842198 -403.911148) (xy 142.842197 -403.911152) (xy 144.279854 -403.911152)
			(xy 144.279854 -403.856648) (xy 144.28761 -403.802699) (xy 144.302965 -403.750403) (xy 144.325606 -403.700825)
			(xy 144.355071 -403.654973) (xy 144.390762 -403.613781) (xy 144.431952 -403.578087) (xy 144.477802 -403.548618)
			(xy 144.527379 -403.525974) (xy 144.579674 -403.510616) (xy 144.633622 -403.502856) (xy 144.660874 -403.502368)
			(xy 145.524474 -403.502368) (xy 145.551726 -403.502878) (xy 145.605677 -403.510631) (xy 145.657974 -403.525984)
			(xy 145.707555 -403.548623) (xy 145.753408 -403.578089) (xy 145.794601 -403.61378) (xy 145.830296 -403.654971)
			(xy 145.859764 -403.700822) (xy 145.882407 -403.750401) (xy 145.897763 -403.802698) (xy 145.905521 -403.856648)
			(xy 145.905521 -403.911152) (xy 145.905521 -403.911155) (xy 147.343031 -403.911155) (xy 147.343031 -403.856645)
			(xy 147.350789 -403.802689) (xy 147.366146 -403.750387) (xy 147.388791 -403.700803) (xy 147.418263 -403.654946)
			(xy 147.45396 -403.61375) (xy 147.495157 -403.578054) (xy 147.541015 -403.548585) (xy 147.5906 -403.525942)
			(xy 147.642903 -403.510586) (xy 147.696859 -403.50283) (xy 147.724114 -403.502368) (xy 148.587714 -403.502368)
			(xy 148.614963 -403.502903) (xy 148.668906 -403.510661) (xy 148.721195 -403.526016) (xy 148.770768 -403.548657)
			(xy 148.816613 -403.578121) (xy 148.857799 -403.613811) (xy 148.893487 -403.654998) (xy 148.92295 -403.700845)
			(xy 148.945589 -403.750418) (xy 148.960942 -403.802708) (xy 148.968698 -403.856651) (xy 148.968698 -403.911149)
			(xy 148.968698 -403.911151) (xy 150.406354 -403.911151) (xy 150.406354 -403.856649) (xy 150.41411 -403.802702)
			(xy 150.429463 -403.750408) (xy 150.452102 -403.70083) (xy 150.481566 -403.654979) (xy 150.517255 -403.613788)
			(xy 150.558442 -403.578094) (xy 150.60429 -403.548625) (xy 150.653865 -403.525979) (xy 150.706157 -403.510619)
			(xy 150.760103 -403.502857) (xy 150.787354 -403.502368) (xy 151.650954 -403.502368) (xy 151.678207 -403.502876)
			(xy 151.73216 -403.510627) (xy 151.78446 -403.525978) (xy 151.834043 -403.548617) (xy 151.879899 -403.578082)
			(xy 151.921094 -403.613773) (xy 151.956791 -403.654964) (xy 151.986261 -403.700817) (xy 152.008906 -403.750397)
			(xy 152.024263 -403.802695) (xy 152.032021 -403.856647) (xy 152.032021 -403.911153) (xy 153.469554 -403.911153)
			(xy 153.469554 -403.856647) (xy 153.477311 -403.802697) (xy 153.492666 -403.750399) (xy 153.515309 -403.700819)
			(xy 153.544776 -403.654966) (xy 153.580469 -403.613774) (xy 153.621661 -403.57808) (xy 153.667514 -403.548611)
			(xy 153.717094 -403.525969) (xy 153.769391 -403.510612) (xy 153.823341 -403.502854) (xy 153.850594 -403.502368)
			(xy 154.714194 -403.502368) (xy 154.741445 -403.502879) (xy 154.795394 -403.510635) (xy 154.847689 -403.525989)
			(xy 154.897267 -403.54863) (xy 154.943118 -403.578096) (xy 154.984308 -403.613787) (xy 155.02 -403.654978)
			(xy 155.049467 -403.700828) (xy 155.072109 -403.750406) (xy 155.087464 -403.802701) (xy 155.095221 -403.856649)
			(xy 155.095221 -403.911151) (xy 155.09522 -403.911156) (xy 156.532731 -403.911156) (xy 156.532731 -403.856644)
			(xy 156.540489 -403.802686) (xy 156.555848 -403.750383) (xy 156.578495 -403.700797) (xy 156.607968 -403.654939)
			(xy 156.643667 -403.613743) (xy 156.684867 -403.578047) (xy 156.730727 -403.548578) (xy 156.780314 -403.525936)
			(xy 156.83262 -403.510582) (xy 156.886578 -403.502829) (xy 156.913834 -403.502368) (xy 157.777434 -403.502368)
			(xy 157.804682 -403.502905) (xy 157.858623 -403.510664) (xy 157.91091 -403.526022) (xy 157.96048 -403.548663)
			(xy 158.006323 -403.578129) (xy 158.047506 -403.613818) (xy 158.083192 -403.655004) (xy 158.112653 -403.70085)
			(xy 158.13529 -403.750422) (xy 158.150643 -403.802711) (xy 158.158398 -403.856652) (xy 158.158398 -403.911148)
			(xy 158.158397 -403.911152) (xy 159.596054 -403.911152) (xy 159.596054 -403.856648) (xy 159.60381 -403.802699)
			(xy 159.619165 -403.750403) (xy 159.641806 -403.700825) (xy 159.671271 -403.654973) (xy 159.706962 -403.613781)
			(xy 159.748152 -403.578087) (xy 159.794002 -403.548618) (xy 159.843579 -403.525974) (xy 159.895874 -403.510616)
			(xy 159.949822 -403.502856) (xy 159.977074 -403.502368) (xy 160.840674 -403.502368) (xy 160.867926 -403.502878)
			(xy 160.921877 -403.510631) (xy 160.974174 -403.525984) (xy 161.023755 -403.548623) (xy 161.069608 -403.578089)
			(xy 161.110801 -403.61378) (xy 161.146496 -403.654971) (xy 161.175964 -403.700822) (xy 161.198607 -403.750401)
			(xy 161.213963 -403.802698) (xy 161.221721 -403.856648) (xy 161.221721 -403.911152) (xy 161.221721 -403.911155)
			(xy 162.659231 -403.911155) (xy 162.659231 -403.856645) (xy 162.666989 -403.802689) (xy 162.682346 -403.750387)
			(xy 162.704991 -403.700803) (xy 162.734463 -403.654946) (xy 162.77016 -403.61375) (xy 162.811357 -403.578054)
			(xy 162.857215 -403.548585) (xy 162.9068 -403.525942) (xy 162.959103 -403.510586) (xy 163.013059 -403.50283)
			(xy 163.040314 -403.502368) (xy 163.903914 -403.502368) (xy 163.931163 -403.502903) (xy 163.985106 -403.510661)
			(xy 164.037395 -403.526016) (xy 164.086968 -403.548657) (xy 164.132813 -403.578121) (xy 164.173999 -403.613811)
			(xy 164.209687 -403.654998) (xy 164.23915 -403.700845) (xy 164.261789 -403.750418) (xy 164.277142 -403.802708)
			(xy 164.284898 -403.856651) (xy 164.284898 -403.911149) (xy 164.284898 -403.911151) (xy 165.722554 -403.911151)
			(xy 165.722554 -403.856649) (xy 165.73031 -403.802702) (xy 165.745663 -403.750408) (xy 165.768302 -403.70083)
			(xy 165.797766 -403.654979) (xy 165.833455 -403.613788) (xy 165.874642 -403.578094) (xy 165.92049 -403.548625)
			(xy 165.970065 -403.525979) (xy 166.022357 -403.510619) (xy 166.076303 -403.502857) (xy 166.103554 -403.502368)
			(xy 166.967154 -403.502368) (xy 166.994407 -403.502876) (xy 167.04836 -403.510627) (xy 167.10066 -403.525978)
			(xy 167.150243 -403.548617) (xy 167.196099 -403.578082) (xy 167.237294 -403.613773) (xy 167.272991 -403.654964)
			(xy 167.302461 -403.700817) (xy 167.325106 -403.750397) (xy 167.340463 -403.802695) (xy 167.348221 -403.856647)
			(xy 167.348221 -403.911153) (xy 167.340463 -403.965105) (xy 167.325106 -404.017403) (xy 167.31136 -404.0475)
			(xy 287.066441 -404.0475) (xy 287.070455 -403.983698) (xy 287.082434 -403.920902) (xy 287.102189 -403.860103)
			(xy 287.129408 -403.80226) (xy 287.163662 -403.748283) (xy 287.204411 -403.699026) (xy 287.251013 -403.655264)
			(xy 287.302731 -403.617688) (xy 287.358752 -403.58689) (xy 287.418191 -403.563357) (xy 287.48011 -403.547458)
			(xy 287.543534 -403.539446) (xy 287.575498 -403.538944) (xy 287.575752 -403.538944) (xy 287.607498 -403.539464)
			(xy 287.670494 -403.547393) (xy 287.732014 -403.563096) (xy 287.791102 -403.58633) (xy 287.846842 -403.616733)
			(xy 287.898367 -403.653834) (xy 287.921954 -403.675088) (xy 287.929217 -403.681272) (xy 287.946967 -403.688223)
			(xy 287.966029 -403.688223) (xy 287.983779 -403.681272) (xy 287.991042 -403.675088) (xy 288.014631 -403.653832)
			(xy 288.06614 -403.6167) (xy 288.121874 -403.586276) (xy 288.180965 -403.563035) (xy 288.242492 -403.547338)
			(xy 288.305495 -403.539431) (xy 288.337244 -403.538944) (xy 288.337498 -403.538944) (xy 288.369457 -403.539521)
			(xy 288.432872 -403.547532) (xy 288.494783 -403.563427) (xy 288.554213 -403.586957) (xy 288.610226 -403.61775)
			(xy 288.661937 -403.655321) (xy 288.708532 -403.699076) (xy 288.749276 -403.748326) (xy 288.783525 -403.802295)
			(xy 288.810741 -403.86013) (xy 288.830493 -403.920921) (xy 288.84247 -403.983707) (xy 288.846484 -404.0475)
			(xy 289.606441 -404.0475) (xy 289.610455 -403.983698) (xy 289.622434 -403.920902) (xy 289.642189 -403.860103)
			(xy 289.669408 -403.80226) (xy 289.703662 -403.748283) (xy 289.744411 -403.699026) (xy 289.791013 -403.655264)
			(xy 289.842731 -403.617688) (xy 289.898752 -403.58689) (xy 289.958191 -403.563357) (xy 290.02011 -403.547458)
			(xy 290.083534 -403.539446) (xy 290.115498 -403.538944) (xy 290.115752 -403.538944) (xy 290.147498 -403.539464)
			(xy 290.210494 -403.547393) (xy 290.272014 -403.563096) (xy 290.331102 -403.58633) (xy 290.386842 -403.616733)
			(xy 290.438367 -403.653834) (xy 290.461954 -403.675088) (xy 290.469217 -403.681272) (xy 290.486967 -403.688223)
			(xy 290.506029 -403.688223) (xy 290.523779 -403.681272) (xy 290.531042 -403.675088) (xy 290.554631 -403.653832)
			(xy 290.60614 -403.6167) (xy 290.661874 -403.586276) (xy 290.720965 -403.563035) (xy 290.782492 -403.547338)
			(xy 290.845495 -403.539431) (xy 290.877244 -403.538944) (xy 290.877498 -403.538944) (xy 290.909457 -403.539521)
			(xy 290.972872 -403.547532) (xy 291.034783 -403.563427) (xy 291.094213 -403.586957) (xy 291.150226 -403.61775)
			(xy 291.201937 -403.655321) (xy 291.248532 -403.699076) (xy 291.289276 -403.748326) (xy 291.323525 -403.802295)
			(xy 291.350741 -403.86013) (xy 291.370493 -403.920921) (xy 291.38247 -403.983707) (xy 291.386484 -404.0475)
			(xy 292.146441 -404.0475) (xy 292.150455 -403.983698) (xy 292.162434 -403.920902) (xy 292.182189 -403.860103)
			(xy 292.209408 -403.80226) (xy 292.243662 -403.748283) (xy 292.284411 -403.699026) (xy 292.331013 -403.655264)
			(xy 292.382731 -403.617688) (xy 292.438752 -403.58689) (xy 292.498191 -403.563357) (xy 292.56011 -403.547458)
			(xy 292.623534 -403.539446) (xy 292.655498 -403.538944) (xy 292.655752 -403.538944) (xy 292.687498 -403.539464)
			(xy 292.750494 -403.547393) (xy 292.812014 -403.563096) (xy 292.871102 -403.58633) (xy 292.926842 -403.616733)
			(xy 292.978367 -403.653834) (xy 293.001954 -403.675088) (xy 293.009217 -403.681272) (xy 293.026967 -403.688223)
			(xy 293.046029 -403.688223) (xy 293.063779 -403.681272) (xy 293.071042 -403.675088) (xy 293.094631 -403.653832)
			(xy 293.14614 -403.6167) (xy 293.201874 -403.586276) (xy 293.260965 -403.563035) (xy 293.322492 -403.547338)
			(xy 293.385495 -403.539431) (xy 293.417244 -403.538944) (xy 293.417498 -403.538944) (xy 293.449457 -403.539521)
			(xy 293.512872 -403.547532) (xy 293.574783 -403.563427) (xy 293.634213 -403.586957) (xy 293.690226 -403.61775)
			(xy 293.741937 -403.655321) (xy 293.788532 -403.699076) (xy 293.829276 -403.748326) (xy 293.863525 -403.802295)
			(xy 293.890741 -403.86013) (xy 293.910493 -403.920921) (xy 293.92247 -403.983707) (xy 293.926484 -404.0475)
			(xy 294.53602 -404.0475) (xy 294.540035 -403.983693) (xy 294.552015 -403.920892) (xy 294.571773 -403.860089)
			(xy 294.598995 -403.802241) (xy 294.633253 -403.748261) (xy 294.674007 -403.699001) (xy 294.720613 -403.655237)
			(xy 294.772338 -403.61766) (xy 294.828364 -403.586862) (xy 294.887809 -403.563329) (xy 294.949734 -403.547433)
			(xy 295.013163 -403.539423) (xy 295.04513 -403.538944) (xy 295.045384 -403.538944) (xy 295.077131 -403.539444)
			(xy 295.140127 -403.547377) (xy 295.201647 -403.563084) (xy 295.260736 -403.586322) (xy 295.316476 -403.616728)
			(xy 295.368 -403.653832) (xy 295.391586 -403.675088) (xy 295.398849 -403.681272) (xy 295.416599 -403.688223)
			(xy 295.435661 -403.688223) (xy 295.453411 -403.681272) (xy 295.460674 -403.675088) (xy 295.48425 -403.653817)
			(xy 295.535761 -403.616686) (xy 295.591498 -403.586265) (xy 295.650592 -403.563026) (xy 295.712121 -403.547332)
			(xy 295.775126 -403.539429) (xy 295.806876 -403.538944) (xy 295.80713 -403.538944) (xy 295.839087 -403.539544)
			(xy 295.902496 -403.547558) (xy 295.964401 -403.563455) (xy 296.023825 -403.586986) (xy 296.079832 -403.617779)
			(xy 296.131538 -403.655348) (xy 296.178128 -403.699102) (xy 296.218866 -403.748349) (xy 296.253112 -403.802314)
			(xy 296.280324 -403.860145) (xy 296.300074 -403.920931) (xy 296.312049 -403.983712) (xy 296.316063 -404.0475)
			(xy 297.07602 -404.0475) (xy 297.080035 -403.983693) (xy 297.092015 -403.920892) (xy 297.111773 -403.860089)
			(xy 297.138995 -403.802241) (xy 297.173253 -403.748261) (xy 297.214007 -403.699001) (xy 297.260613 -403.655237)
			(xy 297.312338 -403.61766) (xy 297.368364 -403.586862) (xy 297.427809 -403.563329) (xy 297.489734 -403.547433)
			(xy 297.553163 -403.539423) (xy 297.58513 -403.538944) (xy 297.585384 -403.538944) (xy 297.617131 -403.539444)
			(xy 297.680127 -403.547377) (xy 297.741647 -403.563084) (xy 297.800736 -403.586322) (xy 297.856476 -403.616728)
			(xy 297.908 -403.653832) (xy 297.931586 -403.675088) (xy 297.938849 -403.681272) (xy 297.956599 -403.688223)
			(xy 297.975661 -403.688223) (xy 297.993411 -403.681272) (xy 298.000674 -403.675088) (xy 298.02425 -403.653817)
			(xy 298.075761 -403.616686) (xy 298.131498 -403.586265) (xy 298.190592 -403.563026) (xy 298.252121 -403.547332)
			(xy 298.315126 -403.539429) (xy 298.346876 -403.538944) (xy 298.34713 -403.538944) (xy 298.379087 -403.539544)
			(xy 298.442496 -403.547558) (xy 298.504401 -403.563455) (xy 298.563825 -403.586986) (xy 298.619832 -403.617779)
			(xy 298.671538 -403.655348) (xy 298.718128 -403.699102) (xy 298.758866 -403.748349) (xy 298.793112 -403.802314)
			(xy 298.820324 -403.860145) (xy 298.836897 -403.911152) (xy 303.599054 -403.911152) (xy 303.599054 -403.856648)
			(xy 303.60681 -403.802698) (xy 303.622166 -403.7504) (xy 303.644808 -403.700821) (xy 303.674275 -403.654968)
			(xy 303.709967 -403.613776) (xy 303.751159 -403.578082) (xy 303.79701 -403.548613) (xy 303.846589 -403.52597)
			(xy 303.898886 -403.510613) (xy 303.952836 -403.502855) (xy 303.980088 -403.502368) (xy 304.843688 -403.502368)
			(xy 304.87094 -403.502878) (xy 304.924889 -403.510634) (xy 304.977185 -403.525988) (xy 305.026763 -403.548628)
			(xy 305.072615 -403.578094) (xy 305.113806 -403.613785) (xy 305.149499 -403.654976) (xy 305.178966 -403.700826)
			(xy 305.201608 -403.750404) (xy 305.216964 -403.8027) (xy 305.224721 -403.856648) (xy 305.224721 -403.911152)
			(xy 305.22472 -403.911156) (xy 306.662231 -403.911156) (xy 306.662231 -403.856644) (xy 306.669989 -403.802687)
			(xy 306.685348 -403.750384) (xy 306.707994 -403.700799) (xy 306.737466 -403.654941) (xy 306.773165 -403.613745)
			(xy 306.814364 -403.578049) (xy 306.860223 -403.54858) (xy 306.90981 -403.525938) (xy 306.962115 -403.510583)
			(xy 307.016072 -403.502829) (xy 307.043328 -403.502368) (xy 307.906928 -403.502368) (xy 307.934176 -403.502904)
			(xy 307.988117 -403.510663) (xy 308.040405 -403.52602) (xy 308.089976 -403.548661) (xy 308.13582 -403.578126)
			(xy 308.177004 -403.613816) (xy 308.21269 -403.655002) (xy 308.242152 -403.700849) (xy 308.26479 -403.750421)
			(xy 308.280143 -403.80271) (xy 308.287898 -403.856652) (xy 308.287898 -403.911148) (xy 308.287897 -403.911152)
			(xy 309.725554 -403.911152) (xy 309.725554 -403.856648) (xy 309.73331 -403.8027) (xy 309.748664 -403.750405)
			(xy 309.771305 -403.700826) (xy 309.80077 -403.654975) (xy 309.83646 -403.613783) (xy 309.877649 -403.578089)
			(xy 309.923498 -403.54862) (xy 309.973075 -403.525976) (xy 310.025369 -403.510617) (xy 310.079317 -403.502856)
			(xy 310.106568 -403.502368) (xy 310.970168 -403.502368) (xy 310.997421 -403.502877) (xy 311.051372 -403.51063)
			(xy 311.10367 -403.525982) (xy 311.153251 -403.548621) (xy 311.199105 -403.578087) (xy 311.240299 -403.613778)
			(xy 311.275994 -403.654969) (xy 311.305463 -403.700821) (xy 311.328107 -403.7504) (xy 311.343463 -403.802697)
			(xy 311.351221 -403.856647) (xy 311.351221 -403.911153) (xy 311.351221 -403.911155) (xy 312.788731 -403.911155)
			(xy 312.788731 -403.856645) (xy 312.796489 -403.80269) (xy 312.811846 -403.750388) (xy 312.834491 -403.700804)
			(xy 312.863961 -403.654948) (xy 312.899658 -403.613752) (xy 312.940854 -403.578056) (xy 312.986711 -403.548587)
			(xy 313.036296 -403.525943) (xy 313.088598 -403.510587) (xy 313.142553 -403.50283) (xy 313.169808 -403.502368)
			(xy 314.033408 -403.502368) (xy 314.060657 -403.502903) (xy 314.114601 -403.51066) (xy 314.166891 -403.526015)
			(xy 314.216464 -403.548655) (xy 314.26231 -403.578119) (xy 314.303497 -403.613809) (xy 314.339186 -403.654996)
			(xy 314.368649 -403.700843) (xy 314.391288 -403.750417) (xy 314.406642 -403.802707) (xy 314.414398 -403.856651)
			(xy 314.414398 -403.911149) (xy 314.414397 -403.911157) (xy 315.851931 -403.911157) (xy 315.851931 -403.856643)
			(xy 315.85969 -403.802685) (xy 315.875049 -403.75038) (xy 315.897697 -403.700793) (xy 315.927171 -403.654935)
			(xy 315.962872 -403.613738) (xy 316.004073 -403.578042) (xy 316.049935 -403.548574) (xy 316.099525 -403.525932)
			(xy 316.151832 -403.51058) (xy 316.205791 -403.502828) (xy 316.233048 -403.502368) (xy 317.096648 -403.502368)
			(xy 317.123895 -403.502905) (xy 317.177834 -403.510667) (xy 317.23012 -403.526025) (xy 317.279688 -403.548668)
			(xy 317.325529 -403.578133) (xy 317.366711 -403.613823) (xy 317.402395 -403.655009) (xy 317.431855 -403.700854)
			(xy 317.454491 -403.750425) (xy 317.469843 -403.802713) (xy 317.477598 -403.856653) (xy 317.477598 -403.911147)
			(xy 317.477597 -403.911152) (xy 318.915254 -403.911152) (xy 318.915254 -403.856648) (xy 318.92301 -403.802698)
			(xy 318.938366 -403.7504) (xy 318.961008 -403.700821) (xy 318.990475 -403.654968) (xy 319.026167 -403.613776)
			(xy 319.067359 -403.578082) (xy 319.11321 -403.548613) (xy 319.162789 -403.52597) (xy 319.215086 -403.510613)
			(xy 319.269036 -403.502855) (xy 319.296288 -403.502368) (xy 320.159888 -403.502368) (xy 320.18714 -403.502878)
			(xy 320.241089 -403.510634) (xy 320.293385 -403.525988) (xy 320.342963 -403.548628) (xy 320.388815 -403.578094)
			(xy 320.430006 -403.613785) (xy 320.465699 -403.654976) (xy 320.495166 -403.700826) (xy 320.517808 -403.750404)
			(xy 320.533164 -403.8027) (xy 320.540921 -403.856648) (xy 320.540921 -403.911152) (xy 320.54092 -403.911156)
			(xy 321.978431 -403.911156) (xy 321.978431 -403.856644) (xy 321.986189 -403.802687) (xy 322.001548 -403.750384)
			(xy 322.024194 -403.700799) (xy 322.053666 -403.654941) (xy 322.089365 -403.613745) (xy 322.130564 -403.578049)
			(xy 322.176423 -403.54858) (xy 322.22601 -403.525938) (xy 322.278315 -403.510583) (xy 322.332272 -403.502829)
			(xy 322.359528 -403.502368) (xy 323.223128 -403.502368) (xy 323.250376 -403.502904) (xy 323.304317 -403.510663)
			(xy 323.356605 -403.52602) (xy 323.406176 -403.548661) (xy 323.45202 -403.578126) (xy 323.493204 -403.613816)
			(xy 323.52889 -403.655002) (xy 323.558352 -403.700849) (xy 323.58099 -403.750421) (xy 323.596343 -403.80271)
			(xy 323.604098 -403.856652) (xy 323.604098 -403.911148) (xy 323.604097 -403.911152) (xy 325.041754 -403.911152)
			(xy 325.041754 -403.856648) (xy 325.04951 -403.8027) (xy 325.064864 -403.750405) (xy 325.087505 -403.700826)
			(xy 325.11697 -403.654975) (xy 325.15266 -403.613783) (xy 325.193849 -403.578089) (xy 325.239698 -403.54862)
			(xy 325.289275 -403.525976) (xy 325.341569 -403.510617) (xy 325.395517 -403.502856) (xy 325.422768 -403.502368)
			(xy 326.286368 -403.502368) (xy 326.313621 -403.502877) (xy 326.367572 -403.51063) (xy 326.41987 -403.525982)
			(xy 326.469451 -403.548621) (xy 326.515305 -403.578087) (xy 326.556499 -403.613778) (xy 326.592194 -403.654969)
			(xy 326.621663 -403.700821) (xy 326.644307 -403.7504) (xy 326.659663 -403.802697) (xy 326.667421 -403.856647)
			(xy 326.667421 -403.911153) (xy 326.667421 -403.911155) (xy 328.104931 -403.911155) (xy 328.104931 -403.856645)
			(xy 328.112689 -403.80269) (xy 328.128046 -403.750388) (xy 328.150691 -403.700804) (xy 328.180161 -403.654948)
			(xy 328.215858 -403.613752) (xy 328.257054 -403.578056) (xy 328.302911 -403.548587) (xy 328.352496 -403.525943)
			(xy 328.404798 -403.510587) (xy 328.458753 -403.50283) (xy 328.486008 -403.502368) (xy 329.349608 -403.502368)
			(xy 329.376857 -403.502903) (xy 329.430801 -403.51066) (xy 329.483091 -403.526015) (xy 329.532664 -403.548655)
			(xy 329.57851 -403.578119) (xy 329.619697 -403.613809) (xy 329.655386 -403.654996) (xy 329.684849 -403.700843)
			(xy 329.707488 -403.750417) (xy 329.722842 -403.802707) (xy 329.730598 -403.856651) (xy 329.730598 -403.911149)
			(xy 329.730597 -403.911157) (xy 331.168131 -403.911157) (xy 331.168131 -403.856643) (xy 331.17589 -403.802685)
			(xy 331.191249 -403.75038) (xy 331.213897 -403.700793) (xy 331.243371 -403.654935) (xy 331.279072 -403.613738)
			(xy 331.320273 -403.578042) (xy 331.366135 -403.548574) (xy 331.415725 -403.525932) (xy 331.468032 -403.51058)
			(xy 331.521991 -403.502828) (xy 331.549248 -403.502368) (xy 332.412848 -403.502368) (xy 332.440095 -403.502905)
			(xy 332.494034 -403.510667) (xy 332.54632 -403.526025) (xy 332.595888 -403.548668) (xy 332.641729 -403.578133)
			(xy 332.682911 -403.613823) (xy 332.718595 -403.655009) (xy 332.748055 -403.700854) (xy 332.770691 -403.750425)
			(xy 332.786043 -403.802713) (xy 332.793798 -403.856653) (xy 332.793798 -403.911147) (xy 332.793797 -403.911152)
			(xy 334.231454 -403.911152) (xy 334.231454 -403.856648) (xy 334.23921 -403.802698) (xy 334.254566 -403.7504)
			(xy 334.277208 -403.700821) (xy 334.306675 -403.654968) (xy 334.342367 -403.613776) (xy 334.383559 -403.578082)
			(xy 334.42941 -403.548613) (xy 334.478989 -403.52597) (xy 334.531286 -403.510613) (xy 334.585236 -403.502855)
			(xy 334.612488 -403.502368) (xy 335.476088 -403.502368) (xy 335.50334 -403.502878) (xy 335.557289 -403.510634)
			(xy 335.609585 -403.525988) (xy 335.659163 -403.548628) (xy 335.705015 -403.578094) (xy 335.746206 -403.613785)
			(xy 335.781899 -403.654976) (xy 335.811366 -403.700826) (xy 335.834008 -403.750404) (xy 335.849364 -403.8027)
			(xy 335.857121 -403.856648) (xy 335.857121 -403.911152) (xy 335.85712 -403.911156) (xy 337.294631 -403.911156)
			(xy 337.294631 -403.856644) (xy 337.302389 -403.802687) (xy 337.317748 -403.750384) (xy 337.340394 -403.700799)
			(xy 337.369866 -403.654941) (xy 337.405565 -403.613745) (xy 337.446764 -403.578049) (xy 337.492623 -403.54858)
			(xy 337.54221 -403.525938) (xy 337.594515 -403.510583) (xy 337.648472 -403.502829) (xy 337.675728 -403.502368)
			(xy 338.539328 -403.502368) (xy 338.566576 -403.502904) (xy 338.620517 -403.510663) (xy 338.672805 -403.52602)
			(xy 338.722376 -403.548661) (xy 338.76822 -403.578126) (xy 338.809404 -403.613816) (xy 338.84509 -403.655002)
			(xy 338.874552 -403.700849) (xy 338.89719 -403.750421) (xy 338.912543 -403.80271) (xy 338.920298 -403.856652)
			(xy 338.920298 -403.911148) (xy 338.920297 -403.911152) (xy 340.357954 -403.911152) (xy 340.357954 -403.856648)
			(xy 340.36571 -403.8027) (xy 340.381064 -403.750405) (xy 340.403705 -403.700826) (xy 340.43317 -403.654975)
			(xy 340.46886 -403.613783) (xy 340.510049 -403.578089) (xy 340.555898 -403.54862) (xy 340.605475 -403.525976)
			(xy 340.657769 -403.510617) (xy 340.711717 -403.502856) (xy 340.738968 -403.502368) (xy 341.602568 -403.502368)
			(xy 341.629821 -403.502877) (xy 341.683772 -403.51063) (xy 341.73607 -403.525982) (xy 341.785651 -403.548621)
			(xy 341.831505 -403.578087) (xy 341.872699 -403.613778) (xy 341.908394 -403.654969) (xy 341.937863 -403.700821)
			(xy 341.960507 -403.7504) (xy 341.975863 -403.802697) (xy 341.983621 -403.856647) (xy 341.983621 -403.911153)
			(xy 341.983621 -403.911155) (xy 343.421131 -403.911155) (xy 343.421131 -403.856645) (xy 343.428889 -403.80269)
			(xy 343.444246 -403.750388) (xy 343.466891 -403.700804) (xy 343.496361 -403.654948) (xy 343.532058 -403.613752)
			(xy 343.573254 -403.578056) (xy 343.619111 -403.548587) (xy 343.668696 -403.525943) (xy 343.720998 -403.510587)
			(xy 343.774953 -403.50283) (xy 343.802208 -403.502368) (xy 344.665808 -403.502368) (xy 344.693057 -403.502903)
			(xy 344.747001 -403.51066) (xy 344.799291 -403.526015) (xy 344.848864 -403.548655) (xy 344.89471 -403.578119)
			(xy 344.935897 -403.613809) (xy 344.971586 -403.654996) (xy 345.001049 -403.700843) (xy 345.023688 -403.750417)
			(xy 345.039042 -403.802707) (xy 345.046798 -403.856651) (xy 345.046798 -403.911149) (xy 345.046797 -403.911157)
			(xy 346.484331 -403.911157) (xy 346.484331 -403.856643) (xy 346.49209 -403.802685) (xy 346.507449 -403.75038)
			(xy 346.530097 -403.700793) (xy 346.559571 -403.654935) (xy 346.595272 -403.613738) (xy 346.636473 -403.578042)
			(xy 346.682335 -403.548574) (xy 346.731925 -403.525932) (xy 346.784232 -403.51058) (xy 346.838191 -403.502828)
			(xy 346.865448 -403.502368) (xy 347.729048 -403.502368) (xy 347.756295 -403.502905) (xy 347.810234 -403.510667)
			(xy 347.86252 -403.526025) (xy 347.912088 -403.548668) (xy 347.957929 -403.578133) (xy 347.999111 -403.613823)
			(xy 348.034795 -403.655009) (xy 348.064255 -403.700854) (xy 348.086891 -403.750425) (xy 348.102243 -403.802713)
			(xy 348.109998 -403.856653) (xy 348.109998 -403.911147) (xy 348.109997 -403.911152) (xy 349.547654 -403.911152)
			(xy 349.547654 -403.856648) (xy 349.55541 -403.802698) (xy 349.570766 -403.7504) (xy 349.593408 -403.700821)
			(xy 349.622875 -403.654968) (xy 349.658567 -403.613776) (xy 349.699759 -403.578082) (xy 349.74561 -403.548613)
			(xy 349.795189 -403.52597) (xy 349.847486 -403.510613) (xy 349.901436 -403.502855) (xy 349.928688 -403.502368)
			(xy 350.792288 -403.502368) (xy 350.81954 -403.502878) (xy 350.873489 -403.510634) (xy 350.925785 -403.525988)
			(xy 350.975363 -403.548628) (xy 351.021215 -403.578094) (xy 351.062406 -403.613785) (xy 351.098099 -403.654976)
			(xy 351.127566 -403.700826) (xy 351.150208 -403.750404) (xy 351.165564 -403.8027) (xy 351.173321 -403.856648)
			(xy 351.173321 -403.911152) (xy 351.17332 -403.911156) (xy 371.041831 -403.911156) (xy 371.041831 -403.856644)
			(xy 371.049589 -403.802687) (xy 371.064948 -403.750383) (xy 371.087594 -403.700798) (xy 371.117067 -403.654941)
			(xy 371.152766 -403.613745) (xy 371.193965 -403.578049) (xy 371.239824 -403.54858) (xy 371.289412 -403.525937)
			(xy 371.341716 -403.510583) (xy 371.395674 -403.502829) (xy 371.42293 -403.502368) (xy 372.28653 -403.502368)
			(xy 372.313778 -403.502904) (xy 372.367719 -403.510664) (xy 372.420007 -403.52602) (xy 372.469577 -403.548662)
			(xy 372.515421 -403.578127) (xy 372.556605 -403.613816) (xy 372.592291 -403.655003) (xy 372.621753 -403.700849)
			(xy 372.64439 -403.750421) (xy 372.659743 -403.80271) (xy 372.667498 -403.856652) (xy 372.667498 -403.911148)
			(xy 372.667497 -403.911152) (xy 374.105154 -403.911152) (xy 374.105154 -403.856648) (xy 374.11291 -403.8027)
			(xy 374.128265 -403.750404) (xy 374.150905 -403.700826) (xy 374.18037 -403.654974) (xy 374.216061 -403.613782)
			(xy 374.25725 -403.578088) (xy 374.3031 -403.548619) (xy 374.352676 -403.525975) (xy 374.404971 -403.510616)
			(xy 374.458918 -403.502856) (xy 374.48617 -403.502368) (xy 375.34977 -403.502368) (xy 375.377023 -403.502877)
			(xy 375.430973 -403.51063) (xy 375.483271 -403.525983) (xy 375.532852 -403.548622) (xy 375.578706 -403.578087)
			(xy 375.6199 -403.613779) (xy 375.655595 -403.65497) (xy 375.685064 -403.700821) (xy 375.707707 -403.7504)
			(xy 375.723063 -403.802697) (xy 375.730821 -403.856647) (xy 375.730821 -403.911153) (xy 375.730821 -403.911155)
			(xy 377.168331 -403.911155) (xy 377.168331 -403.856645) (xy 377.176089 -403.80269) (xy 377.191446 -403.750388)
			(xy 377.214091 -403.700804) (xy 377.243562 -403.654947) (xy 377.279259 -403.613752) (xy 377.320455 -403.578056)
			(xy 377.366313 -403.548586) (xy 377.415897 -403.525943) (xy 377.468199 -403.510587) (xy 377.522155 -403.50283)
			(xy 377.54941 -403.502368) (xy 378.41301 -403.502368) (xy 378.440259 -403.502903) (xy 378.494202 -403.51066)
			(xy 378.546492 -403.526015) (xy 378.596065 -403.548655) (xy 378.641911 -403.57812) (xy 378.683098 -403.613809)
			(xy 378.718786 -403.654997) (xy 378.748249 -403.700844) (xy 378.770888 -403.750417) (xy 378.786242 -403.802708)
			(xy 378.793998 -403.856651) (xy 378.793998 -403.911149) (xy 378.793998 -403.911151) (xy 380.231654 -403.911151)
			(xy 380.231654 -403.856649) (xy 380.239409 -403.802703) (xy 380.254763 -403.750409) (xy 380.277402 -403.700832)
			(xy 380.306865 -403.654981) (xy 380.342554 -403.613789) (xy 380.383741 -403.578095) (xy 380.429588 -403.548626)
			(xy 380.479162 -403.52598) (xy 380.531454 -403.51062) (xy 380.585399 -403.502857) (xy 380.61265 -403.502368)
			(xy 381.47625 -403.502368) (xy 381.503503 -403.502876) (xy 381.557456 -403.510627) (xy 381.609757 -403.525977)
			(xy 381.65934 -403.548616) (xy 381.705197 -403.57808) (xy 381.746393 -403.613772) (xy 381.78209 -403.654963)
			(xy 381.81156 -403.700816) (xy 381.834205 -403.750396) (xy 381.849563 -403.802695) (xy 381.857321 -403.856647)
			(xy 381.857321 -403.911153) (xy 383.294854 -403.911153) (xy 383.294854 -403.856647) (xy 383.302611 -403.802697)
			(xy 383.317966 -403.7504) (xy 383.340608 -403.70082) (xy 383.370075 -403.654968) (xy 383.405768 -403.613775)
			(xy 383.44696 -403.578081) (xy 383.492812 -403.548613) (xy 383.542391 -403.52597) (xy 383.594687 -403.510613)
			(xy 383.648638 -403.502855) (xy 383.67589 -403.502368) (xy 384.53949 -403.502368) (xy 384.566742 -403.502879)
			(xy 384.62069 -403.510634) (xy 384.672986 -403.525988) (xy 384.722564 -403.548629) (xy 384.768416 -403.578095)
			(xy 384.809607 -403.613786) (xy 384.845299 -403.654976) (xy 384.874767 -403.700827) (xy 384.897408 -403.750405)
			(xy 384.912764 -403.8027) (xy 384.920521 -403.856648) (xy 384.920521 -403.911152) (xy 384.92052 -403.911156)
			(xy 386.358031 -403.911156) (xy 386.358031 -403.856644) (xy 386.365789 -403.802687) (xy 386.381148 -403.750383)
			(xy 386.403794 -403.700798) (xy 386.433267 -403.654941) (xy 386.468966 -403.613745) (xy 386.510165 -403.578049)
			(xy 386.556024 -403.54858) (xy 386.605612 -403.525937) (xy 386.657916 -403.510583) (xy 386.711874 -403.502829)
			(xy 386.73913 -403.502368) (xy 387.60273 -403.502368) (xy 387.629978 -403.502904) (xy 387.683919 -403.510664)
			(xy 387.736207 -403.52602) (xy 387.785777 -403.548662) (xy 387.831621 -403.578127) (xy 387.872805 -403.613816)
			(xy 387.908491 -403.655003) (xy 387.937953 -403.700849) (xy 387.96059 -403.750421) (xy 387.975943 -403.80271)
			(xy 387.983698 -403.856652) (xy 387.983698 -403.911148) (xy 387.983697 -403.911152) (xy 389.421354 -403.911152)
			(xy 389.421354 -403.856648) (xy 389.42911 -403.8027) (xy 389.444465 -403.750404) (xy 389.467105 -403.700826)
			(xy 389.49657 -403.654974) (xy 389.532261 -403.613782) (xy 389.57345 -403.578088) (xy 389.6193 -403.548619)
			(xy 389.668876 -403.525975) (xy 389.721171 -403.510616) (xy 389.775118 -403.502856) (xy 389.80237 -403.502368)
			(xy 390.66597 -403.502368) (xy 390.693223 -403.502877) (xy 390.747173 -403.51063) (xy 390.799471 -403.525983)
			(xy 390.849052 -403.548622) (xy 390.894906 -403.578087) (xy 390.9361 -403.613779) (xy 390.971795 -403.65497)
			(xy 391.001264 -403.700821) (xy 391.023907 -403.7504) (xy 391.039263 -403.802697) (xy 391.047021 -403.856647)
			(xy 391.047021 -403.911153) (xy 391.047021 -403.911155) (xy 392.484531 -403.911155) (xy 392.484531 -403.856645)
			(xy 392.492289 -403.80269) (xy 392.507646 -403.750388) (xy 392.530291 -403.700804) (xy 392.559762 -403.654947)
			(xy 392.595459 -403.613752) (xy 392.636655 -403.578056) (xy 392.682513 -403.548586) (xy 392.732097 -403.525943)
			(xy 392.784399 -403.510587) (xy 392.838355 -403.50283) (xy 392.86561 -403.502368) (xy 393.72921 -403.502368)
			(xy 393.756459 -403.502903) (xy 393.810402 -403.51066) (xy 393.862692 -403.526015) (xy 393.912265 -403.548655)
			(xy 393.958111 -403.57812) (xy 393.999298 -403.613809) (xy 394.034986 -403.654997) (xy 394.064449 -403.700844)
			(xy 394.087088 -403.750417) (xy 394.102442 -403.802708) (xy 394.110198 -403.856651) (xy 394.110198 -403.911149)
			(xy 394.110198 -403.911151) (xy 395.547854 -403.911151) (xy 395.547854 -403.856649) (xy 395.555609 -403.802703)
			(xy 395.570963 -403.750409) (xy 395.593602 -403.700832) (xy 395.623065 -403.654981) (xy 395.658754 -403.613789)
			(xy 395.699941 -403.578095) (xy 395.745788 -403.548626) (xy 395.795362 -403.52598) (xy 395.847654 -403.51062)
			(xy 395.901599 -403.502857) (xy 395.92885 -403.502368) (xy 396.79245 -403.502368) (xy 396.819703 -403.502876)
			(xy 396.873656 -403.510627) (xy 396.925957 -403.525977) (xy 396.97554 -403.548616) (xy 397.021397 -403.57808)
			(xy 397.062593 -403.613772) (xy 397.09829 -403.654963) (xy 397.12776 -403.700816) (xy 397.150405 -403.750396)
			(xy 397.165763 -403.802695) (xy 397.173521 -403.856647) (xy 397.173521 -403.911153) (xy 398.611054 -403.911153)
			(xy 398.611054 -403.856647) (xy 398.618811 -403.802697) (xy 398.634166 -403.7504) (xy 398.656808 -403.70082)
			(xy 398.686275 -403.654968) (xy 398.721968 -403.613775) (xy 398.76316 -403.578081) (xy 398.809012 -403.548613)
			(xy 398.858591 -403.52597) (xy 398.910887 -403.510613) (xy 398.964838 -403.502855) (xy 398.99209 -403.502368)
			(xy 399.85569 -403.502368) (xy 399.882942 -403.502879) (xy 399.93689 -403.510634) (xy 399.989186 -403.525988)
			(xy 400.038764 -403.548629) (xy 400.084616 -403.578095) (xy 400.125807 -403.613786) (xy 400.161499 -403.654976)
			(xy 400.190967 -403.700827) (xy 400.213608 -403.750405) (xy 400.228964 -403.8027) (xy 400.236721 -403.856648)
			(xy 400.236721 -403.911152) (xy 400.23672 -403.911156) (xy 401.674231 -403.911156) (xy 401.674231 -403.856644)
			(xy 401.681989 -403.802687) (xy 401.697348 -403.750383) (xy 401.719994 -403.700798) (xy 401.749467 -403.654941)
			(xy 401.785166 -403.613745) (xy 401.826365 -403.578049) (xy 401.872224 -403.54858) (xy 401.921812 -403.525937)
			(xy 401.974116 -403.510583) (xy 402.028074 -403.502829) (xy 402.05533 -403.502368) (xy 402.91893 -403.502368)
			(xy 402.946178 -403.502904) (xy 403.000119 -403.510664) (xy 403.052407 -403.52602) (xy 403.101977 -403.548662)
			(xy 403.147821 -403.578127) (xy 403.189005 -403.613816) (xy 403.224691 -403.655003) (xy 403.254153 -403.700849)
			(xy 403.27679 -403.750421) (xy 403.292143 -403.80271) (xy 403.299898 -403.856652) (xy 403.299898 -403.911148)
			(xy 403.299897 -403.911152) (xy 404.737554 -403.911152) (xy 404.737554 -403.856648) (xy 404.74531 -403.8027)
			(xy 404.760665 -403.750404) (xy 404.783305 -403.700826) (xy 404.81277 -403.654974) (xy 404.848461 -403.613782)
			(xy 404.88965 -403.578088) (xy 404.9355 -403.548619) (xy 404.985076 -403.525975) (xy 405.037371 -403.510616)
			(xy 405.091318 -403.502856) (xy 405.11857 -403.502368) (xy 405.98217 -403.502368) (xy 406.009423 -403.502877)
			(xy 406.063373 -403.51063) (xy 406.115671 -403.525983) (xy 406.165252 -403.548622) (xy 406.211106 -403.578087)
			(xy 406.2523 -403.613779) (xy 406.287995 -403.65497) (xy 406.317464 -403.700821) (xy 406.340107 -403.7504)
			(xy 406.355463 -403.802697) (xy 406.363221 -403.856647) (xy 406.363221 -403.911153) (xy 406.363221 -403.911155)
			(xy 407.800731 -403.911155) (xy 407.800731 -403.856645) (xy 407.808489 -403.80269) (xy 407.823846 -403.750388)
			(xy 407.846491 -403.700804) (xy 407.875962 -403.654947) (xy 407.911659 -403.613752) (xy 407.952855 -403.578056)
			(xy 407.998713 -403.548586) (xy 408.048297 -403.525943) (xy 408.100599 -403.510587) (xy 408.154555 -403.50283)
			(xy 408.18181 -403.502368) (xy 409.04541 -403.502368) (xy 409.072659 -403.502903) (xy 409.126602 -403.51066)
			(xy 409.178892 -403.526015) (xy 409.228465 -403.548655) (xy 409.274311 -403.57812) (xy 409.315498 -403.613809)
			(xy 409.351186 -403.654997) (xy 409.380649 -403.700844) (xy 409.403288 -403.750417) (xy 409.418642 -403.802708)
			(xy 409.426398 -403.856651) (xy 409.426398 -403.911149) (xy 409.426398 -403.911151) (xy 410.864054 -403.911151)
			(xy 410.864054 -403.856649) (xy 410.871809 -403.802703) (xy 410.887163 -403.750409) (xy 410.909802 -403.700832)
			(xy 410.939265 -403.654981) (xy 410.974954 -403.613789) (xy 411.016141 -403.578095) (xy 411.061988 -403.548626)
			(xy 411.111562 -403.52598) (xy 411.163854 -403.51062) (xy 411.217799 -403.502857) (xy 411.24505 -403.502368)
			(xy 412.10865 -403.502368) (xy 412.135903 -403.502876) (xy 412.189856 -403.510627) (xy 412.242157 -403.525977)
			(xy 412.29174 -403.548616) (xy 412.337597 -403.57808) (xy 412.378793 -403.613772) (xy 412.41449 -403.654963)
			(xy 412.44396 -403.700816) (xy 412.466605 -403.750396) (xy 412.481963 -403.802695) (xy 412.489721 -403.856647)
			(xy 412.489721 -403.911153) (xy 413.927254 -403.911153) (xy 413.927254 -403.856647) (xy 413.935011 -403.802697)
			(xy 413.950366 -403.7504) (xy 413.973008 -403.70082) (xy 414.002475 -403.654968) (xy 414.038168 -403.613775)
			(xy 414.07936 -403.578081) (xy 414.125212 -403.548613) (xy 414.174791 -403.52597) (xy 414.227087 -403.510613)
			(xy 414.281038 -403.502855) (xy 414.30829 -403.502368) (xy 415.17189 -403.502368) (xy 415.199142 -403.502879)
			(xy 415.25309 -403.510634) (xy 415.305386 -403.525988) (xy 415.354964 -403.548629) (xy 415.400816 -403.578095)
			(xy 415.442007 -403.613786) (xy 415.477699 -403.654976) (xy 415.507167 -403.700827) (xy 415.529808 -403.750405)
			(xy 415.545164 -403.8027) (xy 415.552921 -403.856648) (xy 415.552921 -403.911152) (xy 415.55292 -403.911156)
			(xy 416.990431 -403.911156) (xy 416.990431 -403.856644) (xy 416.998189 -403.802687) (xy 417.013548 -403.750383)
			(xy 417.036194 -403.700798) (xy 417.065667 -403.654941) (xy 417.101366 -403.613745) (xy 417.142565 -403.578049)
			(xy 417.188424 -403.54858) (xy 417.238012 -403.525937) (xy 417.290316 -403.510583) (xy 417.344274 -403.502829)
			(xy 417.37153 -403.502368) (xy 418.23513 -403.502368) (xy 418.262378 -403.502904) (xy 418.316319 -403.510664)
			(xy 418.368607 -403.52602) (xy 418.418177 -403.548662) (xy 418.464021 -403.578127) (xy 418.505205 -403.613816)
			(xy 418.540891 -403.655003) (xy 418.570353 -403.700849) (xy 418.59299 -403.750421) (xy 418.608343 -403.80271)
			(xy 418.616098 -403.856652) (xy 418.616098 -403.911148) (xy 418.608343 -403.96509) (xy 418.59299 -404.017379)
			(xy 418.570353 -404.066951) (xy 418.540891 -404.112797) (xy 418.505205 -404.153984) (xy 418.464021 -404.189673)
			(xy 418.418177 -404.219138) (xy 418.368607 -404.24178) (xy 418.316319 -404.257136) (xy 418.262378 -404.264896)
			(xy 418.23513 -404.265384) (xy 417.37153 -404.265384) (xy 417.344274 -404.264971) (xy 417.290316 -404.257217)
			(xy 417.238012 -404.241863) (xy 417.188424 -404.21922) (xy 417.142565 -404.189751) (xy 417.101366 -404.154055)
			(xy 417.065667 -404.112859) (xy 417.036194 -404.067002) (xy 417.013548 -404.017417) (xy 416.998189 -403.965113)
			(xy 416.990431 -403.911156) (xy 415.55292 -403.911156) (xy 415.545164 -403.9651) (xy 415.529808 -404.017395)
			(xy 415.507167 -404.066973) (xy 415.477699 -404.112824) (xy 415.442007 -404.154014) (xy 415.400816 -404.189705)
			(xy 415.354964 -404.219171) (xy 415.305386 -404.241812) (xy 415.25309 -404.257166) (xy 415.199142 -404.264921)
			(xy 415.17189 -404.265384) (xy 414.30829 -404.265384) (xy 414.281038 -404.264945) (xy 414.227087 -404.257187)
			(xy 414.174791 -404.24183) (xy 414.125212 -404.219187) (xy 414.07936 -404.189719) (xy 414.038168 -404.154025)
			(xy 414.002475 -404.112832) (xy 413.973008 -404.06698) (xy 413.950366 -404.0174) (xy 413.935011 -403.965103)
			(xy 413.927254 -403.911153) (xy 412.489721 -403.911153) (xy 412.481963 -403.965105) (xy 412.466605 -404.017404)
			(xy 412.44396 -404.066984) (xy 412.41449 -404.112837) (xy 412.378793 -404.154028) (xy 412.337597 -404.18972)
			(xy 412.29174 -404.219184) (xy 412.242157 -404.241823) (xy 412.189856 -404.257173) (xy 412.135903 -404.264924)
			(xy 412.10865 -404.265384) (xy 411.24505 -404.265384) (xy 411.217799 -404.264943) (xy 411.163854 -404.25718)
			(xy 411.111562 -404.24182) (xy 411.061988 -404.219174) (xy 411.016141 -404.189705) (xy 410.974954 -404.154011)
			(xy 410.939265 -404.112819) (xy 410.909802 -404.066968) (xy 410.887163 -404.017391) (xy 410.871809 -403.965097)
			(xy 410.864054 -403.911151) (xy 409.426398 -403.911151) (xy 409.418642 -403.965092) (xy 409.403288 -404.017383)
			(xy 409.380649 -404.066956) (xy 409.351186 -404.112803) (xy 409.315498 -404.153991) (xy 409.274311 -404.18968)
			(xy 409.228465 -404.219145) (xy 409.178892 -404.241785) (xy 409.126602 -404.25714) (xy 409.072659 -404.264897)
			(xy 409.04541 -404.265384) (xy 408.18181 -404.265384) (xy 408.154555 -404.26497) (xy 408.100599 -404.257213)
			(xy 408.048297 -404.241857) (xy 407.998713 -404.219214) (xy 407.952855 -404.189744) (xy 407.911659 -404.154048)
			(xy 407.875962 -404.112853) (xy 407.846491 -404.066996) (xy 407.823846 -404.017412) (xy 407.808489 -403.96511)
			(xy 407.800731 -403.911155) (xy 406.363221 -403.911155) (xy 406.355463 -403.965103) (xy 406.340107 -404.0174)
			(xy 406.317464 -404.066979) (xy 406.287995 -404.11283) (xy 406.2523 -404.154021) (xy 406.211106 -404.189713)
			(xy 406.165252 -404.219178) (xy 406.115671 -404.241817) (xy 406.063373 -404.25717) (xy 406.009423 -404.264923)
			(xy 405.98217 -404.265384) (xy 405.11857 -404.265384) (xy 405.091318 -404.264944) (xy 405.037371 -404.257184)
			(xy 404.985076 -404.241825) (xy 404.9355 -404.219181) (xy 404.88965 -404.189712) (xy 404.848461 -404.154018)
			(xy 404.81277 -404.112826) (xy 404.783305 -404.066974) (xy 404.760665 -404.017396) (xy 404.74531 -403.9651)
			(xy 404.737554 -403.911152) (xy 403.299897 -403.911152) (xy 403.292143 -403.96509) (xy 403.27679 -404.017379)
			(xy 403.254153 -404.066951) (xy 403.224691 -404.112797) (xy 403.189005 -404.153984) (xy 403.147821 -404.189673)
			(xy 403.101977 -404.219138) (xy 403.052407 -404.24178) (xy 403.000119 -404.257136) (xy 402.946178 -404.264896)
			(xy 402.91893 -404.265384) (xy 402.05533 -404.265384) (xy 402.028074 -404.264971) (xy 401.974116 -404.257217)
			(xy 401.921812 -404.241863) (xy 401.872224 -404.21922) (xy 401.826365 -404.189751) (xy 401.785166 -404.154055)
			(xy 401.749467 -404.112859) (xy 401.719994 -404.067002) (xy 401.697348 -404.017417) (xy 401.681989 -403.965113)
			(xy 401.674231 -403.911156) (xy 400.23672 -403.911156) (xy 400.228964 -403.9651) (xy 400.213608 -404.017395)
			(xy 400.190967 -404.066973) (xy 400.161499 -404.112824) (xy 400.125807 -404.154014) (xy 400.084616 -404.189705)
			(xy 400.038764 -404.219171) (xy 399.989186 -404.241812) (xy 399.93689 -404.257166) (xy 399.882942 -404.264921)
			(xy 399.85569 -404.265384) (xy 398.99209 -404.265384) (xy 398.964838 -404.264945) (xy 398.910887 -404.257187)
			(xy 398.858591 -404.24183) (xy 398.809012 -404.219187) (xy 398.76316 -404.189719) (xy 398.721968 -404.154025)
			(xy 398.686275 -404.112832) (xy 398.656808 -404.06698) (xy 398.634166 -404.0174) (xy 398.618811 -403.965103)
			(xy 398.611054 -403.911153) (xy 397.173521 -403.911153) (xy 397.165763 -403.965105) (xy 397.150405 -404.017404)
			(xy 397.12776 -404.066984) (xy 397.09829 -404.112837) (xy 397.062593 -404.154028) (xy 397.021397 -404.18972)
			(xy 396.97554 -404.219184) (xy 396.925957 -404.241823) (xy 396.873656 -404.257173) (xy 396.819703 -404.264924)
			(xy 396.79245 -404.265384) (xy 395.92885 -404.265384) (xy 395.901599 -404.264943) (xy 395.847654 -404.25718)
			(xy 395.795362 -404.24182) (xy 395.745788 -404.219174) (xy 395.699941 -404.189705) (xy 395.658754 -404.154011)
			(xy 395.623065 -404.112819) (xy 395.593602 -404.066968) (xy 395.570963 -404.017391) (xy 395.555609 -403.965097)
			(xy 395.547854 -403.911151) (xy 394.110198 -403.911151) (xy 394.102442 -403.965092) (xy 394.087088 -404.017383)
			(xy 394.064449 -404.066956) (xy 394.034986 -404.112803) (xy 393.999298 -404.153991) (xy 393.958111 -404.18968)
			(xy 393.912265 -404.219145) (xy 393.862692 -404.241785) (xy 393.810402 -404.25714) (xy 393.756459 -404.264897)
			(xy 393.72921 -404.265384) (xy 392.86561 -404.265384) (xy 392.838355 -404.26497) (xy 392.784399 -404.257213)
			(xy 392.732097 -404.241857) (xy 392.682513 -404.219214) (xy 392.636655 -404.189744) (xy 392.595459 -404.154048)
			(xy 392.559762 -404.112853) (xy 392.530291 -404.066996) (xy 392.507646 -404.017412) (xy 392.492289 -403.96511)
			(xy 392.484531 -403.911155) (xy 391.047021 -403.911155) (xy 391.039263 -403.965103) (xy 391.023907 -404.0174)
			(xy 391.001264 -404.066979) (xy 390.971795 -404.11283) (xy 390.9361 -404.154021) (xy 390.894906 -404.189713)
			(xy 390.849052 -404.219178) (xy 390.799471 -404.241817) (xy 390.747173 -404.25717) (xy 390.693223 -404.264923)
			(xy 390.66597 -404.265384) (xy 389.80237 -404.265384) (xy 389.775118 -404.264944) (xy 389.721171 -404.257184)
			(xy 389.668876 -404.241825) (xy 389.6193 -404.219181) (xy 389.57345 -404.189712) (xy 389.532261 -404.154018)
			(xy 389.49657 -404.112826) (xy 389.467105 -404.066974) (xy 389.444465 -404.017396) (xy 389.42911 -403.9651)
			(xy 389.421354 -403.911152) (xy 387.983697 -403.911152) (xy 387.975943 -403.96509) (xy 387.96059 -404.017379)
			(xy 387.937953 -404.066951) (xy 387.908491 -404.112797) (xy 387.872805 -404.153984) (xy 387.831621 -404.189673)
			(xy 387.785777 -404.219138) (xy 387.736207 -404.24178) (xy 387.683919 -404.257136) (xy 387.629978 -404.264896)
			(xy 387.60273 -404.265384) (xy 386.73913 -404.265384) (xy 386.711874 -404.264971) (xy 386.657916 -404.257217)
			(xy 386.605612 -404.241863) (xy 386.556024 -404.21922) (xy 386.510165 -404.189751) (xy 386.468966 -404.154055)
			(xy 386.433267 -404.112859) (xy 386.403794 -404.067002) (xy 386.381148 -404.017417) (xy 386.365789 -403.965113)
			(xy 386.358031 -403.911156) (xy 384.92052 -403.911156) (xy 384.912764 -403.9651) (xy 384.897408 -404.017395)
			(xy 384.874767 -404.066973) (xy 384.845299 -404.112824) (xy 384.809607 -404.154014) (xy 384.768416 -404.189705)
			(xy 384.722564 -404.219171) (xy 384.672986 -404.241812) (xy 384.62069 -404.257166) (xy 384.566742 -404.264921)
			(xy 384.53949 -404.265384) (xy 383.67589 -404.265384) (xy 383.648638 -404.264945) (xy 383.594687 -404.257187)
			(xy 383.542391 -404.24183) (xy 383.492812 -404.219187) (xy 383.44696 -404.189719) (xy 383.405768 -404.154025)
			(xy 383.370075 -404.112832) (xy 383.340608 -404.06698) (xy 383.317966 -404.0174) (xy 383.302611 -403.965103)
			(xy 383.294854 -403.911153) (xy 381.857321 -403.911153) (xy 381.849563 -403.965105) (xy 381.834205 -404.017404)
			(xy 381.81156 -404.066984) (xy 381.78209 -404.112837) (xy 381.746393 -404.154028) (xy 381.705197 -404.18972)
			(xy 381.65934 -404.219184) (xy 381.609757 -404.241823) (xy 381.557456 -404.257173) (xy 381.503503 -404.264924)
			(xy 381.47625 -404.265384) (xy 380.61265 -404.265384) (xy 380.585399 -404.264943) (xy 380.531454 -404.25718)
			(xy 380.479162 -404.24182) (xy 380.429588 -404.219174) (xy 380.383741 -404.189705) (xy 380.342554 -404.154011)
			(xy 380.306865 -404.112819) (xy 380.277402 -404.066968) (xy 380.254763 -404.017391) (xy 380.239409 -403.965097)
			(xy 380.231654 -403.911151) (xy 378.793998 -403.911151) (xy 378.786242 -403.965092) (xy 378.770888 -404.017383)
			(xy 378.748249 -404.066956) (xy 378.718786 -404.112803) (xy 378.683098 -404.153991) (xy 378.641911 -404.18968)
			(xy 378.596065 -404.219145) (xy 378.546492 -404.241785) (xy 378.494202 -404.25714) (xy 378.440259 -404.264897)
			(xy 378.41301 -404.265384) (xy 377.54941 -404.265384) (xy 377.522155 -404.26497) (xy 377.468199 -404.257213)
			(xy 377.415897 -404.241857) (xy 377.366313 -404.219214) (xy 377.320455 -404.189744) (xy 377.279259 -404.154048)
			(xy 377.243562 -404.112853) (xy 377.214091 -404.066996) (xy 377.191446 -404.017412) (xy 377.176089 -403.96511)
			(xy 377.168331 -403.911155) (xy 375.730821 -403.911155) (xy 375.723063 -403.965103) (xy 375.707707 -404.0174)
			(xy 375.685064 -404.066979) (xy 375.655595 -404.11283) (xy 375.6199 -404.154021) (xy 375.578706 -404.189713)
			(xy 375.532852 -404.219178) (xy 375.483271 -404.241817) (xy 375.430973 -404.25717) (xy 375.377023 -404.264923)
			(xy 375.34977 -404.265384) (xy 374.48617 -404.265384) (xy 374.458918 -404.264944) (xy 374.404971 -404.257184)
			(xy 374.352676 -404.241825) (xy 374.3031 -404.219181) (xy 374.25725 -404.189712) (xy 374.216061 -404.154018)
			(xy 374.18037 -404.112826) (xy 374.150905 -404.066974) (xy 374.128265 -404.017396) (xy 374.11291 -403.9651)
			(xy 374.105154 -403.911152) (xy 372.667497 -403.911152) (xy 372.659743 -403.96509) (xy 372.64439 -404.017379)
			(xy 372.621753 -404.066951) (xy 372.592291 -404.112797) (xy 372.556605 -404.153984) (xy 372.515421 -404.189673)
			(xy 372.469577 -404.219138) (xy 372.420007 -404.24178) (xy 372.367719 -404.257136) (xy 372.313778 -404.264896)
			(xy 372.28653 -404.265384) (xy 371.42293 -404.265384) (xy 371.395674 -404.264971) (xy 371.341716 -404.257217)
			(xy 371.289412 -404.241863) (xy 371.239824 -404.21922) (xy 371.193965 -404.189751) (xy 371.152766 -404.154055)
			(xy 371.117067 -404.112859) (xy 371.087594 -404.067002) (xy 371.064948 -404.017417) (xy 371.049589 -403.965113)
			(xy 371.041831 -403.911156) (xy 351.17332 -403.911156) (xy 351.165564 -403.9651) (xy 351.150208 -404.017396)
			(xy 351.127566 -404.066974) (xy 351.098099 -404.112824) (xy 351.062406 -404.154015) (xy 351.021215 -404.189706)
			(xy 350.975363 -404.219172) (xy 350.925785 -404.241812) (xy 350.873489 -404.257166) (xy 350.81954 -404.264922)
			(xy 350.792288 -404.265384) (xy 349.928688 -404.265384) (xy 349.901436 -404.264945) (xy 349.847486 -404.257187)
			(xy 349.795189 -404.24183) (xy 349.74561 -404.219187) (xy 349.699759 -404.189718) (xy 349.658567 -404.154024)
			(xy 349.622875 -404.112832) (xy 349.593408 -404.066979) (xy 349.570766 -404.0174) (xy 349.55541 -403.965102)
			(xy 349.547654 -403.911152) (xy 348.109997 -403.911152) (xy 348.102243 -403.965087) (xy 348.086891 -404.017375)
			(xy 348.064255 -404.066946) (xy 348.034795 -404.112791) (xy 347.999111 -404.153977) (xy 347.957929 -404.189667)
			(xy 347.912088 -404.219132) (xy 347.86252 -404.241775) (xy 347.810234 -404.257133) (xy 347.756295 -404.264895)
			(xy 347.729048 -404.265384) (xy 346.865448 -404.265384) (xy 346.838191 -404.264972) (xy 346.784232 -404.25722)
			(xy 346.731925 -404.241868) (xy 346.682335 -404.219226) (xy 346.636473 -404.189758) (xy 346.595272 -404.154062)
			(xy 346.559571 -404.112865) (xy 346.530097 -404.067007) (xy 346.507449 -404.01742) (xy 346.49209 -403.965115)
			(xy 346.484331 -403.911157) (xy 345.046797 -403.911157) (xy 345.039042 -403.965093) (xy 345.023688 -404.017383)
			(xy 345.001049 -404.066957) (xy 344.971586 -404.112804) (xy 344.935897 -404.153991) (xy 344.89471 -404.189681)
			(xy 344.848864 -404.219145) (xy 344.799291 -404.241785) (xy 344.747001 -404.25714) (xy 344.693057 -404.264897)
			(xy 344.665808 -404.265384) (xy 343.802208 -404.265384) (xy 343.774953 -404.26497) (xy 343.720998 -404.257213)
			(xy 343.668696 -404.241857) (xy 343.619111 -404.219213) (xy 343.573254 -404.189744) (xy 343.532058 -404.154048)
			(xy 343.496361 -404.112852) (xy 343.466891 -404.066996) (xy 343.444246 -404.017412) (xy 343.428889 -403.96511)
			(xy 343.421131 -403.911155) (xy 341.983621 -403.911155) (xy 341.975863 -403.965103) (xy 341.960507 -404.0174)
			(xy 341.937863 -404.066979) (xy 341.908394 -404.112831) (xy 341.872699 -404.154022) (xy 341.831505 -404.189713)
			(xy 341.785651 -404.219179) (xy 341.73607 -404.241818) (xy 341.683772 -404.25717) (xy 341.629821 -404.264923)
			(xy 341.602568 -404.265384) (xy 340.738968 -404.265384) (xy 340.711717 -404.264944) (xy 340.657769 -404.257183)
			(xy 340.605475 -404.241824) (xy 340.555898 -404.21918) (xy 340.510049 -404.189711) (xy 340.46886 -404.154017)
			(xy 340.43317 -404.112825) (xy 340.403705 -404.066974) (xy 340.381064 -404.017395) (xy 340.36571 -403.9651)
			(xy 340.357954 -403.911152) (xy 338.920297 -403.911152) (xy 338.912543 -403.96509) (xy 338.89719 -404.017379)
			(xy 338.874552 -404.066951) (xy 338.84509 -404.112798) (xy 338.809404 -404.153984) (xy 338.76822 -404.189674)
			(xy 338.722376 -404.219139) (xy 338.672805 -404.24178) (xy 338.620517 -404.257137) (xy 338.566576 -404.264896)
			(xy 338.539328 -404.265384) (xy 337.675728 -404.265384) (xy 337.648472 -404.264971) (xy 337.594515 -404.257217)
			(xy 337.54221 -404.241862) (xy 337.492623 -404.21922) (xy 337.446764 -404.189751) (xy 337.405565 -404.154055)
			(xy 337.369866 -404.112859) (xy 337.340394 -404.067001) (xy 337.317748 -404.017416) (xy 337.302389 -403.965113)
			(xy 337.294631 -403.911156) (xy 335.85712 -403.911156) (xy 335.849364 -403.9651) (xy 335.834008 -404.017396)
			(xy 335.811366 -404.066974) (xy 335.781899 -404.112824) (xy 335.746206 -404.154015) (xy 335.705015 -404.189706)
			(xy 335.659163 -404.219172) (xy 335.609585 -404.241812) (xy 335.557289 -404.257166) (xy 335.50334 -404.264922)
			(xy 335.476088 -404.265384) (xy 334.612488 -404.265384) (xy 334.585236 -404.264945) (xy 334.531286 -404.257187)
			(xy 334.478989 -404.24183) (xy 334.42941 -404.219187) (xy 334.383559 -404.189718) (xy 334.342367 -404.154024)
			(xy 334.306675 -404.112832) (xy 334.277208 -404.066979) (xy 334.254566 -404.0174) (xy 334.23921 -403.965102)
			(xy 334.231454 -403.911152) (xy 332.793797 -403.911152) (xy 332.786043 -403.965087) (xy 332.770691 -404.017375)
			(xy 332.748055 -404.066946) (xy 332.718595 -404.112791) (xy 332.682911 -404.153977) (xy 332.641729 -404.189667)
			(xy 332.595888 -404.219132) (xy 332.54632 -404.241775) (xy 332.494034 -404.257133) (xy 332.440095 -404.264895)
			(xy 332.412848 -404.265384) (xy 331.549248 -404.265384) (xy 331.521991 -404.264972) (xy 331.468032 -404.25722)
			(xy 331.415725 -404.241868) (xy 331.366135 -404.219226) (xy 331.320273 -404.189758) (xy 331.279072 -404.154062)
			(xy 331.243371 -404.112865) (xy 331.213897 -404.067007) (xy 331.191249 -404.01742) (xy 331.17589 -403.965115)
			(xy 331.168131 -403.911157) (xy 329.730597 -403.911157) (xy 329.722842 -403.965093) (xy 329.707488 -404.017383)
			(xy 329.684849 -404.066957) (xy 329.655386 -404.112804) (xy 329.619697 -404.153991) (xy 329.57851 -404.189681)
			(xy 329.532664 -404.219145) (xy 329.483091 -404.241785) (xy 329.430801 -404.25714) (xy 329.376857 -404.264897)
			(xy 329.349608 -404.265384) (xy 328.486008 -404.265384) (xy 328.458753 -404.26497) (xy 328.404798 -404.257213)
			(xy 328.352496 -404.241857) (xy 328.302911 -404.219213) (xy 328.257054 -404.189744) (xy 328.215858 -404.154048)
			(xy 328.180161 -404.112852) (xy 328.150691 -404.066996) (xy 328.128046 -404.017412) (xy 328.112689 -403.96511)
			(xy 328.104931 -403.911155) (xy 326.667421 -403.911155) (xy 326.659663 -403.965103) (xy 326.644307 -404.0174)
			(xy 326.621663 -404.066979) (xy 326.592194 -404.112831) (xy 326.556499 -404.154022) (xy 326.515305 -404.189713)
			(xy 326.469451 -404.219179) (xy 326.41987 -404.241818) (xy 326.367572 -404.25717) (xy 326.313621 -404.264923)
			(xy 326.286368 -404.265384) (xy 325.422768 -404.265384) (xy 325.395517 -404.264944) (xy 325.341569 -404.257183)
			(xy 325.289275 -404.241824) (xy 325.239698 -404.21918) (xy 325.193849 -404.189711) (xy 325.15266 -404.154017)
			(xy 325.11697 -404.112825) (xy 325.087505 -404.066974) (xy 325.064864 -404.017395) (xy 325.04951 -403.9651)
			(xy 325.041754 -403.911152) (xy 323.604097 -403.911152) (xy 323.596343 -403.96509) (xy 323.58099 -404.017379)
			(xy 323.558352 -404.066951) (xy 323.52889 -404.112798) (xy 323.493204 -404.153984) (xy 323.45202 -404.189674)
			(xy 323.406176 -404.219139) (xy 323.356605 -404.24178) (xy 323.304317 -404.257137) (xy 323.250376 -404.264896)
			(xy 323.223128 -404.265384) (xy 322.359528 -404.265384) (xy 322.332272 -404.264971) (xy 322.278315 -404.257217)
			(xy 322.22601 -404.241862) (xy 322.176423 -404.21922) (xy 322.130564 -404.189751) (xy 322.089365 -404.154055)
			(xy 322.053666 -404.112859) (xy 322.024194 -404.067001) (xy 322.001548 -404.017416) (xy 321.986189 -403.965113)
			(xy 321.978431 -403.911156) (xy 320.54092 -403.911156) (xy 320.533164 -403.9651) (xy 320.517808 -404.017396)
			(xy 320.495166 -404.066974) (xy 320.465699 -404.112824) (xy 320.430006 -404.154015) (xy 320.388815 -404.189706)
			(xy 320.342963 -404.219172) (xy 320.293385 -404.241812) (xy 320.241089 -404.257166) (xy 320.18714 -404.264922)
			(xy 320.159888 -404.265384) (xy 319.296288 -404.265384) (xy 319.269036 -404.264945) (xy 319.215086 -404.257187)
			(xy 319.162789 -404.24183) (xy 319.11321 -404.219187) (xy 319.067359 -404.189718) (xy 319.026167 -404.154024)
			(xy 318.990475 -404.112832) (xy 318.961008 -404.066979) (xy 318.938366 -404.0174) (xy 318.92301 -403.965102)
			(xy 318.915254 -403.911152) (xy 317.477597 -403.911152) (xy 317.469843 -403.965087) (xy 317.454491 -404.017375)
			(xy 317.431855 -404.066946) (xy 317.402395 -404.112791) (xy 317.366711 -404.153977) (xy 317.325529 -404.189667)
			(xy 317.279688 -404.219132) (xy 317.23012 -404.241775) (xy 317.177834 -404.257133) (xy 317.123895 -404.264895)
			(xy 317.096648 -404.265384) (xy 316.233048 -404.265384) (xy 316.205791 -404.264972) (xy 316.151832 -404.25722)
			(xy 316.099525 -404.241868) (xy 316.049935 -404.219226) (xy 316.004073 -404.189758) (xy 315.962872 -404.154062)
			(xy 315.927171 -404.112865) (xy 315.897697 -404.067007) (xy 315.875049 -404.01742) (xy 315.85969 -403.965115)
			(xy 315.851931 -403.911157) (xy 314.414397 -403.911157) (xy 314.406642 -403.965093) (xy 314.391288 -404.017383)
			(xy 314.368649 -404.066957) (xy 314.339186 -404.112804) (xy 314.303497 -404.153991) (xy 314.26231 -404.189681)
			(xy 314.216464 -404.219145) (xy 314.166891 -404.241785) (xy 314.114601 -404.25714) (xy 314.060657 -404.264897)
			(xy 314.033408 -404.265384) (xy 313.169808 -404.265384) (xy 313.142553 -404.26497) (xy 313.088598 -404.257213)
			(xy 313.036296 -404.241857) (xy 312.986711 -404.219213) (xy 312.940854 -404.189744) (xy 312.899658 -404.154048)
			(xy 312.863961 -404.112852) (xy 312.834491 -404.066996) (xy 312.811846 -404.017412) (xy 312.796489 -403.96511)
			(xy 312.788731 -403.911155) (xy 311.351221 -403.911155) (xy 311.343463 -403.965103) (xy 311.328107 -404.0174)
			(xy 311.305463 -404.066979) (xy 311.275994 -404.112831) (xy 311.240299 -404.154022) (xy 311.199105 -404.189713)
			(xy 311.153251 -404.219179) (xy 311.10367 -404.241818) (xy 311.051372 -404.25717) (xy 310.997421 -404.264923)
			(xy 310.970168 -404.265384) (xy 310.106568 -404.265384) (xy 310.079317 -404.264944) (xy 310.025369 -404.257183)
			(xy 309.973075 -404.241824) (xy 309.923498 -404.21918) (xy 309.877649 -404.189711) (xy 309.83646 -404.154017)
			(xy 309.80077 -404.112825) (xy 309.771305 -404.066974) (xy 309.748664 -404.017395) (xy 309.73331 -403.9651)
			(xy 309.725554 -403.911152) (xy 308.287897 -403.911152) (xy 308.280143 -403.96509) (xy 308.26479 -404.017379)
			(xy 308.242152 -404.066951) (xy 308.21269 -404.112798) (xy 308.177004 -404.153984) (xy 308.13582 -404.189674)
			(xy 308.089976 -404.219139) (xy 308.040405 -404.24178) (xy 307.988117 -404.257137) (xy 307.934176 -404.264896)
			(xy 307.906928 -404.265384) (xy 307.043328 -404.265384) (xy 307.016072 -404.264971) (xy 306.962115 -404.257217)
			(xy 306.90981 -404.241862) (xy 306.860223 -404.21922) (xy 306.814364 -404.189751) (xy 306.773165 -404.154055)
			(xy 306.737466 -404.112859) (xy 306.707994 -404.067001) (xy 306.685348 -404.017416) (xy 306.669989 -403.965113)
			(xy 306.662231 -403.911156) (xy 305.22472 -403.911156) (xy 305.216964 -403.9651) (xy 305.201608 -404.017396)
			(xy 305.178966 -404.066974) (xy 305.149499 -404.112824) (xy 305.113806 -404.154015) (xy 305.072615 -404.189706)
			(xy 305.026763 -404.219172) (xy 304.977185 -404.241812) (xy 304.924889 -404.257166) (xy 304.87094 -404.264922)
			(xy 304.843688 -404.265384) (xy 303.980088 -404.265384) (xy 303.952836 -404.264945) (xy 303.898886 -404.257187)
			(xy 303.846589 -404.24183) (xy 303.79701 -404.219187) (xy 303.751159 -404.189718) (xy 303.709967 -404.154024)
			(xy 303.674275 -404.112832) (xy 303.644808 -404.066979) (xy 303.622166 -404.0174) (xy 303.60681 -403.965102)
			(xy 303.599054 -403.911152) (xy 298.836897 -403.911152) (xy 298.840074 -403.920931) (xy 298.852049 -403.983712)
			(xy 298.856063 -404.0475) (xy 298.852049 -404.111288) (xy 298.840074 -404.174069) (xy 298.820324 -404.234855)
			(xy 298.793112 -404.292686) (xy 298.758866 -404.346651) (xy 298.718128 -404.395898) (xy 298.671538 -404.439652)
			(xy 298.619832 -404.477221) (xy 298.563825 -404.508014) (xy 298.504401 -404.531545) (xy 298.442496 -404.547442)
			(xy 298.379087 -404.555456) (xy 298.34713 -404.55596) (xy 298.346876 -404.55596) (xy 298.315131 -404.555422)
			(xy 298.252136 -404.547497) (xy 298.190616 -404.531797) (xy 298.131527 -404.508566) (xy 298.075787 -404.478166)
			(xy 298.024261 -404.441069) (xy 298.000674 -404.419816) (xy 297.993411 -404.413632) (xy 297.975661 -404.406681)
			(xy 297.956599 -404.406681) (xy 297.938849 -404.413632) (xy 297.931586 -404.419816) (xy 297.908028 -404.441107)
			(xy 297.856512 -404.478235) (xy 297.800771 -404.508654) (xy 297.741674 -404.531889) (xy 297.680142 -404.547579)
			(xy 297.617135 -404.555478) (xy 297.585384 -404.55596) (xy 297.58513 -404.55596) (xy 297.553163 -404.555577)
			(xy 297.489734 -404.547567) (xy 297.427809 -404.531671) (xy 297.368364 -404.508138) (xy 297.312338 -404.47734)
			(xy 297.260613 -404.439763) (xy 297.214007 -404.395999) (xy 297.173253 -404.346739) (xy 297.138995 -404.292759)
			(xy 297.111773 -404.234911) (xy 297.092015 -404.174108) (xy 297.080035 -404.111307) (xy 297.07602 -404.0475)
			(xy 296.316063 -404.0475) (xy 296.312049 -404.111288) (xy 296.300074 -404.174069) (xy 296.280324 -404.234855)
			(xy 296.253112 -404.292686) (xy 296.218866 -404.346651) (xy 296.178128 -404.395898) (xy 296.131538 -404.439652)
			(xy 296.079832 -404.477221) (xy 296.023825 -404.508014) (xy 295.964401 -404.531545) (xy 295.902496 -404.547442)
			(xy 295.839087 -404.555456) (xy 295.80713 -404.55596) (xy 295.806876 -404.55596) (xy 295.775131 -404.555422)
			(xy 295.712136 -404.547497) (xy 295.650616 -404.531797) (xy 295.591527 -404.508566) (xy 295.535787 -404.478166)
			(xy 295.484261 -404.441069) (xy 295.460674 -404.419816) (xy 295.453411 -404.413632) (xy 295.435661 -404.406681)
			(xy 295.416599 -404.406681) (xy 295.398849 -404.413632) (xy 295.391586 -404.419816) (xy 295.368028 -404.441107)
			(xy 295.316512 -404.478235) (xy 295.260771 -404.508654) (xy 295.201674 -404.531889) (xy 295.140142 -404.547579)
			(xy 295.077135 -404.555478) (xy 295.045384 -404.55596) (xy 295.04513 -404.55596) (xy 295.013163 -404.555577)
			(xy 294.949734 -404.547567) (xy 294.887809 -404.531671) (xy 294.828364 -404.508138) (xy 294.772338 -404.47734)
			(xy 294.720613 -404.439763) (xy 294.674007 -404.395999) (xy 294.633253 -404.346739) (xy 294.598995 -404.292759)
			(xy 294.571773 -404.234911) (xy 294.552015 -404.174108) (xy 294.540035 -404.111307) (xy 294.53602 -404.0475)
			(xy 293.926484 -404.0475) (xy 293.92247 -404.111293) (xy 293.910493 -404.174079) (xy 293.890741 -404.23487)
			(xy 293.863525 -404.292705) (xy 293.829276 -404.346674) (xy 293.788532 -404.395924) (xy 293.741937 -404.439679)
			(xy 293.690226 -404.47725) (xy 293.634213 -404.508043) (xy 293.574783 -404.531573) (xy 293.512872 -404.547468)
			(xy 293.449457 -404.555479) (xy 293.417498 -404.55596) (xy 293.417244 -404.55596) (xy 293.385498 -404.555442)
			(xy 293.322502 -404.547512) (xy 293.260982 -404.531809) (xy 293.201894 -404.508575) (xy 293.146154 -404.478171)
			(xy 293.094629 -404.44107) (xy 293.071042 -404.419816) (xy 293.063779 -404.413632) (xy 293.046029 -404.406681)
			(xy 293.026967 -404.406681) (xy 293.009217 -404.413632) (xy 293.001954 -404.419816) (xy 292.978367 -404.441074)
			(xy 292.926858 -404.478206) (xy 292.871123 -404.50863) (xy 292.812032 -404.531871) (xy 292.750504 -404.547567)
			(xy 292.687501 -404.555474) (xy 292.655752 -404.55596) (xy 292.655498 -404.55596) (xy 292.623534 -404.555554)
			(xy 292.56011 -404.547542) (xy 292.498191 -404.531643) (xy 292.438752 -404.50811) (xy 292.382731 -404.477312)
			(xy 292.331013 -404.439736) (xy 292.284411 -404.395974) (xy 292.243662 -404.346717) (xy 292.209408 -404.29274)
			(xy 292.182189 -404.234897) (xy 292.162434 -404.174098) (xy 292.150455 -404.111302) (xy 292.146441 -404.0475)
			(xy 291.386484 -404.0475) (xy 291.38247 -404.111293) (xy 291.370493 -404.174079) (xy 291.350741 -404.23487)
			(xy 291.323525 -404.292705) (xy 291.289276 -404.346674) (xy 291.248532 -404.395924) (xy 291.201937 -404.439679)
			(xy 291.150226 -404.47725) (xy 291.094213 -404.508043) (xy 291.034783 -404.531573) (xy 290.972872 -404.547468)
			(xy 290.909457 -404.555479) (xy 290.877498 -404.55596) (xy 290.877244 -404.55596) (xy 290.845498 -404.555442)
			(xy 290.782502 -404.547512) (xy 290.720982 -404.531809) (xy 290.661894 -404.508575) (xy 290.606154 -404.478171)
			(xy 290.554629 -404.44107) (xy 290.531042 -404.419816) (xy 290.523779 -404.413632) (xy 290.506029 -404.406681)
			(xy 290.486967 -404.406681) (xy 290.469217 -404.413632) (xy 290.461954 -404.419816) (xy 290.438367 -404.441074)
			(xy 290.386858 -404.478206) (xy 290.331123 -404.50863) (xy 290.272032 -404.531871) (xy 290.210504 -404.547567)
			(xy 290.147501 -404.555474) (xy 290.115752 -404.55596) (xy 290.115498 -404.55596) (xy 290.083534 -404.555554)
			(xy 290.02011 -404.547542) (xy 289.958191 -404.531643) (xy 289.898752 -404.50811) (xy 289.842731 -404.477312)
			(xy 289.791013 -404.439736) (xy 289.744411 -404.395974) (xy 289.703662 -404.346717) (xy 289.669408 -404.29274)
			(xy 289.642189 -404.234897) (xy 289.622434 -404.174098) (xy 289.610455 -404.111302) (xy 289.606441 -404.0475)
			(xy 288.846484 -404.0475) (xy 288.84247 -404.111293) (xy 288.830493 -404.174079) (xy 288.810741 -404.23487)
			(xy 288.783525 -404.292705) (xy 288.749276 -404.346674) (xy 288.708532 -404.395924) (xy 288.661937 -404.439679)
			(xy 288.610226 -404.47725) (xy 288.554213 -404.508043) (xy 288.494783 -404.531573) (xy 288.432872 -404.547468)
			(xy 288.369457 -404.555479) (xy 288.337498 -404.55596) (xy 288.337244 -404.55596) (xy 288.305498 -404.555442)
			(xy 288.242502 -404.547512) (xy 288.180982 -404.531809) (xy 288.121894 -404.508575) (xy 288.066154 -404.478171)
			(xy 288.014629 -404.44107) (xy 287.991042 -404.419816) (xy 287.983779 -404.413632) (xy 287.966029 -404.406681)
			(xy 287.946967 -404.406681) (xy 287.929217 -404.413632) (xy 287.921954 -404.419816) (xy 287.898367 -404.441074)
			(xy 287.846858 -404.478206) (xy 287.791123 -404.50863) (xy 287.732032 -404.531871) (xy 287.670504 -404.547567)
			(xy 287.607501 -404.555474) (xy 287.575752 -404.55596) (xy 287.575498 -404.55596) (xy 287.543534 -404.555554)
			(xy 287.48011 -404.547542) (xy 287.418191 -404.531643) (xy 287.358752 -404.50811) (xy 287.302731 -404.477312)
			(xy 287.251013 -404.439736) (xy 287.204411 -404.395974) (xy 287.163662 -404.346717) (xy 287.129408 -404.29274)
			(xy 287.102189 -404.234897) (xy 287.082434 -404.174098) (xy 287.070455 -404.111302) (xy 287.066441 -404.0475)
			(xy 167.31136 -404.0475) (xy 167.302461 -404.066983) (xy 167.272991 -404.112836) (xy 167.237294 -404.154027)
			(xy 167.196099 -404.189718) (xy 167.150243 -404.219183) (xy 167.10066 -404.241822) (xy 167.04836 -404.257173)
			(xy 166.994407 -404.264924) (xy 166.967154 -404.265384) (xy 166.103554 -404.265384) (xy 166.076303 -404.264943)
			(xy 166.022357 -404.257181) (xy 165.970065 -404.241821) (xy 165.92049 -404.219175) (xy 165.874642 -404.189706)
			(xy 165.833455 -404.154012) (xy 165.797766 -404.112821) (xy 165.768302 -404.06697) (xy 165.745663 -404.017392)
			(xy 165.73031 -403.965098) (xy 165.722554 -403.911151) (xy 164.284898 -403.911151) (xy 164.277142 -403.965092)
			(xy 164.261789 -404.017382) (xy 164.23915 -404.066955) (xy 164.209687 -404.112802) (xy 164.173999 -404.153989)
			(xy 164.132813 -404.189679) (xy 164.086968 -404.219143) (xy 164.037395 -404.241784) (xy 163.985106 -404.257139)
			(xy 163.931163 -404.264897) (xy 163.903914 -404.265384) (xy 163.040314 -404.265384) (xy 163.013059 -404.26497)
			(xy 162.959103 -404.257214) (xy 162.9068 -404.241858) (xy 162.857215 -404.219215) (xy 162.811357 -404.189746)
			(xy 162.77016 -404.15405) (xy 162.734463 -404.112854) (xy 162.704991 -404.066997) (xy 162.682346 -404.017413)
			(xy 162.666989 -403.965111) (xy 162.659231 -403.911155) (xy 161.221721 -403.911155) (xy 161.213963 -403.965102)
			(xy 161.198607 -404.017399) (xy 161.175964 -404.066978) (xy 161.146496 -404.112829) (xy 161.110801 -404.15402)
			(xy 161.069608 -404.189711) (xy 161.023755 -404.219177) (xy 160.974174 -404.241816) (xy 160.921877 -404.257169)
			(xy 160.867926 -404.264922) (xy 160.840674 -404.265384) (xy 159.977074 -404.265384) (xy 159.949822 -404.264944)
			(xy 159.895874 -404.257184) (xy 159.843579 -404.241826) (xy 159.794002 -404.219182) (xy 159.748152 -404.189713)
			(xy 159.706962 -404.154019) (xy 159.671271 -404.112827) (xy 159.641806 -404.066975) (xy 159.619165 -404.017397)
			(xy 159.60381 -403.965101) (xy 159.596054 -403.911152) (xy 158.158397 -403.911152) (xy 158.150643 -403.965089)
			(xy 158.13529 -404.017378) (xy 158.112653 -404.06695) (xy 158.083192 -404.112796) (xy 158.047506 -404.153982)
			(xy 158.006323 -404.189671) (xy 157.96048 -404.219137) (xy 157.91091 -404.241778) (xy 157.858623 -404.257136)
			(xy 157.804682 -404.264895) (xy 157.777434 -404.265384) (xy 156.913834 -404.265384) (xy 156.886578 -404.264971)
			(xy 156.83262 -404.257218) (xy 156.780314 -404.241864) (xy 156.730727 -404.219222) (xy 156.684867 -404.189753)
			(xy 156.643667 -404.154057) (xy 156.607968 -404.112861) (xy 156.578495 -404.067003) (xy 156.555848 -404.017417)
			(xy 156.540489 -403.965114) (xy 156.532731 -403.911156) (xy 155.09522 -403.911156) (xy 155.087464 -403.965099)
			(xy 155.072109 -404.017394) (xy 155.049467 -404.066972) (xy 155.02 -404.112822) (xy 154.984308 -404.154013)
			(xy 154.943118 -404.189704) (xy 154.897267 -404.21917) (xy 154.847689 -404.241811) (xy 154.795394 -404.257165)
			(xy 154.741445 -404.264921) (xy 154.714194 -404.265384) (xy 153.850594 -404.265384) (xy 153.823341 -404.264946)
			(xy 153.769391 -404.257188) (xy 153.717094 -404.241831) (xy 153.667514 -404.219189) (xy 153.621661 -404.18972)
			(xy 153.580469 -404.154026) (xy 153.544776 -404.112834) (xy 153.515309 -404.066981) (xy 153.492666 -404.017401)
			(xy 153.477311 -403.965103) (xy 153.469554 -403.911153) (xy 152.032021 -403.911153) (xy 152.024263 -403.965105)
			(xy 152.008906 -404.017403) (xy 151.986261 -404.066983) (xy 151.956791 -404.112836) (xy 151.921094 -404.154027)
			(xy 151.879899 -404.189718) (xy 151.834043 -404.219183) (xy 151.78446 -404.241822) (xy 151.73216 -404.257173)
			(xy 151.678207 -404.264924) (xy 151.650954 -404.265384) (xy 150.787354 -404.265384) (xy 150.760103 -404.264943)
			(xy 150.706157 -404.257181) (xy 150.653865 -404.241821) (xy 150.60429 -404.219175) (xy 150.558442 -404.189706)
			(xy 150.517255 -404.154012) (xy 150.481566 -404.112821) (xy 150.452102 -404.06697) (xy 150.429463 -404.017392)
			(xy 150.41411 -403.965098) (xy 150.406354 -403.911151) (xy 148.968698 -403.911151) (xy 148.960942 -403.965092)
			(xy 148.945589 -404.017382) (xy 148.92295 -404.066955) (xy 148.893487 -404.112802) (xy 148.857799 -404.153989)
			(xy 148.816613 -404.189679) (xy 148.770768 -404.219143) (xy 148.721195 -404.241784) (xy 148.668906 -404.257139)
			(xy 148.614963 -404.264897) (xy 148.587714 -404.265384) (xy 147.724114 -404.265384) (xy 147.696859 -404.26497)
			(xy 147.642903 -404.257214) (xy 147.5906 -404.241858) (xy 147.541015 -404.219215) (xy 147.495157 -404.189746)
			(xy 147.45396 -404.15405) (xy 147.418263 -404.112854) (xy 147.388791 -404.066997) (xy 147.366146 -404.017413)
			(xy 147.350789 -403.965111) (xy 147.343031 -403.911155) (xy 145.905521 -403.911155) (xy 145.897763 -403.965102)
			(xy 145.882407 -404.017399) (xy 145.859764 -404.066978) (xy 145.830296 -404.112829) (xy 145.794601 -404.15402)
			(xy 145.753408 -404.189711) (xy 145.707555 -404.219177) (xy 145.657974 -404.241816) (xy 145.605677 -404.257169)
			(xy 145.551726 -404.264922) (xy 145.524474 -404.265384) (xy 144.660874 -404.265384) (xy 144.633622 -404.264944)
			(xy 144.579674 -404.257184) (xy 144.527379 -404.241826) (xy 144.477802 -404.219182) (xy 144.431952 -404.189713)
			(xy 144.390762 -404.154019) (xy 144.355071 -404.112827) (xy 144.325606 -404.066975) (xy 144.302965 -404.017397)
			(xy 144.28761 -403.965101) (xy 144.279854 -403.911152) (xy 142.842197 -403.911152) (xy 142.834443 -403.965089)
			(xy 142.81909 -404.017378) (xy 142.796453 -404.06695) (xy 142.766992 -404.112796) (xy 142.731306 -404.153982)
			(xy 142.690123 -404.189671) (xy 142.64428 -404.219137) (xy 142.59471 -404.241778) (xy 142.542423 -404.257136)
			(xy 142.488482 -404.264895) (xy 142.461234 -404.265384) (xy 141.597634 -404.265384) (xy 141.570378 -404.264971)
			(xy 141.51642 -404.257218) (xy 141.464114 -404.241864) (xy 141.414527 -404.219222) (xy 141.368667 -404.189753)
			(xy 141.327467 -404.154057) (xy 141.291768 -404.112861) (xy 141.262295 -404.067003) (xy 141.239648 -404.017417)
			(xy 141.224289 -403.965114) (xy 141.216531 -403.911156) (xy 139.77902 -403.911156) (xy 139.771264 -403.965099)
			(xy 139.755909 -404.017394) (xy 139.733267 -404.066972) (xy 139.7038 -404.112822) (xy 139.668108 -404.154013)
			(xy 139.626918 -404.189704) (xy 139.581067 -404.21917) (xy 139.531489 -404.241811) (xy 139.479194 -404.257165)
			(xy 139.425245 -404.264921) (xy 139.397994 -404.265384) (xy 138.534394 -404.265384) (xy 138.507141 -404.264946)
			(xy 138.453191 -404.257188) (xy 138.400894 -404.241831) (xy 138.351314 -404.219189) (xy 138.305461 -404.18972)
			(xy 138.264269 -404.154026) (xy 138.228576 -404.112834) (xy 138.199109 -404.066981) (xy 138.176466 -404.017401)
			(xy 138.161111 -403.965103) (xy 138.153354 -403.911153) (xy 136.715821 -403.911153) (xy 136.708063 -403.965105)
			(xy 136.692706 -404.017403) (xy 136.670061 -404.066983) (xy 136.640591 -404.112836) (xy 136.604894 -404.154027)
			(xy 136.563699 -404.189718) (xy 136.517843 -404.219183) (xy 136.46826 -404.241822) (xy 136.41596 -404.257173)
			(xy 136.362007 -404.264924) (xy 136.334754 -404.265384) (xy 135.471154 -404.265384) (xy 135.443903 -404.264943)
			(xy 135.389957 -404.257181) (xy 135.337665 -404.241821) (xy 135.28809 -404.219175) (xy 135.242242 -404.189706)
			(xy 135.201055 -404.154012) (xy 135.165366 -404.112821) (xy 135.135902 -404.06697) (xy 135.113263 -404.017392)
			(xy 135.09791 -403.965098) (xy 135.090154 -403.911151) (xy 133.652498 -403.911151) (xy 133.644742 -403.965092)
			(xy 133.629389 -404.017382) (xy 133.60675 -404.066955) (xy 133.577287 -404.112802) (xy 133.541599 -404.153989)
			(xy 133.500413 -404.189679) (xy 133.454568 -404.219143) (xy 133.404995 -404.241784) (xy 133.352706 -404.257139)
			(xy 133.298763 -404.264897) (xy 133.271514 -404.265384) (xy 132.407914 -404.265384) (xy 132.380659 -404.26497)
			(xy 132.326703 -404.257214) (xy 132.2744 -404.241858) (xy 132.224815 -404.219215) (xy 132.178957 -404.189746)
			(xy 132.13776 -404.15405) (xy 132.102063 -404.112854) (xy 132.072591 -404.066997) (xy 132.049946 -404.017413)
			(xy 132.034589 -403.965111) (xy 132.026831 -403.911155) (xy 130.589321 -403.911155) (xy 130.581563 -403.965102)
			(xy 130.566207 -404.017399) (xy 130.543564 -404.066978) (xy 130.514096 -404.112829) (xy 130.478401 -404.15402)
			(xy 130.437208 -404.189711) (xy 130.391355 -404.219177) (xy 130.341774 -404.241816) (xy 130.289477 -404.257169)
			(xy 130.235526 -404.264922) (xy 130.208274 -404.265384) (xy 129.344674 -404.265384) (xy 129.317422 -404.264944)
			(xy 129.263474 -404.257184) (xy 129.211179 -404.241826) (xy 129.161602 -404.219182) (xy 129.115752 -404.189713)
			(xy 129.074562 -404.154019) (xy 129.038871 -404.112827) (xy 129.009406 -404.066975) (xy 128.986765 -404.017397)
			(xy 128.97141 -403.965101) (xy 128.963654 -403.911152) (xy 127.525997 -403.911152) (xy 127.518243 -403.965089)
			(xy 127.50289 -404.017378) (xy 127.480253 -404.06695) (xy 127.450792 -404.112796) (xy 127.415106 -404.153982)
			(xy 127.373923 -404.189671) (xy 127.32808 -404.219137) (xy 127.27851 -404.241778) (xy 127.226223 -404.257136)
			(xy 127.172282 -404.264895) (xy 127.145034 -404.265384) (xy 126.281434 -404.265384) (xy 126.254178 -404.264971)
			(xy 126.20022 -404.257218) (xy 126.147914 -404.241864) (xy 126.098327 -404.219222) (xy 126.052467 -404.189753)
			(xy 126.011267 -404.154057) (xy 125.975568 -404.112861) (xy 125.946095 -404.067003) (xy 125.923448 -404.017417)
			(xy 125.908089 -403.965114) (xy 125.900331 -403.911156) (xy 124.46282 -403.911156) (xy 124.455064 -403.965099)
			(xy 124.439709 -404.017394) (xy 124.417067 -404.066972) (xy 124.3876 -404.112822) (xy 124.351908 -404.154013)
			(xy 124.310718 -404.189704) (xy 124.264867 -404.21917) (xy 124.215289 -404.241811) (xy 124.162994 -404.257165)
			(xy 124.109045 -404.264921) (xy 124.081794 -404.265384) (xy 123.218194 -404.265384) (xy 123.190941 -404.264946)
			(xy 123.136991 -404.257188) (xy 123.084694 -404.241831) (xy 123.035114 -404.219189) (xy 122.989261 -404.18972)
			(xy 122.948069 -404.154026) (xy 122.912376 -404.112834) (xy 122.882909 -404.066981) (xy 122.860266 -404.017401)
			(xy 122.844911 -403.965103) (xy 122.837154 -403.911153) (xy 121.399621 -403.911153) (xy 121.391863 -403.965105)
			(xy 121.376506 -404.017403) (xy 121.353861 -404.066983) (xy 121.324391 -404.112836) (xy 121.288694 -404.154027)
			(xy 121.247499 -404.189718) (xy 121.201643 -404.219183) (xy 121.15206 -404.241822) (xy 121.09976 -404.257173)
			(xy 121.045807 -404.264924) (xy 121.018554 -404.265384) (xy 120.154954 -404.265384) (xy 120.127703 -404.264943)
			(xy 120.073757 -404.257181) (xy 120.021465 -404.241821) (xy 119.97189 -404.219175) (xy 119.926042 -404.189706)
			(xy 119.884855 -404.154012) (xy 119.849166 -404.112821) (xy 119.819702 -404.06697) (xy 119.797063 -404.017392)
			(xy 119.78171 -403.965098) (xy 119.773954 -403.911151) (xy 95.172998 -403.911151) (xy 95.165243 -403.965089)
			(xy 95.149891 -404.017377) (xy 95.127254 -404.066949) (xy 95.097793 -404.112794) (xy 95.062108 -404.153981)
			(xy 95.020925 -404.18967) (xy 94.975082 -404.219135) (xy 94.925513 -404.241777) (xy 94.873226 -404.257135)
			(xy 94.819286 -404.264895) (xy 94.792038 -404.265384) (xy 93.928438 -404.265384) (xy 93.901182 -404.264972)
			(xy 93.847223 -404.257219) (xy 93.794917 -404.241865) (xy 93.745329 -404.219223) (xy 93.699468 -404.189754)
			(xy 93.658269 -404.154058) (xy 93.622569 -404.112862) (xy 93.593095 -404.067004) (xy 93.570448 -404.017418)
			(xy 93.555089 -403.965114) (xy 93.547331 -403.911156) (xy 92.10982 -403.911156) (xy 92.102064 -403.965099)
			(xy 92.086709 -404.017394) (xy 92.064068 -404.066971) (xy 92.034601 -404.112821) (xy 91.99891 -404.154011)
			(xy 91.95772 -404.189703) (xy 91.911869 -404.219169) (xy 91.862292 -404.24181) (xy 91.809997 -404.257165)
			(xy 91.756049 -404.264921) (xy 91.728798 -404.265384) (xy 90.865198 -404.265384) (xy 90.837945 -404.264946)
			(xy 90.783994 -404.257189) (xy 90.731696 -404.241833) (xy 90.682116 -404.21919) (xy 90.636263 -404.189722)
			(xy 90.595071 -404.154028) (xy 90.559377 -404.112835) (xy 90.529909 -404.066982) (xy 90.507267 -404.017402)
			(xy 90.491911 -403.965104) (xy 90.484154 -403.911153) (xy 89.046621 -403.911153) (xy 89.038863 -403.965104)
			(xy 89.023506 -404.017402) (xy 89.000862 -404.066982) (xy 88.971392 -404.112834) (xy 88.935696 -404.154025)
			(xy 88.894501 -404.189717) (xy 88.848645 -404.219182) (xy 88.799063 -404.241821) (xy 88.746763 -404.257172)
			(xy 88.692811 -404.264924) (xy 88.665558 -404.265384) (xy 87.801958 -404.265384) (xy 87.774707 -404.264943)
			(xy 87.72076 -404.257181) (xy 87.668467 -404.241822) (xy 87.618892 -404.219177) (xy 87.573044 -404.189707)
			(xy 87.531857 -404.154014) (xy 87.496167 -404.112822) (xy 87.466703 -404.066971) (xy 87.444064 -404.017393)
			(xy 87.42871 -403.965098) (xy 87.420954 -403.911151) (xy 85.983298 -403.911151) (xy 85.975542 -403.965091)
			(xy 85.960189 -404.017381) (xy 85.937551 -404.066954) (xy 85.908088 -404.112801) (xy 85.872401 -404.153988)
			(xy 85.831215 -404.189677) (xy 85.78537 -404.219142) (xy 85.735798 -404.241783) (xy 85.683509 -404.257138)
			(xy 85.629567 -404.264897) (xy 85.602318 -404.265384) (xy 84.738718 -404.265384) (xy 84.711463 -404.26497)
			(xy 84.657506 -404.257215) (xy 84.605203 -404.241859) (xy 84.555617 -404.219217) (xy 84.509759 -404.189747)
			(xy 84.468562 -404.154051) (xy 84.432864 -404.112855) (xy 84.403392 -404.066999) (xy 84.380747 -404.017414)
			(xy 84.365389 -403.965111) (xy 84.357631 -403.911155) (xy 82.920121 -403.911155) (xy 82.912364 -403.965102)
			(xy 82.897007 -404.017398) (xy 82.874365 -404.066976) (xy 82.844897 -404.112828) (xy 82.809203 -404.154018)
			(xy 82.76801 -404.18971) (xy 82.722157 -404.219175) (xy 82.672577 -404.241815) (xy 82.62028 -404.257168)
			(xy 82.56633 -404.264922) (xy 82.539078 -404.265384) (xy 81.675478 -404.265384) (xy 81.648226 -404.264945)
			(xy 81.594277 -404.257185) (xy 81.541982 -404.241827) (xy 81.492404 -404.219183) (xy 81.446554 -404.189715)
			(xy 81.405364 -404.154021) (xy 81.369672 -404.112829) (xy 81.340206 -404.066976) (xy 81.317565 -404.017397)
			(xy 81.30221 -403.965101) (xy 81.294454 -403.911152) (xy 79.856797 -403.911152) (xy 79.849043 -403.965089)
			(xy 79.833691 -404.017377) (xy 79.811054 -404.066949) (xy 79.781593 -404.112794) (xy 79.745908 -404.153981)
			(xy 79.704725 -404.18967) (xy 79.658882 -404.219135) (xy 79.609313 -404.241777) (xy 79.557026 -404.257135)
			(xy 79.503086 -404.264895) (xy 79.475838 -404.265384) (xy 78.612238 -404.265384) (xy 78.584982 -404.264972)
			(xy 78.531023 -404.257219) (xy 78.478717 -404.241865) (xy 78.429129 -404.219223) (xy 78.383268 -404.189754)
			(xy 78.342069 -404.154058) (xy 78.306369 -404.112862) (xy 78.276895 -404.067004) (xy 78.254248 -404.017418)
			(xy 78.238889 -403.965114) (xy 78.231131 -403.911156) (xy 76.79362 -403.911156) (xy 76.785864 -403.965099)
			(xy 76.770509 -404.017394) (xy 76.747868 -404.066971) (xy 76.718401 -404.112821) (xy 76.68271 -404.154011)
			(xy 76.64152 -404.189703) (xy 76.595669 -404.219169) (xy 76.546092 -404.24181) (xy 76.493797 -404.257165)
			(xy 76.439849 -404.264921) (xy 76.412598 -404.265384) (xy 75.548998 -404.265384) (xy 75.521745 -404.264946)
			(xy 75.467794 -404.257189) (xy 75.415496 -404.241833) (xy 75.365916 -404.21919) (xy 75.320063 -404.189722)
			(xy 75.278871 -404.154028) (xy 75.243177 -404.112835) (xy 75.213709 -404.066982) (xy 75.191067 -404.017402)
			(xy 75.175711 -403.965104) (xy 75.167954 -403.911153) (xy 73.730421 -403.911153) (xy 73.722663 -403.965104)
			(xy 73.707306 -404.017402) (xy 73.684662 -404.066982) (xy 73.655192 -404.112834) (xy 73.619496 -404.154025)
			(xy 73.578301 -404.189717) (xy 73.532445 -404.219182) (xy 73.482863 -404.241821) (xy 73.430563 -404.257172)
			(xy 73.376611 -404.264924) (xy 73.349358 -404.265384) (xy 72.485758 -404.265384) (xy 72.458507 -404.264943)
			(xy 72.40456 -404.257181) (xy 72.352267 -404.241822) (xy 72.302692 -404.219177) (xy 72.256844 -404.189707)
			(xy 72.215657 -404.154014) (xy 72.179967 -404.112822) (xy 72.150503 -404.066971) (xy 72.127864 -404.017393)
			(xy 72.11251 -403.965098) (xy 72.104754 -403.911151) (xy 70.667098 -403.911151) (xy 70.659342 -403.965091)
			(xy 70.643989 -404.017381) (xy 70.621351 -404.066954) (xy 70.591888 -404.112801) (xy 70.556201 -404.153988)
			(xy 70.515015 -404.189677) (xy 70.46917 -404.219142) (xy 70.419598 -404.241783) (xy 70.367309 -404.257138)
			(xy 70.313367 -404.264897) (xy 70.286118 -404.265384) (xy 69.422518 -404.265384) (xy 69.395263 -404.26497)
			(xy 69.341306 -404.257215) (xy 69.289003 -404.241859) (xy 69.239417 -404.219217) (xy 69.193559 -404.189747)
			(xy 69.152362 -404.154051) (xy 69.116664 -404.112855) (xy 69.087192 -404.066999) (xy 69.064547 -404.017414)
			(xy 69.049189 -403.965111) (xy 69.041431 -403.911155) (xy 67.603921 -403.911155) (xy 67.596164 -403.965102)
			(xy 67.580807 -404.017398) (xy 67.558165 -404.066976) (xy 67.528697 -404.112828) (xy 67.493003 -404.154018)
			(xy 67.45181 -404.18971) (xy 67.405957 -404.219175) (xy 67.356377 -404.241815) (xy 67.30408 -404.257168)
			(xy 67.25013 -404.264922) (xy 67.222878 -404.265384) (xy 66.359278 -404.265384) (xy 66.332026 -404.264945)
			(xy 66.278077 -404.257185) (xy 66.225782 -404.241827) (xy 66.176204 -404.219183) (xy 66.130354 -404.189715)
			(xy 66.089164 -404.154021) (xy 66.053472 -404.112829) (xy 66.024006 -404.066976) (xy 66.001365 -404.017397)
			(xy 65.98601 -403.965101) (xy 65.978254 -403.911152) (xy 64.540597 -403.911152) (xy 64.532843 -403.965089)
			(xy 64.517491 -404.017377) (xy 64.494854 -404.066949) (xy 64.465393 -404.112794) (xy 64.429708 -404.153981)
			(xy 64.388525 -404.18967) (xy 64.342682 -404.219135) (xy 64.293113 -404.241777) (xy 64.240826 -404.257135)
			(xy 64.186886 -404.264895) (xy 64.159638 -404.265384) (xy 63.296038 -404.265384) (xy 63.268782 -404.264972)
			(xy 63.214823 -404.257219) (xy 63.162517 -404.241865) (xy 63.112929 -404.219223) (xy 63.067068 -404.189754)
			(xy 63.025869 -404.154058) (xy 62.990169 -404.112862) (xy 62.960695 -404.067004) (xy 62.938048 -404.017418)
			(xy 62.922689 -403.965114) (xy 62.914931 -403.911156) (xy 61.47742 -403.911156) (xy 61.469664 -403.965099)
			(xy 61.454309 -404.017394) (xy 61.431668 -404.066971) (xy 61.402201 -404.112821) (xy 61.36651 -404.154011)
			(xy 61.32532 -404.189703) (xy 61.279469 -404.219169) (xy 61.229892 -404.24181) (xy 61.177597 -404.257165)
			(xy 61.123649 -404.264921) (xy 61.096398 -404.265384) (xy 60.232798 -404.265384) (xy 60.205545 -404.264946)
			(xy 60.151594 -404.257189) (xy 60.099296 -404.241833) (xy 60.049716 -404.21919) (xy 60.003863 -404.189722)
			(xy 59.962671 -404.154028) (xy 59.926977 -404.112835) (xy 59.897509 -404.066982) (xy 59.874867 -404.017402)
			(xy 59.859511 -403.965104) (xy 59.851754 -403.911153) (xy 58.414221 -403.911153) (xy 58.406463 -403.965104)
			(xy 58.391106 -404.017402) (xy 58.368462 -404.066982) (xy 58.338992 -404.112834) (xy 58.303296 -404.154025)
			(xy 58.262101 -404.189717) (xy 58.216245 -404.219182) (xy 58.166663 -404.241821) (xy 58.114363 -404.257172)
			(xy 58.060411 -404.264924) (xy 58.033158 -404.265384) (xy 57.169558 -404.265384) (xy 57.142307 -404.264943)
			(xy 57.08836 -404.257181) (xy 57.036067 -404.241822) (xy 56.986492 -404.219177) (xy 56.940644 -404.189707)
			(xy 56.899457 -404.154014) (xy 56.863767 -404.112822) (xy 56.834303 -404.066971) (xy 56.811664 -404.017393)
			(xy 56.79631 -403.965098) (xy 56.788554 -403.911151) (xy 55.350898 -403.911151) (xy 55.343142 -403.965091)
			(xy 55.327789 -404.017381) (xy 55.305151 -404.066954) (xy 55.275688 -404.112801) (xy 55.240001 -404.153988)
			(xy 55.198815 -404.189677) (xy 55.15297 -404.219142) (xy 55.103398 -404.241783) (xy 55.051109 -404.257138)
			(xy 54.997167 -404.264897) (xy 54.969918 -404.265384) (xy 54.106318 -404.265384) (xy 54.079063 -404.26497)
			(xy 54.025106 -404.257215) (xy 53.972803 -404.241859) (xy 53.923217 -404.219217) (xy 53.877359 -404.189747)
			(xy 53.836162 -404.154051) (xy 53.800464 -404.112855) (xy 53.770992 -404.066999) (xy 53.748347 -404.017414)
			(xy 53.732989 -403.965111) (xy 53.725231 -403.911155) (xy 52.287721 -403.911155) (xy 52.279964 -403.965102)
			(xy 52.264607 -404.017398) (xy 52.241965 -404.066976) (xy 52.212497 -404.112828) (xy 52.176803 -404.154018)
			(xy 52.13561 -404.18971) (xy 52.089757 -404.219175) (xy 52.040177 -404.241815) (xy 51.98788 -404.257168)
			(xy 51.93393 -404.264922) (xy 51.906678 -404.265384) (xy 51.043078 -404.265384) (xy 51.015826 -404.264945)
			(xy 50.961877 -404.257185) (xy 50.909582 -404.241827) (xy 50.860004 -404.219183) (xy 50.814154 -404.189715)
			(xy 50.772964 -404.154021) (xy 50.737272 -404.112829) (xy 50.707806 -404.066976) (xy 50.685165 -404.017397)
			(xy 50.66981 -403.965101) (xy 50.662054 -403.911152) (xy 49.224397 -403.911152) (xy 49.216643 -403.965089)
			(xy 49.201291 -404.017377) (xy 49.178654 -404.066949) (xy 49.149193 -404.112794) (xy 49.113508 -404.153981)
			(xy 49.072325 -404.18967) (xy 49.026482 -404.219135) (xy 48.976913 -404.241777) (xy 48.924626 -404.257135)
			(xy 48.870686 -404.264895) (xy 48.843438 -404.265384) (xy 47.979838 -404.265384) (xy 47.952582 -404.264972)
			(xy 47.898623 -404.257219) (xy 47.846317 -404.241865) (xy 47.796729 -404.219223) (xy 47.750868 -404.189754)
			(xy 47.709669 -404.154058) (xy 47.673969 -404.112862) (xy 47.644495 -404.067004) (xy 47.621848 -404.017418)
			(xy 47.606489 -403.965114) (xy 47.598731 -403.911156) (xy 2.610452 -403.911156) (xy 2.622121 -403.942439)
			(xy 2.666338 -404.039266) (xy 2.717346 -404.132693) (xy 2.774884 -404.222247) (xy 2.838661 -404.307471)
			(xy 2.908351 -404.387931) (xy 2.945638 -404.425912) (xy 3.748786 -405.22906) (xy 102.242112 -405.22906)
			(xy 102.242112 -404.36546) (xy 102.242598 -404.338209) (xy 102.250354 -404.284261) (xy 102.265709 -404.231966)
			(xy 102.288351 -404.182389) (xy 102.317817 -404.136539) (xy 102.353508 -404.095348) (xy 102.394699 -404.059657)
			(xy 102.440549 -404.030191) (xy 102.490126 -404.007549) (xy 102.542421 -403.992194) (xy 102.596369 -403.984438)
			(xy 102.650871 -403.984438) (xy 102.704819 -403.992194) (xy 102.757114 -404.007549) (xy 102.806691 -404.030191)
			(xy 102.852541 -404.059657) (xy 102.893732 -404.095348) (xy 102.929423 -404.136539) (xy 102.958889 -404.182389)
			(xy 102.981531 -404.231966) (xy 102.996886 -404.284261) (xy 103.004642 -404.338209) (xy 103.005128 -404.36546)
			(xy 103.005128 -405.22906) (xy 103.004642 -405.256311) (xy 102.996886 -405.310259) (xy 102.981531 -405.362554)
			(xy 102.958889 -405.412131) (xy 102.929423 -405.457981) (xy 102.893732 -405.499172) (xy 102.852541 -405.534863)
			(xy 102.806691 -405.564329) (xy 102.757114 -405.586971) (xy 102.704819 -405.602326) (xy 102.650871 -405.610082)
			(xy 102.596369 -405.610082) (xy 102.542421 -405.602326) (xy 102.490126 -405.586971) (xy 102.440549 -405.564329)
			(xy 102.394699 -405.534863) (xy 102.353508 -405.499172) (xy 102.317817 -405.457981) (xy 102.288351 -405.412131)
			(xy 102.265709 -405.362554) (xy 102.250354 -405.310259) (xy 102.242598 -405.256311) (xy 102.242112 -405.22906)
			(xy 3.748786 -405.22906) (xy 5.555234 -407.035508) (xy 15.978632 -407.035508) (xy 15.978632 -406.171908)
			(xy 15.979118 -406.144657) (xy 15.986874 -406.090709) (xy 16.002229 -406.038414) (xy 16.024871 -405.988837)
			(xy 16.054337 -405.942987) (xy 16.090028 -405.901796) (xy 16.131219 -405.866105) (xy 16.177069 -405.836639)
			(xy 16.226646 -405.813997) (xy 16.278941 -405.798642) (xy 16.332889 -405.790886) (xy 16.387391 -405.790886)
			(xy 16.441339 -405.798642) (xy 16.493634 -405.813997) (xy 16.543211 -405.836639) (xy 16.589061 -405.866105)
			(xy 16.630252 -405.901796) (xy 16.665943 -405.942987) (xy 16.695409 -405.988837) (xy 16.718051 -406.038414)
			(xy 16.733406 -406.090709) (xy 16.741162 -406.144657) (xy 16.741648 -406.171908) (xy 16.741648 -407.031753)
			(xy 48.944975 -407.031753) (xy 48.944975 -406.977247) (xy 48.952733 -406.923295) (xy 48.96809 -406.870997)
			(xy 48.990734 -406.821417) (xy 49.020204 -406.775565) (xy 49.0559 -406.734373) (xy 49.097095 -406.698681)
			(xy 49.142951 -406.669216) (xy 49.192533 -406.646577) (xy 49.244833 -406.631225) (xy 49.298785 -406.623473)
			(xy 49.326038 -406.623012) (xy 50.189638 -406.623012) (xy 50.216889 -406.62346) (xy 50.270835 -406.631222)
			(xy 50.323128 -406.646581) (xy 50.372703 -406.669225) (xy 50.418551 -406.698694) (xy 50.459739 -406.734388)
			(xy 50.495428 -406.775579) (xy 50.524893 -406.82143) (xy 50.547532 -406.871007) (xy 50.562886 -406.923302)
			(xy 50.570642 -406.977249) (xy 50.570642 -407.031749) (xy 52.008298 -407.031749) (xy 52.008298 -406.977251)
			(xy 52.016054 -406.923308) (xy 52.031407 -406.871018) (xy 52.054045 -406.821445) (xy 52.083508 -406.775598)
			(xy 52.119195 -406.734411) (xy 52.16038 -406.698721) (xy 52.206226 -406.669256) (xy 52.255797 -406.646615)
			(xy 52.308087 -406.631258) (xy 52.362029 -406.6235) (xy 52.389278 -406.623012) (xy 53.252878 -406.623012)
			(xy 53.280133 -406.623433) (xy 53.33409 -406.631188) (xy 53.386393 -406.646543) (xy 53.435978 -406.669186)
			(xy 53.481837 -406.698655) (xy 53.523034 -406.73435) (xy 53.558732 -406.775546) (xy 53.588204 -406.821402)
			(xy 53.610849 -406.870987) (xy 53.626207 -406.923289) (xy 53.633965 -406.977245) (xy 53.633965 -407.031752)
			(xy 55.071475 -407.031752) (xy 55.071475 -406.977248) (xy 55.079232 -406.923298) (xy 55.094589 -406.871002)
			(xy 55.117231 -406.821423) (xy 55.146699 -406.775571) (xy 55.182393 -406.73438) (xy 55.223586 -406.698688)
			(xy 55.269439 -406.669222) (xy 55.319018 -406.646582) (xy 55.371316 -406.631229) (xy 55.425266 -406.623474)
			(xy 55.452518 -406.623012) (xy 56.316118 -406.623012) (xy 56.34337 -406.623459) (xy 56.397318 -406.631218)
			(xy 56.449614 -406.646576) (xy 56.499191 -406.669219) (xy 56.545042 -406.698687) (xy 56.586232 -406.734381)
			(xy 56.621924 -406.775573) (xy 56.65139 -406.821424) (xy 56.674031 -406.871003) (xy 56.689386 -406.923299)
			(xy 56.697142 -406.977248) (xy 56.697142 -407.031748) (xy 58.134798 -407.031748) (xy 58.134798 -406.977252)
			(xy 58.142553 -406.923311) (xy 58.157905 -406.871022) (xy 58.180542 -406.821451) (xy 58.210003 -406.775605)
			(xy 58.245688 -406.734418) (xy 58.286871 -406.698728) (xy 58.332714 -406.669262) (xy 58.382283 -406.64662)
			(xy 58.43457 -406.631262) (xy 58.48851 -406.623501) (xy 58.515758 -406.623012) (xy 59.379358 -406.623012)
			(xy 59.406614 -406.623432) (xy 59.460573 -406.631185) (xy 59.512878 -406.646538) (xy 59.562466 -406.669179)
			(xy 59.608327 -406.698648) (xy 59.649527 -406.734343) (xy 59.685227 -406.775539) (xy 59.714701 -406.821397)
			(xy 59.737348 -406.870982) (xy 59.752707 -406.923286) (xy 59.760465 -406.977244) (xy 59.760465 -407.03175)
			(xy 61.197998 -407.03175) (xy 61.197998 -406.97725) (xy 61.205754 -406.923306) (xy 61.221108 -406.871014)
			(xy 61.243748 -406.821439) (xy 61.273213 -406.775592) (xy 61.308902 -406.734404) (xy 61.35009 -406.698714)
			(xy 61.395938 -406.669249) (xy 61.445512 -406.646609) (xy 61.497804 -406.631255) (xy 61.551748 -406.623498)
			(xy 61.578998 -406.623012) (xy 62.442598 -406.623012) (xy 62.469852 -406.623435) (xy 62.523806 -406.631192)
			(xy 62.576107 -406.646549) (xy 62.62569 -406.669192) (xy 62.671546 -406.698662) (xy 62.712741 -406.734357)
			(xy 62.748437 -406.775552) (xy 62.777907 -406.821408) (xy 62.800551 -406.870991) (xy 62.815908 -406.923292)
			(xy 62.823665 -406.977246) (xy 62.823665 -407.031753) (xy 64.261175 -407.031753) (xy 64.261175 -406.977247)
			(xy 64.268933 -406.923295) (xy 64.28429 -406.870997) (xy 64.306934 -406.821417) (xy 64.336404 -406.775565)
			(xy 64.3721 -406.734373) (xy 64.413295 -406.698681) (xy 64.459151 -406.669216) (xy 64.508733 -406.646577)
			(xy 64.561033 -406.631225) (xy 64.614985 -406.623473) (xy 64.642238 -406.623012) (xy 65.505838 -406.623012)
			(xy 65.533089 -406.62346) (xy 65.587035 -406.631222) (xy 65.639328 -406.646581) (xy 65.688903 -406.669225)
			(xy 65.734751 -406.698694) (xy 65.775939 -406.734388) (xy 65.811628 -406.775579) (xy 65.841093 -406.82143)
			(xy 65.863732 -406.871007) (xy 65.879086 -406.923302) (xy 65.886842 -406.977249) (xy 65.886842 -407.031749)
			(xy 67.324498 -407.031749) (xy 67.324498 -406.977251) (xy 67.332254 -406.923308) (xy 67.347607 -406.871018)
			(xy 67.370245 -406.821445) (xy 67.399708 -406.775598) (xy 67.435395 -406.734411) (xy 67.47658 -406.698721)
			(xy 67.522426 -406.669256) (xy 67.571997 -406.646615) (xy 67.624287 -406.631258) (xy 67.678229 -406.6235)
			(xy 67.705478 -406.623012) (xy 68.569078 -406.623012) (xy 68.596333 -406.623433) (xy 68.65029 -406.631188)
			(xy 68.702593 -406.646543) (xy 68.752178 -406.669186) (xy 68.798037 -406.698655) (xy 68.839234 -406.73435)
			(xy 68.874932 -406.775546) (xy 68.904404 -406.821402) (xy 68.927049 -406.870987) (xy 68.942407 -406.923289)
			(xy 68.950165 -406.977245) (xy 68.950165 -407.031752) (xy 70.387675 -407.031752) (xy 70.387675 -406.977248)
			(xy 70.395432 -406.923298) (xy 70.410789 -406.871002) (xy 70.433431 -406.821423) (xy 70.462899 -406.775571)
			(xy 70.498593 -406.73438) (xy 70.539786 -406.698688) (xy 70.585639 -406.669222) (xy 70.635218 -406.646582)
			(xy 70.687516 -406.631229) (xy 70.741466 -406.623474) (xy 70.768718 -406.623012) (xy 71.632318 -406.623012)
			(xy 71.65957 -406.623459) (xy 71.713518 -406.631218) (xy 71.765814 -406.646576) (xy 71.815391 -406.669219)
			(xy 71.861242 -406.698687) (xy 71.902432 -406.734381) (xy 71.938124 -406.775573) (xy 71.96759 -406.821424)
			(xy 71.990231 -406.871003) (xy 72.005586 -406.923299) (xy 72.013342 -406.977248) (xy 72.013342 -407.031748)
			(xy 73.450998 -407.031748) (xy 73.450998 -406.977252) (xy 73.458753 -406.923311) (xy 73.474105 -406.871022)
			(xy 73.496742 -406.821451) (xy 73.526203 -406.775605) (xy 73.561888 -406.734418) (xy 73.603071 -406.698728)
			(xy 73.648914 -406.669262) (xy 73.698483 -406.64662) (xy 73.75077 -406.631262) (xy 73.80471 -406.623501)
			(xy 73.831958 -406.623012) (xy 74.695558 -406.623012) (xy 74.722814 -406.623432) (xy 74.776773 -406.631185)
			(xy 74.829078 -406.646538) (xy 74.878666 -406.669179) (xy 74.924527 -406.698648) (xy 74.965727 -406.734343)
			(xy 75.001427 -406.775539) (xy 75.030901 -406.821397) (xy 75.053548 -406.870982) (xy 75.068907 -406.923286)
			(xy 75.076665 -406.977244) (xy 75.076665 -407.03175) (xy 76.514198 -407.03175) (xy 76.514198 -406.97725)
			(xy 76.521954 -406.923306) (xy 76.537308 -406.871014) (xy 76.559948 -406.821439) (xy 76.589413 -406.775592)
			(xy 76.625102 -406.734404) (xy 76.66629 -406.698714) (xy 76.712138 -406.669249) (xy 76.761712 -406.646609)
			(xy 76.814004 -406.631255) (xy 76.867948 -406.623498) (xy 76.895198 -406.623012) (xy 77.758798 -406.623012)
			(xy 77.786052 -406.623435) (xy 77.840006 -406.631192) (xy 77.892307 -406.646549) (xy 77.94189 -406.669192)
			(xy 77.987746 -406.698662) (xy 78.028941 -406.734357) (xy 78.064637 -406.775552) (xy 78.094107 -406.821408)
			(xy 78.116751 -406.870991) (xy 78.132108 -406.923292) (xy 78.139865 -406.977246) (xy 78.139865 -407.031753)
			(xy 79.577375 -407.031753) (xy 79.577375 -406.977247) (xy 79.585133 -406.923295) (xy 79.60049 -406.870997)
			(xy 79.623134 -406.821417) (xy 79.652604 -406.775565) (xy 79.6883 -406.734373) (xy 79.729495 -406.698681)
			(xy 79.775351 -406.669216) (xy 79.824933 -406.646577) (xy 79.877233 -406.631225) (xy 79.931185 -406.623473)
			(xy 79.958438 -406.623012) (xy 80.822038 -406.623012) (xy 80.849289 -406.62346) (xy 80.903235 -406.631222)
			(xy 80.955528 -406.646581) (xy 81.005103 -406.669225) (xy 81.050951 -406.698694) (xy 81.092139 -406.734388)
			(xy 81.127828 -406.775579) (xy 81.157293 -406.82143) (xy 81.179932 -406.871007) (xy 81.195286 -406.923302)
			(xy 81.203042 -406.977249) (xy 81.203042 -407.031749) (xy 82.640698 -407.031749) (xy 82.640698 -406.977251)
			(xy 82.648454 -406.923308) (xy 82.663807 -406.871018) (xy 82.686445 -406.821445) (xy 82.715908 -406.775598)
			(xy 82.751595 -406.734411) (xy 82.79278 -406.698721) (xy 82.838626 -406.669256) (xy 82.888197 -406.646615)
			(xy 82.940487 -406.631258) (xy 82.994429 -406.6235) (xy 83.021678 -406.623012) (xy 83.885278 -406.623012)
			(xy 83.912533 -406.623433) (xy 83.96649 -406.631188) (xy 84.018793 -406.646543) (xy 84.068378 -406.669186)
			(xy 84.114237 -406.698655) (xy 84.155434 -406.73435) (xy 84.191132 -406.775546) (xy 84.220604 -406.821402)
			(xy 84.243249 -406.870987) (xy 84.258607 -406.923289) (xy 84.266365 -406.977245) (xy 84.266365 -407.031752)
			(xy 85.703875 -407.031752) (xy 85.703875 -406.977248) (xy 85.711632 -406.923298) (xy 85.726989 -406.871002)
			(xy 85.749631 -406.821423) (xy 85.779099 -406.775571) (xy 85.814793 -406.73438) (xy 85.855986 -406.698688)
			(xy 85.901839 -406.669222) (xy 85.951418 -406.646582) (xy 86.003716 -406.631229) (xy 86.057666 -406.623474)
			(xy 86.084918 -406.623012) (xy 86.948518 -406.623012) (xy 86.97577 -406.623459) (xy 87.029718 -406.631218)
			(xy 87.082014 -406.646576) (xy 87.131591 -406.669219) (xy 87.177442 -406.698687) (xy 87.218632 -406.734381)
			(xy 87.254324 -406.775573) (xy 87.28379 -406.821424) (xy 87.306431 -406.871003) (xy 87.321786 -406.923299)
			(xy 87.329542 -406.977248) (xy 87.329542 -407.031748) (xy 88.767198 -407.031748) (xy 88.767198 -406.977252)
			(xy 88.774953 -406.923311) (xy 88.790305 -406.871022) (xy 88.812942 -406.821451) (xy 88.842403 -406.775605)
			(xy 88.878088 -406.734418) (xy 88.919271 -406.698728) (xy 88.965114 -406.669262) (xy 89.014683 -406.64662)
			(xy 89.06697 -406.631262) (xy 89.12091 -406.623501) (xy 89.148158 -406.623012) (xy 90.011758 -406.623012)
			(xy 90.039014 -406.623432) (xy 90.092973 -406.631185) (xy 90.145278 -406.646538) (xy 90.194866 -406.669179)
			(xy 90.240727 -406.698648) (xy 90.281927 -406.734343) (xy 90.317627 -406.775539) (xy 90.347101 -406.821397)
			(xy 90.369748 -406.870982) (xy 90.385107 -406.923286) (xy 90.392865 -406.977244) (xy 90.392865 -407.03175)
			(xy 91.830398 -407.03175) (xy 91.830398 -406.97725) (xy 91.838154 -406.923306) (xy 91.853508 -406.871014)
			(xy 91.876148 -406.821439) (xy 91.905613 -406.775592) (xy 91.941302 -406.734404) (xy 91.98249 -406.698714)
			(xy 92.028338 -406.669249) (xy 92.077912 -406.646609) (xy 92.130204 -406.631255) (xy 92.184148 -406.623498)
			(xy 92.211398 -406.623012) (xy 93.074998 -406.623012) (xy 93.102252 -406.623435) (xy 93.156206 -406.631192)
			(xy 93.208507 -406.646549) (xy 93.25809 -406.669192) (xy 93.303946 -406.698662) (xy 93.345141 -406.734357)
			(xy 93.380837 -406.775552) (xy 93.410307 -406.821408) (xy 93.432951 -406.870991) (xy 93.448308 -406.923292)
			(xy 93.456065 -406.977246) (xy 93.456065 -407.031753) (xy 94.893575 -407.031753) (xy 94.893575 -406.977247)
			(xy 94.901333 -406.923295) (xy 94.91669 -406.870997) (xy 94.939334 -406.821417) (xy 94.968804 -406.775565)
			(xy 95.0045 -406.734373) (xy 95.045695 -406.698681) (xy 95.091551 -406.669216) (xy 95.141133 -406.646577)
			(xy 95.193433 -406.631225) (xy 95.247385 -406.623473) (xy 95.274638 -406.623012) (xy 96.138238 -406.623012)
			(xy 96.165489 -406.62346) (xy 96.219435 -406.631222) (xy 96.271728 -406.646581) (xy 96.321303 -406.669225)
			(xy 96.367151 -406.698694) (xy 96.408339 -406.734388) (xy 96.444028 -406.775579) (xy 96.473493 -406.82143)
			(xy 96.496132 -406.871007) (xy 96.511486 -406.923302) (xy 96.519242 -406.977249) (xy 96.519242 -407.031751)
			(xy 96.511486 -407.085698) (xy 96.496132 -407.137993) (xy 96.495694 -407.138953) (xy 106.243063 -407.138953)
			(xy 106.243063 -407.084447) (xy 106.250821 -407.030495) (xy 106.266177 -406.978197) (xy 106.288821 -406.928617)
			(xy 106.31829 -406.882763) (xy 106.353985 -406.841571) (xy 106.395179 -406.805878) (xy 106.441034 -406.776411)
			(xy 106.490616 -406.75377) (xy 106.542915 -406.738416) (xy 106.596867 -406.730662) (xy 106.62412 -406.7302)
			(xy 107.48772 -406.7302) (xy 107.514971 -406.730671) (xy 107.568918 -406.73843) (xy 107.621211 -406.753787)
			(xy 107.670787 -406.77643) (xy 107.716636 -406.805898) (xy 107.757824 -406.84159) (xy 107.793514 -406.88278)
			(xy 107.82298 -406.928631) (xy 107.84562 -406.978208) (xy 107.860974 -407.030502) (xy 107.861153 -407.031748)
			(xy 121.120198 -407.031748) (xy 121.120198 -406.977252) (xy 121.127953 -406.923312) (xy 121.143305 -406.871023)
			(xy 121.165942 -406.821452) (xy 121.195402 -406.775606) (xy 121.231087 -406.734419) (xy 121.272269 -406.69873)
			(xy 121.318111 -406.669264) (xy 121.36768 -406.646621) (xy 121.419967 -406.631263) (xy 121.473906 -406.623501)
			(xy 121.501154 -406.623012) (xy 122.364754 -406.623012) (xy 122.39201 -406.623432) (xy 122.445969 -406.631184)
			(xy 122.498275 -406.646537) (xy 122.547864 -406.669178) (xy 122.593725 -406.698646) (xy 122.634926 -406.734342)
			(xy 122.670626 -406.775538) (xy 122.7001 -406.821396) (xy 122.722747 -406.870981) (xy 122.738106 -406.923286)
			(xy 122.745865 -406.977244) (xy 122.745865 -407.03175) (xy 124.183398 -407.03175) (xy 124.183398 -406.97725)
			(xy 124.191154 -406.923306) (xy 124.206508 -406.871015) (xy 124.229148 -406.821441) (xy 124.258612 -406.775593)
			(xy 124.294301 -406.734405) (xy 124.335488 -406.698715) (xy 124.381335 -406.669251) (xy 124.430909 -406.64661)
			(xy 124.4832 -406.631255) (xy 124.537144 -406.623499) (xy 124.564394 -406.623012) (xy 125.427994 -406.623012)
			(xy 125.455249 -406.623434) (xy 125.509203 -406.631191) (xy 125.561504 -406.646548) (xy 125.611088 -406.669191)
			(xy 125.656944 -406.69866) (xy 125.69814 -406.734356) (xy 125.733836 -406.775551) (xy 125.763306 -406.821407)
			(xy 125.78595 -406.87099) (xy 125.801308 -406.923291) (xy 125.809065 -406.977245) (xy 125.809065 -407.031753)
			(xy 127.246575 -407.031753) (xy 127.246575 -406.977247) (xy 127.254333 -406.923296) (xy 127.26969 -406.870998)
			(xy 127.292334 -406.821418) (xy 127.321803 -406.775566) (xy 127.357499 -406.734375) (xy 127.398693 -406.698683)
			(xy 127.444548 -406.669217) (xy 127.49413 -406.646578) (xy 127.546429 -406.631226) (xy 127.600381 -406.623473)
			(xy 127.627634 -406.623012) (xy 128.491234 -406.623012) (xy 128.518485 -406.62346) (xy 128.572432 -406.631221)
			(xy 128.624725 -406.64658) (xy 128.674301 -406.669224) (xy 128.720149 -406.698693) (xy 128.761338 -406.734386)
			(xy 128.797028 -406.775578) (xy 128.826492 -406.821429) (xy 128.849132 -406.871007) (xy 128.864486 -406.923301)
			(xy 128.872242 -406.977249) (xy 128.872242 -407.031749) (xy 130.309898 -407.031749) (xy 130.309898 -406.977251)
			(xy 130.317654 -406.923309) (xy 130.333007 -406.871019) (xy 130.355645 -406.821446) (xy 130.385107 -406.775599)
			(xy 130.420794 -406.734412) (xy 130.461979 -406.698722) (xy 130.507823 -406.669257) (xy 130.557395 -406.646616)
			(xy 130.609683 -406.631259) (xy 130.663625 -406.6235) (xy 130.690874 -406.623012) (xy 131.554474 -406.623012)
			(xy 131.58173 -406.623433) (xy 131.635686 -406.631187) (xy 131.68799 -406.646542) (xy 131.737576 -406.669184)
			(xy 131.783435 -406.698653) (xy 131.824633 -406.734349) (xy 131.860331 -406.775544) (xy 131.889803 -406.821401)
			(xy 131.912449 -406.870986) (xy 131.927807 -406.923288) (xy 131.935565 -406.977245) (xy 131.935565 -407.031752)
			(xy 133.373075 -407.031752) (xy 133.373075 -406.977248) (xy 133.380832 -406.923299) (xy 133.396188 -406.871002)
			(xy 133.418831 -406.821424) (xy 133.448298 -406.775573) (xy 133.483992 -406.734382) (xy 133.525184 -406.69869)
			(xy 133.571036 -406.669224) (xy 133.620616 -406.646583) (xy 133.672912 -406.631229) (xy 133.726862 -406.623474)
			(xy 133.754114 -406.623012) (xy 134.617714 -406.623012) (xy 134.644966 -406.623459) (xy 134.698915 -406.631217)
			(xy 134.751211 -406.646574) (xy 134.800789 -406.669218) (xy 134.84664 -406.698686) (xy 134.887831 -406.734379)
			(xy 134.923523 -406.775571) (xy 134.952989 -406.821423) (xy 134.97563 -406.871002) (xy 134.990986 -406.923299)
			(xy 134.998742 -406.977248) (xy 134.998742 -407.031748) (xy 136.436398 -407.031748) (xy 136.436398 -406.977252)
			(xy 136.444153 -406.923312) (xy 136.459505 -406.871023) (xy 136.482142 -406.821452) (xy 136.511602 -406.775606)
			(xy 136.547287 -406.734419) (xy 136.588469 -406.69873) (xy 136.634311 -406.669264) (xy 136.68388 -406.646621)
			(xy 136.736167 -406.631263) (xy 136.790106 -406.623501) (xy 136.817354 -406.623012) (xy 137.680954 -406.623012)
			(xy 137.70821 -406.623432) (xy 137.762169 -406.631184) (xy 137.814475 -406.646537) (xy 137.864064 -406.669178)
			(xy 137.909925 -406.698646) (xy 137.951126 -406.734342) (xy 137.986826 -406.775538) (xy 138.0163 -406.821396)
			(xy 138.038947 -406.870981) (xy 138.054306 -406.923286) (xy 138.062065 -406.977244) (xy 138.062065 -407.03175)
			(xy 139.499598 -407.03175) (xy 139.499598 -406.97725) (xy 139.507354 -406.923306) (xy 139.522708 -406.871015)
			(xy 139.545348 -406.821441) (xy 139.574812 -406.775593) (xy 139.610501 -406.734405) (xy 139.651688 -406.698715)
			(xy 139.697535 -406.669251) (xy 139.747109 -406.64661) (xy 139.7994 -406.631255) (xy 139.853344 -406.623499)
			(xy 139.880594 -406.623012) (xy 140.744194 -406.623012) (xy 140.771449 -406.623434) (xy 140.825403 -406.631191)
			(xy 140.877704 -406.646548) (xy 140.927288 -406.669191) (xy 140.973144 -406.69866) (xy 141.01434 -406.734356)
			(xy 141.050036 -406.775551) (xy 141.079506 -406.821407) (xy 141.10215 -406.87099) (xy 141.117508 -406.923291)
			(xy 141.125265 -406.977245) (xy 141.125265 -407.031753) (xy 142.562775 -407.031753) (xy 142.562775 -406.977247)
			(xy 142.570533 -406.923296) (xy 142.58589 -406.870998) (xy 142.608534 -406.821418) (xy 142.638003 -406.775566)
			(xy 142.673699 -406.734375) (xy 142.714893 -406.698683) (xy 142.760748 -406.669217) (xy 142.81033 -406.646578)
			(xy 142.862629 -406.631226) (xy 142.916581 -406.623473) (xy 142.943834 -406.623012) (xy 143.807434 -406.623012)
			(xy 143.834685 -406.62346) (xy 143.888632 -406.631221) (xy 143.940925 -406.64658) (xy 143.990501 -406.669224)
			(xy 144.036349 -406.698693) (xy 144.077538 -406.734386) (xy 144.113228 -406.775578) (xy 144.142692 -406.821429)
			(xy 144.165332 -406.871007) (xy 144.180686 -406.923301) (xy 144.188442 -406.977249) (xy 144.188442 -407.031749)
			(xy 145.626098 -407.031749) (xy 145.626098 -406.977251) (xy 145.633854 -406.923309) (xy 145.649207 -406.871019)
			(xy 145.671845 -406.821446) (xy 145.701307 -406.775599) (xy 145.736994 -406.734412) (xy 145.778179 -406.698722)
			(xy 145.824023 -406.669257) (xy 145.873595 -406.646616) (xy 145.925883 -406.631259) (xy 145.979825 -406.6235)
			(xy 146.007074 -406.623012) (xy 146.870674 -406.623012) (xy 146.89793 -406.623433) (xy 146.951886 -406.631187)
			(xy 147.00419 -406.646542) (xy 147.053776 -406.669184) (xy 147.099635 -406.698653) (xy 147.140833 -406.734349)
			(xy 147.176531 -406.775544) (xy 147.206003 -406.821401) (xy 147.228649 -406.870986) (xy 147.244007 -406.923288)
			(xy 147.251765 -406.977245) (xy 147.251765 -407.031752) (xy 148.689275 -407.031752) (xy 148.689275 -406.977248)
			(xy 148.697032 -406.923299) (xy 148.712388 -406.871002) (xy 148.735031 -406.821424) (xy 148.764498 -406.775573)
			(xy 148.800192 -406.734382) (xy 148.841384 -406.69869) (xy 148.887236 -406.669224) (xy 148.936816 -406.646583)
			(xy 148.989112 -406.631229) (xy 149.043062 -406.623474) (xy 149.070314 -406.623012) (xy 149.933914 -406.623012)
			(xy 149.961166 -406.623459) (xy 150.015115 -406.631217) (xy 150.067411 -406.646574) (xy 150.116989 -406.669218)
			(xy 150.16284 -406.698686) (xy 150.204031 -406.734379) (xy 150.239723 -406.775571) (xy 150.269189 -406.821423)
			(xy 150.29183 -406.871002) (xy 150.307186 -406.923299) (xy 150.314942 -406.977248) (xy 150.314942 -407.031748)
			(xy 151.752598 -407.031748) (xy 151.752598 -406.977252) (xy 151.760353 -406.923312) (xy 151.775705 -406.871023)
			(xy 151.798342 -406.821452) (xy 151.827802 -406.775606) (xy 151.863487 -406.734419) (xy 151.904669 -406.69873)
			(xy 151.950511 -406.669264) (xy 152.00008 -406.646621) (xy 152.052367 -406.631263) (xy 152.106306 -406.623501)
			(xy 152.133554 -406.623012) (xy 152.997154 -406.623012) (xy 153.02441 -406.623432) (xy 153.078369 -406.631184)
			(xy 153.130675 -406.646537) (xy 153.180264 -406.669178) (xy 153.226125 -406.698646) (xy 153.267326 -406.734342)
			(xy 153.303026 -406.775538) (xy 153.3325 -406.821396) (xy 153.355147 -406.870981) (xy 153.370506 -406.923286)
			(xy 153.378265 -406.977244) (xy 153.378265 -407.03175) (xy 154.815798 -407.03175) (xy 154.815798 -406.97725)
			(xy 154.823554 -406.923306) (xy 154.838908 -406.871015) (xy 154.861548 -406.821441) (xy 154.891012 -406.775593)
			(xy 154.926701 -406.734405) (xy 154.967888 -406.698715) (xy 155.013735 -406.669251) (xy 155.063309 -406.64661)
			(xy 155.1156 -406.631255) (xy 155.169544 -406.623499) (xy 155.196794 -406.623012) (xy 156.060394 -406.623012)
			(xy 156.087649 -406.623434) (xy 156.141603 -406.631191) (xy 156.193904 -406.646548) (xy 156.243488 -406.669191)
			(xy 156.289344 -406.69866) (xy 156.33054 -406.734356) (xy 156.366236 -406.775551) (xy 156.395706 -406.821407)
			(xy 156.41835 -406.87099) (xy 156.433708 -406.923291) (xy 156.441465 -406.977245) (xy 156.441465 -407.031753)
			(xy 157.878975 -407.031753) (xy 157.878975 -406.977247) (xy 157.886733 -406.923296) (xy 157.90209 -406.870998)
			(xy 157.924734 -406.821418) (xy 157.954203 -406.775566) (xy 157.989899 -406.734375) (xy 158.031093 -406.698683)
			(xy 158.076948 -406.669217) (xy 158.12653 -406.646578) (xy 158.178829 -406.631226) (xy 158.232781 -406.623473)
			(xy 158.260034 -406.623012) (xy 159.123634 -406.623012) (xy 159.150885 -406.62346) (xy 159.204832 -406.631221)
			(xy 159.257125 -406.64658) (xy 159.306701 -406.669224) (xy 159.352549 -406.698693) (xy 159.393738 -406.734386)
			(xy 159.429428 -406.775578) (xy 159.458892 -406.821429) (xy 159.481532 -406.871007) (xy 159.496886 -406.923301)
			(xy 159.504642 -406.977249) (xy 159.504642 -407.031749) (xy 160.942298 -407.031749) (xy 160.942298 -406.977251)
			(xy 160.950054 -406.923309) (xy 160.965407 -406.871019) (xy 160.988045 -406.821446) (xy 161.017507 -406.775599)
			(xy 161.053194 -406.734412) (xy 161.094379 -406.698722) (xy 161.140223 -406.669257) (xy 161.189795 -406.646616)
			(xy 161.242083 -406.631259) (xy 161.296025 -406.6235) (xy 161.323274 -406.623012) (xy 162.186874 -406.623012)
			(xy 162.21413 -406.623433) (xy 162.268086 -406.631187) (xy 162.32039 -406.646542) (xy 162.369976 -406.669184)
			(xy 162.415835 -406.698653) (xy 162.457033 -406.734349) (xy 162.492731 -406.775544) (xy 162.522203 -406.821401)
			(xy 162.544849 -406.870986) (xy 162.560207 -406.923288) (xy 162.567965 -406.977245) (xy 162.567965 -407.031752)
			(xy 164.005475 -407.031752) (xy 164.005475 -406.977248) (xy 164.013232 -406.923299) (xy 164.028588 -406.871002)
			(xy 164.051231 -406.821424) (xy 164.080698 -406.775573) (xy 164.116392 -406.734382) (xy 164.157584 -406.69869)
			(xy 164.203436 -406.669224) (xy 164.253016 -406.646583) (xy 164.305312 -406.631229) (xy 164.359262 -406.623474)
			(xy 164.386514 -406.623012) (xy 165.250114 -406.623012) (xy 165.277366 -406.623459) (xy 165.331315 -406.631217)
			(xy 165.383611 -406.646574) (xy 165.433189 -406.669218) (xy 165.47904 -406.698686) (xy 165.520231 -406.734379)
			(xy 165.555923 -406.775571) (xy 165.585389 -406.821423) (xy 165.60803 -406.871002) (xy 165.623386 -406.923299)
			(xy 165.631142 -406.977248) (xy 165.631142 -407.031748) (xy 167.068798 -407.031748) (xy 167.068798 -406.977252)
			(xy 167.076553 -406.923312) (xy 167.091905 -406.871023) (xy 167.114542 -406.821452) (xy 167.144002 -406.775606)
			(xy 167.179687 -406.734419) (xy 167.220869 -406.69873) (xy 167.266711 -406.669264) (xy 167.31628 -406.646621)
			(xy 167.368567 -406.631263) (xy 167.422506 -406.623501) (xy 167.449754 -406.623012) (xy 168.313354 -406.623012)
			(xy 168.34061 -406.623432) (xy 168.394569 -406.631184) (xy 168.446875 -406.646537) (xy 168.496464 -406.669178)
			(xy 168.542325 -406.698646) (xy 168.583526 -406.734342) (xy 168.619226 -406.775538) (xy 168.6487 -406.821396)
			(xy 168.671347 -406.870981) (xy 168.686706 -406.923286) (xy 168.694465 -406.977244) (xy 168.694465 -407.031749)
			(xy 304.945298 -407.031749) (xy 304.945298 -406.977251) (xy 304.953054 -406.923307) (xy 304.968408 -406.871016)
			(xy 304.991047 -406.821442) (xy 305.02051 -406.775595) (xy 305.056199 -406.734407) (xy 305.097385 -406.698718)
			(xy 305.143232 -406.669252) (xy 305.192805 -406.646612) (xy 305.245095 -406.631257) (xy 305.299039 -406.623499)
			(xy 305.326288 -406.623012) (xy 306.189888 -406.623012) (xy 306.217143 -406.623434) (xy 306.271098 -406.63119)
			(xy 306.3234 -406.646546) (xy 306.372984 -406.669189) (xy 306.418841 -406.698658) (xy 306.460038 -406.734354)
			(xy 306.495735 -406.775549) (xy 306.525205 -406.821405) (xy 306.54785 -406.870989) (xy 306.563207 -406.92329)
			(xy 306.570965 -406.977245) (xy 306.570965 -407.031753) (xy 308.008475 -407.031753) (xy 308.008475 -406.977247)
			(xy 308.016233 -406.923297) (xy 308.031589 -406.870999) (xy 308.054233 -406.82142) (xy 308.083702 -406.775568)
			(xy 308.119397 -406.734377) (xy 308.16059 -406.698685) (xy 308.206445 -406.669219) (xy 308.256026 -406.64658)
			(xy 308.308324 -406.631227) (xy 308.362275 -406.623473) (xy 308.389528 -406.623012) (xy 309.253128 -406.623012)
			(xy 309.280379 -406.62346) (xy 309.334327 -406.63122) (xy 309.386621 -406.646578) (xy 309.436197 -406.669222)
			(xy 309.482047 -406.698691) (xy 309.523236 -406.734384) (xy 309.558926 -406.775576) (xy 309.588391 -406.821427)
			(xy 309.611032 -406.871005) (xy 309.626386 -406.923301) (xy 309.634142 -406.977249) (xy 309.634142 -407.031748)
			(xy 311.071798 -407.031748) (xy 311.071798 -406.977252) (xy 311.079553 -406.92331) (xy 311.094906 -406.87102)
			(xy 311.117544 -406.821448) (xy 311.147005 -406.775601) (xy 311.182692 -406.734414) (xy 311.223876 -406.698725)
			(xy 311.26972 -406.669259) (xy 311.31929 -406.646617) (xy 311.371578 -406.63126) (xy 311.42552 -406.6235)
			(xy 311.452768 -406.623012) (xy 312.316368 -406.623012) (xy 312.343624 -406.623433) (xy 312.397581 -406.631186)
			(xy 312.449886 -406.64654) (xy 312.499472 -406.669182) (xy 312.545332 -406.698651) (xy 312.586531 -406.734347)
			(xy 312.62223 -406.775542) (xy 312.651702 -406.821399) (xy 312.674348 -406.870984) (xy 312.689707 -406.923288)
			(xy 312.697465 -406.977244) (xy 312.697465 -407.031752) (xy 314.134975 -407.031752) (xy 314.134975 -406.977248)
			(xy 314.142732 -406.923299) (xy 314.158088 -406.871004) (xy 314.18073 -406.821426) (xy 314.210197 -406.775575)
			(xy 314.245889 -406.734384) (xy 314.287081 -406.698692) (xy 314.332933 -406.669226) (xy 314.382511 -406.646585)
			(xy 314.434807 -406.63123) (xy 314.488756 -406.623475) (xy 314.516008 -406.623012) (xy 315.379608 -406.623012)
			(xy 315.40686 -406.623458) (xy 315.46081 -406.631216) (xy 315.513107 -406.646573) (xy 315.562685 -406.669216)
			(xy 315.608537 -406.698684) (xy 315.649729 -406.734377) (xy 315.685421 -406.775569) (xy 315.714888 -406.821422)
			(xy 315.73753 -406.871001) (xy 315.752885 -406.923298) (xy 315.760642 -406.977248) (xy 315.760642 -407.031752)
			(xy 315.760642 -407.031754) (xy 317.198175 -407.031754) (xy 317.198175 -406.977246) (xy 317.205933 -406.923294)
			(xy 317.221291 -406.870995) (xy 317.243936 -406.821414) (xy 317.273407 -406.775561) (xy 317.309104 -406.73437)
			(xy 317.3503 -406.698678) (xy 317.396157 -406.669213) (xy 317.44574 -406.646574) (xy 317.498041 -406.631223)
			(xy 317.551994 -406.623472) (xy 317.579248 -406.623012) (xy 318.442848 -406.623012) (xy 318.470098 -406.623461)
			(xy 318.524044 -406.631224) (xy 318.576336 -406.646584) (xy 318.625909 -406.669229) (xy 318.671756 -406.698698)
			(xy 318.712943 -406.734391) (xy 318.748631 -406.775582) (xy 318.778094 -406.821433) (xy 318.800733 -406.87101)
			(xy 318.816087 -406.923303) (xy 318.823842 -406.97725) (xy 318.823842 -407.031749) (xy 320.261498 -407.031749)
			(xy 320.261498 -406.977251) (xy 320.269254 -406.923307) (xy 320.284608 -406.871016) (xy 320.307247 -406.821442)
			(xy 320.33671 -406.775595) (xy 320.372399 -406.734407) (xy 320.413585 -406.698718) (xy 320.459432 -406.669252)
			(xy 320.509005 -406.646612) (xy 320.561295 -406.631257) (xy 320.615239 -406.623499) (xy 320.642488 -406.623012)
			(xy 321.506088 -406.623012) (xy 321.533343 -406.623434) (xy 321.587298 -406.63119) (xy 321.6396 -406.646546)
			(xy 321.689184 -406.669189) (xy 321.735041 -406.698658) (xy 321.776238 -406.734354) (xy 321.811935 -406.775549)
			(xy 321.841405 -406.821405) (xy 321.86405 -406.870989) (xy 321.879407 -406.92329) (xy 321.887165 -406.977245)
			(xy 321.887165 -407.031753) (xy 323.324675 -407.031753) (xy 323.324675 -406.977247) (xy 323.332433 -406.923297)
			(xy 323.347789 -406.870999) (xy 323.370433 -406.82142) (xy 323.399902 -406.775568) (xy 323.435597 -406.734377)
			(xy 323.47679 -406.698685) (xy 323.522645 -406.669219) (xy 323.572226 -406.64658) (xy 323.624524 -406.631227)
			(xy 323.678475 -406.623473) (xy 323.705728 -406.623012) (xy 324.569328 -406.623012) (xy 324.596579 -406.62346)
			(xy 324.650527 -406.63122) (xy 324.702821 -406.646578) (xy 324.752397 -406.669222) (xy 324.798247 -406.698691)
			(xy 324.839436 -406.734384) (xy 324.875126 -406.775576) (xy 324.904591 -406.821427) (xy 324.927232 -406.871005)
			(xy 324.942586 -406.923301) (xy 324.950342 -406.977249) (xy 324.950342 -407.031748) (xy 326.387998 -407.031748)
			(xy 326.387998 -406.977252) (xy 326.395753 -406.92331) (xy 326.411106 -406.87102) (xy 326.433744 -406.821448)
			(xy 326.463205 -406.775601) (xy 326.498892 -406.734414) (xy 326.540076 -406.698725) (xy 326.58592 -406.669259)
			(xy 326.63549 -406.646617) (xy 326.687778 -406.63126) (xy 326.74172 -406.6235) (xy 326.768968 -406.623012)
			(xy 327.632568 -406.623012) (xy 327.659824 -406.623433) (xy 327.713781 -406.631186) (xy 327.766086 -406.64654)
			(xy 327.815672 -406.669182) (xy 327.861532 -406.698651) (xy 327.902731 -406.734347) (xy 327.93843 -406.775542)
			(xy 327.967902 -406.821399) (xy 327.990548 -406.870984) (xy 328.005907 -406.923288) (xy 328.013665 -406.977244)
			(xy 328.013665 -407.031752) (xy 329.451175 -407.031752) (xy 329.451175 -406.977248) (xy 329.458932 -406.923299)
			(xy 329.474288 -406.871004) (xy 329.49693 -406.821426) (xy 329.526397 -406.775575) (xy 329.562089 -406.734384)
			(xy 329.603281 -406.698692) (xy 329.649133 -406.669226) (xy 329.698711 -406.646585) (xy 329.751007 -406.63123)
			(xy 329.804956 -406.623475) (xy 329.832208 -406.623012) (xy 330.695808 -406.623012) (xy 330.72306 -406.623458)
			(xy 330.77701 -406.631216) (xy 330.829307 -406.646573) (xy 330.878885 -406.669216) (xy 330.924737 -406.698684)
			(xy 330.965929 -406.734377) (xy 331.001621 -406.775569) (xy 331.031088 -406.821422) (xy 331.05373 -406.871001)
			(xy 331.069085 -406.923298) (xy 331.076842 -406.977248) (xy 331.076842 -407.031752) (xy 331.076842 -407.031754)
			(xy 332.514375 -407.031754) (xy 332.514375 -406.977246) (xy 332.522133 -406.923294) (xy 332.537491 -406.870995)
			(xy 332.560136 -406.821414) (xy 332.589607 -406.775561) (xy 332.625304 -406.73437) (xy 332.6665 -406.698678)
			(xy 332.712357 -406.669213) (xy 332.76194 -406.646574) (xy 332.814241 -406.631223) (xy 332.868194 -406.623472)
			(xy 332.895448 -406.623012) (xy 333.759048 -406.623012) (xy 333.786298 -406.623461) (xy 333.840244 -406.631224)
			(xy 333.892536 -406.646584) (xy 333.942109 -406.669229) (xy 333.987956 -406.698698) (xy 334.029143 -406.734391)
			(xy 334.064831 -406.775582) (xy 334.094294 -406.821433) (xy 334.116933 -406.87101) (xy 334.132287 -406.923303)
			(xy 334.140042 -406.97725) (xy 334.140042 -407.031749) (xy 335.577698 -407.031749) (xy 335.577698 -406.977251)
			(xy 335.585454 -406.923307) (xy 335.600808 -406.871016) (xy 335.623447 -406.821442) (xy 335.65291 -406.775595)
			(xy 335.688599 -406.734407) (xy 335.729785 -406.698718) (xy 335.775632 -406.669252) (xy 335.825205 -406.646612)
			(xy 335.877495 -406.631257) (xy 335.931439 -406.623499) (xy 335.958688 -406.623012) (xy 336.822288 -406.623012)
			(xy 336.849543 -406.623434) (xy 336.903498 -406.63119) (xy 336.9558 -406.646546) (xy 337.005384 -406.669189)
			(xy 337.051241 -406.698658) (xy 337.092438 -406.734354) (xy 337.128135 -406.775549) (xy 337.157605 -406.821405)
			(xy 337.18025 -406.870989) (xy 337.195607 -406.92329) (xy 337.203365 -406.977245) (xy 337.203365 -407.031753)
			(xy 338.640875 -407.031753) (xy 338.640875 -406.977247) (xy 338.648633 -406.923297) (xy 338.663989 -406.870999)
			(xy 338.686633 -406.82142) (xy 338.716102 -406.775568) (xy 338.751797 -406.734377) (xy 338.79299 -406.698685)
			(xy 338.838845 -406.669219) (xy 338.888426 -406.64658) (xy 338.940724 -406.631227) (xy 338.994675 -406.623473)
			(xy 339.021928 -406.623012) (xy 339.885528 -406.623012) (xy 339.912779 -406.62346) (xy 339.966727 -406.63122)
			(xy 340.019021 -406.646578) (xy 340.068597 -406.669222) (xy 340.114447 -406.698691) (xy 340.155636 -406.734384)
			(xy 340.191326 -406.775576) (xy 340.220791 -406.821427) (xy 340.243432 -406.871005) (xy 340.258786 -406.923301)
			(xy 340.266542 -406.977249) (xy 340.266542 -407.031748) (xy 341.704198 -407.031748) (xy 341.704198 -406.977252)
			(xy 341.711953 -406.92331) (xy 341.727306 -406.87102) (xy 341.749944 -406.821448) (xy 341.779405 -406.775601)
			(xy 341.815092 -406.734414) (xy 341.856276 -406.698725) (xy 341.90212 -406.669259) (xy 341.95169 -406.646617)
			(xy 342.003978 -406.63126) (xy 342.05792 -406.6235) (xy 342.085168 -406.623012) (xy 342.948768 -406.623012)
			(xy 342.976024 -406.623433) (xy 343.029981 -406.631186) (xy 343.082286 -406.64654) (xy 343.131872 -406.669182)
			(xy 343.177732 -406.698651) (xy 343.218931 -406.734347) (xy 343.25463 -406.775542) (xy 343.284102 -406.821399)
			(xy 343.306748 -406.870984) (xy 343.322107 -406.923288) (xy 343.329865 -406.977244) (xy 343.329865 -407.031752)
			(xy 344.767375 -407.031752) (xy 344.767375 -406.977248) (xy 344.775132 -406.923299) (xy 344.790488 -406.871004)
			(xy 344.81313 -406.821426) (xy 344.842597 -406.775575) (xy 344.878289 -406.734384) (xy 344.919481 -406.698692)
			(xy 344.965333 -406.669226) (xy 345.014911 -406.646585) (xy 345.067207 -406.63123) (xy 345.121156 -406.623475)
			(xy 345.148408 -406.623012) (xy 346.012008 -406.623012) (xy 346.03926 -406.623458) (xy 346.09321 -406.631216)
			(xy 346.145507 -406.646573) (xy 346.195085 -406.669216) (xy 346.240937 -406.698684) (xy 346.282129 -406.734377)
			(xy 346.317821 -406.775569) (xy 346.347288 -406.821422) (xy 346.36993 -406.871001) (xy 346.385285 -406.923298)
			(xy 346.393042 -406.977248) (xy 346.393042 -407.031752) (xy 346.393042 -407.031754) (xy 347.830575 -407.031754)
			(xy 347.830575 -406.977246) (xy 347.838333 -406.923294) (xy 347.853691 -406.870995) (xy 347.876336 -406.821414)
			(xy 347.905807 -406.775561) (xy 347.941504 -406.73437) (xy 347.9827 -406.698678) (xy 348.028557 -406.669213)
			(xy 348.07814 -406.646574) (xy 348.130441 -406.631223) (xy 348.184394 -406.623472) (xy 348.211648 -406.623012)
			(xy 349.075248 -406.623012) (xy 349.102498 -406.623461) (xy 349.156444 -406.631224) (xy 349.208736 -406.646584)
			(xy 349.258309 -406.669229) (xy 349.304156 -406.698698) (xy 349.345343 -406.734391) (xy 349.381031 -406.775582)
			(xy 349.410494 -406.821433) (xy 349.433133 -406.87101) (xy 349.448487 -406.923303) (xy 349.456242 -406.97725)
			(xy 349.456242 -407.031749) (xy 350.893898 -407.031749) (xy 350.893898 -406.977251) (xy 350.901654 -406.923307)
			(xy 350.917008 -406.871016) (xy 350.939647 -406.821442) (xy 350.96911 -406.775595) (xy 351.004799 -406.734407)
			(xy 351.045985 -406.698718) (xy 351.091832 -406.669252) (xy 351.141405 -406.646612) (xy 351.193695 -406.631257)
			(xy 351.247639 -406.623499) (xy 351.274888 -406.623012) (xy 352.138488 -406.623012) (xy 352.165743 -406.623434)
			(xy 352.219698 -406.63119) (xy 352.272 -406.646546) (xy 352.321584 -406.669189) (xy 352.367441 -406.698658)
			(xy 352.408638 -406.734354) (xy 352.444335 -406.775549) (xy 352.473805 -406.821405) (xy 352.49645 -406.870989)
			(xy 352.511807 -406.92329) (xy 352.519565 -406.977245) (xy 352.519565 -407.031753) (xy 372.388075 -407.031753)
			(xy 372.388075 -406.977247) (xy 372.395833 -406.923296) (xy 372.411189 -406.870999) (xy 372.433833 -406.821419)
			(xy 372.463302 -406.775567) (xy 372.498997 -406.734376) (xy 372.540191 -406.698684) (xy 372.586046 -406.669219)
			(xy 372.635627 -406.646579) (xy 372.687926 -406.631226) (xy 372.741877 -406.623473) (xy 372.76913 -406.623012)
			(xy 373.63273 -406.623012) (xy 373.659981 -406.62346) (xy 373.713929 -406.63122) (xy 373.766222 -406.646579)
			(xy 373.815799 -406.669223) (xy 373.861648 -406.698691) (xy 373.902836 -406.734385) (xy 373.938527 -406.775576)
			(xy 373.967992 -406.821428) (xy 373.990632 -406.871006) (xy 374.005986 -406.923301) (xy 374.013742 -406.977249)
			(xy 374.013742 -407.031748) (xy 375.451398 -407.031748) (xy 375.451398 -406.977252) (xy 375.459153 -406.923309)
			(xy 375.474506 -406.87102) (xy 375.497144 -406.821447) (xy 375.526606 -406.775601) (xy 375.562292 -406.734414)
			(xy 375.603477 -406.698724) (xy 375.649321 -406.669258) (xy 375.698892 -406.646617) (xy 375.75118 -406.63126)
			(xy 375.805122 -406.6235) (xy 375.83237 -406.623012) (xy 376.69597 -406.623012) (xy 376.723226 -406.623433)
			(xy 376.777183 -406.631187) (xy 376.829487 -406.646541) (xy 376.879074 -406.669183) (xy 376.924933 -406.698652)
			(xy 376.966131 -406.734347) (xy 377.00183 -406.775543) (xy 377.031303 -406.8214) (xy 377.053948 -406.870985)
			(xy 377.069307 -406.923288) (xy 377.077065 -406.977244) (xy 377.077065 -407.031752) (xy 378.514575 -407.031752)
			(xy 378.514575 -406.977248) (xy 378.522332 -406.923299) (xy 378.537688 -406.871003) (xy 378.56033 -406.821425)
			(xy 378.589797 -406.775574) (xy 378.62549 -406.734383) (xy 378.666682 -406.698691) (xy 378.712534 -406.669225)
			(xy 378.762113 -406.646584) (xy 378.814409 -406.63123) (xy 378.868358 -406.623475) (xy 378.89561 -406.623012)
			(xy 379.75921 -406.623012) (xy 379.786462 -406.623459) (xy 379.840412 -406.631217) (xy 379.892708 -406.646573)
			(xy 379.942287 -406.669216) (xy 379.988138 -406.698684) (xy 380.029329 -406.734378) (xy 380.065022 -406.77557)
			(xy 380.094489 -406.821422) (xy 380.11713 -406.871001) (xy 380.132486 -406.923298) (xy 380.140242 -406.977248)
			(xy 380.140242 -407.031748) (xy 381.577898 -407.031748) (xy 381.577898 -406.977252) (xy 381.585653 -406.923312)
			(xy 381.601005 -406.871024) (xy 381.623641 -406.821453) (xy 381.653101 -406.775607) (xy 381.688785 -406.734421)
			(xy 381.729967 -406.698731) (xy 381.775809 -406.669265) (xy 381.825377 -406.646622) (xy 381.877663 -406.631264)
			(xy 381.931603 -406.623502) (xy 381.95885 -406.623012) (xy 382.82245 -406.623012) (xy 382.849707 -406.623431)
			(xy 382.903666 -406.631183) (xy 382.955973 -406.646536) (xy 383.005562 -406.669176) (xy 383.051423 -406.698645)
			(xy 383.092624 -406.73434) (xy 383.128325 -406.775536) (xy 383.1578 -406.821394) (xy 383.180447 -406.870981)
			(xy 383.195806 -406.923285) (xy 383.203565 -406.977243) (xy 383.203565 -407.031749) (xy 384.641098 -407.031749)
			(xy 384.641098 -406.977251) (xy 384.648854 -406.923307) (xy 384.664208 -406.871016) (xy 384.686847 -406.821442)
			(xy 384.716311 -406.775594) (xy 384.751999 -406.734406) (xy 384.793186 -406.698717) (xy 384.839033 -406.669252)
			(xy 384.888606 -406.646611) (xy 384.940897 -406.631256) (xy 384.994841 -406.623499) (xy 385.02209 -406.623012)
			(xy 385.88569 -406.623012) (xy 385.912945 -406.623434) (xy 385.9669 -406.63119) (xy 386.019202 -406.646546)
			(xy 386.068786 -406.66919) (xy 386.114642 -406.698659) (xy 386.155838 -406.734354) (xy 386.191535 -406.77555)
			(xy 386.221006 -406.821406) (xy 386.24365 -406.870989) (xy 386.259007 -406.923291) (xy 386.266765 -406.977245)
			(xy 386.266765 -407.031753) (xy 387.704275 -407.031753) (xy 387.704275 -406.977247) (xy 387.712033 -406.923296)
			(xy 387.727389 -406.870999) (xy 387.750033 -406.821419) (xy 387.779502 -406.775567) (xy 387.815197 -406.734376)
			(xy 387.856391 -406.698684) (xy 387.902246 -406.669219) (xy 387.951827 -406.646579) (xy 388.004126 -406.631226)
			(xy 388.058077 -406.623473) (xy 388.08533 -406.623012) (xy 388.94893 -406.623012) (xy 388.976181 -406.62346)
			(xy 389.030129 -406.63122) (xy 389.082422 -406.646579) (xy 389.131999 -406.669223) (xy 389.177848 -406.698691)
			(xy 389.219036 -406.734385) (xy 389.254727 -406.775576) (xy 389.284192 -406.821428) (xy 389.306832 -406.871006)
			(xy 389.322186 -406.923301) (xy 389.329942 -406.977249) (xy 389.329942 -407.031748) (xy 390.767598 -407.031748)
			(xy 390.767598 -406.977252) (xy 390.775353 -406.923309) (xy 390.790706 -406.87102) (xy 390.813344 -406.821447)
			(xy 390.842806 -406.775601) (xy 390.878492 -406.734414) (xy 390.919677 -406.698724) (xy 390.965521 -406.669258)
			(xy 391.015092 -406.646617) (xy 391.06738 -406.63126) (xy 391.121322 -406.6235) (xy 391.14857 -406.623012)
			(xy 392.01217 -406.623012) (xy 392.039426 -406.623433) (xy 392.093383 -406.631187) (xy 392.145687 -406.646541)
			(xy 392.195274 -406.669183) (xy 392.241133 -406.698652) (xy 392.282331 -406.734347) (xy 392.31803 -406.775543)
			(xy 392.347503 -406.8214) (xy 392.370148 -406.870985) (xy 392.385507 -406.923288) (xy 392.393265 -406.977244)
			(xy 392.393265 -407.031752) (xy 393.830775 -407.031752) (xy 393.830775 -406.977248) (xy 393.838532 -406.923299)
			(xy 393.853888 -406.871003) (xy 393.87653 -406.821425) (xy 393.905997 -406.775574) (xy 393.94169 -406.734383)
			(xy 393.982882 -406.698691) (xy 394.028734 -406.669225) (xy 394.078313 -406.646584) (xy 394.130609 -406.63123)
			(xy 394.184558 -406.623475) (xy 394.21181 -406.623012) (xy 395.07541 -406.623012) (xy 395.102662 -406.623459)
			(xy 395.156612 -406.631217) (xy 395.208908 -406.646573) (xy 395.258487 -406.669216) (xy 395.304338 -406.698684)
			(xy 395.345529 -406.734378) (xy 395.381222 -406.77557) (xy 395.410689 -406.821422) (xy 395.43333 -406.871001)
			(xy 395.448686 -406.923298) (xy 395.456442 -406.977248) (xy 395.456442 -407.031748) (xy 396.894098 -407.031748)
			(xy 396.894098 -406.977252) (xy 396.901853 -406.923312) (xy 396.917205 -406.871024) (xy 396.939841 -406.821453)
			(xy 396.969301 -406.775607) (xy 397.004985 -406.734421) (xy 397.046167 -406.698731) (xy 397.092009 -406.669265)
			(xy 397.141577 -406.646622) (xy 397.193863 -406.631264) (xy 397.247803 -406.623502) (xy 397.27505 -406.623012)
			(xy 398.13865 -406.623012) (xy 398.165907 -406.623431) (xy 398.219866 -406.631183) (xy 398.272173 -406.646536)
			(xy 398.321762 -406.669176) (xy 398.367623 -406.698645) (xy 398.408824 -406.73434) (xy 398.444525 -406.775536)
			(xy 398.474 -406.821394) (xy 398.496647 -406.870981) (xy 398.512006 -406.923285) (xy 398.519765 -406.977243)
			(xy 398.519765 -407.031749) (xy 399.957298 -407.031749) (xy 399.957298 -406.977251) (xy 399.965054 -406.923307)
			(xy 399.980408 -406.871016) (xy 400.003047 -406.821442) (xy 400.032511 -406.775594) (xy 400.068199 -406.734406)
			(xy 400.109386 -406.698717) (xy 400.155233 -406.669252) (xy 400.204806 -406.646611) (xy 400.257097 -406.631256)
			(xy 400.311041 -406.623499) (xy 400.33829 -406.623012) (xy 401.20189 -406.623012) (xy 401.229145 -406.623434)
			(xy 401.2831 -406.63119) (xy 401.335402 -406.646546) (xy 401.384986 -406.66919) (xy 401.430842 -406.698659)
			(xy 401.472038 -406.734354) (xy 401.507735 -406.77555) (xy 401.537206 -406.821406) (xy 401.55985 -406.870989)
			(xy 401.575207 -406.923291) (xy 401.582965 -406.977245) (xy 401.582965 -407.031753) (xy 403.020475 -407.031753)
			(xy 403.020475 -406.977247) (xy 403.028233 -406.923296) (xy 403.043589 -406.870999) (xy 403.066233 -406.821419)
			(xy 403.095702 -406.775567) (xy 403.131397 -406.734376) (xy 403.172591 -406.698684) (xy 403.218446 -406.669219)
			(xy 403.268027 -406.646579) (xy 403.320326 -406.631226) (xy 403.374277 -406.623473) (xy 403.40153 -406.623012)
			(xy 404.26513 -406.623012) (xy 404.292381 -406.62346) (xy 404.346329 -406.63122) (xy 404.398622 -406.646579)
			(xy 404.448199 -406.669223) (xy 404.494048 -406.698691) (xy 404.535236 -406.734385) (xy 404.570927 -406.775576)
			(xy 404.600392 -406.821428) (xy 404.623032 -406.871006) (xy 404.638386 -406.923301) (xy 404.646142 -406.977249)
			(xy 404.646142 -407.031748) (xy 406.083798 -407.031748) (xy 406.083798 -406.977252) (xy 406.091553 -406.923309)
			(xy 406.106906 -406.87102) (xy 406.129544 -406.821447) (xy 406.159006 -406.775601) (xy 406.194692 -406.734414)
			(xy 406.235877 -406.698724) (xy 406.281721 -406.669258) (xy 406.331292 -406.646617) (xy 406.38358 -406.63126)
			(xy 406.437522 -406.6235) (xy 406.46477 -406.623012) (xy 407.32837 -406.623012) (xy 407.355626 -406.623433)
			(xy 407.409583 -406.631187) (xy 407.461887 -406.646541) (xy 407.511474 -406.669183) (xy 407.557333 -406.698652)
			(xy 407.598531 -406.734347) (xy 407.63423 -406.775543) (xy 407.663703 -406.8214) (xy 407.686348 -406.870985)
			(xy 407.701707 -406.923288) (xy 407.709465 -406.977244) (xy 407.709465 -407.031752) (xy 409.146975 -407.031752)
			(xy 409.146975 -406.977248) (xy 409.154732 -406.923299) (xy 409.170088 -406.871003) (xy 409.19273 -406.821425)
			(xy 409.222197 -406.775574) (xy 409.25789 -406.734383) (xy 409.299082 -406.698691) (xy 409.344934 -406.669225)
			(xy 409.394513 -406.646584) (xy 409.446809 -406.63123) (xy 409.500758 -406.623475) (xy 409.52801 -406.623012)
			(xy 410.39161 -406.623012) (xy 410.418862 -406.623459) (xy 410.472812 -406.631217) (xy 410.525108 -406.646573)
			(xy 410.574687 -406.669216) (xy 410.620538 -406.698684) (xy 410.661729 -406.734378) (xy 410.697422 -406.77557)
			(xy 410.726889 -406.821422) (xy 410.74953 -406.871001) (xy 410.764886 -406.923298) (xy 410.772642 -406.977248)
			(xy 410.772642 -407.031748) (xy 412.210298 -407.031748) (xy 412.210298 -406.977252) (xy 412.218053 -406.923312)
			(xy 412.233405 -406.871024) (xy 412.256041 -406.821453) (xy 412.285501 -406.775607) (xy 412.321185 -406.734421)
			(xy 412.362367 -406.698731) (xy 412.408209 -406.669265) (xy 412.457777 -406.646622) (xy 412.510063 -406.631264)
			(xy 412.564003 -406.623502) (xy 412.59125 -406.623012) (xy 413.45485 -406.623012) (xy 413.482107 -406.623431)
			(xy 413.536066 -406.631183) (xy 413.588373 -406.646536) (xy 413.637962 -406.669176) (xy 413.683823 -406.698645)
			(xy 413.725024 -406.73434) (xy 413.760725 -406.775536) (xy 413.7902 -406.821394) (xy 413.812847 -406.870981)
			(xy 413.828206 -406.923285) (xy 413.835965 -406.977243) (xy 413.835965 -407.031749) (xy 415.273498 -407.031749)
			(xy 415.273498 -406.977251) (xy 415.281254 -406.923307) (xy 415.296608 -406.871016) (xy 415.319247 -406.821442)
			(xy 415.348711 -406.775594) (xy 415.384399 -406.734406) (xy 415.425586 -406.698717) (xy 415.471433 -406.669252)
			(xy 415.521006 -406.646611) (xy 415.573297 -406.631256) (xy 415.627241 -406.623499) (xy 415.65449 -406.623012)
			(xy 416.51809 -406.623012) (xy 416.545345 -406.623434) (xy 416.5993 -406.63119) (xy 416.651602 -406.646546)
			(xy 416.701186 -406.66919) (xy 416.747042 -406.698659) (xy 416.788238 -406.734354) (xy 416.823935 -406.77555)
			(xy 416.853406 -406.821406) (xy 416.87605 -406.870989) (xy 416.891407 -406.923291) (xy 416.899165 -406.977245)
			(xy 416.899165 -407.031753) (xy 418.336675 -407.031753) (xy 418.336675 -406.977247) (xy 418.344433 -406.923296)
			(xy 418.359789 -406.870999) (xy 418.382433 -406.821419) (xy 418.411902 -406.775567) (xy 418.447597 -406.734376)
			(xy 418.488791 -406.698684) (xy 418.534646 -406.669219) (xy 418.584227 -406.646579) (xy 418.636526 -406.631226)
			(xy 418.690477 -406.623473) (xy 418.71773 -406.623012) (xy 419.58133 -406.623012) (xy 419.608581 -406.62346)
			(xy 419.662529 -406.63122) (xy 419.714822 -406.646579) (xy 419.764399 -406.669223) (xy 419.810248 -406.698691)
			(xy 419.851436 -406.734385) (xy 419.887127 -406.775576) (xy 419.916592 -406.821428) (xy 419.939232 -406.871006)
			(xy 419.954586 -406.923301) (xy 419.962342 -406.977249) (xy 419.962342 -407.031751) (xy 419.954586 -407.085699)
			(xy 419.939232 -407.137994) (xy 419.916592 -407.187572) (xy 419.887127 -407.233424) (xy 419.851436 -407.274615)
			(xy 419.810248 -407.310309) (xy 419.764399 -407.339777) (xy 419.714822 -407.362421) (xy 419.662529 -407.37778)
			(xy 419.608581 -407.38554) (xy 419.58133 -407.386028) (xy 418.71773 -407.386028) (xy 418.690477 -407.385527)
			(xy 418.636526 -407.377774) (xy 418.584227 -407.362421) (xy 418.534646 -407.339781) (xy 418.488791 -407.310316)
			(xy 418.447597 -407.274624) (xy 418.411902 -407.233433) (xy 418.382433 -407.187581) (xy 418.359789 -407.138001)
			(xy 418.344433 -407.085704) (xy 418.336675 -407.031753) (xy 416.899165 -407.031753) (xy 416.899165 -407.031755)
			(xy 416.891407 -407.085709) (xy 416.87605 -407.138011) (xy 416.853406 -407.187594) (xy 416.823935 -407.23345)
			(xy 416.788238 -407.274646) (xy 416.747042 -407.310341) (xy 416.701186 -407.33981) (xy 416.651602 -407.362454)
			(xy 416.5993 -407.37781) (xy 416.545345 -407.385566) (xy 416.51809 -407.386028) (xy 415.65449 -407.386028)
			(xy 415.627241 -407.385501) (xy 415.573297 -407.377744) (xy 415.521006 -407.362389) (xy 415.471433 -407.339748)
			(xy 415.425586 -407.310283) (xy 415.384399 -407.274594) (xy 415.348711 -407.233406) (xy 415.319247 -407.187558)
			(xy 415.296608 -407.137984) (xy 415.281254 -407.085693) (xy 415.273498 -407.031749) (xy 413.835965 -407.031749)
			(xy 413.835965 -407.031757) (xy 413.828206 -407.085715) (xy 413.812847 -407.138019) (xy 413.7902 -407.187606)
			(xy 413.760725 -407.233464) (xy 413.725024 -407.27466) (xy 413.683823 -407.310355) (xy 413.637962 -407.339824)
			(xy 413.588373 -407.362464) (xy 413.536066 -407.377817) (xy 413.482107 -407.385569) (xy 413.45485 -407.386028)
			(xy 412.59125 -407.386028) (xy 412.564003 -407.385498) (xy 412.510063 -407.377736) (xy 412.457777 -407.362378)
			(xy 412.408209 -407.339735) (xy 412.362367 -407.310269) (xy 412.321185 -407.274579) (xy 412.285501 -407.233393)
			(xy 412.256041 -407.187547) (xy 412.233405 -407.137976) (xy 412.218053 -407.085688) (xy 412.210298 -407.031748)
			(xy 410.772642 -407.031748) (xy 410.772642 -407.031752) (xy 410.764886 -407.085702) (xy 410.74953 -407.137999)
			(xy 410.726889 -407.187578) (xy 410.697422 -407.23343) (xy 410.661729 -407.274622) (xy 410.620538 -407.310316)
			(xy 410.574687 -407.339784) (xy 410.525108 -407.362427) (xy 410.472812 -407.377783) (xy 410.418862 -407.385541)
			(xy 410.39161 -407.386028) (xy 409.52801 -407.386028) (xy 409.500758 -407.385525) (xy 409.446809 -407.37777)
			(xy 409.394513 -407.362416) (xy 409.344934 -407.339775) (xy 409.299082 -407.310309) (xy 409.25789 -407.274617)
			(xy 409.222197 -407.233426) (xy 409.19273 -407.187575) (xy 409.170088 -407.137997) (xy 409.154732 -407.085701)
			(xy 409.146975 -407.031752) (xy 407.709465 -407.031752) (xy 407.709465 -407.031756) (xy 407.701707 -407.085712)
			(xy 407.686348 -407.138015) (xy 407.663703 -407.1876) (xy 407.63423 -407.233457) (xy 407.598531 -407.274653)
			(xy 407.557333 -407.310348) (xy 407.511474 -407.339817) (xy 407.461887 -407.362459) (xy 407.409583 -407.377813)
			(xy 407.355626 -407.385567) (xy 407.32837 -407.386028) (xy 406.46477 -407.386028) (xy 406.437522 -407.3855)
			(xy 406.38358 -407.37774) (xy 406.331292 -407.362383) (xy 406.281721 -407.339742) (xy 406.235877 -407.310276)
			(xy 406.194692 -407.274586) (xy 406.159006 -407.233399) (xy 406.129544 -407.187553) (xy 406.106906 -407.13798)
			(xy 406.091553 -407.085691) (xy 406.083798 -407.031748) (xy 404.646142 -407.031748) (xy 404.646142 -407.031751)
			(xy 404.638386 -407.085699) (xy 404.623032 -407.137994) (xy 404.600392 -407.187572) (xy 404.570927 -407.233424)
			(xy 404.535236 -407.274615) (xy 404.494048 -407.310309) (xy 404.448199 -407.339777) (xy 404.398622 -407.362421)
			(xy 404.346329 -407.37778) (xy 404.292381 -407.38554) (xy 404.26513 -407.386028) (xy 403.40153 -407.386028)
			(xy 403.374277 -407.385527) (xy 403.320326 -407.377774) (xy 403.268027 -407.362421) (xy 403.218446 -407.339781)
			(xy 403.172591 -407.310316) (xy 403.131397 -407.274624) (xy 403.095702 -407.233433) (xy 403.066233 -407.187581)
			(xy 403.043589 -407.138001) (xy 403.028233 -407.085704) (xy 403.020475 -407.031753) (xy 401.582965 -407.031753)
			(xy 401.582965 -407.031755) (xy 401.575207 -407.085709) (xy 401.55985 -407.138011) (xy 401.537206 -407.187594)
			(xy 401.507735 -407.23345) (xy 401.472038 -407.274646) (xy 401.430842 -407.310341) (xy 401.384986 -407.33981)
			(xy 401.335402 -407.362454) (xy 401.2831 -407.37781) (xy 401.229145 -407.385566) (xy 401.20189 -407.386028)
			(xy 400.33829 -407.386028) (xy 400.311041 -407.385501) (xy 400.257097 -407.377744) (xy 400.204806 -407.362389)
			(xy 400.155233 -407.339748) (xy 400.109386 -407.310283) (xy 400.068199 -407.274594) (xy 400.032511 -407.233406)
			(xy 400.003047 -407.187558) (xy 399.980408 -407.137984) (xy 399.965054 -407.085693) (xy 399.957298 -407.031749)
			(xy 398.519765 -407.031749) (xy 398.519765 -407.031757) (xy 398.512006 -407.085715) (xy 398.496647 -407.138019)
			(xy 398.474 -407.187606) (xy 398.444525 -407.233464) (xy 398.408824 -407.27466) (xy 398.367623 -407.310355)
			(xy 398.321762 -407.339824) (xy 398.272173 -407.362464) (xy 398.219866 -407.377817) (xy 398.165907 -407.385569)
			(xy 398.13865 -407.386028) (xy 397.27505 -407.386028) (xy 397.247803 -407.385498) (xy 397.193863 -407.377736)
			(xy 397.141577 -407.362378) (xy 397.092009 -407.339735) (xy 397.046167 -407.310269) (xy 397.004985 -407.274579)
			(xy 396.969301 -407.233393) (xy 396.939841 -407.187547) (xy 396.917205 -407.137976) (xy 396.901853 -407.085688)
			(xy 396.894098 -407.031748) (xy 395.456442 -407.031748) (xy 395.456442 -407.031752) (xy 395.448686 -407.085702)
			(xy 395.43333 -407.137999) (xy 395.410689 -407.187578) (xy 395.381222 -407.23343) (xy 395.345529 -407.274622)
			(xy 395.304338 -407.310316) (xy 395.258487 -407.339784) (xy 395.208908 -407.362427) (xy 395.156612 -407.377783)
			(xy 395.102662 -407.385541) (xy 395.07541 -407.386028) (xy 394.21181 -407.386028) (xy 394.184558 -407.385525)
			(xy 394.130609 -407.37777) (xy 394.078313 -407.362416) (xy 394.028734 -407.339775) (xy 393.982882 -407.310309)
			(xy 393.94169 -407.274617) (xy 393.905997 -407.233426) (xy 393.87653 -407.187575) (xy 393.853888 -407.137997)
			(xy 393.838532 -407.085701) (xy 393.830775 -407.031752) (xy 392.393265 -407.031752) (xy 392.393265 -407.031756)
			(xy 392.385507 -407.085712) (xy 392.370148 -407.138015) (xy 392.347503 -407.1876) (xy 392.31803 -407.233457)
			(xy 392.282331 -407.274653) (xy 392.241133 -407.310348) (xy 392.195274 -407.339817) (xy 392.145687 -407.362459)
			(xy 392.093383 -407.377813) (xy 392.039426 -407.385567) (xy 392.01217 -407.386028) (xy 391.14857 -407.386028)
			(xy 391.121322 -407.3855) (xy 391.06738 -407.37774) (xy 391.015092 -407.362383) (xy 390.965521 -407.339742)
			(xy 390.919677 -407.310276) (xy 390.878492 -407.274586) (xy 390.842806 -407.233399) (xy 390.813344 -407.187553)
			(xy 390.790706 -407.13798) (xy 390.775353 -407.085691) (xy 390.767598 -407.031748) (xy 389.329942 -407.031748)
			(xy 389.329942 -407.031751) (xy 389.322186 -407.085699) (xy 389.306832 -407.137994) (xy 389.284192 -407.187572)
			(xy 389.254727 -407.233424) (xy 389.219036 -407.274615) (xy 389.177848 -407.310309) (xy 389.131999 -407.339777)
			(xy 389.082422 -407.362421) (xy 389.030129 -407.37778) (xy 388.976181 -407.38554) (xy 388.94893 -407.386028)
			(xy 388.08533 -407.386028) (xy 388.058077 -407.385527) (xy 388.004126 -407.377774) (xy 387.951827 -407.362421)
			(xy 387.902246 -407.339781) (xy 387.856391 -407.310316) (xy 387.815197 -407.274624) (xy 387.779502 -407.233433)
			(xy 387.750033 -407.187581) (xy 387.727389 -407.138001) (xy 387.712033 -407.085704) (xy 387.704275 -407.031753)
			(xy 386.266765 -407.031753) (xy 386.266765 -407.031755) (xy 386.259007 -407.085709) (xy 386.24365 -407.138011)
			(xy 386.221006 -407.187594) (xy 386.191535 -407.23345) (xy 386.155838 -407.274646) (xy 386.114642 -407.310341)
			(xy 386.068786 -407.33981) (xy 386.019202 -407.362454) (xy 385.9669 -407.37781) (xy 385.912945 -407.385566)
			(xy 385.88569 -407.386028) (xy 385.02209 -407.386028) (xy 384.994841 -407.385501) (xy 384.940897 -407.377744)
			(xy 384.888606 -407.362389) (xy 384.839033 -407.339748) (xy 384.793186 -407.310283) (xy 384.751999 -407.274594)
			(xy 384.716311 -407.233406) (xy 384.686847 -407.187558) (xy 384.664208 -407.137984) (xy 384.648854 -407.085693)
			(xy 384.641098 -407.031749) (xy 383.203565 -407.031749) (xy 383.203565 -407.031757) (xy 383.195806 -407.085715)
			(xy 383.180447 -407.138019) (xy 383.1578 -407.187606) (xy 383.128325 -407.233464) (xy 383.092624 -407.27466)
			(xy 383.051423 -407.310355) (xy 383.005562 -407.339824) (xy 382.955973 -407.362464) (xy 382.903666 -407.377817)
			(xy 382.849707 -407.385569) (xy 382.82245 -407.386028) (xy 381.95885 -407.386028) (xy 381.931603 -407.385498)
			(xy 381.877663 -407.377736) (xy 381.825377 -407.362378) (xy 381.775809 -407.339735) (xy 381.729967 -407.310269)
			(xy 381.688785 -407.274579) (xy 381.653101 -407.233393) (xy 381.623641 -407.187547) (xy 381.601005 -407.137976)
			(xy 381.585653 -407.085688) (xy 381.577898 -407.031748) (xy 380.140242 -407.031748) (xy 380.140242 -407.031752)
			(xy 380.132486 -407.085702) (xy 380.11713 -407.137999) (xy 380.094489 -407.187578) (xy 380.065022 -407.23343)
			(xy 380.029329 -407.274622) (xy 379.988138 -407.310316) (xy 379.942287 -407.339784) (xy 379.892708 -407.362427)
			(xy 379.840412 -407.377783) (xy 379.786462 -407.385541) (xy 379.75921 -407.386028) (xy 378.89561 -407.386028)
			(xy 378.868358 -407.385525) (xy 378.814409 -407.37777) (xy 378.762113 -407.362416) (xy 378.712534 -407.339775)
			(xy 378.666682 -407.310309) (xy 378.62549 -407.274617) (xy 378.589797 -407.233426) (xy 378.56033 -407.187575)
			(xy 378.537688 -407.137997) (xy 378.522332 -407.085701) (xy 378.514575 -407.031752) (xy 377.077065 -407.031752)
			(xy 377.077065 -407.031756) (xy 377.069307 -407.085712) (xy 377.053948 -407.138015) (xy 377.031303 -407.1876)
			(xy 377.00183 -407.233457) (xy 376.966131 -407.274653) (xy 376.924933 -407.310348) (xy 376.879074 -407.339817)
			(xy 376.829487 -407.362459) (xy 376.777183 -407.377813) (xy 376.723226 -407.385567) (xy 376.69597 -407.386028)
			(xy 375.83237 -407.386028) (xy 375.805122 -407.3855) (xy 375.75118 -407.37774) (xy 375.698892 -407.362383)
			(xy 375.649321 -407.339742) (xy 375.603477 -407.310276) (xy 375.562292 -407.274586) (xy 375.526606 -407.233399)
			(xy 375.497144 -407.187553) (xy 375.474506 -407.13798) (xy 375.459153 -407.085691) (xy 375.451398 -407.031748)
			(xy 374.013742 -407.031748) (xy 374.013742 -407.031751) (xy 374.005986 -407.085699) (xy 373.990632 -407.137994)
			(xy 373.967992 -407.187572) (xy 373.938527 -407.233424) (xy 373.902836 -407.274615) (xy 373.861648 -407.310309)
			(xy 373.815799 -407.339777) (xy 373.766222 -407.362421) (xy 373.713929 -407.37778) (xy 373.659981 -407.38554)
			(xy 373.63273 -407.386028) (xy 372.76913 -407.386028) (xy 372.741877 -407.385527) (xy 372.687926 -407.377774)
			(xy 372.635627 -407.362421) (xy 372.586046 -407.339781) (xy 372.540191 -407.310316) (xy 372.498997 -407.274624)
			(xy 372.463302 -407.233433) (xy 372.433833 -407.187581) (xy 372.411189 -407.138001) (xy 372.395833 -407.085704)
			(xy 372.388075 -407.031753) (xy 352.519565 -407.031753) (xy 352.519565 -407.031755) (xy 352.511807 -407.08571)
			(xy 352.49645 -407.138011) (xy 352.473805 -407.187595) (xy 352.444335 -407.233451) (xy 352.408638 -407.274646)
			(xy 352.367441 -407.310342) (xy 352.321584 -407.339811) (xy 352.272 -407.362454) (xy 352.219698 -407.37781)
			(xy 352.165743 -407.385566) (xy 352.138488 -407.386028) (xy 351.274888 -407.386028) (xy 351.247639 -407.385501)
			(xy 351.193695 -407.377743) (xy 351.141405 -407.362388) (xy 351.091832 -407.339748) (xy 351.045985 -407.310282)
			(xy 351.004799 -407.274593) (xy 350.96911 -407.233405) (xy 350.939647 -407.187558) (xy 350.917008 -407.137984)
			(xy 350.901654 -407.085693) (xy 350.893898 -407.031749) (xy 349.456242 -407.031749) (xy 349.456242 -407.03175)
			(xy 349.448487 -407.085697) (xy 349.433133 -407.137991) (xy 349.410494 -407.187567) (xy 349.381031 -407.233418)
			(xy 349.345343 -407.274609) (xy 349.304156 -407.310302) (xy 349.258309 -407.339771) (xy 349.208736 -407.362416)
			(xy 349.156444 -407.377776) (xy 349.102498 -407.385539) (xy 349.075248 -407.386028) (xy 348.211648 -407.386028)
			(xy 348.184394 -407.385528) (xy 348.130441 -407.377777) (xy 348.07814 -407.362426) (xy 348.028557 -407.339787)
			(xy 347.9827 -407.310322) (xy 347.941504 -407.27463) (xy 347.905807 -407.233439) (xy 347.876336 -407.187586)
			(xy 347.853691 -407.138005) (xy 347.838333 -407.085706) (xy 347.830575 -407.031754) (xy 346.393042 -407.031754)
			(xy 346.385285 -407.085702) (xy 346.36993 -407.137999) (xy 346.347288 -407.187578) (xy 346.317821 -407.233431)
			(xy 346.282129 -407.274623) (xy 346.240937 -407.310316) (xy 346.195085 -407.339784) (xy 346.145507 -407.362427)
			(xy 346.09321 -407.377784) (xy 346.03926 -407.385542) (xy 346.012008 -407.386028) (xy 345.148408 -407.386028)
			(xy 345.121156 -407.385525) (xy 345.067207 -407.37777) (xy 345.014911 -407.362415) (xy 344.965333 -407.339774)
			(xy 344.919481 -407.310308) (xy 344.878289 -407.274616) (xy 344.842597 -407.233425) (xy 344.81313 -407.187574)
			(xy 344.790488 -407.137996) (xy 344.775132 -407.085701) (xy 344.767375 -407.031752) (xy 343.329865 -407.031752)
			(xy 343.329865 -407.031756) (xy 343.322107 -407.085712) (xy 343.306748 -407.138016) (xy 343.284102 -407.187601)
			(xy 343.25463 -407.233458) (xy 343.218931 -407.274653) (xy 343.177732 -407.310349) (xy 343.131872 -407.339818)
			(xy 343.082286 -407.36246) (xy 343.029981 -407.377814) (xy 342.976024 -407.385567) (xy 342.948768 -407.386028)
			(xy 342.085168 -407.386028) (xy 342.05792 -407.3855) (xy 342.003978 -407.37774) (xy 341.95169 -407.362383)
			(xy 341.90212 -407.339741) (xy 341.856276 -407.310275) (xy 341.815092 -407.274586) (xy 341.779405 -407.233399)
			(xy 341.749944 -407.187552) (xy 341.727306 -407.13798) (xy 341.711953 -407.08569) (xy 341.704198 -407.031748)
			(xy 340.266542 -407.031748) (xy 340.266542 -407.031751) (xy 340.258786 -407.0857) (xy 340.243432 -407.137995)
			(xy 340.220791 -407.187573) (xy 340.191326 -407.233424) (xy 340.155636 -407.274616) (xy 340.114447 -407.310309)
			(xy 340.068597 -407.339778) (xy 340.019021 -407.362422) (xy 339.966727 -407.37778) (xy 339.912779 -407.38554)
			(xy 339.885528 -407.386028) (xy 339.021928 -407.386028) (xy 338.994675 -407.385527) (xy 338.940724 -407.377773)
			(xy 338.888426 -407.36242) (xy 338.838845 -407.339781) (xy 338.79299 -407.310315) (xy 338.751797 -407.274623)
			(xy 338.716102 -407.233432) (xy 338.686633 -407.18758) (xy 338.663989 -407.138001) (xy 338.648633 -407.085703)
			(xy 338.640875 -407.031753) (xy 337.203365 -407.031753) (xy 337.203365 -407.031755) (xy 337.195607 -407.08571)
			(xy 337.18025 -407.138011) (xy 337.157605 -407.187595) (xy 337.128135 -407.233451) (xy 337.092438 -407.274646)
			(xy 337.051241 -407.310342) (xy 337.005384 -407.339811) (xy 336.9558 -407.362454) (xy 336.903498 -407.37781)
			(xy 336.849543 -407.385566) (xy 336.822288 -407.386028) (xy 335.958688 -407.386028) (xy 335.931439 -407.385501)
			(xy 335.877495 -407.377743) (xy 335.825205 -407.362388) (xy 335.775632 -407.339748) (xy 335.729785 -407.310282)
			(xy 335.688599 -407.274593) (xy 335.65291 -407.233405) (xy 335.623447 -407.187558) (xy 335.600808 -407.137984)
			(xy 335.585454 -407.085693) (xy 335.577698 -407.031749) (xy 334.140042 -407.031749) (xy 334.140042 -407.03175)
			(xy 334.132287 -407.085697) (xy 334.116933 -407.137991) (xy 334.094294 -407.187567) (xy 334.064831 -407.233418)
			(xy 334.029143 -407.274609) (xy 333.987956 -407.310302) (xy 333.942109 -407.339771) (xy 333.892536 -407.362416)
			(xy 333.840244 -407.377776) (xy 333.786298 -407.385539) (xy 333.759048 -407.386028) (xy 332.895448 -407.386028)
			(xy 332.868194 -407.385528) (xy 332.814241 -407.377777) (xy 332.76194 -407.362426) (xy 332.712357 -407.339787)
			(xy 332.6665 -407.310322) (xy 332.625304 -407.27463) (xy 332.589607 -407.233439) (xy 332.560136 -407.187586)
			(xy 332.537491 -407.138005) (xy 332.522133 -407.085706) (xy 332.514375 -407.031754) (xy 331.076842 -407.031754)
			(xy 331.069085 -407.085702) (xy 331.05373 -407.137999) (xy 331.031088 -407.187578) (xy 331.001621 -407.233431)
			(xy 330.965929 -407.274623) (xy 330.924737 -407.310316) (xy 330.878885 -407.339784) (xy 330.829307 -407.362427)
			(xy 330.77701 -407.377784) (xy 330.72306 -407.385542) (xy 330.695808 -407.386028) (xy 329.832208 -407.386028)
			(xy 329.804956 -407.385525) (xy 329.751007 -407.37777) (xy 329.698711 -407.362415) (xy 329.649133 -407.339774)
			(xy 329.603281 -407.310308) (xy 329.562089 -407.274616) (xy 329.526397 -407.233425) (xy 329.49693 -407.187574)
			(xy 329.474288 -407.137996) (xy 329.458932 -407.085701) (xy 329.451175 -407.031752) (xy 328.013665 -407.031752)
			(xy 328.013665 -407.031756) (xy 328.005907 -407.085712) (xy 327.990548 -407.138016) (xy 327.967902 -407.187601)
			(xy 327.93843 -407.233458) (xy 327.902731 -407.274653) (xy 327.861532 -407.310349) (xy 327.815672 -407.339818)
			(xy 327.766086 -407.36246) (xy 327.713781 -407.377814) (xy 327.659824 -407.385567) (xy 327.632568 -407.386028)
			(xy 326.768968 -407.386028) (xy 326.74172 -407.3855) (xy 326.687778 -407.37774) (xy 326.63549 -407.362383)
			(xy 326.58592 -407.339741) (xy 326.540076 -407.310275) (xy 326.498892 -407.274586) (xy 326.463205 -407.233399)
			(xy 326.433744 -407.187552) (xy 326.411106 -407.13798) (xy 326.395753 -407.08569) (xy 326.387998 -407.031748)
			(xy 324.950342 -407.031748) (xy 324.950342 -407.031751) (xy 324.942586 -407.0857) (xy 324.927232 -407.137995)
			(xy 324.904591 -407.187573) (xy 324.875126 -407.233424) (xy 324.839436 -407.274616) (xy 324.798247 -407.310309)
			(xy 324.752397 -407.339778) (xy 324.702821 -407.362422) (xy 324.650527 -407.37778) (xy 324.596579 -407.38554)
			(xy 324.569328 -407.386028) (xy 323.705728 -407.386028) (xy 323.678475 -407.385527) (xy 323.624524 -407.377773)
			(xy 323.572226 -407.36242) (xy 323.522645 -407.339781) (xy 323.47679 -407.310315) (xy 323.435597 -407.274623)
			(xy 323.399902 -407.233432) (xy 323.370433 -407.18758) (xy 323.347789 -407.138001) (xy 323.332433 -407.085703)
			(xy 323.324675 -407.031753) (xy 321.887165 -407.031753) (xy 321.887165 -407.031755) (xy 321.879407 -407.08571)
			(xy 321.86405 -407.138011) (xy 321.841405 -407.187595) (xy 321.811935 -407.233451) (xy 321.776238 -407.274646)
			(xy 321.735041 -407.310342) (xy 321.689184 -407.339811) (xy 321.6396 -407.362454) (xy 321.587298 -407.37781)
			(xy 321.533343 -407.385566) (xy 321.506088 -407.386028) (xy 320.642488 -407.386028) (xy 320.615239 -407.385501)
			(xy 320.561295 -407.377743) (xy 320.509005 -407.362388) (xy 320.459432 -407.339748) (xy 320.413585 -407.310282)
			(xy 320.372399 -407.274593) (xy 320.33671 -407.233405) (xy 320.307247 -407.187558) (xy 320.284608 -407.137984)
			(xy 320.269254 -407.085693) (xy 320.261498 -407.031749) (xy 318.823842 -407.031749) (xy 318.823842 -407.03175)
			(xy 318.816087 -407.085697) (xy 318.800733 -407.137991) (xy 318.778094 -407.187567) (xy 318.748631 -407.233418)
			(xy 318.712943 -407.274609) (xy 318.671756 -407.310302) (xy 318.625909 -407.339771) (xy 318.576336 -407.362416)
			(xy 318.524044 -407.377776) (xy 318.470098 -407.385539) (xy 318.442848 -407.386028) (xy 317.579248 -407.386028)
			(xy 317.551994 -407.385528) (xy 317.498041 -407.377777) (xy 317.44574 -407.362426) (xy 317.396157 -407.339787)
			(xy 317.3503 -407.310322) (xy 317.309104 -407.27463) (xy 317.273407 -407.233439) (xy 317.243936 -407.187586)
			(xy 317.221291 -407.138005) (xy 317.205933 -407.085706) (xy 317.198175 -407.031754) (xy 315.760642 -407.031754)
			(xy 315.752885 -407.085702) (xy 315.73753 -407.137999) (xy 315.714888 -407.187578) (xy 315.685421 -407.233431)
			(xy 315.649729 -407.274623) (xy 315.608537 -407.310316) (xy 315.562685 -407.339784) (xy 315.513107 -407.362427)
			(xy 315.46081 -407.377784) (xy 315.40686 -407.385542) (xy 315.379608 -407.386028) (xy 314.516008 -407.386028)
			(xy 314.488756 -407.385525) (xy 314.434807 -407.37777) (xy 314.382511 -407.362415) (xy 314.332933 -407.339774)
			(xy 314.287081 -407.310308) (xy 314.245889 -407.274616) (xy 314.210197 -407.233425) (xy 314.18073 -407.187574)
			(xy 314.158088 -407.137996) (xy 314.142732 -407.085701) (xy 314.134975 -407.031752) (xy 312.697465 -407.031752)
			(xy 312.697465 -407.031756) (xy 312.689707 -407.085712) (xy 312.674348 -407.138016) (xy 312.651702 -407.187601)
			(xy 312.62223 -407.233458) (xy 312.586531 -407.274653) (xy 312.545332 -407.310349) (xy 312.499472 -407.339818)
			(xy 312.449886 -407.36246) (xy 312.397581 -407.377814) (xy 312.343624 -407.385567) (xy 312.316368 -407.386028)
			(xy 311.452768 -407.386028) (xy 311.42552 -407.3855) (xy 311.371578 -407.37774) (xy 311.31929 -407.362383)
			(xy 311.26972 -407.339741) (xy 311.223876 -407.310275) (xy 311.182692 -407.274586) (xy 311.147005 -407.233399)
			(xy 311.117544 -407.187552) (xy 311.094906 -407.13798) (xy 311.079553 -407.08569) (xy 311.071798 -407.031748)
			(xy 309.634142 -407.031748) (xy 309.634142 -407.031751) (xy 309.626386 -407.0857) (xy 309.611032 -407.137995)
			(xy 309.588391 -407.187573) (xy 309.558926 -407.233424) (xy 309.523236 -407.274616) (xy 309.482047 -407.310309)
			(xy 309.436197 -407.339778) (xy 309.386621 -407.362422) (xy 309.334327 -407.37778) (xy 309.280379 -407.38554)
			(xy 309.253128 -407.386028) (xy 308.389528 -407.386028) (xy 308.362275 -407.385527) (xy 308.308324 -407.377773)
			(xy 308.256026 -407.36242) (xy 308.206445 -407.339781) (xy 308.16059 -407.310315) (xy 308.119397 -407.274623)
			(xy 308.083702 -407.233432) (xy 308.054233 -407.18758) (xy 308.031589 -407.138001) (xy 308.016233 -407.085703)
			(xy 308.008475 -407.031753) (xy 306.570965 -407.031753) (xy 306.570965 -407.031755) (xy 306.563207 -407.08571)
			(xy 306.54785 -407.138011) (xy 306.525205 -407.187595) (xy 306.495735 -407.233451) (xy 306.460038 -407.274646)
			(xy 306.418841 -407.310342) (xy 306.372984 -407.339811) (xy 306.3234 -407.362454) (xy 306.271098 -407.37781)
			(xy 306.217143 -407.385566) (xy 306.189888 -407.386028) (xy 305.326288 -407.386028) (xy 305.299039 -407.385501)
			(xy 305.245095 -407.377743) (xy 305.192805 -407.362388) (xy 305.143232 -407.339748) (xy 305.097385 -407.310282)
			(xy 305.056199 -407.274593) (xy 305.02051 -407.233405) (xy 304.991047 -407.187558) (xy 304.968408 -407.137984)
			(xy 304.953054 -407.085693) (xy 304.945298 -407.031749) (xy 168.694465 -407.031749) (xy 168.694465 -407.031756)
			(xy 168.686706 -407.085714) (xy 168.671347 -407.138019) (xy 168.6487 -407.187604) (xy 168.619226 -407.233462)
			(xy 168.583526 -407.274658) (xy 168.542325 -407.310354) (xy 168.496464 -407.339822) (xy 168.446875 -407.362463)
			(xy 168.394569 -407.377816) (xy 168.34061 -407.385568) (xy 168.313354 -407.386028) (xy 167.449754 -407.386028)
			(xy 167.422506 -407.385499) (xy 167.368567 -407.377737) (xy 167.31628 -407.362379) (xy 167.266711 -407.339736)
			(xy 167.220869 -407.31027) (xy 167.179687 -407.274581) (xy 167.144002 -407.233394) (xy 167.114542 -407.187548)
			(xy 167.091905 -407.137977) (xy 167.076553 -407.085688) (xy 167.068798 -407.031748) (xy 165.631142 -407.031748)
			(xy 165.631142 -407.031752) (xy 165.623386 -407.085701) (xy 165.60803 -407.137998) (xy 165.585389 -407.187577)
			(xy 165.555923 -407.233429) (xy 165.520231 -407.274621) (xy 165.47904 -407.310314) (xy 165.433189 -407.339782)
			(xy 165.383611 -407.362426) (xy 165.331315 -407.377783) (xy 165.277366 -407.385541) (xy 165.250114 -407.386028)
			(xy 164.386514 -407.386028) (xy 164.359262 -407.385526) (xy 164.305312 -407.377771) (xy 164.253016 -407.362417)
			(xy 164.203436 -407.339776) (xy 164.157584 -407.31031) (xy 164.116392 -407.274618) (xy 164.080698 -407.233427)
			(xy 164.051231 -407.187576) (xy 164.028588 -407.137998) (xy 164.013232 -407.085701) (xy 164.005475 -407.031752)
			(xy 162.567965 -407.031752) (xy 162.567965 -407.031755) (xy 162.560207 -407.085712) (xy 162.544849 -407.138014)
			(xy 162.522203 -407.187599) (xy 162.492731 -407.233456) (xy 162.457033 -407.274651) (xy 162.415835 -407.310347)
			(xy 162.369976 -407.339816) (xy 162.32039 -407.362458) (xy 162.268086 -407.377813) (xy 162.21413 -407.385567)
			(xy 162.186874 -407.386028) (xy 161.323274 -407.386028) (xy 161.296025 -407.3855) (xy 161.242083 -407.377741)
			(xy 161.189795 -407.362384) (xy 161.140223 -407.339743) (xy 161.094379 -407.310278) (xy 161.053194 -407.274588)
			(xy 161.017507 -407.233401) (xy 160.988045 -407.187554) (xy 160.965407 -407.137981) (xy 160.950054 -407.085691)
			(xy 160.942298 -407.031749) (xy 159.504642 -407.031749) (xy 159.504642 -407.031751) (xy 159.496886 -407.085699)
			(xy 159.481532 -407.137993) (xy 159.458892 -407.187571) (xy 159.429428 -407.233422) (xy 159.393738 -407.274614)
			(xy 159.352549 -407.310307) (xy 159.306701 -407.339776) (xy 159.257125 -407.36242) (xy 159.204832 -407.377779)
			(xy 159.150885 -407.38554) (xy 159.123634 -407.386028) (xy 158.260034 -407.386028) (xy 158.232781 -407.385527)
			(xy 158.178829 -407.377774) (xy 158.12653 -407.362422) (xy 158.076948 -407.339783) (xy 158.031093 -407.310317)
			(xy 157.989899 -407.274625) (xy 157.954203 -407.233434) (xy 157.924734 -407.187582) (xy 157.90209 -407.138002)
			(xy 157.886733 -407.085704) (xy 157.878975 -407.031753) (xy 156.441465 -407.031753) (xy 156.441465 -407.031755)
			(xy 156.433708 -407.085709) (xy 156.41835 -407.13801) (xy 156.395706 -407.187593) (xy 156.366236 -407.233449)
			(xy 156.33054 -407.274644) (xy 156.289344 -407.31034) (xy 156.243488 -407.339809) (xy 156.193904 -407.362452)
			(xy 156.141603 -407.377809) (xy 156.087649 -407.385566) (xy 156.060394 -407.386028) (xy 155.196794 -407.386028)
			(xy 155.169544 -407.385501) (xy 155.1156 -407.377745) (xy 155.063309 -407.36239) (xy 155.013735 -407.339749)
			(xy 154.967888 -407.310285) (xy 154.926701 -407.274595) (xy 154.891012 -407.233407) (xy 154.861548 -407.187559)
			(xy 154.838908 -407.137985) (xy 154.823554 -407.085694) (xy 154.815798 -407.03175) (xy 153.378265 -407.03175)
			(xy 153.378265 -407.031756) (xy 153.370506 -407.085714) (xy 153.355147 -407.138019) (xy 153.3325 -407.187604)
			(xy 153.303026 -407.233462) (xy 153.267326 -407.274658) (xy 153.226125 -407.310354) (xy 153.180264 -407.339822)
			(xy 153.130675 -407.362463) (xy 153.078369 -407.377816) (xy 153.02441 -407.385568) (xy 152.997154 -407.386028)
			(xy 152.133554 -407.386028) (xy 152.106306 -407.385499) (xy 152.052367 -407.377737) (xy 152.00008 -407.362379)
			(xy 151.950511 -407.339736) (xy 151.904669 -407.31027) (xy 151.863487 -407.274581) (xy 151.827802 -407.233394)
			(xy 151.798342 -407.187548) (xy 151.775705 -407.137977) (xy 151.760353 -407.085688) (xy 151.752598 -407.031748)
			(xy 150.314942 -407.031748) (xy 150.314942 -407.031752) (xy 150.307186 -407.085701) (xy 150.29183 -407.137998)
			(xy 150.269189 -407.187577) (xy 150.239723 -407.233429) (xy 150.204031 -407.274621) (xy 150.16284 -407.310314)
			(xy 150.116989 -407.339782) (xy 150.067411 -407.362426) (xy 150.015115 -407.377783) (xy 149.961166 -407.385541)
			(xy 149.933914 -407.386028) (xy 149.070314 -407.386028) (xy 149.043062 -407.385526) (xy 148.989112 -407.377771)
			(xy 148.936816 -407.362417) (xy 148.887236 -407.339776) (xy 148.841384 -407.31031) (xy 148.800192 -407.274618)
			(xy 148.764498 -407.233427) (xy 148.735031 -407.187576) (xy 148.712388 -407.137998) (xy 148.697032 -407.085701)
			(xy 148.689275 -407.031752) (xy 147.251765 -407.031752) (xy 147.251765 -407.031755) (xy 147.244007 -407.085712)
			(xy 147.228649 -407.138014) (xy 147.206003 -407.187599) (xy 147.176531 -407.233456) (xy 147.140833 -407.274651)
			(xy 147.099635 -407.310347) (xy 147.053776 -407.339816) (xy 147.00419 -407.362458) (xy 146.951886 -407.377813)
			(xy 146.89793 -407.385567) (xy 146.870674 -407.386028) (xy 146.007074 -407.386028) (xy 145.979825 -407.3855)
			(xy 145.925883 -407.377741) (xy 145.873595 -407.362384) (xy 145.824023 -407.339743) (xy 145.778179 -407.310278)
			(xy 145.736994 -407.274588) (xy 145.701307 -407.233401) (xy 145.671845 -407.187554) (xy 145.649207 -407.137981)
			(xy 145.633854 -407.085691) (xy 145.626098 -407.031749) (xy 144.188442 -407.031749) (xy 144.188442 -407.031751)
			(xy 144.180686 -407.085699) (xy 144.165332 -407.137993) (xy 144.142692 -407.187571) (xy 144.113228 -407.233422)
			(xy 144.077538 -407.274614) (xy 144.036349 -407.310307) (xy 143.990501 -407.339776) (xy 143.940925 -407.36242)
			(xy 143.888632 -407.377779) (xy 143.834685 -407.38554) (xy 143.807434 -407.386028) (xy 142.943834 -407.386028)
			(xy 142.916581 -407.385527) (xy 142.862629 -407.377774) (xy 142.81033 -407.362422) (xy 142.760748 -407.339783)
			(xy 142.714893 -407.310317) (xy 142.673699 -407.274625) (xy 142.638003 -407.233434) (xy 142.608534 -407.187582)
			(xy 142.58589 -407.138002) (xy 142.570533 -407.085704) (xy 142.562775 -407.031753) (xy 141.125265 -407.031753)
			(xy 141.125265 -407.031755) (xy 141.117508 -407.085709) (xy 141.10215 -407.13801) (xy 141.079506 -407.187593)
			(xy 141.050036 -407.233449) (xy 141.01434 -407.274644) (xy 140.973144 -407.31034) (xy 140.927288 -407.339809)
			(xy 140.877704 -407.362452) (xy 140.825403 -407.377809) (xy 140.771449 -407.385566) (xy 140.744194 -407.386028)
			(xy 139.880594 -407.386028) (xy 139.853344 -407.385501) (xy 139.7994 -407.377745) (xy 139.747109 -407.36239)
			(xy 139.697535 -407.339749) (xy 139.651688 -407.310285) (xy 139.610501 -407.274595) (xy 139.574812 -407.233407)
			(xy 139.545348 -407.187559) (xy 139.522708 -407.137985) (xy 139.507354 -407.085694) (xy 139.499598 -407.03175)
			(xy 138.062065 -407.03175) (xy 138.062065 -407.031756) (xy 138.054306 -407.085714) (xy 138.038947 -407.138019)
			(xy 138.0163 -407.187604) (xy 137.986826 -407.233462) (xy 137.951126 -407.274658) (xy 137.909925 -407.310354)
			(xy 137.864064 -407.339822) (xy 137.814475 -407.362463) (xy 137.762169 -407.377816) (xy 137.70821 -407.385568)
			(xy 137.680954 -407.386028) (xy 136.817354 -407.386028) (xy 136.790106 -407.385499) (xy 136.736167 -407.377737)
			(xy 136.68388 -407.362379) (xy 136.634311 -407.339736) (xy 136.588469 -407.31027) (xy 136.547287 -407.274581)
			(xy 136.511602 -407.233394) (xy 136.482142 -407.187548) (xy 136.459505 -407.137977) (xy 136.444153 -407.085688)
			(xy 136.436398 -407.031748) (xy 134.998742 -407.031748) (xy 134.998742 -407.031752) (xy 134.990986 -407.085701)
			(xy 134.97563 -407.137998) (xy 134.952989 -407.187577) (xy 134.923523 -407.233429) (xy 134.887831 -407.274621)
			(xy 134.84664 -407.310314) (xy 134.800789 -407.339782) (xy 134.751211 -407.362426) (xy 134.698915 -407.377783)
			(xy 134.644966 -407.385541) (xy 134.617714 -407.386028) (xy 133.754114 -407.386028) (xy 133.726862 -407.385526)
			(xy 133.672912 -407.377771) (xy 133.620616 -407.362417) (xy 133.571036 -407.339776) (xy 133.525184 -407.31031)
			(xy 133.483992 -407.274618) (xy 133.448298 -407.233427) (xy 133.418831 -407.187576) (xy 133.396188 -407.137998)
			(xy 133.380832 -407.085701) (xy 133.373075 -407.031752) (xy 131.935565 -407.031752) (xy 131.935565 -407.031755)
			(xy 131.927807 -407.085712) (xy 131.912449 -407.138014) (xy 131.889803 -407.187599) (xy 131.860331 -407.233456)
			(xy 131.824633 -407.274651) (xy 131.783435 -407.310347) (xy 131.737576 -407.339816) (xy 131.68799 -407.362458)
			(xy 131.635686 -407.377813) (xy 131.58173 -407.385567) (xy 131.554474 -407.386028) (xy 130.690874 -407.386028)
			(xy 130.663625 -407.3855) (xy 130.609683 -407.377741) (xy 130.557395 -407.362384) (xy 130.507823 -407.339743)
			(xy 130.461979 -407.310278) (xy 130.420794 -407.274588) (xy 130.385107 -407.233401) (xy 130.355645 -407.187554)
			(xy 130.333007 -407.137981) (xy 130.317654 -407.085691) (xy 130.309898 -407.031749) (xy 128.872242 -407.031749)
			(xy 128.872242 -407.031751) (xy 128.864486 -407.085699) (xy 128.849132 -407.137993) (xy 128.826492 -407.187571)
			(xy 128.797028 -407.233422) (xy 128.761338 -407.274614) (xy 128.720149 -407.310307) (xy 128.674301 -407.339776)
			(xy 128.624725 -407.36242) (xy 128.572432 -407.377779) (xy 128.518485 -407.38554) (xy 128.491234 -407.386028)
			(xy 127.627634 -407.386028) (xy 127.600381 -407.385527) (xy 127.546429 -407.377774) (xy 127.49413 -407.362422)
			(xy 127.444548 -407.339783) (xy 127.398693 -407.310317) (xy 127.357499 -407.274625) (xy 127.321803 -407.233434)
			(xy 127.292334 -407.187582) (xy 127.26969 -407.138002) (xy 127.254333 -407.085704) (xy 127.246575 -407.031753)
			(xy 125.809065 -407.031753) (xy 125.809065 -407.031755) (xy 125.801308 -407.085709) (xy 125.78595 -407.13801)
			(xy 125.763306 -407.187593) (xy 125.733836 -407.233449) (xy 125.69814 -407.274644) (xy 125.656944 -407.31034)
			(xy 125.611088 -407.339809) (xy 125.561504 -407.362452) (xy 125.509203 -407.377809) (xy 125.455249 -407.385566)
			(xy 125.427994 -407.386028) (xy 124.564394 -407.386028) (xy 124.537144 -407.385501) (xy 124.4832 -407.377745)
			(xy 124.430909 -407.36239) (xy 124.381335 -407.339749) (xy 124.335488 -407.310285) (xy 124.294301 -407.274595)
			(xy 124.258612 -407.233407) (xy 124.229148 -407.187559) (xy 124.206508 -407.137985) (xy 124.191154 -407.085694)
			(xy 124.183398 -407.03175) (xy 122.745865 -407.03175) (xy 122.745865 -407.031756) (xy 122.738106 -407.085714)
			(xy 122.722747 -407.138019) (xy 122.7001 -407.187604) (xy 122.670626 -407.233462) (xy 122.634926 -407.274658)
			(xy 122.593725 -407.310354) (xy 122.547864 -407.339822) (xy 122.498275 -407.362463) (xy 122.445969 -407.377816)
			(xy 122.39201 -407.385568) (xy 122.364754 -407.386028) (xy 121.501154 -407.386028) (xy 121.473906 -407.385499)
			(xy 121.419967 -407.377737) (xy 121.36768 -407.362379) (xy 121.318111 -407.339736) (xy 121.272269 -407.31027)
			(xy 121.231087 -407.274581) (xy 121.195402 -407.233394) (xy 121.165942 -407.187548) (xy 121.143305 -407.137977)
			(xy 121.127953 -407.085688) (xy 121.120198 -407.031748) (xy 107.861153 -407.031748) (xy 107.86873 -407.084449)
			(xy 107.86873 -407.138951) (xy 107.860974 -407.192898) (xy 107.84562 -407.245192) (xy 107.822979 -407.294769)
			(xy 107.793514 -407.34062) (xy 107.757824 -407.38181) (xy 107.716636 -407.417502) (xy 107.670787 -407.44697)
			(xy 107.621211 -407.469613) (xy 107.568918 -407.48497) (xy 107.514971 -407.492729) (xy 107.48772 -407.493216)
			(xy 106.62412 -407.493216) (xy 106.596867 -407.492738) (xy 106.542915 -407.484984) (xy 106.490616 -407.46963)
			(xy 106.441034 -407.446989) (xy 106.395179 -407.417522) (xy 106.353985 -407.381829) (xy 106.31829 -407.340637)
			(xy 106.288821 -407.294783) (xy 106.266177 -407.245203) (xy 106.250821 -407.192905) (xy 106.243063 -407.138953)
			(xy 96.495694 -407.138953) (xy 96.473493 -407.18757) (xy 96.444028 -407.233421) (xy 96.408339 -407.274612)
			(xy 96.367151 -407.310306) (xy 96.321303 -407.339775) (xy 96.271728 -407.362419) (xy 96.219435 -407.377778)
			(xy 96.165489 -407.38554) (xy 96.138238 -407.386028) (xy 95.274638 -407.386028) (xy 95.247385 -407.385527)
			(xy 95.193433 -407.377775) (xy 95.141133 -407.362423) (xy 95.091551 -407.339784) (xy 95.045695 -407.310319)
			(xy 95.0045 -407.274627) (xy 94.968804 -407.233435) (xy 94.939334 -407.187583) (xy 94.91669 -407.138003)
			(xy 94.901333 -407.085705) (xy 94.893575 -407.031753) (xy 93.456065 -407.031753) (xy 93.456065 -407.031754)
			(xy 93.448308 -407.085708) (xy 93.432951 -407.138009) (xy 93.410307 -407.187592) (xy 93.380837 -407.233448)
			(xy 93.345141 -407.274643) (xy 93.303946 -407.310338) (xy 93.25809 -407.339808) (xy 93.208507 -407.362451)
			(xy 93.156206 -407.377808) (xy 93.102252 -407.385565) (xy 93.074998 -407.386028) (xy 92.211398 -407.386028)
			(xy 92.184148 -407.385502) (xy 92.130204 -407.377745) (xy 92.077912 -407.362391) (xy 92.028338 -407.339751)
			(xy 91.98249 -407.310286) (xy 91.941302 -407.274596) (xy 91.905613 -407.233408) (xy 91.876148 -407.187561)
			(xy 91.853508 -407.137986) (xy 91.838154 -407.085694) (xy 91.830398 -407.03175) (xy 90.392865 -407.03175)
			(xy 90.392865 -407.031756) (xy 90.385107 -407.085714) (xy 90.369748 -407.138018) (xy 90.347101 -407.187603)
			(xy 90.317627 -407.233461) (xy 90.281927 -407.274657) (xy 90.240727 -407.310352) (xy 90.194866 -407.339821)
			(xy 90.145278 -407.362462) (xy 90.092973 -407.377815) (xy 90.039014 -407.385568) (xy 90.011758 -407.386028)
			(xy 89.148158 -407.386028) (xy 89.12091 -407.385499) (xy 89.06697 -407.377738) (xy 89.014683 -407.36238)
			(xy 88.965114 -407.339738) (xy 88.919271 -407.310272) (xy 88.878088 -407.274582) (xy 88.842403 -407.233395)
			(xy 88.812942 -407.187549) (xy 88.790305 -407.137978) (xy 88.774953 -407.085689) (xy 88.767198 -407.031748)
			(xy 87.329542 -407.031748) (xy 87.329542 -407.031752) (xy 87.321786 -407.085701) (xy 87.306431 -407.137997)
			(xy 87.28379 -407.187576) (xy 87.254324 -407.233427) (xy 87.218632 -407.274619) (xy 87.177442 -407.310313)
			(xy 87.131591 -407.339781) (xy 87.082014 -407.362424) (xy 87.029718 -407.377782) (xy 86.97577 -407.385541)
			(xy 86.948518 -407.386028) (xy 86.084918 -407.386028) (xy 86.057666 -407.385526) (xy 86.003716 -407.377771)
			(xy 85.951418 -407.362418) (xy 85.901839 -407.339778) (xy 85.855986 -407.310312) (xy 85.814793 -407.27462)
			(xy 85.779099 -407.233429) (xy 85.749631 -407.187577) (xy 85.726989 -407.137998) (xy 85.711632 -407.085702)
			(xy 85.703875 -407.031752) (xy 84.266365 -407.031752) (xy 84.266365 -407.031755) (xy 84.258607 -407.085711)
			(xy 84.243249 -407.138013) (xy 84.220604 -407.187598) (xy 84.191132 -407.233454) (xy 84.155434 -407.27465)
			(xy 84.114237 -407.310345) (xy 84.068378 -407.339814) (xy 84.018793 -407.362457) (xy 83.96649 -407.377812)
			(xy 83.912533 -407.385567) (xy 83.885278 -407.386028) (xy 83.021678 -407.386028) (xy 82.994429 -407.3855)
			(xy 82.940487 -407.377742) (xy 82.888197 -407.362385) (xy 82.838626 -407.339744) (xy 82.79278 -407.310279)
			(xy 82.751595 -407.274589) (xy 82.715908 -407.233402) (xy 82.686445 -407.187555) (xy 82.663807 -407.137982)
			(xy 82.648454 -407.085692) (xy 82.640698 -407.031749) (xy 81.203042 -407.031749) (xy 81.203042 -407.031751)
			(xy 81.195286 -407.085698) (xy 81.179932 -407.137993) (xy 81.157293 -407.18757) (xy 81.127828 -407.233421)
			(xy 81.092139 -407.274612) (xy 81.050951 -407.310306) (xy 81.005103 -407.339775) (xy 80.955528 -407.362419)
			(xy 80.903235 -407.377778) (xy 80.849289 -407.38554) (xy 80.822038 -407.386028) (xy 79.958438 -407.386028)
			(xy 79.931185 -407.385527) (xy 79.877233 -407.377775) (xy 79.824933 -407.362423) (xy 79.775351 -407.339784)
			(xy 79.729495 -407.310319) (xy 79.6883 -407.274627) (xy 79.652604 -407.233435) (xy 79.623134 -407.187583)
			(xy 79.60049 -407.138003) (xy 79.585133 -407.085705) (xy 79.577375 -407.031753) (xy 78.139865 -407.031753)
			(xy 78.139865 -407.031754) (xy 78.132108 -407.085708) (xy 78.116751 -407.138009) (xy 78.094107 -407.187592)
			(xy 78.064637 -407.233448) (xy 78.028941 -407.274643) (xy 77.987746 -407.310338) (xy 77.94189 -407.339808)
			(xy 77.892307 -407.362451) (xy 77.840006 -407.377808) (xy 77.786052 -407.385565) (xy 77.758798 -407.386028)
			(xy 76.895198 -407.386028) (xy 76.867948 -407.385502) (xy 76.814004 -407.377745) (xy 76.761712 -407.362391)
			(xy 76.712138 -407.339751) (xy 76.66629 -407.310286) (xy 76.625102 -407.274596) (xy 76.589413 -407.233408)
			(xy 76.559948 -407.187561) (xy 76.537308 -407.137986) (xy 76.521954 -407.085694) (xy 76.514198 -407.03175)
			(xy 75.076665 -407.03175) (xy 75.076665 -407.031756) (xy 75.068907 -407.085714) (xy 75.053548 -407.138018)
			(xy 75.030901 -407.187603) (xy 75.001427 -407.233461) (xy 74.965727 -407.274657) (xy 74.924527 -407.310352)
			(xy 74.878666 -407.339821) (xy 74.829078 -407.362462) (xy 74.776773 -407.377815) (xy 74.722814 -407.385568)
			(xy 74.695558 -407.386028) (xy 73.831958 -407.386028) (xy 73.80471 -407.385499) (xy 73.75077 -407.377738)
			(xy 73.698483 -407.36238) (xy 73.648914 -407.339738) (xy 73.603071 -407.310272) (xy 73.561888 -407.274582)
			(xy 73.526203 -407.233395) (xy 73.496742 -407.187549) (xy 73.474105 -407.137978) (xy 73.458753 -407.085689)
			(xy 73.450998 -407.031748) (xy 72.013342 -407.031748) (xy 72.013342 -407.031752) (xy 72.005586 -407.085701)
			(xy 71.990231 -407.137997) (xy 71.96759 -407.187576) (xy 71.938124 -407.233427) (xy 71.902432 -407.274619)
			(xy 71.861242 -407.310313) (xy 71.815391 -407.339781) (xy 71.765814 -407.362424) (xy 71.713518 -407.377782)
			(xy 71.65957 -407.385541) (xy 71.632318 -407.386028) (xy 70.768718 -407.386028) (xy 70.741466 -407.385526)
			(xy 70.687516 -407.377771) (xy 70.635218 -407.362418) (xy 70.585639 -407.339778) (xy 70.539786 -407.310312)
			(xy 70.498593 -407.27462) (xy 70.462899 -407.233429) (xy 70.433431 -407.187577) (xy 70.410789 -407.137998)
			(xy 70.395432 -407.085702) (xy 70.387675 -407.031752) (xy 68.950165 -407.031752) (xy 68.950165 -407.031755)
			(xy 68.942407 -407.085711) (xy 68.927049 -407.138013) (xy 68.904404 -407.187598) (xy 68.874932 -407.233454)
			(xy 68.839234 -407.27465) (xy 68.798037 -407.310345) (xy 68.752178 -407.339814) (xy 68.702593 -407.362457)
			(xy 68.65029 -407.377812) (xy 68.596333 -407.385567) (xy 68.569078 -407.386028) (xy 67.705478 -407.386028)
			(xy 67.678229 -407.3855) (xy 67.624287 -407.377742) (xy 67.571997 -407.362385) (xy 67.522426 -407.339744)
			(xy 67.47658 -407.310279) (xy 67.435395 -407.274589) (xy 67.399708 -407.233402) (xy 67.370245 -407.187555)
			(xy 67.347607 -407.137982) (xy 67.332254 -407.085692) (xy 67.324498 -407.031749) (xy 65.886842 -407.031749)
			(xy 65.886842 -407.031751) (xy 65.879086 -407.085698) (xy 65.863732 -407.137993) (xy 65.841093 -407.18757)
			(xy 65.811628 -407.233421) (xy 65.775939 -407.274612) (xy 65.734751 -407.310306) (xy 65.688903 -407.339775)
			(xy 65.639328 -407.362419) (xy 65.587035 -407.377778) (xy 65.533089 -407.38554) (xy 65.505838 -407.386028)
			(xy 64.642238 -407.386028) (xy 64.614985 -407.385527) (xy 64.561033 -407.377775) (xy 64.508733 -407.362423)
			(xy 64.459151 -407.339784) (xy 64.413295 -407.310319) (xy 64.3721 -407.274627) (xy 64.336404 -407.233435)
			(xy 64.306934 -407.187583) (xy 64.28429 -407.138003) (xy 64.268933 -407.085705) (xy 64.261175 -407.031753)
			(xy 62.823665 -407.031753) (xy 62.823665 -407.031754) (xy 62.815908 -407.085708) (xy 62.800551 -407.138009)
			(xy 62.777907 -407.187592) (xy 62.748437 -407.233448) (xy 62.712741 -407.274643) (xy 62.671546 -407.310338)
			(xy 62.62569 -407.339808) (xy 62.576107 -407.362451) (xy 62.523806 -407.377808) (xy 62.469852 -407.385565)
			(xy 62.442598 -407.386028) (xy 61.578998 -407.386028) (xy 61.551748 -407.385502) (xy 61.497804 -407.377745)
			(xy 61.445512 -407.362391) (xy 61.395938 -407.339751) (xy 61.35009 -407.310286) (xy 61.308902 -407.274596)
			(xy 61.273213 -407.233408) (xy 61.243748 -407.187561) (xy 61.221108 -407.137986) (xy 61.205754 -407.085694)
			(xy 61.197998 -407.03175) (xy 59.760465 -407.03175) (xy 59.760465 -407.031756) (xy 59.752707 -407.085714)
			(xy 59.737348 -407.138018) (xy 59.714701 -407.187603) (xy 59.685227 -407.233461) (xy 59.649527 -407.274657)
			(xy 59.608327 -407.310352) (xy 59.562466 -407.339821) (xy 59.512878 -407.362462) (xy 59.460573 -407.377815)
			(xy 59.406614 -407.385568) (xy 59.379358 -407.386028) (xy 58.515758 -407.386028) (xy 58.48851 -407.385499)
			(xy 58.43457 -407.377738) (xy 58.382283 -407.36238) (xy 58.332714 -407.339738) (xy 58.286871 -407.310272)
			(xy 58.245688 -407.274582) (xy 58.210003 -407.233395) (xy 58.180542 -407.187549) (xy 58.157905 -407.137978)
			(xy 58.142553 -407.085689) (xy 58.134798 -407.031748) (xy 56.697142 -407.031748) (xy 56.697142 -407.031752)
			(xy 56.689386 -407.085701) (xy 56.674031 -407.137997) (xy 56.65139 -407.187576) (xy 56.621924 -407.233427)
			(xy 56.586232 -407.274619) (xy 56.545042 -407.310313) (xy 56.499191 -407.339781) (xy 56.449614 -407.362424)
			(xy 56.397318 -407.377782) (xy 56.34337 -407.385541) (xy 56.316118 -407.386028) (xy 55.452518 -407.386028)
			(xy 55.425266 -407.385526) (xy 55.371316 -407.377771) (xy 55.319018 -407.362418) (xy 55.269439 -407.339778)
			(xy 55.223586 -407.310312) (xy 55.182393 -407.27462) (xy 55.146699 -407.233429) (xy 55.117231 -407.187577)
			(xy 55.094589 -407.137998) (xy 55.079232 -407.085702) (xy 55.071475 -407.031752) (xy 53.633965 -407.031752)
			(xy 53.633965 -407.031755) (xy 53.626207 -407.085711) (xy 53.610849 -407.138013) (xy 53.588204 -407.187598)
			(xy 53.558732 -407.233454) (xy 53.523034 -407.27465) (xy 53.481837 -407.310345) (xy 53.435978 -407.339814)
			(xy 53.386393 -407.362457) (xy 53.33409 -407.377812) (xy 53.280133 -407.385567) (xy 53.252878 -407.386028)
			(xy 52.389278 -407.386028) (xy 52.362029 -407.3855) (xy 52.308087 -407.377742) (xy 52.255797 -407.362385)
			(xy 52.206226 -407.339744) (xy 52.16038 -407.310279) (xy 52.119195 -407.274589) (xy 52.083508 -407.233402)
			(xy 52.054045 -407.187555) (xy 52.031407 -407.137982) (xy 52.016054 -407.085692) (xy 52.008298 -407.031749)
			(xy 50.570642 -407.031749) (xy 50.570642 -407.031751) (xy 50.562886 -407.085698) (xy 50.547532 -407.137993)
			(xy 50.524893 -407.18757) (xy 50.495428 -407.233421) (xy 50.459739 -407.274612) (xy 50.418551 -407.310306)
			(xy 50.372703 -407.339775) (xy 50.323128 -407.362419) (xy 50.270835 -407.377778) (xy 50.216889 -407.38554)
			(xy 50.189638 -407.386028) (xy 49.326038 -407.386028) (xy 49.298785 -407.385527) (xy 49.244833 -407.377775)
			(xy 49.192533 -407.362423) (xy 49.142951 -407.339784) (xy 49.097095 -407.310319) (xy 49.0559 -407.274627)
			(xy 49.020204 -407.233435) (xy 48.990734 -407.187583) (xy 48.96809 -407.138003) (xy 48.952733 -407.085705)
			(xy 48.944975 -407.031753) (xy 16.741648 -407.031753) (xy 16.741648 -407.035508) (xy 16.741162 -407.062759)
			(xy 16.733406 -407.116707) (xy 16.718051 -407.169002) (xy 16.695409 -407.218579) (xy 16.665943 -407.264429)
			(xy 16.630252 -407.30562) (xy 16.589061 -407.341311) (xy 16.543211 -407.370777) (xy 16.493634 -407.393419)
			(xy 16.441339 -407.408774) (xy 16.387391 -407.41653) (xy 16.332889 -407.41653) (xy 16.278941 -407.408774)
			(xy 16.226646 -407.393419) (xy 16.177069 -407.370777) (xy 16.131219 -407.341311) (xy 16.090028 -407.30562)
			(xy 16.054337 -407.264429) (xy 16.024871 -407.218579) (xy 16.002229 -407.169002) (xy 15.986874 -407.116707)
			(xy 15.979118 -407.062759) (xy 15.978632 -407.035508) (xy 5.555234 -407.035508) (xy 6.274054 -407.754328)
			(xy 6.323476 -407.804436) (xy 6.417282 -407.909377) (xy 6.505056 -408.019414) (xy 6.586523 -408.134198)
			(xy 6.661426 -408.25337) (xy 6.729529 -408.376554) (xy 6.790618 -408.503362) (xy 6.844501 -408.633397)
			(xy 6.891008 -408.766247) (xy 6.929993 -408.901497) (xy 6.961334 -409.03872) (xy 6.984932 -409.177484)
			(xy 7.000712 -409.317352) (xy 7.008625 -409.457886) (xy 7.00913 -409.528264) (xy 7.00913 -410.057457)
			(xy 48.944923 -410.057457) (xy 48.944923 -410.002943) (xy 48.952682 -409.948984) (xy 48.968041 -409.896679)
			(xy 48.990688 -409.847092) (xy 49.020162 -409.801233) (xy 49.055863 -409.760036) (xy 49.097064 -409.724339)
			(xy 49.142925 -409.69487) (xy 49.192515 -409.672228) (xy 49.244821 -409.656874) (xy 49.298781 -409.64912)
			(xy 49.326038 -409.64866) (xy 50.189638 -409.64866) (xy 50.216885 -409.649213) (xy 50.270824 -409.656973)
			(xy 50.32311 -409.67233) (xy 50.372678 -409.694972) (xy 50.41852 -409.724436) (xy 50.459702 -409.760125)
			(xy 50.495386 -409.801311) (xy 50.524847 -409.847155) (xy 50.547483 -409.896726) (xy 50.562835 -409.949013)
			(xy 50.57059 -410.002953) (xy 50.57059 -410.057447) (xy 50.570589 -410.057453) (xy 52.008246 -410.057453)
			(xy 52.008246 -410.002947) (xy 52.016002 -409.948997) (xy 52.031358 -409.8967) (xy 52.053999 -409.84712)
			(xy 52.083466 -409.801267) (xy 52.119158 -409.760074) (xy 52.160349 -409.724379) (xy 52.206201 -409.69491)
			(xy 52.255779 -409.672265) (xy 52.308076 -409.656907) (xy 52.362025 -409.649147) (xy 52.389278 -409.64866)
			(xy 53.252878 -409.64866) (xy 53.28013 -409.649186) (xy 53.334078 -409.65694) (xy 53.386374 -409.672292)
			(xy 53.435953 -409.694932) (xy 53.481805 -409.724397) (xy 53.522997 -409.760087) (xy 53.55869 -409.801277)
			(xy 53.588158 -409.847127) (xy 53.6108 -409.896705) (xy 53.626156 -409.949) (xy 53.633913 -410.002948)
			(xy 53.633913 -410.057452) (xy 53.633912 -410.057456) (xy 55.071423 -410.057456) (xy 55.071423 -410.002944)
			(xy 55.079181 -409.948987) (xy 55.094539 -409.896683) (xy 55.117185 -409.847098) (xy 55.146657 -409.80124)
			(xy 55.182356 -409.760043) (xy 55.223554 -409.724346) (xy 55.269413 -409.694876) (xy 55.319 -409.672233)
			(xy 55.371305 -409.656877) (xy 55.425262 -409.649122) (xy 55.452518 -409.64866) (xy 56.316118 -409.64866)
			(xy 56.343366 -409.649211) (xy 56.397307 -409.656969) (xy 56.449595 -409.672325) (xy 56.499166 -409.694965)
			(xy 56.54501 -409.724429) (xy 56.586195 -409.760118) (xy 56.621882 -409.801304) (xy 56.651344 -409.84715)
			(xy 56.673982 -409.896721) (xy 56.689334 -409.94901) (xy 56.69709 -410.002952) (xy 56.69709 -410.057448)
			(xy 56.697089 -410.057452) (xy 58.134746 -410.057452) (xy 58.134746 -410.002948) (xy 58.142502 -409.949)
			(xy 58.157856 -409.896704) (xy 58.180496 -409.847125) (xy 58.209961 -409.801273) (xy 58.245651 -409.760081)
			(xy 58.28684 -409.724386) (xy 58.332689 -409.694916) (xy 58.382265 -409.672271) (xy 58.434559 -409.656911)
			(xy 58.488506 -409.649149) (xy 58.515758 -409.64866) (xy 59.379358 -409.64866) (xy 59.406611 -409.649184)
			(xy 59.460561 -409.656936) (xy 59.51286 -409.672287) (xy 59.562441 -409.694925) (xy 59.608296 -409.72439)
			(xy 59.64949 -409.76008) (xy 59.685185 -409.801271) (xy 59.714655 -409.847122) (xy 59.737298 -409.896701)
			(xy 59.752655 -409.948997) (xy 59.760413 -410.002948) (xy 59.760413 -410.057452) (xy 59.760413 -410.057453)
			(xy 61.197946 -410.057453) (xy 61.197946 -410.002947) (xy 61.205703 -409.948994) (xy 61.221059 -409.896695)
			(xy 61.243702 -409.847114) (xy 61.273171 -409.80126) (xy 61.308865 -409.760066) (xy 61.350059 -409.724372)
			(xy 61.395913 -409.694903) (xy 61.445494 -409.67226) (xy 61.497793 -409.656903) (xy 61.551745 -409.649146)
			(xy 61.578998 -409.64866) (xy 62.442598 -409.64866) (xy 62.469849 -409.649187) (xy 62.523795 -409.656943)
			(xy 62.576089 -409.672298) (xy 62.625665 -409.694938) (xy 62.671515 -409.724404) (xy 62.712704 -409.760094)
			(xy 62.748395 -409.801284) (xy 62.777861 -409.847133) (xy 62.800502 -409.896709) (xy 62.815856 -409.949003)
			(xy 62.823613 -410.002949) (xy 62.823613 -410.057451) (xy 62.823612 -410.057457) (xy 64.261123 -410.057457)
			(xy 64.261123 -410.002943) (xy 64.268882 -409.948984) (xy 64.284241 -409.896679) (xy 64.306888 -409.847092)
			(xy 64.336362 -409.801233) (xy 64.372063 -409.760036) (xy 64.413264 -409.724339) (xy 64.459125 -409.69487)
			(xy 64.508715 -409.672228) (xy 64.561021 -409.656874) (xy 64.614981 -409.64912) (xy 64.642238 -409.64866)
			(xy 65.505838 -409.64866) (xy 65.533085 -409.649213) (xy 65.587024 -409.656973) (xy 65.63931 -409.67233)
			(xy 65.688878 -409.694972) (xy 65.73472 -409.724436) (xy 65.775902 -409.760125) (xy 65.811586 -409.801311)
			(xy 65.841047 -409.847155) (xy 65.863683 -409.896726) (xy 65.879035 -409.949013) (xy 65.88679 -410.002953)
			(xy 65.88679 -410.057447) (xy 65.886789 -410.057453) (xy 67.324446 -410.057453) (xy 67.324446 -410.002947)
			(xy 67.332202 -409.948997) (xy 67.347558 -409.8967) (xy 67.370199 -409.84712) (xy 67.399666 -409.801267)
			(xy 67.435358 -409.760074) (xy 67.476549 -409.724379) (xy 67.522401 -409.69491) (xy 67.571979 -409.672265)
			(xy 67.624276 -409.656907) (xy 67.678225 -409.649147) (xy 67.705478 -409.64866) (xy 68.569078 -409.64866)
			(xy 68.59633 -409.649186) (xy 68.650278 -409.65694) (xy 68.702574 -409.672292) (xy 68.752153 -409.694932)
			(xy 68.798005 -409.724397) (xy 68.839197 -409.760087) (xy 68.87489 -409.801277) (xy 68.904358 -409.847127)
			(xy 68.927 -409.896705) (xy 68.942356 -409.949) (xy 68.950113 -410.002948) (xy 68.950113 -410.057452)
			(xy 68.950112 -410.057456) (xy 70.387623 -410.057456) (xy 70.387623 -410.002944) (xy 70.395381 -409.948987)
			(xy 70.410739 -409.896683) (xy 70.433385 -409.847098) (xy 70.462857 -409.80124) (xy 70.498556 -409.760043)
			(xy 70.539754 -409.724346) (xy 70.585613 -409.694876) (xy 70.6352 -409.672233) (xy 70.687505 -409.656877)
			(xy 70.741462 -409.649122) (xy 70.768718 -409.64866) (xy 71.632318 -409.64866) (xy 71.659566 -409.649211)
			(xy 71.713507 -409.656969) (xy 71.765795 -409.672325) (xy 71.815366 -409.694965) (xy 71.86121 -409.724429)
			(xy 71.902395 -409.760118) (xy 71.938082 -409.801304) (xy 71.967544 -409.84715) (xy 71.990182 -409.896721)
			(xy 72.005534 -409.94901) (xy 72.01329 -410.002952) (xy 72.01329 -410.057448) (xy 72.013289 -410.057452)
			(xy 73.450946 -410.057452) (xy 73.450946 -410.002948) (xy 73.458702 -409.949) (xy 73.474056 -409.896704)
			(xy 73.496696 -409.847125) (xy 73.526161 -409.801273) (xy 73.561851 -409.760081) (xy 73.60304 -409.724386)
			(xy 73.648889 -409.694916) (xy 73.698465 -409.672271) (xy 73.750759 -409.656911) (xy 73.804706 -409.649149)
			(xy 73.831958 -409.64866) (xy 74.695558 -409.64866) (xy 74.722811 -409.649184) (xy 74.776761 -409.656936)
			(xy 74.82906 -409.672287) (xy 74.878641 -409.694925) (xy 74.924496 -409.72439) (xy 74.96569 -409.76008)
			(xy 75.001385 -409.801271) (xy 75.030855 -409.847122) (xy 75.053498 -409.896701) (xy 75.068855 -409.948997)
			(xy 75.076613 -410.002948) (xy 75.076613 -410.057452) (xy 75.076613 -410.057453) (xy 76.514146 -410.057453)
			(xy 76.514146 -410.002947) (xy 76.521903 -409.948994) (xy 76.537259 -409.896695) (xy 76.559902 -409.847114)
			(xy 76.589371 -409.80126) (xy 76.625065 -409.760066) (xy 76.666259 -409.724372) (xy 76.712113 -409.694903)
			(xy 76.761694 -409.67226) (xy 76.813993 -409.656903) (xy 76.867945 -409.649146) (xy 76.895198 -409.64866)
			(xy 77.758798 -409.64866) (xy 77.786049 -409.649187) (xy 77.839995 -409.656943) (xy 77.892289 -409.672298)
			(xy 77.941865 -409.694938) (xy 77.987715 -409.724404) (xy 78.028904 -409.760094) (xy 78.064595 -409.801284)
			(xy 78.094061 -409.847133) (xy 78.116702 -409.896709) (xy 78.132056 -409.949003) (xy 78.139813 -410.002949)
			(xy 78.139813 -410.057451) (xy 78.139812 -410.057457) (xy 79.577323 -410.057457) (xy 79.577323 -410.002943)
			(xy 79.585082 -409.948984) (xy 79.600441 -409.896679) (xy 79.623088 -409.847092) (xy 79.652562 -409.801233)
			(xy 79.688263 -409.760036) (xy 79.729464 -409.724339) (xy 79.775325 -409.69487) (xy 79.824915 -409.672228)
			(xy 79.877221 -409.656874) (xy 79.931181 -409.64912) (xy 79.958438 -409.64866) (xy 80.822038 -409.64866)
			(xy 80.849285 -409.649213) (xy 80.903224 -409.656973) (xy 80.95551 -409.67233) (xy 81.005078 -409.694972)
			(xy 81.05092 -409.724436) (xy 81.092102 -409.760125) (xy 81.127786 -409.801311) (xy 81.157247 -409.847155)
			(xy 81.179883 -409.896726) (xy 81.195235 -409.949013) (xy 81.20299 -410.002953) (xy 81.20299 -410.057447)
			(xy 81.202989 -410.057453) (xy 82.640646 -410.057453) (xy 82.640646 -410.002947) (xy 82.648402 -409.948997)
			(xy 82.663758 -409.8967) (xy 82.686399 -409.84712) (xy 82.715866 -409.801267) (xy 82.751558 -409.760074)
			(xy 82.792749 -409.724379) (xy 82.838601 -409.69491) (xy 82.888179 -409.672265) (xy 82.940476 -409.656907)
			(xy 82.994425 -409.649147) (xy 83.021678 -409.64866) (xy 83.885278 -409.64866) (xy 83.91253 -409.649186)
			(xy 83.966478 -409.65694) (xy 84.018774 -409.672292) (xy 84.068353 -409.694932) (xy 84.114205 -409.724397)
			(xy 84.155397 -409.760087) (xy 84.19109 -409.801277) (xy 84.220558 -409.847127) (xy 84.2432 -409.896705)
			(xy 84.258556 -409.949) (xy 84.266313 -410.002948) (xy 84.266313 -410.057452) (xy 84.266312 -410.057456)
			(xy 85.703823 -410.057456) (xy 85.703823 -410.002944) (xy 85.711581 -409.948987) (xy 85.726939 -409.896683)
			(xy 85.749585 -409.847098) (xy 85.779057 -409.80124) (xy 85.814756 -409.760043) (xy 85.855954 -409.724346)
			(xy 85.901813 -409.694876) (xy 85.9514 -409.672233) (xy 86.003705 -409.656877) (xy 86.057662 -409.649122)
			(xy 86.084918 -409.64866) (xy 86.948518 -409.64866) (xy 86.975766 -409.649211) (xy 87.029707 -409.656969)
			(xy 87.081995 -409.672325) (xy 87.131566 -409.694965) (xy 87.17741 -409.724429) (xy 87.218595 -409.760118)
			(xy 87.254282 -409.801304) (xy 87.283744 -409.84715) (xy 87.306382 -409.896721) (xy 87.321734 -409.94901)
			(xy 87.32949 -410.002952) (xy 87.32949 -410.057448) (xy 87.329489 -410.057452) (xy 88.767146 -410.057452)
			(xy 88.767146 -410.002948) (xy 88.774902 -409.949) (xy 88.790256 -409.896704) (xy 88.812896 -409.847125)
			(xy 88.842361 -409.801273) (xy 88.878051 -409.760081) (xy 88.91924 -409.724386) (xy 88.965089 -409.694916)
			(xy 89.014665 -409.672271) (xy 89.066959 -409.656911) (xy 89.120906 -409.649149) (xy 89.148158 -409.64866)
			(xy 90.011758 -409.64866) (xy 90.039011 -409.649184) (xy 90.092961 -409.656936) (xy 90.14526 -409.672287)
			(xy 90.194841 -409.694925) (xy 90.240696 -409.72439) (xy 90.28189 -409.76008) (xy 90.317585 -409.801271)
			(xy 90.347055 -409.847122) (xy 90.369698 -409.896701) (xy 90.385055 -409.948997) (xy 90.392813 -410.002948)
			(xy 90.392813 -410.057452) (xy 90.392813 -410.057453) (xy 91.830346 -410.057453) (xy 91.830346 -410.002947)
			(xy 91.838103 -409.948994) (xy 91.853459 -409.896695) (xy 91.876102 -409.847114) (xy 91.905571 -409.80126)
			(xy 91.941265 -409.760066) (xy 91.982459 -409.724372) (xy 92.028313 -409.694903) (xy 92.077894 -409.67226)
			(xy 92.130193 -409.656903) (xy 92.184145 -409.649146) (xy 92.211398 -409.64866) (xy 93.074998 -409.64866)
			(xy 93.102249 -409.649187) (xy 93.156195 -409.656943) (xy 93.208489 -409.672298) (xy 93.258065 -409.694938)
			(xy 93.303915 -409.724404) (xy 93.345104 -409.760094) (xy 93.380795 -409.801284) (xy 93.410261 -409.847133)
			(xy 93.432902 -409.896709) (xy 93.448256 -409.949003) (xy 93.456013 -410.002949) (xy 93.456013 -410.057451)
			(xy 93.456012 -410.057457) (xy 94.893523 -410.057457) (xy 94.893523 -410.002943) (xy 94.901282 -409.948984)
			(xy 94.916641 -409.896679) (xy 94.939288 -409.847092) (xy 94.968762 -409.801233) (xy 95.004463 -409.760036)
			(xy 95.045664 -409.724339) (xy 95.091525 -409.69487) (xy 95.141115 -409.672228) (xy 95.193421 -409.656874)
			(xy 95.247381 -409.64912) (xy 95.274638 -409.64866) (xy 96.138238 -409.64866) (xy 96.165485 -409.649213)
			(xy 96.219424 -409.656973) (xy 96.27171 -409.67233) (xy 96.321278 -409.694972) (xy 96.36712 -409.724436)
			(xy 96.408302 -409.760125) (xy 96.443986 -409.801311) (xy 96.473447 -409.847155) (xy 96.496083 -409.896726)
			(xy 96.511435 -409.949013) (xy 96.51919 -410.002953) (xy 96.51919 -410.057447) (xy 96.519189 -410.057451)
			(xy 121.120146 -410.057451) (xy 121.120146 -410.002949) (xy 121.127902 -409.949) (xy 121.143256 -409.896705)
			(xy 121.165895 -409.847127) (xy 121.19536 -409.801275) (xy 121.231049 -409.760082) (xy 121.272238 -409.724388)
			(xy 121.318086 -409.694918) (xy 121.367662 -409.672272) (xy 121.419955 -409.656911) (xy 121.473903 -409.649149)
			(xy 121.501154 -409.64866) (xy 122.364754 -409.64866) (xy 122.392007 -409.649184) (xy 122.445958 -409.656935)
			(xy 122.498257 -409.672286) (xy 122.547839 -409.694924) (xy 122.593694 -409.724388) (xy 122.634889 -409.760079)
			(xy 122.670584 -409.801269) (xy 122.700054 -409.847121) (xy 122.722698 -409.8967) (xy 122.738055 -409.948997)
			(xy 122.745813 -410.002947) (xy 122.745813 -410.057453) (xy 124.183346 -410.057453) (xy 124.183346 -410.002947)
			(xy 124.191103 -409.948995) (xy 124.206459 -409.896696) (xy 124.229102 -409.847115) (xy 124.25857 -409.801261)
			(xy 124.294264 -409.760068) (xy 124.335457 -409.724373) (xy 124.38131 -409.694904) (xy 124.430891 -409.672261)
			(xy 124.483189 -409.656904) (xy 124.537141 -409.649146) (xy 124.564394 -409.64866) (xy 125.427994 -409.64866)
			(xy 125.455245 -409.649187) (xy 125.509192 -409.656942) (xy 125.561486 -409.672297) (xy 125.611063 -409.694937)
			(xy 125.656913 -409.724402) (xy 125.698103 -409.760093) (xy 125.733794 -409.801282) (xy 125.76326 -409.847132)
			(xy 125.785901 -409.896708) (xy 125.801256 -409.949002) (xy 125.809013 -410.002949) (xy 125.809013 -410.057451)
			(xy 125.809012 -410.057457) (xy 127.246523 -410.057457) (xy 127.246523 -410.002943) (xy 127.254282 -409.948985)
			(xy 127.269641 -409.89668) (xy 127.292287 -409.847093) (xy 127.321761 -409.801235) (xy 127.357462 -409.760037)
			(xy 127.398662 -409.724341) (xy 127.444523 -409.694871) (xy 127.494112 -409.672229) (xy 127.546418 -409.656874)
			(xy 127.600377 -409.649121) (xy 127.627634 -409.64866) (xy 128.491234 -409.64866) (xy 128.518481 -409.649213)
			(xy 128.572421 -409.656972) (xy 128.624707 -409.672329) (xy 128.674276 -409.69497) (xy 128.720118 -409.724435)
			(xy 128.761301 -409.760123) (xy 128.796985 -409.801309) (xy 128.826446 -409.847154) (xy 128.849083 -409.896725)
			(xy 128.864435 -409.949012) (xy 128.87219 -410.002953) (xy 128.87219 -410.057447) (xy 128.872189 -410.057452)
			(xy 130.309846 -410.057452) (xy 130.309846 -410.002948) (xy 130.317602 -409.948998) (xy 130.332957 -409.896701)
			(xy 130.355599 -409.847121) (xy 130.385065 -409.801268) (xy 130.420757 -409.760075) (xy 130.461947 -409.72438)
			(xy 130.507798 -409.694911) (xy 130.557376 -409.672266) (xy 130.609672 -409.656908) (xy 130.663622 -409.649148)
			(xy 130.690874 -409.64866) (xy 131.554474 -409.64866) (xy 131.581726 -409.649185) (xy 131.635675 -409.656939)
			(xy 131.687972 -409.672291) (xy 131.737551 -409.69493) (xy 131.783403 -409.724395) (xy 131.824596 -409.760086)
			(xy 131.860289 -409.801276) (xy 131.889757 -409.847126) (xy 131.9124 -409.896704) (xy 131.927756 -409.949)
			(xy 131.935513 -410.002948) (xy 131.935513 -410.057452) (xy 131.935512 -410.057456) (xy 133.373023 -410.057456)
			(xy 133.373023 -410.002944) (xy 133.380781 -409.948987) (xy 133.396139 -409.896684) (xy 133.418784 -409.847099)
			(xy 133.448256 -409.801241) (xy 133.483954 -409.760045) (xy 133.525152 -409.724348) (xy 133.571011 -409.694878)
			(xy 133.620597 -409.672234) (xy 133.672901 -409.656878) (xy 133.726858 -409.649122) (xy 133.754114 -409.64866)
			(xy 134.617714 -409.64866) (xy 134.644962 -409.649211) (xy 134.698904 -409.656969) (xy 134.751193 -409.672324)
			(xy 134.800764 -409.694964) (xy 134.846609 -409.724428) (xy 134.887794 -409.760116) (xy 134.923481 -409.801303)
			(xy 134.952943 -409.847149) (xy 134.975581 -409.896721) (xy 134.990934 -409.94901) (xy 134.99869 -410.002952)
			(xy 134.99869 -410.057448) (xy 134.99869 -410.057451) (xy 136.436346 -410.057451) (xy 136.436346 -410.002949)
			(xy 136.444102 -409.949) (xy 136.459456 -409.896705) (xy 136.482095 -409.847127) (xy 136.51156 -409.801275)
			(xy 136.547249 -409.760082) (xy 136.588438 -409.724388) (xy 136.634286 -409.694918) (xy 136.683862 -409.672272)
			(xy 136.736155 -409.656911) (xy 136.790103 -409.649149) (xy 136.817354 -409.64866) (xy 137.680954 -409.64866)
			(xy 137.708207 -409.649184) (xy 137.762158 -409.656935) (xy 137.814457 -409.672286) (xy 137.864039 -409.694924)
			(xy 137.909894 -409.724388) (xy 137.951089 -409.760079) (xy 137.986784 -409.801269) (xy 138.016254 -409.847121)
			(xy 138.038898 -409.8967) (xy 138.054255 -409.948997) (xy 138.062013 -410.002947) (xy 138.062013 -410.057453)
			(xy 139.499546 -410.057453) (xy 139.499546 -410.002947) (xy 139.507303 -409.948995) (xy 139.522659 -409.896696)
			(xy 139.545302 -409.847115) (xy 139.57477 -409.801261) (xy 139.610464 -409.760068) (xy 139.651657 -409.724373)
			(xy 139.69751 -409.694904) (xy 139.747091 -409.672261) (xy 139.799389 -409.656904) (xy 139.853341 -409.649146)
			(xy 139.880594 -409.64866) (xy 140.744194 -409.64866) (xy 140.771445 -409.649187) (xy 140.825392 -409.656942)
			(xy 140.877686 -409.672297) (xy 140.927263 -409.694937) (xy 140.973113 -409.724402) (xy 141.014303 -409.760093)
			(xy 141.049994 -409.801282) (xy 141.07946 -409.847132) (xy 141.102101 -409.896708) (xy 141.117456 -409.949002)
			(xy 141.125213 -410.002949) (xy 141.125213 -410.057451) (xy 141.125212 -410.057457) (xy 142.562723 -410.057457)
			(xy 142.562723 -410.002943) (xy 142.570482 -409.948985) (xy 142.585841 -409.89668) (xy 142.608487 -409.847093)
			(xy 142.637961 -409.801235) (xy 142.673662 -409.760037) (xy 142.714862 -409.724341) (xy 142.760723 -409.694871)
			(xy 142.810312 -409.672229) (xy 142.862618 -409.656874) (xy 142.916577 -409.649121) (xy 142.943834 -409.64866)
			(xy 143.807434 -409.64866) (xy 143.834681 -409.649213) (xy 143.888621 -409.656972) (xy 143.940907 -409.672329)
			(xy 143.990476 -409.69497) (xy 144.036318 -409.724435) (xy 144.077501 -409.760123) (xy 144.113185 -409.801309)
			(xy 144.142646 -409.847154) (xy 144.165283 -409.896725) (xy 144.180635 -409.949012) (xy 144.18839 -410.002953)
			(xy 144.18839 -410.057447) (xy 144.188389 -410.057452) (xy 145.626046 -410.057452) (xy 145.626046 -410.002948)
			(xy 145.633802 -409.948998) (xy 145.649157 -409.896701) (xy 145.671799 -409.847121) (xy 145.701265 -409.801268)
			(xy 145.736957 -409.760075) (xy 145.778147 -409.72438) (xy 145.823998 -409.694911) (xy 145.873576 -409.672266)
			(xy 145.925872 -409.656908) (xy 145.979822 -409.649148) (xy 146.007074 -409.64866) (xy 146.870674 -409.64866)
			(xy 146.897926 -409.649185) (xy 146.951875 -409.656939) (xy 147.004172 -409.672291) (xy 147.053751 -409.69493)
			(xy 147.099603 -409.724395) (xy 147.140796 -409.760086) (xy 147.176489 -409.801276) (xy 147.205957 -409.847126)
			(xy 147.2286 -409.896704) (xy 147.243956 -409.949) (xy 147.251713 -410.002948) (xy 147.251713 -410.057452)
			(xy 147.251712 -410.057456) (xy 148.689223 -410.057456) (xy 148.689223 -410.002944) (xy 148.696981 -409.948987)
			(xy 148.712339 -409.896684) (xy 148.734984 -409.847099) (xy 148.764456 -409.801241) (xy 148.800154 -409.760045)
			(xy 148.841352 -409.724348) (xy 148.887211 -409.694878) (xy 148.936797 -409.672234) (xy 148.989101 -409.656878)
			(xy 149.043058 -409.649122) (xy 149.070314 -409.64866) (xy 149.933914 -409.64866) (xy 149.961162 -409.649211)
			(xy 150.015104 -409.656969) (xy 150.067393 -409.672324) (xy 150.116964 -409.694964) (xy 150.162809 -409.724428)
			(xy 150.203994 -409.760116) (xy 150.239681 -409.801303) (xy 150.269143 -409.847149) (xy 150.291781 -409.896721)
			(xy 150.307134 -409.94901) (xy 150.31489 -410.002952) (xy 150.31489 -410.057448) (xy 150.31489 -410.057451)
			(xy 151.752546 -410.057451) (xy 151.752546 -410.002949) (xy 151.760302 -409.949) (xy 151.775656 -409.896705)
			(xy 151.798295 -409.847127) (xy 151.82776 -409.801275) (xy 151.863449 -409.760082) (xy 151.904638 -409.724388)
			(xy 151.950486 -409.694918) (xy 152.000062 -409.672272) (xy 152.052355 -409.656911) (xy 152.106303 -409.649149)
			(xy 152.133554 -409.64866) (xy 152.997154 -409.64866) (xy 153.024407 -409.649184) (xy 153.078358 -409.656935)
			(xy 153.130657 -409.672286) (xy 153.180239 -409.694924) (xy 153.226094 -409.724388) (xy 153.267289 -409.760079)
			(xy 153.302984 -409.801269) (xy 153.332454 -409.847121) (xy 153.355098 -409.8967) (xy 153.370455 -409.948997)
			(xy 153.378213 -410.002947) (xy 153.378213 -410.057453) (xy 154.815746 -410.057453) (xy 154.815746 -410.002947)
			(xy 154.823503 -409.948995) (xy 154.838859 -409.896696) (xy 154.861502 -409.847115) (xy 154.89097 -409.801261)
			(xy 154.926664 -409.760068) (xy 154.967857 -409.724373) (xy 155.01371 -409.694904) (xy 155.063291 -409.672261)
			(xy 155.115589 -409.656904) (xy 155.169541 -409.649146) (xy 155.196794 -409.64866) (xy 156.060394 -409.64866)
			(xy 156.087645 -409.649187) (xy 156.141592 -409.656942) (xy 156.193886 -409.672297) (xy 156.243463 -409.694937)
			(xy 156.289313 -409.724402) (xy 156.330503 -409.760093) (xy 156.366194 -409.801282) (xy 156.39566 -409.847132)
			(xy 156.418301 -409.896708) (xy 156.433656 -409.949002) (xy 156.441413 -410.002949) (xy 156.441413 -410.057451)
			(xy 156.441412 -410.057457) (xy 157.878923 -410.057457) (xy 157.878923 -410.002943) (xy 157.886682 -409.948985)
			(xy 157.902041 -409.89668) (xy 157.924687 -409.847093) (xy 157.954161 -409.801235) (xy 157.989862 -409.760037)
			(xy 158.031062 -409.724341) (xy 158.076923 -409.694871) (xy 158.126512 -409.672229) (xy 158.178818 -409.656874)
			(xy 158.232777 -409.649121) (xy 158.260034 -409.64866) (xy 159.123634 -409.64866) (xy 159.150881 -409.649213)
			(xy 159.204821 -409.656972) (xy 159.257107 -409.672329) (xy 159.306676 -409.69497) (xy 159.352518 -409.724435)
			(xy 159.393701 -409.760123) (xy 159.429385 -409.801309) (xy 159.458846 -409.847154) (xy 159.481483 -409.896725)
			(xy 159.496835 -409.949012) (xy 159.50459 -410.002953) (xy 159.50459 -410.057447) (xy 159.504589 -410.057452)
			(xy 160.942246 -410.057452) (xy 160.942246 -410.002948) (xy 160.950002 -409.948998) (xy 160.965357 -409.896701)
			(xy 160.987999 -409.847121) (xy 161.017465 -409.801268) (xy 161.053157 -409.760075) (xy 161.094347 -409.72438)
			(xy 161.140198 -409.694911) (xy 161.189776 -409.672266) (xy 161.242072 -409.656908) (xy 161.296022 -409.649148)
			(xy 161.323274 -409.64866) (xy 162.186874 -409.64866) (xy 162.214126 -409.649185) (xy 162.268075 -409.656939)
			(xy 162.320372 -409.672291) (xy 162.369951 -409.69493) (xy 162.415803 -409.724395) (xy 162.456996 -409.760086)
			(xy 162.492689 -409.801276) (xy 162.522157 -409.847126) (xy 162.5448 -409.896704) (xy 162.560156 -409.949)
			(xy 162.567913 -410.002948) (xy 162.567913 -410.057452) (xy 162.567912 -410.057456) (xy 164.005423 -410.057456)
			(xy 164.005423 -410.002944) (xy 164.013181 -409.948987) (xy 164.028539 -409.896684) (xy 164.051184 -409.847099)
			(xy 164.080656 -409.801241) (xy 164.116354 -409.760045) (xy 164.157552 -409.724348) (xy 164.203411 -409.694878)
			(xy 164.252997 -409.672234) (xy 164.305301 -409.656878) (xy 164.359258 -409.649122) (xy 164.386514 -409.64866)
			(xy 165.250114 -409.64866) (xy 165.277362 -409.649211) (xy 165.331304 -409.656969) (xy 165.383593 -409.672324)
			(xy 165.433164 -409.694964) (xy 165.479009 -409.724428) (xy 165.520194 -409.760116) (xy 165.555881 -409.801303)
			(xy 165.585343 -409.847149) (xy 165.607981 -409.896721) (xy 165.623334 -409.94901) (xy 165.63109 -410.002952)
			(xy 165.63109 -410.057448) (xy 165.63109 -410.057451) (xy 167.068746 -410.057451) (xy 167.068746 -410.002949)
			(xy 167.076502 -409.949) (xy 167.091856 -409.896705) (xy 167.114495 -409.847127) (xy 167.14396 -409.801275)
			(xy 167.179649 -409.760082) (xy 167.220838 -409.724388) (xy 167.266686 -409.694918) (xy 167.316262 -409.672272)
			(xy 167.368555 -409.656911) (xy 167.422503 -409.649149) (xy 167.449754 -409.64866) (xy 168.313354 -409.64866)
			(xy 168.340607 -409.649184) (xy 168.394558 -409.656935) (xy 168.446857 -409.672286) (xy 168.496439 -409.694924)
			(xy 168.542294 -409.724388) (xy 168.583489 -409.760079) (xy 168.619184 -409.801269) (xy 168.648654 -409.847121)
			(xy 168.671298 -409.8967) (xy 168.686655 -409.948997) (xy 168.694413 -410.002947) (xy 168.694413 -410.057453)
			(xy 168.686655 -410.111403) (xy 168.671298 -410.1637) (xy 168.648654 -410.213279) (xy 168.619184 -410.259131)
			(xy 168.583489 -410.300321) (xy 168.542294 -410.336012) (xy 168.496439 -410.365476) (xy 168.446857 -410.388114)
			(xy 168.394558 -410.403465) (xy 168.340607 -410.411216) (xy 168.313354 -410.411676) (xy 167.449754 -410.411676)
			(xy 167.422503 -410.411251) (xy 167.368555 -410.403489) (xy 167.316262 -410.388128) (xy 167.266686 -410.365482)
			(xy 167.220838 -410.336012) (xy 167.179649 -410.300318) (xy 167.14396 -410.259125) (xy 167.114495 -410.213273)
			(xy 167.091856 -410.163695) (xy 167.076502 -410.1114) (xy 167.068746 -410.057451) (xy 165.63109 -410.057451)
			(xy 165.623334 -410.11139) (xy 165.607981 -410.163679) (xy 165.585343 -410.213251) (xy 165.555881 -410.259097)
			(xy 165.520194 -410.300284) (xy 165.479009 -410.335972) (xy 165.433164 -410.365436) (xy 165.383593 -410.388076)
			(xy 165.331304 -410.403431) (xy 165.277362 -410.411189) (xy 165.250114 -410.411676) (xy 164.386514 -410.411676)
			(xy 164.359258 -410.411278) (xy 164.305301 -410.403522) (xy 164.252997 -410.388166) (xy 164.203411 -410.365522)
			(xy 164.157552 -410.336052) (xy 164.116354 -410.300355) (xy 164.080656 -410.259159) (xy 164.051184 -410.213301)
			(xy 164.028539 -410.163716) (xy 164.013181 -410.111413) (xy 164.005423 -410.057456) (xy 162.567912 -410.057456)
			(xy 162.560156 -410.1114) (xy 162.5448 -410.163696) (xy 162.522157 -410.213274) (xy 162.492689 -410.259124)
			(xy 162.456996 -410.300314) (xy 162.415803 -410.336005) (xy 162.369951 -410.36547) (xy 162.320372 -410.388109)
			(xy 162.268075 -410.403461) (xy 162.214126 -410.411215) (xy 162.186874 -410.411676) (xy 161.323274 -410.411676)
			(xy 161.296022 -410.411252) (xy 161.242072 -410.403492) (xy 161.189776 -410.388134) (xy 161.140198 -410.365489)
			(xy 161.094347 -410.33602) (xy 161.053157 -410.300325) (xy 161.017465 -410.259132) (xy 160.987999 -410.213279)
			(xy 160.965357 -410.163699) (xy 160.950002 -410.111402) (xy 160.942246 -410.057452) (xy 159.504589 -410.057452)
			(xy 159.496835 -410.111388) (xy 159.481483 -410.163675) (xy 159.458846 -410.213246) (xy 159.429385 -410.259091)
			(xy 159.393701 -410.300277) (xy 159.352518 -410.335965) (xy 159.306676 -410.36543) (xy 159.257107 -410.388071)
			(xy 159.204821 -410.403428) (xy 159.150881 -410.411187) (xy 159.123634 -410.411676) (xy 158.260034 -410.411676)
			(xy 158.232777 -410.411279) (xy 158.178818 -410.403526) (xy 158.126512 -410.388171) (xy 158.076923 -410.365529)
			(xy 158.031062 -410.336059) (xy 157.989862 -410.300363) (xy 157.954161 -410.259165) (xy 157.924687 -410.213307)
			(xy 157.902041 -410.16372) (xy 157.886682 -410.111415) (xy 157.878923 -410.057457) (xy 156.441412 -410.057457)
			(xy 156.433656 -410.111398) (xy 156.418301 -410.163692) (xy 156.39566 -410.213268) (xy 156.366194 -410.259118)
			(xy 156.330503 -410.300307) (xy 156.289313 -410.335998) (xy 156.243463 -410.365463) (xy 156.193886 -410.388103)
			(xy 156.141592 -410.403458) (xy 156.087645 -410.411213) (xy 156.060394 -410.411676) (xy 155.196794 -410.411676)
			(xy 155.169541 -410.411254) (xy 155.115589 -410.403496) (xy 155.063291 -410.388139) (xy 155.01371 -410.365496)
			(xy 154.967857 -410.336027) (xy 154.926664 -410.300332) (xy 154.89097 -410.259139) (xy 154.861502 -410.213285)
			(xy 154.838859 -410.163704) (xy 154.823503 -410.111405) (xy 154.815746 -410.057453) (xy 153.378213 -410.057453)
			(xy 153.370455 -410.111403) (xy 153.355098 -410.1637) (xy 153.332454 -410.213279) (xy 153.302984 -410.259131)
			(xy 153.267289 -410.300321) (xy 153.226094 -410.336012) (xy 153.180239 -410.365476) (xy 153.130657 -410.388114)
			(xy 153.078358 -410.403465) (xy 153.024407 -410.411216) (xy 152.997154 -410.411676) (xy 152.133554 -410.411676)
			(xy 152.106303 -410.411251) (xy 152.052355 -410.403489) (xy 152.000062 -410.388128) (xy 151.950486 -410.365482)
			(xy 151.904638 -410.336012) (xy 151.863449 -410.300318) (xy 151.82776 -410.259125) (xy 151.798295 -410.213273)
			(xy 151.775656 -410.163695) (xy 151.760302 -410.1114) (xy 151.752546 -410.057451) (xy 150.31489 -410.057451)
			(xy 150.307134 -410.11139) (xy 150.291781 -410.163679) (xy 150.269143 -410.213251) (xy 150.239681 -410.259097)
			(xy 150.203994 -410.300284) (xy 150.162809 -410.335972) (xy 150.116964 -410.365436) (xy 150.067393 -410.388076)
			(xy 150.015104 -410.403431) (xy 149.961162 -410.411189) (xy 149.933914 -410.411676) (xy 149.070314 -410.411676)
			(xy 149.043058 -410.411278) (xy 148.989101 -410.403522) (xy 148.936797 -410.388166) (xy 148.887211 -410.365522)
			(xy 148.841352 -410.336052) (xy 148.800154 -410.300355) (xy 148.764456 -410.259159) (xy 148.734984 -410.213301)
			(xy 148.712339 -410.163716) (xy 148.696981 -410.111413) (xy 148.689223 -410.057456) (xy 147.251712 -410.057456)
			(xy 147.243956 -410.1114) (xy 147.2286 -410.163696) (xy 147.205957 -410.213274) (xy 147.176489 -410.259124)
			(xy 147.140796 -410.300314) (xy 147.099603 -410.336005) (xy 147.053751 -410.36547) (xy 147.004172 -410.388109)
			(xy 146.951875 -410.403461) (xy 146.897926 -410.411215) (xy 146.870674 -410.411676) (xy 146.007074 -410.411676)
			(xy 145.979822 -410.411252) (xy 145.925872 -410.403492) (xy 145.873576 -410.388134) (xy 145.823998 -410.365489)
			(xy 145.778147 -410.33602) (xy 145.736957 -410.300325) (xy 145.701265 -410.259132) (xy 145.671799 -410.213279)
			(xy 145.649157 -410.163699) (xy 145.633802 -410.111402) (xy 145.626046 -410.057452) (xy 144.188389 -410.057452)
			(xy 144.180635 -410.111388) (xy 144.165283 -410.163675) (xy 144.142646 -410.213246) (xy 144.113185 -410.259091)
			(xy 144.077501 -410.300277) (xy 144.036318 -410.335965) (xy 143.990476 -410.36543) (xy 143.940907 -410.388071)
			(xy 143.888621 -410.403428) (xy 143.834681 -410.411187) (xy 143.807434 -410.411676) (xy 142.943834 -410.411676)
			(xy 142.916577 -410.411279) (xy 142.862618 -410.403526) (xy 142.810312 -410.388171) (xy 142.760723 -410.365529)
			(xy 142.714862 -410.336059) (xy 142.673662 -410.300363) (xy 142.637961 -410.259165) (xy 142.608487 -410.213307)
			(xy 142.585841 -410.16372) (xy 142.570482 -410.111415) (xy 142.562723 -410.057457) (xy 141.125212 -410.057457)
			(xy 141.117456 -410.111398) (xy 141.102101 -410.163692) (xy 141.07946 -410.213268) (xy 141.049994 -410.259118)
			(xy 141.014303 -410.300307) (xy 140.973113 -410.335998) (xy 140.927263 -410.365463) (xy 140.877686 -410.388103)
			(xy 140.825392 -410.403458) (xy 140.771445 -410.411213) (xy 140.744194 -410.411676) (xy 139.880594 -410.411676)
			(xy 139.853341 -410.411254) (xy 139.799389 -410.403496) (xy 139.747091 -410.388139) (xy 139.69751 -410.365496)
			(xy 139.651657 -410.336027) (xy 139.610464 -410.300332) (xy 139.57477 -410.259139) (xy 139.545302 -410.213285)
			(xy 139.522659 -410.163704) (xy 139.507303 -410.111405) (xy 139.499546 -410.057453) (xy 138.062013 -410.057453)
			(xy 138.054255 -410.111403) (xy 138.038898 -410.1637) (xy 138.016254 -410.213279) (xy 137.986784 -410.259131)
			(xy 137.951089 -410.300321) (xy 137.909894 -410.336012) (xy 137.864039 -410.365476) (xy 137.814457 -410.388114)
			(xy 137.762158 -410.403465) (xy 137.708207 -410.411216) (xy 137.680954 -410.411676) (xy 136.817354 -410.411676)
			(xy 136.790103 -410.411251) (xy 136.736155 -410.403489) (xy 136.683862 -410.388128) (xy 136.634286 -410.365482)
			(xy 136.588438 -410.336012) (xy 136.547249 -410.300318) (xy 136.51156 -410.259125) (xy 136.482095 -410.213273)
			(xy 136.459456 -410.163695) (xy 136.444102 -410.1114) (xy 136.436346 -410.057451) (xy 134.99869 -410.057451)
			(xy 134.990934 -410.11139) (xy 134.975581 -410.163679) (xy 134.952943 -410.213251) (xy 134.923481 -410.259097)
			(xy 134.887794 -410.300284) (xy 134.846609 -410.335972) (xy 134.800764 -410.365436) (xy 134.751193 -410.388076)
			(xy 134.698904 -410.403431) (xy 134.644962 -410.411189) (xy 134.617714 -410.411676) (xy 133.754114 -410.411676)
			(xy 133.726858 -410.411278) (xy 133.672901 -410.403522) (xy 133.620597 -410.388166) (xy 133.571011 -410.365522)
			(xy 133.525152 -410.336052) (xy 133.483954 -410.300355) (xy 133.448256 -410.259159) (xy 133.418784 -410.213301)
			(xy 133.396139 -410.163716) (xy 133.380781 -410.111413) (xy 133.373023 -410.057456) (xy 131.935512 -410.057456)
			(xy 131.927756 -410.1114) (xy 131.9124 -410.163696) (xy 131.889757 -410.213274) (xy 131.860289 -410.259124)
			(xy 131.824596 -410.300314) (xy 131.783403 -410.336005) (xy 131.737551 -410.36547) (xy 131.687972 -410.388109)
			(xy 131.635675 -410.403461) (xy 131.581726 -410.411215) (xy 131.554474 -410.411676) (xy 130.690874 -410.411676)
			(xy 130.663622 -410.411252) (xy 130.609672 -410.403492) (xy 130.557376 -410.388134) (xy 130.507798 -410.365489)
			(xy 130.461947 -410.33602) (xy 130.420757 -410.300325) (xy 130.385065 -410.259132) (xy 130.355599 -410.213279)
			(xy 130.332957 -410.163699) (xy 130.317602 -410.111402) (xy 130.309846 -410.057452) (xy 128.872189 -410.057452)
			(xy 128.864435 -410.111388) (xy 128.849083 -410.163675) (xy 128.826446 -410.213246) (xy 128.796985 -410.259091)
			(xy 128.761301 -410.300277) (xy 128.720118 -410.335965) (xy 128.674276 -410.36543) (xy 128.624707 -410.388071)
			(xy 128.572421 -410.403428) (xy 128.518481 -410.411187) (xy 128.491234 -410.411676) (xy 127.627634 -410.411676)
			(xy 127.600377 -410.411279) (xy 127.546418 -410.403526) (xy 127.494112 -410.388171) (xy 127.444523 -410.365529)
			(xy 127.398662 -410.336059) (xy 127.357462 -410.300363) (xy 127.321761 -410.259165) (xy 127.292287 -410.213307)
			(xy 127.269641 -410.16372) (xy 127.254282 -410.111415) (xy 127.246523 -410.057457) (xy 125.809012 -410.057457)
			(xy 125.801256 -410.111398) (xy 125.785901 -410.163692) (xy 125.76326 -410.213268) (xy 125.733794 -410.259118)
			(xy 125.698103 -410.300307) (xy 125.656913 -410.335998) (xy 125.611063 -410.365463) (xy 125.561486 -410.388103)
			(xy 125.509192 -410.403458) (xy 125.455245 -410.411213) (xy 125.427994 -410.411676) (xy 124.564394 -410.411676)
			(xy 124.537141 -410.411254) (xy 124.483189 -410.403496) (xy 124.430891 -410.388139) (xy 124.38131 -410.365496)
			(xy 124.335457 -410.336027) (xy 124.294264 -410.300332) (xy 124.25857 -410.259139) (xy 124.229102 -410.213285)
			(xy 124.206459 -410.163704) (xy 124.191103 -410.111405) (xy 124.183346 -410.057453) (xy 122.745813 -410.057453)
			(xy 122.738055 -410.111403) (xy 122.722698 -410.1637) (xy 122.700054 -410.213279) (xy 122.670584 -410.259131)
			(xy 122.634889 -410.300321) (xy 122.593694 -410.336012) (xy 122.547839 -410.365476) (xy 122.498257 -410.388114)
			(xy 122.445958 -410.403465) (xy 122.392007 -410.411216) (xy 122.364754 -410.411676) (xy 121.501154 -410.411676)
			(xy 121.473903 -410.411251) (xy 121.419955 -410.403489) (xy 121.367662 -410.388128) (xy 121.318086 -410.365482)
			(xy 121.272238 -410.336012) (xy 121.231049 -410.300318) (xy 121.19536 -410.259125) (xy 121.165895 -410.213273)
			(xy 121.143256 -410.163695) (xy 121.127902 -410.1114) (xy 121.120146 -410.057451) (xy 96.519189 -410.057451)
			(xy 96.511435 -410.111387) (xy 96.496083 -410.163674) (xy 96.473447 -410.213245) (xy 96.443986 -410.259089)
			(xy 96.408302 -410.300275) (xy 96.36712 -410.335964) (xy 96.321278 -410.365428) (xy 96.27171 -410.38807)
			(xy 96.219424 -410.403427) (xy 96.165485 -410.411187) (xy 96.138238 -410.411676) (xy 95.274638 -410.411676)
			(xy 95.247381 -410.41128) (xy 95.193421 -410.403526) (xy 95.141115 -410.388172) (xy 95.091525 -410.36553)
			(xy 95.045664 -410.336061) (xy 95.004463 -410.300364) (xy 94.968762 -410.259167) (xy 94.939288 -410.213308)
			(xy 94.916641 -410.163721) (xy 94.901282 -410.111416) (xy 94.893523 -410.057457) (xy 93.456012 -410.057457)
			(xy 93.448256 -410.111397) (xy 93.432902 -410.163691) (xy 93.410261 -410.213267) (xy 93.380795 -410.259116)
			(xy 93.345104 -410.300306) (xy 93.303915 -410.335996) (xy 93.258065 -410.365462) (xy 93.208489 -410.388102)
			(xy 93.156195 -410.403457) (xy 93.102249 -410.411213) (xy 93.074998 -410.411676) (xy 92.211398 -410.411676)
			(xy 92.184145 -410.411254) (xy 92.130193 -410.403497) (xy 92.077894 -410.38814) (xy 92.028313 -410.365497)
			(xy 91.982459 -410.336028) (xy 91.941265 -410.300334) (xy 91.905571 -410.25914) (xy 91.876102 -410.213286)
			(xy 91.853459 -410.163705) (xy 91.838103 -410.111406) (xy 91.830346 -410.057453) (xy 90.392813 -410.057453)
			(xy 90.385055 -410.111403) (xy 90.369698 -410.163699) (xy 90.347055 -410.213278) (xy 90.317585 -410.259129)
			(xy 90.28189 -410.30032) (xy 90.240696 -410.33601) (xy 90.194841 -410.365475) (xy 90.14526 -410.388113)
			(xy 90.092961 -410.403464) (xy 90.039011 -410.411216) (xy 90.011758 -410.411676) (xy 89.148158 -410.411676)
			(xy 89.120906 -410.411251) (xy 89.066959 -410.403489) (xy 89.014665 -410.388129) (xy 88.965089 -410.365484)
			(xy 88.91924 -410.336014) (xy 88.878051 -410.300319) (xy 88.842361 -410.259127) (xy 88.812896 -410.213275)
			(xy 88.790256 -410.163696) (xy 88.774902 -410.1114) (xy 88.767146 -410.057452) (xy 87.329489 -410.057452)
			(xy 87.321734 -410.11139) (xy 87.306382 -410.163679) (xy 87.283744 -410.21325) (xy 87.254282 -410.259096)
			(xy 87.218595 -410.300282) (xy 87.17741 -410.335971) (xy 87.131566 -410.365435) (xy 87.081995 -410.388075)
			(xy 87.029707 -410.403431) (xy 86.975766 -410.411189) (xy 86.948518 -410.411676) (xy 86.084918 -410.411676)
			(xy 86.057662 -410.411278) (xy 86.003705 -410.403523) (xy 85.9514 -410.388167) (xy 85.901813 -410.365524)
			(xy 85.855954 -410.336054) (xy 85.814756 -410.300357) (xy 85.779057 -410.25916) (xy 85.749585 -410.213302)
			(xy 85.726939 -410.163717) (xy 85.711581 -410.111413) (xy 85.703823 -410.057456) (xy 84.266312 -410.057456)
			(xy 84.258556 -410.1114) (xy 84.2432 -410.163695) (xy 84.220558 -410.213273) (xy 84.19109 -410.259123)
			(xy 84.155397 -410.300313) (xy 84.114205 -410.336003) (xy 84.068353 -410.365468) (xy 84.018774 -410.388108)
			(xy 83.966478 -410.40346) (xy 83.91253 -410.411214) (xy 83.885278 -410.411676) (xy 83.021678 -410.411676)
			(xy 82.994425 -410.411253) (xy 82.940476 -410.403493) (xy 82.888179 -410.388135) (xy 82.838601 -410.36549)
			(xy 82.792749 -410.336021) (xy 82.751558 -410.300326) (xy 82.715866 -410.259133) (xy 82.686399 -410.21328)
			(xy 82.663758 -410.1637) (xy 82.648402 -410.111403) (xy 82.640646 -410.057453) (xy 81.202989 -410.057453)
			(xy 81.195235 -410.111387) (xy 81.179883 -410.163674) (xy 81.157247 -410.213245) (xy 81.127786 -410.259089)
			(xy 81.092102 -410.300275) (xy 81.05092 -410.335964) (xy 81.005078 -410.365428) (xy 80.95551 -410.38807)
			(xy 80.903224 -410.403427) (xy 80.849285 -410.411187) (xy 80.822038 -410.411676) (xy 79.958438 -410.411676)
			(xy 79.931181 -410.41128) (xy 79.877221 -410.403526) (xy 79.824915 -410.388172) (xy 79.775325 -410.36553)
			(xy 79.729464 -410.336061) (xy 79.688263 -410.300364) (xy 79.652562 -410.259167) (xy 79.623088 -410.213308)
			(xy 79.600441 -410.163721) (xy 79.585082 -410.111416) (xy 79.577323 -410.057457) (xy 78.139812 -410.057457)
			(xy 78.132056 -410.111397) (xy 78.116702 -410.163691) (xy 78.094061 -410.213267) (xy 78.064595 -410.259116)
			(xy 78.028904 -410.300306) (xy 77.987715 -410.335996) (xy 77.941865 -410.365462) (xy 77.892289 -410.388102)
			(xy 77.839995 -410.403457) (xy 77.786049 -410.411213) (xy 77.758798 -410.411676) (xy 76.895198 -410.411676)
			(xy 76.867945 -410.411254) (xy 76.813993 -410.403497) (xy 76.761694 -410.38814) (xy 76.712113 -410.365497)
			(xy 76.666259 -410.336028) (xy 76.625065 -410.300334) (xy 76.589371 -410.25914) (xy 76.559902 -410.213286)
			(xy 76.537259 -410.163705) (xy 76.521903 -410.111406) (xy 76.514146 -410.057453) (xy 75.076613 -410.057453)
			(xy 75.068855 -410.111403) (xy 75.053498 -410.163699) (xy 75.030855 -410.213278) (xy 75.001385 -410.259129)
			(xy 74.96569 -410.30032) (xy 74.924496 -410.33601) (xy 74.878641 -410.365475) (xy 74.82906 -410.388113)
			(xy 74.776761 -410.403464) (xy 74.722811 -410.411216) (xy 74.695558 -410.411676) (xy 73.831958 -410.411676)
			(xy 73.804706 -410.411251) (xy 73.750759 -410.403489) (xy 73.698465 -410.388129) (xy 73.648889 -410.365484)
			(xy 73.60304 -410.336014) (xy 73.561851 -410.300319) (xy 73.526161 -410.259127) (xy 73.496696 -410.213275)
			(xy 73.474056 -410.163696) (xy 73.458702 -410.1114) (xy 73.450946 -410.057452) (xy 72.013289 -410.057452)
			(xy 72.005534 -410.11139) (xy 71.990182 -410.163679) (xy 71.967544 -410.21325) (xy 71.938082 -410.259096)
			(xy 71.902395 -410.300282) (xy 71.86121 -410.335971) (xy 71.815366 -410.365435) (xy 71.765795 -410.388075)
			(xy 71.713507 -410.403431) (xy 71.659566 -410.411189) (xy 71.632318 -410.411676) (xy 70.768718 -410.411676)
			(xy 70.741462 -410.411278) (xy 70.687505 -410.403523) (xy 70.6352 -410.388167) (xy 70.585613 -410.365524)
			(xy 70.539754 -410.336054) (xy 70.498556 -410.300357) (xy 70.462857 -410.25916) (xy 70.433385 -410.213302)
			(xy 70.410739 -410.163717) (xy 70.395381 -410.111413) (xy 70.387623 -410.057456) (xy 68.950112 -410.057456)
			(xy 68.942356 -410.1114) (xy 68.927 -410.163695) (xy 68.904358 -410.213273) (xy 68.87489 -410.259123)
			(xy 68.839197 -410.300313) (xy 68.798005 -410.336003) (xy 68.752153 -410.365468) (xy 68.702574 -410.388108)
			(xy 68.650278 -410.40346) (xy 68.59633 -410.411214) (xy 68.569078 -410.411676) (xy 67.705478 -410.411676)
			(xy 67.678225 -410.411253) (xy 67.624276 -410.403493) (xy 67.571979 -410.388135) (xy 67.522401 -410.36549)
			(xy 67.476549 -410.336021) (xy 67.435358 -410.300326) (xy 67.399666 -410.259133) (xy 67.370199 -410.21328)
			(xy 67.347558 -410.1637) (xy 67.332202 -410.111403) (xy 67.324446 -410.057453) (xy 65.886789 -410.057453)
			(xy 65.879035 -410.111387) (xy 65.863683 -410.163674) (xy 65.841047 -410.213245) (xy 65.811586 -410.259089)
			(xy 65.775902 -410.300275) (xy 65.73472 -410.335964) (xy 65.688878 -410.365428) (xy 65.63931 -410.38807)
			(xy 65.587024 -410.403427) (xy 65.533085 -410.411187) (xy 65.505838 -410.411676) (xy 64.642238 -410.411676)
			(xy 64.614981 -410.41128) (xy 64.561021 -410.403526) (xy 64.508715 -410.388172) (xy 64.459125 -410.36553)
			(xy 64.413264 -410.336061) (xy 64.372063 -410.300364) (xy 64.336362 -410.259167) (xy 64.306888 -410.213308)
			(xy 64.284241 -410.163721) (xy 64.268882 -410.111416) (xy 64.261123 -410.057457) (xy 62.823612 -410.057457)
			(xy 62.815856 -410.111397) (xy 62.800502 -410.163691) (xy 62.777861 -410.213267) (xy 62.748395 -410.259116)
			(xy 62.712704 -410.300306) (xy 62.671515 -410.335996) (xy 62.625665 -410.365462) (xy 62.576089 -410.388102)
			(xy 62.523795 -410.403457) (xy 62.469849 -410.411213) (xy 62.442598 -410.411676) (xy 61.578998 -410.411676)
			(xy 61.551745 -410.411254) (xy 61.497793 -410.403497) (xy 61.445494 -410.38814) (xy 61.395913 -410.365497)
			(xy 61.350059 -410.336028) (xy 61.308865 -410.300334) (xy 61.273171 -410.25914) (xy 61.243702 -410.213286)
			(xy 61.221059 -410.163705) (xy 61.205703 -410.111406) (xy 61.197946 -410.057453) (xy 59.760413 -410.057453)
			(xy 59.752655 -410.111403) (xy 59.737298 -410.163699) (xy 59.714655 -410.213278) (xy 59.685185 -410.259129)
			(xy 59.64949 -410.30032) (xy 59.608296 -410.33601) (xy 59.562441 -410.365475) (xy 59.51286 -410.388113)
			(xy 59.460561 -410.403464) (xy 59.406611 -410.411216) (xy 59.379358 -410.411676) (xy 58.515758 -410.411676)
			(xy 58.488506 -410.411251) (xy 58.434559 -410.403489) (xy 58.382265 -410.388129) (xy 58.332689 -410.365484)
			(xy 58.28684 -410.336014) (xy 58.245651 -410.300319) (xy 58.209961 -410.259127) (xy 58.180496 -410.213275)
			(xy 58.157856 -410.163696) (xy 58.142502 -410.1114) (xy 58.134746 -410.057452) (xy 56.697089 -410.057452)
			(xy 56.689334 -410.11139) (xy 56.673982 -410.163679) (xy 56.651344 -410.21325) (xy 56.621882 -410.259096)
			(xy 56.586195 -410.300282) (xy 56.54501 -410.335971) (xy 56.499166 -410.365435) (xy 56.449595 -410.388075)
			(xy 56.397307 -410.403431) (xy 56.343366 -410.411189) (xy 56.316118 -410.411676) (xy 55.452518 -410.411676)
			(xy 55.425262 -410.411278) (xy 55.371305 -410.403523) (xy 55.319 -410.388167) (xy 55.269413 -410.365524)
			(xy 55.223554 -410.336054) (xy 55.182356 -410.300357) (xy 55.146657 -410.25916) (xy 55.117185 -410.213302)
			(xy 55.094539 -410.163717) (xy 55.079181 -410.111413) (xy 55.071423 -410.057456) (xy 53.633912 -410.057456)
			(xy 53.626156 -410.1114) (xy 53.6108 -410.163695) (xy 53.588158 -410.213273) (xy 53.55869 -410.259123)
			(xy 53.522997 -410.300313) (xy 53.481805 -410.336003) (xy 53.435953 -410.365468) (xy 53.386374 -410.388108)
			(xy 53.334078 -410.40346) (xy 53.28013 -410.411214) (xy 53.252878 -410.411676) (xy 52.389278 -410.411676)
			(xy 52.362025 -410.411253) (xy 52.308076 -410.403493) (xy 52.255779 -410.388135) (xy 52.206201 -410.36549)
			(xy 52.160349 -410.336021) (xy 52.119158 -410.300326) (xy 52.083466 -410.259133) (xy 52.053999 -410.21328)
			(xy 52.031358 -410.1637) (xy 52.016002 -410.111403) (xy 52.008246 -410.057453) (xy 50.570589 -410.057453)
			(xy 50.562835 -410.111387) (xy 50.547483 -410.163674) (xy 50.524847 -410.213245) (xy 50.495386 -410.259089)
			(xy 50.459702 -410.300275) (xy 50.41852 -410.335964) (xy 50.372678 -410.365428) (xy 50.32311 -410.38807)
			(xy 50.270824 -410.403427) (xy 50.216885 -410.411187) (xy 50.189638 -410.411676) (xy 49.326038 -410.411676)
			(xy 49.298781 -410.41128) (xy 49.244821 -410.403526) (xy 49.192515 -410.388172) (xy 49.142925 -410.36553)
			(xy 49.097064 -410.336061) (xy 49.055863 -410.300364) (xy 49.020162 -410.259167) (xy 48.990688 -410.213308)
			(xy 48.968041 -410.163721) (xy 48.952682 -410.111416) (xy 48.944923 -410.057457) (xy 7.00913 -410.057457)
			(xy 7.00913 -411.241049) (xy 101.876886 -411.241049) (xy 101.876886 -411.186551) (xy 101.884641 -411.132608)
			(xy 101.899994 -411.080318) (xy 101.922631 -411.030744) (xy 101.952093 -410.984897) (xy 101.98778 -410.943708)
			(xy 102.028964 -410.908017) (xy 102.074809 -410.878551) (xy 102.12438 -410.855908) (xy 102.176669 -410.840549)
			(xy 102.230611 -410.832788) (xy 102.25786 -410.8323) (xy 103.12146 -410.8323) (xy 103.148715 -410.832745)
			(xy 103.202672 -410.840497) (xy 103.254975 -410.85585) (xy 103.304562 -410.878491) (xy 103.350421 -410.907958)
			(xy 103.391619 -410.943653) (xy 103.427318 -410.984847) (xy 103.45679 -411.030703) (xy 103.479436 -411.080287)
			(xy 103.494794 -411.132589) (xy 103.502553 -411.186545) (xy 103.502553 -411.241055) (xy 103.494794 -411.295011)
			(xy 103.479436 -411.347313) (xy 103.45679 -411.396897) (xy 103.427318 -411.442753) (xy 103.391619 -411.483947)
			(xy 103.350421 -411.519642) (xy 103.304562 -411.549109) (xy 103.254975 -411.57175) (xy 103.202672 -411.587103)
			(xy 103.148715 -411.594855) (xy 103.12146 -411.595316) (xy 102.25786 -411.595316) (xy 102.230611 -411.594812)
			(xy 102.176669 -411.587051) (xy 102.12438 -411.571692) (xy 102.074809 -411.549049) (xy 102.028964 -411.519583)
			(xy 101.98778 -411.483892) (xy 101.952093 -411.442703) (xy 101.922631 -411.396856) (xy 101.899994 -411.347282)
			(xy 101.884641 -411.294992) (xy 101.876886 -411.241049) (xy 7.00913 -411.241049) (xy 7.00913 -424.470068)
			(xy 39.528496 -424.470068) (xy 39.528496 -417.770056) (xy 39.529001 -417.664532) (xy 39.537085 -417.453638)
			(xy 39.553241 -417.243209) (xy 39.577444 -417.033552) (xy 39.609661 -416.824977) (xy 39.649843 -416.617789)
			(xy 39.697931 -416.412292) (xy 39.753855 -416.208788) (xy 39.817532 -416.007575) (xy 39.88887 -415.808948)
			(xy 39.967764 -415.6132) (xy 40.054097 -415.420618) (xy 40.147744 -415.231483) (xy 40.248566 -415.046074)
			(xy 40.356416 -414.864663) (xy 40.471135 -414.687516) (xy 40.592555 -414.514894) (xy 40.720498 -414.347048)
			(xy 40.854776 -414.184226) (xy 40.995192 -414.026667) (xy 41.14154 -413.874602) (xy 41.293605 -413.728254)
			(xy 41.451164 -413.587838) (xy 41.613986 -413.45356) (xy 41.781832 -413.325617) (xy 41.954454 -413.204197)
			(xy 42.131601 -413.089478) (xy 42.313012 -412.981628) (xy 42.498421 -412.880806) (xy 42.687556 -412.787159)
			(xy 42.880138 -412.700826) (xy 43.075886 -412.621932) (xy 43.274513 -412.550594) (xy 43.475726 -412.486917)
			(xy 43.67923 -412.430993) (xy 43.884727 -412.382905) (xy 44.091915 -412.342723) (xy 44.30049 -412.310506)
			(xy 44.510147 -412.286303) (xy 44.720576 -412.270147) (xy 44.93147 -412.262063) (xy 45.142518 -412.262063)
			(xy 45.353412 -412.270147) (xy 45.563841 -412.286303) (xy 45.773498 -412.310506) (xy 45.982073 -412.342723)
			(xy 46.189261 -412.382905) (xy 46.394758 -412.430993) (xy 46.598262 -412.486917) (xy 46.799475 -412.550594)
			(xy 46.998102 -412.621932) (xy 47.19385 -412.700826) (xy 47.386432 -412.787159) (xy 47.575567 -412.880806)
			(xy 47.760976 -412.981628) (xy 47.942387 -413.089478) (xy 48.119534 -413.204197) (xy 48.292156 -413.325617)
			(xy 48.460002 -413.45356) (xy 48.622824 -413.587838) (xy 48.649451 -413.611568) (xy 104.877616 -413.611568)
			(xy 104.877616 -412.747968) (xy 104.878102 -412.720717) (xy 104.885858 -412.666769) (xy 104.901213 -412.614474)
			(xy 104.923855 -412.564897) (xy 104.953321 -412.519047) (xy 104.989012 -412.477856) (xy 105.030203 -412.442165)
			(xy 105.076053 -412.412699) (xy 105.12563 -412.390057) (xy 105.177925 -412.374702) (xy 105.231873 -412.366946)
			(xy 105.286375 -412.366946) (xy 105.340323 -412.374702) (xy 105.392618 -412.390057) (xy 105.442195 -412.412699)
			(xy 105.488045 -412.442165) (xy 105.529236 -412.477856) (xy 105.564927 -412.519047) (xy 105.594393 -412.564897)
			(xy 105.617035 -412.614474) (xy 105.63239 -412.666769) (xy 105.640146 -412.720717) (xy 105.640632 -412.747968)
			(xy 105.640632 -413.611568) (xy 105.640146 -413.638819) (xy 105.63239 -413.692767) (xy 105.617035 -413.745062)
			(xy 105.594393 -413.794639) (xy 105.584722 -413.809688) (xy 116.689632 -413.809688) (xy 116.689632 -412.946088)
			(xy 116.690118 -412.918837) (xy 116.697874 -412.864889) (xy 116.713229 -412.812594) (xy 116.735871 -412.763017)
			(xy 116.765337 -412.717167) (xy 116.801028 -412.675976) (xy 116.842219 -412.640285) (xy 116.888069 -412.610819)
			(xy 116.937646 -412.588177) (xy 116.989941 -412.572822) (xy 117.043889 -412.565066) (xy 117.098391 -412.565066)
			(xy 117.152339 -412.572822) (xy 117.204634 -412.588177) (xy 117.254211 -412.610819) (xy 117.300061 -412.640285)
			(xy 117.341252 -412.675976) (xy 117.376943 -412.717167) (xy 117.406409 -412.763017) (xy 117.429051 -412.812594)
			(xy 117.444406 -412.864889) (xy 117.452162 -412.918837) (xy 117.452648 -412.946088) (xy 117.452648 -413.809688)
			(xy 117.452162 -413.836939) (xy 117.444406 -413.890887) (xy 117.429051 -413.943182) (xy 117.406409 -413.992759)
			(xy 117.376943 -414.038609) (xy 117.341252 -414.0798) (xy 117.300061 -414.115491) (xy 117.254211 -414.144957)
			(xy 117.204634 -414.167599) (xy 117.152339 -414.182954) (xy 117.098391 -414.19071) (xy 117.043889 -414.19071)
			(xy 116.989941 -414.182954) (xy 116.937646 -414.167599) (xy 116.888069 -414.144957) (xy 116.842219 -414.115491)
			(xy 116.801028 -414.0798) (xy 116.765337 -414.038609) (xy 116.735871 -413.992759) (xy 116.713229 -413.943182)
			(xy 116.697874 -413.890887) (xy 116.690118 -413.836939) (xy 116.689632 -413.809688) (xy 105.584722 -413.809688)
			(xy 105.564927 -413.840489) (xy 105.529236 -413.88168) (xy 105.488045 -413.917371) (xy 105.442195 -413.946837)
			(xy 105.392618 -413.969479) (xy 105.340323 -413.984834) (xy 105.286375 -413.99259) (xy 105.231873 -413.99259)
			(xy 105.177925 -413.984834) (xy 105.12563 -413.969479) (xy 105.076053 -413.946837) (xy 105.030203 -413.917371)
			(xy 104.989012 -413.88168) (xy 104.953321 -413.840489) (xy 104.923855 -413.794639) (xy 104.901213 -413.745062)
			(xy 104.885858 -413.692767) (xy 104.878102 -413.638819) (xy 104.877616 -413.611568) (xy 48.649451 -413.611568)
			(xy 48.780383 -413.728254) (xy 48.932448 -413.874602) (xy 49.078796 -414.026667) (xy 49.219212 -414.184226)
			(xy 49.35349 -414.347048) (xy 49.481433 -414.514894) (xy 49.602853 -414.687516) (xy 49.717572 -414.864663)
			(xy 49.825422 -415.046074) (xy 49.926244 -415.231483) (xy 50.019891 -415.420618) (xy 50.106224 -415.6132)
			(xy 50.133819 -415.681668) (xy 100.559616 -415.681668) (xy 100.559616 -414.818068) (xy 100.560102 -414.790817)
			(xy 100.567858 -414.736869) (xy 100.583213 -414.684574) (xy 100.605855 -414.634997) (xy 100.635321 -414.589147)
			(xy 100.671012 -414.547956) (xy 100.712203 -414.512265) (xy 100.758053 -414.482799) (xy 100.80763 -414.460157)
			(xy 100.859925 -414.444802) (xy 100.913873 -414.437046) (xy 100.968375 -414.437046) (xy 101.022323 -414.444802)
			(xy 101.074618 -414.460157) (xy 101.124195 -414.482799) (xy 101.170045 -414.512265) (xy 101.211236 -414.547956)
			(xy 101.246927 -414.589147) (xy 101.276393 -414.634997) (xy 101.299035 -414.684574) (xy 101.31439 -414.736869)
			(xy 101.322146 -414.790817) (xy 101.322632 -414.818068) (xy 101.322632 -415.681668) (xy 101.322146 -415.708919)
			(xy 101.31439 -415.762867) (xy 101.299035 -415.815162) (xy 101.276393 -415.864739) (xy 101.246927 -415.910589)
			(xy 101.211236 -415.95178) (xy 101.170045 -415.987471) (xy 101.124195 -416.016937) (xy 101.074618 -416.039579)
			(xy 101.022323 -416.054934) (xy 100.968375 -416.06269) (xy 100.913873 -416.06269) (xy 100.859925 -416.054934)
			(xy 100.80763 -416.039579) (xy 100.758053 -416.016937) (xy 100.712203 -415.987471) (xy 100.671012 -415.95178)
			(xy 100.635321 -415.910589) (xy 100.605855 -415.864739) (xy 100.583213 -415.815162) (xy 100.567858 -415.762867)
			(xy 100.560102 -415.708919) (xy 100.559616 -415.681668) (xy 50.133819 -415.681668) (xy 50.185118 -415.808948)
			(xy 50.256456 -416.007575) (xy 50.320133 -416.208788) (xy 50.376057 -416.412292) (xy 50.424145 -416.617789)
			(xy 50.464327 -416.824977) (xy 50.496544 -417.033552) (xy 50.520747 -417.243209) (xy 50.536903 -417.453638)
			(xy 50.544987 -417.664532) (xy 50.545492 -417.770056) (xy 50.545492 -420.089838) (xy 58.13806 -420.089838)
			(xy 58.138171 -420.074752) (xy 58.139951 -420.044634) (xy 58.141616 -420.02964) (xy 58.141616 -418.95014)
			(xy 58.139949 -418.935146) (xy 58.138169 -418.905028) (xy 58.13806 -418.889942) (xy 58.138171 -418.874856)
			(xy 58.139951 -418.844738) (xy 58.141616 -418.829744) (xy 58.141616 -418.218874) (xy 58.142085 -418.206785)
			(xy 58.149546 -418.183788) (xy 58.163733 -418.164211) (xy 58.183264 -418.14996) (xy 58.206237 -418.142424)
			(xy 58.218324 -418.141912) (xy 59.158124 -418.141912) (xy 59.170235 -418.142296) (xy 59.193265 -418.149803)
			(xy 59.212839 -418.164073) (xy 59.227033 -418.183702) (xy 59.234451 -418.206761) (xy 59.234832 -418.218874)
			(xy 59.234832 -420.760398) (xy 59.23439 -420.77249) (xy 59.226931 -420.795495) (xy 59.212739 -420.815078)
			(xy 59.193198 -420.829327) (xy 59.170215 -420.836854) (xy 59.158124 -420.83736) (xy 58.218324 -420.83736)
			(xy 58.206212 -420.836963) (xy 58.183179 -420.829465) (xy 58.163602 -420.8152) (xy 58.149408 -420.795571)
			(xy 58.141994 -420.772511) (xy 58.141616 -420.760398) (xy 58.141616 -420.150036) (xy 58.139948 -420.135042)
			(xy 58.138169 -420.104924) (xy 58.13806 -420.089838) (xy 50.545492 -420.089838) (xy 50.545492 -421.089836)
			(xy 60.138056 -421.089836) (xy 60.138167 -421.07475) (xy 60.139947 -421.044632) (xy 60.141612 -421.029638)
			(xy 60.141612 -419.950138) (xy 60.139945 -419.935144) (xy 60.138165 -419.905026) (xy 60.138056 -419.88994)
			(xy 60.138167 -419.874854) (xy 60.139947 -419.844736) (xy 60.141612 -419.829742) (xy 60.141612 -419.218872)
			(xy 60.14204 -419.206794) (xy 60.149513 -419.183822) (xy 60.163718 -419.164284) (xy 60.183265 -419.150091)
			(xy 60.206242 -419.142633) (xy 60.21832 -419.142164) (xy 61.15812 -419.142164) (xy 61.170193 -419.142647)
			(xy 61.193156 -419.150112) (xy 61.21269 -419.164304) (xy 61.226885 -419.183837) (xy 61.234352 -419.206799)
			(xy 61.234828 -419.218872) (xy 61.234828 -421.089836) (xy 68.13804 -421.089836) (xy 68.138151 -421.07475)
			(xy 68.139931 -421.044632) (xy 68.141596 -421.029638) (xy 68.141596 -419.950138) (xy 68.139929 -419.935144)
			(xy 68.138149 -419.905026) (xy 68.13804 -419.88994) (xy 68.138151 -419.874854) (xy 68.139931 -419.844736)
			(xy 68.141596 -419.829742) (xy 68.141596 -419.218872) (xy 68.14204 -419.206796) (xy 68.149511 -419.183827)
			(xy 68.163712 -419.16429) (xy 68.183255 -419.150096) (xy 68.206227 -419.142635) (xy 68.218304 -419.142164)
			(xy 69.158104 -419.142164) (xy 69.170176 -419.14266) (xy 69.193139 -419.150121) (xy 69.212673 -419.16431)
			(xy 69.226868 -419.18384) (xy 69.234336 -419.2068) (xy 69.234812 -419.218872) (xy 69.234812 -420.089838)
			(xy 70.138036 -420.089838) (xy 70.138149 -420.074753) (xy 70.139929 -420.044634) (xy 70.141592 -420.02964)
			(xy 70.141592 -418.95014) (xy 70.139925 -418.935146) (xy 70.138145 -418.905028) (xy 70.138036 -418.889942)
			(xy 70.13815 -418.874857) (xy 70.139929 -418.844738) (xy 70.141592 -418.829744) (xy 70.141592 -418.218874)
			(xy 70.142084 -418.206788) (xy 70.149542 -418.183794) (xy 70.163724 -418.164219) (xy 70.183249 -418.149968)
			(xy 70.206216 -418.142428) (xy 70.2183 -418.141912) (xy 71.1581 -418.141912) (xy 71.17021 -418.142316)
			(xy 71.193239 -418.149817) (xy 71.212814 -418.164081) (xy 71.227008 -418.183706) (xy 71.234426 -418.206762)
			(xy 71.234808 -418.218874) (xy 71.234808 -420.760398) (xy 71.234292 -420.772483) (xy 71.226841 -420.795475)
			(xy 71.212666 -420.815051) (xy 71.193146 -420.829303) (xy 71.170183 -420.836844) (xy 71.1581 -420.83736)
			(xy 70.2183 -420.83736) (xy 70.206187 -420.836983) (xy 70.183153 -420.829479) (xy 70.163576 -420.815209)
			(xy 70.149383 -420.795576) (xy 70.14197 -420.772512) (xy 70.141592 -420.760398) (xy 70.141592 -420.150036)
			(xy 70.139924 -420.135042) (xy 70.138145 -420.104924) (xy 70.138036 -420.089838) (xy 69.234812 -420.089838)
			(xy 69.234812 -421.089836) (xy 72.138032 -421.089836) (xy 72.138145 -421.074751) (xy 72.139925 -421.044632)
			(xy 72.141588 -421.029638) (xy 72.141588 -419.950138) (xy 72.13992 -419.935144) (xy 72.138141 -419.905026)
			(xy 72.138032 -419.88994) (xy 72.138145 -419.874855) (xy 72.139925 -419.844736) (xy 72.141588 -419.829742)
			(xy 72.141588 -419.218872) (xy 72.14204 -419.206796) (xy 72.14951 -419.183829) (xy 72.16371 -419.164293)
			(xy 72.18325 -419.150099) (xy 72.20622 -419.142636) (xy 72.218296 -419.142164) (xy 73.158096 -419.142164)
			(xy 73.170168 -419.142667) (xy 73.19313 -419.150125) (xy 73.212665 -419.164313) (xy 73.22686 -419.183841)
			(xy 73.234328 -419.206801) (xy 73.234804 -419.218872) (xy 73.234804 -419.702852) (xy 110.957342 -419.702852)
			(xy 110.957342 -419.648348) (xy 110.965098 -419.594399) (xy 110.980453 -419.542102) (xy 111.003093 -419.492523)
			(xy 111.032558 -419.44667) (xy 111.068249 -419.405477) (xy 111.109438 -419.369782) (xy 111.155288 -419.340312)
			(xy 111.204865 -419.317667) (xy 111.25716 -419.302306) (xy 111.311108 -419.294545) (xy 111.33836 -419.294056)
			(xy 112.20196 -419.294056) (xy 112.229212 -419.294589) (xy 112.283162 -419.30234) (xy 112.33546 -419.317691)
			(xy 112.385041 -419.340329) (xy 112.430894 -419.369793) (xy 112.472088 -419.405484) (xy 112.507783 -419.446674)
			(xy 112.537251 -419.492524) (xy 112.559895 -419.542102) (xy 112.575251 -419.594399) (xy 112.583009 -419.648348)
			(xy 112.583009 -419.702852) (xy 112.575251 -419.756801) (xy 112.559895 -419.809098) (xy 112.537251 -419.858676)
			(xy 112.507783 -419.904526) (xy 112.472088 -419.945716) (xy 112.430894 -419.981407) (xy 112.385041 -420.010871)
			(xy 112.33546 -420.033509) (xy 112.283162 -420.04886) (xy 112.229212 -420.056611) (xy 112.20196 -420.057072)
			(xy 111.33836 -420.057072) (xy 111.311108 -420.056655) (xy 111.25716 -420.048894) (xy 111.204865 -420.033533)
			(xy 111.155288 -420.010888) (xy 111.109438 -419.981418) (xy 111.068249 -419.945723) (xy 111.032558 -419.90453)
			(xy 111.003093 -419.858677) (xy 110.980453 -419.809098) (xy 110.965098 -419.756801) (xy 110.957342 -419.702852)
			(xy 73.234804 -419.702852) (xy 73.234804 -421.760396) (xy 73.234384 -421.772479) (xy 73.226917 -421.795462)
			(xy 73.212713 -421.815013) (xy 73.193162 -421.829217) (xy 73.170179 -421.836684) (xy 73.158096 -421.837104)
			(xy 72.218296 -421.837104) (xy 72.206221 -421.836639) (xy 72.183253 -421.829175) (xy 72.163716 -421.814979)
			(xy 72.149521 -421.79544) (xy 72.14206 -421.772471) (xy 72.141588 -421.760396) (xy 72.141588 -421.150034)
			(xy 72.13992 -421.13504) (xy 72.138141 -421.104922) (xy 72.138032 -421.089836) (xy 69.234812 -421.089836)
			(xy 69.234812 -421.760396) (xy 69.234332 -421.77247) (xy 69.226871 -421.795436) (xy 69.212679 -421.814973)
			(xy 69.193143 -421.829168) (xy 69.170178 -421.836631) (xy 69.158104 -421.837104) (xy 68.218304 -421.837104)
			(xy 68.206221 -421.836684) (xy 68.183238 -421.829217) (xy 68.163687 -421.815013) (xy 68.149483 -421.795462)
			(xy 68.142016 -421.772479) (xy 68.141596 -421.760396) (xy 68.141596 -421.150034) (xy 68.139928 -421.13504)
			(xy 68.138149 -421.104922) (xy 68.13804 -421.089836) (xy 61.234828 -421.089836) (xy 61.234828 -421.760396)
			(xy 61.234333 -421.772468) (xy 61.226874 -421.795432) (xy 61.212684 -421.814967) (xy 61.193154 -421.829163)
			(xy 61.170192 -421.836629) (xy 61.15812 -421.837104) (xy 60.21832 -421.837104) (xy 60.206238 -421.83667)
			(xy 60.183255 -421.829208) (xy 60.163704 -421.815007) (xy 60.1495 -421.795459) (xy 60.142032 -421.772478)
			(xy 60.141612 -421.760396) (xy 60.141612 -421.150034) (xy 60.139944 -421.13504) (xy 60.138165 -421.104922)
			(xy 60.138056 -421.089836) (xy 50.545492 -421.089836) (xy 50.545492 -423.68978) (xy 58.13806 -423.68978)
			(xy 58.138175 -423.674695) (xy 58.139953 -423.644576) (xy 58.141616 -423.629582) (xy 58.141616 -422.550082)
			(xy 58.139952 -422.535088) (xy 58.138171 -422.50497) (xy 58.13806 -422.489884) (xy 58.138175 -422.474799)
			(xy 58.139953 -422.44468) (xy 58.141616 -422.429686) (xy 58.141616 -421.81907) (xy 58.142081 -421.806981)
			(xy 58.149543 -421.783984) (xy 58.163731 -421.764406) (xy 58.183263 -421.750156) (xy 58.206237 -421.74262)
			(xy 58.218324 -421.742108) (xy 59.158124 -421.742108) (xy 59.170235 -421.742496) (xy 59.193264 -421.750003)
			(xy 59.212838 -421.764272) (xy 59.227031 -421.783899) (xy 59.23445 -421.806958) (xy 59.234832 -421.81907)
			(xy 59.234832 -423.68978) (xy 62.138052 -423.68978) (xy 62.138167 -423.674695) (xy 62.139945 -423.644576)
			(xy 62.141608 -423.629582) (xy 62.141608 -422.550082) (xy 62.139944 -422.535088) (xy 62.138163 -422.50497)
			(xy 62.138052 -422.489884) (xy 62.138167 -422.474799) (xy 62.139945 -422.44468) (xy 62.141608 -422.429686)
			(xy 62.141608 -421.81907) (xy 62.142081 -421.806982) (xy 62.149542 -421.783986) (xy 62.163728 -421.764409)
			(xy 62.183258 -421.750158) (xy 62.20623 -421.742621) (xy 62.218316 -421.742108) (xy 63.158116 -421.742108)
			(xy 63.170227 -421.742503) (xy 63.193256 -421.750008) (xy 63.212829 -421.764274) (xy 63.227023 -421.783901)
			(xy 63.234442 -421.806958) (xy 63.234824 -421.81907) (xy 63.234824 -424.360594) (xy 63.234387 -424.372687)
			(xy 63.226927 -424.395693) (xy 63.212734 -424.415276) (xy 63.193192 -424.429526) (xy 63.170207 -424.437051)
			(xy 63.158116 -424.437556) (xy 62.218316 -424.437556) (xy 62.206214 -424.437071) (xy 62.183196 -424.429582)
			(xy 62.163628 -424.415337) (xy 62.149431 -424.395733) (xy 62.142 -424.372697) (xy 62.141608 -424.360594)
			(xy 62.141608 -423.749978) (xy 62.139944 -423.734984) (xy 62.138162 -423.704866) (xy 62.138052 -423.68978)
			(xy 59.234832 -423.68978) (xy 59.234832 -424.360594) (xy 59.234387 -424.372686) (xy 59.226928 -424.395691)
			(xy 59.212737 -424.415274) (xy 59.193197 -424.429523) (xy 59.170215 -424.43705) (xy 59.158124 -424.437556)
			(xy 58.218324 -424.437556) (xy 58.206222 -424.437064) (xy 58.183205 -424.429578) (xy 58.163637 -424.415334)
			(xy 58.149439 -424.395732) (xy 58.142008 -424.372697) (xy 58.141616 -424.360594) (xy 58.141616 -423.749978)
			(xy 58.139952 -423.734984) (xy 58.13817 -423.704866) (xy 58.13806 -423.68978) (xy 50.545492 -423.68978)
			(xy 50.545492 -424.470068) (xy 50.544987 -424.575592) (xy 50.54061 -424.689778) (xy 64.138048 -424.689778)
			(xy 64.138163 -424.674693) (xy 64.139941 -424.644574) (xy 64.141604 -424.62958) (xy 64.141604 -423.55008)
			(xy 64.13994 -423.535086) (xy 64.138158 -423.504968) (xy 64.138048 -423.489882) (xy 64.138163 -423.474797)
			(xy 64.139941 -423.444678) (xy 64.141604 -423.429684) (xy 64.141604 -422.819068) (xy 64.142037 -422.806991)
			(xy 64.14951 -422.78402) (xy 64.163714 -422.764483) (xy 64.18326 -422.75029) (xy 64.206234 -422.74283)
			(xy 64.218312 -422.74236) (xy 65.158112 -422.74236) (xy 65.170184 -422.742854) (xy 65.193146 -422.750316)
			(xy 65.21268 -422.764506) (xy 65.226875 -422.784036) (xy 65.234343 -422.806996) (xy 65.23482 -422.819068)
			(xy 65.23482 -424.689778) (xy 68.13804 -424.689778) (xy 68.138155 -424.674693) (xy 68.139933 -424.644574)
			(xy 68.141596 -424.62958) (xy 68.141596 -423.55008) (xy 68.139932 -423.535086) (xy 68.13815 -423.504968)
			(xy 68.13804 -423.489882) (xy 68.138155 -423.474797) (xy 68.139933 -423.444678) (xy 68.141596 -423.429684)
			(xy 68.141596 -422.819068) (xy 68.142037 -422.806991) (xy 68.149509 -422.784022) (xy 68.163711 -422.764485)
			(xy 68.183255 -422.750292) (xy 68.206227 -422.742831) (xy 68.218304 -422.74236) (xy 69.158104 -422.74236)
			(xy 69.170176 -422.74286) (xy 69.193137 -422.75032) (xy 69.212672 -422.764508) (xy 69.226867 -422.784037)
			(xy 69.234335 -422.806997) (xy 69.234812 -422.819068) (xy 69.234812 -423.68978) (xy 70.138036 -423.68978)
			(xy 70.138153 -423.674695) (xy 70.139931 -423.644576) (xy 70.141592 -423.629582) (xy 70.141592 -422.550082)
			(xy 70.139928 -422.535088) (xy 70.138147 -422.50497) (xy 70.138036 -422.489884) (xy 70.138153 -422.474799)
			(xy 70.139931 -422.44468) (xy 70.141592 -422.429686) (xy 70.141592 -421.81907) (xy 70.142081 -421.806984)
			(xy 70.14954 -421.78399) (xy 70.163723 -421.764415) (xy 70.183248 -421.750163) (xy 70.206215 -421.742624)
			(xy 70.2183 -421.742108) (xy 71.1581 -421.742108) (xy 71.17021 -421.742516) (xy 71.193238 -421.750017)
			(xy 71.212812 -421.76428) (xy 71.227007 -421.783904) (xy 71.234426 -421.806959) (xy 71.234808 -421.81907)
			(xy 71.234808 -424.360594) (xy 71.234288 -424.372678) (xy 71.226839 -424.395671) (xy 71.212664 -424.415247)
			(xy 71.193145 -424.429499) (xy 71.170183 -424.43704) (xy 71.1581 -424.437556) (xy 70.2183 -424.437556)
			(xy 70.206197 -424.437085) (xy 70.183179 -424.429592) (xy 70.163611 -424.415343) (xy 70.149414 -424.395736)
			(xy 70.141983 -424.372698) (xy 70.141592 -424.360594) (xy 70.141592 -423.749978) (xy 70.139928 -423.734984)
			(xy 70.138146 -423.704866) (xy 70.138036 -423.68978) (xy 69.234812 -423.68978) (xy 69.234812 -424.689778)
			(xy 72.138032 -424.689778) (xy 72.138149 -424.674693) (xy 72.139927 -424.644574) (xy 72.141588 -424.62958)
			(xy 72.141588 -423.55008) (xy 72.139924 -423.535086) (xy 72.138142 -423.504968) (xy 72.138032 -423.489882)
			(xy 72.138149 -423.474797) (xy 72.139927 -423.444678) (xy 72.141588 -423.429684) (xy 72.141588 -422.819068)
			(xy 72.142037 -422.806992) (xy 72.149508 -422.784025) (xy 72.163708 -422.764488) (xy 72.18325 -422.750295)
			(xy 72.20622 -422.742832) (xy 72.218296 -422.74236) (xy 73.158096 -422.74236) (xy 73.170167 -422.742867)
			(xy 73.193129 -422.750325) (xy 73.212663 -422.764511) (xy 73.226859 -422.784039) (xy 73.234327 -422.806997)
			(xy 73.234804 -422.819068) (xy 73.234804 -424.80464) (xy 109.929157 -424.80464) (xy 109.929157 -424.6755)
			(xy 109.937107 -424.546605) (xy 109.952977 -424.418445) (xy 109.976706 -424.291504) (xy 110.008205 -424.166265)
			(xy 110.047354 -424.043202) (xy 110.094005 -423.922783) (xy 110.14798 -423.805464) (xy 110.209075 -423.69169)
			(xy 110.277058 -423.581893) (xy 110.351672 -423.47649) (xy 110.432633 -423.37588) (xy 110.519633 -423.280445)
			(xy 110.612344 -423.190546) (xy 110.710414 -423.106525) (xy 110.813469 -423.028701) (xy 110.92112 -422.957369)
			(xy 111.032959 -422.892799) (xy 111.14856 -422.835237) (xy 111.267485 -422.7849) (xy 111.389284 -422.74198)
			(xy 111.513494 -422.706639) (xy 111.639643 -422.679012) (xy 111.767255 -422.659203) (xy 111.895844 -422.647287)
			(xy 112.024922 -422.643311) (xy 112.154 -422.647287) (xy 112.282589 -422.659203) (xy 112.410201 -422.679012)
			(xy 112.53635 -422.706639) (xy 112.66056 -422.74198) (xy 112.782359 -422.7849) (xy 112.901284 -422.835237)
			(xy 113.016885 -422.892799) (xy 113.128724 -422.957369) (xy 113.236375 -423.028701) (xy 113.33943 -423.106525)
			(xy 113.4375 -423.190546) (xy 113.530211 -423.280445) (xy 113.617211 -423.37588) (xy 113.698172 -423.47649)
			(xy 113.772786 -423.581893) (xy 113.840769 -423.69169) (xy 113.901864 -423.805464) (xy 113.955839 -423.922783)
			(xy 114.00249 -424.043202) (xy 114.041639 -424.166265) (xy 114.073138 -424.291504) (xy 114.096867 -424.418445)
			(xy 114.112737 -424.546605) (xy 114.120687 -424.6755) (xy 114.121184 -424.74007) (xy 114.120687 -424.80464)
			(xy 114.112737 -424.933535) (xy 114.096867 -425.061695) (xy 114.073138 -425.188636) (xy 114.041639 -425.313875)
			(xy 114.00249 -425.436938) (xy 113.955839 -425.557357) (xy 113.901864 -425.674676) (xy 113.840769 -425.78845)
			(xy 113.772786 -425.898247) (xy 113.698172 -426.00365) (xy 113.617211 -426.10426) (xy 113.530211 -426.199695)
			(xy 113.4375 -426.289594) (xy 113.33943 -426.373615) (xy 113.236375 -426.451439) (xy 113.128724 -426.522771)
			(xy 113.016885 -426.587341) (xy 112.901284 -426.644903) (xy 112.782359 -426.69524) (xy 112.66056 -426.73816)
			(xy 112.53635 -426.773501) (xy 112.410201 -426.801128) (xy 112.282589 -426.820937) (xy 112.154 -426.832853)
			(xy 112.024922 -426.83683) (xy 111.895844 -426.832853) (xy 111.767255 -426.820937) (xy 111.639643 -426.801128)
			(xy 111.513494 -426.773501) (xy 111.389284 -426.73816) (xy 111.267485 -426.69524) (xy 111.14856 -426.644903)
			(xy 111.032959 -426.587341) (xy 110.92112 -426.522771) (xy 110.813469 -426.451439) (xy 110.710414 -426.373615)
			(xy 110.612344 -426.289594) (xy 110.519633 -426.199695) (xy 110.432633 -426.10426) (xy 110.351672 -426.00365)
			(xy 110.277058 -425.898247) (xy 110.209075 -425.78845) (xy 110.14798 -425.674676) (xy 110.094005 -425.557357)
			(xy 110.047354 -425.436938) (xy 110.008205 -425.313875) (xy 109.976706 -425.188636) (xy 109.952977 -425.061695)
			(xy 109.937107 -424.933535) (xy 109.929157 -424.80464) (xy 73.234804 -424.80464) (xy 73.234804 -425.360592)
			(xy 73.234381 -425.372675) (xy 73.226915 -425.395658) (xy 73.212712 -425.415209) (xy 73.193162 -425.429413)
			(xy 73.170179 -425.43688) (xy 73.158096 -425.4373) (xy 72.218296 -425.4373) (xy 72.206212 -425.436891)
			(xy 72.183228 -425.429421) (xy 72.163677 -425.415214) (xy 72.149473 -425.395661) (xy 72.142007 -425.372676)
			(xy 72.141588 -425.360592) (xy 72.141588 -424.749976) (xy 72.139924 -424.734982) (xy 72.138142 -424.704864)
			(xy 72.138032 -424.689778) (xy 69.234812 -424.689778) (xy 69.234812 -425.360592) (xy 69.234381 -425.372674)
			(xy 69.226916 -425.395656) (xy 69.212714 -425.415206) (xy 69.193167 -425.429411) (xy 69.170186 -425.436879)
			(xy 69.158104 -425.4373) (xy 68.218304 -425.4373) (xy 68.206221 -425.436884) (xy 68.183237 -425.429417)
			(xy 68.163686 -425.415212) (xy 68.149482 -425.39566) (xy 68.142015 -425.372675) (xy 68.141596 -425.360592)
			(xy 68.141596 -424.749976) (xy 68.139932 -424.734982) (xy 68.13815 -424.704864) (xy 68.13804 -424.689778)
			(xy 65.23482 -424.689778) (xy 65.23482 -425.360592) (xy 65.234329 -425.372665) (xy 65.22687 -425.39563)
			(xy 65.21268 -425.415166) (xy 65.193148 -425.429361) (xy 65.170185 -425.436826) (xy 65.158112 -425.4373)
			(xy 64.218312 -425.4373) (xy 64.206229 -425.436877) (xy 64.183246 -425.429412) (xy 64.163694 -425.415208)
			(xy 64.14949 -425.395658) (xy 64.142024 -425.372675) (xy 64.141604 -425.360592) (xy 64.141604 -424.749976)
			(xy 64.13994 -424.734982) (xy 64.138158 -424.704864) (xy 64.138048 -424.689778) (xy 50.54061 -424.689778)
			(xy 50.536903 -424.786486) (xy 50.520747 -424.996915) (xy 50.496544 -425.206572) (xy 50.464327 -425.415147)
			(xy 50.424145 -425.622335) (xy 50.376057 -425.827832) (xy 50.320133 -426.031336) (xy 50.256456 -426.232549)
			(xy 50.185118 -426.431176) (xy 50.106224 -426.626924) (xy 50.019891 -426.819506) (xy 49.926244 -427.008641)
			(xy 49.825422 -427.19405) (xy 49.768393 -427.289976) (xy 58.118502 -427.289976) (xy 58.118998 -427.25742)
			(xy 58.126945 -427.192795) (xy 58.142732 -427.129626) (xy 58.166119 -427.068859) (xy 58.196758 -427.011406)
			(xy 58.234188 -426.958128) (xy 58.277848 -426.909824) (xy 58.302144 -426.888148) (xy 58.382916 -426.723302)
			(xy 58.387603 -426.71278) (xy 58.391097 -426.690025) (xy 58.387618 -426.667268) (xy 58.382916 -426.656754)
			(xy 58.30189 -426.491654) (xy 58.277623 -426.469962) (xy 58.234027 -426.421628) (xy 58.196653 -426.368337)
			(xy 58.16606 -426.310884) (xy 58.142706 -426.250127) (xy 58.126938 -426.186975) (xy 58.118994 -426.122371)
			(xy 58.118502 -426.089826) (xy 58.119221 -426.050501) (xy 58.130831 -425.972711) (xy 58.141616 -425.934886)
			(xy 58.141616 -425.419012) (xy 58.142023 -425.406928) (xy 58.149491 -425.383941) (xy 58.163697 -425.364389)
			(xy 58.183252 -425.350185) (xy 58.206239 -425.342722) (xy 58.218324 -425.342304) (xy 59.158124 -425.342304)
			(xy 59.170201 -425.342744) (xy 59.193171 -425.350215) (xy 59.212709 -425.364417) (xy 59.226902 -425.383961)
			(xy 59.234361 -425.406935) (xy 59.234832 -425.419012) (xy 59.234832 -427.960536) (xy 59.234367 -427.97261)
			(xy 59.226898 -427.995574) (xy 59.2127 -428.015109) (xy 59.193164 -428.029303) (xy 59.170198 -428.036769)
			(xy 59.158124 -428.037244) (xy 58.218324 -428.037244) (xy 58.206254 -428.036716) (xy 58.183294 -428.029264)
			(xy 58.16376 -428.015083) (xy 58.149563 -427.99556) (xy 58.142093 -427.972605) (xy 58.141616 -427.960536)
			(xy 58.141616 -427.444916) (xy 58.130812 -427.407096) (xy 58.119209 -427.329303) (xy 58.118502 -427.289976)
			(xy 49.768393 -427.289976) (xy 49.717572 -427.375461) (xy 49.602853 -427.552608) (xy 49.481433 -427.72523)
			(xy 49.35349 -427.893076) (xy 49.219212 -428.055898) (xy 49.078796 -428.213457) (xy 49.0054 -428.28972)
			(xy 60.118498 -428.28972) (xy 60.119034 -428.257141) (xy 60.127005 -428.192471) (xy 60.142819 -428.12926)
			(xy 60.166237 -428.068455) (xy 60.19691 -428.010967) (xy 60.234377 -427.957658) (xy 60.278077 -427.909326)
			(xy 60.302394 -427.887638) (xy 60.382912 -427.7233) (xy 60.387601 -427.712779) (xy 60.391095 -427.690023)
			(xy 60.387615 -427.667266) (xy 60.382912 -427.656752) (xy 60.301886 -427.491652) (xy 60.277617 -427.469962)
			(xy 60.234021 -427.421628) (xy 60.196648 -427.368336) (xy 60.166055 -427.310882) (xy 60.142701 -427.250126)
			(xy 60.126934 -427.186973) (xy 60.118989 -427.122369) (xy 60.118498 -427.089824) (xy 60.119217 -427.050499)
			(xy 60.130827 -426.972709) (xy 60.141612 -426.934884) (xy 60.141612 -426.41901) (xy 60.142115 -426.406924)
			(xy 60.149566 -426.383928) (xy 60.163744 -426.364351) (xy 60.183268 -426.350099) (xy 60.206236 -426.342562)
			(xy 60.21832 -426.342048) (xy 61.15812 -426.342048) (xy 61.170225 -426.342499) (xy 61.193244 -426.349997)
			(xy 61.212812 -426.364252) (xy 61.227008 -426.383863) (xy 61.234437 -426.406904) (xy 61.234828 -426.41901)
			(xy 61.234828 -427.289976) (xy 62.118494 -427.289976) (xy 62.118958 -427.257419) (xy 62.126908 -427.192791)
			(xy 62.142697 -427.12962) (xy 62.166089 -427.068853) (xy 62.196733 -427.0114) (xy 62.234169 -426.958123)
			(xy 62.277837 -426.909822) (xy 62.302136 -426.888148) (xy 62.382908 -426.723302) (xy 62.387595 -426.71278)
			(xy 62.39109 -426.690025) (xy 62.387611 -426.667268) (xy 62.382908 -426.656754) (xy 62.301882 -426.491654)
			(xy 62.277614 -426.469963) (xy 62.234017 -426.42163) (xy 62.196644 -426.368338) (xy 62.166052 -426.310884)
			(xy 62.142697 -426.250128) (xy 62.12693 -426.186975) (xy 62.118986 -426.122371) (xy 62.118494 -426.089826)
			(xy 62.119213 -426.050501) (xy 62.130824 -425.972711) (xy 62.141608 -425.934886) (xy 62.141608 -425.419012)
			(xy 62.142023 -425.406928) (xy 62.149489 -425.383943) (xy 62.163694 -425.364392) (xy 62.183247 -425.350188)
			(xy 62.206232 -425.342723) (xy 62.218316 -425.342304) (xy 63.158116 -425.342304) (xy 63.170193 -425.342751)
			(xy 63.193162 -425.350219) (xy 63.2127 -425.36442) (xy 63.226894 -425.383963) (xy 63.234353 -425.406935)
			(xy 63.234824 -425.419012) (xy 63.234824 -427.960536) (xy 63.234367 -427.972611) (xy 63.226896 -427.995577)
			(xy 63.212697 -428.015112) (xy 63.193159 -428.029306) (xy 63.170191 -428.03677) (xy 63.158116 -428.037244)
			(xy 62.218316 -428.037244) (xy 62.206246 -428.036723) (xy 62.183285 -428.029269) (xy 62.163751 -428.015086)
			(xy 62.149555 -427.995561) (xy 62.142085 -427.972606) (xy 62.141608 -427.960536) (xy 62.141608 -427.444916)
			(xy 62.130804 -427.407096) (xy 62.119201 -427.329303) (xy 62.118494 -427.289976) (xy 61.234828 -427.289976)
			(xy 61.234828 -428.28972) (xy 64.11849 -428.28972) (xy 64.119028 -428.257141) (xy 64.126999 -428.192471)
			(xy 64.142813 -428.129261) (xy 64.166231 -428.068456) (xy 64.196903 -428.010968) (xy 64.23437 -427.957658)
			(xy 64.278069 -427.909326) (xy 64.302386 -427.887638) (xy 64.382904 -427.7233) (xy 64.387593 -427.712779)
			(xy 64.391087 -427.690023) (xy 64.387607 -427.667266) (xy 64.382904 -427.656752) (xy 64.301878 -427.491652)
			(xy 64.277608 -427.469963) (xy 64.234012 -427.421629) (xy 64.196639 -427.368337) (xy 64.166047 -427.310883)
			(xy 64.142693 -427.250126) (xy 64.126926 -427.186974) (xy 64.118981 -427.122369) (xy 64.11849 -427.089824)
			(xy 64.119209 -427.050499) (xy 64.130819 -426.972709) (xy 64.141604 -426.934884) (xy 64.141604 -426.41901)
			(xy 64.142115 -426.406925) (xy 64.149565 -426.38393) (xy 64.163741 -426.364353) (xy 64.183263 -426.350101)
			(xy 64.206228 -426.342563) (xy 64.218312 -426.342048) (xy 65.158112 -426.342048) (xy 65.170216 -426.342505)
			(xy 65.193235 -426.350002) (xy 65.212804 -426.364255) (xy 65.227 -426.383864) (xy 65.234429 -426.406905)
			(xy 65.23482 -426.41901) (xy 65.23482 -427.289976) (xy 66.118486 -427.289976) (xy 66.118953 -427.257419)
			(xy 66.126902 -427.192792) (xy 66.142691 -427.129621) (xy 66.166083 -427.068853) (xy 66.196726 -427.0114)
			(xy 66.234162 -426.958124) (xy 66.277829 -426.909822) (xy 66.302128 -426.888148) (xy 66.3829 -426.723302)
			(xy 66.387588 -426.71278) (xy 66.391083 -426.690025) (xy 66.387603 -426.667268) (xy 66.3829 -426.656754)
			(xy 66.301874 -426.491654) (xy 66.277604 -426.469965) (xy 66.234008 -426.421631) (xy 66.196635 -426.368339)
			(xy 66.166043 -426.310885) (xy 66.142689 -426.250128) (xy 66.126922 -426.186976) (xy 66.118978 -426.122371)
			(xy 66.118486 -426.089826) (xy 66.119205 -426.050501) (xy 66.130816 -425.972711) (xy 66.1416 -425.934886)
			(xy 66.1416 -425.419012) (xy 66.142023 -425.406929) (xy 66.149488 -425.383946) (xy 66.163692 -425.364394)
			(xy 66.183242 -425.35019) (xy 66.206225 -425.342724) (xy 66.218308 -425.342304) (xy 67.158108 -425.342304)
			(xy 67.170192 -425.342706) (xy 67.193177 -425.350177) (xy 67.212729 -425.364386) (xy 67.226932 -425.383941)
			(xy 67.234397 -425.406928) (xy 67.234816 -425.419012) (xy 67.234816 -427.960536) (xy 67.234367 -427.972612)
			(xy 67.226895 -427.995579) (xy 67.212695 -428.015115) (xy 67.193154 -428.029308) (xy 67.170184 -428.036771)
			(xy 67.158108 -428.037244) (xy 66.218308 -428.037244) (xy 66.206237 -428.03673) (xy 66.183277 -428.029274)
			(xy 66.163743 -428.015089) (xy 66.149547 -427.995563) (xy 66.142077 -427.972606) (xy 66.1416 -427.960536)
			(xy 66.1416 -427.444916) (xy 66.130796 -427.407096) (xy 66.119192 -427.329303) (xy 66.118486 -427.289976)
			(xy 65.23482 -427.289976) (xy 65.23482 -428.28972) (xy 68.118482 -428.28972) (xy 68.119023 -428.257141)
			(xy 68.126994 -428.192472) (xy 68.142807 -428.129261) (xy 68.166225 -428.068456) (xy 68.196897 -428.010968)
			(xy 68.234363 -427.957658) (xy 68.278062 -427.909326) (xy 68.302378 -427.887638) (xy 68.382896 -427.7233)
			(xy 68.387585 -427.712779) (xy 68.39108 -427.690023) (xy 68.387599 -427.667266) (xy 68.382896 -427.656752)
			(xy 68.30187 -427.491652) (xy 68.277618 -427.469943) (xy 68.234018 -427.421614) (xy 68.196641 -427.368327)
			(xy 68.166045 -427.310876) (xy 68.142688 -427.250122) (xy 68.126919 -427.186972) (xy 68.118974 -427.122369)
			(xy 68.118482 -427.089824) (xy 68.119201 -427.050499) (xy 68.130812 -426.972709) (xy 68.141596 -426.934884)
			(xy 68.141596 -426.41901) (xy 68.142115 -426.406925) (xy 68.149564 -426.383932) (xy 68.163739 -426.364356)
			(xy 68.183258 -426.350104) (xy 68.206221 -426.342564) (xy 68.218304 -426.342048) (xy 69.158104 -426.342048)
			(xy 69.170208 -426.342512) (xy 69.193227 -426.350006) (xy 69.212795 -426.364257) (xy 69.226991 -426.383866)
			(xy 69.234421 -426.406905) (xy 69.234812 -426.41901) (xy 69.234812 -427.289976) (xy 70.118478 -427.289976)
			(xy 70.118947 -427.257419) (xy 70.126897 -427.192792) (xy 70.142685 -427.129621) (xy 70.166076 -427.068854)
			(xy 70.196719 -427.011401) (xy 70.234155 -426.958124) (xy 70.277821 -426.909822) (xy 70.30212 -426.888148)
			(xy 70.382892 -426.723302) (xy 70.38758 -426.71278) (xy 70.391076 -426.690025) (xy 70.387595 -426.667268)
			(xy 70.382892 -426.656754) (xy 70.301866 -426.491654) (xy 70.277615 -426.469945) (xy 70.234014 -426.421616)
			(xy 70.196637 -426.368329) (xy 70.166041 -426.310878) (xy 70.142684 -426.250124) (xy 70.126915 -426.186973)
			(xy 70.11897 -426.122371) (xy 70.118478 -426.089826) (xy 70.119198 -426.050501) (xy 70.130808 -425.972711)
			(xy 70.141592 -425.934886) (xy 70.141592 -425.419012) (xy 70.142023 -425.40693) (xy 70.149487 -425.383948)
			(xy 70.163689 -425.364397) (xy 70.183237 -425.350193) (xy 70.206218 -425.342725) (xy 70.2183 -425.342304)
			(xy 71.1581 -425.342304) (xy 71.170184 -425.342713) (xy 71.193169 -425.350182) (xy 71.21272 -425.364388)
			(xy 71.226924 -425.383942) (xy 71.234389 -425.406928) (xy 71.234808 -425.419012) (xy 71.234808 -427.960536)
			(xy 71.234367 -427.972612) (xy 71.226894 -427.995581) (xy 71.212692 -428.015117) (xy 71.193149 -428.029311)
			(xy 71.170177 -428.036772) (xy 71.1581 -428.037244) (xy 70.2183 -428.037244) (xy 70.206229 -428.036736)
			(xy 70.183268 -428.029278) (xy 70.163734 -428.015092) (xy 70.149538 -427.995564) (xy 70.142069 -427.972607)
			(xy 70.141592 -427.960536) (xy 70.141592 -427.444916) (xy 70.130788 -427.407096) (xy 70.119184 -427.329303)
			(xy 70.118478 -427.289976) (xy 69.234812 -427.289976) (xy 69.234812 -428.28972) (xy 72.118474 -428.28972)
			(xy 72.119018 -428.257141) (xy 72.126989 -428.192472) (xy 72.142801 -428.129262) (xy 72.166219 -428.068457)
			(xy 72.19689 -428.010969) (xy 72.234356 -427.957659) (xy 72.278054 -427.909326) (xy 72.30237 -427.887638)
			(xy 72.382888 -427.7233) (xy 72.387578 -427.712779) (xy 72.391073 -427.690023) (xy 72.387592 -427.667266)
			(xy 72.382888 -427.656752) (xy 72.301862 -427.491652) (xy 72.277609 -427.469945) (xy 72.234009 -427.421616)
			(xy 72.196632 -427.368328) (xy 72.166036 -427.310877) (xy 72.14268 -427.250122) (xy 72.126911 -427.186972)
			(xy 72.118966 -427.122369) (xy 72.118474 -427.089824) (xy 72.119193 -427.050499) (xy 72.130804 -426.972709)
			(xy 72.141588 -426.934884) (xy 72.141588 -426.41901) (xy 72.142017 -426.406916) (xy 72.149477 -426.383908)
			(xy 72.163671 -426.364324) (xy 72.183216 -426.350075) (xy 72.206204 -426.342551) (xy 72.218296 -426.342048)
			(xy 73.158096 -426.342048) (xy 73.170199 -426.342519) (xy 73.193218 -426.350011) (xy 73.212787 -426.36426)
			(xy 73.226983 -426.383867) (xy 73.234413 -426.406905) (xy 73.234804 -426.41901) (xy 73.234804 -427.289976)
			(xy 75.118468 -427.289976) (xy 75.118941 -427.257419) (xy 75.12689 -427.192792) (xy 75.142678 -427.129622)
			(xy 75.166069 -427.068854) (xy 75.196711 -427.011401) (xy 75.234146 -426.958124) (xy 75.277811 -426.909822)
			(xy 75.30211 -426.888148) (xy 75.382882 -426.723302) (xy 75.387571 -426.71278) (xy 75.391067 -426.690025)
			(xy 75.387586 -426.667268) (xy 75.382882 -426.656754) (xy 75.301856 -426.491654) (xy 75.277603 -426.469947)
			(xy 75.234003 -426.421618) (xy 75.196626 -426.36833) (xy 75.166031 -426.310879) (xy 75.142674 -426.250124)
			(xy 75.126905 -426.186974) (xy 75.11896 -426.122371) (xy 75.118468 -426.089826) (xy 75.119172 -426.0507)
			(xy 75.130644 -425.973293) (xy 75.141328 -425.935648) (xy 75.141328 -425.419012) (xy 75.141727 -425.406901)
			(xy 75.149227 -425.383869) (xy 75.163492 -425.364294) (xy 75.183119 -425.3501) (xy 75.206178 -425.342684)
			(xy 75.21829 -425.342304) (xy 76.15809 -425.342304) (xy 76.170175 -425.342815) (xy 76.19317 -425.350265)
			(xy 76.212747 -425.364441) (xy 76.226999 -425.383963) (xy 76.234537 -425.406928) (xy 76.235052 -425.419012)
			(xy 76.235052 -427.960536) (xy 76.234615 -427.972642) (xy 76.227112 -427.995661) (xy 76.212854 -428.015229)
			(xy 76.19324 -428.029424) (xy 76.170197 -428.036854) (xy 76.15809 -428.037244) (xy 75.21829 -428.037244)
			(xy 75.206198 -428.036801) (xy 75.183195 -428.029339) (xy 75.163614 -428.015147) (xy 75.149364 -427.995608)
			(xy 75.141835 -427.972626) (xy 75.141328 -427.960536) (xy 75.141328 -427.444154) (xy 75.130636 -427.40651)
			(xy 75.119162 -427.329103) (xy 75.118468 -427.289976) (xy 73.234804 -427.289976) (xy 73.234804 -428.28972)
			(xy 77.118464 -428.28972) (xy 77.118977 -428.25714) (xy 77.12695 -428.192469) (xy 77.142765 -428.129256)
			(xy 77.166187 -428.06845) (xy 77.196864 -428.010962) (xy 77.234335 -427.957654) (xy 77.278041 -427.909324)
			(xy 77.30236 -427.887638) (xy 77.382878 -427.7233) (xy 77.387568 -427.712779) (xy 77.391064 -427.690023)
			(xy 77.387582 -427.667266) (xy 77.382878 -427.656752) (xy 77.301852 -427.491652) (xy 77.277597 -427.469947)
			(xy 77.233997 -427.421617) (xy 77.196621 -427.368329) (xy 77.166026 -427.310878) (xy 77.142669 -427.250123)
			(xy 77.126901 -427.186972) (xy 77.118956 -427.122369) (xy 77.118464 -427.089824) (xy 77.119168 -427.050698)
			(xy 77.13064 -426.973291) (xy 77.141324 -426.935646) (xy 77.141324 -426.41901) (xy 77.14182 -426.406897)
			(xy 77.149303 -426.383857) (xy 77.163539 -426.364256) (xy 77.183135 -426.350014) (xy 77.206174 -426.342524)
			(xy 77.218286 -426.342048) (xy 78.158086 -426.342048) (xy 78.170209 -426.342472) (xy 78.193269 -426.349962)
			(xy 78.212885 -426.364212) (xy 78.227136 -426.383827) (xy 78.234627 -426.406887) (xy 78.235048 -426.41901)
			(xy 78.235048 -427.289976) (xy 79.11846 -427.289976) (xy 79.118936 -427.257419) (xy 79.126885 -427.192793)
			(xy 79.142672 -427.129622) (xy 79.166063 -427.068855) (xy 79.196705 -427.011402) (xy 79.234139 -426.958125)
			(xy 79.277804 -426.909822) (xy 79.302102 -426.888148) (xy 79.382874 -426.723302) (xy 79.387563 -426.71278)
			(xy 79.39106 -426.690025) (xy 79.387578 -426.667268) (xy 79.382874 -426.656754) (xy 79.301848 -426.491654)
			(xy 79.277593 -426.469949) (xy 79.233994 -426.421619) (xy 79.196617 -426.36833) (xy 79.166022 -426.310879)
			(xy 79.142666 -426.250125) (xy 79.126897 -426.186974) (xy 79.118952 -426.122371) (xy 79.11846 -426.089826)
			(xy 79.119165 -426.0507) (xy 79.130636 -425.973293) (xy 79.14132 -425.935648) (xy 79.14132 -425.419012)
			(xy 79.141727 -425.406902) (xy 79.149226 -425.383872) (xy 79.163489 -425.364297) (xy 79.183114 -425.350102)
			(xy 79.20617 -425.342685) (xy 79.218282 -425.342304) (xy 80.158082 -425.342304) (xy 80.170167 -425.342822)
			(xy 80.193161 -425.35027) (xy 80.212738 -425.364444) (xy 80.226991 -425.383965) (xy 80.234529 -425.406929)
			(xy 80.235044 -425.419012) (xy 80.235044 -427.960536) (xy 80.234615 -427.972642) (xy 80.227111 -427.995663)
			(xy 80.212851 -428.015232) (xy 80.193235 -428.029427) (xy 80.17019 -428.036855) (xy 80.158082 -428.037244)
			(xy 79.218282 -428.037244) (xy 79.20619 -428.036808) (xy 79.183186 -428.029344) (xy 79.163605 -428.01515)
			(xy 79.149355 -427.995609) (xy 79.141827 -427.972627) (xy 79.14132 -427.960536) (xy 79.14132 -427.444154)
			(xy 79.130628 -427.40651) (xy 79.119154 -427.329103) (xy 79.11846 -427.289976) (xy 78.235048 -427.289976)
			(xy 78.235048 -428.28972) (xy 81.118456 -428.28972) (xy 81.118972 -428.25714) (xy 81.126944 -428.192469)
			(xy 81.14276 -428.129257) (xy 81.166181 -428.068451) (xy 81.196857 -428.010963) (xy 81.234328 -427.957655)
			(xy 81.278033 -427.909325) (xy 81.302352 -427.887638) (xy 81.38287 -427.7233) (xy 81.387561 -427.712779)
			(xy 81.391057 -427.690023) (xy 81.387575 -427.667266) (xy 81.38287 -427.656752) (xy 81.301844 -427.491652)
			(xy 81.277587 -427.469949) (xy 81.233988 -427.421619) (xy 81.196612 -427.36833) (xy 81.166017 -427.310878)
			(xy 81.142661 -427.250123) (xy 81.126893 -427.186972) (xy 81.118948 -427.122369) (xy 81.118456 -427.089824)
			(xy 81.11916 -427.050698) (xy 81.130632 -426.973291) (xy 81.141316 -426.935646) (xy 81.141316 -426.41901)
			(xy 81.14182 -426.406898) (xy 81.149302 -426.383859) (xy 81.163536 -426.364259) (xy 81.18313 -426.350016)
			(xy 81.206166 -426.342525) (xy 81.218278 -426.342048) (xy 82.158078 -426.342048) (xy 82.170201 -426.342479)
			(xy 82.19326 -426.349966) (xy 82.212877 -426.364215) (xy 82.227128 -426.383829) (xy 82.234619 -426.406887)
			(xy 82.23504 -426.41901) (xy 82.23504 -427.289976) (xy 83.118452 -427.289976) (xy 83.11893 -427.257419)
			(xy 83.126879 -427.192793) (xy 83.142667 -427.129623) (xy 83.166057 -427.068856) (xy 83.196698 -427.011403)
			(xy 83.234132 -426.958125) (xy 83.277796 -426.909823) (xy 83.302094 -426.888148) (xy 83.382866 -426.723302)
			(xy 83.387551 -426.712779) (xy 83.391043 -426.690025) (xy 83.387566 -426.667269) (xy 83.382866 -426.656754)
			(xy 83.30184 -426.491654) (xy 83.277583 -426.469951) (xy 83.233984 -426.42162) (xy 83.196608 -426.368331)
			(xy 83.166013 -426.31088) (xy 83.142657 -426.250125) (xy 83.126889 -426.186974) (xy 83.118944 -426.122371)
			(xy 83.118452 -426.089826) (xy 83.119157 -426.0507) (xy 83.130628 -425.973293) (xy 83.141312 -425.935648)
			(xy 83.141312 -425.419012) (xy 83.141727 -425.406903) (xy 83.149224 -425.383874) (xy 83.163486 -425.364299)
			(xy 83.183109 -425.350105) (xy 83.206163 -425.342686) (xy 83.218274 -425.342304) (xy 84.158074 -425.342304)
			(xy 84.170159 -425.342829) (xy 84.193152 -425.350274) (xy 84.21273 -425.364447) (xy 84.226982 -425.383966)
			(xy 84.234521 -425.406929) (xy 84.235036 -425.419012) (xy 84.235036 -427.960536) (xy 84.234615 -427.972643)
			(xy 84.22711 -427.995665) (xy 84.212848 -428.015235) (xy 84.19323 -428.029429) (xy 84.170183 -428.036856)
			(xy 84.158074 -428.037244) (xy 83.218274 -428.037244) (xy 83.206181 -428.036815) (xy 83.183177 -428.029349)
			(xy 83.163596 -428.015153) (xy 83.149347 -427.995611) (xy 83.141819 -427.972627) (xy 83.141312 -427.960536)
			(xy 83.141312 -427.444154) (xy 83.13062 -427.40651) (xy 83.119146 -427.329103) (xy 83.118452 -427.289976)
			(xy 82.23504 -427.289976) (xy 82.23504 -428.28972) (xy 85.118448 -428.28972) (xy 85.118967 -428.25714)
			(xy 85.126939 -428.192469) (xy 85.142754 -428.129257) (xy 85.166175 -428.068452) (xy 85.196851 -428.010964)
			(xy 85.234321 -427.957655) (xy 85.278025 -427.909325) (xy 85.302344 -427.887638) (xy 85.382862 -427.7233)
			(xy 85.387548 -427.712778) (xy 85.39104 -427.690023) (xy 85.387562 -427.667267) (xy 85.382862 -427.656752)
			(xy 85.301836 -427.491652) (xy 85.277578 -427.469951) (xy 85.233979 -427.42162) (xy 85.196603 -427.36833)
			(xy 85.166008 -427.310879) (xy 85.142653 -427.250123) (xy 85.126884 -427.186972) (xy 85.11894 -427.122369)
			(xy 85.118448 -427.089824) (xy 85.119153 -427.050698) (xy 85.130624 -426.973291) (xy 85.141308 -426.935646)
			(xy 85.141308 -426.41901) (xy 85.14182 -426.406899) (xy 85.149301 -426.383861) (xy 85.163533 -426.364262)
			(xy 85.183125 -426.350019) (xy 85.206159 -426.342526) (xy 85.21827 -426.342048) (xy 86.15807 -426.342048)
			(xy 86.170192 -426.342486) (xy 86.193252 -426.349971) (xy 86.212868 -426.364218) (xy 86.22712 -426.38383)
			(xy 86.234611 -426.406888) (xy 86.235032 -426.41901) (xy 86.235032 -427.289976) (xy 87.118444 -427.289976)
			(xy 87.118925 -427.257419) (xy 87.126874 -427.192793) (xy 87.142661 -427.129623) (xy 87.166051 -427.068856)
			(xy 87.196692 -427.011403) (xy 87.234125 -426.958126) (xy 87.277788 -426.909823) (xy 87.302086 -426.888148)
			(xy 87.382858 -426.723302) (xy 87.387543 -426.71278) (xy 87.391036 -426.690025) (xy 87.387558 -426.667269)
			(xy 87.382858 -426.656754) (xy 87.301832 -426.491654) (xy 87.277574 -426.469952) (xy 87.233975 -426.421622)
			(xy 87.196599 -426.368332) (xy 87.166005 -426.310881) (xy 87.142649 -426.250125) (xy 87.126881 -426.186974)
			(xy 87.118936 -426.122371) (xy 87.118444 -426.089826) (xy 87.119149 -426.0507) (xy 87.13062 -425.973293)
			(xy 87.141304 -425.935648) (xy 87.141304 -425.419012) (xy 87.141727 -425.406903) (xy 87.149223 -425.383876)
			(xy 87.163483 -425.364302) (xy 87.183104 -425.350107) (xy 87.206156 -425.342687) (xy 87.218266 -425.342304)
			(xy 88.158066 -425.342304) (xy 88.17015 -425.342836) (xy 88.193144 -425.350279) (xy 88.212721 -425.36445)
			(xy 88.226974 -425.383968) (xy 88.234513 -425.40693) (xy 88.235028 -425.419012) (xy 88.235028 -427.960536)
			(xy 88.234615 -427.972644) (xy 88.227109 -427.995668) (xy 88.212845 -428.015238) (xy 88.193225 -428.029432)
			(xy 88.170175 -428.036857) (xy 88.158066 -428.037244) (xy 87.218266 -428.037244) (xy 87.206173 -428.036821)
			(xy 87.183169 -428.029353) (xy 87.163588 -428.015156) (xy 87.149339 -427.995612) (xy 87.141811 -427.972628)
			(xy 87.141304 -427.960536) (xy 87.141304 -427.444154) (xy 87.130611 -427.40651) (xy 87.119138 -427.329103)
			(xy 87.118444 -427.289976) (xy 86.235032 -427.289976) (xy 86.235032 -428.28972) (xy 89.11844 -428.28972)
			(xy 89.118962 -428.25714) (xy 89.126934 -428.192469) (xy 89.142748 -428.129258) (xy 89.166169 -428.068452)
			(xy 89.196844 -428.010964) (xy 89.234314 -427.957655) (xy 89.278018 -427.909325) (xy 89.302336 -427.887638)
			(xy 89.382854 -427.7233) (xy 89.387541 -427.712778) (xy 89.391033 -427.690023) (xy 89.387555 -427.667267)
			(xy 89.382854 -427.656752) (xy 89.301828 -427.491652) (xy 89.277568 -427.469952) (xy 89.23397 -427.421621)
			(xy 89.196594 -427.368331) (xy 89.166 -427.310879) (xy 89.142644 -427.250124) (xy 89.126876 -427.186972)
			(xy 89.118931 -427.122369) (xy 89.11844 -427.089824) (xy 89.119145 -427.050698) (xy 89.130616 -426.973291)
			(xy 89.1413 -426.935646) (xy 89.1413 -426.41901) (xy 89.14182 -426.4069) (xy 89.1493 -426.383863)
			(xy 89.163531 -426.364265) (xy 89.18312 -426.350022) (xy 89.206152 -426.342527) (xy 89.218262 -426.342048)
			(xy 90.158062 -426.342048) (xy 90.170184 -426.342492) (xy 90.193243 -426.349975) (xy 90.21286 -426.36422)
			(xy 90.227112 -426.383832) (xy 90.234603 -426.406888) (xy 90.235024 -426.41901) (xy 90.235024 -427.289976)
			(xy 125.238002 -427.289976) (xy 125.238092 -427.275402) (xy 125.239747 -427.246301) (xy 125.241304 -427.23181)
			(xy 125.241304 -426.147992) (xy 125.239761 -426.1335) (xy 125.238108 -426.1044) (xy 125.238002 -426.089826)
			(xy 125.238097 -426.075252) (xy 125.239748 -426.046151) (xy 125.241304 -426.03166) (xy 125.241304 -425.419012)
			(xy 125.241727 -425.406903) (xy 125.249223 -425.383876) (xy 125.263483 -425.364302) (xy 125.283104 -425.350107)
			(xy 125.306156 -425.342687) (xy 125.318266 -425.342304) (xy 126.258066 -425.342304) (xy 126.27015 -425.342836)
			(xy 126.293144 -425.350279) (xy 126.312721 -425.36445) (xy 126.326974 -425.383968) (xy 126.334513 -425.40693)
			(xy 126.335028 -425.419012) (xy 126.335028 -427.960536) (xy 126.334615 -427.972644) (xy 126.327109 -427.995668)
			(xy 126.312845 -428.015238) (xy 126.293225 -428.029432) (xy 126.270175 -428.036857) (xy 126.258066 -428.037244)
			(xy 125.318266 -428.037244) (xy 125.306173 -428.036821) (xy 125.283169 -428.029353) (xy 125.263588 -428.015156)
			(xy 125.249339 -427.995612) (xy 125.241811 -427.972628) (xy 125.241304 -427.960536) (xy 125.241304 -427.348142)
			(xy 125.239757 -427.33365) (xy 125.238107 -427.30455) (xy 125.238002 -427.289976) (xy 90.235024 -427.289976)
			(xy 90.235024 -428.960534) (xy 90.234669 -428.972662) (xy 90.227162 -428.995729) (xy 90.212895 -429.015347)
			(xy 90.193264 -429.029595) (xy 90.170191 -429.03708) (xy 90.158062 -429.037496) (xy 89.218262 -429.037496)
			(xy 89.206149 -429.037021) (xy 89.18311 -429.029528) (xy 89.163512 -429.015285) (xy 89.14927 -428.995686)
			(xy 89.141778 -428.972647) (xy 89.1413 -428.960534) (xy 89.1413 -428.443898) (xy 89.130617 -428.406252)
			(xy 89.119137 -428.328846) (xy 89.11844 -428.28972) (xy 86.235032 -428.28972) (xy 86.235032 -428.960534)
			(xy 86.234617 -428.972653) (xy 86.227117 -428.995703) (xy 86.212861 -429.015307) (xy 86.193245 -429.029546)
			(xy 86.17019 -429.037027) (xy 86.15807 -429.037496) (xy 85.21827 -429.037496) (xy 85.206157 -429.037014)
			(xy 85.183119 -429.029523) (xy 85.16352 -429.015282) (xy 85.149279 -428.995685) (xy 85.141786 -428.972647)
			(xy 85.141308 -428.960534) (xy 85.141308 -428.443898) (xy 85.130625 -428.406252) (xy 85.119145 -428.328846)
			(xy 85.118448 -428.28972) (xy 82.23504 -428.28972) (xy 82.23504 -428.960534) (xy 82.234617 -428.972653)
			(xy 82.227118 -428.995701) (xy 82.212864 -429.015304) (xy 82.19325 -429.029543) (xy 82.170197 -429.037026)
			(xy 82.158078 -429.037496) (xy 81.218278 -429.037496) (xy 81.206166 -429.037008) (xy 81.183127 -429.029519)
			(xy 81.163529 -429.01528) (xy 81.149287 -428.995683) (xy 81.141794 -428.972646) (xy 81.141316 -428.960534)
			(xy 81.141316 -428.443898) (xy 81.130633 -428.406252) (xy 81.119153 -428.328846) (xy 81.118456 -428.28972)
			(xy 78.235048 -428.28972) (xy 78.235048 -428.960534) (xy 78.234617 -428.972652) (xy 78.227119 -428.995698)
			(xy 78.212867 -429.015301) (xy 78.193255 -429.029541) (xy 78.170204 -429.037025) (xy 78.158086 -429.037496)
			(xy 77.218286 -429.037496) (xy 77.206174 -429.037001) (xy 77.183136 -429.029514) (xy 77.163537 -429.015277)
			(xy 77.149295 -428.995682) (xy 77.141802 -428.972646) (xy 77.141324 -428.960534) (xy 77.141324 -428.443898)
			(xy 77.130641 -428.406252) (xy 77.119161 -428.328846) (xy 77.118464 -428.28972) (xy 73.234804 -428.28972)
			(xy 73.234804 -428.960534) (xy 73.234323 -428.972621) (xy 73.226862 -428.995615) (xy 73.212677 -429.015191)
			(xy 73.19315 -429.029442) (xy 73.170181 -429.036981) (xy 73.158096 -429.037496) (xy 72.218296 -429.037496)
			(xy 72.206187 -429.037087) (xy 72.183158 -429.029586) (xy 72.163585 -429.015323) (xy 72.149391 -428.995699)
			(xy 72.141971 -428.972645) (xy 72.141588 -428.960534) (xy 72.141588 -428.44466) (xy 72.130793 -428.406837)
			(xy 72.119184 -428.329046) (xy 72.118474 -428.28972) (xy 69.234812 -428.28972) (xy 69.234812 -428.960534)
			(xy 69.234421 -428.97263) (xy 69.226949 -428.99564) (xy 69.212744 -429.015223) (xy 69.193192 -429.029471)
			(xy 69.170199 -429.036994) (xy 69.158104 -429.037496) (xy 68.218304 -429.037496) (xy 68.206195 -429.03708)
			(xy 68.183167 -429.029582) (xy 68.163593 -429.01532) (xy 68.149399 -428.995698) (xy 68.141979 -428.972644)
			(xy 68.141596 -428.960534) (xy 68.141596 -428.44466) (xy 68.130801 -428.406837) (xy 68.119192 -428.329046)
			(xy 68.118482 -428.28972) (xy 65.23482 -428.28972) (xy 65.23482 -428.960534) (xy 65.234421 -428.972629)
			(xy 65.22695 -428.995638) (xy 65.212747 -429.015221) (xy 65.193197 -429.029469) (xy 65.170206 -429.036993)
			(xy 65.158112 -429.037496) (xy 64.218312 -429.037496) (xy 64.206203 -429.037073) (xy 64.183176 -429.029577)
			(xy 64.163602 -429.015317) (xy 64.149407 -428.995696) (xy 64.141987 -428.972644) (xy 64.141604 -428.960534)
			(xy 64.141604 -428.44466) (xy 64.130809 -428.406837) (xy 64.1192 -428.329046) (xy 64.11849 -428.28972)
			(xy 61.234828 -428.28972) (xy 61.234828 -428.960534) (xy 61.234421 -428.972629) (xy 61.226951 -428.995636)
			(xy 61.21275 -429.015218) (xy 61.193202 -429.029466) (xy 61.170213 -429.036992) (xy 61.15812 -429.037496)
			(xy 60.21832 -429.037496) (xy 60.206212 -429.037066) (xy 60.183185 -429.029572) (xy 60.163611 -429.015314)
			(xy 60.149416 -428.995695) (xy 60.141995 -428.972643) (xy 60.141612 -428.960534) (xy 60.141612 -428.44466)
			(xy 60.130818 -428.406837) (xy 60.119208 -428.329046) (xy 60.118498 -428.28972) (xy 49.0054 -428.28972)
			(xy 48.932448 -428.365522) (xy 48.780383 -428.51187) (xy 48.622824 -428.652286) (xy 48.460002 -428.786564)
			(xy 48.292156 -428.914507) (xy 48.119534 -429.035927) (xy 47.942387 -429.150646) (xy 47.760976 -429.258496)
			(xy 47.575567 -429.359318) (xy 47.386432 -429.452965) (xy 47.19385 -429.539298) (xy 46.998102 -429.618192)
			(xy 46.799475 -429.68953) (xy 46.598262 -429.753207) (xy 46.394758 -429.809131) (xy 46.189261 -429.857219)
			(xy 45.982073 -429.897401) (xy 45.773498 -429.929618) (xy 45.563841 -429.953821) (xy 45.353412 -429.969977)
			(xy 45.142518 -429.978061) (xy 44.93147 -429.978061) (xy 44.720576 -429.969977) (xy 44.510147 -429.953821)
			(xy 44.30049 -429.929618) (xy 44.091915 -429.897401) (xy 43.884727 -429.857219) (xy 43.67923 -429.809131)
			(xy 43.475726 -429.753207) (xy 43.274513 -429.68953) (xy 43.075886 -429.618192) (xy 42.880138 -429.539298)
			(xy 42.687556 -429.452965) (xy 42.498421 -429.359318) (xy 42.313012 -429.258496) (xy 42.131601 -429.150646)
			(xy 41.954454 -429.035927) (xy 41.781832 -428.914507) (xy 41.613986 -428.786564) (xy 41.451164 -428.652286)
			(xy 41.293605 -428.51187) (xy 41.14154 -428.365522) (xy 40.995192 -428.213457) (xy 40.854776 -428.055898)
			(xy 40.720498 -427.893076) (xy 40.592555 -427.72523) (xy 40.471135 -427.552608) (xy 40.356416 -427.375461)
			(xy 40.248566 -427.19405) (xy 40.147744 -427.008641) (xy 40.054097 -426.819506) (xy 39.967764 -426.626924)
			(xy 39.88887 -426.431176) (xy 39.817532 -426.232549) (xy 39.753855 -426.031336) (xy 39.697931 -425.827832)
			(xy 39.649843 -425.622335) (xy 39.609661 -425.415147) (xy 39.577444 -425.206572) (xy 39.553241 -424.996915)
			(xy 39.537085 -424.786486) (xy 39.529001 -424.575592) (xy 39.528496 -424.470068) (xy 7.00913 -424.470068)
			(xy 7.00913 -430.889918) (xy 58.13806 -430.889918) (xy 58.138169 -430.874832) (xy 58.139951 -430.844714)
			(xy 58.141616 -430.82972) (xy 58.141616 -429.749966) (xy 58.139951 -429.734972) (xy 58.13817 -429.704854)
			(xy 58.13806 -429.689768) (xy 58.138174 -429.674682) (xy 58.139952 -429.644564) (xy 58.141616 -429.62957)
			(xy 58.141616 -429.018954) (xy 58.142068 -429.006864) (xy 58.149534 -428.983866) (xy 58.163726 -428.964289)
			(xy 58.18326 -428.950039) (xy 58.206236 -428.942504) (xy 58.218324 -428.941992) (xy 59.158124 -428.941992)
			(xy 59.170233 -428.942396) (xy 59.19326 -428.949901) (xy 59.212832 -428.964166) (xy 59.227026 -428.983789)
			(xy 59.234448 -429.006843) (xy 59.234832 -429.018954) (xy 59.234832 -431.560478) (xy 59.234373 -431.572569)
			(xy 59.226919 -431.595574) (xy 59.212732 -431.615156) (xy 59.193194 -431.629407) (xy 59.170214 -431.636934)
			(xy 59.158124 -431.63744) (xy 58.218324 -431.63744) (xy 58.20622 -431.636964) (xy 58.183201 -431.629476)
			(xy 58.163631 -431.615228) (xy 58.149434 -431.595622) (xy 58.142005 -431.572583) (xy 58.141616 -431.560478)
			(xy 58.141616 -430.950116) (xy 58.139947 -430.935123) (xy 58.138169 -430.905004) (xy 58.13806 -430.889918)
			(xy 7.00913 -430.889918) (xy 7.00913 -431.889916) (xy 60.138056 -431.889916) (xy 60.138165 -431.87483)
			(xy 60.139947 -431.844712) (xy 60.141612 -431.829718) (xy 60.141612 -430.749964) (xy 60.139947 -430.73497)
			(xy 60.138166 -430.704852) (xy 60.138056 -430.689766) (xy 60.13817 -430.67468) (xy 60.139948 -430.644562)
			(xy 60.141612 -430.629568) (xy 60.141612 -430.018952) (xy 60.142024 -430.006873) (xy 60.149502 -429.983901)
			(xy 60.163711 -429.964363) (xy 60.183262 -429.950171) (xy 60.206241 -429.942713) (xy 60.21832 -429.942244)
			(xy 61.15812 -429.942244) (xy 61.170191 -429.942747) (xy 61.19315 -429.950209) (xy 61.212683 -429.964397)
			(xy 61.226878 -429.983924) (xy 61.234349 -430.006881) (xy 61.234828 -430.018952) (xy 61.234828 -430.889918)
			(xy 62.138052 -430.889918) (xy 62.138161 -430.874832) (xy 62.139943 -430.844714) (xy 62.141608 -430.82972)
			(xy 62.141608 -429.749966) (xy 62.139943 -429.734972) (xy 62.138162 -429.704854) (xy 62.138052 -429.689768)
			(xy 62.138166 -429.674682) (xy 62.139944 -429.644564) (xy 62.141608 -429.62957) (xy 62.141608 -429.018954)
			(xy 62.142068 -429.006865) (xy 62.149533 -428.983868) (xy 62.163723 -428.964292) (xy 62.183255 -428.950042)
			(xy 62.206229 -428.942505) (xy 62.218316 -428.941992) (xy 63.158116 -428.941992) (xy 63.170225 -428.942402)
			(xy 63.193251 -428.949905) (xy 63.212824 -428.964169) (xy 63.227018 -428.983791) (xy 63.23444 -429.006844)
			(xy 63.234824 -429.018954) (xy 63.234824 -431.560478) (xy 63.234373 -431.57257) (xy 63.226918 -431.595576)
			(xy 63.212729 -431.615159) (xy 63.193189 -431.629409) (xy 63.170206 -431.636935) (xy 63.158116 -431.63744)
			(xy 62.218316 -431.63744) (xy 62.206212 -431.63697) (xy 62.183192 -431.62948) (xy 62.163622 -431.615231)
			(xy 62.149426 -431.595623) (xy 62.141997 -431.572583) (xy 62.141608 -431.560478) (xy 62.141608 -430.950116)
			(xy 62.139939 -430.935123) (xy 62.138161 -430.905004) (xy 62.138052 -430.889918) (xy 61.234828 -430.889918)
			(xy 61.234828 -431.889916) (xy 64.138048 -431.889916) (xy 64.138157 -431.87483) (xy 64.139939 -431.844712)
			(xy 64.141604 -431.829718) (xy 64.141604 -430.749964) (xy 64.139939 -430.73497) (xy 64.138158 -430.704852)
			(xy 64.138048 -430.689766) (xy 64.138162 -430.67468) (xy 64.13994 -430.644562) (xy 64.141604 -430.629568)
			(xy 64.141604 -430.018952) (xy 64.142023 -430.006874) (xy 64.149501 -429.983903) (xy 64.163708 -429.964366)
			(xy 64.183257 -429.950173) (xy 64.206233 -429.942714) (xy 64.218312 -429.942244) (xy 65.158112 -429.942244)
			(xy 65.170182 -429.942753) (xy 65.193142 -429.950213) (xy 65.212674 -429.9644) (xy 65.22687 -429.983926)
			(xy 65.234341 -430.006882) (xy 65.23482 -430.018952) (xy 65.23482 -430.889918) (xy 66.138044 -430.889918)
			(xy 66.138153 -430.874832) (xy 66.139935 -430.844714) (xy 66.1416 -430.82972) (xy 66.1416 -429.749966)
			(xy 66.139935 -429.734972) (xy 66.138154 -429.704854) (xy 66.138044 -429.689768) (xy 66.138158 -429.674682)
			(xy 66.139936 -429.644564) (xy 66.1416 -429.62957) (xy 66.1416 -429.018954) (xy 66.142067 -429.006866)
			(xy 66.149532 -428.983871) (xy 66.16372 -428.964295) (xy 66.18325 -428.950044) (xy 66.206222 -428.942507)
			(xy 66.218308 -428.941992) (xy 67.158108 -428.941992) (xy 67.170217 -428.942409) (xy 67.193243 -428.94991)
			(xy 67.212815 -428.964172) (xy 67.22701 -428.983792) (xy 67.234432 -429.006844) (xy 67.234816 -429.018954)
			(xy 67.234816 -431.560478) (xy 67.234373 -431.572571) (xy 67.226917 -431.595578) (xy 67.212726 -431.615162)
			(xy 67.193184 -431.629412) (xy 67.170199 -431.636937) (xy 67.158108 -431.63744) (xy 66.218308 -431.63744)
			(xy 66.206204 -431.636978) (xy 66.183183 -431.629485) (xy 66.163613 -431.615234) (xy 66.149417 -431.595625)
			(xy 66.141989 -431.572584) (xy 66.1416 -431.560478) (xy 66.1416 -430.950116) (xy 66.139931 -430.935123)
			(xy 66.138153 -430.905004) (xy 66.138044 -430.889918) (xy 65.23482 -430.889918) (xy 65.23482 -431.889916)
			(xy 68.13804 -431.889916) (xy 68.138151 -431.87483) (xy 68.139933 -431.844712) (xy 68.141596 -431.829718)
			(xy 68.141596 -430.749964) (xy 68.139931 -430.73497) (xy 68.13815 -430.704852) (xy 68.13804 -430.689766)
			(xy 68.138154 -430.67468) (xy 68.139932 -430.644562) (xy 68.141596 -430.629568) (xy 68.141596 -430.018952)
			(xy 68.142023 -430.006875) (xy 68.149499 -429.983905) (xy 68.163705 -429.964368) (xy 68.183252 -429.950176)
			(xy 68.206226 -429.942715) (xy 68.218304 -429.942244) (xy 69.158104 -429.942244) (xy 69.170174 -429.94276)
			(xy 69.193133 -429.950218) (xy 69.212666 -429.964403) (xy 69.226862 -429.983927) (xy 69.234333 -430.006882)
			(xy 69.234812 -430.018952) (xy 69.234812 -430.889918) (xy 70.138036 -430.889918) (xy 70.138147 -430.874832)
			(xy 70.139929 -430.844714) (xy 70.141592 -430.82972) (xy 70.141592 -429.749966) (xy 70.139927 -429.734972)
			(xy 70.138146 -429.704854) (xy 70.138036 -429.689768) (xy 70.138152 -429.674683) (xy 70.13993 -429.644564)
			(xy 70.141592 -429.62957) (xy 70.141592 -429.018954) (xy 70.142067 -429.006867) (xy 70.149531 -428.983873)
			(xy 70.163717 -428.964298) (xy 70.183245 -428.950047) (xy 70.206214 -428.942508) (xy 70.2183 -428.941992)
			(xy 71.1581 -428.941992) (xy 71.170208 -428.942416) (xy 71.193234 -428.949914) (xy 71.212807 -428.964174)
			(xy 71.227001 -428.983794) (xy 71.234424 -429.006845) (xy 71.234808 -429.018954) (xy 71.234808 -431.560478)
			(xy 71.234275 -431.572562) (xy 71.22683 -431.595553) (xy 71.212659 -431.61513) (xy 71.193142 -431.629383)
			(xy 71.170182 -431.636924) (xy 71.1581 -431.63744) (xy 70.2183 -431.63744) (xy 70.206195 -431.636984)
			(xy 70.183175 -431.62949) (xy 70.163605 -431.615237) (xy 70.149409 -431.595626) (xy 70.141981 -431.572584)
			(xy 70.141592 -431.560478) (xy 70.141592 -430.950116) (xy 70.139923 -430.935123) (xy 70.138145 -430.905004)
			(xy 70.138036 -430.889918) (xy 69.234812 -430.889918) (xy 69.234812 -431.889916) (xy 72.138032 -431.889916)
			(xy 72.138143 -431.87483) (xy 72.139925 -431.844712) (xy 72.141588 -431.829718) (xy 72.141588 -430.749964)
			(xy 72.139923 -430.73497) (xy 72.138142 -430.704852) (xy 72.138032 -430.689766) (xy 72.138148 -430.674681)
			(xy 72.139926 -430.644562) (xy 72.141588 -430.629568) (xy 72.141588 -430.018952) (xy 72.142023 -430.006875)
			(xy 72.149498 -429.983907) (xy 72.163703 -429.964371) (xy 72.183247 -429.950178) (xy 72.206219 -429.942716)
			(xy 72.218296 -429.942244) (xy 73.158096 -429.942244) (xy 73.170166 -429.942767) (xy 73.193124 -429.950222)
			(xy 73.212657 -429.964406) (xy 73.226854 -429.983929) (xy 73.234325 -430.006883) (xy 73.234804 -430.018952)
			(xy 73.234804 -430.889918) (xy 75.138026 -430.889918) (xy 75.13812 -430.875344) (xy 75.139772 -430.846243)
			(xy 75.141328 -430.831752) (xy 75.141328 -429.747934) (xy 75.13978 -429.733442) (xy 75.13813 -429.704342)
			(xy 75.138026 -429.689768) (xy 75.138125 -429.675194) (xy 75.139774 -429.646093) (xy 75.141328 -429.631602)
			(xy 75.141328 -429.018954) (xy 75.141772 -429.006838) (xy 75.149271 -428.983795) (xy 75.163521 -428.964195)
			(xy 75.183127 -428.949955) (xy 75.206174 -428.942467) (xy 75.21829 -428.941992) (xy 76.15809 -428.941992)
			(xy 76.170199 -428.94252) (xy 76.193235 -428.949999) (xy 76.212832 -428.964228) (xy 76.227076 -428.983815)
			(xy 76.234572 -429.006845) (xy 76.235052 -429.018954) (xy 76.235052 -431.560478) (xy 76.234621 -431.572601)
			(xy 76.227134 -431.59566) (xy 76.212885 -431.615277) (xy 76.193271 -431.629528) (xy 76.170213 -431.637019)
			(xy 76.15809 -431.63744) (xy 75.21829 -431.63744) (xy 75.206165 -431.637048) (xy 75.183102 -431.62955)
			(xy 75.163485 -431.615292) (xy 75.149235 -431.59567) (xy 75.141747 -431.572604) (xy 75.141328 -431.560478)
			(xy 75.141328 -430.948084) (xy 75.139785 -430.933592) (xy 75.138132 -430.904492) (xy 75.138026 -430.889918)
			(xy 73.234804 -430.889918) (xy 73.234804 -431.889916) (xy 77.138022 -431.889916) (xy 77.138116 -431.875342)
			(xy 77.139768 -431.846241) (xy 77.141324 -431.83175) (xy 77.141324 -430.747932) (xy 77.139776 -430.73344)
			(xy 77.138126 -430.70434) (xy 77.138022 -430.689766) (xy 77.138121 -430.675192) (xy 77.13977 -430.646091)
			(xy 77.141324 -430.6316) (xy 77.141324 -430.018952) (xy 77.141676 -430.006838) (xy 77.149191 -429.983805)
			(xy 77.163469 -429.964231) (xy 77.183105 -429.950039) (xy 77.20617 -429.942624) (xy 77.218286 -429.942244)
			(xy 78.158086 -429.942244) (xy 78.170175 -429.942719) (xy 78.193176 -429.950173) (xy 78.212757 -429.964357)
			(xy 78.227007 -429.983889) (xy 78.234539 -430.006864) (xy 78.235048 -430.018952) (xy 78.235048 -430.889918)
			(xy 79.138018 -430.889918) (xy 79.138112 -430.875344) (xy 79.139764 -430.846243) (xy 79.14132 -430.831752)
			(xy 79.14132 -429.747934) (xy 79.139772 -429.733442) (xy 79.138122 -429.704342) (xy 79.138018 -429.689768)
			(xy 79.138117 -429.675194) (xy 79.139766 -429.646093) (xy 79.14132 -429.631602) (xy 79.14132 -429.018954)
			(xy 79.141772 -429.006839) (xy 79.14927 -428.983797) (xy 79.163518 -428.964198) (xy 79.183122 -428.949957)
			(xy 79.206167 -428.942468) (xy 79.218282 -428.941992) (xy 80.158082 -428.941992) (xy 80.170191 -428.942526)
			(xy 80.193226 -428.950003) (xy 80.212824 -428.964231) (xy 80.227068 -428.983817) (xy 80.234563 -429.006845)
			(xy 80.235044 -429.018954) (xy 80.235044 -431.560478) (xy 80.234621 -431.572601) (xy 80.227133 -431.595663)
			(xy 80.212882 -431.61528) (xy 80.193266 -431.629531) (xy 80.170205 -431.63702) (xy 80.158082 -431.63744)
			(xy 79.218282 -431.63744) (xy 79.206156 -431.637055) (xy 79.183093 -431.629555) (xy 79.163476 -431.615295)
			(xy 79.149227 -431.595671) (xy 79.141739 -431.572604) (xy 79.14132 -431.560478) (xy 79.14132 -430.948084)
			(xy 79.139777 -430.933592) (xy 79.138124 -430.904492) (xy 79.138018 -430.889918) (xy 78.235048 -430.889918)
			(xy 78.235048 -431.889916) (xy 81.138014 -431.889916) (xy 81.138108 -431.875342) (xy 81.13976 -431.846241)
			(xy 81.141316 -431.83175) (xy 81.141316 -430.747932) (xy 81.139768 -430.73344) (xy 81.138118 -430.70434)
			(xy 81.138014 -430.689766) (xy 81.138112 -430.675192) (xy 81.139761 -430.646091) (xy 81.141316 -430.6316)
			(xy 81.141316 -430.018952) (xy 81.141676 -430.006839) (xy 81.14919 -429.983807) (xy 81.163466 -429.964234)
			(xy 81.1831 -429.950041) (xy 81.206163 -429.942625) (xy 81.218278 -429.942244) (xy 82.158078 -429.942244)
			(xy 82.170167 -429.942726) (xy 82.193167 -429.950177) (xy 82.212748 -429.96436) (xy 82.226999 -429.983891)
			(xy 82.234531 -430.006865) (xy 82.23504 -430.018952) (xy 82.23504 -430.889918) (xy 83.13801 -430.889918)
			(xy 83.138104 -430.875344) (xy 83.139756 -430.846243) (xy 83.141312 -430.831752) (xy 83.141312 -429.747934)
			(xy 83.139764 -429.733442) (xy 83.138114 -429.704342) (xy 83.13801 -429.689768) (xy 83.138108 -429.675194)
			(xy 83.139758 -429.646093) (xy 83.141312 -429.631602) (xy 83.141312 -429.018954) (xy 83.141772 -429.00684)
			(xy 83.149269 -428.983799) (xy 83.163515 -428.964201) (xy 83.183117 -428.94996) (xy 83.20616 -428.942469)
			(xy 83.218274 -428.941992) (xy 84.158074 -428.941992) (xy 84.170183 -428.942533) (xy 84.193217 -428.950008)
			(xy 84.212815 -428.964233) (xy 84.227059 -428.983818) (xy 84.234555 -429.006846) (xy 84.235036 -429.018954)
			(xy 84.235036 -431.560478) (xy 84.234621 -431.572602) (xy 84.227132 -431.595665) (xy 84.21288 -431.615282)
			(xy 84.193261 -431.629533) (xy 84.170198 -431.637022) (xy 84.158074 -431.63744) (xy 83.218274 -431.63744)
			(xy 83.206156 -431.63701) (xy 83.183108 -431.629513) (xy 83.163505 -431.615261) (xy 83.149265 -431.595649)
			(xy 83.141782 -431.572596) (xy 83.141312 -431.560478) (xy 83.141312 -430.948084) (xy 83.139769 -430.933592)
			(xy 83.138116 -430.904492) (xy 83.13801 -430.889918) (xy 82.23504 -430.889918) (xy 82.23504 -431.889916)
			(xy 85.138006 -431.889916) (xy 85.1381 -431.875342) (xy 85.139752 -431.846241) (xy 85.141308 -431.83175)
			(xy 85.141308 -430.747932) (xy 85.13976 -430.73344) (xy 85.13811 -430.70434) (xy 85.138006 -430.689766)
			(xy 85.138104 -430.675192) (xy 85.139753 -430.646091) (xy 85.141308 -430.6316) (xy 85.141308 -430.018952)
			(xy 85.141676 -430.00684) (xy 85.149189 -429.98381) (xy 85.163463 -429.964237) (xy 85.183095 -429.950044)
			(xy 85.206156 -429.942626) (xy 85.21827 -429.942244) (xy 86.15807 -429.942244) (xy 86.170158 -429.942733)
			(xy 86.193159 -429.950182) (xy 86.212739 -429.964363) (xy 86.226991 -429.983892) (xy 86.234523 -430.006865)
			(xy 86.235032 -430.018952) (xy 86.235032 -430.889918) (xy 87.138002 -430.889918) (xy 87.138096 -430.875344)
			(xy 87.139748 -430.846243) (xy 87.141304 -430.831752) (xy 87.141304 -429.747934) (xy 87.139756 -429.733442)
			(xy 87.138106 -429.704342) (xy 87.138002 -429.689768) (xy 87.1381 -429.675194) (xy 87.13975 -429.646093)
			(xy 87.141304 -429.631602) (xy 87.141304 -429.018954) (xy 87.141772 -429.00684) (xy 87.149268 -428.983801)
			(xy 87.163512 -428.964203) (xy 87.183112 -428.949962) (xy 87.206152 -428.94247) (xy 87.218266 -428.941992)
			(xy 88.158066 -428.941992) (xy 88.170174 -428.94254) (xy 88.193209 -428.950012) (xy 88.212807 -428.964236)
			(xy 88.227051 -428.98382) (xy 88.234547 -429.006846) (xy 88.235028 -429.018954) (xy 88.235028 -431.560478)
			(xy 88.234621 -431.572603) (xy 88.22713 -431.595667) (xy 88.212877 -431.615285) (xy 88.193256 -431.629536)
			(xy 88.170191 -431.637023) (xy 88.158066 -431.63744) (xy 87.218266 -431.63744) (xy 87.206147 -431.637017)
			(xy 87.183099 -431.629518) (xy 87.163496 -431.615264) (xy 87.149257 -431.59565) (xy 87.141774 -431.572597)
			(xy 87.141304 -431.560478) (xy 87.141304 -430.948084) (xy 87.13976 -430.933592) (xy 87.138108 -430.904492)
			(xy 87.138002 -430.889918) (xy 86.235032 -430.889918) (xy 86.235032 -431.889916) (xy 89.137998 -431.889916)
			(xy 89.138092 -431.875342) (xy 89.139744 -431.846241) (xy 89.1413 -431.83175) (xy 89.1413 -430.747932)
			(xy 89.139752 -430.73344) (xy 89.138102 -430.70434) (xy 89.137998 -430.689766) (xy 89.138096 -430.675192)
			(xy 89.139746 -430.646091) (xy 89.1413 -430.6316) (xy 89.1413 -430.018952) (xy 89.141676 -430.006841)
			(xy 89.149188 -429.983812) (xy 89.16346 -429.96424) (xy 89.18309 -429.950047) (xy 89.206149 -429.942627)
			(xy 89.218262 -429.942244) (xy 90.158062 -429.942244) (xy 90.17015 -429.94274) (xy 90.19315 -429.950187)
			(xy 90.212731 -429.964366) (xy 90.226983 -429.983894) (xy 90.234515 -430.006866) (xy 90.235024 -430.018952)
			(xy 90.235024 -431.360072) (xy 108.40466 -431.360072) (xy 108.405158 -431.275192) (xy 108.413115 -431.105619)
			(xy 108.429011 -430.936605) (xy 108.452812 -430.768522) (xy 108.484466 -430.601739) (xy 108.523902 -430.436623)
			(xy 108.571034 -430.273538) (xy 108.625758 -430.11284) (xy 108.687955 -429.954885) (xy 108.757487 -429.800018)
			(xy 108.834202 -429.648581) (xy 108.91793 -429.500905) (xy 109.008488 -429.357317) (xy 109.105677 -429.218131)
			(xy 109.209284 -429.083654) (xy 109.319079 -428.954181) (xy 109.434823 -428.829996) (xy 109.55626 -428.711373)
			(xy 109.683124 -428.598572) (xy 109.815135 -428.491842) (xy 109.952005 -428.391417) (xy 110.09343 -428.297518)
			(xy 110.239102 -428.21035) (xy 110.3887 -428.130107) (xy 110.541894 -428.056963) (xy 110.698348 -427.991081)
			(xy 110.857718 -427.932604) (xy 111.019654 -427.881662) (xy 111.1838 -427.838366) (xy 111.349795 -427.802811)
			(xy 111.517274 -427.775076) (xy 111.685869 -427.755222) (xy 111.855209 -427.743292) (xy 112.024922 -427.739313)
			(xy 112.194635 -427.743292) (xy 112.363975 -427.755222) (xy 112.53257 -427.775076) (xy 112.700049 -427.802811)
			(xy 112.866044 -427.838366) (xy 113.03019 -427.881662) (xy 113.192126 -427.932604) (xy 113.351496 -427.991081)
			(xy 113.50795 -428.056963) (xy 113.661144 -428.130107) (xy 113.810742 -428.21035) (xy 113.943382 -428.28972)
			(xy 127.237998 -428.28972) (xy 127.238092 -428.275146) (xy 127.239744 -428.246045) (xy 127.2413 -428.231554)
			(xy 127.2413 -427.14799) (xy 127.239757 -427.133498) (xy 127.238104 -427.104398) (xy 127.237998 -427.089824)
			(xy 127.238092 -427.07525) (xy 127.239744 -427.046149) (xy 127.2413 -427.031658) (xy 127.2413 -426.41901)
			(xy 127.24182 -426.4069) (xy 127.2493 -426.383863) (xy 127.263531 -426.364265) (xy 127.28312 -426.350022)
			(xy 127.306152 -426.342527) (xy 127.318262 -426.342048) (xy 128.258062 -426.342048) (xy 128.270184 -426.342492)
			(xy 128.293243 -426.349975) (xy 128.31286 -426.36422) (xy 128.327112 -426.383832) (xy 128.334603 -426.406888)
			(xy 128.335024 -426.41901) (xy 128.335024 -427.289976) (xy 129.237994 -427.289976) (xy 129.238084 -427.275402)
			(xy 129.239739 -427.246301) (xy 129.241296 -427.23181) (xy 129.241296 -426.147992) (xy 129.239753 -426.1335)
			(xy 129.2381 -426.1044) (xy 129.237994 -426.089826) (xy 129.238089 -426.075252) (xy 129.23974 -426.046151)
			(xy 129.241296 -426.03166) (xy 129.241296 -425.419012) (xy 129.241727 -425.406904) (xy 129.249222 -425.383878)
			(xy 129.26348 -425.364305) (xy 129.283099 -425.35011) (xy 129.306149 -425.342688) (xy 129.318258 -425.342304)
			(xy 130.258058 -425.342304) (xy 130.270142 -425.342842) (xy 130.293135 -425.350283) (xy 130.312713 -425.364453)
			(xy 130.326966 -425.383969) (xy 130.334505 -425.40693) (xy 130.33502 -425.419012) (xy 130.33502 -427.960536)
			(xy 130.334615 -427.972645) (xy 130.327108 -427.99567) (xy 130.312843 -428.01524) (xy 130.29322 -428.029435)
			(xy 130.270168 -428.036858) (xy 130.258058 -428.037244) (xy 129.318258 -428.037244) (xy 129.306165 -428.036828)
			(xy 129.28316 -428.029358) (xy 129.263579 -428.015159) (xy 129.249331 -427.995614) (xy 129.241803 -427.972628)
			(xy 129.241296 -427.960536) (xy 129.241296 -427.348142) (xy 129.239749 -427.33365) (xy 129.238099 -427.30455)
			(xy 129.237994 -427.289976) (xy 128.335024 -427.289976) (xy 128.335024 -428.28972) (xy 131.23799 -428.28972)
			(xy 131.238084 -428.275146) (xy 131.239736 -428.246045) (xy 131.241292 -428.231554) (xy 131.241292 -427.14799)
			(xy 131.239749 -427.133498) (xy 131.238096 -427.104398) (xy 131.23799 -427.089824) (xy 131.238085 -427.07525)
			(xy 131.239736 -427.046149) (xy 131.241292 -427.031658) (xy 131.241292 -426.41901) (xy 131.24182 -426.406901)
			(xy 131.249299 -426.383865) (xy 131.263528 -426.364268) (xy 131.283115 -426.350024) (xy 131.306145 -426.342528)
			(xy 131.318254 -426.342048) (xy 132.258054 -426.342048) (xy 132.270175 -426.342499) (xy 132.293234 -426.34998)
			(xy 132.312851 -426.364223) (xy 132.327104 -426.383833) (xy 132.334595 -426.406889) (xy 132.335016 -426.41901)
			(xy 132.335016 -427.289976) (xy 133.237986 -427.289976) (xy 133.238076 -427.275402) (xy 133.239731 -427.246301)
			(xy 133.241288 -427.23181) (xy 133.241288 -426.147992) (xy 133.239745 -426.1335) (xy 133.238092 -426.1044)
			(xy 133.237986 -426.089826) (xy 133.238081 -426.075252) (xy 133.239732 -426.046151) (xy 133.241288 -426.03166)
			(xy 133.241288 -425.419012) (xy 133.241727 -425.406905) (xy 133.249221 -425.38388) (xy 133.263477 -425.364308)
			(xy 133.283094 -425.350113) (xy 133.306142 -425.342689) (xy 133.31825 -425.342304) (xy 134.25805 -425.342304)
			(xy 134.270133 -425.342849) (xy 134.293126 -425.350288) (xy 134.312704 -425.364455) (xy 134.326958 -425.383971)
			(xy 134.334497 -425.406931) (xy 134.335012 -425.419012) (xy 134.335012 -427.960536) (xy 134.334614 -427.972646)
			(xy 134.327107 -427.995672) (xy 134.31284 -428.015243) (xy 134.293215 -428.029437) (xy 134.270161 -428.036859)
			(xy 134.25805 -428.037244) (xy 133.31825 -428.037244) (xy 133.306161 -428.03675) (xy 133.28316 -428.029305)
			(xy 133.263578 -428.015126) (xy 133.249326 -427.995597) (xy 133.241795 -427.972623) (xy 133.241288 -427.960536)
			(xy 133.241288 -427.348142) (xy 133.239741 -427.33365) (xy 133.238091 -427.30455) (xy 133.237986 -427.289976)
			(xy 132.335016 -427.289976) (xy 132.335016 -428.28972) (xy 135.237982 -428.28972) (xy 135.238076 -428.275146)
			(xy 135.239728 -428.246045) (xy 135.241284 -428.231554) (xy 135.241284 -427.14799) (xy 135.239741 -427.133498)
			(xy 135.238088 -427.104398) (xy 135.237982 -427.089824) (xy 135.238077 -427.07525) (xy 135.239728 -427.046149)
			(xy 135.241284 -427.031658) (xy 135.241284 -426.41901) (xy 135.241669 -426.406883) (xy 135.249164 -426.383817)
			(xy 135.263423 -426.364198) (xy 135.283049 -426.349948) (xy 135.306119 -426.342464) (xy 135.318246 -426.342048)
			(xy 136.258046 -426.342048) (xy 136.270164 -426.342473) (xy 136.29321 -426.349974) (xy 136.312812 -426.364228)
			(xy 136.327052 -426.38384) (xy 136.334536 -426.406892) (xy 136.335008 -426.41901) (xy 136.335008 -427.289976)
			(xy 137.237978 -427.289976) (xy 137.238068 -427.275402) (xy 137.239723 -427.246301) (xy 137.24128 -427.23181)
			(xy 137.24128 -426.147992) (xy 137.239737 -426.1335) (xy 137.238084 -426.1044) (xy 137.237978 -426.089826)
			(xy 137.238073 -426.075252) (xy 137.239724 -426.046151) (xy 137.24128 -426.03166) (xy 137.24128 -425.419012)
			(xy 137.241727 -425.406906) (xy 137.24922 -425.383882) (xy 137.263475 -425.364311) (xy 137.283089 -425.350115)
			(xy 137.306135 -425.342691) (xy 137.318242 -425.342304) (xy 138.258042 -425.342304) (xy 138.27013 -425.342771)
			(xy 138.293126 -425.350235) (xy 138.312702 -425.364423) (xy 138.326953 -425.383953) (xy 138.33449 -425.406925)
			(xy 138.335004 -425.419012) (xy 138.335004 -427.960536) (xy 138.334614 -427.972646) (xy 138.327106 -427.995674)
			(xy 138.312837 -428.015246) (xy 138.29321 -428.02944) (xy 138.270154 -428.03686) (xy 138.258042 -428.037244)
			(xy 137.318242 -428.037244) (xy 137.306153 -428.036757) (xy 137.283151 -428.029309) (xy 137.263569 -428.015129)
			(xy 137.249318 -427.995598) (xy 137.241787 -427.972623) (xy 137.24128 -427.960536) (xy 137.24128 -427.348142)
			(xy 137.239733 -427.33365) (xy 137.238083 -427.30455) (xy 137.237978 -427.289976) (xy 136.335008 -427.289976)
			(xy 136.335008 -428.28972) (xy 139.237974 -428.28972) (xy 139.238068 -428.275146) (xy 139.23972 -428.246045)
			(xy 139.241276 -428.231554) (xy 139.241276 -427.14799) (xy 139.239733 -427.133498) (xy 139.23808 -427.104398)
			(xy 139.237974 -427.089824) (xy 139.238069 -427.07525) (xy 139.23972 -427.046149) (xy 139.241276 -427.031658)
			(xy 139.241276 -426.41901) (xy 139.241669 -426.406884) (xy 139.249163 -426.383819) (xy 139.26342 -426.364201)
			(xy 139.283044 -426.34995) (xy 139.306112 -426.342465) (xy 139.318238 -426.342048) (xy 140.258038 -426.342048)
			(xy 140.270156 -426.342479) (xy 140.293202 -426.349978) (xy 140.312804 -426.36423) (xy 140.327044 -426.383841)
			(xy 140.334528 -426.406892) (xy 140.335 -426.41901) (xy 140.335 -427.289976) (xy 142.237968 -427.289976)
			(xy 142.238082 -427.274891) (xy 142.23986 -427.244772) (xy 142.241524 -427.229778) (xy 142.241524 -426.150024)
			(xy 142.239855 -426.135031) (xy 142.238077 -426.104912) (xy 142.237968 -426.089826) (xy 142.238078 -426.07474)
			(xy 142.239859 -426.044622) (xy 142.241524 -426.029628) (xy 142.241524 -425.419012) (xy 142.241924 -425.406927)
			(xy 142.249392 -425.383939) (xy 142.2636 -425.364386) (xy 142.283157 -425.350183) (xy 142.306147 -425.34272)
			(xy 142.318232 -425.342304) (xy 143.258032 -425.342304) (xy 143.270109 -425.342737) (xy 143.29308 -425.35021)
			(xy 143.312617 -425.364414) (xy 143.32681 -425.38396) (xy 143.33427 -425.406934) (xy 143.33474 -425.419012)
			(xy 143.33474 -427.960536) (xy 143.334267 -427.972609) (xy 143.326799 -427.995572) (xy 143.312603 -428.015106)
			(xy 143.293069 -428.0293) (xy 143.270105 -428.036768) (xy 143.258032 -428.037244) (xy 142.318232 -428.037244)
			(xy 142.306163 -428.036709) (xy 142.283203 -428.02926) (xy 142.263668 -428.01508) (xy 142.249471 -427.995558)
			(xy 142.242001 -427.972605) (xy 142.241524 -427.960536) (xy 142.241524 -427.350174) (xy 142.23986 -427.33518)
			(xy 142.238078 -427.305062) (xy 142.237968 -427.289976) (xy 140.335 -427.289976) (xy 140.335 -428.28972)
			(xy 144.237964 -428.28972) (xy 144.238073 -428.274634) (xy 144.239855 -428.244516) (xy 144.24152 -428.229522)
			(xy 144.24152 -427.150022) (xy 144.239851 -427.135029) (xy 144.238073 -427.10491) (xy 144.237964 -427.089824)
			(xy 144.238074 -427.074738) (xy 144.239855 -427.04462) (xy 144.24152 -427.029626) (xy 144.24152 -426.41901)
			(xy 144.242016 -426.406923) (xy 144.249467 -426.383926) (xy 144.263647 -426.364348) (xy 144.283173 -426.350096)
			(xy 144.306143 -426.34256) (xy 144.318228 -426.342048) (xy 145.258028 -426.342048) (xy 145.270133 -426.342492)
			(xy 145.293152 -426.349993) (xy 145.312721 -426.364249) (xy 145.326916 -426.383861) (xy 145.334345 -426.406904)
			(xy 145.334736 -426.41901) (xy 145.334736 -427.289976) (xy 146.23796 -427.289976) (xy 146.238074 -427.274891)
			(xy 146.239852 -427.244772) (xy 146.241516 -427.229778) (xy 146.241516 -426.150024) (xy 146.239847 -426.135031)
			(xy 146.238069 -426.104912) (xy 146.23796 -426.089826) (xy 146.23807 -426.07474) (xy 146.239851 -426.044622)
			(xy 146.241516 -426.029628) (xy 146.241516 -425.419012) (xy 146.241923 -425.406928) (xy 146.249391 -425.383941)
			(xy 146.263597 -425.364389) (xy 146.283152 -425.350185) (xy 146.306139 -425.342722) (xy 146.318224 -425.342304)
			(xy 147.258024 -425.342304) (xy 147.270101 -425.342744) (xy 147.293071 -425.350215) (xy 147.312609 -425.364417)
			(xy 147.326802 -425.383961) (xy 147.334261 -425.406935) (xy 147.334732 -425.419012) (xy 147.334732 -427.960536)
			(xy 147.334267 -427.97261) (xy 147.326798 -427.995574) (xy 147.3126 -428.015109) (xy 147.293064 -428.029303)
			(xy 147.270098 -428.036769) (xy 147.258024 -428.037244) (xy 146.318224 -428.037244) (xy 146.306154 -428.036716)
			(xy 146.283194 -428.029264) (xy 146.26366 -428.015083) (xy 146.249463 -427.99556) (xy 146.241993 -427.972605)
			(xy 146.241516 -427.960536) (xy 146.241516 -427.350174) (xy 146.239852 -427.33518) (xy 146.23807 -427.305062)
			(xy 146.23796 -427.289976) (xy 145.334736 -427.289976) (xy 145.334736 -428.28972) (xy 148.237956 -428.28972)
			(xy 148.238066 -428.274634) (xy 148.239847 -428.244516) (xy 148.241512 -428.229522) (xy 148.241512 -427.150022)
			(xy 148.239843 -427.135029) (xy 148.238065 -427.10491) (xy 148.237956 -427.089824) (xy 148.238066 -427.074738)
			(xy 148.239847 -427.04462) (xy 148.241512 -427.029626) (xy 148.241512 -426.41901) (xy 148.242015 -426.406924)
			(xy 148.249466 -426.383928) (xy 148.263644 -426.364351) (xy 148.283168 -426.350099) (xy 148.306136 -426.342562)
			(xy 148.31822 -426.342048) (xy 149.25802 -426.342048) (xy 149.270125 -426.342499) (xy 149.293144 -426.349997)
			(xy 149.312712 -426.364252) (xy 149.326908 -426.383863) (xy 149.334337 -426.406904) (xy 149.334728 -426.41901)
			(xy 149.334728 -427.289976) (xy 150.237952 -427.289976) (xy 150.238066 -427.274891) (xy 150.239844 -427.244772)
			(xy 150.241508 -427.229778) (xy 150.241508 -426.150024) (xy 150.239839 -426.135031) (xy 150.238061 -426.104912)
			(xy 150.237952 -426.089826) (xy 150.238062 -426.07474) (xy 150.239843 -426.044622) (xy 150.241508 -426.029628)
			(xy 150.241508 -425.419012) (xy 150.241923 -425.406928) (xy 150.249389 -425.383943) (xy 150.263594 -425.364392)
			(xy 150.283147 -425.350188) (xy 150.306132 -425.342723) (xy 150.318216 -425.342304) (xy 151.258016 -425.342304)
			(xy 151.270093 -425.342751) (xy 151.293062 -425.350219) (xy 151.3126 -425.36442) (xy 151.326794 -425.383963)
			(xy 151.334253 -425.406935) (xy 151.334724 -425.419012) (xy 151.334724 -427.960536) (xy 151.334267 -427.972611)
			(xy 151.326796 -427.995577) (xy 151.312597 -428.015112) (xy 151.293059 -428.029306) (xy 151.270091 -428.03677)
			(xy 151.258016 -428.037244) (xy 150.318216 -428.037244) (xy 150.306146 -428.036723) (xy 150.283185 -428.029269)
			(xy 150.263651 -428.015086) (xy 150.249455 -427.995561) (xy 150.241985 -427.972606) (xy 150.241508 -427.960536)
			(xy 150.241508 -427.350174) (xy 150.239844 -427.33518) (xy 150.238062 -427.305062) (xy 150.237952 -427.289976)
			(xy 149.334728 -427.289976) (xy 149.334728 -428.28972) (xy 152.237948 -428.28972) (xy 152.238058 -428.274634)
			(xy 152.239839 -428.244516) (xy 152.241504 -428.229522) (xy 152.241504 -427.150022) (xy 152.239835 -427.135029)
			(xy 152.238057 -427.10491) (xy 152.237948 -427.089824) (xy 152.238058 -427.074738) (xy 152.239839 -427.04462)
			(xy 152.241504 -427.029626) (xy 152.241504 -426.41901) (xy 152.242015 -426.406925) (xy 152.249465 -426.38393)
			(xy 152.263641 -426.364353) (xy 152.283163 -426.350101) (xy 152.306128 -426.342563) (xy 152.318212 -426.342048)
			(xy 153.258012 -426.342048) (xy 153.270116 -426.342505) (xy 153.293135 -426.350002) (xy 153.312704 -426.364255)
			(xy 153.3269 -426.383864) (xy 153.334329 -426.406905) (xy 153.33472 -426.41901) (xy 153.33472 -427.289976)
			(xy 154.237944 -427.289976) (xy 154.238059 -427.274891) (xy 154.239836 -427.244772) (xy 154.2415 -427.229778)
			(xy 154.2415 -426.150024) (xy 154.239831 -426.135031) (xy 154.238053 -426.104912) (xy 154.237944 -426.089826)
			(xy 154.238054 -426.07474) (xy 154.239835 -426.044622) (xy 154.2415 -426.029628) (xy 154.2415 -425.419012)
			(xy 154.241923 -425.406929) (xy 154.249388 -425.383946) (xy 154.263592 -425.364394) (xy 154.283142 -425.35019)
			(xy 154.306125 -425.342724) (xy 154.318208 -425.342304) (xy 155.258008 -425.342304) (xy 155.270092 -425.342706)
			(xy 155.293077 -425.350177) (xy 155.312629 -425.364386) (xy 155.326832 -425.383941) (xy 155.334297 -425.406928)
			(xy 155.334716 -425.419012) (xy 155.334716 -427.960536) (xy 155.334267 -427.972612) (xy 155.326795 -427.995579)
			(xy 155.312595 -428.015115) (xy 155.293054 -428.029308) (xy 155.270084 -428.036771) (xy 155.258008 -428.037244)
			(xy 154.318208 -428.037244) (xy 154.306137 -428.03673) (xy 154.283177 -428.029274) (xy 154.263643 -428.015089)
			(xy 154.249447 -427.995563) (xy 154.241977 -427.972606) (xy 154.2415 -427.960536) (xy 154.2415 -427.350174)
			(xy 154.239836 -427.33518) (xy 154.238054 -427.305062) (xy 154.237944 -427.289976) (xy 153.33472 -427.289976)
			(xy 153.33472 -428.28972) (xy 156.23794 -428.28972) (xy 156.238052 -428.274634) (xy 156.239833 -428.244516)
			(xy 156.241496 -428.229522) (xy 156.241496 -427.150022) (xy 156.239827 -427.135029) (xy 156.238049 -427.10491)
			(xy 156.23794 -427.089824) (xy 156.23805 -427.074738) (xy 156.239831 -427.04462) (xy 156.241496 -427.029626)
			(xy 156.241496 -426.41901) (xy 156.242015 -426.406925) (xy 156.249464 -426.383932) (xy 156.263639 -426.364356)
			(xy 156.283158 -426.350104) (xy 156.306121 -426.342564) (xy 156.318204 -426.342048) (xy 157.258004 -426.342048)
			(xy 157.270108 -426.342512) (xy 157.293127 -426.350006) (xy 157.312695 -426.364257) (xy 157.326891 -426.383866)
			(xy 157.334321 -426.406905) (xy 157.334712 -426.41901) (xy 157.334712 -428.960534) (xy 157.334321 -428.97263)
			(xy 157.326849 -428.99564) (xy 157.312644 -429.015223) (xy 157.293092 -429.029471) (xy 157.270099 -429.036994)
			(xy 157.258004 -429.037496) (xy 156.318204 -429.037496) (xy 156.306095 -429.03708) (xy 156.283067 -429.029582)
			(xy 156.263493 -429.01532) (xy 156.249299 -428.995698) (xy 156.241879 -428.972644) (xy 156.241496 -428.960534)
			(xy 156.241496 -428.349918) (xy 156.239827 -428.334925) (xy 156.238049 -428.304806) (xy 156.23794 -428.28972)
			(xy 153.33472 -428.28972) (xy 153.33472 -428.960534) (xy 153.334321 -428.972629) (xy 153.32685 -428.995638)
			(xy 153.312647 -429.015221) (xy 153.293097 -429.029469) (xy 153.270106 -429.036993) (xy 153.258012 -429.037496)
			(xy 152.318212 -429.037496) (xy 152.306103 -429.037073) (xy 152.283076 -429.029577) (xy 152.263502 -429.015317)
			(xy 152.249307 -428.995696) (xy 152.241887 -428.972644) (xy 152.241504 -428.960534) (xy 152.241504 -428.349918)
			(xy 152.239835 -428.334925) (xy 152.238057 -428.304806) (xy 152.237948 -428.28972) (xy 149.334728 -428.28972)
			(xy 149.334728 -428.960534) (xy 149.334321 -428.972629) (xy 149.326851 -428.995636) (xy 149.31265 -429.015218)
			(xy 149.293102 -429.029466) (xy 149.270113 -429.036992) (xy 149.25802 -429.037496) (xy 148.31822 -429.037496)
			(xy 148.306112 -429.037066) (xy 148.283085 -429.029572) (xy 148.263511 -429.015314) (xy 148.249316 -428.995695)
			(xy 148.241895 -428.972643) (xy 148.241512 -428.960534) (xy 148.241512 -428.349918) (xy 148.239843 -428.334925)
			(xy 148.238065 -428.304806) (xy 148.237956 -428.28972) (xy 145.334736 -428.28972) (xy 145.334736 -428.960534)
			(xy 145.334321 -428.972628) (xy 145.326852 -428.995634) (xy 145.312653 -429.015215) (xy 145.293107 -429.029464)
			(xy 145.27012 -429.03699) (xy 145.258028 -429.037496) (xy 144.318228 -429.037496) (xy 144.30612 -429.03706)
			(xy 144.283093 -429.029567) (xy 144.263519 -429.015311) (xy 144.249324 -428.995693) (xy 144.241903 -428.972643)
			(xy 144.24152 -428.960534) (xy 144.24152 -428.349918) (xy 144.239851 -428.334925) (xy 144.238073 -428.304806)
			(xy 144.237964 -428.28972) (xy 140.335 -428.28972) (xy 140.335 -428.960534) (xy 140.334518 -428.972647)
			(xy 140.327026 -428.995684) (xy 140.312785 -429.015282) (xy 140.293188 -429.029524) (xy 140.270151 -429.037017)
			(xy 140.258038 -429.037496) (xy 139.318238 -429.037496) (xy 139.306121 -429.037008) (xy 139.283069 -429.029531)
			(xy 139.263456 -429.015295) (xy 139.249202 -428.995696) (xy 139.241703 -428.972651) (xy 139.241276 -428.960534)
			(xy 139.241276 -428.347886) (xy 139.239733 -428.333394) (xy 139.23808 -428.304294) (xy 139.237974 -428.28972)
			(xy 136.335008 -428.28972) (xy 136.335008 -428.960534) (xy 136.334518 -428.972646) (xy 136.327027 -428.995682)
			(xy 136.312788 -429.01528) (xy 136.293193 -429.029522) (xy 136.270158 -429.037016) (xy 136.258046 -429.037496)
			(xy 135.318246 -429.037496) (xy 135.306129 -429.037002) (xy 135.283077 -429.029526) (xy 135.263464 -429.015292)
			(xy 135.249211 -428.995694) (xy 135.241711 -428.972651) (xy 135.241284 -428.960534) (xy 135.241284 -428.347886)
			(xy 135.239741 -428.333394) (xy 135.238088 -428.304294) (xy 135.237982 -428.28972) (xy 132.335016 -428.28972)
			(xy 132.335016 -428.960534) (xy 132.334668 -428.972663) (xy 132.327161 -428.995731) (xy 132.312892 -429.015349)
			(xy 132.293259 -429.029598) (xy 132.270184 -429.037081) (xy 132.258054 -429.037496) (xy 131.318254 -429.037496)
			(xy 131.30614 -429.037028) (xy 131.283101 -429.029532) (xy 131.263503 -429.015288) (xy 131.249262 -428.995688)
			(xy 131.24177 -428.972648) (xy 131.241292 -428.960534) (xy 131.241292 -428.347886) (xy 131.239749 -428.333394)
			(xy 131.238096 -428.304294) (xy 131.23799 -428.28972) (xy 128.335024 -428.28972) (xy 128.335024 -428.960534)
			(xy 128.334669 -428.972662) (xy 128.327162 -428.995729) (xy 128.312895 -429.015347) (xy 128.293264 -429.029595)
			(xy 128.270191 -429.03708) (xy 128.258062 -429.037496) (xy 127.318262 -429.037496) (xy 127.306149 -429.037021)
			(xy 127.28311 -429.029528) (xy 127.263512 -429.015285) (xy 127.24927 -428.995686) (xy 127.241778 -428.972647)
			(xy 127.2413 -428.960534) (xy 127.2413 -428.347886) (xy 127.239757 -428.333394) (xy 127.238104 -428.304294)
			(xy 127.237998 -428.28972) (xy 113.943382 -428.28972) (xy 113.956414 -428.297518) (xy 114.097839 -428.391417)
			(xy 114.234709 -428.491842) (xy 114.36672 -428.598572) (xy 114.493584 -428.711373) (xy 114.615021 -428.829996)
			(xy 114.730765 -428.954181) (xy 114.84056 -429.083654) (xy 114.944167 -429.218131) (xy 115.041356 -429.357317)
			(xy 115.131914 -429.500905) (xy 115.215642 -429.648581) (xy 115.292357 -429.800018) (xy 115.361889 -429.954885)
			(xy 115.424086 -430.11284) (xy 115.47881 -430.273538) (xy 115.525942 -430.436623) (xy 115.565378 -430.601739)
			(xy 115.597032 -430.768522) (xy 115.614222 -430.889918) (xy 125.218444 -430.889918) (xy 125.218955 -430.857362)
			(xy 125.226898 -430.792738) (xy 125.242681 -430.729568) (xy 125.266066 -430.668801) (xy 125.296702 -430.611348)
			(xy 125.334131 -430.55807) (xy 125.377791 -430.509766) (xy 125.402086 -430.48809) (xy 125.482858 -430.323244)
			(xy 125.487583 -430.312737) (xy 125.491061 -430.289973) (xy 125.487567 -430.267211) (xy 125.482858 -430.256696)
			(xy 125.401832 -430.091596) (xy 125.377594 -430.069872) (xy 125.333994 -430.021546) (xy 125.296616 -429.96826)
			(xy 125.266019 -429.910812) (xy 125.24266 -429.85006) (xy 125.226888 -429.786912) (xy 125.218938 -429.722312)
			(xy 125.218444 -429.689768) (xy 125.219137 -429.650641) (xy 125.230616 -429.573235) (xy 125.241304 -429.53559)
			(xy 125.241304 -429.018954) (xy 125.241772 -429.00684) (xy 125.249268 -428.983801) (xy 125.263512 -428.964203)
			(xy 125.283112 -428.949962) (xy 125.306152 -428.94247) (xy 125.318266 -428.941992) (xy 126.258066 -428.941992)
			(xy 126.270174 -428.94254) (xy 126.293209 -428.950012) (xy 126.312807 -428.964236) (xy 126.327051 -428.98382)
			(xy 126.334547 -429.006846) (xy 126.335028 -429.018954) (xy 126.335028 -431.560478) (xy 126.334621 -431.572603)
			(xy 126.32713 -431.595667) (xy 126.312877 -431.615285) (xy 126.293256 -431.629536) (xy 126.270191 -431.637023)
			(xy 126.258066 -431.63744) (xy 125.318266 -431.63744) (xy 125.306147 -431.637017) (xy 125.283099 -431.629518)
			(xy 125.263496 -431.615264) (xy 125.249257 -431.59565) (xy 125.241774 -431.572597) (xy 125.241304 -431.560478)
			(xy 125.241304 -431.044096) (xy 125.23062 -431.00645) (xy 125.219141 -430.929044) (xy 125.218444 -430.889918)
			(xy 115.614222 -430.889918) (xy 115.620833 -430.936605) (xy 115.636729 -431.105619) (xy 115.644686 -431.275192)
			(xy 115.645184 -431.360072) (xy 115.644698 -431.445674) (xy 115.63661 -431.616688) (xy 115.620446 -431.787128)
			(xy 115.605768 -431.889916) (xy 127.21844 -431.889916) (xy 127.218951 -431.85736) (xy 127.226895 -431.792736)
			(xy 127.242677 -431.729566) (xy 127.266062 -431.668799) (xy 127.296698 -431.611346) (xy 127.334127 -431.558068)
			(xy 127.377787 -431.509764) (xy 127.402082 -431.488088) (xy 127.482854 -431.323242) (xy 127.487581 -431.312736)
			(xy 127.491058 -431.289971) (xy 127.487563 -431.267209) (xy 127.482854 -431.256694) (xy 127.401828 -431.091594)
			(xy 127.377588 -431.069872) (xy 127.333989 -431.021545) (xy 127.296611 -430.968259) (xy 127.266014 -430.910811)
			(xy 127.242655 -430.850059) (xy 127.226883 -430.786911) (xy 127.218934 -430.72231) (xy 127.21844 -430.689766)
			(xy 127.219132 -430.650639) (xy 127.230612 -430.573233) (xy 127.2413 -430.535588) (xy 127.2413 -430.018952)
			(xy 127.241676 -430.006841) (xy 127.249188 -429.983812) (xy 127.26346 -429.96424) (xy 127.28309 -429.950047)
			(xy 127.306149 -429.942627) (xy 127.318262 -429.942244) (xy 128.258062 -429.942244) (xy 128.27015 -429.94274)
			(xy 128.29315 -429.950187) (xy 128.312731 -429.964366) (xy 128.326983 -429.983894) (xy 128.334515 -430.006866)
			(xy 128.335024 -430.018952) (xy 128.335024 -430.889918) (xy 129.218436 -430.889918) (xy 129.21895 -430.857362)
			(xy 129.226893 -430.792738) (xy 129.242675 -430.729569) (xy 129.26606 -430.668802) (xy 129.296696 -430.611349)
			(xy 129.334124 -430.55807) (xy 129.377783 -430.509766) (xy 129.402078 -430.48809) (xy 129.48285 -430.323244)
			(xy 129.487576 -430.312737) (xy 129.491054 -430.289973) (xy 129.487559 -430.267211) (xy 129.48285 -430.256696)
			(xy 129.401824 -430.091596) (xy 129.377585 -430.069874) (xy 129.333985 -430.021547) (xy 129.296608 -429.968261)
			(xy 129.266011 -429.910813) (xy 129.242652 -429.850061) (xy 129.22688 -429.786913) (xy 129.21893 -429.722312)
			(xy 129.218436 -429.689768) (xy 129.219129 -429.650642) (xy 129.230608 -429.573235) (xy 129.241296 -429.53559)
			(xy 129.241296 -429.018954) (xy 129.241772 -429.006841) (xy 129.249267 -428.983804) (xy 129.263509 -428.964206)
			(xy 129.283107 -428.949965) (xy 129.306145 -428.942471) (xy 129.318258 -428.941992) (xy 130.258058 -428.941992)
			(xy 130.270166 -428.942547) (xy 130.2932 -428.950017) (xy 130.312798 -428.964239) (xy 130.327043 -428.983821)
			(xy 130.334539 -429.006847) (xy 130.33502 -429.018954) (xy 130.33502 -431.560478) (xy 130.334621 -431.572604)
			(xy 130.327129 -431.595669) (xy 130.312874 -431.615288) (xy 130.293251 -431.629538) (xy 130.270184 -431.637024)
			(xy 130.258058 -431.63744) (xy 129.318258 -431.63744) (xy 129.306139 -431.637024) (xy 129.283091 -431.629522)
			(xy 129.263488 -431.615267) (xy 129.249248 -431.595652) (xy 129.241766 -431.572597) (xy 129.241296 -431.560478)
			(xy 129.241296 -431.044096) (xy 129.230612 -431.00645) (xy 129.219133 -430.929044) (xy 129.218436 -430.889918)
			(xy 128.335024 -430.889918) (xy 128.335024 -431.889916) (xy 131.218432 -431.889916) (xy 131.218945 -431.85736)
			(xy 131.226889 -431.792736) (xy 131.242671 -431.729567) (xy 131.266055 -431.6688) (xy 131.296691 -431.611346)
			(xy 131.334119 -431.558068) (xy 131.377779 -431.509764) (xy 131.402074 -431.488088) (xy 131.482846 -431.323242)
			(xy 131.487573 -431.312736) (xy 131.491051 -431.289971) (xy 131.487556 -431.267209) (xy 131.482846 -431.256694)
			(xy 131.40182 -431.091594) (xy 131.377579 -431.069874) (xy 131.333979 -431.021546) (xy 131.296602 -430.96826)
			(xy 131.266006 -430.910812) (xy 131.242647 -430.850059) (xy 131.226875 -430.786911) (xy 131.218926 -430.72231)
			(xy 131.218432 -430.689766) (xy 131.219125 -430.650639) (xy 131.230604 -430.573233) (xy 131.241292 -430.535588)
			(xy 131.241292 -430.018952) (xy 131.241675 -430.006841) (xy 131.249187 -429.983814) (xy 131.263458 -429.964242)
			(xy 131.283085 -429.950049) (xy 131.306142 -429.942628) (xy 131.318254 -429.942244) (xy 132.258054 -429.942244)
			(xy 132.270142 -429.942747) (xy 132.293141 -429.950191) (xy 132.312722 -429.964368) (xy 132.326974 -429.983895)
			(xy 132.334507 -430.006866) (xy 132.335016 -430.018952) (xy 132.335016 -430.889918) (xy 133.218428 -430.889918)
			(xy 133.218944 -430.857362) (xy 133.226887 -430.792738) (xy 133.242669 -430.729569) (xy 133.266053 -430.668802)
			(xy 133.296689 -430.611349) (xy 133.334116 -430.55807) (xy 133.377775 -430.509766) (xy 133.40207 -430.48809)
			(xy 133.482842 -430.323244) (xy 133.487568 -430.312737) (xy 133.491047 -430.289973) (xy 133.487552 -430.267211)
			(xy 133.482842 -430.256696) (xy 133.401816 -430.091596) (xy 133.377575 -430.069876) (xy 133.333976 -430.021548)
			(xy 133.296599 -429.968262) (xy 133.266002 -429.910813) (xy 133.242644 -429.850061) (xy 133.226872 -429.786913)
			(xy 133.218922 -429.722312) (xy 133.218428 -429.689768) (xy 133.219121 -429.650642) (xy 133.230601 -429.573235)
			(xy 133.241288 -429.53559) (xy 133.241288 -429.018954) (xy 133.241772 -429.006842) (xy 133.249266 -428.983806)
			(xy 133.263506 -428.964209) (xy 133.283102 -428.949967) (xy 133.306138 -428.942472) (xy 133.31825 -428.941992)
			(xy 134.25805 -428.941992) (xy 134.270163 -428.942468) (xy 134.2932 -428.949964) (xy 134.312797 -428.964206)
			(xy 134.327038 -428.983804) (xy 134.334532 -429.006841) (xy 134.335012 -429.018954) (xy 134.335012 -431.560478)
			(xy 134.33447 -431.572586) (xy 134.326995 -431.59562) (xy 134.312769 -431.615218) (xy 134.293185 -431.629462)
			(xy 134.270158 -431.636959) (xy 134.25805 -431.63744) (xy 133.31825 -431.63744) (xy 133.306131 -431.63703)
			(xy 133.283082 -431.629527) (xy 133.263479 -431.615269) (xy 133.24924 -431.595653) (xy 133.241758 -431.572598)
			(xy 133.241288 -431.560478) (xy 133.241288 -431.044096) (xy 133.230604 -431.00645) (xy 133.219125 -430.929044)
			(xy 133.218428 -430.889918) (xy 132.335016 -430.889918) (xy 132.335016 -431.889916) (xy 135.218424 -431.889916)
			(xy 135.21894 -431.857361) (xy 135.226883 -431.792736) (xy 135.242665 -431.729567) (xy 135.266049 -431.6688)
			(xy 135.296685 -431.611347) (xy 135.334112 -431.558069) (xy 135.377771 -431.509764) (xy 135.402066 -431.488088)
			(xy 135.482838 -431.323242) (xy 135.487566 -431.312736) (xy 135.491044 -431.289971) (xy 135.487548 -431.267209)
			(xy 135.482838 -431.256694) (xy 135.401812 -431.091594) (xy 135.377569 -431.069876) (xy 135.33397 -431.021548)
			(xy 135.296594 -430.968261) (xy 135.265997 -430.910812) (xy 135.242639 -430.85006) (xy 135.226867 -430.786911)
			(xy 135.218918 -430.72231) (xy 135.218424 -430.689766) (xy 135.219117 -430.65064) (xy 135.230596 -430.573233)
			(xy 135.241284 -430.535588) (xy 135.241284 -430.018952) (xy 135.241675 -430.006842) (xy 135.249186 -429.983816)
			(xy 135.263455 -429.964245) (xy 135.28308 -429.950052) (xy 135.306135 -429.942629) (xy 135.318246 -429.942244)
			(xy 136.258046 -429.942244) (xy 136.270138 -429.942668) (xy 136.293141 -429.950138) (xy 136.312721 -429.964336)
			(xy 136.32697 -429.983878) (xy 136.3345 -430.006861) (xy 136.335008 -430.018952) (xy 136.335008 -430.889918)
			(xy 137.21842 -430.889918) (xy 137.218939 -430.857363) (xy 137.226882 -430.792738) (xy 137.242663 -430.729569)
			(xy 137.266047 -430.668803) (xy 137.296682 -430.611349) (xy 137.334109 -430.558071) (xy 137.377767 -430.509766)
			(xy 137.402062 -430.48809) (xy 137.482834 -430.323244) (xy 137.48756 -430.312737) (xy 137.49104 -430.289973)
			(xy 137.487544 -430.267211) (xy 137.482834 -430.256696) (xy 137.401808 -430.091596) (xy 137.377565 -430.069878)
			(xy 137.333967 -430.021549) (xy 137.29659 -429.968263) (xy 137.265994 -429.910814) (xy 137.242635 -429.850062)
			(xy 137.226864 -429.786913) (xy 137.218914 -429.722312) (xy 137.21842 -429.689768) (xy 137.219114 -429.650642)
			(xy 137.230593 -429.573235) (xy 137.24128 -429.53559) (xy 137.24128 -429.018954) (xy 137.241673 -429.006833)
			(xy 137.249178 -428.983781) (xy 137.263439 -428.964176) (xy 137.28306 -428.949938) (xy 137.30612 -428.942459)
			(xy 137.318242 -428.941992) (xy 138.258042 -428.941992) (xy 138.270154 -428.942475) (xy 138.293191 -428.949968)
			(xy 138.312788 -428.964209) (xy 138.32703 -428.983805) (xy 138.334524 -429.006842) (xy 138.335004 -429.018954)
			(xy 138.335004 -431.560478) (xy 138.33447 -431.572587) (xy 138.326994 -431.595623) (xy 138.312767 -431.615221)
			(xy 138.29318 -431.629465) (xy 138.270151 -431.63696) (xy 138.258042 -431.63744) (xy 137.318242 -431.63744)
			(xy 137.306119 -431.637004) (xy 137.283058 -431.629521) (xy 137.26344 -431.615274) (xy 137.249188 -431.59566)
			(xy 137.241699 -431.572601) (xy 137.24128 -431.560478) (xy 137.24128 -431.044096) (xy 137.230596 -431.00645)
			(xy 137.219117 -430.929044) (xy 137.21842 -430.889918) (xy 136.335008 -430.889918) (xy 136.335008 -431.889916)
			(xy 139.218416 -431.889916) (xy 139.218935 -431.857361) (xy 139.226878 -431.792736) (xy 139.24266 -431.729568)
			(xy 139.266043 -431.668801) (xy 139.296678 -431.611348) (xy 139.334105 -431.558069) (xy 139.377763 -431.509764)
			(xy 139.402058 -431.488088) (xy 139.48283 -431.323242) (xy 139.487558 -431.312736) (xy 139.491037 -431.289971)
			(xy 139.487541 -431.267209) (xy 139.48283 -431.256694) (xy 139.401804 -431.091594) (xy 139.37756 -431.069878)
			(xy 139.333961 -431.021549) (xy 139.296585 -430.968262) (xy 139.265989 -430.910813) (xy 139.242631 -430.85006)
			(xy 139.226859 -430.786911) (xy 139.21891 -430.72231) (xy 139.218416 -430.689766) (xy 139.219105 -430.650639)
			(xy 139.230587 -430.573233) (xy 139.241276 -430.535588) (xy 139.241276 -430.018952) (xy 139.241675 -430.006843)
			(xy 139.249185 -429.983818) (xy 139.263452 -429.964248) (xy 139.283075 -429.950054) (xy 139.306128 -429.94263)
			(xy 139.318238 -429.942244) (xy 140.258038 -429.942244) (xy 140.27013 -429.942675) (xy 140.293133 -429.950143)
			(xy 140.312712 -429.964338) (xy 140.326961 -429.983879) (xy 140.334492 -430.006861) (xy 140.335 -430.018952)
			(xy 140.335 -430.889918) (xy 142.21841 -430.889918) (xy 142.218932 -430.857363) (xy 142.226875 -430.792739)
			(xy 142.242656 -430.72957) (xy 142.26604 -430.668803) (xy 142.296674 -430.61135) (xy 142.3341 -430.558071)
			(xy 142.377758 -430.509766) (xy 142.402052 -430.48809) (xy 142.482824 -430.323244) (xy 142.487551 -430.312738)
			(xy 142.491031 -430.289973) (xy 142.487535 -430.267211) (xy 142.482824 -430.256696) (xy 142.401798 -430.091596)
			(xy 142.377553 -430.06988) (xy 142.333955 -430.021551) (xy 142.296579 -429.968264) (xy 142.265983 -429.910815)
			(xy 142.242625 -429.850062) (xy 142.226853 -429.786913) (xy 142.218904 -429.722312) (xy 142.21841 -429.689768)
			(xy 142.219138 -429.650443) (xy 142.230742 -429.572653) (xy 142.241524 -429.534828) (xy 142.241524 -429.018954)
			(xy 142.241968 -429.006864) (xy 142.249435 -428.983864) (xy 142.263628 -428.964286) (xy 142.283165 -428.950037)
			(xy 142.306143 -428.942503) (xy 142.318232 -428.941992) (xy 143.258032 -428.941992) (xy 143.270142 -428.942389)
			(xy 143.293169 -428.949896) (xy 143.312741 -428.964163) (xy 143.326934 -428.983788) (xy 143.334356 -429.006843)
			(xy 143.33474 -429.018954) (xy 143.33474 -431.560478) (xy 143.334273 -431.572568) (xy 143.32682 -431.595572)
			(xy 143.312634 -431.615154) (xy 143.293099 -431.629404) (xy 143.270121 -431.636933) (xy 143.258032 -431.63744)
			(xy 142.318232 -431.63744) (xy 142.306129 -431.636957) (xy 142.283109 -431.629471) (xy 142.263539 -431.615225)
			(xy 142.249342 -431.59562) (xy 142.241913 -431.572582) (xy 142.241524 -431.560478) (xy 142.241524 -431.044858)
			(xy 142.230729 -431.007035) (xy 142.21912 -430.929244) (xy 142.21841 -430.889918) (xy 140.335 -430.889918)
			(xy 140.335 -431.889916) (xy 144.218406 -431.889916) (xy 144.218928 -431.857361) (xy 144.226871 -431.792737)
			(xy 144.242653 -431.729568) (xy 144.266036 -431.668802) (xy 144.29667 -431.611348) (xy 144.334097 -431.55807)
			(xy 144.377754 -431.509764) (xy 144.402048 -431.488088) (xy 144.48282 -431.323242) (xy 144.487549 -431.312736)
			(xy 144.491028 -431.289971) (xy 144.487531 -431.267209) (xy 144.48282 -431.256694) (xy 144.401794 -431.091594)
			(xy 144.377548 -431.06988) (xy 144.33395 -431.02155) (xy 144.296574 -430.968263) (xy 144.265978 -430.910813)
			(xy 144.24262 -430.85006) (xy 144.226849 -430.786912) (xy 144.2189 -430.72231) (xy 144.218406 -430.689766)
			(xy 144.219133 -430.650441) (xy 144.230738 -430.572651) (xy 144.24152 -430.534826) (xy 144.24152 -430.018952)
			(xy 144.241924 -430.006872) (xy 144.249403 -429.983899) (xy 144.263614 -429.96436) (xy 144.283167 -429.950168)
			(xy 144.306148 -429.942712) (xy 144.318228 -429.942244) (xy 145.258028 -429.942244) (xy 145.270099 -429.942739)
			(xy 145.293059 -429.950204) (xy 145.312592 -429.964394) (xy 145.326787 -429.983923) (xy 145.334258 -430.006881)
			(xy 145.334736 -430.018952) (xy 145.334736 -430.889918) (xy 146.218402 -430.889918) (xy 146.218927 -430.857363)
			(xy 146.22687 -430.792739) (xy 146.242651 -430.72957) (xy 146.266034 -430.668804) (xy 146.296668 -430.611351)
			(xy 146.334093 -430.558072) (xy 146.37775 -430.509766) (xy 146.402044 -430.48809) (xy 146.482816 -430.323244)
			(xy 146.487543 -430.312738) (xy 146.491023 -430.289973) (xy 146.487527 -430.267211) (xy 146.482816 -430.256696)
			(xy 146.40179 -430.091596) (xy 146.377544 -430.069882) (xy 146.333946 -430.021552) (xy 146.29657 -429.968265)
			(xy 146.265975 -429.910815) (xy 146.242617 -429.850062) (xy 146.226845 -429.786913) (xy 146.218896 -429.722312)
			(xy 146.218402 -429.689768) (xy 146.21913 -429.650443) (xy 146.230734 -429.572653) (xy 146.241516 -429.534828)
			(xy 146.241516 -429.018954) (xy 146.241968 -429.006864) (xy 146.249434 -428.983866) (xy 146.263626 -428.964289)
			(xy 146.28316 -428.950039) (xy 146.306136 -428.942504) (xy 146.318224 -428.941992) (xy 147.258024 -428.941992)
			(xy 147.270133 -428.942396) (xy 147.29316 -428.949901) (xy 147.312732 -428.964166) (xy 147.326926 -428.983789)
			(xy 147.334348 -429.006843) (xy 147.334732 -429.018954) (xy 147.334732 -431.560478) (xy 147.334273 -431.572569)
			(xy 147.326819 -431.595574) (xy 147.312632 -431.615156) (xy 147.293094 -431.629407) (xy 147.270114 -431.636934)
			(xy 147.258024 -431.63744) (xy 146.318224 -431.63744) (xy 146.30612 -431.636964) (xy 146.283101 -431.629476)
			(xy 146.263531 -431.615228) (xy 146.249334 -431.595622) (xy 146.241905 -431.572583) (xy 146.241516 -431.560478)
			(xy 146.241516 -431.044858) (xy 146.230721 -431.007035) (xy 146.219112 -430.929244) (xy 146.218402 -430.889918)
			(xy 145.334736 -430.889918) (xy 145.334736 -431.889916) (xy 148.218398 -431.889916) (xy 148.218923 -431.857361)
			(xy 148.226866 -431.792737) (xy 148.242647 -431.729569) (xy 148.26603 -431.668802) (xy 148.296664 -431.611349)
			(xy 148.334089 -431.55807) (xy 148.377746 -431.509764) (xy 148.40204 -431.488088) (xy 148.482812 -431.323242)
			(xy 148.487541 -431.312736) (xy 148.491021 -431.289971) (xy 148.487524 -431.267209) (xy 148.482812 -431.256694)
			(xy 148.401786 -431.091594) (xy 148.377538 -431.069882) (xy 148.33394 -431.021552) (xy 148.296565 -430.968264)
			(xy 148.26597 -430.910814) (xy 148.242612 -430.850061) (xy 148.226841 -430.786912) (xy 148.218892 -430.72231)
			(xy 148.218398 -430.689766) (xy 148.219126 -430.650441) (xy 148.23073 -430.572651) (xy 148.241512 -430.534826)
			(xy 148.241512 -430.018952) (xy 148.241924 -430.006873) (xy 148.249402 -429.983901) (xy 148.263611 -429.964363)
			(xy 148.283162 -429.950171) (xy 148.306141 -429.942713) (xy 148.31822 -429.942244) (xy 149.25802 -429.942244)
			(xy 149.270091 -429.942747) (xy 149.29305 -429.950209) (xy 149.312583 -429.964397) (xy 149.326778 -429.983924)
			(xy 149.334249 -430.006881) (xy 149.334728 -430.018952) (xy 149.334728 -430.889918) (xy 150.218394 -430.889918)
			(xy 150.218888 -430.857362) (xy 150.226832 -430.792736) (xy 150.242616 -430.729565) (xy 150.266003 -430.668798)
			(xy 150.296643 -430.611344) (xy 150.334075 -430.558067) (xy 150.377739 -430.509765) (xy 150.402036 -430.48809)
			(xy 150.482808 -430.323244) (xy 150.487536 -430.312738) (xy 150.491016 -430.289973) (xy 150.48752 -430.26721)
			(xy 150.482808 -430.256696) (xy 150.401782 -430.091596) (xy 150.377534 -430.069883) (xy 150.333937 -430.021553)
			(xy 150.296561 -429.968266) (xy 150.265966 -429.910816) (xy 150.242608 -429.850063) (xy 150.226837 -429.786914)
			(xy 150.218888 -429.722312) (xy 150.218394 -429.689768) (xy 150.219122 -429.650443) (xy 150.230727 -429.572653)
			(xy 150.241508 -429.534828) (xy 150.241508 -429.018954) (xy 150.241968 -429.006865) (xy 150.249433 -428.983868)
			(xy 150.263623 -428.964292) (xy 150.283155 -428.950042) (xy 150.306129 -428.942505) (xy 150.318216 -428.941992)
			(xy 151.258016 -428.941992) (xy 151.270125 -428.942402) (xy 151.293151 -428.949905) (xy 151.312724 -428.964169)
			(xy 151.326918 -428.983791) (xy 151.33434 -429.006844) (xy 151.334724 -429.018954) (xy 151.334724 -431.560478)
			(xy 151.334273 -431.57257) (xy 151.326818 -431.595576) (xy 151.312629 -431.615159) (xy 151.293089 -431.629409)
			(xy 151.270106 -431.636935) (xy 151.258016 -431.63744) (xy 150.318216 -431.63744) (xy 150.306112 -431.63697)
			(xy 150.283092 -431.62948) (xy 150.263522 -431.615231) (xy 150.249326 -431.595623) (xy 150.241897 -431.572583)
			(xy 150.241508 -431.560478) (xy 150.241508 -431.044858) (xy 150.230713 -431.007035) (xy 150.219104 -430.929244)
			(xy 150.218394 -430.889918) (xy 149.334728 -430.889918) (xy 149.334728 -431.889916) (xy 152.21839 -431.889916)
			(xy 152.218884 -431.85736) (xy 152.226828 -431.792734) (xy 152.242612 -431.729563) (xy 152.266 -431.668796)
			(xy 152.296639 -431.611343) (xy 152.334071 -431.558065) (xy 152.377735 -431.509763) (xy 152.402032 -431.488088)
			(xy 152.482804 -431.323242) (xy 152.487534 -431.312736) (xy 152.491014 -431.289971) (xy 152.487516 -431.267208)
			(xy 152.482804 -431.256694) (xy 152.401778 -431.091594) (xy 152.377528 -431.069883) (xy 152.333931 -431.021553)
			(xy 152.296556 -430.968265) (xy 152.265961 -430.910815) (xy 152.242604 -430.850061) (xy 152.226833 -430.786912)
			(xy 152.218884 -430.72231) (xy 152.21839 -430.689766) (xy 152.219118 -430.650441) (xy 152.230722 -430.572651)
			(xy 152.241504 -430.534826) (xy 152.241504 -430.018952) (xy 152.241923 -430.006874) (xy 152.249401 -429.983903)
			(xy 152.263608 -429.964366) (xy 152.283157 -429.950173) (xy 152.306133 -429.942714) (xy 152.318212 -429.942244)
			(xy 153.258012 -429.942244) (xy 153.270082 -429.942753) (xy 153.293042 -429.950213) (xy 153.312574 -429.9644)
			(xy 153.32677 -429.983926) (xy 153.334241 -430.006882) (xy 153.33472 -430.018952) (xy 153.33472 -430.889918)
			(xy 154.218386 -430.889918) (xy 154.218882 -430.857362) (xy 154.226827 -430.792736) (xy 154.24261 -430.729566)
			(xy 154.265997 -430.668798) (xy 154.296636 -430.611345) (xy 154.334068 -430.558067) (xy 154.377731 -430.509765)
			(xy 154.402028 -430.48809) (xy 154.4828 -430.323244) (xy 154.487528 -430.312738) (xy 154.491009 -430.289973)
			(xy 154.487512 -430.26721) (xy 154.4828 -430.256696) (xy 154.401774 -430.091596) (xy 154.377524 -430.069885)
			(xy 154.333927 -430.021555) (xy 154.296552 -429.968266) (xy 154.265957 -429.910816) (xy 154.2426 -429.850063)
			(xy 154.226829 -429.786914) (xy 154.21888 -429.722312) (xy 154.218386 -429.689768) (xy 154.219115 -429.650443)
			(xy 154.230719 -429.572653) (xy 154.2415 -429.534828) (xy 154.2415 -429.018954) (xy 154.241967 -429.006866)
			(xy 154.249432 -428.983871) (xy 154.26362 -428.964295) (xy 154.28315 -428.950044) (xy 154.306122 -428.942507)
			(xy 154.318208 -428.941992) (xy 155.258008 -428.941992) (xy 155.270117 -428.942409) (xy 155.293143 -428.94991)
			(xy 155.312715 -428.964172) (xy 155.32691 -428.983792) (xy 155.334332 -429.006844) (xy 155.334716 -429.018954)
			(xy 155.334716 -431.560478) (xy 155.334273 -431.572571) (xy 155.326817 -431.595578) (xy 155.312626 -431.615162)
			(xy 155.293084 -431.629412) (xy 155.270099 -431.636937) (xy 155.258008 -431.63744) (xy 154.318208 -431.63744)
			(xy 154.306104 -431.636978) (xy 154.283083 -431.629485) (xy 154.263513 -431.615234) (xy 154.249317 -431.595625)
			(xy 154.241889 -431.572584) (xy 154.2415 -431.560478) (xy 154.2415 -431.044858) (xy 154.230705 -431.007035)
			(xy 154.219096 -430.929244) (xy 154.218386 -430.889918) (xy 153.33472 -430.889918) (xy 153.33472 -431.889916)
			(xy 156.218382 -431.889916) (xy 156.218878 -431.85736) (xy 156.226823 -431.792734) (xy 156.242607 -431.729564)
			(xy 156.265994 -431.668796) (xy 156.296632 -431.611343) (xy 156.334064 -431.558066) (xy 156.377727 -431.509763)
			(xy 156.402024 -431.488088) (xy 156.482796 -431.323242) (xy 156.487526 -431.312737) (xy 156.491006 -431.289971)
			(xy 156.487509 -431.267208) (xy 156.482796 -431.256694) (xy 156.40177 -431.091594) (xy 156.377539 -431.069863)
			(xy 156.333937 -431.021538) (xy 156.296558 -430.968255) (xy 156.265959 -430.910808) (xy 156.242599 -430.850057)
			(xy 156.226826 -430.78691) (xy 156.218876 -430.72231) (xy 156.218382 -430.689766) (xy 156.21911 -430.650441)
			(xy 156.230715 -430.572651) (xy 156.241496 -430.534826) (xy 156.241496 -430.018952) (xy 156.241923 -430.006875)
			(xy 156.249399 -429.983905) (xy 156.263605 -429.964368) (xy 156.283152 -429.950176) (xy 156.306126 -429.942715)
			(xy 156.318204 -429.942244) (xy 157.258004 -429.942244) (xy 157.270074 -429.94276) (xy 157.293033 -429.950218)
			(xy 157.312566 -429.964403) (xy 157.326762 -429.983927) (xy 157.334233 -430.006882) (xy 157.334712 -430.018952)
			(xy 157.334712 -432.560476) (xy 157.334267 -432.572557) (xy 157.326806 -432.595538) (xy 157.312609 -432.615089)
			(xy 157.293063 -432.629294) (xy 157.270085 -432.636762) (xy 157.258004 -432.637184) (xy 156.318204 -432.637184)
			(xy 156.306119 -432.636784) (xy 156.283132 -432.629314) (xy 156.26358 -432.615106) (xy 156.249376 -432.59555)
			(xy 156.241913 -432.572561) (xy 156.241496 -432.560476) (xy 156.241496 -432.044856) (xy 156.2307 -432.007034)
			(xy 156.219091 -431.929242) (xy 156.218382 -431.889916) (xy 153.33472 -431.889916) (xy 153.33472 -432.560476)
			(xy 153.334267 -432.572556) (xy 153.326807 -432.595536) (xy 153.312611 -432.615086) (xy 153.293068 -432.629291)
			(xy 153.270092 -432.636761) (xy 153.258012 -432.637184) (xy 152.318212 -432.637184) (xy 152.306128 -432.636777)
			(xy 152.283141 -432.629309) (xy 152.263589 -432.615103) (xy 152.249385 -432.595548) (xy 152.241922 -432.572561)
			(xy 152.241504 -432.560476) (xy 152.241504 -432.044856) (xy 152.230708 -432.007034) (xy 152.219099 -431.929242)
			(xy 152.21839 -431.889916) (xy 149.334728 -431.889916) (xy 149.334728 -432.560476) (xy 149.334267 -432.572555)
			(xy 149.326809 -432.595534) (xy 149.312614 -432.615083) (xy 149.293073 -432.629288) (xy 149.270099 -432.63676)
			(xy 149.25802 -432.637184) (xy 148.31822 -432.637184) (xy 148.306136 -432.63677) (xy 148.28315 -432.629305)
			(xy 148.263597 -432.6151) (xy 148.249393 -432.595547) (xy 148.24193 -432.57256) (xy 148.241512 -432.560476)
			(xy 148.241512 -432.044856) (xy 148.230717 -432.007033) (xy 148.219107 -431.929242) (xy 148.218398 -431.889916)
			(xy 145.334736 -431.889916) (xy 145.334736 -432.560476) (xy 145.334216 -432.572547) (xy 145.326763 -432.595508)
			(xy 145.31258 -432.615043) (xy 145.293055 -432.62924) (xy 145.270098 -432.636708) (xy 145.258028 -432.637184)
			(xy 144.318228 -432.637184) (xy 144.306144 -432.636763) (xy 144.283159 -432.6293) (xy 144.263606 -432.615097)
			(xy 144.249402 -432.595545) (xy 144.241938 -432.57256) (xy 144.24152 -432.560476) (xy 144.24152 -432.044856)
			(xy 144.230725 -432.007033) (xy 144.219115 -431.929242) (xy 144.218406 -431.889916) (xy 140.335 -431.889916)
			(xy 140.335 -432.560476) (xy 140.334563 -432.572584) (xy 140.32707 -432.59561) (xy 140.312814 -432.615184)
			(xy 140.293196 -432.629379) (xy 140.270147 -432.6368) (xy 140.258038 -432.637184) (xy 139.318238 -432.637184)
			(xy 139.306153 -432.636661) (xy 139.283157 -432.629217) (xy 139.263579 -432.615044) (xy 139.249326 -432.595524)
			(xy 139.241789 -432.572559) (xy 139.241276 -432.560476) (xy 139.241276 -432.044094) (xy 139.230591 -432.006448)
			(xy 139.219113 -431.929042) (xy 139.218416 -431.889916) (xy 136.335008 -431.889916) (xy 136.335008 -432.560476)
			(xy 136.334563 -432.572583) (xy 136.327071 -432.595608) (xy 136.312817 -432.615181) (xy 136.293201 -432.629376)
			(xy 136.270154 -432.636799) (xy 136.258046 -432.637184) (xy 135.318246 -432.637184) (xy 135.306161 -432.636654)
			(xy 135.283166 -432.629213) (xy 135.263587 -432.615042) (xy 135.249334 -432.595522) (xy 135.241797 -432.572559)
			(xy 135.241284 -432.560476) (xy 135.241284 -432.044094) (xy 135.230599 -432.006448) (xy 135.219121 -431.929042)
			(xy 135.218424 -431.889916) (xy 132.335016 -431.889916) (xy 132.335016 -432.560476) (xy 132.334563 -432.572582)
			(xy 132.327072 -432.595606) (xy 132.31282 -432.615178) (xy 132.293206 -432.629374) (xy 132.270161 -432.636798)
			(xy 132.258054 -432.637184) (xy 131.318254 -432.637184) (xy 131.306164 -432.636732) (xy 131.283166 -432.629266)
			(xy 131.263589 -432.615074) (xy 131.249339 -432.59554) (xy 131.241804 -432.572564) (xy 131.241292 -432.560476)
			(xy 131.241292 -432.044094) (xy 131.230608 -432.006448) (xy 131.219129 -431.929042) (xy 131.218432 -431.889916)
			(xy 128.335024 -431.889916) (xy 128.335024 -432.560476) (xy 128.334563 -432.572581) (xy 128.327074 -432.595604)
			(xy 128.312823 -432.615175) (xy 128.293212 -432.629371) (xy 128.270168 -432.636797) (xy 128.258062 -432.637184)
			(xy 127.318262 -432.637184) (xy 127.306173 -432.636726) (xy 127.283175 -432.629261) (xy 127.263598 -432.615072)
			(xy 127.249348 -432.595538) (xy 127.241812 -432.572564) (xy 127.2413 -432.560476) (xy 127.2413 -432.044094)
			(xy 127.230616 -432.006448) (xy 127.219137 -431.929042) (xy 127.21844 -431.889916) (xy 115.605768 -431.889916)
			(xy 115.596243 -431.956613) (xy 115.564055 -432.124765) (xy 115.523953 -432.291207) (xy 115.476027 -432.455567)
			(xy 115.420385 -432.617477) (xy 115.35715 -432.776576) (xy 115.286464 -432.932508) (xy 115.208486 -433.084923)
			(xy 115.12339 -433.233482) (xy 115.031365 -433.377851) (xy 114.932619 -433.517709) (xy 114.82737 -433.652742)
			(xy 114.715856 -433.782648) (xy 114.598325 -433.907137) (xy 114.47504 -434.02593) (xy 114.346277 -434.138763)
			(xy 114.212324 -434.245381) (xy 114.07348 -434.345548) (xy 113.930056 -434.439039) (xy 113.843394 -434.48986)
			(xy 125.238002 -434.48986) (xy 125.2381 -434.475286) (xy 125.239749 -434.446185) (xy 125.241304 -434.431694)
			(xy 125.241304 -433.34813) (xy 125.239756 -433.333638) (xy 125.238106 -433.304538) (xy 125.238002 -433.289964)
			(xy 125.2381 -433.27539) (xy 125.239749 -433.246289) (xy 125.241304 -433.231798) (xy 125.241304 -432.618896)
			(xy 125.241713 -432.606787) (xy 125.249214 -432.583758) (xy 125.263477 -432.564185) (xy 125.283101 -432.549991)
			(xy 125.306155 -432.542571) (xy 125.318266 -432.542188) (xy 126.258066 -432.542188) (xy 126.270159 -432.542637)
			(xy 126.293166 -432.55009) (xy 126.312751 -432.56428) (xy 126.327001 -432.583821) (xy 126.334525 -432.606805)
			(xy 126.335028 -432.618896) (xy 126.335028 -435.16042) (xy 126.334601 -435.172527) (xy 126.3271 -435.19555)
			(xy 126.31284 -435.215121) (xy 126.293222 -435.229316) (xy 126.270174 -435.236741) (xy 126.258066 -435.237128)
			(xy 125.318266 -435.237128) (xy 125.306171 -435.236721) (xy 125.283164 -435.229251) (xy 125.263582 -435.21505)
			(xy 125.249334 -435.195502) (xy 125.241808 -435.172513) (xy 125.241304 -435.16042) (xy 125.241304 -434.548026)
			(xy 125.239756 -434.533534) (xy 125.238106 -434.504434) (xy 125.238002 -434.48986) (xy 113.843394 -434.48986)
			(xy 113.782372 -434.525645) (xy 113.630759 -434.605172) (xy 113.475556 -434.677443) (xy 113.396522 -434.710332)
			(xy 113.382851 -434.716444) (xy 113.359598 -434.735293) (xy 113.342813 -434.760077) (xy 113.333939 -434.788665)
			(xy 113.333741 -434.818598) (xy 113.342235 -434.847301) (xy 113.358691 -434.872305) (xy 113.369852 -434.88229)
			(xy 113.419298 -434.924299) (xy 113.513487 -435.013553) (xy 113.601975 -435.108462) (xy 113.684422 -435.208663)
			(xy 113.760513 -435.313772) (xy 113.829956 -435.423387) (xy 113.866512 -435.489858) (xy 127.237998 -435.489858)
			(xy 127.238095 -435.475284) (xy 127.239745 -435.446183) (xy 127.2413 -435.431692) (xy 127.2413 -434.348128)
			(xy 127.239752 -434.333636) (xy 127.238102 -434.304536) (xy 127.237998 -434.289962) (xy 127.238096 -434.275388)
			(xy 127.239745 -434.246287) (xy 127.2413 -434.231796) (xy 127.2413 -433.618894) (xy 127.241806 -433.606783)
			(xy 127.24929 -433.583746) (xy 127.263525 -433.564148) (xy 127.283117 -433.549905) (xy 127.306151 -433.542411)
			(xy 127.318262 -433.541932) (xy 128.258062 -433.541932) (xy 128.270182 -433.542392) (xy 128.293239 -433.549873)
			(xy 128.312854 -433.564115) (xy 128.327107 -433.583722) (xy 128.334601 -433.606774) (xy 128.335024 -433.618894)
			(xy 128.335024 -434.48986) (xy 129.237994 -434.48986) (xy 129.238092 -434.475286) (xy 129.239741 -434.446185)
			(xy 129.241296 -434.431694) (xy 129.241296 -433.34813) (xy 129.239748 -433.333638) (xy 129.238098 -433.304538)
			(xy 129.237994 -433.289964) (xy 129.238092 -433.27539) (xy 129.239741 -433.246289) (xy 129.241296 -433.231798)
			(xy 129.241296 -432.618896) (xy 129.241713 -432.606787) (xy 129.249213 -432.583761) (xy 129.263474 -432.564188)
			(xy 129.283096 -432.549993) (xy 129.306148 -432.542572) (xy 129.318258 -432.542188) (xy 130.258058 -432.542188)
			(xy 130.27015 -432.542644) (xy 130.293158 -432.550095) (xy 130.312742 -432.564283) (xy 130.326993 -432.583822)
			(xy 130.334517 -432.606805) (xy 130.33502 -432.618896) (xy 130.33502 -435.16042) (xy 130.334601 -435.172528)
			(xy 130.327099 -435.195552) (xy 130.312837 -435.215123) (xy 130.293217 -435.229318) (xy 130.270167 -435.236742)
			(xy 130.258058 -435.237128) (xy 129.318258 -435.237128) (xy 129.306163 -435.236728) (xy 129.283156 -435.229256)
			(xy 129.263574 -435.215053) (xy 129.249326 -435.195504) (xy 129.2418 -435.172514) (xy 129.241296 -435.16042)
			(xy 129.241296 -434.548026) (xy 129.239748 -434.533534) (xy 129.238098 -434.504434) (xy 129.237994 -434.48986)
			(xy 128.335024 -434.48986) (xy 128.335024 -435.489858) (xy 131.23799 -435.489858) (xy 131.238087 -435.475284)
			(xy 131.239737 -435.446183) (xy 131.241292 -435.431692) (xy 131.241292 -434.348128) (xy 131.239744 -434.333636)
			(xy 131.238094 -434.304536) (xy 131.23799 -434.289962) (xy 131.238088 -434.275388) (xy 131.239737 -434.246287)
			(xy 131.241292 -434.231796) (xy 131.241292 -433.618894) (xy 131.241806 -433.606784) (xy 131.249289 -433.583748)
			(xy 131.263522 -433.564151) (xy 131.283112 -433.549908) (xy 131.306144 -433.542412) (xy 131.318254 -433.541932)
			(xy 132.258054 -433.541932) (xy 132.270174 -433.542399) (xy 132.29323 -433.549878) (xy 132.312846 -433.564117)
			(xy 132.327098 -433.583723) (xy 132.334593 -433.606775) (xy 132.335016 -433.618894) (xy 132.335016 -434.48986)
			(xy 133.237986 -434.48986) (xy 133.238084 -434.475286) (xy 133.239733 -434.446185) (xy 133.241288 -434.431694)
			(xy 133.241288 -433.34813) (xy 133.23974 -433.333638) (xy 133.23809 -433.304538) (xy 133.237986 -433.289964)
			(xy 133.238084 -433.27539) (xy 133.239733 -433.246289) (xy 133.241288 -433.231798) (xy 133.241288 -432.618896)
			(xy 133.241713 -432.606788) (xy 133.249212 -432.583763) (xy 133.263472 -432.564191) (xy 133.283091 -432.549996)
			(xy 133.306141 -432.542573) (xy 133.31825 -432.542188) (xy 134.25805 -432.542188) (xy 134.270142 -432.542651)
			(xy 134.293149 -432.5501) (xy 134.312734 -432.564285) (xy 134.326984 -432.583823) (xy 134.334509 -432.606806)
			(xy 134.335012 -432.618896) (xy 134.335012 -435.16042) (xy 134.334601 -435.172529) (xy 134.327097 -435.195555)
			(xy 134.312834 -435.215126) (xy 134.293212 -435.229321) (xy 134.27016 -435.236743) (xy 134.25805 -435.237128)
			(xy 133.31825 -435.237128) (xy 133.30616 -435.23665) (xy 133.283155 -435.229203) (xy 133.263572 -435.21502)
			(xy 133.249321 -435.195487) (xy 133.241793 -435.172508) (xy 133.241288 -435.16042) (xy 133.241288 -434.548026)
			(xy 133.23974 -434.533534) (xy 133.23809 -434.504434) (xy 133.237986 -434.48986) (xy 132.335016 -434.48986)
			(xy 132.335016 -435.489858) (xy 135.237982 -435.489858) (xy 135.238079 -435.475284) (xy 135.239729 -435.446183)
			(xy 135.241284 -435.431692) (xy 135.241284 -434.348128) (xy 135.239736 -434.333636) (xy 135.238086 -434.304536)
			(xy 135.237982 -434.289962) (xy 135.23808 -434.275388) (xy 135.239729 -434.246287) (xy 135.241284 -434.231796)
			(xy 135.241284 -433.618894) (xy 135.241656 -433.606766) (xy 135.249155 -433.5837) (xy 135.263418 -433.564081)
			(xy 135.283046 -433.549831) (xy 135.306118 -433.542348) (xy 135.318246 -433.541932) (xy 136.258046 -433.541932)
			(xy 136.270162 -433.542372) (xy 136.293206 -433.549872) (xy 136.312807 -433.564122) (xy 136.327047 -433.58373)
			(xy 136.334534 -433.606777) (xy 136.335008 -433.618894) (xy 136.335008 -434.48986) (xy 137.237978 -434.48986)
			(xy 137.238076 -434.475286) (xy 137.239725 -434.446185) (xy 137.24128 -434.431694) (xy 137.24128 -433.34813)
			(xy 137.239732 -433.333638) (xy 137.238082 -433.304538) (xy 137.237978 -433.289964) (xy 137.238076 -433.27539)
			(xy 137.239726 -433.246289) (xy 137.24128 -433.231798) (xy 137.24128 -432.618896) (xy 137.241712 -432.606789)
			(xy 137.249211 -432.583765) (xy 137.263469 -432.564194) (xy 137.283086 -432.549998) (xy 137.306134 -432.542574)
			(xy 137.318242 -432.542188) (xy 138.258042 -432.542188) (xy 138.270139 -432.542572) (xy 138.293149 -432.550047)
			(xy 138.312732 -432.564253) (xy 138.326979 -432.583806) (xy 138.334502 -432.606801) (xy 138.335004 -432.618896)
			(xy 138.335004 -435.16042) (xy 138.334601 -435.17253) (xy 138.327096 -435.195557) (xy 138.312831 -435.215129)
			(xy 138.293207 -435.229323) (xy 138.270153 -435.236744) (xy 138.258042 -435.237128) (xy 137.318242 -435.237128)
			(xy 137.306151 -435.236656) (xy 137.283147 -435.229207) (xy 137.263563 -435.215023) (xy 137.249313 -435.195488)
			(xy 137.241785 -435.172509) (xy 137.24128 -435.16042) (xy 137.24128 -434.548026) (xy 137.239732 -434.533534)
			(xy 137.238082 -434.504434) (xy 137.237978 -434.48986) (xy 136.335008 -434.48986) (xy 136.335008 -435.489858)
			(xy 139.237974 -435.489858) (xy 139.238072 -435.475284) (xy 139.239721 -435.446183) (xy 139.241276 -435.431692)
			(xy 139.241276 -434.348128) (xy 139.239728 -434.333636) (xy 139.238078 -434.304536) (xy 139.237974 -434.289962)
			(xy 139.238072 -434.275388) (xy 139.239721 -434.246287) (xy 139.241276 -434.231796) (xy 139.241276 -433.618894)
			(xy 139.241656 -433.606767) (xy 139.249154 -433.583702) (xy 139.263415 -433.564084) (xy 139.283041 -433.549834)
			(xy 139.306111 -433.542349) (xy 139.318238 -433.541932) (xy 140.258038 -433.541932) (xy 140.270154 -433.542379)
			(xy 140.293197 -433.549876) (xy 140.312798 -433.564125) (xy 140.327038 -433.583731) (xy 140.334526 -433.606778)
			(xy 140.335 -433.618894) (xy 140.335 -434.48986) (xy 142.237968 -434.48986) (xy 142.238081 -434.474774)
			(xy 142.23986 -434.444656) (xy 142.241524 -434.429662) (xy 142.241524 -433.350162) (xy 142.239859 -433.335168)
			(xy 142.238078 -433.30505) (xy 142.237968 -433.289964) (xy 142.238081 -433.274878) (xy 142.23986 -433.24476)
			(xy 142.241524 -433.229766) (xy 142.241524 -432.618896) (xy 142.24191 -432.60681) (xy 142.249382 -432.583822)
			(xy 142.263594 -432.564268) (xy 142.283154 -432.550066) (xy 142.306146 -432.542604) (xy 142.318232 -432.542188)
			(xy 143.258032 -432.542188) (xy 143.270108 -432.542637) (xy 143.293075 -432.550108) (xy 143.312612 -432.564308)
			(xy 143.326805 -432.58385) (xy 143.334268 -432.60682) (xy 143.33474 -432.618896) (xy 143.33474 -435.16042)
			(xy 143.334253 -435.172492) (xy 143.326789 -435.195455) (xy 143.312597 -435.214989) (xy 143.293065 -435.229184)
			(xy 143.270104 -435.236651) (xy 143.258032 -435.237128) (xy 142.318232 -435.237128) (xy 142.306153 -435.23666)
			(xy 142.283175 -435.229204) (xy 142.263626 -435.215011) (xy 142.24942 -435.195472) (xy 142.241948 -435.172499)
			(xy 142.241524 -435.16042) (xy 142.241524 -434.550058) (xy 142.239858 -434.535064) (xy 142.238078 -434.504946)
			(xy 142.237968 -434.48986) (xy 140.335 -434.48986) (xy 140.335 -435.489858) (xy 144.237964 -435.489858)
			(xy 144.238077 -435.474772) (xy 144.239856 -435.444654) (xy 144.24152 -435.42966) (xy 144.24152 -434.35016)
			(xy 144.239855 -434.335166) (xy 144.238074 -434.305048) (xy 144.237964 -434.289962) (xy 144.238077 -434.274876)
			(xy 144.239856 -434.244758) (xy 144.24152 -434.229764) (xy 144.24152 -433.618894) (xy 144.242002 -433.606806)
			(xy 144.249458 -433.583809) (xy 144.263641 -433.564231) (xy 144.28317 -433.54998) (xy 144.306142 -433.542444)
			(xy 144.318228 -433.541932) (xy 145.258028 -433.541932) (xy 145.270142 -433.542293) (xy 145.293175 -433.549804)
			(xy 145.312751 -433.564079) (xy 145.326943 -433.583714) (xy 145.334357 -433.606779) (xy 145.334736 -433.618894)
			(xy 145.334736 -434.48986) (xy 146.23796 -434.48986) (xy 146.238073 -434.474774) (xy 146.239852 -434.444656)
			(xy 146.241516 -434.429662) (xy 146.241516 -433.350162) (xy 146.239851 -433.335168) (xy 146.23807 -433.30505)
			(xy 146.23796 -433.289964) (xy 146.238073 -433.274878) (xy 146.239852 -433.24476) (xy 146.241516 -433.229766)
			(xy 146.241516 -432.618896) (xy 146.241909 -432.606811) (xy 146.249381 -432.583824) (xy 146.263591 -432.564271)
			(xy 146.283149 -432.550068) (xy 146.306138 -432.542605) (xy 146.318224 -432.542188) (xy 147.258024 -432.542188)
			(xy 147.270099 -432.542644) (xy 147.293067 -432.550113) (xy 147.312603 -432.564311) (xy 147.326797 -432.583851)
			(xy 147.334259 -432.606821) (xy 147.334732 -432.618896) (xy 147.334732 -435.16042) (xy 147.334253 -435.172493)
			(xy 147.326788 -435.195457) (xy 147.312594 -435.214991) (xy 147.29306 -435.229186) (xy 147.270097 -435.236652)
			(xy 147.258024 -435.237128) (xy 146.318224 -435.237128) (xy 146.306145 -435.236667) (xy 146.283166 -435.229209)
			(xy 146.263617 -435.215014) (xy 146.249412 -435.195473) (xy 146.24194 -435.172499) (xy 146.241516 -435.16042)
			(xy 146.241516 -434.550058) (xy 146.23985 -434.535064) (xy 146.23807 -434.504946) (xy 146.23796 -434.48986)
			(xy 145.334736 -434.48986) (xy 145.334736 -435.489858) (xy 148.237956 -435.489858) (xy 148.238069 -435.474772)
			(xy 148.239848 -435.444654) (xy 148.241512 -435.42966) (xy 148.241512 -434.35016) (xy 148.239847 -434.335166)
			(xy 148.238066 -434.305048) (xy 148.237956 -434.289962) (xy 148.238069 -434.274876) (xy 148.239848 -434.244758)
			(xy 148.241512 -434.229764) (xy 148.241512 -433.618894) (xy 148.242002 -433.606807) (xy 148.249457 -433.583811)
			(xy 148.263639 -433.564234) (xy 148.283165 -433.549982) (xy 148.306135 -433.542445) (xy 148.31822 -433.541932)
			(xy 149.25802 -433.541932) (xy 149.270133 -433.5423) (xy 149.293167 -433.549808) (xy 149.312742 -433.564081)
			(xy 149.326935 -433.583715) (xy 149.334349 -433.606779) (xy 149.334728 -433.618894) (xy 149.334728 -434.48986)
			(xy 150.237952 -434.48986) (xy 150.238065 -434.474774) (xy 150.239844 -434.444656) (xy 150.241508 -434.429662)
			(xy 150.241508 -433.350162) (xy 150.239843 -433.335168) (xy 150.238062 -433.30505) (xy 150.237952 -433.289964)
			(xy 150.238065 -433.274878) (xy 150.239844 -433.24476) (xy 150.241508 -433.229766) (xy 150.241508 -432.618896)
			(xy 150.241909 -432.606811) (xy 150.24938 -432.583826) (xy 150.263588 -432.564274) (xy 150.283144 -432.550071)
			(xy 150.306131 -432.542606) (xy 150.318216 -432.542188) (xy 151.258016 -432.542188) (xy 151.270091 -432.542651)
			(xy 151.293058 -432.550117) (xy 151.312594 -432.564314) (xy 151.326788 -432.583853) (xy 151.334251 -432.606821)
			(xy 151.334724 -432.618896) (xy 151.334724 -435.16042) (xy 151.334253 -435.172494) (xy 151.326787 -435.195459)
			(xy 151.312591 -435.214994) (xy 151.293055 -435.229189) (xy 151.27009 -435.236654) (xy 151.258016 -435.237128)
			(xy 150.318216 -435.237128) (xy 150.306144 -435.236622) (xy 150.283181 -435.229167) (xy 150.263645 -435.21498)
			(xy 150.24945 -435.195451) (xy 150.241983 -435.172492) (xy 150.241508 -435.16042) (xy 150.241508 -434.550058)
			(xy 150.239842 -434.535064) (xy 150.238062 -434.504946) (xy 150.237952 -434.48986) (xy 149.334728 -434.48986)
			(xy 149.334728 -435.489858) (xy 152.237948 -435.489858) (xy 152.238061 -435.474772) (xy 152.23984 -435.444654)
			(xy 152.241504 -435.42966) (xy 152.241504 -434.35016) (xy 152.239838 -434.335166) (xy 152.238058 -434.305048)
			(xy 152.237948 -434.289962) (xy 152.238061 -434.274876) (xy 152.23984 -434.244758) (xy 152.241504 -434.229764)
			(xy 152.241504 -433.618894) (xy 152.242002 -433.606808) (xy 152.249456 -433.583813) (xy 152.263636 -433.564236)
			(xy 152.28316 -433.549985) (xy 152.306128 -433.542447) (xy 152.318212 -433.541932) (xy 153.258012 -433.541932)
			(xy 153.270125 -433.542306) (xy 153.293158 -433.549813) (xy 153.312734 -433.564084) (xy 153.326927 -433.583717)
			(xy 153.334341 -433.60678) (xy 153.33472 -433.618894) (xy 153.33472 -434.48986) (xy 154.237944 -434.48986)
			(xy 154.238057 -434.474774) (xy 154.239836 -434.444656) (xy 154.2415 -434.429662) (xy 154.2415 -433.350162)
			(xy 154.239835 -433.335168) (xy 154.238054 -433.30505) (xy 154.237944 -433.289964) (xy 154.238057 -433.274878)
			(xy 154.239836 -433.24476) (xy 154.2415 -433.229766) (xy 154.2415 -432.618896) (xy 154.241909 -432.606812)
			(xy 154.249379 -432.583828) (xy 154.263586 -432.564277) (xy 154.283139 -432.550073) (xy 154.306124 -432.542607)
			(xy 154.318208 -432.542188) (xy 155.258008 -432.542188) (xy 155.270083 -432.542657) (xy 155.293049 -432.550122)
			(xy 155.312586 -432.564317) (xy 155.32678 -432.583854) (xy 155.334243 -432.606821) (xy 155.334716 -432.618896)
			(xy 155.334716 -433.130695) (xy 197.035917 -433.130695) (xy 197.035917 -432.953425) (xy 197.04387 -432.776334)
			(xy 197.059761 -432.599778) (xy 197.083556 -432.424113) (xy 197.115209 -432.249692) (xy 197.154655 -432.076867)
			(xy 197.201815 -431.905986) (xy 197.256594 -431.737392) (xy 197.318882 -431.571427) (xy 197.388554 -431.408422)
			(xy 197.465468 -431.248708) (xy 197.549471 -431.092605) (xy 197.640392 -430.940428) (xy 197.738049 -430.792484)
			(xy 197.842246 -430.64907) (xy 197.952772 -430.510475) (xy 198.069404 -430.376978) (xy 198.191909 -430.248849)
			(xy 198.320038 -430.126344) (xy 198.453535 -430.009712) (xy 198.59213 -429.899186) (xy 198.735544 -429.794989)
			(xy 198.883488 -429.697332) (xy 199.035665 -429.606411) (xy 199.191768 -429.522408) (xy 199.351482 -429.445494)
			(xy 199.514487 -429.375822) (xy 199.680452 -429.313534) (xy 199.849046 -429.258755) (xy 200.019927 -429.211595)
			(xy 200.192752 -429.172149) (xy 200.367173 -429.140496) (xy 200.542838 -429.116701) (xy 200.719394 -429.10081)
			(xy 200.896485 -429.092857) (xy 201.073755 -429.092857) (xy 201.250846 -429.10081) (xy 201.427402 -429.116701)
			(xy 201.603067 -429.140496) (xy 201.777488 -429.172149) (xy 201.950313 -429.211595) (xy 202.121194 -429.258755)
			(xy 202.289788 -429.313534) (xy 202.455753 -429.375822) (xy 202.618758 -429.445494) (xy 202.778472 -429.522408)
			(xy 202.934575 -429.606411) (xy 203.086752 -429.697332) (xy 203.234696 -429.794989) (xy 203.37811 -429.899186)
			(xy 203.516705 -430.009712) (xy 203.650202 -430.126344) (xy 203.778331 -430.248849) (xy 203.900836 -430.376978)
			(xy 204.017468 -430.510475) (xy 204.127994 -430.64907) (xy 204.232191 -430.792484) (xy 204.329848 -430.940428)
			(xy 204.420769 -431.092605) (xy 204.504772 -431.248708) (xy 204.581686 -431.408422) (xy 204.651358 -431.571427)
			(xy 204.713646 -431.737392) (xy 204.768425 -431.905986) (xy 204.815585 -432.076867) (xy 204.855031 -432.249692)
			(xy 204.886684 -432.424113) (xy 204.910479 -432.599778) (xy 204.92637 -432.776334) (xy 204.934323 -432.953425)
			(xy 204.93482 -433.04206) (xy 204.934323 -433.130695) (xy 204.92637 -433.307786) (xy 204.910479 -433.484342)
			(xy 204.886684 -433.660007) (xy 204.855031 -433.834428) (xy 204.815585 -434.007253) (xy 204.768425 -434.178134)
			(xy 204.713646 -434.346728) (xy 204.651358 -434.512693) (xy 204.581686 -434.675698) (xy 204.504772 -434.835412)
			(xy 204.420769 -434.991515) (xy 204.329848 -435.143692) (xy 204.232191 -435.291636) (xy 204.127994 -435.43505)
			(xy 204.057751 -435.523132) (xy 205.85684 -435.523132) (xy 205.85684 -415.567368) (xy 205.857337 -415.542419)
			(xy 205.865152 -415.493137) (xy 205.88057 -415.44568) (xy 205.903211 -415.401214) (xy 205.93252 -415.360831)
			(xy 205.949804 -415.342832) (xy 206.989172 -414.303464) (xy 207.007169 -414.286175) (xy 207.047542 -414.256843)
			(xy 207.092007 -414.234188) (xy 207.139468 -414.218769) (xy 207.188756 -414.210963) (xy 207.213708 -414.2105)
			(xy 232.807256 -414.2105) (xy 239.488472 -407.529284) (xy 239.506473 -407.512) (xy 239.546848 -407.482676)
			(xy 239.591312 -407.460027) (xy 239.638771 -407.444612) (xy 239.688058 -407.436808) (xy 239.713008 -407.43632)
			(xy 280.100532 -407.43632) (xy 280.125481 -407.436823) (xy 280.174763 -407.444637) (xy 280.222219 -407.460054)
			(xy 280.266685 -407.482694) (xy 280.307069 -407.512001) (xy 280.325068 -407.529284) (xy 280.739596 -407.943812)
			(xy 280.756896 -407.961798) (xy 280.786219 -408.002177) (xy 280.808865 -408.046645) (xy 280.824276 -408.094108)
			(xy 280.832075 -408.143397) (xy 280.83256 -408.168348) (xy 280.83256 -410.057453) (xy 304.945246 -410.057453)
			(xy 304.945246 -410.002947) (xy 304.953003 -409.948996) (xy 304.968358 -409.896698) (xy 304.991001 -409.847117)
			(xy 305.020468 -409.801263) (xy 305.056162 -409.76007) (xy 305.097354 -409.724375) (xy 305.143207 -409.694906)
			(xy 305.192786 -409.672263) (xy 305.245084 -409.656905) (xy 305.299035 -409.649147) (xy 305.326288 -409.64866)
			(xy 306.189888 -409.64866) (xy 306.217139 -409.649186) (xy 306.271087 -409.656941) (xy 306.323382 -409.672295)
			(xy 306.372959 -409.694935) (xy 306.41881 -409.7244) (xy 306.460001 -409.760091) (xy 306.495693 -409.80128)
			(xy 306.525159 -409.84713) (xy 306.547801 -409.896707) (xy 306.563156 -409.949001) (xy 306.570913 -410.002949)
			(xy 306.570913 -410.057451) (xy 306.570912 -410.057456) (xy 308.008423 -410.057456) (xy 308.008423 -410.002944)
			(xy 308.016181 -409.948986) (xy 308.03154 -409.896681) (xy 308.054187 -409.847095) (xy 308.08366 -409.801236)
			(xy 308.119359 -409.76004) (xy 308.160559 -409.724343) (xy 308.206419 -409.694873) (xy 308.256007 -409.67223)
			(xy 308.308313 -409.656875) (xy 308.362272 -409.649121) (xy 308.389528 -409.64866) (xy 309.253128 -409.64866)
			(xy 309.280376 -409.649212) (xy 309.334316 -409.656971) (xy 309.386603 -409.672327) (xy 309.436172 -409.694968)
			(xy 309.482015 -409.724433) (xy 309.523199 -409.760121) (xy 309.558884 -409.801307) (xy 309.588345 -409.847152)
			(xy 309.610982 -409.896724) (xy 309.626335 -409.949012) (xy 309.63409 -410.002952) (xy 309.63409 -410.057448)
			(xy 309.634089 -410.057452) (xy 311.071746 -410.057452) (xy 311.071746 -410.002948) (xy 311.079502 -409.948998)
			(xy 311.094857 -409.896702) (xy 311.117498 -409.847123) (xy 311.146963 -409.80127) (xy 311.182654 -409.760077)
			(xy 311.223844 -409.724383) (xy 311.269695 -409.694913) (xy 311.319272 -409.672268) (xy 311.371567 -409.656909)
			(xy 311.425516 -409.649148) (xy 311.452768 -409.64866) (xy 312.316368 -409.64866) (xy 312.34362 -409.649185)
			(xy 312.39757 -409.656938) (xy 312.449867 -409.67229) (xy 312.499447 -409.694928) (xy 312.545301 -409.724393)
			(xy 312.586494 -409.760084) (xy 312.622188 -409.801274) (xy 312.651656 -409.847125) (xy 312.674299 -409.896703)
			(xy 312.689655 -409.948999) (xy 312.697413 -410.002948) (xy 312.697413 -410.057452) (xy 312.697412 -410.057456)
			(xy 314.134923 -410.057456) (xy 314.134923 -410.002944) (xy 314.142681 -409.948988) (xy 314.158039 -409.896685)
			(xy 314.180684 -409.8471) (xy 314.210155 -409.801243) (xy 314.245852 -409.760047) (xy 314.287049 -409.72435)
			(xy 314.332907 -409.69488) (xy 314.382493 -409.672236) (xy 314.434796 -409.656879) (xy 314.488752 -409.649122)
			(xy 314.516008 -409.64866) (xy 315.379608 -409.64866) (xy 315.406857 -409.649211) (xy 315.460799 -409.656968)
			(xy 315.513088 -409.672322) (xy 315.56266 -409.694962) (xy 315.608506 -409.724426) (xy 315.649691 -409.760114)
			(xy 315.685379 -409.801301) (xy 315.714842 -409.847147) (xy 315.737481 -409.896719) (xy 315.752834 -409.949009)
			(xy 315.76059 -410.002951) (xy 315.76059 -410.057449) (xy 315.760589 -410.057457) (xy 317.198123 -410.057457)
			(xy 317.198123 -410.002943) (xy 317.205882 -409.948983) (xy 317.221242 -409.896677) (xy 317.24389 -409.847089)
			(xy 317.273365 -409.80123) (xy 317.309066 -409.760033) (xy 317.350268 -409.724336) (xy 317.396131 -409.694867)
			(xy 317.445722 -409.672225) (xy 317.49803 -409.656872) (xy 317.551991 -409.64912) (xy 317.579248 -409.64866)
			(xy 318.442848 -409.64866) (xy 318.470095 -409.649213) (xy 318.524033 -409.656975) (xy 318.576317 -409.672333)
			(xy 318.625884 -409.694975) (xy 318.671725 -409.72444) (xy 318.712906 -409.760128) (xy 318.748589 -409.801314)
			(xy 318.778048 -409.847158) (xy 318.800684 -409.896728) (xy 318.816035 -409.949014) (xy 318.82379 -410.002953)
			(xy 318.82379 -410.057447) (xy 318.823789 -410.057453) (xy 320.261446 -410.057453) (xy 320.261446 -410.002947)
			(xy 320.269203 -409.948996) (xy 320.284558 -409.896698) (xy 320.307201 -409.847117) (xy 320.336668 -409.801263)
			(xy 320.372362 -409.76007) (xy 320.413554 -409.724375) (xy 320.459407 -409.694906) (xy 320.508986 -409.672263)
			(xy 320.561284 -409.656905) (xy 320.615235 -409.649147) (xy 320.642488 -409.64866) (xy 321.506088 -409.64866)
			(xy 321.533339 -409.649186) (xy 321.587287 -409.656941) (xy 321.639582 -409.672295) (xy 321.689159 -409.694935)
			(xy 321.73501 -409.7244) (xy 321.776201 -409.760091) (xy 321.811893 -409.80128) (xy 321.841359 -409.84713)
			(xy 321.864001 -409.896707) (xy 321.879356 -409.949001) (xy 321.887113 -410.002949) (xy 321.887113 -410.057451)
			(xy 321.887112 -410.057456) (xy 323.324623 -410.057456) (xy 323.324623 -410.002944) (xy 323.332381 -409.948986)
			(xy 323.34774 -409.896681) (xy 323.370387 -409.847095) (xy 323.39986 -409.801236) (xy 323.435559 -409.76004)
			(xy 323.476759 -409.724343) (xy 323.522619 -409.694873) (xy 323.572207 -409.67223) (xy 323.624513 -409.656875)
			(xy 323.678472 -409.649121) (xy 323.705728 -409.64866) (xy 324.569328 -409.64866) (xy 324.596576 -409.649212)
			(xy 324.650516 -409.656971) (xy 324.702803 -409.672327) (xy 324.752372 -409.694968) (xy 324.798215 -409.724433)
			(xy 324.839399 -409.760121) (xy 324.875084 -409.801307) (xy 324.904545 -409.847152) (xy 324.927182 -409.896724)
			(xy 324.942535 -409.949012) (xy 324.95029 -410.002952) (xy 324.95029 -410.057448) (xy 324.950289 -410.057452)
			(xy 326.387946 -410.057452) (xy 326.387946 -410.002948) (xy 326.395702 -409.948998) (xy 326.411057 -409.896702)
			(xy 326.433698 -409.847123) (xy 326.463163 -409.80127) (xy 326.498854 -409.760077) (xy 326.540044 -409.724383)
			(xy 326.585895 -409.694913) (xy 326.635472 -409.672268) (xy 326.687767 -409.656909) (xy 326.741716 -409.649148)
			(xy 326.768968 -409.64866) (xy 327.632568 -409.64866) (xy 327.65982 -409.649185) (xy 327.71377 -409.656938)
			(xy 327.766067 -409.67229) (xy 327.815647 -409.694928) (xy 327.861501 -409.724393) (xy 327.902694 -409.760084)
			(xy 327.938388 -409.801274) (xy 327.967856 -409.847125) (xy 327.990499 -409.896703) (xy 328.005855 -409.948999)
			(xy 328.013613 -410.002948) (xy 328.013613 -410.057452) (xy 328.013612 -410.057456) (xy 329.451123 -410.057456)
			(xy 329.451123 -410.002944) (xy 329.458881 -409.948988) (xy 329.474239 -409.896685) (xy 329.496884 -409.8471)
			(xy 329.526355 -409.801243) (xy 329.562052 -409.760047) (xy 329.603249 -409.72435) (xy 329.649107 -409.69488)
			(xy 329.698693 -409.672236) (xy 329.750996 -409.656879) (xy 329.804952 -409.649122) (xy 329.832208 -409.64866)
			(xy 330.695808 -409.64866) (xy 330.723057 -409.649211) (xy 330.776999 -409.656968) (xy 330.829288 -409.672322)
			(xy 330.87886 -409.694962) (xy 330.924706 -409.724426) (xy 330.965891 -409.760114) (xy 331.001579 -409.801301)
			(xy 331.031042 -409.847147) (xy 331.053681 -409.896719) (xy 331.069034 -409.949009) (xy 331.07679 -410.002951)
			(xy 331.07679 -410.057449) (xy 331.076789 -410.057457) (xy 332.514323 -410.057457) (xy 332.514323 -410.002943)
			(xy 332.522082 -409.948983) (xy 332.537442 -409.896677) (xy 332.56009 -409.847089) (xy 332.589565 -409.80123)
			(xy 332.625266 -409.760033) (xy 332.666468 -409.724336) (xy 332.712331 -409.694867) (xy 332.761922 -409.672225)
			(xy 332.81423 -409.656872) (xy 332.868191 -409.64912) (xy 332.895448 -409.64866) (xy 333.759048 -409.64866)
			(xy 333.786295 -409.649213) (xy 333.840233 -409.656975) (xy 333.892517 -409.672333) (xy 333.942084 -409.694975)
			(xy 333.987925 -409.72444) (xy 334.029106 -409.760128) (xy 334.064789 -409.801314) (xy 334.094248 -409.847158)
			(xy 334.116884 -409.896728) (xy 334.132235 -409.949014) (xy 334.13999 -410.002953) (xy 334.13999 -410.057447)
			(xy 334.139989 -410.057453) (xy 335.577646 -410.057453) (xy 335.577646 -410.002947) (xy 335.585403 -409.948996)
			(xy 335.600758 -409.896698) (xy 335.623401 -409.847117) (xy 335.652868 -409.801263) (xy 335.688562 -409.76007)
			(xy 335.729754 -409.724375) (xy 335.775607 -409.694906) (xy 335.825186 -409.672263) (xy 335.877484 -409.656905)
			(xy 335.931435 -409.649147) (xy 335.958688 -409.64866) (xy 336.822288 -409.64866) (xy 336.849539 -409.649186)
			(xy 336.903487 -409.656941) (xy 336.955782 -409.672295) (xy 337.005359 -409.694935) (xy 337.05121 -409.7244)
			(xy 337.092401 -409.760091) (xy 337.128093 -409.80128) (xy 337.157559 -409.84713) (xy 337.180201 -409.896707)
			(xy 337.195556 -409.949001) (xy 337.203313 -410.002949) (xy 337.203313 -410.057451) (xy 337.203312 -410.057456)
			(xy 338.640823 -410.057456) (xy 338.640823 -410.002944) (xy 338.648581 -409.948986) (xy 338.66394 -409.896681)
			(xy 338.686587 -409.847095) (xy 338.71606 -409.801236) (xy 338.751759 -409.76004) (xy 338.792959 -409.724343)
			(xy 338.838819 -409.694873) (xy 338.888407 -409.67223) (xy 338.940713 -409.656875) (xy 338.994672 -409.649121)
			(xy 339.021928 -409.64866) (xy 339.885528 -409.64866) (xy 339.912776 -409.649212) (xy 339.966716 -409.656971)
			(xy 340.019003 -409.672327) (xy 340.068572 -409.694968) (xy 340.114415 -409.724433) (xy 340.155599 -409.760121)
			(xy 340.191284 -409.801307) (xy 340.220745 -409.847152) (xy 340.243382 -409.896724) (xy 340.258735 -409.949012)
			(xy 340.26649 -410.002952) (xy 340.26649 -410.057448) (xy 340.266489 -410.057452) (xy 341.704146 -410.057452)
			(xy 341.704146 -410.002948) (xy 341.711902 -409.948998) (xy 341.727257 -409.896702) (xy 341.749898 -409.847123)
			(xy 341.779363 -409.80127) (xy 341.815054 -409.760077) (xy 341.856244 -409.724383) (xy 341.902095 -409.694913)
			(xy 341.951672 -409.672268) (xy 342.003967 -409.656909) (xy 342.057916 -409.649148) (xy 342.085168 -409.64866)
			(xy 342.948768 -409.64866) (xy 342.97602 -409.649185) (xy 343.02997 -409.656938) (xy 343.082267 -409.67229)
			(xy 343.131847 -409.694928) (xy 343.177701 -409.724393) (xy 343.218894 -409.760084) (xy 343.254588 -409.801274)
			(xy 343.284056 -409.847125) (xy 343.306699 -409.896703) (xy 343.322055 -409.948999) (xy 343.329813 -410.002948)
			(xy 343.329813 -410.057452) (xy 343.329812 -410.057456) (xy 344.767323 -410.057456) (xy 344.767323 -410.002944)
			(xy 344.775081 -409.948988) (xy 344.790439 -409.896685) (xy 344.813084 -409.8471) (xy 344.842555 -409.801243)
			(xy 344.878252 -409.760047) (xy 344.919449 -409.72435) (xy 344.965307 -409.69488) (xy 345.014893 -409.672236)
			(xy 345.067196 -409.656879) (xy 345.121152 -409.649122) (xy 345.148408 -409.64866) (xy 346.012008 -409.64866)
			(xy 346.039257 -409.649211) (xy 346.093199 -409.656968) (xy 346.145488 -409.672322) (xy 346.19506 -409.694962)
			(xy 346.240906 -409.724426) (xy 346.282091 -409.760114) (xy 346.317779 -409.801301) (xy 346.347242 -409.847147)
			(xy 346.369881 -409.896719) (xy 346.385234 -409.949009) (xy 346.39299 -410.002951) (xy 346.39299 -410.057449)
			(xy 346.392989 -410.057457) (xy 347.830523 -410.057457) (xy 347.830523 -410.002943) (xy 347.838282 -409.948983)
			(xy 347.853642 -409.896677) (xy 347.87629 -409.847089) (xy 347.905765 -409.80123) (xy 347.941466 -409.760033)
			(xy 347.982668 -409.724336) (xy 348.028531 -409.694867) (xy 348.078122 -409.672225) (xy 348.13043 -409.656872)
			(xy 348.184391 -409.64912) (xy 348.211648 -409.64866) (xy 349.075248 -409.64866) (xy 349.102495 -409.649213)
			(xy 349.156433 -409.656975) (xy 349.208717 -409.672333) (xy 349.258284 -409.694975) (xy 349.304125 -409.72444)
			(xy 349.345306 -409.760128) (xy 349.380989 -409.801314) (xy 349.410448 -409.847158) (xy 349.433084 -409.896728)
			(xy 349.448435 -409.949014) (xy 349.45619 -410.002953) (xy 349.45619 -410.057447) (xy 349.456189 -410.057453)
			(xy 350.893846 -410.057453) (xy 350.893846 -410.002947) (xy 350.901603 -409.948996) (xy 350.916958 -409.896698)
			(xy 350.939601 -409.847117) (xy 350.969068 -409.801263) (xy 351.004762 -409.76007) (xy 351.045954 -409.724375)
			(xy 351.091807 -409.694906) (xy 351.141386 -409.672263) (xy 351.193684 -409.656905) (xy 351.247635 -409.649147)
			(xy 351.274888 -409.64866) (xy 352.138488 -409.64866) (xy 352.165739 -409.649186) (xy 352.219687 -409.656941)
			(xy 352.271982 -409.672295) (xy 352.321559 -409.694935) (xy 352.36741 -409.7244) (xy 352.408601 -409.760091)
			(xy 352.444293 -409.80128) (xy 352.473759 -409.84713) (xy 352.496401 -409.896707) (xy 352.511756 -409.949001)
			(xy 352.519513 -410.002949) (xy 352.519513 -410.057451) (xy 352.519512 -410.057457) (xy 372.388023 -410.057457)
			(xy 372.388023 -410.002943) (xy 372.395781 -409.948985) (xy 372.41114 -409.896681) (xy 372.433787 -409.847094)
			(xy 372.46326 -409.801236) (xy 372.49896 -409.760039) (xy 372.54016 -409.724342) (xy 372.586021 -409.694872)
			(xy 372.635609 -409.67223) (xy 372.687915 -409.656875) (xy 372.741873 -409.649121) (xy 372.76913 -409.64866)
			(xy 373.63273 -409.64866) (xy 373.659978 -409.649212) (xy 373.713917 -409.656972) (xy 373.766204 -409.672328)
			(xy 373.815773 -409.694969) (xy 373.861616 -409.724434) (xy 373.902799 -409.760122) (xy 373.938484 -409.801308)
			(xy 373.967945 -409.847153) (xy 373.990583 -409.896724) (xy 374.005935 -409.949012) (xy 374.01369 -410.002952)
			(xy 374.01369 -410.057448) (xy 374.013689 -410.057452) (xy 375.451346 -410.057452) (xy 375.451346 -410.002948)
			(xy 375.459102 -409.948998) (xy 375.474457 -409.896701) (xy 375.497098 -409.847122) (xy 375.526564 -409.801269)
			(xy 375.562255 -409.760076) (xy 375.603445 -409.724382) (xy 375.649296 -409.694912) (xy 375.698873 -409.672268)
			(xy 375.751169 -409.656909) (xy 375.805118 -409.649148) (xy 375.83237 -409.64866) (xy 376.69597 -409.64866)
			(xy 376.723222 -409.649185) (xy 376.777172 -409.656938) (xy 376.829469 -409.67229) (xy 376.879048 -409.694929)
			(xy 376.924901 -409.724394) (xy 376.966094 -409.760084) (xy 377.001788 -409.801274) (xy 377.031257 -409.847125)
			(xy 377.053899 -409.896703) (xy 377.069256 -409.948999) (xy 377.077013 -410.002948) (xy 377.077013 -410.057452)
			(xy 377.077012 -410.057456) (xy 378.514523 -410.057456) (xy 378.514523 -410.002944) (xy 378.522281 -409.948988)
			(xy 378.537639 -409.896685) (xy 378.560284 -409.8471) (xy 378.589755 -409.801242) (xy 378.625453 -409.760046)
			(xy 378.66665 -409.724349) (xy 378.712509 -409.694879) (xy 378.762094 -409.672235) (xy 378.814398 -409.656879)
			(xy 378.868354 -409.649122) (xy 378.89561 -409.64866) (xy 379.75921 -409.64866) (xy 379.786458 -409.649211)
			(xy 379.840401 -409.656968) (xy 379.89269 -409.672323) (xy 379.942261 -409.694962) (xy 379.988107 -409.724426)
			(xy 380.029292 -409.760115) (xy 380.06498 -409.801301) (xy 380.094442 -409.847147) (xy 380.117081 -409.89672)
			(xy 380.132434 -409.949009) (xy 380.14019 -410.002952) (xy 380.14019 -410.057448) (xy 380.14019 -410.057451)
			(xy 381.577846 -410.057451) (xy 381.577846 -410.002949) (xy 381.585602 -409.949001) (xy 381.600955 -409.896706)
			(xy 381.623595 -409.847128) (xy 381.653059 -409.801276) (xy 381.688748 -409.760083) (xy 381.729936 -409.724389)
			(xy 381.775784 -409.694919) (xy 381.825359 -409.672273) (xy 381.877652 -409.656912) (xy 381.931599 -409.649149)
			(xy 381.95885 -409.64866) (xy 382.82245 -409.64866) (xy 382.849703 -409.649184) (xy 382.903655 -409.656934)
			(xy 382.955954 -409.672285) (xy 383.005536 -409.694923) (xy 383.051392 -409.724387) (xy 383.092587 -409.760077)
			(xy 383.128283 -409.801268) (xy 383.157753 -409.84712) (xy 383.180398 -409.896699) (xy 383.195755 -409.948996)
			(xy 383.203513 -410.002947) (xy 383.203513 -410.057453) (xy 384.641046 -410.057453) (xy 384.641046 -410.002947)
			(xy 384.648803 -409.948996) (xy 384.664159 -409.896697) (xy 384.686801 -409.847117) (xy 384.716269 -409.801263)
			(xy 384.751962 -409.760069) (xy 384.793155 -409.724375) (xy 384.839008 -409.694906) (xy 384.888588 -409.672262)
			(xy 384.940886 -409.656905) (xy 384.994837 -409.649147) (xy 385.02209 -409.64866) (xy 385.88569 -409.64866)
			(xy 385.912941 -409.649187) (xy 385.966889 -409.656942) (xy 386.019183 -409.672296) (xy 386.06876 -409.694936)
			(xy 386.114611 -409.724401) (xy 386.155801 -409.760092) (xy 386.191493 -409.801281) (xy 386.22096 -409.847131)
			(xy 386.243601 -409.896707) (xy 386.258956 -409.949002) (xy 386.266713 -410.002949) (xy 386.266713 -410.057451)
			(xy 386.266712 -410.057457) (xy 387.704223 -410.057457) (xy 387.704223 -410.002943) (xy 387.711981 -409.948985)
			(xy 387.72734 -409.896681) (xy 387.749987 -409.847094) (xy 387.77946 -409.801236) (xy 387.81516 -409.760039)
			(xy 387.85636 -409.724342) (xy 387.902221 -409.694872) (xy 387.951809 -409.67223) (xy 388.004115 -409.656875)
			(xy 388.058073 -409.649121) (xy 388.08533 -409.64866) (xy 388.94893 -409.64866) (xy 388.976178 -409.649212)
			(xy 389.030117 -409.656972) (xy 389.082404 -409.672328) (xy 389.131973 -409.694969) (xy 389.177816 -409.724434)
			(xy 389.218999 -409.760122) (xy 389.254684 -409.801308) (xy 389.284145 -409.847153) (xy 389.306783 -409.896724)
			(xy 389.322135 -409.949012) (xy 389.32989 -410.002952) (xy 389.32989 -410.057448) (xy 389.329889 -410.057452)
			(xy 390.767546 -410.057452) (xy 390.767546 -410.002948) (xy 390.775302 -409.948998) (xy 390.790657 -409.896701)
			(xy 390.813298 -409.847122) (xy 390.842764 -409.801269) (xy 390.878455 -409.760076) (xy 390.919645 -409.724382)
			(xy 390.965496 -409.694912) (xy 391.015073 -409.672268) (xy 391.067369 -409.656909) (xy 391.121318 -409.649148)
			(xy 391.14857 -409.64866) (xy 392.01217 -409.64866) (xy 392.039422 -409.649185) (xy 392.093372 -409.656938)
			(xy 392.145669 -409.67229) (xy 392.195248 -409.694929) (xy 392.241101 -409.724394) (xy 392.282294 -409.760084)
			(xy 392.317988 -409.801274) (xy 392.347457 -409.847125) (xy 392.370099 -409.896703) (xy 392.385456 -409.948999)
			(xy 392.393213 -410.002948) (xy 392.393213 -410.057452) (xy 392.393212 -410.057456) (xy 393.830723 -410.057456)
			(xy 393.830723 -410.002944) (xy 393.838481 -409.948988) (xy 393.853839 -409.896685) (xy 393.876484 -409.8471)
			(xy 393.905955 -409.801242) (xy 393.941653 -409.760046) (xy 393.98285 -409.724349) (xy 394.028709 -409.694879)
			(xy 394.078294 -409.672235) (xy 394.130598 -409.656879) (xy 394.184554 -409.649122) (xy 394.21181 -409.64866)
			(xy 395.07541 -409.64866) (xy 395.102658 -409.649211) (xy 395.156601 -409.656968) (xy 395.20889 -409.672323)
			(xy 395.258461 -409.694962) (xy 395.304307 -409.724426) (xy 395.345492 -409.760115) (xy 395.38118 -409.801301)
			(xy 395.410642 -409.847147) (xy 395.433281 -409.89672) (xy 395.448634 -409.949009) (xy 395.45639 -410.002952)
			(xy 395.45639 -410.057448) (xy 395.45639 -410.057451) (xy 396.894046 -410.057451) (xy 396.894046 -410.002949)
			(xy 396.901802 -409.949001) (xy 396.917155 -409.896706) (xy 396.939795 -409.847128) (xy 396.969259 -409.801276)
			(xy 397.004948 -409.760083) (xy 397.046136 -409.724389) (xy 397.091984 -409.694919) (xy 397.141559 -409.672273)
			(xy 397.193852 -409.656912) (xy 397.247799 -409.649149) (xy 397.27505 -409.64866) (xy 398.13865 -409.64866)
			(xy 398.165903 -409.649184) (xy 398.219855 -409.656934) (xy 398.272154 -409.672285) (xy 398.321736 -409.694923)
			(xy 398.367592 -409.724387) (xy 398.408787 -409.760077) (xy 398.444483 -409.801268) (xy 398.473953 -409.84712)
			(xy 398.496598 -409.896699) (xy 398.511955 -409.948996) (xy 398.519713 -410.002947) (xy 398.519713 -410.057453)
			(xy 399.957246 -410.057453) (xy 399.957246 -410.002947) (xy 399.965003 -409.948996) (xy 399.980359 -409.896697)
			(xy 400.003001 -409.847117) (xy 400.032469 -409.801263) (xy 400.068162 -409.760069) (xy 400.109355 -409.724375)
			(xy 400.155208 -409.694906) (xy 400.204788 -409.672262) (xy 400.257086 -409.656905) (xy 400.311037 -409.649147)
			(xy 400.33829 -409.64866) (xy 401.20189 -409.64866) (xy 401.229141 -409.649187) (xy 401.283089 -409.656942)
			(xy 401.335383 -409.672296) (xy 401.38496 -409.694936) (xy 401.430811 -409.724401) (xy 401.472001 -409.760092)
			(xy 401.507693 -409.801281) (xy 401.53716 -409.847131) (xy 401.559801 -409.896707) (xy 401.575156 -409.949002)
			(xy 401.582913 -410.002949) (xy 401.582913 -410.057451) (xy 401.582912 -410.057457) (xy 403.020423 -410.057457)
			(xy 403.020423 -410.002943) (xy 403.028181 -409.948985) (xy 403.04354 -409.896681) (xy 403.066187 -409.847094)
			(xy 403.09566 -409.801236) (xy 403.13136 -409.760039) (xy 403.17256 -409.724342) (xy 403.218421 -409.694872)
			(xy 403.268009 -409.67223) (xy 403.320315 -409.656875) (xy 403.374273 -409.649121) (xy 403.40153 -409.64866)
			(xy 404.26513 -409.64866) (xy 404.292378 -409.649212) (xy 404.346317 -409.656972) (xy 404.398604 -409.672328)
			(xy 404.448173 -409.694969) (xy 404.494016 -409.724434) (xy 404.535199 -409.760122) (xy 404.570884 -409.801308)
			(xy 404.600345 -409.847153) (xy 404.622983 -409.896724) (xy 404.638335 -409.949012) (xy 404.64609 -410.002952)
			(xy 404.64609 -410.057448) (xy 404.646089 -410.057452) (xy 406.083746 -410.057452) (xy 406.083746 -410.002948)
			(xy 406.091502 -409.948998) (xy 406.106857 -409.896701) (xy 406.129498 -409.847122) (xy 406.158964 -409.801269)
			(xy 406.194655 -409.760076) (xy 406.235845 -409.724382) (xy 406.281696 -409.694912) (xy 406.331273 -409.672268)
			(xy 406.383569 -409.656909) (xy 406.437518 -409.649148) (xy 406.46477 -409.64866) (xy 407.32837 -409.64866)
			(xy 407.355622 -409.649185) (xy 407.409572 -409.656938) (xy 407.461869 -409.67229) (xy 407.511448 -409.694929)
			(xy 407.557301 -409.724394) (xy 407.598494 -409.760084) (xy 407.634188 -409.801274) (xy 407.663657 -409.847125)
			(xy 407.686299 -409.896703) (xy 407.701656 -409.948999) (xy 407.709413 -410.002948) (xy 407.709413 -410.057452)
			(xy 407.709412 -410.057456) (xy 409.146923 -410.057456) (xy 409.146923 -410.002944) (xy 409.154681 -409.948988)
			(xy 409.170039 -409.896685) (xy 409.192684 -409.8471) (xy 409.222155 -409.801242) (xy 409.257853 -409.760046)
			(xy 409.29905 -409.724349) (xy 409.344909 -409.694879) (xy 409.394494 -409.672235) (xy 409.446798 -409.656879)
			(xy 409.500754 -409.649122) (xy 409.52801 -409.64866) (xy 410.39161 -409.64866) (xy 410.418858 -409.649211)
			(xy 410.472801 -409.656968) (xy 410.52509 -409.672323) (xy 410.574661 -409.694962) (xy 410.620507 -409.724426)
			(xy 410.661692 -409.760115) (xy 410.69738 -409.801301) (xy 410.726842 -409.847147) (xy 410.749481 -409.89672)
			(xy 410.764834 -409.949009) (xy 410.77259 -410.002952) (xy 410.77259 -410.057448) (xy 410.77259 -410.057451)
			(xy 412.210246 -410.057451) (xy 412.210246 -410.002949) (xy 412.218002 -409.949001) (xy 412.233355 -409.896706)
			(xy 412.255995 -409.847128) (xy 412.285459 -409.801276) (xy 412.321148 -409.760083) (xy 412.362336 -409.724389)
			(xy 412.408184 -409.694919) (xy 412.457759 -409.672273) (xy 412.510052 -409.656912) (xy 412.563999 -409.649149)
			(xy 412.59125 -409.64866) (xy 413.45485 -409.64866) (xy 413.482103 -409.649184) (xy 413.536055 -409.656934)
			(xy 413.588354 -409.672285) (xy 413.637936 -409.694923) (xy 413.683792 -409.724387) (xy 413.724987 -409.760077)
			(xy 413.760683 -409.801268) (xy 413.790153 -409.84712) (xy 413.812798 -409.896699) (xy 413.828155 -409.948996)
			(xy 413.835913 -410.002947) (xy 413.835913 -410.057453) (xy 415.273446 -410.057453) (xy 415.273446 -410.002947)
			(xy 415.281203 -409.948996) (xy 415.296559 -409.896697) (xy 415.319201 -409.847117) (xy 415.348669 -409.801263)
			(xy 415.384362 -409.760069) (xy 415.425555 -409.724375) (xy 415.471408 -409.694906) (xy 415.520988 -409.672262)
			(xy 415.573286 -409.656905) (xy 415.627237 -409.649147) (xy 415.65449 -409.64866) (xy 416.51809 -409.64866)
			(xy 416.545341 -409.649187) (xy 416.599289 -409.656942) (xy 416.651583 -409.672296) (xy 416.70116 -409.694936)
			(xy 416.747011 -409.724401) (xy 416.788201 -409.760092) (xy 416.823893 -409.801281) (xy 416.85336 -409.847131)
			(xy 416.876001 -409.896707) (xy 416.891356 -409.949002) (xy 416.899113 -410.002949) (xy 416.899113 -410.057451)
			(xy 416.899112 -410.057457) (xy 418.336623 -410.057457) (xy 418.336623 -410.002943) (xy 418.344381 -409.948985)
			(xy 418.35974 -409.896681) (xy 418.382387 -409.847094) (xy 418.41186 -409.801236) (xy 418.44756 -409.760039)
			(xy 418.48876 -409.724342) (xy 418.534621 -409.694872) (xy 418.584209 -409.67223) (xy 418.636515 -409.656875)
			(xy 418.690473 -409.649121) (xy 418.71773 -409.64866) (xy 419.58133 -409.64866) (xy 419.608578 -409.649212)
			(xy 419.662517 -409.656972) (xy 419.714804 -409.672328) (xy 419.764373 -409.694969) (xy 419.810216 -409.724434)
			(xy 419.851399 -409.760122) (xy 419.887084 -409.801308) (xy 419.916545 -409.847153) (xy 419.939183 -409.896724)
			(xy 419.954535 -409.949012) (xy 419.96229 -410.002952) (xy 419.96229 -410.057448) (xy 419.954535 -410.111388)
			(xy 419.939183 -410.163676) (xy 419.916545 -410.213247) (xy 419.887084 -410.259092) (xy 419.851399 -410.300278)
			(xy 419.810216 -410.335966) (xy 419.764373 -410.365431) (xy 419.714804 -410.388072) (xy 419.662517 -410.403428)
			(xy 419.608578 -410.411188) (xy 419.58133 -410.411676) (xy 418.71773 -410.411676) (xy 418.690473 -410.411279)
			(xy 418.636515 -410.403525) (xy 418.584209 -410.38817) (xy 418.534621 -410.365528) (xy 418.48876 -410.336058)
			(xy 418.44756 -410.300361) (xy 418.41186 -410.259164) (xy 418.382387 -410.213306) (xy 418.35974 -410.163719)
			(xy 418.344381 -410.111415) (xy 418.336623 -410.057457) (xy 416.899112 -410.057457) (xy 416.891356 -410.111398)
			(xy 416.876001 -410.163693) (xy 416.85336 -410.213269) (xy 416.823893 -410.259119) (xy 416.788201 -410.300308)
			(xy 416.747011 -410.335999) (xy 416.70116 -410.365464) (xy 416.651583 -410.388104) (xy 416.599289 -410.403458)
			(xy 416.545341 -410.411213) (xy 416.51809 -410.411676) (xy 415.65449 -410.411676) (xy 415.627237 -410.411253)
			(xy 415.573286 -410.403495) (xy 415.520988 -410.388138) (xy 415.471408 -410.365494) (xy 415.425555 -410.336025)
			(xy 415.384362 -410.300331) (xy 415.348669 -410.259137) (xy 415.319201 -410.213283) (xy 415.296559 -410.163703)
			(xy 415.281203 -410.111404) (xy 415.273446 -410.057453) (xy 413.835913 -410.057453) (xy 413.828155 -410.111404)
			(xy 413.812798 -410.163701) (xy 413.790153 -410.21328) (xy 413.760683 -410.259132) (xy 413.724987 -410.300323)
			(xy 413.683792 -410.336013) (xy 413.637936 -410.365477) (xy 413.588354 -410.388115) (xy 413.536055 -410.403466)
			(xy 413.482103 -410.411216) (xy 413.45485 -410.411676) (xy 412.59125 -410.411676) (xy 412.563999 -410.411251)
			(xy 412.510052 -410.403488) (xy 412.457759 -410.388127) (xy 412.408184 -410.365481) (xy 412.362336 -410.336011)
			(xy 412.321148 -410.300317) (xy 412.285459 -410.259124) (xy 412.255995 -410.213272) (xy 412.233355 -410.163694)
			(xy 412.218002 -410.111399) (xy 412.210246 -410.057451) (xy 410.77259 -410.057451) (xy 410.764834 -410.111391)
			(xy 410.749481 -410.16368) (xy 410.726842 -410.213253) (xy 410.69738 -410.259099) (xy 410.661692 -410.300285)
			(xy 410.620507 -410.335974) (xy 410.574661 -410.365438) (xy 410.52509 -410.388077) (xy 410.472801 -410.403432)
			(xy 410.418858 -410.411189) (xy 410.39161 -410.411676) (xy 409.52801 -410.411676) (xy 409.500754 -410.411278)
			(xy 409.446798 -410.403521) (xy 409.394494 -410.388165) (xy 409.344909 -410.365521) (xy 409.29905 -410.336051)
			(xy 409.257853 -410.300354) (xy 409.222155 -410.259158) (xy 409.192684 -410.2133) (xy 409.170039 -410.163715)
			(xy 409.154681 -410.111412) (xy 409.146923 -410.057456) (xy 407.709412 -410.057456) (xy 407.701656 -410.111401)
			(xy 407.686299 -410.163697) (xy 407.663657 -410.213275) (xy 407.634188 -410.259126) (xy 407.598494 -410.300316)
			(xy 407.557301 -410.336006) (xy 407.511448 -410.365471) (xy 407.461869 -410.38811) (xy 407.409572 -410.403462)
			(xy 407.355622 -410.411215) (xy 407.32837 -410.411676) (xy 406.46477 -410.411676) (xy 406.437518 -410.411252)
			(xy 406.383569 -410.403491) (xy 406.331273 -410.388132) (xy 406.281696 -410.365488) (xy 406.235845 -410.336018)
			(xy 406.194655 -410.300324) (xy 406.158964 -410.259131) (xy 406.129498 -410.213278) (xy 406.106857 -410.163699)
			(xy 406.091502 -410.111402) (xy 406.083746 -410.057452) (xy 404.646089 -410.057452) (xy 404.638335 -410.111388)
			(xy 404.622983 -410.163676) (xy 404.600345 -410.213247) (xy 404.570884 -410.259092) (xy 404.535199 -410.300278)
			(xy 404.494016 -410.335966) (xy 404.448173 -410.365431) (xy 404.398604 -410.388072) (xy 404.346317 -410.403428)
			(xy 404.292378 -410.411188) (xy 404.26513 -410.411676) (xy 403.40153 -410.411676) (xy 403.374273 -410.411279)
			(xy 403.320315 -410.403525) (xy 403.268009 -410.38817) (xy 403.218421 -410.365528) (xy 403.17256 -410.336058)
			(xy 403.13136 -410.300361) (xy 403.09566 -410.259164) (xy 403.066187 -410.213306) (xy 403.04354 -410.163719)
			(xy 403.028181 -410.111415) (xy 403.020423 -410.057457) (xy 401.582912 -410.057457) (xy 401.575156 -410.111398)
			(xy 401.559801 -410.163693) (xy 401.53716 -410.213269) (xy 401.507693 -410.259119) (xy 401.472001 -410.300308)
			(xy 401.430811 -410.335999) (xy 401.38496 -410.365464) (xy 401.335383 -410.388104) (xy 401.283089 -410.403458)
			(xy 401.229141 -410.411213) (xy 401.20189 -410.411676) (xy 400.33829 -410.411676) (xy 400.311037 -410.411253)
			(xy 400.257086 -410.403495) (xy 400.204788 -410.388138) (xy 400.155208 -410.365494) (xy 400.109355 -410.336025)
			(xy 400.068162 -410.300331) (xy 400.032469 -410.259137) (xy 400.003001 -410.213283) (xy 399.980359 -410.163703)
			(xy 399.965003 -410.111404) (xy 399.957246 -410.057453) (xy 398.519713 -410.057453) (xy 398.511955 -410.111404)
			(xy 398.496598 -410.163701) (xy 398.473953 -410.21328) (xy 398.444483 -410.259132) (xy 398.408787 -410.300323)
			(xy 398.367592 -410.336013) (xy 398.321736 -410.365477) (xy 398.272154 -410.388115) (xy 398.219855 -410.403466)
			(xy 398.165903 -410.411216) (xy 398.13865 -410.411676) (xy 397.27505 -410.411676) (xy 397.247799 -410.411251)
			(xy 397.193852 -410.403488) (xy 397.141559 -410.388127) (xy 397.091984 -410.365481) (xy 397.046136 -410.336011)
			(xy 397.004948 -410.300317) (xy 396.969259 -410.259124) (xy 396.939795 -410.213272) (xy 396.917155 -410.163694)
			(xy 396.901802 -410.111399) (xy 396.894046 -410.057451) (xy 395.45639 -410.057451) (xy 395.448634 -410.111391)
			(xy 395.433281 -410.16368) (xy 395.410642 -410.213253) (xy 395.38118 -410.259099) (xy 395.345492 -410.300285)
			(xy 395.304307 -410.335974) (xy 395.258461 -410.365438) (xy 395.20889 -410.388077) (xy 395.156601 -410.403432)
			(xy 395.102658 -410.411189) (xy 395.07541 -410.411676) (xy 394.21181 -410.411676) (xy 394.184554 -410.411278)
			(xy 394.130598 -410.403521) (xy 394.078294 -410.388165) (xy 394.028709 -410.365521) (xy 393.98285 -410.336051)
			(xy 393.941653 -410.300354) (xy 393.905955 -410.259158) (xy 393.876484 -410.2133) (xy 393.853839 -410.163715)
			(xy 393.838481 -410.111412) (xy 393.830723 -410.057456) (xy 392.393212 -410.057456) (xy 392.385456 -410.111401)
			(xy 392.370099 -410.163697) (xy 392.347457 -410.213275) (xy 392.317988 -410.259126) (xy 392.282294 -410.300316)
			(xy 392.241101 -410.336006) (xy 392.195248 -410.365471) (xy 392.145669 -410.38811) (xy 392.093372 -410.403462)
			(xy 392.039422 -410.411215) (xy 392.01217 -410.411676) (xy 391.14857 -410.411676) (xy 391.121318 -410.411252)
			(xy 391.067369 -410.403491) (xy 391.015073 -410.388132) (xy 390.965496 -410.365488) (xy 390.919645 -410.336018)
			(xy 390.878455 -410.300324) (xy 390.842764 -410.259131) (xy 390.813298 -410.213278) (xy 390.790657 -410.163699)
			(xy 390.775302 -410.111402) (xy 390.767546 -410.057452) (xy 389.329889 -410.057452) (xy 389.322135 -410.111388)
			(xy 389.306783 -410.163676) (xy 389.284145 -410.213247) (xy 389.254684 -410.259092) (xy 389.218999 -410.300278)
			(xy 389.177816 -410.335966) (xy 389.131973 -410.365431) (xy 389.082404 -410.388072) (xy 389.030117 -410.403428)
			(xy 388.976178 -410.411188) (xy 388.94893 -410.411676) (xy 388.08533 -410.411676) (xy 388.058073 -410.411279)
			(xy 388.004115 -410.403525) (xy 387.951809 -410.38817) (xy 387.902221 -410.365528) (xy 387.85636 -410.336058)
			(xy 387.81516 -410.300361) (xy 387.77946 -410.259164) (xy 387.749987 -410.213306) (xy 387.72734 -410.163719)
			(xy 387.711981 -410.111415) (xy 387.704223 -410.057457) (xy 386.266712 -410.057457) (xy 386.258956 -410.111398)
			(xy 386.243601 -410.163693) (xy 386.22096 -410.213269) (xy 386.191493 -410.259119) (xy 386.155801 -410.300308)
			(xy 386.114611 -410.335999) (xy 386.06876 -410.365464) (xy 386.019183 -410.388104) (xy 385.966889 -410.403458)
			(xy 385.912941 -410.411213) (xy 385.88569 -410.411676) (xy 385.02209 -410.411676) (xy 384.994837 -410.411253)
			(xy 384.940886 -410.403495) (xy 384.888588 -410.388138) (xy 384.839008 -410.365494) (xy 384.793155 -410.336025)
			(xy 384.751962 -410.300331) (xy 384.716269 -410.259137) (xy 384.686801 -410.213283) (xy 384.664159 -410.163703)
			(xy 384.648803 -410.111404) (xy 384.641046 -410.057453) (xy 383.203513 -410.057453) (xy 383.195755 -410.111404)
			(xy 383.180398 -410.163701) (xy 383.157753 -410.21328) (xy 383.128283 -410.259132) (xy 383.092587 -410.300323)
			(xy 383.051392 -410.336013) (xy 383.005536 -410.365477) (xy 382.955954 -410.388115) (xy 382.903655 -410.403466)
			(xy 382.849703 -410.411216) (xy 382.82245 -410.411676) (xy 381.95885 -410.411676) (xy 381.931599 -410.411251)
			(xy 381.877652 -410.403488) (xy 381.825359 -410.388127) (xy 381.775784 -410.365481) (xy 381.729936 -410.336011)
			(xy 381.688748 -410.300317) (xy 381.653059 -410.259124) (xy 381.623595 -410.213272) (xy 381.600955 -410.163694)
			(xy 381.585602 -410.111399) (xy 381.577846 -410.057451) (xy 380.14019 -410.057451) (xy 380.132434 -410.111391)
			(xy 380.117081 -410.16368) (xy 380.094442 -410.213253) (xy 380.06498 -410.259099) (xy 380.029292 -410.300285)
			(xy 379.988107 -410.335974) (xy 379.942261 -410.365438) (xy 379.89269 -410.388077) (xy 379.840401 -410.403432)
			(xy 379.786458 -410.411189) (xy 379.75921 -410.411676) (xy 378.89561 -410.411676) (xy 378.868354 -410.411278)
			(xy 378.814398 -410.403521) (xy 378.762094 -410.388165) (xy 378.712509 -410.365521) (xy 378.66665 -410.336051)
			(xy 378.625453 -410.300354) (xy 378.589755 -410.259158) (xy 378.560284 -410.2133) (xy 378.537639 -410.163715)
			(xy 378.522281 -410.111412) (xy 378.514523 -410.057456) (xy 377.077012 -410.057456) (xy 377.069256 -410.111401)
			(xy 377.053899 -410.163697) (xy 377.031257 -410.213275) (xy 377.001788 -410.259126) (xy 376.966094 -410.300316)
			(xy 376.924901 -410.336006) (xy 376.879048 -410.365471) (xy 376.829469 -410.38811) (xy 376.777172 -410.403462)
			(xy 376.723222 -410.411215) (xy 376.69597 -410.411676) (xy 375.83237 -410.411676) (xy 375.805118 -410.411252)
			(xy 375.751169 -410.403491) (xy 375.698873 -410.388132) (xy 375.649296 -410.365488) (xy 375.603445 -410.336018)
			(xy 375.562255 -410.300324) (xy 375.526564 -410.259131) (xy 375.497098 -410.213278) (xy 375.474457 -410.163699)
			(xy 375.459102 -410.111402) (xy 375.451346 -410.057452) (xy 374.013689 -410.057452) (xy 374.005935 -410.111388)
			(xy 373.990583 -410.163676) (xy 373.967945 -410.213247) (xy 373.938484 -410.259092) (xy 373.902799 -410.300278)
			(xy 373.861616 -410.335966) (xy 373.815773 -410.365431) (xy 373.766204 -410.388072) (xy 373.713917 -410.403428)
			(xy 373.659978 -410.411188) (xy 373.63273 -410.411676) (xy 372.76913 -410.411676) (xy 372.741873 -410.411279)
			(xy 372.687915 -410.403525) (xy 372.635609 -410.38817) (xy 372.586021 -410.365528) (xy 372.54016 -410.336058)
			(xy 372.49896 -410.300361) (xy 372.46326 -410.259164) (xy 372.433787 -410.213306) (xy 372.41114 -410.163719)
			(xy 372.395781 -410.111415) (xy 372.388023 -410.057457) (xy 352.519512 -410.057457) (xy 352.511756 -410.111399)
			(xy 352.496401 -410.163693) (xy 352.473759 -410.21327) (xy 352.444293 -410.25912) (xy 352.408601 -410.300309)
			(xy 352.36741 -410.336) (xy 352.321559 -410.365465) (xy 352.271982 -410.388105) (xy 352.219687 -410.403459)
			(xy 352.165739 -410.411214) (xy 352.138488 -410.411676) (xy 351.274888 -410.411676) (xy 351.247635 -410.411253)
			(xy 351.193684 -410.403495) (xy 351.141386 -410.388137) (xy 351.091807 -410.365494) (xy 351.045954 -410.336025)
			(xy 351.004762 -410.30033) (xy 350.969068 -410.259137) (xy 350.939601 -410.213283) (xy 350.916958 -410.163702)
			(xy 350.901603 -410.111404) (xy 350.893846 -410.057453) (xy 349.456189 -410.057453) (xy 349.448435 -410.111386)
			(xy 349.433084 -410.163672) (xy 349.410448 -410.213242) (xy 349.380989 -410.259086) (xy 349.345306 -410.300272)
			(xy 349.304125 -410.33596) (xy 349.258284 -410.365425) (xy 349.208717 -410.388067) (xy 349.156433 -410.403425)
			(xy 349.102495 -410.411187) (xy 349.075248 -410.411676) (xy 348.211648 -410.411676) (xy 348.184391 -410.41128)
			(xy 348.13043 -410.403528) (xy 348.078122 -410.388175) (xy 348.028531 -410.365533) (xy 347.982668 -410.336064)
			(xy 347.941466 -410.300367) (xy 347.905765 -410.25917) (xy 347.87629 -410.213311) (xy 347.853642 -410.163723)
			(xy 347.838282 -410.111417) (xy 347.830523 -410.057457) (xy 346.392989 -410.057457) (xy 346.385234 -410.111391)
			(xy 346.369881 -410.163681) (xy 346.347242 -410.213253) (xy 346.317779 -410.259099) (xy 346.282091 -410.300286)
			(xy 346.240906 -410.335974) (xy 346.19506 -410.365438) (xy 346.145488 -410.388078) (xy 346.093199 -410.403432)
			(xy 346.039257 -410.411189) (xy 346.012008 -410.411676) (xy 345.148408 -410.411676) (xy 345.121152 -410.411278)
			(xy 345.067196 -410.403521) (xy 345.014893 -410.388164) (xy 344.965307 -410.36552) (xy 344.919449 -410.33605)
			(xy 344.878252 -410.300353) (xy 344.842555 -410.259157) (xy 344.813084 -410.2133) (xy 344.790439 -410.163715)
			(xy 344.775081 -410.111412) (xy 344.767323 -410.057456) (xy 343.329812 -410.057456) (xy 343.322055 -410.111401)
			(xy 343.306699 -410.163697) (xy 343.284056 -410.213275) (xy 343.254588 -410.259126) (xy 343.218894 -410.300316)
			(xy 343.177701 -410.336007) (xy 343.131847 -410.365472) (xy 343.082267 -410.38811) (xy 343.02997 -410.403462)
			(xy 342.97602 -410.411215) (xy 342.948768 -410.411676) (xy 342.085168 -410.411676) (xy 342.057916 -410.411252)
			(xy 342.003967 -410.403491) (xy 341.951672 -410.388132) (xy 341.902095 -410.365487) (xy 341.856244 -410.336017)
			(xy 341.815054 -410.300323) (xy 341.779363 -410.25913) (xy 341.749898 -410.213277) (xy 341.727257 -410.163698)
			(xy 341.711902 -410.111402) (xy 341.704146 -410.057452) (xy 340.266489 -410.057452) (xy 340.258735 -410.111388)
			(xy 340.243382 -410.163676) (xy 340.220745 -410.213248) (xy 340.191284 -410.259093) (xy 340.155599 -410.300279)
			(xy 340.114415 -410.335967) (xy 340.068572 -410.365432) (xy 340.019003 -410.388073) (xy 339.966716 -410.403429)
			(xy 339.912776 -410.411188) (xy 339.885528 -410.411676) (xy 339.021928 -410.411676) (xy 338.994672 -410.411279)
			(xy 338.940713 -410.403525) (xy 338.888407 -410.38817) (xy 338.838819 -410.365527) (xy 338.792959 -410.336057)
			(xy 338.751759 -410.30036) (xy 338.71606 -410.259164) (xy 338.686587 -410.213305) (xy 338.66394 -410.163719)
			(xy 338.648581 -410.111414) (xy 338.640823 -410.057456) (xy 337.203312 -410.057456) (xy 337.195556 -410.111399)
			(xy 337.180201 -410.163693) (xy 337.157559 -410.21327) (xy 337.128093 -410.25912) (xy 337.092401 -410.300309)
			(xy 337.05121 -410.336) (xy 337.005359 -410.365465) (xy 336.955782 -410.388105) (xy 336.903487 -410.403459)
			(xy 336.849539 -410.411214) (xy 336.822288 -410.411676) (xy 335.958688 -410.411676) (xy 335.931435 -410.411253)
			(xy 335.877484 -410.403495) (xy 335.825186 -410.388137) (xy 335.775607 -410.365494) (xy 335.729754 -410.336025)
			(xy 335.688562 -410.30033) (xy 335.652868 -410.259137) (xy 335.623401 -410.213283) (xy 335.600758 -410.163702)
			(xy 335.585403 -410.111404) (xy 335.577646 -410.057453) (xy 334.139989 -410.057453) (xy 334.132235 -410.111386)
			(xy 334.116884 -410.163672) (xy 334.094248 -410.213242) (xy 334.064789 -410.259086) (xy 334.029106 -410.300272)
			(xy 333.987925 -410.33596) (xy 333.942084 -410.365425) (xy 333.892517 -410.388067) (xy 333.840233 -410.403425)
			(xy 333.786295 -410.411187) (xy 333.759048 -410.411676) (xy 332.895448 -410.411676) (xy 332.868191 -410.41128)
			(xy 332.81423 -410.403528) (xy 332.761922 -410.388175) (xy 332.712331 -410.365533) (xy 332.666468 -410.336064)
			(xy 332.625266 -410.300367) (xy 332.589565 -410.25917) (xy 332.56009 -410.213311) (xy 332.537442 -410.163723)
			(xy 332.522082 -410.111417) (xy 332.514323 -410.057457) (xy 331.076789 -410.057457) (xy 331.069034 -410.111391)
			(xy 331.053681 -410.163681) (xy 331.031042 -410.213253) (xy 331.001579 -410.259099) (xy 330.965891 -410.300286)
			(xy 330.924706 -410.335974) (xy 330.87886 -410.365438) (xy 330.829288 -410.388078) (xy 330.776999 -410.403432)
			(xy 330.723057 -410.411189) (xy 330.695808 -410.411676) (xy 329.832208 -410.411676) (xy 329.804952 -410.411278)
			(xy 329.750996 -410.403521) (xy 329.698693 -410.388164) (xy 329.649107 -410.36552) (xy 329.603249 -410.33605)
			(xy 329.562052 -410.300353) (xy 329.526355 -410.259157) (xy 329.496884 -410.2133) (xy 329.474239 -410.163715)
			(xy 329.458881 -410.111412) (xy 329.451123 -410.057456) (xy 328.013612 -410.057456) (xy 328.005855 -410.111401)
			(xy 327.990499 -410.163697) (xy 327.967856 -410.213275) (xy 327.938388 -410.259126) (xy 327.902694 -410.300316)
			(xy 327.861501 -410.336007) (xy 327.815647 -410.365472) (xy 327.766067 -410.38811) (xy 327.71377 -410.403462)
			(xy 327.65982 -410.411215) (xy 327.632568 -410.411676) (xy 326.768968 -410.411676) (xy 326.741716 -410.411252)
			(xy 326.687767 -410.403491) (xy 326.635472 -410.388132) (xy 326.585895 -410.365487) (xy 326.540044 -410.336017)
			(xy 326.498854 -410.300323) (xy 326.463163 -410.25913) (xy 326.433698 -410.213277) (xy 326.411057 -410.163698)
			(xy 326.395702 -410.111402) (xy 326.387946 -410.057452) (xy 324.950289 -410.057452) (xy 324.942535 -410.111388)
			(xy 324.927182 -410.163676) (xy 324.904545 -410.213248) (xy 324.875084 -410.259093) (xy 324.839399 -410.300279)
			(xy 324.798215 -410.335967) (xy 324.752372 -410.365432) (xy 324.702803 -410.388073) (xy 324.650516 -410.403429)
			(xy 324.596576 -410.411188) (xy 324.569328 -410.411676) (xy 323.705728 -410.411676) (xy 323.678472 -410.411279)
			(xy 323.624513 -410.403525) (xy 323.572207 -410.38817) (xy 323.522619 -410.365527) (xy 323.476759 -410.336057)
			(xy 323.435559 -410.30036) (xy 323.39986 -410.259164) (xy 323.370387 -410.213305) (xy 323.34774 -410.163719)
			(xy 323.332381 -410.111414) (xy 323.324623 -410.057456) (xy 321.887112 -410.057456) (xy 321.879356 -410.111399)
			(xy 321.864001 -410.163693) (xy 321.841359 -410.21327) (xy 321.811893 -410.25912) (xy 321.776201 -410.300309)
			(xy 321.73501 -410.336) (xy 321.689159 -410.365465) (xy 321.639582 -410.388105) (xy 321.587287 -410.403459)
			(xy 321.533339 -410.411214) (xy 321.506088 -410.411676) (xy 320.642488 -410.411676) (xy 320.615235 -410.411253)
			(xy 320.561284 -410.403495) (xy 320.508986 -410.388137) (xy 320.459407 -410.365494) (xy 320.413554 -410.336025)
			(xy 320.372362 -410.30033) (xy 320.336668 -410.259137) (xy 320.307201 -410.213283) (xy 320.284558 -410.163702)
			(xy 320.269203 -410.111404) (xy 320.261446 -410.057453) (xy 318.823789 -410.057453) (xy 318.816035 -410.111386)
			(xy 318.800684 -410.163672) (xy 318.778048 -410.213242) (xy 318.748589 -410.259086) (xy 318.712906 -410.300272)
			(xy 318.671725 -410.33596) (xy 318.625884 -410.365425) (xy 318.576317 -410.388067) (xy 318.524033 -410.403425)
			(xy 318.470095 -410.411187) (xy 318.442848 -410.411676) (xy 317.579248 -410.411676) (xy 317.551991 -410.41128)
			(xy 317.49803 -410.403528) (xy 317.445722 -410.388175) (xy 317.396131 -410.365533) (xy 317.350268 -410.336064)
			(xy 317.309066 -410.300367) (xy 317.273365 -410.25917) (xy 317.24389 -410.213311) (xy 317.221242 -410.163723)
			(xy 317.205882 -410.111417) (xy 317.198123 -410.057457) (xy 315.760589 -410.057457) (xy 315.752834 -410.111391)
			(xy 315.737481 -410.163681) (xy 315.714842 -410.213253) (xy 315.685379 -410.259099) (xy 315.649691 -410.300286)
			(xy 315.608506 -410.335974) (xy 315.56266 -410.365438) (xy 315.513088 -410.388078) (xy 315.460799 -410.403432)
			(xy 315.406857 -410.411189) (xy 315.379608 -410.411676) (xy 314.516008 -410.411676) (xy 314.488752 -410.411278)
			(xy 314.434796 -410.403521) (xy 314.382493 -410.388164) (xy 314.332907 -410.36552) (xy 314.287049 -410.33605)
			(xy 314.245852 -410.300353) (xy 314.210155 -410.259157) (xy 314.180684 -410.2133) (xy 314.158039 -410.163715)
			(xy 314.142681 -410.111412) (xy 314.134923 -410.057456) (xy 312.697412 -410.057456) (xy 312.689655 -410.111401)
			(xy 312.674299 -410.163697) (xy 312.651656 -410.213275) (xy 312.622188 -410.259126) (xy 312.586494 -410.300316)
			(xy 312.545301 -410.336007) (xy 312.499447 -410.365472) (xy 312.449867 -410.38811) (xy 312.39757 -410.403462)
			(xy 312.34362 -410.411215) (xy 312.316368 -410.411676) (xy 311.452768 -410.411676) (xy 311.425516 -410.411252)
			(xy 311.371567 -410.403491) (xy 311.319272 -410.388132) (xy 311.269695 -410.365487) (xy 311.223844 -410.336017)
			(xy 311.182654 -410.300323) (xy 311.146963 -410.25913) (xy 311.117498 -410.213277) (xy 311.094857 -410.163698)
			(xy 311.079502 -410.111402) (xy 311.071746 -410.057452) (xy 309.634089 -410.057452) (xy 309.626335 -410.111388)
			(xy 309.610982 -410.163676) (xy 309.588345 -410.213248) (xy 309.558884 -410.259093) (xy 309.523199 -410.300279)
			(xy 309.482015 -410.335967) (xy 309.436172 -410.365432) (xy 309.386603 -410.388073) (xy 309.334316 -410.403429)
			(xy 309.280376 -410.411188) (xy 309.253128 -410.411676) (xy 308.389528 -410.411676) (xy 308.362272 -410.411279)
			(xy 308.308313 -410.403525) (xy 308.256007 -410.38817) (xy 308.206419 -410.365527) (xy 308.160559 -410.336057)
			(xy 308.119359 -410.30036) (xy 308.08366 -410.259164) (xy 308.054187 -410.213305) (xy 308.03154 -410.163719)
			(xy 308.016181 -410.111414) (xy 308.008423 -410.057456) (xy 306.570912 -410.057456) (xy 306.563156 -410.111399)
			(xy 306.547801 -410.163693) (xy 306.525159 -410.21327) (xy 306.495693 -410.25912) (xy 306.460001 -410.300309)
			(xy 306.41881 -410.336) (xy 306.372959 -410.365465) (xy 306.323382 -410.388105) (xy 306.271087 -410.403459)
			(xy 306.217139 -410.411214) (xy 306.189888 -410.411676) (xy 305.326288 -410.411676) (xy 305.299035 -410.411253)
			(xy 305.245084 -410.403495) (xy 305.192786 -410.388137) (xy 305.143207 -410.365494) (xy 305.097354 -410.336025)
			(xy 305.056162 -410.30033) (xy 305.020468 -410.259137) (xy 304.991001 -410.213283) (xy 304.968358 -410.163702)
			(xy 304.953003 -410.111404) (xy 304.945246 -410.057453) (xy 280.83256 -410.057453) (xy 280.83256 -415.172652)
			(xy 280.832075 -415.197601) (xy 280.824257 -415.246884) (xy 280.808837 -415.294341) (xy 280.786193 -415.338807)
			(xy 280.756881 -415.37919) (xy 280.739596 -415.397188) (xy 280.152348 -415.984436) (xy 280.134386 -416.001764)
			(xy 280.094003 -416.03109) (xy 280.04953 -416.053738) (xy 280.002061 -416.069148) (xy 279.952766 -416.076943)
			(xy 279.927812 -416.0774) (xy 275.812504 -416.0774) (xy 270.721328 -421.168576) (xy 270.703321 -421.185853)
			(xy 270.662948 -421.21518) (xy 270.618486 -421.23783) (xy 270.571027 -421.253247) (xy 270.521742 -421.261051)
			(xy 270.496792 -421.26154) (xy 233.321352 -421.26154) (xy 231.01554 -423.567352) (xy 231.01554 -424.804386)
			(xy 357.679233 -424.804386) (xy 357.679233 -424.675246) (xy 357.687183 -424.546351) (xy 357.703053 -424.418191)
			(xy 357.726782 -424.29125) (xy 357.758281 -424.166011) (xy 357.79743 -424.042948) (xy 357.844081 -423.922529)
			(xy 357.898056 -423.80521) (xy 357.959151 -423.691436) (xy 358.027134 -423.581639) (xy 358.101748 -423.476236)
			(xy 358.182709 -423.375626) (xy 358.269709 -423.280191) (xy 358.36242 -423.190292) (xy 358.46049 -423.106271)
			(xy 358.563545 -423.028447) (xy 358.671196 -422.957115) (xy 358.783035 -422.892545) (xy 358.898636 -422.834983)
			(xy 359.017561 -422.784646) (xy 359.13936 -422.741726) (xy 359.26357 -422.706385) (xy 359.389719 -422.678758)
			(xy 359.517331 -422.658949) (xy 359.64592 -422.647033) (xy 359.774998 -422.643057) (xy 359.904076 -422.647033)
			(xy 360.032665 -422.658949) (xy 360.160277 -422.678758) (xy 360.286426 -422.706385) (xy 360.410636 -422.741726)
			(xy 360.532435 -422.784646) (xy 360.65136 -422.834983) (xy 360.766961 -422.892545) (xy 360.8788 -422.957115)
			(xy 360.986451 -423.028447) (xy 361.089506 -423.106271) (xy 361.187576 -423.190292) (xy 361.280287 -423.280191)
			(xy 361.367287 -423.375626) (xy 361.448248 -423.476236) (xy 361.522862 -423.581639) (xy 361.590845 -423.691436)
			(xy 361.65194 -423.80521) (xy 361.705915 -423.922529) (xy 361.752566 -424.042948) (xy 361.791715 -424.166011)
			(xy 361.823214 -424.29125) (xy 361.846943 -424.418191) (xy 361.853367 -424.470068) (xy 421.270176 -424.470068)
			(xy 421.270176 -417.770056) (xy 421.270681 -417.664527) (xy 421.278765 -417.453623) (xy 421.294922 -417.243184)
			(xy 421.319127 -417.033518) (xy 421.351345 -416.824934) (xy 421.391528 -416.617736) (xy 421.439619 -416.412229)
			(xy 421.495545 -416.208716) (xy 421.559226 -416.007493) (xy 421.630567 -415.808858) (xy 421.709464 -415.613101)
			(xy 421.795802 -415.420509) (xy 421.889452 -415.231366) (xy 421.990279 -415.045949) (xy 422.098134 -414.864529)
			(xy 422.212858 -414.687374) (xy 422.334284 -414.514743) (xy 422.462233 -414.34689) (xy 422.596517 -414.184061)
			(xy 422.73694 -414.026495) (xy 422.883295 -413.874423) (xy 423.035367 -413.728068) (xy 423.192933 -413.587645)
			(xy 423.355762 -413.453361) (xy 423.523615 -413.325412) (xy 423.696246 -413.203986) (xy 423.873401 -413.089262)
			(xy 424.054821 -412.981407) (xy 424.240238 -412.88058) (xy 424.429381 -412.78693) (xy 424.621973 -412.700592)
			(xy 424.81773 -412.621695) (xy 425.016365 -412.550354) (xy 425.217588 -412.486673) (xy 425.421101 -412.430747)
			(xy 425.626608 -412.382656) (xy 425.833806 -412.342473) (xy 426.04239 -412.310255) (xy 426.252056 -412.28605)
			(xy 426.462495 -412.269893) (xy 426.673399 -412.261809) (xy 426.884457 -412.261809) (xy 427.095361 -412.269893)
			(xy 427.3058 -412.28605) (xy 427.515466 -412.310255) (xy 427.72405 -412.342473) (xy 427.931248 -412.382656)
			(xy 428.136755 -412.430747) (xy 428.340268 -412.486673) (xy 428.541491 -412.550354) (xy 428.740126 -412.621695)
			(xy 428.935883 -412.700592) (xy 429.128475 -412.78693) (xy 429.317618 -412.88058) (xy 429.503035 -412.981407)
			(xy 429.684455 -413.089262) (xy 429.86161 -413.203986) (xy 430.034241 -413.325412) (xy 430.202094 -413.453361)
			(xy 430.364923 -413.587645) (xy 430.522489 -413.728068) (xy 430.674561 -413.874423) (xy 430.820916 -414.026495)
			(xy 430.961339 -414.184061) (xy 431.095623 -414.34689) (xy 431.223572 -414.514743) (xy 431.344998 -414.687374)
			(xy 431.459722 -414.864529) (xy 431.567577 -415.045949) (xy 431.668404 -415.231366) (xy 431.762054 -415.420509)
			(xy 431.848392 -415.613101) (xy 431.927289 -415.808858) (xy 431.99863 -416.007493) (xy 432.062311 -416.208716)
			(xy 432.118237 -416.412229) (xy 432.166328 -416.617736) (xy 432.206511 -416.824934) (xy 432.238729 -417.033518)
			(xy 432.262934 -417.243184) (xy 432.279091 -417.453623) (xy 432.287175 -417.664527) (xy 432.28768 -417.770056)
			(xy 432.28768 -424.470068) (xy 432.287175 -424.575597) (xy 432.279091 -424.786501) (xy 432.262934 -424.99694)
			(xy 432.238729 -425.206606) (xy 432.206511 -425.41519) (xy 432.166328 -425.622388) (xy 432.118237 -425.827895)
			(xy 432.062311 -426.031408) (xy 431.99863 -426.232631) (xy 431.927289 -426.431266) (xy 431.848392 -426.627023)
			(xy 431.762054 -426.819615) (xy 431.668404 -427.008758) (xy 431.567577 -427.194175) (xy 431.459722 -427.375595)
			(xy 431.344998 -427.55275) (xy 431.223572 -427.725381) (xy 431.095623 -427.893234) (xy 430.961339 -428.056063)
			(xy 430.820916 -428.213629) (xy 430.674561 -428.365701) (xy 430.522489 -428.512056) (xy 430.364923 -428.652479)
			(xy 430.202094 -428.786763) (xy 430.034241 -428.914712) (xy 429.86161 -429.036138) (xy 429.684455 -429.150862)
			(xy 429.503035 -429.258717) (xy 429.317618 -429.359544) (xy 429.128475 -429.453194) (xy 428.935883 -429.539532)
			(xy 428.740126 -429.618429) (xy 428.541491 -429.68977) (xy 428.340268 -429.753451) (xy 428.136755 -429.809377)
			(xy 427.931248 -429.857468) (xy 427.72405 -429.897651) (xy 427.515466 -429.929869) (xy 427.3058 -429.954074)
			(xy 427.095361 -429.970231) (xy 426.884457 -429.978315) (xy 426.673399 -429.978315) (xy 426.462495 -429.970231)
			(xy 426.252056 -429.954074) (xy 426.04239 -429.929869) (xy 425.833806 -429.897651) (xy 425.626608 -429.857468)
			(xy 425.421101 -429.809377) (xy 425.217588 -429.753451) (xy 425.016365 -429.68977) (xy 424.81773 -429.618429)
			(xy 424.621973 -429.539532) (xy 424.429381 -429.453194) (xy 424.240238 -429.359544) (xy 424.054821 -429.258717)
			(xy 423.873401 -429.150862) (xy 423.696246 -429.036138) (xy 423.523615 -428.914712) (xy 423.355762 -428.786763)
			(xy 423.192933 -428.652479) (xy 423.035367 -428.512056) (xy 422.883295 -428.365701) (xy 422.73694 -428.213629)
			(xy 422.596517 -428.056063) (xy 422.462233 -427.893234) (xy 422.334284 -427.725381) (xy 422.212858 -427.55275)
			(xy 422.098134 -427.375595) (xy 421.990279 -427.194175) (xy 421.889452 -427.008758) (xy 421.795802 -426.819615)
			(xy 421.709464 -426.627023) (xy 421.630567 -426.431266) (xy 421.559226 -426.232631) (xy 421.495545 -426.031408)
			(xy 421.439619 -425.827895) (xy 421.391528 -425.622388) (xy 421.351345 -425.41519) (xy 421.319127 -425.206606)
			(xy 421.294922 -424.99694) (xy 421.278765 -424.786501) (xy 421.270681 -424.575597) (xy 421.270176 -424.470068)
			(xy 361.853367 -424.470068) (xy 361.862813 -424.546351) (xy 361.870763 -424.675246) (xy 361.87126 -424.739816)
			(xy 361.870763 -424.804386) (xy 361.862813 -424.933281) (xy 361.846943 -425.061441) (xy 361.823214 -425.188382)
			(xy 361.791715 -425.313621) (xy 361.752566 -425.436684) (xy 361.705915 -425.557103) (xy 361.65194 -425.674422)
			(xy 361.590845 -425.788196) (xy 361.522862 -425.897993) (xy 361.448248 -426.003396) (xy 361.367287 -426.104006)
			(xy 361.280287 -426.199441) (xy 361.187576 -426.28934) (xy 361.089506 -426.373361) (xy 360.986451 -426.451185)
			(xy 360.8788 -426.522517) (xy 360.766961 -426.587087) (xy 360.65136 -426.644649) (xy 360.532435 -426.694986)
			(xy 360.410636 -426.737906) (xy 360.286426 -426.773247) (xy 360.160277 -426.800874) (xy 360.032665 -426.820683)
			(xy 359.904076 -426.832599) (xy 359.774998 -426.836576) (xy 359.64592 -426.832599) (xy 359.517331 -426.820683)
			(xy 359.389719 -426.800874) (xy 359.26357 -426.773247) (xy 359.13936 -426.737906) (xy 359.017561 -426.694986)
			(xy 358.898636 -426.644649) (xy 358.783035 -426.587087) (xy 358.671196 -426.522517) (xy 358.563545 -426.451185)
			(xy 358.46049 -426.373361) (xy 358.36242 -426.28934) (xy 358.269709 -426.199441) (xy 358.182709 -426.104006)
			(xy 358.101748 -426.003396) (xy 358.027134 -425.897993) (xy 357.959151 -425.788196) (xy 357.898056 -425.674422)
			(xy 357.844081 -425.557103) (xy 357.79743 -425.436684) (xy 357.758281 -425.313621) (xy 357.726782 -425.188382)
			(xy 357.703053 -425.061441) (xy 357.687183 -424.933281) (xy 357.679233 -424.804386) (xy 231.01554 -424.804386)
			(xy 231.01554 -427.289976) (xy 314.118498 -427.289976) (xy 314.118995 -427.25742) (xy 314.126943 -427.192795)
			(xy 314.142729 -427.129626) (xy 314.166116 -427.068859) (xy 314.196754 -427.011407) (xy 314.234184 -426.958128)
			(xy 314.277844 -426.909824) (xy 314.30214 -426.888148) (xy 314.382912 -426.723302) (xy 314.387599 -426.71278)
			(xy 314.391094 -426.690025) (xy 314.387614 -426.667268) (xy 314.382912 -426.656754) (xy 314.301886 -426.491654)
			(xy 314.277618 -426.469963) (xy 314.234022 -426.421629) (xy 314.196648 -426.368337) (xy 314.166056 -426.310884)
			(xy 314.142701 -426.250127) (xy 314.126934 -426.186975) (xy 314.11899 -426.122371) (xy 314.118498 -426.089826)
			(xy 314.119217 -426.050501) (xy 314.130827 -425.972711) (xy 314.141612 -425.934886) (xy 314.141612 -425.419012)
			(xy 314.142023 -425.406928) (xy 314.14949 -425.383942) (xy 314.163696 -425.36439) (xy 314.183249 -425.350186)
			(xy 314.206236 -425.342722) (xy 314.21832 -425.342304) (xy 315.15812 -425.342304) (xy 315.170197 -425.342748)
			(xy 315.193167 -425.350217) (xy 315.212704 -425.364419) (xy 315.226898 -425.383962) (xy 315.234357 -425.406935)
			(xy 315.234828 -425.419012) (xy 315.234828 -427.960536) (xy 315.234367 -427.97261) (xy 315.226897 -427.995576)
			(xy 315.212699 -428.01511) (xy 315.193161 -428.029304) (xy 315.170195 -428.036769) (xy 315.15812 -428.037244)
			(xy 314.21832 -428.037244) (xy 314.20625 -428.036719) (xy 314.18329 -428.029267) (xy 314.163755 -428.015085)
			(xy 314.149559 -427.995561) (xy 314.142089 -427.972606) (xy 314.141612 -427.960536) (xy 314.141612 -427.444916)
			(xy 314.130808 -427.407096) (xy 314.119205 -427.329303) (xy 314.118498 -427.289976) (xy 231.01554 -427.289976)
			(xy 231.01554 -428.28972) (xy 316.118494 -428.28972) (xy 316.119031 -428.257141) (xy 316.127002 -428.192471)
			(xy 316.142815 -428.12926) (xy 316.166234 -428.068455) (xy 316.196906 -428.010967) (xy 316.234373 -427.957658)
			(xy 316.278073 -427.909326) (xy 316.30239 -427.887638) (xy 316.382908 -427.7233) (xy 316.387597 -427.712779)
			(xy 316.391091 -427.690023) (xy 316.387611 -427.667266) (xy 316.382908 -427.656752) (xy 316.301882 -427.491652)
			(xy 316.277613 -427.469963) (xy 316.234017 -427.421628) (xy 316.196643 -427.368336) (xy 316.166051 -427.310883)
			(xy 316.142697 -427.250126) (xy 316.12693 -427.186974) (xy 316.118985 -427.122369) (xy 316.118494 -427.089824)
			(xy 316.119213 -427.050499) (xy 316.130823 -426.972709) (xy 316.141608 -426.934884) (xy 316.141608 -426.41901)
			(xy 316.142115 -426.406924) (xy 316.149565 -426.383929) (xy 316.163743 -426.364352) (xy 316.183266 -426.3501)
			(xy 316.206232 -426.342562) (xy 316.218316 -426.342048) (xy 317.158116 -426.342048) (xy 317.170221 -426.342502)
			(xy 317.193239 -426.349999) (xy 317.212808 -426.364253) (xy 317.227004 -426.383863) (xy 317.234433 -426.406904)
			(xy 317.234824 -426.41901) (xy 317.234824 -427.289976) (xy 318.11849 -427.289976) (xy 318.118956 -427.257419)
			(xy 318.126905 -427.192792) (xy 318.142694 -427.129621) (xy 318.166086 -427.068853) (xy 318.196729 -427.0114)
			(xy 318.234166 -426.958124) (xy 318.277833 -426.909822) (xy 318.302132 -426.888148) (xy 318.382904 -426.723302)
			(xy 318.387592 -426.71278) (xy 318.391087 -426.690025) (xy 318.387607 -426.667268) (xy 318.382904 -426.656754)
			(xy 318.301878 -426.491654) (xy 318.277609 -426.469964) (xy 318.234013 -426.42163) (xy 318.19664 -426.368338)
			(xy 318.166047 -426.310884) (xy 318.142693 -426.250128) (xy 318.126926 -426.186975) (xy 318.118982 -426.122371)
			(xy 318.11849 -426.089826) (xy 318.119209 -426.050501) (xy 318.13082 -425.972711) (xy 318.141604 -425.934886)
			(xy 318.141604 -425.419012) (xy 318.142023 -425.406929) (xy 318.149489 -425.383944) (xy 318.163693 -425.364393)
			(xy 318.183244 -425.350189) (xy 318.206229 -425.342723) (xy 318.218312 -425.342304) (xy 319.158112 -425.342304)
			(xy 319.170188 -425.342754) (xy 319.193158 -425.350222) (xy 319.212696 -425.364421) (xy 319.226889 -425.383964)
			(xy 319.234349 -425.406935) (xy 319.23482 -425.419012) (xy 319.23482 -427.960536) (xy 319.234367 -427.972611)
			(xy 319.226896 -427.995578) (xy 319.212696 -428.015113) (xy 319.193156 -428.029307) (xy 319.170187 -428.036771)
			(xy 319.158112 -428.037244) (xy 318.218312 -428.037244) (xy 318.206242 -428.036726) (xy 318.183281 -428.029271)
			(xy 318.163747 -428.015087) (xy 318.149551 -427.995562) (xy 318.142081 -427.972606) (xy 318.141604 -427.960536)
			(xy 318.141604 -427.444916) (xy 318.1308 -427.407096) (xy 318.119197 -427.329303) (xy 318.11849 -427.289976)
			(xy 317.234824 -427.289976) (xy 317.234824 -428.28972) (xy 320.118486 -428.28972) (xy 320.119026 -428.257141)
			(xy 320.126997 -428.192472) (xy 320.14281 -428.129261) (xy 320.166228 -428.068456) (xy 320.1969 -428.010968)
			(xy 320.234366 -427.957658) (xy 320.278066 -427.909326) (xy 320.302382 -427.887638) (xy 320.3829 -427.7233)
			(xy 320.387589 -427.712779) (xy 320.391084 -427.690023) (xy 320.387603 -427.667266) (xy 320.3829 -427.656752)
			(xy 320.301874 -427.491652) (xy 320.277603 -427.469964) (xy 320.234007 -427.42163) (xy 320.196634 -427.368337)
			(xy 320.166042 -427.310883) (xy 320.142688 -427.250126) (xy 320.126922 -427.186974) (xy 320.118977 -427.122369)
			(xy 320.118486 -427.089824) (xy 320.119205 -427.050499) (xy 320.130816 -426.972709) (xy 320.1416 -426.934884)
			(xy 320.1416 -426.41901) (xy 320.142115 -426.406925) (xy 320.149564 -426.383931) (xy 320.16374 -426.364355)
			(xy 320.183261 -426.350103) (xy 320.206225 -426.342563) (xy 320.218308 -426.342048) (xy 321.158108 -426.342048)
			(xy 321.170212 -426.342509) (xy 321.193231 -426.350004) (xy 321.212799 -426.364256) (xy 321.226996 -426.383865)
			(xy 321.234425 -426.406905) (xy 321.234816 -426.41901) (xy 321.234816 -427.289976) (xy 322.118482 -427.289976)
			(xy 322.118951 -427.257419) (xy 322.1269 -427.192792) (xy 322.142688 -427.129621) (xy 322.16608 -427.068854)
			(xy 322.196723 -427.011401) (xy 322.234159 -426.958124) (xy 322.277825 -426.909822) (xy 322.302124 -426.888148)
			(xy 322.382896 -426.723302) (xy 322.387584 -426.71278) (xy 322.391079 -426.690025) (xy 322.387599 -426.667268)
			(xy 322.382896 -426.656754) (xy 322.30187 -426.491654) (xy 322.277619 -426.469944) (xy 322.234019 -426.421616)
			(xy 322.196641 -426.368328) (xy 322.166045 -426.310878) (xy 322.142688 -426.250124) (xy 322.126919 -426.186973)
			(xy 322.118974 -426.122371) (xy 322.118482 -426.089826) (xy 322.119202 -426.050501) (xy 322.130812 -425.972711)
			(xy 322.141596 -425.934886) (xy 322.141596 -425.419012) (xy 322.142023 -425.40693) (xy 322.149488 -425.383947)
			(xy 322.16369 -425.364396) (xy 322.183239 -425.350191) (xy 322.206222 -425.342724) (xy 322.218304 -425.342304)
			(xy 323.158104 -425.342304) (xy 323.170188 -425.342709) (xy 323.193173 -425.350179) (xy 323.212724 -425.364387)
			(xy 323.226928 -425.383941) (xy 323.234393 -425.406928) (xy 323.234812 -425.419012) (xy 323.234812 -427.960536)
			(xy 323.234367 -427.972612) (xy 323.226895 -427.99558) (xy 323.212693 -428.015116) (xy 323.193151 -428.029309)
			(xy 323.17018 -428.036772) (xy 323.158104 -428.037244) (xy 322.218304 -428.037244) (xy 322.206233 -428.036733)
			(xy 322.183272 -428.029276) (xy 322.163738 -428.01509) (xy 322.149542 -427.995564) (xy 322.142073 -427.972607)
			(xy 322.141596 -427.960536) (xy 322.141596 -427.444916) (xy 322.130792 -427.407096) (xy 322.119188 -427.329303)
			(xy 322.118482 -427.289976) (xy 321.234816 -427.289976) (xy 321.234816 -428.28972) (xy 324.118478 -428.28972)
			(xy 324.11902 -428.257141) (xy 324.126991 -428.192472) (xy 324.142804 -428.129261) (xy 324.166222 -428.068456)
			(xy 324.196893 -428.010968) (xy 324.234359 -427.957659) (xy 324.278058 -427.909326) (xy 324.302374 -427.887638)
			(xy 324.382892 -427.7233) (xy 324.387582 -427.712779) (xy 324.391077 -427.690023) (xy 324.387596 -427.667266)
			(xy 324.382892 -427.656752) (xy 324.301866 -427.491652) (xy 324.277614 -427.469944) (xy 324.234013 -427.421615)
			(xy 324.196636 -427.368327) (xy 324.16604 -427.310877) (xy 324.142684 -427.250122) (xy 324.126915 -427.186972)
			(xy 324.11897 -427.122369) (xy 324.118478 -427.089824) (xy 324.119197 -427.050499) (xy 324.130808 -426.972709)
			(xy 324.141592 -426.934884) (xy 324.141592 -426.41901) (xy 324.142115 -426.406926) (xy 324.149563 -426.383934)
			(xy 324.163737 -426.364358) (xy 324.183256 -426.350105) (xy 324.206218 -426.342564) (xy 324.2183 -426.342048)
			(xy 325.1581 -426.342048) (xy 325.170204 -426.342515) (xy 325.193222 -426.350009) (xy 325.212791 -426.364259)
			(xy 325.226987 -426.383866) (xy 325.234417 -426.406905) (xy 325.234808 -426.41901) (xy 325.234808 -427.289976)
			(xy 326.118474 -427.289976) (xy 326.118945 -427.257419) (xy 326.126894 -427.192792) (xy 326.142682 -427.129621)
			(xy 326.166073 -427.068854) (xy 326.196716 -427.011401) (xy 326.234151 -426.958124) (xy 326.277817 -426.909822)
			(xy 326.302116 -426.888148) (xy 326.382888 -426.723302) (xy 326.387576 -426.71278) (xy 326.391072 -426.690025)
			(xy 326.387592 -426.667268) (xy 326.382888 -426.656754) (xy 326.301862 -426.491654) (xy 326.27761 -426.469946)
			(xy 326.23401 -426.421617) (xy 326.196633 -426.368329) (xy 326.166037 -426.310878) (xy 326.14268 -426.250124)
			(xy 326.126911 -426.186974) (xy 326.118966 -426.122371) (xy 326.118474 -426.089826) (xy 326.119194 -426.050501)
			(xy 326.130804 -425.972711) (xy 326.141588 -425.934886) (xy 326.141588 -425.419012) (xy 326.142023 -425.40693)
			(xy 326.149487 -425.383949) (xy 326.163687 -425.364399) (xy 326.183234 -425.350194) (xy 326.206214 -425.342726)
			(xy 326.218296 -425.342304) (xy 327.158096 -425.342304) (xy 327.17018 -425.342716) (xy 327.193164 -425.350184)
			(xy 327.212716 -425.36439) (xy 327.22692 -425.383943) (xy 327.234385 -425.406928) (xy 327.234804 -425.419012)
			(xy 327.234804 -427.960536) (xy 327.234367 -427.972613) (xy 327.226894 -427.995582) (xy 327.21269 -428.015119)
			(xy 327.193146 -428.029312) (xy 327.170173 -428.036773) (xy 327.158096 -428.037244) (xy 326.218296 -428.037244)
			(xy 326.206225 -428.03674) (xy 326.183264 -428.02928) (xy 326.16373 -428.015093) (xy 326.149534 -427.995565)
			(xy 326.142065 -427.972607) (xy 326.141588 -427.960536) (xy 326.141588 -427.444916) (xy 326.130784 -427.407096)
			(xy 326.11918 -427.329303) (xy 326.118474 -427.289976) (xy 325.234808 -427.289976) (xy 325.234808 -428.28972)
			(xy 328.11847 -428.28972) (xy 328.119015 -428.257141) (xy 328.126986 -428.192472) (xy 328.142799 -428.129262)
			(xy 328.166216 -428.068457) (xy 328.196887 -428.010969) (xy 328.234352 -427.957659) (xy 328.27805 -427.909326)
			(xy 328.302366 -427.887638) (xy 328.382884 -427.7233) (xy 328.387574 -427.712779) (xy 328.39107 -427.690023)
			(xy 328.387588 -427.667266) (xy 328.382884 -427.656752) (xy 328.301858 -427.491652) (xy 328.277604 -427.469946)
			(xy 328.234004 -427.421616) (xy 328.196627 -427.368328) (xy 328.166032 -427.310877) (xy 328.142675 -427.250123)
			(xy 328.126907 -427.186972) (xy 328.118962 -427.122369) (xy 328.11847 -427.089824) (xy 328.11919 -427.050499)
			(xy 328.1308 -426.972709) (xy 328.141584 -426.934884) (xy 328.141584 -426.41901) (xy 328.142017 -426.406917)
			(xy 328.149476 -426.383909) (xy 328.16367 -426.364325) (xy 328.183214 -426.350076) (xy 328.2062 -426.342551)
			(xy 328.218292 -426.342048) (xy 329.158092 -426.342048) (xy 329.170195 -426.342522) (xy 329.193214 -426.350013)
			(xy 329.212782 -426.364262) (xy 329.226979 -426.383868) (xy 329.234409 -426.406906) (xy 329.2348 -426.41901)
			(xy 329.2348 -427.289976) (xy 331.118464 -427.289976) (xy 331.118938 -427.257419) (xy 331.126887 -427.192793)
			(xy 331.142675 -427.129622) (xy 331.166066 -427.068855) (xy 331.196708 -427.011402) (xy 331.234142 -426.958125)
			(xy 331.277808 -426.909822) (xy 331.302106 -426.888148) (xy 331.382878 -426.723302) (xy 331.387567 -426.71278)
			(xy 331.391063 -426.690025) (xy 331.387582 -426.667268) (xy 331.382878 -426.656754) (xy 331.301852 -426.491654)
			(xy 331.277598 -426.469948) (xy 331.233998 -426.421618) (xy 331.196621 -426.36833) (xy 331.166026 -426.310879)
			(xy 331.14267 -426.250124) (xy 331.126901 -426.186974) (xy 331.118956 -426.122371) (xy 331.118464 -426.089826)
			(xy 331.119168 -426.0507) (xy 331.13064 -425.973293) (xy 331.141324 -425.935648) (xy 331.141324 -425.419012)
			(xy 331.141727 -425.406901) (xy 331.149226 -425.38387) (xy 331.16349 -425.364295) (xy 331.183116 -425.350101)
			(xy 331.206174 -425.342684) (xy 331.218286 -425.342304) (xy 332.158086 -425.342304) (xy 332.170171 -425.342819)
			(xy 332.193165 -425.350267) (xy 332.212742 -425.364443) (xy 332.226995 -425.383964) (xy 332.234533 -425.406929)
			(xy 332.235048 -425.419012) (xy 332.235048 -427.960536) (xy 332.234615 -427.972642) (xy 332.227111 -427.995662)
			(xy 332.212852 -428.01523) (xy 332.193238 -428.029426) (xy 332.170193 -428.036854) (xy 332.158086 -428.037244)
			(xy 331.218286 -428.037244) (xy 331.206194 -428.036804) (xy 331.18319 -428.029342) (xy 331.163609 -428.015149)
			(xy 331.14936 -427.995609) (xy 331.141831 -427.972627) (xy 331.141324 -427.960536) (xy 331.141324 -427.444154)
			(xy 331.130632 -427.40651) (xy 331.119158 -427.329103) (xy 331.118464 -427.289976) (xy 329.2348 -427.289976)
			(xy 329.2348 -428.28972) (xy 333.11846 -428.28972) (xy 333.118975 -428.25714) (xy 333.126947 -428.192469)
			(xy 333.142763 -428.129257) (xy 333.166184 -428.068451) (xy 333.19686 -428.010963) (xy 333.234332 -427.957654)
			(xy 333.278037 -427.909324) (xy 333.302356 -427.887638) (xy 333.382874 -427.7233) (xy 333.387565 -427.712779)
			(xy 333.391061 -427.690023) (xy 333.387579 -427.667266) (xy 333.382874 -427.656752) (xy 333.301848 -427.491652)
			(xy 333.277592 -427.469948) (xy 333.233993 -427.421618) (xy 333.196616 -427.368329) (xy 333.166021 -427.310878)
			(xy 333.142665 -427.250123) (xy 333.126897 -427.186972) (xy 333.118952 -427.122369) (xy 333.11846 -427.089824)
			(xy 333.119164 -427.050698) (xy 333.130636 -426.973291) (xy 333.14132 -426.935646) (xy 333.14132 -426.41901)
			(xy 333.14182 -426.406898) (xy 333.149302 -426.383858) (xy 333.163538 -426.364258) (xy 333.183133 -426.350015)
			(xy 333.20617 -426.342525) (xy 333.218282 -426.342048) (xy 334.158082 -426.342048) (xy 334.170205 -426.342475)
			(xy 334.193265 -426.349964) (xy 334.212881 -426.364213) (xy 334.227132 -426.383828) (xy 334.234623 -426.406887)
			(xy 334.235044 -426.41901) (xy 334.235044 -427.289976) (xy 335.118456 -427.289976) (xy 335.118933 -427.257419)
			(xy 335.126882 -427.192793) (xy 335.14267 -427.129623) (xy 335.16606 -427.068855) (xy 335.196701 -427.011402)
			(xy 335.234135 -426.958125) (xy 335.2778 -426.909822) (xy 335.302098 -426.888148) (xy 335.38287 -426.723302)
			(xy 335.387559 -426.712781) (xy 335.391056 -426.690025) (xy 335.387575 -426.667268) (xy 335.38287 -426.656754)
			(xy 335.301844 -426.491654) (xy 335.277588 -426.46995) (xy 335.233989 -426.42162) (xy 335.196613 -426.368331)
			(xy 335.166018 -426.31088) (xy 335.142661 -426.250125) (xy 335.126893 -426.186974) (xy 335.118948 -426.122371)
			(xy 335.118456 -426.089826) (xy 335.119161 -426.0507) (xy 335.130632 -425.973293) (xy 335.141316 -425.935648)
			(xy 335.141316 -425.419012) (xy 335.141727 -425.406902) (xy 335.149225 -425.383873) (xy 335.163487 -425.364298)
			(xy 335.183111 -425.350104) (xy 335.206167 -425.342685) (xy 335.218278 -425.342304) (xy 336.158078 -425.342304)
			(xy 336.170163 -425.342825) (xy 336.193157 -425.350272) (xy 336.212734 -425.364446) (xy 336.226986 -425.383966)
			(xy 336.234525 -425.406929) (xy 336.23504 -425.419012) (xy 336.23504 -427.960536) (xy 336.234615 -427.972643)
			(xy 336.22711 -427.995664) (xy 336.21285 -428.015233) (xy 336.193233 -428.029428) (xy 336.170186 -428.036855)
			(xy 336.158078 -428.037244) (xy 335.218278 -428.037244) (xy 335.206186 -428.036811) (xy 335.183182 -428.029347)
			(xy 335.163601 -428.015152) (xy 335.149351 -427.99561) (xy 335.141823 -427.972627) (xy 335.141316 -427.960536)
			(xy 335.141316 -427.444154) (xy 335.130624 -427.40651) (xy 335.11915 -427.329103) (xy 335.118456 -427.289976)
			(xy 334.235044 -427.289976) (xy 334.235044 -428.28972) (xy 337.118452 -428.28972) (xy 337.118969 -428.25714)
			(xy 337.126942 -428.192469) (xy 337.142757 -428.129257) (xy 337.166178 -428.068451) (xy 337.196854 -428.010963)
			(xy 337.234325 -427.957655) (xy 337.278029 -427.909325) (xy 337.302348 -427.887638) (xy 337.382866 -427.7233)
			(xy 337.387552 -427.712778) (xy 337.391044 -427.690023) (xy 337.387566 -427.667267) (xy 337.382866 -427.656752)
			(xy 337.30184 -427.491652) (xy 337.277582 -427.46995) (xy 337.233983 -427.421619) (xy 337.196607 -427.36833)
			(xy 337.166013 -427.310879) (xy 337.142657 -427.250123) (xy 337.126888 -427.186972) (xy 337.118944 -427.122369)
			(xy 337.118452 -427.089824) (xy 337.119157 -427.050698) (xy 337.130628 -426.973291) (xy 337.141312 -426.935646)
			(xy 337.141312 -426.41901) (xy 337.14182 -426.406899) (xy 337.149301 -426.38386) (xy 337.163535 -426.36426)
			(xy 337.183128 -426.350018) (xy 337.206163 -426.342526) (xy 337.218274 -426.342048) (xy 338.158074 -426.342048)
			(xy 338.170196 -426.342482) (xy 338.193256 -426.349969) (xy 338.212872 -426.364216) (xy 338.227124 -426.38383)
			(xy 338.234615 -426.406888) (xy 338.235036 -426.41901) (xy 338.235036 -427.289976) (xy 339.118448 -427.289976)
			(xy 339.118928 -427.257419) (xy 339.126876 -427.192793) (xy 339.142664 -427.129623) (xy 339.166054 -427.068856)
			(xy 339.196695 -427.011403) (xy 339.234128 -426.958126) (xy 339.277792 -426.909823) (xy 339.30209 -426.888148)
			(xy 339.382862 -426.723302) (xy 339.387547 -426.712779) (xy 339.391039 -426.690025) (xy 339.387562 -426.667269)
			(xy 339.382862 -426.656754) (xy 339.301836 -426.491654) (xy 339.277579 -426.469951) (xy 339.23398 -426.421621)
			(xy 339.196604 -426.368332) (xy 339.166009 -426.31088) (xy 339.142653 -426.250125) (xy 339.126885 -426.186974)
			(xy 339.11894 -426.122371) (xy 339.118448 -426.089826) (xy 339.119153 -426.0507) (xy 339.130624 -425.973293)
			(xy 339.141308 -425.935648) (xy 339.141308 -425.419012) (xy 339.141727 -425.406903) (xy 339.149224 -425.383875)
			(xy 339.163485 -425.364301) (xy 339.183106 -425.350106) (xy 339.20616 -425.342687) (xy 339.21827 -425.342304)
			(xy 340.15807 -425.342304) (xy 340.170154 -425.342832) (xy 340.193148 -425.350276) (xy 340.212725 -425.364448)
			(xy 340.226978 -425.383967) (xy 340.234517 -425.40693) (xy 340.235032 -425.419012) (xy 340.235032 -427.960536)
			(xy 340.234615 -427.972644) (xy 340.227109 -427.995667) (xy 340.212847 -428.015236) (xy 340.193228 -428.029431)
			(xy 340.170179 -428.036856) (xy 340.15807 -428.037244) (xy 339.21827 -428.037244) (xy 339.206177 -428.036818)
			(xy 339.183173 -428.029351) (xy 339.163592 -428.015154) (xy 339.149343 -427.995612) (xy 339.141815 -427.972627)
			(xy 339.141308 -427.960536) (xy 339.141308 -427.444154) (xy 339.130615 -427.40651) (xy 339.119142 -427.329103)
			(xy 339.118448 -427.289976) (xy 338.235036 -427.289976) (xy 338.235036 -428.28972) (xy 341.118444 -428.28972)
			(xy 341.118956 -428.257164) (xy 341.1269 -428.19254) (xy 341.142682 -428.12937) (xy 341.166066 -428.068603)
			(xy 341.196703 -428.01115) (xy 341.234131 -427.957872) (xy 341.277791 -427.909568) (xy 341.302086 -427.887892)
			(xy 341.382858 -427.723046) (xy 341.387582 -427.712539) (xy 341.39106 -427.689775) (xy 341.387567 -427.667013)
			(xy 341.382858 -427.656498) (xy 341.302086 -427.491652) (xy 341.277781 -427.469987) (xy 341.23413 -427.421675)
			(xy 341.196706 -427.368392) (xy 341.166071 -427.310938) (xy 341.142684 -427.250171) (xy 341.126894 -427.187003)
			(xy 341.118937 -427.12238) (xy 341.118444 -427.089824) (xy 341.119149 -427.050698) (xy 341.13062 -426.973291)
			(xy 341.141304 -426.935646) (xy 341.141304 -426.418756) (xy 341.141679 -426.406644) (xy 341.149191 -426.383615)
			(xy 341.163463 -426.364042) (xy 341.183093 -426.349849) (xy 341.206153 -426.342431) (xy 341.218266 -426.342048)
			(xy 342.158066 -426.342048) (xy 342.170155 -426.342536) (xy 342.193155 -426.349985) (xy 342.212737 -426.364166)
			(xy 342.226988 -426.383695) (xy 342.234519 -426.406669) (xy 342.235028 -426.418756) (xy 342.235028 -427.289976)
			(xy 343.11844 -427.289976) (xy 343.118922 -427.257419) (xy 343.126871 -427.192794) (xy 343.142658 -427.129623)
			(xy 343.166048 -427.068856) (xy 343.196688 -427.011404) (xy 343.234121 -426.958126) (xy 343.277785 -426.909823)
			(xy 343.302082 -426.888148) (xy 343.382854 -426.723302) (xy 343.387539 -426.71278) (xy 343.391032 -426.690025)
			(xy 343.387554 -426.667269) (xy 343.382854 -426.656754) (xy 343.301828 -426.491654) (xy 343.277569 -426.469953)
			(xy 343.233971 -426.421622) (xy 343.196595 -426.368333) (xy 343.166001 -426.310881) (xy 343.142645 -426.250126)
			(xy 343.126877 -426.186974) (xy 343.118932 -426.122371) (xy 343.11844 -426.089826) (xy 343.119145 -426.0507)
			(xy 343.130616 -425.973293) (xy 343.1413 -425.935648) (xy 343.1413 -425.419012) (xy 343.141727 -425.406904)
			(xy 343.149223 -425.383877) (xy 343.163482 -425.364304) (xy 343.183101 -425.350109) (xy 343.206152 -425.342688)
			(xy 343.218262 -425.342304) (xy 344.158062 -425.342304) (xy 344.170146 -425.342839) (xy 344.193139 -425.350281)
			(xy 344.212717 -425.364451) (xy 344.22697 -425.383968) (xy 344.234509 -425.40693) (xy 344.235024 -425.419012)
			(xy 344.235024 -427.960536) (xy 344.234615 -427.972644) (xy 344.227108 -427.995669) (xy 344.212844 -428.015239)
			(xy 344.193223 -428.029433) (xy 344.170172 -428.036857) (xy 344.158062 -428.037244) (xy 343.218262 -428.037244)
			(xy 343.206169 -428.036825) (xy 343.183164 -428.029356) (xy 343.163584 -428.015157) (xy 343.149335 -427.995613)
			(xy 343.141807 -427.972628) (xy 343.1413 -427.960536) (xy 343.1413 -427.444154) (xy 343.130607 -427.40651)
			(xy 343.119134 -427.329103) (xy 343.11844 -427.289976) (xy 342.235028 -427.289976) (xy 342.235028 -428.28972)
			(xy 345.118436 -428.28972) (xy 345.118959 -428.25714) (xy 345.126931 -428.19247) (xy 345.142746 -428.129258)
			(xy 345.166166 -428.068452) (xy 345.196841 -428.010965) (xy 345.234311 -427.957656) (xy 345.278014 -427.909325)
			(xy 345.302332 -427.887638) (xy 345.38285 -427.7233) (xy 345.387537 -427.712778) (xy 345.391029 -427.690023)
			(xy 345.387551 -427.667267) (xy 345.38285 -427.656752) (xy 345.301824 -427.491652) (xy 345.277563 -427.469953)
			(xy 345.233965 -427.421622) (xy 345.19659 -427.368332) (xy 345.165996 -427.31088) (xy 345.14264 -427.250124)
			(xy 345.126872 -427.186973) (xy 345.118927 -427.122369) (xy 345.118436 -427.089824) (xy 345.119141 -427.050698)
			(xy 345.130612 -426.973291) (xy 345.141296 -426.935646) (xy 345.141296 -426.41901) (xy 345.14182 -426.4069)
			(xy 345.149299 -426.383864) (xy 345.163529 -426.364266) (xy 345.183118 -426.350023) (xy 345.206148 -426.342528)
			(xy 345.218258 -426.342048) (xy 346.158058 -426.342048) (xy 346.17018 -426.342496) (xy 346.193239 -426.349978)
			(xy 346.212855 -426.364222) (xy 346.227108 -426.383833) (xy 346.234599 -426.406889) (xy 346.23502 -426.41901)
			(xy 346.23502 -427.289976) (xy 381.237998 -427.289976) (xy 381.238088 -427.275402) (xy 381.239743 -427.246301)
			(xy 381.2413 -427.23181) (xy 381.2413 -426.147992) (xy 381.239757 -426.1335) (xy 381.238104 -426.1044)
			(xy 381.237998 -426.089826) (xy 381.238093 -426.075252) (xy 381.239744 -426.046151) (xy 381.2413 -426.03166)
			(xy 381.2413 -425.419012) (xy 381.241727 -425.406904) (xy 381.249223 -425.383877) (xy 381.263482 -425.364304)
			(xy 381.283101 -425.350109) (xy 381.306152 -425.342688) (xy 381.318262 -425.342304) (xy 382.258062 -425.342304)
			(xy 382.270146 -425.342839) (xy 382.293139 -425.350281) (xy 382.312717 -425.364451) (xy 382.32697 -425.383968)
			(xy 382.334509 -425.40693) (xy 382.335024 -425.419012) (xy 382.335024 -427.960536) (xy 382.334615 -427.972644)
			(xy 382.327108 -427.995669) (xy 382.312844 -428.015239) (xy 382.293223 -428.029433) (xy 382.270172 -428.036857)
			(xy 382.258062 -428.037244) (xy 381.318262 -428.037244) (xy 381.306169 -428.036825) (xy 381.283164 -428.029356)
			(xy 381.263584 -428.015157) (xy 381.249335 -427.995613) (xy 381.241807 -427.972628) (xy 381.2413 -427.960536)
			(xy 381.2413 -427.348142) (xy 381.239753 -427.33365) (xy 381.238103 -427.30455) (xy 381.237998 -427.289976)
			(xy 346.23502 -427.289976) (xy 346.23502 -428.960534) (xy 346.234669 -428.972663) (xy 346.227162 -428.99573)
			(xy 346.212894 -429.015348) (xy 346.193262 -429.029597) (xy 346.170187 -429.03708) (xy 346.158058 -429.037496)
			(xy 345.218258 -429.037496) (xy 345.206145 -429.037025) (xy 345.183106 -429.02953) (xy 345.163508 -429.015287)
			(xy 345.149266 -428.995687) (xy 345.141774 -428.972647) (xy 345.141296 -428.960534) (xy 345.141296 -428.443898)
			(xy 345.130613 -428.406252) (xy 345.119133 -428.328846) (xy 345.118436 -428.28972) (xy 342.235028 -428.28972)
			(xy 342.235028 -428.96028) (xy 342.234567 -428.972385) (xy 342.227076 -428.995407) (xy 342.212825 -429.014978)
			(xy 342.193215 -429.029174) (xy 342.170172 -429.0366) (xy 342.158066 -429.036988) (xy 341.218266 -429.036988)
			(xy 341.206177 -429.036522) (xy 341.18318 -429.02906) (xy 341.163603 -429.014872) (xy 341.149353 -428.99534)
			(xy 341.141817 -428.972367) (xy 341.141304 -428.96028) (xy 341.141304 -428.443898) (xy 341.130621 -428.406252)
			(xy 341.119141 -428.328846) (xy 341.118444 -428.28972) (xy 338.235036 -428.28972) (xy 338.235036 -428.960534)
			(xy 338.234617 -428.972653) (xy 338.227117 -428.995702) (xy 338.212862 -429.015305) (xy 338.193248 -429.029545)
			(xy 338.170193 -429.037026) (xy 338.158074 -429.037496) (xy 337.218274 -429.037496) (xy 337.206161 -429.037011)
			(xy 337.183123 -429.029521) (xy 337.163525 -429.015281) (xy 337.149283 -428.995684) (xy 337.14179 -428.972646)
			(xy 337.141312 -428.960534) (xy 337.141312 -428.443898) (xy 337.130629 -428.406252) (xy 337.119149 -428.328846)
			(xy 337.118452 -428.28972) (xy 334.235044 -428.28972) (xy 334.235044 -428.960534) (xy 334.234617 -428.972652)
			(xy 334.227118 -428.9957) (xy 334.212865 -429.015302) (xy 334.193253 -429.029542) (xy 334.1702 -429.037025)
			(xy 334.158082 -429.037496) (xy 333.218282 -429.037496) (xy 333.20617 -429.037004) (xy 333.183132 -429.029516)
			(xy 333.163533 -429.015278) (xy 333.149291 -428.995683) (xy 333.141798 -428.972646) (xy 333.14132 -428.960534)
			(xy 333.14132 -428.443898) (xy 333.130637 -428.406252) (xy 333.119157 -428.328846) (xy 333.11846 -428.28972)
			(xy 329.2348 -428.28972) (xy 329.2348 -428.960534) (xy 329.234322 -428.972621) (xy 329.226861 -428.995616)
			(xy 329.212676 -429.015192) (xy 329.193148 -429.029443) (xy 329.170178 -429.036981) (xy 329.158092 -429.037496)
			(xy 328.218292 -429.037496) (xy 328.206182 -429.037091) (xy 328.183154 -429.029588) (xy 328.163581 -429.015324)
			(xy 328.149386 -428.9957) (xy 328.141967 -428.972645) (xy 328.141584 -428.960534) (xy 328.141584 -428.44466)
			(xy 328.130788 -428.406838) (xy 328.119179 -428.329046) (xy 328.11847 -428.28972) (xy 325.234808 -428.28972)
			(xy 325.234808 -428.960534) (xy 325.234323 -428.972621) (xy 325.226862 -428.995614) (xy 325.212679 -429.01519)
			(xy 325.193153 -429.029441) (xy 325.170185 -429.03698) (xy 325.1581 -429.037496) (xy 324.2183 -429.037496)
			(xy 324.206191 -429.037084) (xy 324.183163 -429.029584) (xy 324.163589 -429.015321) (xy 324.149395 -428.995699)
			(xy 324.141975 -428.972645) (xy 324.141592 -428.960534) (xy 324.141592 -428.44466) (xy 324.130797 -428.406837)
			(xy 324.119188 -428.329046) (xy 324.118478 -428.28972) (xy 321.234816 -428.28972) (xy 321.234816 -428.960534)
			(xy 321.234421 -428.97263) (xy 321.226949 -428.995639) (xy 321.212746 -429.015222) (xy 321.193195 -429.02947)
			(xy 321.170203 -429.036993) (xy 321.158108 -429.037496) (xy 320.218308 -429.037496) (xy 320.206199 -429.037077)
			(xy 320.183171 -429.029579) (xy 320.163598 -429.015319) (xy 320.149403 -428.995697) (xy 320.141983 -428.972644)
			(xy 320.1416 -428.960534) (xy 320.1416 -428.44466) (xy 320.130805 -428.406837) (xy 320.119196 -428.329046)
			(xy 320.118486 -428.28972) (xy 317.234824 -428.28972) (xy 317.234824 -428.960534) (xy 317.234421 -428.972629)
			(xy 317.226951 -428.995637) (xy 317.212749 -429.015219) (xy 317.1932 -429.029467) (xy 317.17021 -429.036992)
			(xy 317.158116 -429.037496) (xy 316.218316 -429.037496) (xy 316.206208 -429.03707) (xy 316.18318 -429.029574)
			(xy 316.163607 -429.015315) (xy 316.149412 -428.995695) (xy 316.141991 -428.972644) (xy 316.141608 -428.960534)
			(xy 316.141608 -428.44466) (xy 316.130813 -428.406837) (xy 316.119204 -428.329046) (xy 316.118494 -428.28972)
			(xy 231.01554 -428.28972) (xy 231.01554 -433.130695) (xy 266.885917 -433.130695) (xy 266.885917 -432.953425)
			(xy 266.89387 -432.776334) (xy 266.909761 -432.599778) (xy 266.933556 -432.424113) (xy 266.965209 -432.249692)
			(xy 267.004655 -432.076867) (xy 267.051815 -431.905986) (xy 267.106594 -431.737392) (xy 267.168882 -431.571427)
			(xy 267.238554 -431.408422) (xy 267.315468 -431.248708) (xy 267.399471 -431.092605) (xy 267.490392 -430.940428)
			(xy 267.588049 -430.792484) (xy 267.692246 -430.64907) (xy 267.802772 -430.510475) (xy 267.919404 -430.376978)
			(xy 268.041909 -430.248849) (xy 268.170038 -430.126344) (xy 268.303535 -430.009712) (xy 268.44213 -429.899186)
			(xy 268.585544 -429.794989) (xy 268.733488 -429.697332) (xy 268.885665 -429.606411) (xy 269.041768 -429.522408)
			(xy 269.201482 -429.445494) (xy 269.364487 -429.375822) (xy 269.530452 -429.313534) (xy 269.699046 -429.258755)
			(xy 269.869927 -429.211595) (xy 270.042752 -429.172149) (xy 270.217173 -429.140496) (xy 270.392838 -429.116701)
			(xy 270.569394 -429.10081) (xy 270.746485 -429.092857) (xy 270.923755 -429.092857) (xy 271.100846 -429.10081)
			(xy 271.277402 -429.116701) (xy 271.453067 -429.140496) (xy 271.627488 -429.172149) (xy 271.800313 -429.211595)
			(xy 271.971194 -429.258755) (xy 272.139788 -429.313534) (xy 272.305753 -429.375822) (xy 272.468758 -429.445494)
			(xy 272.628472 -429.522408) (xy 272.784575 -429.606411) (xy 272.936752 -429.697332) (xy 273.084696 -429.794989)
			(xy 273.22811 -429.899186) (xy 273.366705 -430.009712) (xy 273.500202 -430.126344) (xy 273.628331 -430.248849)
			(xy 273.750836 -430.376978) (xy 273.867468 -430.510475) (xy 273.977994 -430.64907) (xy 274.082191 -430.792484)
			(xy 274.146507 -430.889918) (xy 314.138056 -430.889918) (xy 314.138165 -430.874832) (xy 314.139947 -430.844714)
			(xy 314.141612 -430.82972) (xy 314.141612 -429.749966) (xy 314.139947 -429.734972) (xy 314.138166 -429.704854)
			(xy 314.138056 -429.689768) (xy 314.13817 -429.674682) (xy 314.139948 -429.644564) (xy 314.141612 -429.62957)
			(xy 314.141612 -429.018954) (xy 314.142068 -429.006865) (xy 314.149534 -428.983867) (xy 314.163724 -428.964291)
			(xy 314.183258 -428.950041) (xy 314.206232 -428.942505) (xy 314.21832 -428.941992) (xy 315.15812 -428.941992)
			(xy 315.170229 -428.942399) (xy 315.193256 -428.949903) (xy 315.212828 -428.964167) (xy 315.227022 -428.98379)
			(xy 315.234444 -429.006843) (xy 315.234828 -429.018954) (xy 315.234828 -431.560478) (xy 315.234373 -431.57257)
			(xy 315.226919 -431.595575) (xy 315.21273 -431.615158) (xy 315.193192 -431.629408) (xy 315.17021 -431.636935)
			(xy 315.15812 -431.63744) (xy 314.21832 -431.63744) (xy 314.206216 -431.636967) (xy 314.183196 -431.629478)
			(xy 314.163627 -431.61523) (xy 314.14943 -431.595622) (xy 314.142001 -431.572583) (xy 314.141612 -431.560478)
			(xy 314.141612 -430.950116) (xy 314.139943 -430.935123) (xy 314.138165 -430.905004) (xy 314.138056 -430.889918)
			(xy 274.146507 -430.889918) (xy 274.179848 -430.940428) (xy 274.270769 -431.092605) (xy 274.354772 -431.248708)
			(xy 274.431686 -431.408422) (xy 274.501358 -431.571427) (xy 274.563646 -431.737392) (xy 274.613204 -431.889916)
			(xy 316.138052 -431.889916) (xy 316.138161 -431.87483) (xy 316.139943 -431.844712) (xy 316.141608 -431.829718)
			(xy 316.141608 -430.749964) (xy 316.139943 -430.73497) (xy 316.138162 -430.704852) (xy 316.138052 -430.689766)
			(xy 316.138166 -430.67468) (xy 316.139944 -430.644562) (xy 316.141608 -430.629568) (xy 316.141608 -430.018952)
			(xy 316.142023 -430.006873) (xy 316.149501 -429.983902) (xy 316.16371 -429.964364) (xy 316.183259 -429.950172)
			(xy 316.206237 -429.942713) (xy 316.218316 -429.942244) (xy 317.158116 -429.942244) (xy 317.170187 -429.94275)
			(xy 317.193146 -429.950211) (xy 317.212679 -429.964399) (xy 317.226874 -429.983925) (xy 317.234345 -430.006882)
			(xy 317.234824 -430.018952) (xy 317.234824 -430.889918) (xy 318.138048 -430.889918) (xy 318.138157 -430.874832)
			(xy 318.139939 -430.844714) (xy 318.141604 -430.82972) (xy 318.141604 -429.749966) (xy 318.139939 -429.734972)
			(xy 318.138158 -429.704854) (xy 318.138048 -429.689768) (xy 318.138162 -429.674682) (xy 318.13994 -429.644564)
			(xy 318.141604 -429.62957) (xy 318.141604 -429.018954) (xy 318.142067 -429.006866) (xy 318.149532 -428.98387)
			(xy 318.163721 -428.964293) (xy 318.183253 -428.950043) (xy 318.206225 -428.942506) (xy 318.218312 -428.941992)
			(xy 319.158112 -428.941992) (xy 319.170221 -428.942406) (xy 319.193247 -428.949908) (xy 319.212819 -428.96417)
			(xy 319.227014 -428.983792) (xy 319.234436 -429.006844) (xy 319.23482 -429.018954) (xy 319.23482 -431.560478)
			(xy 319.234373 -431.57257) (xy 319.226918 -431.595577) (xy 319.212727 -431.615161) (xy 319.193187 -431.629411)
			(xy 319.170203 -431.636936) (xy 319.158112 -431.63744) (xy 318.218312 -431.63744) (xy 318.206208 -431.636974)
			(xy 318.183188 -431.629483) (xy 318.163618 -431.615232) (xy 318.149422 -431.595624) (xy 318.141993 -431.572583)
			(xy 318.141604 -431.560478) (xy 318.141604 -430.950116) (xy 318.139935 -430.935123) (xy 318.138157 -430.905004)
			(xy 318.138048 -430.889918) (xy 317.234824 -430.889918) (xy 317.234824 -431.889916) (xy 320.138044 -431.889916)
			(xy 320.138153 -431.87483) (xy 320.139935 -431.844712) (xy 320.1416 -431.829718) (xy 320.1416 -430.749964)
			(xy 320.139935 -430.73497) (xy 320.138154 -430.704852) (xy 320.138044 -430.689766) (xy 320.138158 -430.67468)
			(xy 320.139936 -430.644562) (xy 320.1416 -430.629568) (xy 320.1416 -430.018952) (xy 320.142023 -430.006874)
			(xy 320.1495 -429.983904) (xy 320.163707 -429.964367) (xy 320.183254 -429.950174) (xy 320.20623 -429.942714)
			(xy 320.218308 -429.942244) (xy 321.158108 -429.942244) (xy 321.170178 -429.942757) (xy 321.193137 -429.950216)
			(xy 321.21267 -429.964401) (xy 321.226866 -429.983927) (xy 321.234337 -430.006882) (xy 321.234816 -430.018952)
			(xy 321.234816 -430.889918) (xy 322.13804 -430.889918) (xy 322.138151 -430.874832) (xy 322.139933 -430.844714)
			(xy 322.141596 -430.82972) (xy 322.141596 -429.749966) (xy 322.139931 -429.734972) (xy 322.13815 -429.704854)
			(xy 322.13804 -429.689768) (xy 322.138154 -429.674682) (xy 322.139932 -429.644564) (xy 322.141596 -429.62957)
			(xy 322.141596 -429.018954) (xy 322.142067 -429.006866) (xy 322.149531 -428.983872) (xy 322.163718 -428.964296)
			(xy 322.183248 -428.950046) (xy 322.206218 -428.942507) (xy 322.218304 -428.941992) (xy 323.158104 -428.941992)
			(xy 323.170212 -428.942413) (xy 323.193238 -428.949912) (xy 323.212811 -428.964173) (xy 323.227006 -428.983793)
			(xy 323.234428 -429.006844) (xy 323.234812 -429.018954) (xy 323.234812 -431.560478) (xy 323.234373 -431.572571)
			(xy 323.226916 -431.595579) (xy 323.212724 -431.615164) (xy 323.193182 -431.629413) (xy 323.170196 -431.636937)
			(xy 323.158104 -431.63744) (xy 322.218304 -431.63744) (xy 322.206199 -431.636981) (xy 322.183179 -431.629488)
			(xy 322.163609 -431.615236) (xy 322.149413 -431.595625) (xy 322.141985 -431.572584) (xy 322.141596 -431.560478)
			(xy 322.141596 -430.950116) (xy 322.139927 -430.935123) (xy 322.138149 -430.905004) (xy 322.13804 -430.889918)
			(xy 321.234816 -430.889918) (xy 321.234816 -431.889916) (xy 324.138036 -431.889916) (xy 324.138147 -431.87483)
			(xy 324.139929 -431.844712) (xy 324.141592 -431.829718) (xy 324.141592 -430.749964) (xy 324.139927 -430.73497)
			(xy 324.138146 -430.704852) (xy 324.138036 -430.689766) (xy 324.138152 -430.674681) (xy 324.13993 -430.644562)
			(xy 324.141592 -430.629568) (xy 324.141592 -430.018952) (xy 324.142023 -430.006875) (xy 324.149499 -429.983906)
			(xy 324.163704 -429.96437) (xy 324.183249 -429.950177) (xy 324.206223 -429.942716) (xy 324.2183 -429.942244)
			(xy 325.1581 -429.942244) (xy 325.17017 -429.942764) (xy 325.193129 -429.95022) (xy 325.212662 -429.964404)
			(xy 325.226858 -429.983928) (xy 325.234329 -430.006883) (xy 325.234808 -430.018952) (xy 325.234808 -430.889918)
			(xy 326.138032 -430.889918) (xy 326.138143 -430.874832) (xy 326.139925 -430.844714) (xy 326.141588 -430.82972)
			(xy 326.141588 -429.749966) (xy 326.139923 -429.734972) (xy 326.138142 -429.704854) (xy 326.138032 -429.689768)
			(xy 326.138148 -429.674683) (xy 326.139926 -429.644564) (xy 326.141588 -429.62957) (xy 326.141588 -429.018954)
			(xy 326.141969 -429.006857) (xy 326.149444 -428.983847) (xy 326.163651 -428.964264) (xy 326.183205 -428.950016)
			(xy 326.2062 -428.942494) (xy 326.218296 -428.941992) (xy 327.158096 -428.941992) (xy 327.170204 -428.942419)
			(xy 327.19323 -428.949917) (xy 327.212802 -428.964176) (xy 327.226997 -428.983795) (xy 327.23442 -429.006845)
			(xy 327.234804 -429.018954) (xy 327.234804 -431.560478) (xy 327.234275 -431.572562) (xy 327.226829 -431.595555)
			(xy 327.212657 -431.615131) (xy 327.19314 -431.629384) (xy 327.170178 -431.636924) (xy 327.158096 -431.63744)
			(xy 326.218296 -431.63744) (xy 326.206191 -431.636988) (xy 326.18317 -431.629492) (xy 326.163601 -431.615238)
			(xy 326.149405 -431.595627) (xy 326.141977 -431.572584) (xy 326.141588 -431.560478) (xy 326.141588 -430.950116)
			(xy 326.139919 -430.935123) (xy 326.138141 -430.905004) (xy 326.138032 -430.889918) (xy 325.234808 -430.889918)
			(xy 325.234808 -431.889916) (xy 328.138028 -431.889916) (xy 328.138139 -431.87483) (xy 328.139921 -431.844712)
			(xy 328.141584 -431.829718) (xy 328.141584 -430.749964) (xy 328.139919 -430.73497) (xy 328.138138 -430.704852)
			(xy 328.138028 -430.689766) (xy 328.138144 -430.674681) (xy 328.139922 -430.644562) (xy 328.141584 -430.629568)
			(xy 328.141584 -430.018952) (xy 328.142023 -430.006876) (xy 328.149498 -429.983908) (xy 328.163701 -429.964373)
			(xy 328.183244 -429.95018) (xy 328.206215 -429.942717) (xy 328.218292 -429.942244) (xy 329.158092 -429.942244)
			(xy 329.170161 -429.94277) (xy 329.19312 -429.950225) (xy 329.212653 -429.964407) (xy 329.22685 -429.98393)
			(xy 329.234321 -430.006883) (xy 329.2348 -430.018952) (xy 329.2348 -430.889918) (xy 331.138022 -430.889918)
			(xy 331.138116 -430.875344) (xy 331.139768 -430.846243) (xy 331.141324 -430.831752) (xy 331.141324 -429.747934)
			(xy 331.139776 -429.733442) (xy 331.138126 -429.704342) (xy 331.138022 -429.689768) (xy 331.138121 -429.675194)
			(xy 331.13977 -429.646093) (xy 331.141324 -429.631602) (xy 331.141324 -429.018954) (xy 331.141772 -429.006838)
			(xy 331.14927 -428.983796) (xy 331.163519 -428.964196) (xy 331.183125 -428.949956) (xy 331.20617 -428.942467)
			(xy 331.218286 -428.941992) (xy 332.158086 -428.941992) (xy 332.170195 -428.942523) (xy 332.19323 -428.950001)
			(xy 332.212828 -428.964229) (xy 332.227072 -428.983816) (xy 332.234568 -429.006845) (xy 332.235048 -429.018954)
			(xy 332.235048 -431.560478) (xy 332.234621 -431.572601) (xy 332.227133 -431.595662) (xy 332.212884 -431.615278)
			(xy 332.193269 -431.62953) (xy 332.170209 -431.63702) (xy 332.158086 -431.63744) (xy 331.218286 -431.63744)
			(xy 331.20616 -431.637051) (xy 331.183097 -431.629553) (xy 331.163481 -431.615294) (xy 331.149231 -431.59567)
			(xy 331.141743 -431.572604) (xy 331.141324 -431.560478) (xy 331.141324 -430.948084) (xy 331.139781 -430.933592)
			(xy 331.138128 -430.904492) (xy 331.138022 -430.889918) (xy 329.2348 -430.889918) (xy 329.2348 -431.889916)
			(xy 333.138018 -431.889916) (xy 333.138112 -431.875342) (xy 333.139764 -431.846241) (xy 333.14132 -431.83175)
			(xy 333.14132 -430.747932) (xy 333.139772 -430.73344) (xy 333.138122 -430.70434) (xy 333.138018 -430.689766)
			(xy 333.138117 -430.675192) (xy 333.139766 -430.646091) (xy 333.14132 -430.6316) (xy 333.14132 -430.018952)
			(xy 333.141676 -430.006839) (xy 333.149191 -429.983806) (xy 333.163467 -429.964232) (xy 333.183103 -429.95004)
			(xy 333.206167 -429.942624) (xy 333.218282 -429.942244) (xy 334.158082 -429.942244) (xy 334.170171 -429.942723)
			(xy 334.193172 -429.950175) (xy 334.212752 -429.964358) (xy 334.227003 -429.98389) (xy 334.234535 -430.006865)
			(xy 334.235044 -430.018952) (xy 334.235044 -430.889918) (xy 335.138014 -430.889918) (xy 335.138108 -430.875344)
			(xy 335.13976 -430.846243) (xy 335.141316 -430.831752) (xy 335.141316 -429.747934) (xy 335.139768 -429.733442)
			(xy 335.138118 -429.704342) (xy 335.138014 -429.689768) (xy 335.138112 -429.675194) (xy 335.139762 -429.646093)
			(xy 335.141316 -429.631602) (xy 335.141316 -429.018954) (xy 335.141772 -429.006839) (xy 335.149269 -428.983798)
			(xy 335.163516 -428.964199) (xy 335.18312 -428.949958) (xy 335.206163 -428.942468) (xy 335.218278 -428.941992)
			(xy 336.158078 -428.941992) (xy 336.170187 -428.94253) (xy 336.193222 -428.950005) (xy 336.21282 -428.964232)
			(xy 336.227064 -428.983817) (xy 336.234559 -429.006846) (xy 336.23504 -429.018954) (xy 336.23504 -431.560478)
			(xy 336.234621 -431.572602) (xy 336.227132 -431.595664) (xy 336.212881 -431.615281) (xy 336.193264 -431.629532)
			(xy 336.170202 -431.637021) (xy 336.158078 -431.63744) (xy 335.218278 -431.63744) (xy 335.20616 -431.637007)
			(xy 335.183112 -431.629511) (xy 335.163509 -431.61526) (xy 335.149269 -431.595648) (xy 335.141786 -431.572596)
			(xy 335.141316 -431.560478) (xy 335.141316 -430.948084) (xy 335.139773 -430.933592) (xy 335.13812 -430.904492)
			(xy 335.138014 -430.889918) (xy 334.235044 -430.889918) (xy 334.235044 -431.889916) (xy 337.13801 -431.889916)
			(xy 337.138104 -431.875342) (xy 337.139756 -431.846241) (xy 337.141312 -431.83175) (xy 337.141312 -430.747932)
			(xy 337.139764 -430.73344) (xy 337.138114 -430.70434) (xy 337.13801 -430.689766) (xy 337.138108 -430.675192)
			(xy 337.139757 -430.646091) (xy 337.141312 -430.6316) (xy 337.141312 -430.018952) (xy 337.141676 -430.006839)
			(xy 337.14919 -429.983809) (xy 337.163465 -429.964235) (xy 337.183098 -429.950043) (xy 337.20616 -429.942625)
			(xy 337.218274 -429.942244) (xy 338.158074 -429.942244) (xy 338.170163 -429.94273) (xy 338.193163 -429.95018)
			(xy 338.212744 -429.964361) (xy 338.226995 -429.983891) (xy 338.234527 -430.006865) (xy 338.235036 -430.018952)
			(xy 338.235036 -430.889918) (xy 339.138006 -430.889918) (xy 339.1381 -430.875344) (xy 339.139752 -430.846243)
			(xy 339.141308 -430.831752) (xy 339.141308 -429.747934) (xy 339.13976 -429.733442) (xy 339.13811 -429.704342)
			(xy 339.138006 -429.689768) (xy 339.138104 -429.675194) (xy 339.139754 -429.646093) (xy 339.141308 -429.631602)
			(xy 339.141308 -429.018954) (xy 339.141772 -429.00684) (xy 339.149268 -428.9838) (xy 339.163513 -428.964202)
			(xy 339.183115 -428.949961) (xy 339.206156 -428.94247) (xy 339.21827 -428.941992) (xy 340.15807 -428.941992)
			(xy 340.170178 -428.942537) (xy 340.193213 -428.95001) (xy 340.212811 -428.964235) (xy 340.227055 -428.983819)
			(xy 340.234551 -429.006846) (xy 340.235032 -429.018954) (xy 340.235032 -431.560478) (xy 340.234621 -431.572603)
			(xy 340.227131 -431.595666) (xy 340.212878 -431.615284) (xy 340.193259 -431.629535) (xy 340.170195 -431.637022)
			(xy 340.15807 -431.63744) (xy 339.21827 -431.63744) (xy 339.206152 -431.637014) (xy 339.183104 -431.629515)
			(xy 339.163501 -431.615262) (xy 339.149261 -431.59565) (xy 339.141778 -431.572597) (xy 339.141308 -431.560478)
			(xy 339.141308 -430.948084) (xy 339.139764 -430.933592) (xy 339.138112 -430.904492) (xy 339.138006 -430.889918)
			(xy 338.235036 -430.889918) (xy 338.235036 -431.889916) (xy 341.138002 -431.889916) (xy 341.138096 -431.875342)
			(xy 341.139748 -431.846241) (xy 341.141304 -431.83175) (xy 341.141304 -430.747932) (xy 341.139756 -430.73344)
			(xy 341.138106 -430.70434) (xy 341.138002 -430.689766) (xy 341.1381 -430.675192) (xy 341.13975 -430.646091)
			(xy 341.141304 -430.6316) (xy 341.141304 -430.018952) (xy 341.141676 -430.00684) (xy 341.149189 -429.983811)
			(xy 341.163462 -429.964238) (xy 341.183093 -429.950045) (xy 341.206153 -429.942626) (xy 341.218266 -429.942244)
			(xy 342.158066 -429.942244) (xy 342.170154 -429.942736) (xy 342.193154 -429.950184) (xy 342.212735 -429.964364)
			(xy 342.226987 -429.983893) (xy 342.234519 -430.006866) (xy 342.235028 -430.018952) (xy 342.235028 -430.889918)
			(xy 343.137998 -430.889918) (xy 343.138092 -430.875344) (xy 343.139744 -430.846243) (xy 343.1413 -430.831752)
			(xy 343.1413 -429.747934) (xy 343.139752 -429.733442) (xy 343.138102 -429.704342) (xy 343.137998 -429.689768)
			(xy 343.138096 -429.675194) (xy 343.139746 -429.646093) (xy 343.1413 -429.631602) (xy 343.1413 -429.018954)
			(xy 343.141772 -429.006841) (xy 343.149267 -428.983803) (xy 343.163511 -428.964205) (xy 343.18311 -428.949964)
			(xy 343.206149 -428.942471) (xy 343.218262 -428.941992) (xy 344.158062 -428.941992) (xy 344.17017 -428.942543)
			(xy 344.193204 -428.950015) (xy 344.212803 -428.964238) (xy 344.227047 -428.98382) (xy 344.234543 -429.006847)
			(xy 344.235024 -429.018954) (xy 344.235024 -431.560478) (xy 344.234621 -431.572603) (xy 344.22713 -431.595668)
			(xy 344.212875 -431.615287) (xy 344.193254 -431.629537) (xy 344.170187 -431.637023) (xy 344.158062 -431.63744)
			(xy 343.218262 -431.63744) (xy 343.206143 -431.63702) (xy 343.183095 -431.62952) (xy 343.163492 -431.615265)
			(xy 343.149253 -431.595651) (xy 343.14177 -431.572597) (xy 343.1413 -431.560478) (xy 343.1413 -430.948084)
			(xy 343.139756 -430.933592) (xy 343.138104 -430.904492) (xy 343.137998 -430.889918) (xy 342.235028 -430.889918)
			(xy 342.235028 -431.889916) (xy 345.137994 -431.889916) (xy 345.138088 -431.875342) (xy 345.13974 -431.846241)
			(xy 345.141296 -431.83175) (xy 345.141296 -430.747932) (xy 345.139748 -430.73344) (xy 345.138098 -430.70434)
			(xy 345.137994 -430.689766) (xy 345.138092 -430.675192) (xy 345.139742 -430.646091) (xy 345.141296 -430.6316)
			(xy 345.141296 -430.018952) (xy 345.141676 -430.006841) (xy 345.149188 -429.983813) (xy 345.163459 -429.964241)
			(xy 345.183088 -429.950048) (xy 345.206145 -429.942628) (xy 345.218258 -429.942244) (xy 346.158058 -429.942244)
			(xy 346.170146 -429.942743) (xy 346.193146 -429.950189) (xy 346.212727 -429.964367) (xy 346.226979 -429.983894)
			(xy 346.234511 -430.006866) (xy 346.23502 -430.018952) (xy 346.23502 -431.359818) (xy 356.154736 -431.359818)
			(xy 356.155234 -431.274938) (xy 356.163191 -431.105365) (xy 356.179087 -430.936351) (xy 356.202888 -430.768268)
			(xy 356.234542 -430.601485) (xy 356.273978 -430.436369) (xy 356.32111 -430.273284) (xy 356.375834 -430.112586)
			(xy 356.438031 -429.954631) (xy 356.507563 -429.799764) (xy 356.584278 -429.648327) (xy 356.668006 -429.500651)
			(xy 356.758564 -429.357063) (xy 356.855753 -429.217877) (xy 356.95936 -429.0834) (xy 357.069155 -428.953927)
			(xy 357.184899 -428.829742) (xy 357.306336 -428.711119) (xy 357.4332 -428.598318) (xy 357.565211 -428.491588)
			(xy 357.702081 -428.391163) (xy 357.843506 -428.297264) (xy 357.989178 -428.210096) (xy 358.138776 -428.129853)
			(xy 358.29197 -428.056709) (xy 358.448424 -427.990827) (xy 358.607794 -427.93235) (xy 358.76973 -427.881408)
			(xy 358.933876 -427.838112) (xy 359.099871 -427.802557) (xy 359.26735 -427.774822) (xy 359.435945 -427.754968)
			(xy 359.605285 -427.743038) (xy 359.774998 -427.739059) (xy 359.944711 -427.743038) (xy 360.114051 -427.754968)
			(xy 360.282646 -427.774822) (xy 360.450125 -427.802557) (xy 360.61612 -427.838112) (xy 360.780266 -427.881408)
			(xy 360.942202 -427.93235) (xy 361.101572 -427.990827) (xy 361.258026 -428.056709) (xy 361.41122 -428.129853)
			(xy 361.560818 -428.210096) (xy 361.693883 -428.28972) (xy 383.237994 -428.28972) (xy 383.238088 -428.275146)
			(xy 383.23974 -428.246045) (xy 383.241296 -428.231554) (xy 383.241296 -427.14799) (xy 383.239753 -427.133498)
			(xy 383.2381 -427.104398) (xy 383.237994 -427.089824) (xy 383.238088 -427.07525) (xy 383.23974 -427.046149)
			(xy 383.241296 -427.031658) (xy 383.241296 -426.41901) (xy 383.24182 -426.4069) (xy 383.249299 -426.383864)
			(xy 383.263529 -426.364266) (xy 383.283118 -426.350023) (xy 383.306148 -426.342528) (xy 383.318258 -426.342048)
			(xy 384.258058 -426.342048) (xy 384.27018 -426.342496) (xy 384.293239 -426.349978) (xy 384.312855 -426.364222)
			(xy 384.327108 -426.383833) (xy 384.334599 -426.406889) (xy 384.33502 -426.41901) (xy 384.33502 -427.289976)
			(xy 385.23799 -427.289976) (xy 385.23808 -427.275402) (xy 385.239735 -427.246301) (xy 385.241292 -427.23181)
			(xy 385.241292 -426.147992) (xy 385.239749 -426.1335) (xy 385.238096 -426.1044) (xy 385.23799 -426.089826)
			(xy 385.238085 -426.075252) (xy 385.239736 -426.046151) (xy 385.241292 -426.03166) (xy 385.241292 -425.419012)
			(xy 385.241727 -425.406905) (xy 385.249222 -425.383879) (xy 385.263479 -425.364307) (xy 385.283096 -425.350111)
			(xy 385.306145 -425.342689) (xy 385.318254 -425.342304) (xy 386.258054 -425.342304) (xy 386.270138 -425.342846)
			(xy 386.293131 -425.350286) (xy 386.312708 -425.364454) (xy 386.326962 -425.38397) (xy 386.334501 -425.40693)
			(xy 386.335016 -425.419012) (xy 386.335016 -427.960536) (xy 386.334615 -427.972645) (xy 386.327107 -427.995671)
			(xy 386.312841 -428.015242) (xy 386.293218 -428.029436) (xy 386.270165 -428.036859) (xy 386.258054 -428.037244)
			(xy 385.318254 -428.037244) (xy 385.30616 -428.036832) (xy 385.283156 -428.02936) (xy 385.263575 -428.01516)
			(xy 385.249327 -427.995615) (xy 385.241799 -427.972628) (xy 385.241292 -427.960536) (xy 385.241292 -427.348142)
			(xy 385.239745 -427.33365) (xy 385.238095 -427.30455) (xy 385.23799 -427.289976) (xy 384.33502 -427.289976)
			(xy 384.33502 -428.28972) (xy 387.237986 -428.28972) (xy 387.23808 -428.275146) (xy 387.239732 -428.246045)
			(xy 387.241288 -428.231554) (xy 387.241288 -427.14799) (xy 387.239745 -427.133498) (xy 387.238092 -427.104398)
			(xy 387.237986 -427.089824) (xy 387.238081 -427.07525) (xy 387.239732 -427.046149) (xy 387.241288 -427.031658)
			(xy 387.241288 -426.41901) (xy 387.24182 -426.406901) (xy 387.249298 -426.383867) (xy 387.263526 -426.364269)
			(xy 387.283113 -426.350025) (xy 387.306141 -426.342529) (xy 387.31825 -426.342048) (xy 388.25805 -426.342048)
			(xy 388.270168 -426.342469) (xy 388.293215 -426.349972) (xy 388.312816 -426.364226) (xy 388.327056 -426.383839)
			(xy 388.33454 -426.406891) (xy 388.335012 -426.41901) (xy 388.335012 -427.289976) (xy 389.237982 -427.289976)
			(xy 389.238072 -427.275402) (xy 389.239727 -427.246301) (xy 389.241284 -427.23181) (xy 389.241284 -426.147992)
			(xy 389.239741 -426.1335) (xy 389.238088 -426.1044) (xy 389.237982 -426.089826) (xy 389.238077 -426.075252)
			(xy 389.239728 -426.046151) (xy 389.241284 -426.03166) (xy 389.241284 -425.419012) (xy 389.241727 -425.406905)
			(xy 389.249221 -425.383881) (xy 389.263476 -425.364309) (xy 389.283091 -425.350114) (xy 389.306138 -425.34269)
			(xy 389.318246 -425.342304) (xy 390.258046 -425.342304) (xy 390.270134 -425.342767) (xy 390.29313 -425.350232)
			(xy 390.312707 -425.364421) (xy 390.326957 -425.383953) (xy 390.334494 -425.406925) (xy 390.335008 -425.419012)
			(xy 390.335008 -427.960536) (xy 390.334614 -427.972646) (xy 390.327106 -427.995673) (xy 390.312838 -428.015245)
			(xy 390.293213 -428.029438) (xy 390.270157 -428.03686) (xy 390.258046 -428.037244) (xy 389.318246 -428.037244)
			(xy 389.306157 -428.036753) (xy 389.283155 -428.029307) (xy 389.263573 -428.015127) (xy 389.249322 -427.995597)
			(xy 389.241791 -427.972623) (xy 389.241284 -427.960536) (xy 389.241284 -427.348142) (xy 389.239737 -427.33365)
			(xy 389.238087 -427.30455) (xy 389.237982 -427.289976) (xy 388.335012 -427.289976) (xy 388.335012 -428.28972)
			(xy 391.237978 -428.28972) (xy 391.238072 -428.275146) (xy 391.239724 -428.246045) (xy 391.24128 -428.231554)
			(xy 391.24128 -427.14799) (xy 391.239737 -427.133498) (xy 391.238084 -427.104398) (xy 391.237978 -427.089824)
			(xy 391.238073 -427.07525) (xy 391.239724 -427.046149) (xy 391.24128 -427.031658) (xy 391.24128 -426.41901)
			(xy 391.241669 -426.406884) (xy 391.249164 -426.383818) (xy 391.263422 -426.364199) (xy 391.283047 -426.349949)
			(xy 391.306115 -426.342464) (xy 391.318242 -426.342048) (xy 392.258042 -426.342048) (xy 392.27016 -426.342476)
			(xy 392.293206 -426.349976) (xy 392.312808 -426.364229) (xy 392.327048 -426.383841) (xy 392.334532 -426.406892)
			(xy 392.335004 -426.41901) (xy 392.335004 -427.289976) (xy 393.237974 -427.289976) (xy 393.238064 -427.275402)
			(xy 393.239719 -427.246301) (xy 393.241276 -427.23181) (xy 393.241276 -426.147992) (xy 393.239733 -426.1335)
			(xy 393.23808 -426.1044) (xy 393.237974 -426.089826) (xy 393.238069 -426.075252) (xy 393.23972 -426.046151)
			(xy 393.241276 -426.03166) (xy 393.241276 -425.419012) (xy 393.241726 -425.406906) (xy 393.24922 -425.383883)
			(xy 393.263473 -425.364312) (xy 393.283086 -425.350116) (xy 393.306131 -425.342691) (xy 393.318238 -425.342304)
			(xy 394.258038 -425.342304) (xy 394.270126 -425.342774) (xy 394.293122 -425.350237) (xy 394.312698 -425.364424)
			(xy 394.326949 -425.383954) (xy 394.334486 -425.406926) (xy 394.335 -425.419012) (xy 394.335 -427.960536)
			(xy 394.334614 -427.972647) (xy 394.327105 -427.995675) (xy 394.312835 -428.015248) (xy 394.293208 -428.029441)
			(xy 394.27015 -428.036861) (xy 394.258038 -428.037244) (xy 393.318238 -428.037244) (xy 393.306149 -428.03676)
			(xy 393.283147 -428.029312) (xy 393.263565 -428.01513) (xy 393.249314 -427.995599) (xy 393.241783 -427.972623)
			(xy 393.241276 -427.960536) (xy 393.241276 -427.348142) (xy 393.239729 -427.33365) (xy 393.238079 -427.30455)
			(xy 393.237974 -427.289976) (xy 392.335004 -427.289976) (xy 392.335004 -428.28972) (xy 395.23797 -428.28972)
			(xy 395.238064 -428.275146) (xy 395.239716 -428.246045) (xy 395.241272 -428.231554) (xy 395.241272 -427.14799)
			(xy 395.239729 -427.133498) (xy 395.238076 -427.104398) (xy 395.23797 -427.089824) (xy 395.238065 -427.07525)
			(xy 395.239716 -427.046149) (xy 395.241272 -427.031658) (xy 395.241272 -426.41901) (xy 395.241669 -426.406884)
			(xy 395.249163 -426.38382) (xy 395.263419 -426.364202) (xy 395.283042 -426.349952) (xy 395.306108 -426.342465)
			(xy 395.318234 -426.342048) (xy 396.258034 -426.342048) (xy 396.270151 -426.342483) (xy 396.293197 -426.349981)
			(xy 396.312799 -426.364232) (xy 396.327039 -426.383842) (xy 396.334524 -426.406892) (xy 396.334996 -426.41901)
			(xy 396.334996 -427.289976) (xy 398.237964 -427.289976) (xy 398.238078 -427.274891) (xy 398.239856 -427.244772)
			(xy 398.24152 -427.229778) (xy 398.24152 -426.150024) (xy 398.239851 -426.135031) (xy 398.238073 -426.104912)
			(xy 398.237964 -426.089826) (xy 398.238074 -426.07474) (xy 398.239855 -426.044622) (xy 398.24152 -426.029628)
			(xy 398.24152 -425.419012) (xy 398.241924 -425.406927) (xy 398.249391 -425.38394) (xy 398.263599 -425.364387)
			(xy 398.283154 -425.350184) (xy 398.306143 -425.342721) (xy 398.318228 -425.342304) (xy 399.258028 -425.342304)
			(xy 399.270105 -425.34274) (xy 399.293075 -425.350212) (xy 399.312613 -425.364415) (xy 399.326806 -425.38396)
			(xy 399.334266 -425.406935) (xy 399.334736 -425.419012) (xy 399.334736 -427.960536) (xy 399.334267 -427.97261)
			(xy 399.326798 -427.995573) (xy 399.312602 -428.015107) (xy 399.293066 -428.029302) (xy 399.270102 -428.036768)
			(xy 399.258028 -428.037244) (xy 398.318228 -428.037244) (xy 398.306158 -428.036713) (xy 398.283198 -428.029262)
			(xy 398.263664 -428.015082) (xy 398.249467 -427.995559) (xy 398.241997 -427.972605) (xy 398.24152 -427.960536)
			(xy 398.24152 -427.350174) (xy 398.239856 -427.33518) (xy 398.238074 -427.305062) (xy 398.237964 -427.289976)
			(xy 396.334996 -427.289976) (xy 396.334996 -428.28972) (xy 400.23796 -428.28972) (xy 400.238069 -428.274634)
			(xy 400.239851 -428.244516) (xy 400.241516 -428.229522) (xy 400.241516 -427.150022) (xy 400.239847 -427.135029)
			(xy 400.238069 -427.10491) (xy 400.23796 -427.089824) (xy 400.23807 -427.074738) (xy 400.239851 -427.04462)
			(xy 400.241516 -427.029626) (xy 400.241516 -426.41901) (xy 400.242016 -426.406923) (xy 400.249467 -426.383927)
			(xy 400.263646 -426.364349) (xy 400.283171 -426.350097) (xy 400.306139 -426.342561) (xy 400.318224 -426.342048)
			(xy 401.258024 -426.342048) (xy 401.270129 -426.342495) (xy 401.293148 -426.349995) (xy 401.312716 -426.36425)
			(xy 401.326912 -426.383862) (xy 401.334341 -426.406904) (xy 401.334732 -426.41901) (xy 401.334732 -427.289976)
			(xy 402.237956 -427.289976) (xy 402.23807 -427.274891) (xy 402.239848 -427.244772) (xy 402.241512 -427.229778)
			(xy 402.241512 -426.150024) (xy 402.239843 -426.135031) (xy 402.238065 -426.104912) (xy 402.237956 -426.089826)
			(xy 402.238066 -426.07474) (xy 402.239847 -426.044622) (xy 402.241512 -426.029628) (xy 402.241512 -425.419012)
			(xy 402.241923 -425.406928) (xy 402.24939 -425.383942) (xy 402.263596 -425.36439) (xy 402.283149 -425.350186)
			(xy 402.306136 -425.342722) (xy 402.31822 -425.342304) (xy 403.25802 -425.342304) (xy 403.270097 -425.342748)
			(xy 403.293067 -425.350217) (xy 403.312604 -425.364419) (xy 403.326798 -425.383962) (xy 403.334257 -425.406935)
			(xy 403.334728 -425.419012) (xy 403.334728 -427.960536) (xy 403.334267 -427.97261) (xy 403.326797 -427.995576)
			(xy 403.312599 -428.01511) (xy 403.293061 -428.029304) (xy 403.270095 -428.036769) (xy 403.25802 -428.037244)
			(xy 402.31822 -428.037244) (xy 402.30615 -428.036719) (xy 402.28319 -428.029267) (xy 402.263655 -428.015085)
			(xy 402.249459 -427.995561) (xy 402.241989 -427.972606) (xy 402.241512 -427.960536) (xy 402.241512 -427.350174)
			(xy 402.239848 -427.33518) (xy 402.238066 -427.305062) (xy 402.237956 -427.289976) (xy 401.334732 -427.289976)
			(xy 401.334732 -428.28972) (xy 404.237952 -428.28972) (xy 404.238062 -428.274634) (xy 404.239843 -428.244516)
			(xy 404.241508 -428.229522) (xy 404.241508 -427.150022) (xy 404.239839 -427.135029) (xy 404.238061 -427.10491)
			(xy 404.237952 -427.089824) (xy 404.238062 -427.074738) (xy 404.239843 -427.04462) (xy 404.241508 -427.029626)
			(xy 404.241508 -426.41901) (xy 404.242015 -426.406924) (xy 404.249465 -426.383929) (xy 404.263643 -426.364352)
			(xy 404.283166 -426.3501) (xy 404.306132 -426.342562) (xy 404.318216 -426.342048) (xy 405.258016 -426.342048)
			(xy 405.270121 -426.342502) (xy 405.293139 -426.349999) (xy 405.312708 -426.364253) (xy 405.326904 -426.383863)
			(xy 405.334333 -426.406904) (xy 405.334724 -426.41901) (xy 405.334724 -427.289976) (xy 406.237948 -427.289976)
			(xy 406.238062 -427.274891) (xy 406.23984 -427.244772) (xy 406.241504 -427.229778) (xy 406.241504 -426.150024)
			(xy 406.239835 -426.135031) (xy 406.238057 -426.104912) (xy 406.237948 -426.089826) (xy 406.238058 -426.07474)
			(xy 406.239839 -426.044622) (xy 406.241504 -426.029628) (xy 406.241504 -425.419012) (xy 406.241923 -425.406929)
			(xy 406.249389 -425.383944) (xy 406.263593 -425.364393) (xy 406.283144 -425.350189) (xy 406.306129 -425.342723)
			(xy 406.318212 -425.342304) (xy 407.258012 -425.342304) (xy 407.270088 -425.342754) (xy 407.293058 -425.350222)
			(xy 407.312596 -425.364421) (xy 407.326789 -425.383964) (xy 407.334249 -425.406935) (xy 407.33472 -425.419012)
			(xy 407.33472 -427.960536) (xy 407.334267 -427.972611) (xy 407.326796 -427.995578) (xy 407.312596 -428.015113)
			(xy 407.293056 -428.029307) (xy 407.270087 -428.036771) (xy 407.258012 -428.037244) (xy 406.318212 -428.037244)
			(xy 406.306142 -428.036726) (xy 406.283181 -428.029271) (xy 406.263647 -428.015087) (xy 406.249451 -427.995562)
			(xy 406.241981 -427.972606) (xy 406.241504 -427.960536) (xy 406.241504 -427.350174) (xy 406.23984 -427.33518)
			(xy 406.238058 -427.305062) (xy 406.237948 -427.289976) (xy 405.334724 -427.289976) (xy 405.334724 -428.28972)
			(xy 408.237944 -428.28972) (xy 408.238054 -428.274634) (xy 408.239835 -428.244516) (xy 408.2415 -428.229522)
			(xy 408.2415 -427.150022) (xy 408.239831 -427.135029) (xy 408.238053 -427.10491) (xy 408.237944 -427.089824)
			(xy 408.238054 -427.074738) (xy 408.239835 -427.04462) (xy 408.2415 -427.029626) (xy 408.2415 -426.41901)
			(xy 408.242015 -426.406925) (xy 408.249464 -426.383931) (xy 408.26364 -426.364355) (xy 408.283161 -426.350103)
			(xy 408.306125 -426.342563) (xy 408.318208 -426.342048) (xy 409.258008 -426.342048) (xy 409.270112 -426.342509)
			(xy 409.293131 -426.350004) (xy 409.312699 -426.364256) (xy 409.326896 -426.383865) (xy 409.334325 -426.406905)
			(xy 409.334716 -426.41901) (xy 409.334716 -427.289976) (xy 410.23794 -427.289976) (xy 410.238055 -427.274891)
			(xy 410.239832 -427.244772) (xy 410.241496 -427.229778) (xy 410.241496 -426.150024) (xy 410.239827 -426.135031)
			(xy 410.238049 -426.104912) (xy 410.23794 -426.089826) (xy 410.23805 -426.07474) (xy 410.239831 -426.044622)
			(xy 410.241496 -426.029628) (xy 410.241496 -425.419012) (xy 410.241923 -425.40693) (xy 410.249388 -425.383947)
			(xy 410.26359 -425.364396) (xy 410.283139 -425.350191) (xy 410.306122 -425.342724) (xy 410.318204 -425.342304)
			(xy 411.258004 -425.342304) (xy 411.270088 -425.342709) (xy 411.293073 -425.350179) (xy 411.312624 -425.364387)
			(xy 411.326828 -425.383941) (xy 411.334293 -425.406928) (xy 411.334712 -425.419012) (xy 411.334712 -427.960536)
			(xy 411.334267 -427.972612) (xy 411.326795 -427.99558) (xy 411.312593 -428.015116) (xy 411.293051 -428.029309)
			(xy 411.27008 -428.036772) (xy 411.258004 -428.037244) (xy 410.318204 -428.037244) (xy 410.306133 -428.036733)
			(xy 410.283172 -428.029276) (xy 410.263638 -428.01509) (xy 410.249442 -427.995564) (xy 410.241973 -427.972607)
			(xy 410.241496 -427.960536) (xy 410.241496 -427.350174) (xy 410.239832 -427.33518) (xy 410.23805 -427.305062)
			(xy 410.23794 -427.289976) (xy 409.334716 -427.289976) (xy 409.334716 -428.28972) (xy 412.237936 -428.28972)
			(xy 412.238048 -428.274634) (xy 412.239829 -428.244516) (xy 412.241492 -428.229522) (xy 412.241492 -427.150022)
			(xy 412.239823 -427.135029) (xy 412.238045 -427.10491) (xy 412.237936 -427.089824) (xy 412.238048 -427.074738)
			(xy 412.239829 -427.04462) (xy 412.241492 -427.029626) (xy 412.241492 -426.41901) (xy 412.242015 -426.406926)
			(xy 412.249463 -426.383934) (xy 412.263637 -426.364358) (xy 412.283156 -426.350105) (xy 412.306118 -426.342564)
			(xy 412.3182 -426.342048) (xy 413.258 -426.342048) (xy 413.270104 -426.342515) (xy 413.293122 -426.350009)
			(xy 413.312691 -426.364259) (xy 413.326887 -426.383866) (xy 413.334317 -426.406905) (xy 413.334708 -426.41901)
			(xy 413.334708 -428.960534) (xy 413.334223 -428.972621) (xy 413.326762 -428.995614) (xy 413.312579 -429.01519)
			(xy 413.293053 -429.029441) (xy 413.270085 -429.03698) (xy 413.258 -429.037496) (xy 412.3182 -429.037496)
			(xy 412.306091 -429.037084) (xy 412.283063 -429.029584) (xy 412.263489 -429.015321) (xy 412.249295 -428.995699)
			(xy 412.241875 -428.972645) (xy 412.241492 -428.960534) (xy 412.241492 -428.349918) (xy 412.239823 -428.334925)
			(xy 412.238045 -428.304806) (xy 412.237936 -428.28972) (xy 409.334716 -428.28972) (xy 409.334716 -428.960534)
			(xy 409.334321 -428.97263) (xy 409.326849 -428.995639) (xy 409.312646 -429.015222) (xy 409.293095 -429.02947)
			(xy 409.270103 -429.036993) (xy 409.258008 -429.037496) (xy 408.318208 -429.037496) (xy 408.306099 -429.037077)
			(xy 408.283071 -429.029579) (xy 408.263498 -429.015319) (xy 408.249303 -428.995697) (xy 408.241883 -428.972644)
			(xy 408.2415 -428.960534) (xy 408.2415 -428.349918) (xy 408.239831 -428.334925) (xy 408.238053 -428.304806)
			(xy 408.237944 -428.28972) (xy 405.334724 -428.28972) (xy 405.334724 -428.960534) (xy 405.334321 -428.972629)
			(xy 405.326851 -428.995637) (xy 405.312649 -429.015219) (xy 405.2931 -429.029467) (xy 405.27011 -429.036992)
			(xy 405.258016 -429.037496) (xy 404.318216 -429.037496) (xy 404.306108 -429.03707) (xy 404.28308 -429.029574)
			(xy 404.263507 -429.015315) (xy 404.249312 -428.995695) (xy 404.241891 -428.972644) (xy 404.241508 -428.960534)
			(xy 404.241508 -428.349918) (xy 404.239839 -428.334925) (xy 404.238061 -428.304806) (xy 404.237952 -428.28972)
			(xy 401.334732 -428.28972) (xy 401.334732 -428.960534) (xy 401.334321 -428.972628) (xy 401.326852 -428.995635)
			(xy 401.312652 -429.015216) (xy 401.293105 -429.029465) (xy 401.270117 -429.036991) (xy 401.258024 -429.037496)
			(xy 400.318224 -429.037496) (xy 400.306116 -429.037063) (xy 400.283089 -429.02957) (xy 400.263515 -429.015313)
			(xy 400.24932 -428.995694) (xy 400.241899 -428.972643) (xy 400.241516 -428.960534) (xy 400.241516 -428.349918)
			(xy 400.239847 -428.334925) (xy 400.238069 -428.304806) (xy 400.23796 -428.28972) (xy 396.334996 -428.28972)
			(xy 396.334996 -428.960534) (xy 396.334518 -428.972647) (xy 396.327025 -428.995686) (xy 396.312784 -429.015284)
			(xy 396.293186 -429.029525) (xy 396.270147 -429.037018) (xy 396.258034 -429.037496) (xy 395.318234 -429.037496)
			(xy 395.306125 -429.03696) (xy 395.283088 -429.029486) (xy 395.263489 -429.01526) (xy 395.249245 -428.995673)
			(xy 395.241751 -428.972643) (xy 395.241272 -428.960534) (xy 395.241272 -428.347886) (xy 395.239729 -428.333394)
			(xy 395.238076 -428.304294) (xy 395.23797 -428.28972) (xy 392.335004 -428.28972) (xy 392.335004 -428.960534)
			(xy 392.334518 -428.972646) (xy 392.327027 -428.995683) (xy 392.312787 -429.015281) (xy 392.293191 -429.029523)
			(xy 392.270154 -429.037017) (xy 392.258042 -429.037496) (xy 391.318242 -429.037496) (xy 391.306125 -429.037005)
			(xy 391.283073 -429.029528) (xy 391.26346 -429.015294) (xy 391.249206 -428.995695) (xy 391.241707 -428.972651)
			(xy 391.24128 -428.960534) (xy 391.24128 -428.347886) (xy 391.239737 -428.333394) (xy 391.238084 -428.304294)
			(xy 391.237978 -428.28972) (xy 388.335012 -428.28972) (xy 388.335012 -428.960534) (xy 388.334518 -428.972645)
			(xy 388.327028 -428.995681) (xy 388.31279 -429.015278) (xy 388.293196 -429.02952) (xy 388.270161 -429.037016)
			(xy 388.25805 -429.037496) (xy 387.31825 -429.037496) (xy 387.306136 -429.037031) (xy 387.283097 -429.029535)
			(xy 387.263499 -429.015289) (xy 387.249258 -428.995689) (xy 387.241766 -428.972648) (xy 387.241288 -428.960534)
			(xy 387.241288 -428.347886) (xy 387.239745 -428.333394) (xy 387.238092 -428.304294) (xy 387.237986 -428.28972)
			(xy 384.33502 -428.28972) (xy 384.33502 -428.960534) (xy 384.334669 -428.972663) (xy 384.327162 -428.99573)
			(xy 384.312894 -429.015348) (xy 384.293262 -429.029597) (xy 384.270187 -429.03708) (xy 384.258058 -429.037496)
			(xy 383.318258 -429.037496) (xy 383.306145 -429.037025) (xy 383.283106 -429.02953) (xy 383.263508 -429.015287)
			(xy 383.249266 -428.995687) (xy 383.241774 -428.972647) (xy 383.241296 -428.960534) (xy 383.241296 -428.347886)
			(xy 383.239753 -428.333394) (xy 383.2381 -428.304294) (xy 383.237994 -428.28972) (xy 361.693883 -428.28972)
			(xy 361.70649 -428.297264) (xy 361.847915 -428.391163) (xy 361.984785 -428.491588) (xy 362.116796 -428.598318)
			(xy 362.24366 -428.711119) (xy 362.365097 -428.829742) (xy 362.480841 -428.953927) (xy 362.590636 -429.0834)
			(xy 362.694243 -429.217877) (xy 362.791432 -429.357063) (xy 362.88199 -429.500651) (xy 362.965718 -429.648327)
			(xy 363.042433 -429.799764) (xy 363.111965 -429.954631) (xy 363.174162 -430.112586) (xy 363.228886 -430.273284)
			(xy 363.276018 -430.436369) (xy 363.315454 -430.601485) (xy 363.347108 -430.768268) (xy 363.364334 -430.889918)
			(xy 381.21844 -430.889918) (xy 381.218952 -430.857362) (xy 381.226896 -430.792738) (xy 381.242678 -430.729568)
			(xy 381.266063 -430.668801) (xy 381.296699 -430.611348) (xy 381.334127 -430.55807) (xy 381.377787 -430.509766)
			(xy 381.402082 -430.48809) (xy 381.482854 -430.323244) (xy 381.487579 -430.312737) (xy 381.491058 -430.289973)
			(xy 381.487563 -430.267211) (xy 381.482854 -430.256696) (xy 381.401828 -430.091596) (xy 381.377589 -430.069873)
			(xy 381.33399 -430.021546) (xy 381.296612 -429.968261) (xy 381.266015 -429.910813) (xy 381.242656 -429.850061)
			(xy 381.226884 -429.786913) (xy 381.218934 -429.722312) (xy 381.21844 -429.689768) (xy 381.219133 -429.650641)
			(xy 381.230612 -429.573235) (xy 381.2413 -429.53559) (xy 381.2413 -429.018954) (xy 381.241772 -429.006841)
			(xy 381.249267 -428.983803) (xy 381.263511 -428.964205) (xy 381.28311 -428.949964) (xy 381.306149 -428.942471)
			(xy 381.318262 -428.941992) (xy 382.258062 -428.941992) (xy 382.27017 -428.942543) (xy 382.293204 -428.950015)
			(xy 382.312803 -428.964238) (xy 382.327047 -428.98382) (xy 382.334543 -429.006847) (xy 382.335024 -429.018954)
			(xy 382.335024 -431.560478) (xy 382.334621 -431.572603) (xy 382.32713 -431.595668) (xy 382.312875 -431.615287)
			(xy 382.293254 -431.629537) (xy 382.270187 -431.637023) (xy 382.258062 -431.63744) (xy 381.318262 -431.63744)
			(xy 381.306143 -431.63702) (xy 381.283095 -431.62952) (xy 381.263492 -431.615265) (xy 381.249253 -431.595651)
			(xy 381.24177 -431.572597) (xy 381.2413 -431.560478) (xy 381.2413 -431.044096) (xy 381.230616 -431.00645)
			(xy 381.219137 -430.929044) (xy 381.21844 -430.889918) (xy 363.364334 -430.889918) (xy 363.370909 -430.936351)
			(xy 363.386805 -431.105365) (xy 363.394762 -431.274938) (xy 363.39526 -431.359818) (xy 363.39483 -431.445421)
			(xy 363.38674 -431.616436) (xy 363.370574 -431.786877) (xy 363.355859 -431.889916) (xy 383.218436 -431.889916)
			(xy 383.218948 -431.85736) (xy 383.226892 -431.792736) (xy 383.242674 -431.729566) (xy 383.266059 -431.6688)
			(xy 383.296695 -431.611346) (xy 383.334123 -431.558068) (xy 383.377783 -431.509764) (xy 383.402078 -431.488088)
			(xy 383.48285 -431.323242) (xy 383.487577 -431.312736) (xy 383.491055 -431.289971) (xy 383.48756 -431.267209)
			(xy 383.48285 -431.256694) (xy 383.401824 -431.091594) (xy 383.377584 -431.069873) (xy 383.333984 -431.021546)
			(xy 383.296607 -430.96826) (xy 383.26601 -430.910811) (xy 383.242651 -430.850059) (xy 383.226879 -430.786911)
			(xy 383.21893 -430.72231) (xy 383.218436 -430.689766) (xy 383.219129 -430.650639) (xy 383.230608 -430.573233)
			(xy 383.241296 -430.535588) (xy 383.241296 -430.018952) (xy 383.241676 -430.006841) (xy 383.249188 -429.983813)
			(xy 383.263459 -429.964241) (xy 383.283088 -429.950048) (xy 383.306145 -429.942628) (xy 383.318258 -429.942244)
			(xy 384.258058 -429.942244) (xy 384.270146 -429.942743) (xy 384.293146 -429.950189) (xy 384.312727 -429.964367)
			(xy 384.326979 -429.983894) (xy 384.334511 -430.006866) (xy 384.33502 -430.018952) (xy 384.33502 -430.889918)
			(xy 385.218432 -430.889918) (xy 385.218947 -430.857362) (xy 385.22689 -430.792738) (xy 385.242672 -430.729569)
			(xy 385.266057 -430.668802) (xy 385.296692 -430.611349) (xy 385.33412 -430.558071) (xy 385.377779 -430.509766)
			(xy 385.402074 -430.48809) (xy 385.482846 -430.323244) (xy 385.487572 -430.312737) (xy 385.49105 -430.289973)
			(xy 385.487556 -430.267211) (xy 385.482846 -430.256696) (xy 385.40182 -430.091596) (xy 385.37758 -430.069875)
			(xy 385.33398 -430.021547) (xy 385.296603 -429.968261) (xy 385.266007 -429.910813) (xy 385.242648 -429.850061)
			(xy 385.226876 -429.786913) (xy 385.218926 -429.722312) (xy 385.218432 -429.689768) (xy 385.219125 -429.650642)
			(xy 385.230604 -429.573235) (xy 385.241292 -429.53559) (xy 385.241292 -429.018954) (xy 385.241772 -429.006842)
			(xy 385.249266 -428.983805) (xy 385.263508 -428.964208) (xy 385.283105 -428.949966) (xy 385.306142 -428.942472)
			(xy 385.318254 -428.941992) (xy 386.258054 -428.941992) (xy 386.270162 -428.94255) (xy 386.293196 -428.950019)
			(xy 386.312794 -428.96424) (xy 386.327039 -428.983822) (xy 386.334535 -429.006847) (xy 386.335016 -429.018954)
			(xy 386.335016 -431.560478) (xy 386.334621 -431.572604) (xy 386.327129 -431.59567) (xy 386.312872 -431.61529)
			(xy 386.293249 -431.62954) (xy 386.27018 -431.637024) (xy 386.258054 -431.63744) (xy 385.318254 -431.63744)
			(xy 385.306135 -431.637027) (xy 385.283086 -431.629525) (xy 385.263484 -431.615268) (xy 385.249244 -431.595653)
			(xy 385.241762 -431.572598) (xy 385.241292 -431.560478) (xy 385.241292 -431.044096) (xy 385.230608 -431.00645)
			(xy 385.219129 -430.929044) (xy 385.218432 -430.889918) (xy 384.33502 -430.889918) (xy 384.33502 -431.889916)
			(xy 387.218428 -431.889916) (xy 387.218942 -431.85736) (xy 387.226886 -431.792736) (xy 387.242668 -431.729567)
			(xy 387.266052 -431.6688) (xy 387.296688 -431.611347) (xy 387.334116 -431.558068) (xy 387.377775 -431.509764)
			(xy 387.40207 -431.488088) (xy 387.482842 -431.323242) (xy 387.487569 -431.312736) (xy 387.491048 -431.289971)
			(xy 387.487552 -431.267209) (xy 387.482842 -431.256694) (xy 387.401816 -431.091594) (xy 387.377574 -431.069875)
			(xy 387.333975 -431.021547) (xy 387.296598 -430.968261) (xy 387.266002 -430.910812) (xy 387.242643 -430.85006)
			(xy 387.226871 -430.786911) (xy 387.218922 -430.72231) (xy 387.218428 -430.689766) (xy 387.219121 -430.650639)
			(xy 387.2306 -430.573233) (xy 387.241288 -430.535588) (xy 387.241288 -430.018952) (xy 387.241675 -430.006842)
			(xy 387.249187 -429.983815) (xy 387.263456 -429.964244) (xy 387.283083 -429.95005) (xy 387.306138 -429.942629)
			(xy 387.31825 -429.942244) (xy 388.25805 -429.942244) (xy 388.270137 -429.94275) (xy 388.293137 -429.950193)
			(xy 388.312718 -429.96437) (xy 388.32697 -429.983896) (xy 388.334503 -430.006866) (xy 388.335012 -430.018952)
			(xy 388.335012 -430.889918) (xy 389.218424 -430.889918) (xy 389.218941 -430.857363) (xy 389.226884 -430.792738)
			(xy 389.242666 -430.729569) (xy 389.26605 -430.668802) (xy 389.296685 -430.611349) (xy 389.334113 -430.558071)
			(xy 389.377771 -430.509766) (xy 389.402066 -430.48809) (xy 389.482838 -430.323244) (xy 389.487564 -430.312737)
			(xy 389.491043 -430.289973) (xy 389.487548 -430.267211) (xy 389.482838 -430.256696) (xy 389.401812 -430.091596)
			(xy 389.37757 -430.069877) (xy 389.333971 -430.021549) (xy 389.296594 -429.968262) (xy 389.265998 -429.910814)
			(xy 389.242639 -429.850061) (xy 389.226868 -429.786913) (xy 389.218918 -429.722312) (xy 389.218424 -429.689768)
			(xy 389.219118 -429.650642) (xy 389.230597 -429.573235) (xy 389.241284 -429.53559) (xy 389.241284 -429.018954)
			(xy 389.241673 -429.006832) (xy 389.249179 -428.98378) (xy 389.26344 -428.964175) (xy 389.283062 -428.949937)
			(xy 389.306124 -428.942459) (xy 389.318246 -428.941992) (xy 390.258046 -428.941992) (xy 390.270158 -428.942472)
			(xy 390.293195 -428.949966) (xy 390.312792 -428.964208) (xy 390.327034 -428.983805) (xy 390.334528 -429.006842)
			(xy 390.335008 -429.018954) (xy 390.335008 -431.560478) (xy 390.33447 -431.572587) (xy 390.326995 -431.595622)
			(xy 390.312768 -431.61522) (xy 390.293183 -431.629464) (xy 390.270154 -431.636959) (xy 390.258046 -431.63744)
			(xy 389.318246 -431.63744) (xy 389.306123 -431.637001) (xy 389.283062 -431.629518) (xy 389.263445 -431.615273)
			(xy 389.249193 -431.595659) (xy 389.241703 -431.5726) (xy 389.241284 -431.560478) (xy 389.241284 -431.044096)
			(xy 389.2306 -431.00645) (xy 389.219121 -430.929044) (xy 389.218424 -430.889918) (xy 388.335012 -430.889918)
			(xy 388.335012 -431.889916) (xy 391.21842 -431.889916) (xy 391.218937 -431.857361) (xy 391.226881 -431.792736)
			(xy 391.242663 -431.729567) (xy 391.266046 -431.668801) (xy 391.296682 -431.611347) (xy 391.334109 -431.558069)
			(xy 391.377767 -431.509764) (xy 391.402062 -431.488088) (xy 391.482834 -431.323242) (xy 391.487562 -431.312736)
			(xy 391.49104 -431.289971) (xy 391.487545 -431.267209) (xy 391.482834 -431.256694) (xy 391.401808 -431.091594)
			(xy 391.377564 -431.069877) (xy 391.333966 -431.021548) (xy 391.296589 -430.968261) (xy 391.265993 -430.910812)
			(xy 391.242635 -430.85006) (xy 391.226863 -430.786911) (xy 391.218914 -430.72231) (xy 391.21842 -430.689766)
			(xy 391.219113 -430.65064) (xy 391.230593 -430.573233) (xy 391.24128 -430.535588) (xy 391.24128 -430.018952)
			(xy 391.241675 -430.006843) (xy 391.249186 -429.983817) (xy 391.263453 -429.964247) (xy 391.283077 -429.950053)
			(xy 391.306131 -429.94263) (xy 391.318242 -429.942244) (xy 392.258042 -429.942244) (xy 392.270134 -429.942672)
			(xy 392.293137 -429.95014) (xy 392.312716 -429.964337) (xy 392.326965 -429.983879) (xy 392.334496 -430.006861)
			(xy 392.335004 -430.018952) (xy 392.335004 -430.889918) (xy 393.218416 -430.889918) (xy 393.218936 -430.857363)
			(xy 393.226879 -430.792739) (xy 393.242661 -430.72957) (xy 393.266044 -430.668803) (xy 393.296679 -430.61135)
			(xy 393.334106 -430.558071) (xy 393.377763 -430.509766) (xy 393.402058 -430.48809) (xy 393.48283 -430.323244)
			(xy 393.487557 -430.312738) (xy 393.491036 -430.289973) (xy 393.48754 -430.267211) (xy 393.48283 -430.256696)
			(xy 393.401804 -430.091596) (xy 393.37756 -430.069879) (xy 393.333962 -430.02155) (xy 393.296585 -429.968263)
			(xy 393.265989 -429.910814) (xy 393.242631 -429.850062) (xy 393.226859 -429.786913) (xy 393.21891 -429.722312)
			(xy 393.218416 -429.689768) (xy 393.219106 -429.650641) (xy 393.230587 -429.573235) (xy 393.241276 -429.53559)
			(xy 393.241276 -429.018954) (xy 393.241673 -429.006833) (xy 393.249178 -428.983782) (xy 393.263438 -428.964178)
			(xy 393.283057 -428.949939) (xy 393.306117 -428.94246) (xy 393.318238 -428.941992) (xy 394.258038 -428.941992)
			(xy 394.27015 -428.942479) (xy 394.293187 -428.949971) (xy 394.312784 -428.964211) (xy 394.327026 -428.983806)
			(xy 394.33452 -429.006842) (xy 394.335 -429.018954) (xy 394.335 -431.560478) (xy 394.33447 -431.572588)
			(xy 394.326994 -431.595624) (xy 394.312765 -431.615223) (xy 394.293177 -431.629466) (xy 394.270147 -431.636961)
			(xy 394.258038 -431.63744) (xy 393.318238 -431.63744) (xy 393.306115 -431.637007) (xy 393.283054 -431.629523)
			(xy 393.263436 -431.615275) (xy 393.249184 -431.595661) (xy 393.241695 -431.572601) (xy 393.241276 -431.560478)
			(xy 393.241276 -431.044096) (xy 393.230592 -431.00645) (xy 393.219113 -430.929044) (xy 393.218416 -430.889918)
			(xy 392.335004 -430.889918) (xy 392.335004 -431.889916) (xy 395.218412 -431.889916) (xy 395.218932 -431.857361)
			(xy 395.226875 -431.792737) (xy 395.242657 -431.729568) (xy 395.26604 -431.668801) (xy 395.296675 -431.611348)
			(xy 395.334102 -431.558069) (xy 395.377759 -431.509764) (xy 395.402054 -431.488088) (xy 395.482826 -431.323242)
			(xy 395.487554 -431.312736) (xy 395.491033 -431.289971) (xy 395.487537 -431.267209) (xy 395.482826 -431.256694)
			(xy 395.4018 -431.091594) (xy 395.377555 -431.069879) (xy 395.333956 -431.021549) (xy 395.29658 -430.968262)
			(xy 395.265985 -430.910813) (xy 395.242626 -430.85006) (xy 395.226855 -430.786911) (xy 395.218906 -430.72231)
			(xy 395.218412 -430.689766) (xy 395.219102 -430.650639) (xy 395.230583 -430.573233) (xy 395.241272 -430.535588)
			(xy 395.241272 -430.018952) (xy 395.241675 -430.006843) (xy 395.249184 -429.983819) (xy 395.26345 -429.96425)
			(xy 395.283072 -429.950056) (xy 395.306124 -429.942631) (xy 395.318234 -429.942244) (xy 396.258034 -429.942244)
			(xy 396.270126 -429.942678) (xy 396.293128 -429.950145) (xy 396.312708 -429.96434) (xy 396.326957 -429.98388)
			(xy 396.334488 -430.006862) (xy 396.334996 -430.018952) (xy 396.334996 -430.889918) (xy 398.218406 -430.889918)
			(xy 398.218929 -430.857363) (xy 398.226872 -430.792739) (xy 398.242654 -430.72957) (xy 398.266037 -430.668804)
			(xy 398.296671 -430.61135) (xy 398.334097 -430.558072) (xy 398.377754 -430.509766) (xy 398.402048 -430.48809)
			(xy 398.48282 -430.323244) (xy 398.487547 -430.312738) (xy 398.491027 -430.289973) (xy 398.487531 -430.267211)
			(xy 398.48282 -430.256696) (xy 398.401794 -430.091596) (xy 398.377548 -430.069881) (xy 398.33395 -430.021552)
			(xy 398.296574 -429.968264) (xy 398.265979 -429.910815) (xy 398.242621 -429.850062) (xy 398.226849 -429.786913)
			(xy 398.2189 -429.722312) (xy 398.218406 -429.689768) (xy 398.219134 -429.650443) (xy 398.230738 -429.572653)
			(xy 398.24152 -429.534828) (xy 398.24152 -429.018954) (xy 398.241968 -429.006864) (xy 398.249435 -428.983865)
			(xy 398.263627 -428.964288) (xy 398.283163 -428.950038) (xy 398.306139 -428.942504) (xy 398.318228 -428.941992)
			(xy 399.258028 -428.941992) (xy 399.270138 -428.942392) (xy 399.293164 -428.949899) (xy 399.312736 -428.964165)
			(xy 399.32693 -428.983789) (xy 399.334352 -429.006843) (xy 399.334736 -429.018954) (xy 399.334736 -431.560478)
			(xy 399.334273 -431.572569) (xy 399.32682 -431.595573) (xy 399.312633 -431.615155) (xy 399.293097 -431.629405)
			(xy 399.270117 -431.636934) (xy 399.258028 -431.63744) (xy 398.318228 -431.63744) (xy 398.306125 -431.63696)
			(xy 398.283105 -431.629473) (xy 398.263535 -431.615227) (xy 398.249338 -431.595621) (xy 398.241909 -431.572582)
			(xy 398.24152 -431.560478) (xy 398.24152 -431.044858) (xy 398.230725 -431.007035) (xy 398.219116 -430.929244)
			(xy 398.218406 -430.889918) (xy 396.334996 -430.889918) (xy 396.334996 -431.889916) (xy 400.218402 -431.889916)
			(xy 400.218925 -431.857361) (xy 400.226868 -431.792737) (xy 400.24265 -431.729568) (xy 400.266033 -431.668802)
			(xy 400.296667 -431.611349) (xy 400.334093 -431.55807) (xy 400.37775 -431.509764) (xy 400.402044 -431.488088)
			(xy 400.482816 -431.323242) (xy 400.487545 -431.312736) (xy 400.491024 -431.289971) (xy 400.487528 -431.267209)
			(xy 400.482816 -431.256694) (xy 400.40179 -431.091594) (xy 400.377543 -431.069881) (xy 400.333945 -431.021551)
			(xy 400.296569 -430.968263) (xy 400.265974 -430.910814) (xy 400.242616 -430.850061) (xy 400.226845 -430.786912)
			(xy 400.218896 -430.72231) (xy 400.218402 -430.689766) (xy 400.219129 -430.650441) (xy 400.230734 -430.572651)
			(xy 400.241516 -430.534826) (xy 400.241516 -430.018952) (xy 400.241924 -430.006873) (xy 400.249402 -429.9839)
			(xy 400.263613 -429.964361) (xy 400.283164 -429.950169) (xy 400.306144 -429.942712) (xy 400.318224 -429.942244)
			(xy 401.258024 -429.942244) (xy 401.270095 -429.942743) (xy 401.293055 -429.950206) (xy 401.312587 -429.964396)
			(xy 401.326783 -429.983924) (xy 401.334253 -430.006881) (xy 401.334732 -430.018952) (xy 401.334732 -430.889918)
			(xy 402.218398 -430.889918) (xy 402.218924 -430.857363) (xy 402.226867 -430.792739) (xy 402.242648 -430.729571)
			(xy 402.266031 -430.668804) (xy 402.296664 -430.611351) (xy 402.33409 -430.558072) (xy 402.377746 -430.509767)
			(xy 402.40204 -430.48809) (xy 402.482812 -430.323244) (xy 402.48754 -430.312738) (xy 402.49102 -430.289973)
			(xy 402.487523 -430.267211) (xy 402.482812 -430.256696) (xy 402.401786 -430.091596) (xy 402.377539 -430.069883)
			(xy 402.333941 -430.021553) (xy 402.296566 -429.968265) (xy 402.26597 -429.910816) (xy 402.242613 -429.850062)
			(xy 402.226841 -429.786914) (xy 402.218892 -429.722312) (xy 402.218398 -429.689768) (xy 402.219126 -429.650443)
			(xy 402.23073 -429.572653) (xy 402.241512 -429.534828) (xy 402.241512 -429.018954) (xy 402.241968 -429.006865)
			(xy 402.249434 -428.983867) (xy 402.263624 -428.964291) (xy 402.283158 -428.950041) (xy 402.306132 -428.942505)
			(xy 402.31822 -428.941992) (xy 403.25802 -428.941992) (xy 403.270129 -428.942399) (xy 403.293156 -428.949903)
			(xy 403.312728 -428.964167) (xy 403.326922 -428.98379) (xy 403.334344 -429.006843) (xy 403.334728 -429.018954)
			(xy 403.334728 -431.560478) (xy 403.334273 -431.57257) (xy 403.326819 -431.595575) (xy 403.31263 -431.615158)
			(xy 403.293092 -431.629408) (xy 403.27011 -431.636935) (xy 403.25802 -431.63744) (xy 402.31822 -431.63744)
			(xy 402.306116 -431.636967) (xy 402.283096 -431.629478) (xy 402.263527 -431.61523) (xy 402.24933 -431.595622)
			(xy 402.241901 -431.572583) (xy 402.241512 -431.560478) (xy 402.241512 -431.044858) (xy 402.230717 -431.007035)
			(xy 402.219108 -430.929244) (xy 402.218398 -430.889918) (xy 401.334732 -430.889918) (xy 401.334732 -431.889916)
			(xy 404.218394 -431.889916) (xy 404.218886 -431.85736) (xy 404.226831 -431.792733) (xy 404.242615 -431.729563)
			(xy 404.266003 -431.668795) (xy 404.296642 -431.611342) (xy 404.334075 -431.558065) (xy 404.377738 -431.509763)
			(xy 404.402036 -431.488088) (xy 404.482808 -431.323242) (xy 404.487537 -431.312736) (xy 404.491017 -431.289971)
			(xy 404.48752 -431.267208) (xy 404.482808 -431.256694) (xy 404.401782 -431.091594) (xy 404.377533 -431.069883)
			(xy 404.333936 -431.021552) (xy 404.29656 -430.968264) (xy 404.265965 -430.910814) (xy 404.242608 -430.850061)
			(xy 404.226837 -430.786912) (xy 404.218888 -430.72231) (xy 404.218394 -430.689766) (xy 404.219122 -430.650441)
			(xy 404.230726 -430.572651) (xy 404.241508 -430.534826) (xy 404.241508 -430.018952) (xy 404.241923 -430.006873)
			(xy 404.249401 -429.983902) (xy 404.26361 -429.964364) (xy 404.283159 -429.950172) (xy 404.306137 -429.942713)
			(xy 404.318216 -429.942244) (xy 405.258016 -429.942244) (xy 405.270087 -429.94275) (xy 405.293046 -429.950211)
			(xy 405.312579 -429.964399) (xy 405.326774 -429.983925) (xy 405.334245 -430.006882) (xy 405.334724 -430.018952)
			(xy 405.334724 -430.889918) (xy 406.21839 -430.889918) (xy 406.218885 -430.857362) (xy 406.226829 -430.792736)
			(xy 406.242613 -430.729565) (xy 406.266 -430.668798) (xy 406.296639 -430.611345) (xy 406.334071 -430.558067)
			(xy 406.377735 -430.509765) (xy 406.402032 -430.48809) (xy 406.482804 -430.323244) (xy 406.487532 -430.312738)
			(xy 406.491013 -430.289973) (xy 406.487516 -430.26721) (xy 406.482804 -430.256696) (xy 406.401778 -430.091596)
			(xy 406.377529 -430.069884) (xy 406.333932 -430.021554) (xy 406.296557 -429.968266) (xy 406.265962 -429.910816)
			(xy 406.242604 -429.850063) (xy 406.226833 -429.786914) (xy 406.218884 -429.722312) (xy 406.21839 -429.689768)
			(xy 406.219118 -429.650443) (xy 406.230723 -429.572653) (xy 406.241504 -429.534828) (xy 406.241504 -429.018954)
			(xy 406.241967 -429.006866) (xy 406.249432 -428.98387) (xy 406.263621 -428.964293) (xy 406.283153 -428.950043)
			(xy 406.306125 -428.942506) (xy 406.318212 -428.941992) (xy 407.258012 -428.941992) (xy 407.270121 -428.942406)
			(xy 407.293147 -428.949908) (xy 407.312719 -428.96417) (xy 407.326914 -428.983792) (xy 407.334336 -429.006844)
			(xy 407.33472 -429.018954) (xy 407.33472 -431.560478) (xy 407.334273 -431.57257) (xy 407.326818 -431.595577)
			(xy 407.312627 -431.615161) (xy 407.293087 -431.629411) (xy 407.270103 -431.636936) (xy 407.258012 -431.63744)
			(xy 406.318212 -431.63744) (xy 406.306108 -431.636974) (xy 406.283088 -431.629483) (xy 406.263518 -431.615232)
			(xy 406.249322 -431.595624) (xy 406.241893 -431.572583) (xy 406.241504 -431.560478) (xy 406.241504 -431.044858)
			(xy 406.230709 -431.007035) (xy 406.2191 -430.929244) (xy 406.21839 -430.889918) (xy 405.334724 -430.889918)
			(xy 405.334724 -431.889916) (xy 408.218386 -431.889916) (xy 408.218881 -431.85736) (xy 408.226825 -431.792734)
			(xy 408.24261 -431.729563) (xy 408.265997 -431.668796) (xy 408.296636 -431.611343) (xy 408.334068 -431.558065)
			(xy 408.377731 -431.509763) (xy 408.402028 -431.488088) (xy 408.4828 -431.323242) (xy 408.48753 -431.312736)
			(xy 408.49101 -431.289971) (xy 408.487512 -431.267208) (xy 408.4828 -431.256694) (xy 408.401774 -431.091594)
			(xy 408.377523 -431.069884) (xy 408.333926 -431.021554) (xy 408.296551 -430.968265) (xy 408.265957 -430.910815)
			(xy 408.2426 -430.850061) (xy 408.226829 -430.786912) (xy 408.21888 -430.72231) (xy 408.218386 -430.689766)
			(xy 408.219114 -430.650441) (xy 408.230719 -430.572651) (xy 408.2415 -430.534826) (xy 408.2415 -430.018952)
			(xy 408.241923 -430.006874) (xy 408.2494 -429.983904) (xy 408.263607 -429.964367) (xy 408.283154 -429.950174)
			(xy 408.30613 -429.942714) (xy 408.318208 -429.942244) (xy 409.258008 -429.942244) (xy 409.270078 -429.942757)
			(xy 409.293037 -429.950216) (xy 409.31257 -429.964401) (xy 409.326766 -429.983927) (xy 409.334237 -430.006882)
			(xy 409.334716 -430.018952) (xy 409.334716 -430.889918) (xy 410.218382 -430.889918) (xy 410.21888 -430.857362)
			(xy 410.226824 -430.792736) (xy 410.242608 -430.729566) (xy 410.265994 -430.668798) (xy 410.296633 -430.611345)
			(xy 410.334064 -430.558068) (xy 410.377727 -430.509765) (xy 410.402024 -430.48809) (xy 410.482796 -430.323244)
			(xy 410.487525 -430.312738) (xy 410.491005 -430.289973) (xy 410.487508 -430.26721) (xy 410.482796 -430.256696)
			(xy 410.40177 -430.091596) (xy 410.37754 -430.069864) (xy 410.333938 -430.02154) (xy 410.296558 -429.968256)
			(xy 410.26596 -429.91081) (xy 410.242599 -429.850059) (xy 410.226826 -429.786912) (xy 410.218876 -429.722312)
			(xy 410.218382 -429.689768) (xy 410.219111 -429.650443) (xy 410.230715 -429.572653) (xy 410.241496 -429.534828)
			(xy 410.241496 -429.018954) (xy 410.241967 -429.006866) (xy 410.249431 -428.983872) (xy 410.263618 -428.964296)
			(xy 410.283148 -428.950046) (xy 410.306118 -428.942507) (xy 410.318204 -428.941992) (xy 411.258004 -428.941992)
			(xy 411.270112 -428.942413) (xy 411.293138 -428.949912) (xy 411.312711 -428.964173) (xy 411.326906 -428.983793)
			(xy 411.334328 -429.006844) (xy 411.334712 -429.018954) (xy 411.334712 -431.560478) (xy 411.334273 -431.572571)
			(xy 411.326816 -431.595579) (xy 411.312624 -431.615164) (xy 411.293082 -431.629413) (xy 411.270096 -431.636937)
			(xy 411.258004 -431.63744) (xy 410.318204 -431.63744) (xy 410.306099 -431.636981) (xy 410.283079 -431.629488)
			(xy 410.263509 -431.615236) (xy 410.249313 -431.595625) (xy 410.241885 -431.572584) (xy 410.241496 -431.560478)
			(xy 410.241496 -431.044858) (xy 410.230701 -431.007035) (xy 410.219092 -430.929244) (xy 410.218382 -430.889918)
			(xy 409.334716 -430.889918) (xy 409.334716 -431.889916) (xy 412.218378 -431.889916) (xy 412.218876 -431.85736)
			(xy 412.22682 -431.792734) (xy 412.242604 -431.729564) (xy 412.265991 -431.668797) (xy 412.296629 -431.611343)
			(xy 412.33406 -431.558066) (xy 412.377723 -431.509763) (xy 412.40202 -431.488088) (xy 412.482792 -431.323242)
			(xy 412.487522 -431.312737) (xy 412.491003 -431.289971) (xy 412.487505 -431.267208) (xy 412.482792 -431.256694)
			(xy 412.401766 -431.091594) (xy 412.377534 -431.069864) (xy 412.333932 -431.021539) (xy 412.296553 -430.968255)
			(xy 412.265955 -430.910808) (xy 412.242595 -430.850057) (xy 412.226822 -430.78691) (xy 412.218872 -430.72231)
			(xy 412.218378 -430.689766) (xy 412.219106 -430.650441) (xy 412.230711 -430.572651) (xy 412.241492 -430.534826)
			(xy 412.241492 -430.018952) (xy 412.241923 -430.006875) (xy 412.249399 -429.983906) (xy 412.263604 -429.96437)
			(xy 412.283149 -429.950177) (xy 412.306123 -429.942716) (xy 412.3182 -429.942244) (xy 413.258 -429.942244)
			(xy 413.27007 -429.942764) (xy 413.293029 -429.95022) (xy 413.312562 -429.964404) (xy 413.326758 -429.983928)
			(xy 413.334229 -430.006883) (xy 413.334708 -430.018952) (xy 413.334708 -432.560476) (xy 413.334267 -432.572557)
			(xy 413.326806 -432.595539) (xy 413.312607 -432.61509) (xy 413.293061 -432.629295) (xy 413.270081 -432.636763)
			(xy 413.258 -432.637184) (xy 412.3182 -432.637184) (xy 412.306115 -432.636787) (xy 412.283128 -432.629317)
			(xy 412.263576 -432.615107) (xy 412.249372 -432.59555) (xy 412.241909 -432.572561) (xy 412.241492 -432.560476)
			(xy 412.241492 -432.044856) (xy 412.230696 -432.007034) (xy 412.219087 -431.929242) (xy 412.218378 -431.889916)
			(xy 409.334716 -431.889916) (xy 409.334716 -432.560476) (xy 409.334267 -432.572557) (xy 409.326807 -432.595537)
			(xy 409.31261 -432.615087) (xy 409.293066 -432.629292) (xy 409.270088 -432.636762) (xy 409.258008 -432.637184)
			(xy 408.318208 -432.637184) (xy 408.306123 -432.63678) (xy 408.283137 -432.629312) (xy 408.263584 -432.615105)
			(xy 408.249381 -432.595549) (xy 408.241917 -432.572561) (xy 408.2415 -432.560476) (xy 408.2415 -432.044856)
			(xy 408.230704 -432.007034) (xy 408.219095 -431.929242) (xy 408.218386 -431.889916) (xy 405.334724 -431.889916)
			(xy 405.334724 -432.560476) (xy 405.334267 -432.572556) (xy 405.326808 -432.595535) (xy 405.312613 -432.615084)
			(xy 405.293071 -432.62929) (xy 405.270096 -432.636761) (xy 405.258016 -432.637184) (xy 404.318216 -432.637184)
			(xy 404.306132 -432.636773) (xy 404.283146 -432.629307) (xy 404.263593 -432.615101) (xy 404.249389 -432.595547)
			(xy 404.241926 -432.57256) (xy 404.241508 -432.560476) (xy 404.241508 -432.044856) (xy 404.230713 -432.007034)
			(xy 404.219103 -431.929242) (xy 404.218394 -431.889916) (xy 401.334732 -431.889916) (xy 401.334732 -432.560476)
			(xy 401.334216 -432.572547) (xy 401.326763 -432.595509) (xy 401.312579 -432.615045) (xy 401.293052 -432.629241)
			(xy 401.270095 -432.636708) (xy 401.258024 -432.637184) (xy 400.318224 -432.637184) (xy 400.30614 -432.636766)
			(xy 400.283154 -432.629303) (xy 400.263601 -432.615099) (xy 400.249397 -432.595546) (xy 400.241934 -432.57256)
			(xy 400.241516 -432.560476) (xy 400.241516 -432.044856) (xy 400.230721 -432.007033) (xy 400.219111 -431.929242)
			(xy 400.218402 -431.889916) (xy 396.334996 -431.889916) (xy 396.334996 -432.560476) (xy 396.334563 -432.572584)
			(xy 396.32707 -432.595611) (xy 396.312813 -432.615185) (xy 396.293194 -432.62938) (xy 396.270143 -432.636801)
			(xy 396.258034 -432.637184) (xy 395.318234 -432.637184) (xy 395.306149 -432.636664) (xy 395.283153 -432.62922)
			(xy 395.263575 -432.615046) (xy 395.249322 -432.595525) (xy 395.241785 -432.572559) (xy 395.241272 -432.560476)
			(xy 395.241272 -432.044094) (xy 395.230587 -432.006448) (xy 395.219109 -431.929042) (xy 395.218412 -431.889916)
			(xy 392.335004 -431.889916) (xy 392.335004 -432.560476) (xy 392.334563 -432.572583) (xy 392.327071 -432.595609)
			(xy 392.312815 -432.615182) (xy 392.293199 -432.629378) (xy 392.27015 -432.6368) (xy 392.258042 -432.637184)
			(xy 391.318242 -432.637184) (xy 391.306157 -432.636657) (xy 391.283162 -432.629215) (xy 391.263583 -432.615043)
			(xy 391.24933 -432.595523) (xy 391.241793 -432.572559) (xy 391.24128 -432.560476) (xy 391.24128 -432.044094)
			(xy 391.230595 -432.006448) (xy 391.219117 -431.929042) (xy 391.21842 -431.889916) (xy 388.335012 -431.889916)
			(xy 388.335012 -432.560476) (xy 388.334563 -432.572582) (xy 388.327072 -432.595607) (xy 388.312818 -432.615179)
			(xy 388.293204 -432.629375) (xy 388.270158 -432.636799) (xy 388.25805 -432.637184) (xy 387.31825 -432.637184)
			(xy 387.306165 -432.636651) (xy 387.28317 -432.62921) (xy 387.263592 -432.61504) (xy 387.249339 -432.595522)
			(xy 387.241801 -432.572559) (xy 387.241288 -432.560476) (xy 387.241288 -432.044094) (xy 387.230604 -432.006448)
			(xy 387.219125 -431.929042) (xy 387.218428 -431.889916) (xy 384.33502 -431.889916) (xy 384.33502 -432.560476)
			(xy 384.334563 -432.572582) (xy 384.327073 -432.595605) (xy 384.312821 -432.615176) (xy 384.293209 -432.629373)
			(xy 384.270165 -432.636797) (xy 384.258058 -432.637184) (xy 383.318258 -432.637184) (xy 383.306169 -432.636729)
			(xy 383.283171 -432.629264) (xy 383.263593 -432.615073) (xy 383.249343 -432.595539) (xy 383.241808 -432.572564)
			(xy 383.241296 -432.560476) (xy 383.241296 -432.044094) (xy 383.230612 -432.006448) (xy 383.219133 -431.929042)
			(xy 383.218436 -431.889916) (xy 363.355859 -431.889916) (xy 363.346369 -431.956363) (xy 363.314178 -432.124516)
			(xy 363.274074 -432.290959) (xy 363.226145 -432.455319) (xy 363.170501 -432.61723) (xy 363.107264 -432.776329)
			(xy 363.036576 -432.932261) (xy 362.958595 -433.084677) (xy 362.873496 -433.233236) (xy 362.781469 -433.377605)
			(xy 362.68272 -433.517463) (xy 362.577469 -433.652495) (xy 362.465953 -433.782401) (xy 362.348419 -433.90689)
			(xy 362.225132 -434.025683) (xy 362.096367 -434.138515) (xy 361.962411 -434.245133) (xy 361.823565 -434.345299)
			(xy 361.680139 -434.438789) (xy 361.593049 -434.48986) (xy 381.237998 -434.48986) (xy 381.238096 -434.475286)
			(xy 381.239745 -434.446185) (xy 381.2413 -434.431694) (xy 381.2413 -433.34813) (xy 381.239752 -433.333638)
			(xy 381.238102 -433.304538) (xy 381.237998 -433.289964) (xy 381.238096 -433.27539) (xy 381.239745 -433.246289)
			(xy 381.2413 -433.231798) (xy 381.2413 -432.618896) (xy 381.241713 -432.606787) (xy 381.249213 -432.583759)
			(xy 381.263476 -432.564186) (xy 381.283098 -432.549992) (xy 381.306152 -432.542571) (xy 381.318262 -432.542188)
			(xy 382.258062 -432.542188) (xy 382.270154 -432.542641) (xy 382.293162 -432.550093) (xy 382.312747 -432.564281)
			(xy 382.326997 -432.583821) (xy 382.334521 -432.606805) (xy 382.335024 -432.618896) (xy 382.335024 -435.16042)
			(xy 382.334601 -435.172528) (xy 382.327099 -435.195551) (xy 382.312838 -435.215122) (xy 382.29322 -435.229317)
			(xy 382.270171 -435.236741) (xy 382.258062 -435.237128) (xy 381.318262 -435.237128) (xy 381.306167 -435.236724)
			(xy 381.28316 -435.229253) (xy 381.263578 -435.215052) (xy 381.24933 -435.195503) (xy 381.241804 -435.172514)
			(xy 381.2413 -435.16042) (xy 381.2413 -434.548026) (xy 381.239752 -434.533534) (xy 381.238102 -434.504434)
			(xy 381.237998 -434.48986) (xy 361.593049 -434.48986) (xy 361.532453 -434.525394) (xy 361.380838 -434.60492)
			(xy 361.225633 -434.67719) (xy 361.146598 -434.710078) (xy 361.132966 -434.716266) (xy 361.109724 -434.735103)
			(xy 361.092944 -434.759873) (xy 361.084069 -434.788444) (xy 361.083862 -434.818361) (xy 361.092341 -434.847052)
			(xy 361.108777 -434.872051) (xy 361.119928 -434.882036) (xy 361.169374 -434.924045) (xy 361.263563 -435.013299)
			(xy 361.352051 -435.108208) (xy 361.434498 -435.208409) (xy 361.510589 -435.313518) (xy 361.580032 -435.423133)
			(xy 361.616728 -435.489858) (xy 383.237994 -435.489858) (xy 383.238091 -435.475284) (xy 383.239741 -435.446183)
			(xy 383.241296 -435.431692) (xy 383.241296 -434.348128) (xy 383.239748 -434.333636) (xy 383.238098 -434.304536)
			(xy 383.237994 -434.289962) (xy 383.238092 -434.275388) (xy 383.239741 -434.246287) (xy 383.241296 -434.231796)
			(xy 383.241296 -433.618894) (xy 383.241806 -433.606783) (xy 383.24929 -433.583747) (xy 383.263524 -433.564149)
			(xy 383.283115 -433.549906) (xy 383.306148 -433.542412) (xy 383.318258 -433.541932) (xy 384.258058 -433.541932)
			(xy 384.270178 -433.542396) (xy 384.293234 -433.549876) (xy 384.31285 -433.564116) (xy 384.327103 -433.583722)
			(xy 384.334597 -433.606774) (xy 384.33502 -433.618894) (xy 384.33502 -434.48986) (xy 385.23799 -434.48986)
			(xy 385.238088 -434.475286) (xy 385.239737 -434.446185) (xy 385.241292 -434.431694) (xy 385.241292 -433.34813)
			(xy 385.239744 -433.333638) (xy 385.238094 -433.304538) (xy 385.23799 -433.289964) (xy 385.238088 -433.27539)
			(xy 385.239737 -433.246289) (xy 385.241292 -433.231798) (xy 385.241292 -432.618896) (xy 385.241713 -432.606788)
			(xy 385.249212 -432.583762) (xy 385.263473 -432.564189) (xy 385.283093 -432.549994) (xy 385.306144 -432.542572)
			(xy 385.318254 -432.542188) (xy 386.258054 -432.542188) (xy 386.270146 -432.542647) (xy 386.293153 -432.550097)
			(xy 386.312738 -432.564284) (xy 386.326988 -432.583823) (xy 386.334513 -432.606806) (xy 386.335016 -432.618896)
			(xy 386.335016 -435.16042) (xy 386.334601 -435.172528) (xy 386.327098 -435.195554) (xy 386.312836 -435.215125)
			(xy 386.293215 -435.229319) (xy 386.270164 -435.236743) (xy 386.258054 -435.237128) (xy 385.318254 -435.237128)
			(xy 385.306159 -435.236731) (xy 385.283151 -435.229258) (xy 385.263569 -435.215054) (xy 385.249322 -435.195505)
			(xy 385.241796 -435.172514) (xy 385.241292 -435.16042) (xy 385.241292 -434.548026) (xy 385.239744 -434.533534)
			(xy 385.238094 -434.504434) (xy 385.23799 -434.48986) (xy 384.33502 -434.48986) (xy 384.33502 -435.489858)
			(xy 387.237986 -435.489858) (xy 387.238083 -435.475284) (xy 387.239733 -435.446183) (xy 387.241288 -435.431692)
			(xy 387.241288 -434.348128) (xy 387.23974 -434.333636) (xy 387.23809 -434.304536) (xy 387.237986 -434.289962)
			(xy 387.238084 -434.275388) (xy 387.239733 -434.246287) (xy 387.241288 -434.231796) (xy 387.241288 -433.618894)
			(xy 387.241806 -433.606784) (xy 387.249289 -433.583749) (xy 387.263521 -433.564152) (xy 387.28311 -433.549909)
			(xy 387.30614 -433.542413) (xy 387.31825 -433.541932) (xy 388.25805 -433.541932) (xy 388.270167 -433.542369)
			(xy 388.29321 -433.549869) (xy 388.312811 -433.564121) (xy 388.327051 -433.583729) (xy 388.334538 -433.606777)
			(xy 388.335012 -433.618894) (xy 388.335012 -434.48986) (xy 389.237982 -434.48986) (xy 389.23808 -434.475286)
			(xy 389.239729 -434.446185) (xy 389.241284 -434.431694) (xy 389.241284 -433.34813) (xy 389.239736 -433.333638)
			(xy 389.238086 -433.304538) (xy 389.237982 -433.289964) (xy 389.23808 -433.27539) (xy 389.23973 -433.246289)
			(xy 389.241284 -433.231798) (xy 389.241284 -432.618896) (xy 389.241713 -432.606789) (xy 389.249211 -432.583764)
			(xy 389.26347 -432.564192) (xy 389.283088 -432.549997) (xy 389.306137 -432.542573) (xy 389.318246 -432.542188)
			(xy 390.258046 -432.542188) (xy 390.270143 -432.542569) (xy 390.293153 -432.550044) (xy 390.312736 -432.564251)
			(xy 390.326984 -432.583805) (xy 390.334506 -432.6068) (xy 390.335008 -432.618896) (xy 390.335008 -435.16042)
			(xy 390.334601 -435.172529) (xy 390.327097 -435.195556) (xy 390.312833 -435.215128) (xy 390.29321 -435.229322)
			(xy 390.270157 -435.236744) (xy 390.258046 -435.237128) (xy 389.318246 -435.237128) (xy 389.306156 -435.236653)
			(xy 389.283151 -435.229205) (xy 389.263568 -435.215022) (xy 389.249317 -435.195487) (xy 389.241789 -435.172509)
			(xy 389.241284 -435.16042) (xy 389.241284 -434.548026) (xy 389.239736 -434.533534) (xy 389.238086 -434.504434)
			(xy 389.237982 -434.48986) (xy 388.335012 -434.48986) (xy 388.335012 -435.489858) (xy 391.237978 -435.489858)
			(xy 391.238076 -435.475284) (xy 391.239725 -435.446183) (xy 391.24128 -435.431692) (xy 391.24128 -434.348128)
			(xy 391.239732 -434.333636) (xy 391.238082 -434.304536) (xy 391.237978 -434.289962) (xy 391.238076 -434.275388)
			(xy 391.239725 -434.246287) (xy 391.24128 -434.231796) (xy 391.24128 -433.618894) (xy 391.241656 -433.606767)
			(xy 391.249155 -433.583701) (xy 391.263416 -433.564082) (xy 391.283044 -433.549833) (xy 391.306115 -433.542348)
			(xy 391.318242 -433.541932) (xy 392.258042 -433.541932) (xy 392.270158 -433.542376) (xy 392.293202 -433.549874)
			(xy 392.312802 -433.564123) (xy 392.327043 -433.583731) (xy 392.33453 -433.606778) (xy 392.335004 -433.618894)
			(xy 392.335004 -434.48986) (xy 393.237974 -434.48986) (xy 393.238072 -434.475286) (xy 393.239721 -434.446185)
			(xy 393.241276 -434.431694) (xy 393.241276 -433.34813) (xy 393.239728 -433.333638) (xy 393.238078 -433.304538)
			(xy 393.237974 -433.289964) (xy 393.238072 -433.27539) (xy 393.239722 -433.246289) (xy 393.241276 -433.231798)
			(xy 393.241276 -432.618896) (xy 393.241712 -432.606789) (xy 393.24921 -432.583766) (xy 393.263467 -432.564195)
			(xy 393.283083 -432.55) (xy 393.30613 -432.542575) (xy 393.318238 -432.542188) (xy 394.258038 -432.542188)
			(xy 394.270134 -432.542576) (xy 394.293144 -432.550049) (xy 394.312728 -432.564254) (xy 394.326975 -432.583807)
			(xy 394.334498 -432.606801) (xy 394.335 -432.618896) (xy 394.335 -435.16042) (xy 394.334601 -435.17253)
			(xy 394.327096 -435.195558) (xy 394.31283 -435.215131) (xy 394.293205 -435.229325) (xy 394.270149 -435.236745)
			(xy 394.258038 -435.237128) (xy 393.318238 -435.237128) (xy 393.306147 -435.23666) (xy 393.283142 -435.22921)
			(xy 393.263559 -435.215024) (xy 393.249308 -435.195489) (xy 393.241781 -435.172509) (xy 393.241276 -435.16042)
			(xy 393.241276 -434.548026) (xy 393.239728 -434.533534) (xy 393.238078 -434.504434) (xy 393.237974 -434.48986)
			(xy 392.335004 -434.48986) (xy 392.335004 -435.489858) (xy 395.23797 -435.489858) (xy 395.238068 -435.475284)
			(xy 395.239717 -435.446183) (xy 395.241272 -435.431692) (xy 395.241272 -434.348128) (xy 395.239724 -434.333636)
			(xy 395.238074 -434.304536) (xy 395.23797 -434.289962) (xy 395.238068 -434.275388) (xy 395.239717 -434.246287)
			(xy 395.241272 -434.231796) (xy 395.241272 -433.618894) (xy 395.241656 -433.606768) (xy 395.249154 -433.583703)
			(xy 395.263413 -433.564085) (xy 395.283039 -433.549835) (xy 395.306107 -433.542349) (xy 395.318234 -433.541932)
			(xy 396.258034 -433.541932) (xy 396.27015 -433.542383) (xy 396.293193 -433.549878) (xy 396.312794 -433.564126)
			(xy 396.327034 -433.583732) (xy 396.334522 -433.606778) (xy 396.334996 -433.618894) (xy 396.334996 -434.48986)
			(xy 398.237964 -434.48986) (xy 398.238077 -434.474774) (xy 398.239856 -434.444656) (xy 398.24152 -434.429662)
			(xy 398.24152 -433.350162) (xy 398.239855 -433.335168) (xy 398.238074 -433.30505) (xy 398.237964 -433.289964)
			(xy 398.238077 -433.274878) (xy 398.239856 -433.24476) (xy 398.24152 -433.229766) (xy 398.24152 -432.618896)
			(xy 398.241909 -432.60681) (xy 398.249382 -432.583823) (xy 398.263593 -432.56427) (xy 398.283151 -432.550067)
			(xy 398.306142 -432.542604) (xy 398.318228 -432.542188) (xy 399.258028 -432.542188) (xy 399.270104 -432.54264)
			(xy 399.293071 -432.55011) (xy 399.312607 -432.56431) (xy 399.326801 -432.58385) (xy 399.334264 -432.60682)
			(xy 399.334736 -432.618896) (xy 399.334736 -435.16042) (xy 399.334253 -435.172493) (xy 399.326788 -435.195456)
			(xy 399.312596 -435.21499) (xy 399.293063 -435.229185) (xy 399.270101 -435.236652) (xy 399.258028 -435.237128)
			(xy 398.318228 -435.237128) (xy 398.306149 -435.236664) (xy 398.28317 -435.229206) (xy 398.263621 -435.215013)
			(xy 398.249416 -435.195473) (xy 398.241944 -435.172499) (xy 398.24152 -435.16042) (xy 398.24152 -434.550058)
			(xy 398.239854 -434.535064) (xy 398.238074 -434.504946) (xy 398.237964 -434.48986) (xy 396.334996 -434.48986)
			(xy 396.334996 -435.489858) (xy 400.23796 -435.489858) (xy 400.238073 -435.474772) (xy 400.239852 -435.444654)
			(xy 400.241516 -435.42966) (xy 400.241516 -434.35016) (xy 400.239851 -434.335166) (xy 400.23807 -434.305048)
			(xy 400.23796 -434.289962) (xy 400.238073 -434.274876) (xy 400.239852 -434.244758) (xy 400.241516 -434.229764)
			(xy 400.241516 -433.618894) (xy 400.242002 -433.606807) (xy 400.249457 -433.58381) (xy 400.26364 -433.564232)
			(xy 400.283168 -433.549981) (xy 400.306138 -433.542445) (xy 400.318224 -433.541932) (xy 401.258024 -433.541932)
			(xy 401.270137 -433.542296) (xy 401.293171 -433.549806) (xy 401.312746 -433.56408) (xy 401.326939 -433.583715)
			(xy 401.334353 -433.606779) (xy 401.334732 -433.618894) (xy 401.334732 -434.48986) (xy 402.237956 -434.48986)
			(xy 402.238069 -434.474774) (xy 402.239848 -434.444656) (xy 402.241512 -434.429662) (xy 402.241512 -433.350162)
			(xy 402.239847 -433.335168) (xy 402.238066 -433.30505) (xy 402.237956 -433.289964) (xy 402.238069 -433.274878)
			(xy 402.239848 -433.24476) (xy 402.241512 -433.229766) (xy 402.241512 -432.618896) (xy 402.241909 -432.606811)
			(xy 402.24938 -432.583825) (xy 402.26359 -432.564273) (xy 402.283146 -432.550069) (xy 402.306135 -432.542606)
			(xy 402.31822 -432.542188) (xy 403.25802 -432.542188) (xy 403.270095 -432.542647) (xy 403.293062 -432.550115)
			(xy 403.312599 -432.564313) (xy 403.326793 -432.583852) (xy 403.334255 -432.606821) (xy 403.334728 -432.618896)
			(xy 403.334728 -435.16042) (xy 403.334253 -435.172494) (xy 403.326787 -435.195458) (xy 403.312593 -435.214993)
			(xy 403.293058 -435.229187) (xy 403.270094 -435.236653) (xy 403.25802 -435.237128) (xy 402.31822 -435.237128)
			(xy 402.306148 -435.236619) (xy 402.283185 -435.229165) (xy 402.26365 -435.214979) (xy 402.249454 -435.195451)
			(xy 402.241987 -435.172491) (xy 402.241512 -435.16042) (xy 402.241512 -434.550058) (xy 402.239846 -434.535064)
			(xy 402.238066 -434.504946) (xy 402.237956 -434.48986) (xy 401.334732 -434.48986) (xy 401.334732 -435.489858)
			(xy 404.237952 -435.489858) (xy 404.238065 -435.474772) (xy 404.239844 -435.444654) (xy 404.241508 -435.42966)
			(xy 404.241508 -434.35016) (xy 404.239843 -434.335166) (xy 404.238062 -434.305048) (xy 404.237952 -434.289962)
			(xy 404.238065 -434.274876) (xy 404.239844 -434.244758) (xy 404.241508 -434.229764) (xy 404.241508 -433.618894)
			(xy 404.242002 -433.606807) (xy 404.249456 -433.583812) (xy 404.263637 -433.564235) (xy 404.283163 -433.549984)
			(xy 404.306131 -433.542446) (xy 404.318216 -433.541932) (xy 405.258016 -433.541932) (xy 405.270129 -433.542303)
			(xy 405.293162 -433.549811) (xy 405.312738 -433.564083) (xy 405.326931 -433.583716) (xy 405.334345 -433.606779)
			(xy 405.334724 -433.618894) (xy 405.334724 -434.48986) (xy 406.237948 -434.48986) (xy 406.238061 -434.474774)
			(xy 406.23984 -434.444656) (xy 406.241504 -434.429662) (xy 406.241504 -433.350162) (xy 406.239839 -433.335168)
			(xy 406.238058 -433.30505) (xy 406.237948 -433.289964) (xy 406.238061 -433.274878) (xy 406.23984 -433.24476)
			(xy 406.241504 -433.229766) (xy 406.241504 -432.618896) (xy 406.241909 -432.606812) (xy 406.249379 -432.583827)
			(xy 406.263587 -432.564276) (xy 406.283141 -432.550072) (xy 406.306128 -432.542607) (xy 406.318212 -432.542188)
			(xy 407.258012 -432.542188) (xy 407.270087 -432.542654) (xy 407.293054 -432.550119) (xy 407.31259 -432.564316)
			(xy 407.326784 -432.583854) (xy 407.334247 -432.606821) (xy 407.33472 -432.618896) (xy 407.33472 -435.16042)
			(xy 407.334253 -435.172494) (xy 407.326786 -435.19546) (xy 407.31259 -435.214996) (xy 407.293053 -435.22919)
			(xy 407.270086 -435.236654) (xy 407.258012 -435.237128) (xy 406.318212 -435.237128) (xy 406.30614 -435.236626)
			(xy 406.283177 -435.229169) (xy 406.263641 -435.214982) (xy 406.249446 -435.195452) (xy 406.241979 -435.172492)
			(xy 406.241504 -435.16042) (xy 406.241504 -434.550058) (xy 406.239838 -434.535064) (xy 406.238058 -434.504946)
			(xy 406.237948 -434.48986) (xy 405.334724 -434.48986) (xy 405.334724 -435.489858) (xy 408.237944 -435.489858)
			(xy 408.238057 -435.474772) (xy 408.239836 -435.444654) (xy 408.2415 -435.42966) (xy 408.2415 -434.35016)
			(xy 408.239834 -434.335166) (xy 408.238054 -434.305048) (xy 408.237944 -434.289962) (xy 408.238057 -434.274876)
			(xy 408.239836 -434.244758) (xy 408.2415 -434.229764) (xy 408.2415 -433.618894) (xy 408.242002 -433.606808)
			(xy 408.249455 -433.583814) (xy 408.263634 -433.564238) (xy 408.283158 -433.549986) (xy 408.306124 -433.542447)
			(xy 408.318208 -433.541932) (xy 409.258008 -433.541932) (xy 409.270121 -433.54231) (xy 409.293154 -433.549815)
			(xy 409.312729 -433.564086) (xy 409.326923 -433.583717) (xy 409.334337 -433.60678) (xy 409.334716 -433.618894)
			(xy 409.334716 -434.48986) (xy 410.23794 -434.48986) (xy 410.238053 -434.474774) (xy 410.239832 -434.444656)
			(xy 410.241496 -434.429662) (xy 410.241496 -433.350162) (xy 410.239831 -433.335168) (xy 410.23805 -433.30505)
			(xy 410.23794 -433.289964) (xy 410.238053 -433.274878) (xy 410.239832 -433.24476) (xy 410.241496 -433.229766)
			(xy 410.241496 -432.618896) (xy 410.241961 -432.606821) (xy 410.249425 -432.583853) (xy 410.263621 -432.564316)
			(xy 410.28316 -432.550121) (xy 410.306129 -432.54266) (xy 410.318204 -432.542188) (xy 411.258004 -432.542188)
			(xy 411.270078 -432.542661) (xy 411.293045 -432.550124) (xy 411.312582 -432.564318) (xy 411.326776 -432.583855)
			(xy 411.334239 -432.606822) (xy 411.334712 -432.618896) (xy 411.334712 -435.16042) (xy 411.334253 -435.172495)
			(xy 411.326785 -435.195462) (xy 411.312587 -435.214999) (xy 411.293048 -435.229193) (xy 411.270079 -435.236655)
			(xy 411.258004 -435.237128) (xy 410.318204 -435.237128) (xy 410.306132 -435.236633) (xy 410.283168 -435.229174)
			(xy 410.263633 -435.214984) (xy 410.249437 -435.195454) (xy 410.241971 -435.172492) (xy 410.241496 -435.16042)
			(xy 410.241496 -434.550058) (xy 410.23983 -434.535064) (xy 410.23805 -434.504946) (xy 410.23794 -434.48986)
			(xy 409.334716 -434.48986) (xy 409.334716 -435.489858) (xy 412.237936 -435.489858) (xy 412.238051 -435.474773)
			(xy 412.23983 -435.444654) (xy 412.241492 -435.42966) (xy 412.241492 -434.35016) (xy 412.239826 -434.335166)
			(xy 412.238046 -434.305048) (xy 412.237936 -434.289962) (xy 412.238051 -434.274877) (xy 412.23983 -434.244758)
			(xy 412.241492 -434.229764) (xy 412.241492 -433.618894) (xy 412.242002 -433.606809) (xy 412.249454 -433.583816)
			(xy 412.263631 -433.564241) (xy 412.283153 -433.549989) (xy 412.306117 -433.542448) (xy 412.3182 -433.541932)
			(xy 413.258 -433.541932) (xy 413.270112 -433.542317) (xy 413.293145 -433.54982) (xy 413.312721 -433.564088)
			(xy 413.326914 -433.583719) (xy 413.334329 -433.60678) (xy 413.334708 -433.618894) (xy 413.334708 -436.160418)
			(xy 413.334209 -436.172504) (xy 413.326753 -436.195497) (xy 413.312573 -436.215072) (xy 413.29305 -436.229324)
			(xy 413.270084 -436.236864) (xy 413.258 -436.23738) (xy 412.3182 -436.23738) (xy 412.306089 -436.236984)
			(xy 412.283058 -436.229482) (xy 412.263483 -436.215216) (xy 412.24929 -436.195589) (xy 412.241872 -436.17253)
			(xy 412.241492 -436.160418) (xy 412.241492 -435.550056) (xy 412.239826 -435.535062) (xy 412.238046 -435.504944)
			(xy 412.237936 -435.489858) (xy 409.334716 -435.489858) (xy 409.334716 -436.160418) (xy 409.334307 -436.172513)
			(xy 409.32684 -436.195522) (xy 409.31264 -436.215105) (xy 409.293092 -436.229353) (xy 409.270102 -436.236877)
			(xy 409.258008 -436.23738) (xy 408.318208 -436.23738) (xy 408.306098 -436.236977) (xy 408.283067 -436.229477)
			(xy 408.263492 -436.215213) (xy 408.249298 -436.195587) (xy 408.24188 -436.17253) (xy 408.2415 -436.160418)
			(xy 408.2415 -435.550056) (xy 408.239834 -435.535062) (xy 408.238054 -435.504944) (xy 408.237944 -435.489858)
			(xy 405.334724 -435.489858) (xy 405.334724 -436.160418) (xy 405.334307 -436.172512) (xy 405.326841 -436.195519)
			(xy 405.312643 -436.215102) (xy 405.293097 -436.229351) (xy 405.270109 -436.236876) (xy 405.258016 -436.23738)
			(xy 404.318216 -436.23738) (xy 404.306106 -436.23697) (xy 404.283076 -436.229472) (xy 404.263501 -436.21521)
			(xy 404.249306 -436.195585) (xy 404.241889 -436.172529) (xy 404.241508 -436.160418) (xy 404.241508 -435.550056)
			(xy 404.239842 -435.535062) (xy 404.238062 -435.504944) (xy 404.237952 -435.489858) (xy 401.334732 -435.489858)
			(xy 401.334732 -436.160418) (xy 401.334308 -436.172511) (xy 401.326843 -436.195517) (xy 401.312646 -436.215099)
			(xy 401.293102 -436.229348) (xy 401.270116 -436.236875) (xy 401.258024 -436.23738) (xy 400.318224 -436.23738)
			(xy 400.306114 -436.236963) (xy 400.283085 -436.229468) (xy 400.263509 -436.215207) (xy 400.249315 -436.195584)
			(xy 400.241897 -436.172529) (xy 400.241516 -436.160418) (xy 400.241516 -435.550056) (xy 400.23985 -435.535062)
			(xy 400.23807 -435.504944) (xy 400.23796 -435.489858) (xy 396.334996 -435.489858) (xy 396.334996 -436.160418)
			(xy 396.334504 -436.17253) (xy 396.327016 -436.195568) (xy 396.312778 -436.215167) (xy 396.293183 -436.229409)
			(xy 396.270146 -436.236902) (xy 396.258034 -436.23738) (xy 395.318234 -436.23738) (xy 395.306115 -436.236911)
			(xy 395.28306 -436.229431) (xy 395.263446 -436.215191) (xy 395.249193 -436.195587) (xy 395.241697 -436.172537)
			(xy 395.241272 -436.160418) (xy 395.241272 -435.548024) (xy 395.239724 -435.533532) (xy 395.238074 -435.504432)
			(xy 395.23797 -435.489858) (xy 392.335004 -435.489858) (xy 392.335004 -436.160418) (xy 392.334504 -436.172529)
			(xy 392.327017 -436.195566) (xy 392.312781 -436.215164) (xy 392.293188 -436.229406) (xy 392.270153 -436.236901)
			(xy 392.258042 -436.23738) (xy 391.318242 -436.23738) (xy 391.306123 -436.236905) (xy 391.283069 -436.229426)
			(xy 391.263455 -436.215188) (xy 391.249201 -436.195585) (xy 391.241705 -436.172536) (xy 391.24128 -436.160418)
			(xy 391.24128 -435.548024) (xy 391.239732 -435.533532) (xy 391.238082 -435.504432) (xy 391.237978 -435.489858)
			(xy 388.335012 -435.489858) (xy 388.335012 -436.160418) (xy 388.334505 -436.172529) (xy 388.327018 -436.195564)
			(xy 388.312784 -436.215161) (xy 388.293193 -436.229404) (xy 388.27016 -436.2369) (xy 388.25805 -436.23738)
			(xy 387.31825 -436.23738) (xy 387.306135 -436.236931) (xy 387.283093 -436.229432) (xy 387.263493 -436.215184)
			(xy 387.249253 -436.195578) (xy 387.241764 -436.172534) (xy 387.241288 -436.160418) (xy 387.241288 -435.548024)
			(xy 387.23974 -435.533532) (xy 387.23809 -435.504432) (xy 387.237986 -435.489858) (xy 384.33502 -435.489858)
			(xy 384.33502 -436.160418) (xy 384.334654 -436.172546) (xy 384.327152 -436.195612) (xy 384.312888 -436.215231)
			(xy 384.293258 -436.22948) (xy 384.270186 -436.236964) (xy 384.258058 -436.23738) (xy 383.318258 -436.23738)
			(xy 383.306143 -436.236924) (xy 383.283101 -436.229428) (xy 383.263502 -436.215181) (xy 383.249261 -436.195577)
			(xy 383.241772 -436.172533) (xy 383.241296 -436.160418) (xy 383.241296 -435.548024) (xy 383.239748 -435.533532)
			(xy 383.238098 -435.504432) (xy 383.237994 -435.489858) (xy 361.616728 -435.489858) (xy 361.642562 -435.536833)
			(xy 361.697938 -435.654184) (xy 361.74595 -435.774736) (xy 361.786412 -435.898026) (xy 361.81917 -436.023584)
			(xy 361.844098 -436.150927) (xy 361.861101 -436.279569) (xy 361.870114 -436.409016) (xy 361.871103 -436.538773)
			(xy 361.864062 -436.668342) (xy 361.849021 -436.797228) (xy 361.826035 -436.924936) (xy 361.795194 -437.050978)
			(xy 361.756614 -437.174871) (xy 361.710445 -437.29614) (xy 361.656862 -437.41432) (xy 361.596072 -437.52896)
			(xy 361.528306 -437.63962) (xy 361.453825 -437.745876) (xy 361.372914 -437.847321) (xy 361.285882 -437.943567)
			(xy 361.193064 -438.034245) (xy 361.128666 -438.089802) (xy 381.21844 -438.089802) (xy 381.218949 -438.057222)
			(xy 381.226923 -437.992551) (xy 381.24274 -437.929339) (xy 381.266163 -437.868533) (xy 381.29684 -437.811045)
			(xy 381.334312 -437.757737) (xy 381.378017 -437.709407) (xy 381.402336 -437.68772) (xy 381.482854 -437.523382)
			(xy 381.487553 -437.512865) (xy 381.491041 -437.490107) (xy 381.487557 -437.467349) (xy 381.482854 -437.456834)
			(xy 381.401828 -437.291734) (xy 381.377559 -437.270044) (xy 381.333961 -437.221711) (xy 381.296587 -437.168419)
			(xy 381.265994 -437.110966) (xy 381.24264 -437.050209) (xy 381.226873 -436.987056) (xy 381.21893 -436.922451)
			(xy 381.21844 -436.889906) (xy 381.219141 -436.85078) (xy 381.230615 -436.773373) (xy 381.2413 -436.735728)
			(xy 381.2413 -436.219092) (xy 381.241709 -436.206983) (xy 381.249211 -436.183955) (xy 381.263474 -436.164382)
			(xy 381.283097 -436.150188) (xy 381.306151 -436.142767) (xy 381.318262 -436.142384) (xy 382.258062 -436.142384)
			(xy 382.270154 -436.142841) (xy 382.293161 -436.150292) (xy 382.312745 -436.16448) (xy 382.326995 -436.184019)
			(xy 382.334521 -436.207002) (xy 382.335024 -436.219092) (xy 382.335024 -438.760616) (xy 382.334598 -438.772723)
			(xy 382.327097 -438.795747) (xy 382.312837 -438.815318) (xy 382.293219 -438.829513) (xy 382.270171 -438.836937)
			(xy 382.258062 -438.837324) (xy 381.318262 -438.837324) (xy 381.306167 -438.836924) (xy 381.283159 -438.829453)
			(xy 381.263577 -438.81525) (xy 381.249329 -438.795701) (xy 381.241804 -438.77271) (xy 381.2413 -438.760616)
			(xy 381.2413 -438.24398) (xy 381.230613 -438.206335) (xy 381.219136 -438.128928) (xy 381.21844 -438.089802)
			(xy 361.128666 -438.089802) (xy 361.094814 -438.119007) (xy 360.991508 -438.19753) (xy 360.883543 -438.269512)
			(xy 360.771333 -438.334677) (xy 360.655306 -438.392776) (xy 360.535907 -438.443587) (xy 360.413594 -438.486915)
			(xy 360.288835 -438.522593) (xy 360.162108 -438.550485) (xy 360.033898 -438.570485) (xy 359.904696 -438.582516)
			(xy 359.774998 -438.586531) (xy 359.6453 -438.582516) (xy 359.516098 -438.570485) (xy 359.387888 -438.550485)
			(xy 359.261161 -438.522593) (xy 359.136402 -438.486915) (xy 359.014089 -438.443587) (xy 358.89469 -438.392776)
			(xy 358.778663 -438.334677) (xy 358.666453 -438.269512) (xy 358.558488 -438.19753) (xy 358.455182 -438.119007)
			(xy 358.356932 -438.034245) (xy 358.264114 -437.943567) (xy 358.177082 -437.847321) (xy 358.096171 -437.745876)
			(xy 358.02169 -437.63962) (xy 357.953924 -437.52896) (xy 357.893134 -437.41432) (xy 357.839551 -437.29614)
			(xy 357.793382 -437.174871) (xy 357.754802 -437.050978) (xy 357.723961 -436.924936) (xy 357.700975 -436.797228)
			(xy 357.685934 -436.668342) (xy 357.678893 -436.538773) (xy 357.679882 -436.409016) (xy 357.688895 -436.279569)
			(xy 357.705898 -436.150927) (xy 357.730826 -436.023584) (xy 357.763584 -435.898026) (xy 357.804046 -435.774736)
			(xy 357.852058 -435.654184) (xy 357.907434 -435.536833) (xy 357.969964 -435.423133) (xy 358.039407 -435.313518)
			(xy 358.115498 -435.208409) (xy 358.197945 -435.108208) (xy 358.286433 -435.013299) (xy 358.380622 -434.924045)
			(xy 358.430068 -434.882036) (xy 358.441235 -434.872067) (xy 358.457661 -434.847056) (xy 358.466134 -434.818358)
			(xy 358.465926 -434.788437) (xy 358.457055 -434.759859) (xy 358.440283 -434.735079) (xy 358.417049 -434.716224)
			(xy 358.403398 -434.710078) (xy 358.324356 -434.677212) (xy 358.169157 -434.604934) (xy 358.017549 -434.5254)
			(xy 357.869871 -434.438788) (xy 357.726451 -434.345291) (xy 357.587612 -434.24512) (xy 357.453663 -434.138498)
			(xy 357.324904 -434.025662) (xy 357.201623 -433.906867) (xy 357.084096 -433.782376) (xy 356.972584 -433.652469)
			(xy 356.867339 -433.517435) (xy 356.768594 -433.377578) (xy 356.676571 -433.233209) (xy 356.591476 -433.084651)
			(xy 356.513498 -432.932237) (xy 356.442812 -432.776307) (xy 356.379576 -432.61721) (xy 356.323932 -432.455301)
			(xy 356.276004 -432.290943) (xy 356.235899 -432.124503) (xy 356.203706 -431.956354) (xy 356.179498 -431.78687)
			(xy 356.163329 -431.616432) (xy 356.155235 -431.44542) (xy 356.154736 -431.359818) (xy 346.23502 -431.359818)
			(xy 346.23502 -432.560476) (xy 346.234563 -432.572582) (xy 346.227073 -432.595605) (xy 346.212821 -432.615176)
			(xy 346.193209 -432.629373) (xy 346.170165 -432.636797) (xy 346.158058 -432.637184) (xy 345.218258 -432.637184)
			(xy 345.206169 -432.636729) (xy 345.183171 -432.629264) (xy 345.163593 -432.615073) (xy 345.149343 -432.595539)
			(xy 345.141808 -432.572564) (xy 345.141296 -432.560476) (xy 345.141296 -431.948082) (xy 345.139753 -431.93359)
			(xy 345.1381 -431.90449) (xy 345.137994 -431.889916) (xy 342.235028 -431.889916) (xy 342.235028 -432.560476)
			(xy 342.234563 -432.572581) (xy 342.227074 -432.595602) (xy 342.212824 -432.615174) (xy 342.193214 -432.62937)
			(xy 342.170172 -432.636796) (xy 342.158066 -432.637184) (xy 341.218266 -432.637184) (xy 341.206177 -432.636722)
			(xy 341.183179 -432.629259) (xy 341.163602 -432.61507) (xy 341.149352 -432.595538) (xy 341.141816 -432.572563)
			(xy 341.141304 -432.560476) (xy 341.141304 -431.948082) (xy 341.13976 -431.93359) (xy 341.138108 -431.90449)
			(xy 341.138002 -431.889916) (xy 338.235036 -431.889916) (xy 338.235036 -432.560476) (xy 338.234564 -432.57258)
			(xy 338.227075 -432.5956) (xy 338.212827 -432.615171) (xy 338.193219 -432.629367) (xy 338.170179 -432.636795)
			(xy 338.158074 -432.637184) (xy 337.218274 -432.637184) (xy 337.206185 -432.636715) (xy 337.183188 -432.629254)
			(xy 337.163611 -432.615067) (xy 337.14936 -432.595536) (xy 337.141824 -432.572563) (xy 337.141312 -432.560476)
			(xy 337.141312 -431.948082) (xy 337.139768 -431.93359) (xy 337.138116 -431.90449) (xy 337.13801 -431.889916)
			(xy 334.235044 -431.889916) (xy 334.235044 -432.560476) (xy 334.234564 -432.572579) (xy 334.227076 -432.595598)
			(xy 334.21283 -432.615168) (xy 334.193224 -432.629365) (xy 334.170186 -432.636794) (xy 334.158082 -432.637184)
			(xy 333.218282 -432.637184) (xy 333.206194 -432.636709) (xy 333.183197 -432.62925) (xy 333.163619 -432.615065)
			(xy 333.149368 -432.595535) (xy 333.141832 -432.572563) (xy 333.14132 -432.560476) (xy 333.14132 -431.948082)
			(xy 333.139776 -431.93359) (xy 333.138124 -431.90449) (xy 333.138018 -431.889916) (xy 329.2348 -431.889916)
			(xy 329.2348 -432.560476) (xy 329.234367 -432.572558) (xy 329.226905 -432.595542) (xy 329.212704 -432.615093)
			(xy 329.193156 -432.629297) (xy 329.170174 -432.636764) (xy 329.158092 -432.637184) (xy 328.218292 -432.637184)
			(xy 328.206206 -432.636794) (xy 328.183219 -432.629321) (xy 328.163667 -432.61511) (xy 328.149464 -432.595552)
			(xy 328.142001 -432.572562) (xy 328.141584 -432.560476) (xy 328.141584 -431.950114) (xy 328.139914 -431.935121)
			(xy 328.138137 -431.905002) (xy 328.138028 -431.889916) (xy 325.234808 -431.889916) (xy 325.234808 -432.560476)
			(xy 325.234367 -432.572557) (xy 325.226906 -432.595539) (xy 325.212707 -432.61509) (xy 325.193161 -432.629295)
			(xy 325.170181 -432.636763) (xy 325.1581 -432.637184) (xy 324.2183 -432.637184) (xy 324.206215 -432.636787)
			(xy 324.183228 -432.629317) (xy 324.163676 -432.615107) (xy 324.149472 -432.59555) (xy 324.142009 -432.572561)
			(xy 324.141592 -432.560476) (xy 324.141592 -431.950114) (xy 324.139922 -431.935121) (xy 324.138145 -431.905002)
			(xy 324.138036 -431.889916) (xy 321.234816 -431.889916) (xy 321.234816 -432.560476) (xy 321.234367 -432.572557)
			(xy 321.226907 -432.595537) (xy 321.21271 -432.615087) (xy 321.193166 -432.629292) (xy 321.170188 -432.636762)
			(xy 321.158108 -432.637184) (xy 320.218308 -432.637184) (xy 320.206223 -432.63678) (xy 320.183237 -432.629312)
			(xy 320.163684 -432.615105) (xy 320.149481 -432.595549) (xy 320.142017 -432.572561) (xy 320.1416 -432.560476)
			(xy 320.1416 -431.950114) (xy 320.13993 -431.935121) (xy 320.138153 -431.905002) (xy 320.138044 -431.889916)
			(xy 317.234824 -431.889916) (xy 317.234824 -432.560476) (xy 317.234367 -432.572556) (xy 317.226908 -432.595535)
			(xy 317.212713 -432.615084) (xy 317.193171 -432.62929) (xy 317.170196 -432.636761) (xy 317.158116 -432.637184)
			(xy 316.218316 -432.637184) (xy 316.206232 -432.636773) (xy 316.183246 -432.629307) (xy 316.163693 -432.615101)
			(xy 316.149489 -432.595547) (xy 316.142026 -432.57256) (xy 316.141608 -432.560476) (xy 316.141608 -431.950114)
			(xy 316.139938 -431.935121) (xy 316.138161 -431.905002) (xy 316.138052 -431.889916) (xy 274.613204 -431.889916)
			(xy 274.618425 -431.905986) (xy 274.665585 -432.076867) (xy 274.705031 -432.249692) (xy 274.736684 -432.424113)
			(xy 274.760479 -432.599778) (xy 274.77637 -432.776334) (xy 274.784323 -432.953425) (xy 274.78482 -433.04206)
			(xy 274.784323 -433.130695) (xy 274.77637 -433.307786) (xy 274.760479 -433.484342) (xy 274.736684 -433.660007)
			(xy 274.705031 -433.834428) (xy 274.665585 -434.007253) (xy 274.618425 -434.178134) (xy 274.563646 -434.346728)
			(xy 274.509927 -434.48986) (xy 314.118498 -434.48986) (xy 314.118984 -434.457304) (xy 314.126934 -434.392678)
			(xy 314.142721 -434.329509) (xy 314.166111 -434.268742) (xy 314.196751 -434.21129) (xy 314.234182 -434.158012)
			(xy 314.277844 -434.109708) (xy 314.30214 -434.088032) (xy 314.382912 -433.923186) (xy 314.38761 -433.912668)
			(xy 314.391101 -433.889911) (xy 314.387617 -433.867152) (xy 314.382912 -433.856638) (xy 314.30214 -433.691792)
			(xy 314.277865 -433.670094) (xy 314.23421 -433.621789) (xy 314.196782 -433.568513) (xy 314.166143 -433.511064)
			(xy 314.14275 -433.450303) (xy 314.126955 -433.387139) (xy 314.118994 -433.322518) (xy 314.118498 -433.289964)
			(xy 314.119225 -433.250639) (xy 314.13083 -433.172849) (xy 314.141612 -433.135024) (xy 314.141612 -432.618896)
			(xy 314.142009 -432.606811) (xy 314.14948 -432.583825) (xy 314.16369 -432.564273) (xy 314.183246 -432.550069)
			(xy 314.206235 -432.542606) (xy 314.21832 -432.542188) (xy 315.15812 -432.542188) (xy 315.170195 -432.542647)
			(xy 315.193162 -432.550115) (xy 315.212699 -432.564313) (xy 315.226893 -432.583852) (xy 315.234355 -432.606821)
			(xy 315.234828 -432.618896) (xy 315.234828 -435.16042) (xy 315.234353 -435.172494) (xy 315.226887 -435.195458)
			(xy 315.212693 -435.214993) (xy 315.193158 -435.229187) (xy 315.170194 -435.236653) (xy 315.15812 -435.237128)
			(xy 314.21832 -435.237128) (xy 314.206248 -435.236619) (xy 314.183285 -435.229165) (xy 314.16375 -435.214979)
			(xy 314.149554 -435.195451) (xy 314.142087 -435.172491) (xy 314.141612 -435.16042) (xy 314.141612 -434.6448)
			(xy 314.130805 -434.606981) (xy 314.119203 -434.529187) (xy 314.118498 -434.48986) (xy 274.509927 -434.48986)
			(xy 274.501358 -434.512693) (xy 274.431686 -434.675698) (xy 274.354772 -434.835412) (xy 274.270769 -434.991515)
			(xy 274.179848 -435.143692) (xy 274.082191 -435.291636) (xy 273.977994 -435.43505) (xy 273.934286 -435.489858)
			(xy 316.118494 -435.489858) (xy 316.118945 -435.4573) (xy 316.126897 -435.392672) (xy 316.142688 -435.329501)
			(xy 316.166082 -435.268733) (xy 316.196728 -435.211281) (xy 316.234166 -435.158004) (xy 316.277836 -435.109703)
			(xy 316.302136 -435.08803) (xy 316.382908 -434.923184) (xy 316.387608 -434.912667) (xy 316.391098 -434.889909)
			(xy 316.387613 -434.86715) (xy 316.382908 -434.856636) (xy 316.302136 -434.69179) (xy 316.27786 -434.670094)
			(xy 316.234205 -434.621788) (xy 316.196777 -434.568512) (xy 316.166138 -434.511063) (xy 316.142745 -434.450301)
			(xy 316.126951 -434.387137) (xy 316.11899 -434.322516) (xy 316.118494 -434.289962) (xy 316.119221 -434.250637)
			(xy 316.130826 -434.172847) (xy 316.141608 -434.135022) (xy 316.141608 -433.618894) (xy 316.142102 -433.606807)
			(xy 316.149556 -433.583812) (xy 316.163737 -433.564235) (xy 316.183263 -433.549984) (xy 316.206231 -433.542446)
			(xy 316.218316 -433.541932) (xy 317.158116 -433.541932) (xy 317.170229 -433.542303) (xy 317.193262 -433.549811)
			(xy 317.212838 -433.564083) (xy 317.227031 -433.583716) (xy 317.234445 -433.606779) (xy 317.234824 -433.618894)
			(xy 317.234824 -434.48986) (xy 318.11849 -434.48986) (xy 318.118944 -434.457302) (xy 318.126896 -434.392675)
			(xy 318.142686 -434.329503) (xy 318.16608 -434.268736) (xy 318.196725 -434.211283) (xy 318.234163 -434.158007)
			(xy 318.277832 -434.109705) (xy 318.302132 -434.088032) (xy 318.382904 -433.923186) (xy 318.387603 -433.912668)
			(xy 318.391094 -433.889911) (xy 318.387609 -433.867152) (xy 318.382904 -433.856638) (xy 318.302132 -433.691792)
			(xy 318.277856 -433.670096) (xy 318.234201 -433.62179) (xy 318.196773 -433.568514) (xy 318.166134 -433.511065)
			(xy 318.142742 -433.450303) (xy 318.126947 -433.387139) (xy 318.118986 -433.322518) (xy 318.11849 -433.289964)
			(xy 318.119218 -433.250639) (xy 318.130822 -433.172849) (xy 318.141604 -433.135024) (xy 318.141604 -432.618896)
			(xy 318.142009 -432.606812) (xy 318.149479 -432.583827) (xy 318.163687 -432.564276) (xy 318.183241 -432.550072)
			(xy 318.206228 -432.542607) (xy 318.218312 -432.542188) (xy 319.158112 -432.542188) (xy 319.170187 -432.542654)
			(xy 319.193154 -432.550119) (xy 319.21269 -432.564316) (xy 319.226884 -432.583854) (xy 319.234347 -432.606821)
			(xy 319.23482 -432.618896) (xy 319.23482 -435.16042) (xy 319.234353 -435.172494) (xy 319.226886 -435.19546)
			(xy 319.21269 -435.214996) (xy 319.193153 -435.22919) (xy 319.170186 -435.236654) (xy 319.158112 -435.237128)
			(xy 318.218312 -435.237128) (xy 318.20624 -435.236626) (xy 318.183277 -435.229169) (xy 318.163741 -435.214982)
			(xy 318.149546 -435.195452) (xy 318.142079 -435.172492) (xy 318.141604 -435.16042) (xy 318.141604 -434.6448)
			(xy 318.130797 -434.606981) (xy 318.119195 -434.529187) (xy 318.11849 -434.48986) (xy 317.234824 -434.48986)
			(xy 317.234824 -435.489858) (xy 320.118486 -435.489858) (xy 320.11894 -435.4573) (xy 320.126892 -435.392673)
			(xy 320.142683 -435.329502) (xy 320.166076 -435.268734) (xy 320.196722 -435.211281) (xy 320.234159 -435.158005)
			(xy 320.277828 -435.109703) (xy 320.302128 -435.08803) (xy 320.3829 -434.923184) (xy 320.3876 -434.912667)
			(xy 320.391091 -434.889909) (xy 320.387606 -434.86715) (xy 320.3829 -434.856636) (xy 320.302128 -434.69179)
			(xy 320.27785 -434.670096) (xy 320.234195 -434.62179) (xy 320.196768 -434.568513) (xy 320.166129 -434.511063)
			(xy 320.142737 -434.450301) (xy 320.126942 -434.387137) (xy 320.118982 -434.322517) (xy 320.118486 -434.289962)
			(xy 320.119213 -434.250637) (xy 320.130818 -434.172847) (xy 320.1416 -434.135022) (xy 320.1416 -433.618894)
			(xy 320.142102 -433.606808) (xy 320.149555 -433.583814) (xy 320.163734 -433.564238) (xy 320.183258 -433.549986)
			(xy 320.206224 -433.542447) (xy 320.218308 -433.541932) (xy 321.158108 -433.541932) (xy 321.170221 -433.54231)
			(xy 321.193254 -433.549815) (xy 321.212829 -433.564086) (xy 321.227023 -433.583717) (xy 321.234437 -433.60678)
			(xy 321.234816 -433.618894) (xy 321.234816 -434.48986) (xy 322.118482 -434.48986) (xy 322.118939 -434.457303)
			(xy 322.12689 -434.392675) (xy 322.142681 -434.329504) (xy 322.166074 -434.268736) (xy 322.196719 -434.211284)
			(xy 322.234156 -434.158007) (xy 322.277824 -434.109706) (xy 322.302124 -434.088032) (xy 322.382896 -433.923186)
			(xy 322.387595 -433.912668) (xy 322.391086 -433.889911) (xy 322.387602 -433.867152) (xy 322.382896 -433.856638)
			(xy 322.302124 -433.691792) (xy 322.277846 -433.670097) (xy 322.234192 -433.621791) (xy 322.196765 -433.568515)
			(xy 322.166126 -433.511065) (xy 322.142734 -433.450303) (xy 322.126939 -433.387139) (xy 322.118978 -433.322518)
			(xy 322.118482 -433.289964) (xy 322.11921 -433.250639) (xy 322.130814 -433.172849) (xy 322.141596 -433.135024)
			(xy 322.141596 -432.618896) (xy 322.142061 -432.606821) (xy 322.149525 -432.583853) (xy 322.163721 -432.564316)
			(xy 322.18326 -432.550121) (xy 322.206229 -432.54266) (xy 322.218304 -432.542188) (xy 323.158104 -432.542188)
			(xy 323.170178 -432.542661) (xy 323.193145 -432.550124) (xy 323.212682 -432.564318) (xy 323.226876 -432.583855)
			(xy 323.234339 -432.606822) (xy 323.234812 -432.618896) (xy 323.234812 -435.16042) (xy 323.234353 -435.172495)
			(xy 323.226885 -435.195462) (xy 323.212687 -435.214999) (xy 323.193148 -435.229193) (xy 323.170179 -435.236655)
			(xy 323.158104 -435.237128) (xy 322.218304 -435.237128) (xy 322.206232 -435.236633) (xy 322.183268 -435.229174)
			(xy 322.163733 -435.214984) (xy 322.149537 -435.195454) (xy 322.142071 -435.172492) (xy 322.141596 -435.16042)
			(xy 322.141596 -434.6448) (xy 322.130788 -434.606981) (xy 322.119187 -434.529187) (xy 322.118482 -434.48986)
			(xy 321.234816 -434.48986) (xy 321.234816 -435.489858) (xy 324.118478 -435.489858) (xy 324.118935 -435.457301)
			(xy 324.126886 -435.392673) (xy 324.142677 -435.329502) (xy 324.16607 -435.268734) (xy 324.196715 -435.211282)
			(xy 324.234152 -435.158005) (xy 324.27782 -435.109704) (xy 324.30212 -435.08803) (xy 324.382892 -434.923184)
			(xy 324.387593 -434.912667) (xy 324.391084 -434.889909) (xy 324.387598 -434.86715) (xy 324.382892 -434.856636)
			(xy 324.30212 -434.69179) (xy 324.27784 -434.670097) (xy 324.234186 -434.621791) (xy 324.196759 -434.568514)
			(xy 324.166121 -434.511064) (xy 324.142729 -434.450302) (xy 324.126934 -434.387137) (xy 324.118974 -434.322517)
			(xy 324.118478 -434.289962) (xy 324.119206 -434.250637) (xy 324.13081 -434.172847) (xy 324.141592 -434.135022)
			(xy 324.141592 -433.618894) (xy 324.142102 -433.606809) (xy 324.149554 -433.583816) (xy 324.163731 -433.564241)
			(xy 324.183253 -433.549989) (xy 324.206217 -433.542448) (xy 324.2183 -433.541932) (xy 325.1581 -433.541932)
			(xy 325.170212 -433.542317) (xy 325.193245 -433.54982) (xy 325.212821 -433.564088) (xy 325.227014 -433.583719)
			(xy 325.234429 -433.60678) (xy 325.234808 -433.618894) (xy 325.234808 -434.48986) (xy 326.118474 -434.48986)
			(xy 326.118934 -434.457303) (xy 326.126885 -434.392675) (xy 326.142675 -434.329504) (xy 326.166068 -434.268737)
			(xy 326.196712 -434.211284) (xy 326.234149 -434.158007) (xy 326.277816 -434.109706) (xy 326.302116 -434.088032)
			(xy 326.382888 -433.923186) (xy 326.387588 -433.912669) (xy 326.391079 -433.889911) (xy 326.387594 -433.867152)
			(xy 326.382888 -433.856638) (xy 326.302116 -433.691792) (xy 326.277837 -433.670099) (xy 326.234182 -433.621793)
			(xy 326.196756 -433.568516) (xy 326.166117 -433.511066) (xy 326.142725 -433.450304) (xy 326.126931 -433.387139)
			(xy 326.11897 -433.322519) (xy 326.118474 -433.289964) (xy 326.119202 -433.250639) (xy 326.130807 -433.172849)
			(xy 326.141588 -433.135024) (xy 326.141588 -432.618896) (xy 326.142061 -432.606822) (xy 326.149524 -432.583855)
			(xy 326.163718 -432.564318) (xy 326.183255 -432.550124) (xy 326.206222 -432.542661) (xy 326.218296 -432.542188)
			(xy 327.158096 -432.542188) (xy 327.17017 -432.542668) (xy 327.193136 -432.550129) (xy 327.212673 -432.564321)
			(xy 327.226868 -432.583857) (xy 327.234331 -432.606822) (xy 327.234804 -432.618896) (xy 327.234804 -435.16042)
			(xy 327.234353 -435.172496) (xy 327.226884 -435.195464) (xy 327.212684 -435.215001) (xy 327.193143 -435.229195)
			(xy 327.170172 -435.236656) (xy 327.158096 -435.237128) (xy 326.218296 -435.237128) (xy 326.206223 -435.236639)
			(xy 326.183259 -435.229178) (xy 326.163724 -435.214987) (xy 326.149529 -435.195455) (xy 326.142063 -435.172493)
			(xy 326.141588 -435.16042) (xy 326.141588 -434.6448) (xy 326.13078 -434.606981) (xy 326.119179 -434.529187)
			(xy 326.118474 -434.48986) (xy 325.234808 -434.48986) (xy 325.234808 -435.489858) (xy 328.11847 -435.489858)
			(xy 328.11893 -435.457301) (xy 328.126881 -435.392673) (xy 328.142671 -435.329503) (xy 328.166064 -435.268735)
			(xy 328.196709 -435.211282) (xy 328.234145 -435.158006) (xy 328.277813 -435.109704) (xy 328.302112 -435.08803)
			(xy 328.382884 -434.923184) (xy 328.387585 -434.912667) (xy 328.391077 -434.889909) (xy 328.387591 -434.86715)
			(xy 328.382884 -434.856636) (xy 328.302112 -434.69179) (xy 328.277831 -434.670099) (xy 328.234177 -434.621792)
			(xy 328.196751 -434.568515) (xy 328.166112 -434.511065) (xy 328.142721 -434.450302) (xy 328.126926 -434.387138)
			(xy 328.118966 -434.322517) (xy 328.11847 -434.289962) (xy 328.119198 -434.250637) (xy 328.130803 -434.172847)
			(xy 328.141584 -434.135022) (xy 328.141584 -433.618894) (xy 328.142003 -433.6068) (xy 328.149467 -433.583792)
			(xy 328.163664 -433.564208) (xy 328.183211 -433.549959) (xy 328.206199 -433.542435) (xy 328.218292 -433.541932)
			(xy 329.158092 -433.541932) (xy 329.170204 -433.542323) (xy 329.193236 -433.549824) (xy 329.212812 -433.564091)
			(xy 329.227006 -433.58372) (xy 329.234421 -433.606781) (xy 329.2348 -433.618894) (xy 329.2348 -434.48986)
			(xy 331.118464 -434.48986) (xy 331.118927 -434.457303) (xy 331.126878 -434.392676) (xy 331.142668 -434.329505)
			(xy 331.16606 -434.268738) (xy 331.196704 -434.211285) (xy 331.23414 -434.158008) (xy 331.277807 -434.109706)
			(xy 331.302106 -434.088032) (xy 331.382878 -433.923186) (xy 331.387578 -433.912669) (xy 331.39107 -433.889911)
			(xy 331.387585 -433.867152) (xy 331.382878 -433.856638) (xy 331.302106 -433.691792) (xy 331.277825 -433.670101)
			(xy 331.234171 -433.621794) (xy 331.196745 -433.568517) (xy 331.166106 -433.511066) (xy 331.142715 -433.450304)
			(xy 331.126921 -433.387139) (xy 331.11896 -433.322519) (xy 331.118464 -433.289964) (xy 331.119155 -433.250837)
			(xy 331.130636 -433.173431) (xy 331.141324 -433.135786) (xy 331.141324 -432.618896) (xy 331.141713 -432.606785)
			(xy 331.149217 -432.583753) (xy 331.163484 -432.564178) (xy 331.183113 -432.549984) (xy 331.206173 -432.542568)
			(xy 331.218286 -432.542188) (xy 332.158086 -432.542188) (xy 332.17018 -432.54262) (xy 332.193188 -432.550079)
			(xy 332.212772 -432.564273) (xy 332.227021 -432.583817) (xy 332.234545 -432.606804) (xy 332.235048 -432.618896)
			(xy 332.235048 -435.16042) (xy 332.234601 -435.172525) (xy 332.227102 -435.195545) (xy 332.212847 -435.215113)
			(xy 332.193235 -435.229309) (xy 332.170192 -435.236738) (xy 332.158086 -435.237128) (xy 331.218286 -435.237128)
			(xy 331.206192 -435.236704) (xy 331.183186 -435.22924) (xy 331.163603 -435.215043) (xy 331.149354 -435.195499)
			(xy 331.141828 -435.172512) (xy 331.141324 -435.16042) (xy 331.141324 -434.644038) (xy 331.130628 -434.606395)
			(xy 331.119157 -434.528987) (xy 331.118464 -434.48986) (xy 329.2348 -434.48986) (xy 329.2348 -435.489858)
			(xy 333.11846 -435.489858) (xy 333.118923 -435.457301) (xy 333.126874 -435.392674) (xy 333.142664 -435.329503)
			(xy 333.166057 -435.268736) (xy 333.1967 -435.211283) (xy 333.234136 -435.158006) (xy 333.277803 -435.109704)
			(xy 333.302102 -435.08803) (xy 333.382874 -434.923184) (xy 333.387576 -434.912667) (xy 333.391068 -434.889909)
			(xy 333.387581 -434.86715) (xy 333.382874 -434.856636) (xy 333.302102 -434.69179) (xy 333.277819 -434.670101)
			(xy 333.234165 -434.621794) (xy 333.196739 -434.568516) (xy 333.166101 -434.511065) (xy 333.14271 -434.450303)
			(xy 333.126916 -434.387138) (xy 333.118956 -434.322517) (xy 333.11846 -434.289962) (xy 333.119151 -434.250835)
			(xy 333.130632 -434.173429) (xy 333.14132 -434.135784) (xy 333.14132 -433.618894) (xy 333.141807 -433.606781)
			(xy 333.149293 -433.583741) (xy 333.163532 -433.564141) (xy 333.18313 -433.549899) (xy 333.206169 -433.542408)
			(xy 333.218282 -433.541932) (xy 334.158082 -433.541932) (xy 334.170203 -433.542375) (xy 334.19326 -433.549862)
			(xy 334.212875 -433.564108) (xy 334.227127 -433.583718) (xy 334.234621 -433.606773) (xy 334.235044 -433.618894)
			(xy 334.235044 -434.48986) (xy 335.118456 -434.48986) (xy 335.118922 -434.457303) (xy 335.126873 -434.392676)
			(xy 335.142662 -434.329505) (xy 335.166054 -434.268738) (xy 335.196698 -434.211285) (xy 335.234133 -434.158008)
			(xy 335.277799 -434.109706) (xy 335.302098 -434.088032) (xy 335.38287 -433.923186) (xy 335.387571 -433.912669)
			(xy 335.391063 -433.889911) (xy 335.387577 -433.867152) (xy 335.38287 -433.856638) (xy 335.302098 -433.691792)
			(xy 335.277815 -433.670103) (xy 335.234162 -433.621796) (xy 335.196736 -433.568518) (xy 335.166098 -433.511067)
			(xy 335.142707 -433.450304) (xy 335.126912 -433.38714) (xy 335.118952 -433.322519) (xy 335.118456 -433.289964)
			(xy 335.119147 -433.250837) (xy 335.130628 -433.173431) (xy 335.141316 -433.135786) (xy 335.141316 -432.618896)
			(xy 335.141713 -432.606785) (xy 335.149215 -432.583755) (xy 335.163481 -432.564181) (xy 335.183108 -432.549987)
			(xy 335.206166 -432.542569) (xy 335.218278 -432.542188) (xy 336.158078 -432.542188) (xy 336.170171 -432.542627)
			(xy 336.193179 -432.550084) (xy 336.212764 -432.564276) (xy 336.227013 -432.583818) (xy 336.234537 -432.606804)
			(xy 336.23504 -432.618896) (xy 336.23504 -435.16042) (xy 336.234601 -435.172526) (xy 336.227101 -435.195547)
			(xy 336.212844 -435.215116) (xy 336.19323 -435.229312) (xy 336.170185 -435.236739) (xy 336.158078 -435.237128)
			(xy 335.218278 -435.237128) (xy 335.206184 -435.236711) (xy 335.183177 -435.229244) (xy 335.163595 -435.215046)
			(xy 335.149346 -435.1955) (xy 335.14182 -435.172513) (xy 335.141316 -435.16042) (xy 335.141316 -434.644038)
			(xy 335.13062 -434.606395) (xy 335.119149 -434.528987) (xy 335.118456 -434.48986) (xy 334.235044 -434.48986)
			(xy 334.235044 -435.489858) (xy 337.118452 -435.489858) (xy 337.118918 -435.457301) (xy 337.126869 -435.392674)
			(xy 337.142659 -435.329504) (xy 337.166051 -435.268736) (xy 337.196694 -435.211284) (xy 337.234129 -435.158007)
			(xy 337.277795 -435.109704) (xy 337.302094 -435.08803) (xy 337.382866 -434.923184) (xy 337.387563 -434.912666)
			(xy 337.391051 -434.889909) (xy 337.387568 -434.867151) (xy 337.382866 -434.856636) (xy 337.302094 -434.69179)
			(xy 337.277809 -434.670103) (xy 337.234156 -434.621795) (xy 337.196731 -434.568517) (xy 337.166093 -434.511066)
			(xy 337.142702 -434.450303) (xy 337.126908 -434.387138) (xy 337.118948 -434.322517) (xy 337.118452 -434.289962)
			(xy 337.119143 -434.250835) (xy 337.130624 -434.173429) (xy 337.141312 -434.135784) (xy 337.141312 -433.618894)
			(xy 337.141806 -433.606782) (xy 337.149292 -433.583743) (xy 337.163529 -433.564143) (xy 337.183125 -433.549901)
			(xy 337.206162 -433.54241) (xy 337.218274 -433.541932) (xy 338.158074 -433.541932) (xy 338.170195 -433.542382)
			(xy 338.193252 -433.549866) (xy 338.212867 -433.56411) (xy 338.227119 -433.58372) (xy 338.234613 -433.606773)
			(xy 338.235036 -433.618894) (xy 338.235036 -434.48986) (xy 339.118448 -434.48986) (xy 339.118917 -434.457303)
			(xy 339.126867 -434.392676) (xy 339.142657 -434.329506) (xy 339.166048 -434.268739) (xy 339.196691 -434.211286)
			(xy 339.234126 -434.158009) (xy 339.277792 -434.109706) (xy 339.30209 -434.088032) (xy 339.382862 -433.923186)
			(xy 339.387558 -433.912668) (xy 339.391046 -433.889911) (xy 339.387564 -433.867153) (xy 339.382862 -433.856638)
			(xy 339.30209 -433.691792) (xy 339.277805 -433.670105) (xy 339.234152 -433.621797) (xy 339.196727 -433.568518)
			(xy 339.166089 -433.511068) (xy 339.142698 -433.450305) (xy 339.126904 -433.38714) (xy 339.118944 -433.322519)
			(xy 339.118448 -433.289964) (xy 339.11914 -433.250837) (xy 339.13062 -433.173431) (xy 339.141308 -433.135786)
			(xy 339.141308 -432.618896) (xy 339.141713 -432.606786) (xy 339.149214 -432.583757) (xy 339.163479 -432.564184)
			(xy 339.183103 -432.549989) (xy 339.206159 -432.54257) (xy 339.21827 -432.542188) (xy 340.15807 -432.542188)
			(xy 340.170163 -432.542634) (xy 340.19317 -432.550088) (xy 340.212755 -432.564278) (xy 340.227005 -432.58382)
			(xy 340.234529 -432.606805) (xy 340.235032 -432.618896) (xy 340.235032 -435.16042) (xy 340.234601 -435.172527)
			(xy 340.2271 -435.195549) (xy 340.212841 -435.215119) (xy 340.193225 -435.229314) (xy 340.170178 -435.23674)
			(xy 340.15807 -435.237128) (xy 339.21827 -435.237128) (xy 339.206176 -435.236718) (xy 339.183169 -435.229249)
			(xy 339.163586 -435.215049) (xy 339.149338 -435.195502) (xy 339.141812 -435.172513) (xy 339.141308 -435.16042)
			(xy 339.141308 -434.644038) (xy 339.130612 -434.606395) (xy 339.119141 -434.528987) (xy 339.118448 -434.48986)
			(xy 338.235036 -434.48986) (xy 338.235036 -435.489858) (xy 341.118444 -435.489858) (xy 341.118913 -435.457301)
			(xy 341.126863 -435.392674) (xy 341.142653 -435.329504) (xy 341.166045 -435.268737) (xy 341.196687 -435.211284)
			(xy 341.234122 -435.158007) (xy 341.277788 -435.109704) (xy 341.302086 -435.08803) (xy 341.382858 -434.923184)
			(xy 341.387556 -434.912666) (xy 341.391043 -434.889909) (xy 341.387561 -434.867151) (xy 341.382858 -434.856636)
			(xy 341.302086 -434.69179) (xy 341.2778 -434.670105) (xy 341.234147 -434.621796) (xy 341.196722 -434.568518)
			(xy 341.166084 -434.511066) (xy 341.142694 -434.450303) (xy 341.1269 -434.387138) (xy 341.11894 -434.322517)
			(xy 341.118444 -434.289962) (xy 341.119135 -434.250835) (xy 341.130616 -434.173429) (xy 341.141304 -434.135784)
			(xy 341.141304 -433.618894) (xy 341.141806 -433.606783) (xy 341.149291 -433.583745) (xy 341.163526 -433.564146)
			(xy 341.18312 -433.549904) (xy 341.206155 -433.542411) (xy 341.218266 -433.541932) (xy 342.158066 -433.541932)
			(xy 342.170186 -433.542389) (xy 342.193243 -433.549871) (xy 342.212858 -433.564113) (xy 342.227111 -433.583721)
			(xy 342.234605 -433.606774) (xy 342.235028 -433.618894) (xy 342.235028 -434.48986) (xy 343.11844 -434.48986)
			(xy 343.118911 -434.457303) (xy 343.126862 -434.392677) (xy 343.142651 -434.329506) (xy 343.166042 -434.268739)
			(xy 343.196685 -434.211287) (xy 343.234119 -434.158009) (xy 343.277784 -434.109707) (xy 343.302082 -434.088032)
			(xy 343.382854 -433.923186) (xy 343.38755 -433.912668) (xy 343.391039 -433.889911) (xy 343.387557 -433.867153)
			(xy 343.382854 -433.856638) (xy 343.302082 -433.691792) (xy 343.277796 -433.670107) (xy 343.234143 -433.621798)
			(xy 343.196718 -433.568519) (xy 343.166081 -433.511068) (xy 343.14269 -433.450305) (xy 343.126896 -433.38714)
			(xy 343.118936 -433.322519) (xy 343.11844 -433.289964) (xy 343.119132 -433.250837) (xy 343.130612 -433.173431)
			(xy 343.1413 -433.135786) (xy 343.1413 -432.618896) (xy 343.141713 -432.606787) (xy 343.149213 -432.583759)
			(xy 343.163476 -432.564186) (xy 343.183098 -432.549992) (xy 343.206152 -432.542571) (xy 343.218262 -432.542188)
			(xy 344.158062 -432.542188) (xy 344.170154 -432.542641) (xy 344.193162 -432.550093) (xy 344.212747 -432.564281)
			(xy 344.226997 -432.583821) (xy 344.234521 -432.606805) (xy 344.235024 -432.618896) (xy 344.235024 -435.16042)
			(xy 344.234601 -435.172528) (xy 344.227099 -435.195551) (xy 344.212838 -435.215122) (xy 344.19322 -435.229317)
			(xy 344.170171 -435.236741) (xy 344.158062 -435.237128) (xy 343.218262 -435.237128) (xy 343.206167 -435.236724)
			(xy 343.18316 -435.229253) (xy 343.163578 -435.215052) (xy 343.14933 -435.195503) (xy 343.141804 -435.172514)
			(xy 343.1413 -435.16042) (xy 343.1413 -434.644038) (xy 343.130604 -434.606395) (xy 343.119133 -434.528987)
			(xy 343.11844 -434.48986) (xy 342.235028 -434.48986) (xy 342.235028 -435.489858) (xy 345.118436 -435.489858)
			(xy 345.118907 -435.457301) (xy 345.126858 -435.392675) (xy 345.142647 -435.329505) (xy 345.166039 -435.268738)
			(xy 345.196681 -435.211285) (xy 345.234115 -435.158008) (xy 345.27778 -435.109705) (xy 345.302078 -435.08803)
			(xy 345.38285 -434.923184) (xy 345.387548 -434.912666) (xy 345.391036 -434.889909) (xy 345.387553 -434.867151)
			(xy 345.38285 -434.856636) (xy 345.302078 -434.69179) (xy 345.27781 -434.670084) (xy 345.234153 -434.621782)
			(xy 345.196724 -434.568507) (xy 345.166083 -434.51106) (xy 345.142689 -434.450299) (xy 345.126893 -434.387136)
			(xy 345.118932 -434.322516) (xy 345.118436 -434.289962) (xy 345.119128 -434.250835) (xy 345.130608 -434.173429)
			(xy 345.141296 -434.135784) (xy 345.141296 -433.618894) (xy 345.141806 -433.606783) (xy 345.14929 -433.583747)
			(xy 345.163524 -433.564149) (xy 345.183115 -433.549906) (xy 345.206148 -433.542412) (xy 345.218258 -433.541932)
			(xy 346.158058 -433.541932) (xy 346.170178 -433.542396) (xy 346.193234 -433.549876) (xy 346.21285 -433.564116)
			(xy 346.227103 -433.583722) (xy 346.234597 -433.606774) (xy 346.23502 -433.618894) (xy 346.23502 -436.160418)
			(xy 346.234654 -436.172546) (xy 346.227152 -436.195612) (xy 346.212888 -436.215231) (xy 346.193258 -436.22948)
			(xy 346.170186 -436.236964) (xy 346.158058 -436.23738) (xy 345.218258 -436.23738) (xy 345.206143 -436.236924)
			(xy 345.183101 -436.229428) (xy 345.163502 -436.215181) (xy 345.149261 -436.195577) (xy 345.141772 -436.172533)
			(xy 345.141296 -436.160418) (xy 345.141296 -435.644036) (xy 345.130599 -435.606393) (xy 345.119128 -435.528985)
			(xy 345.118436 -435.489858) (xy 342.235028 -435.489858) (xy 342.235028 -436.160418) (xy 342.234655 -436.172545)
			(xy 342.227153 -436.19561) (xy 342.212891 -436.215228) (xy 342.193264 -436.229477) (xy 342.170193 -436.236963)
			(xy 342.158066 -436.23738) (xy 341.218266 -436.23738) (xy 341.206151 -436.236918) (xy 341.18311 -436.229423)
			(xy 341.16351 -436.215178) (xy 341.149269 -436.195576) (xy 341.14178 -436.172533) (xy 341.141304 -436.160418)
			(xy 341.141304 -435.644036) (xy 341.130608 -435.606393) (xy 341.119136 -435.528985) (xy 341.118444 -435.489858)
			(xy 338.235036 -435.489858) (xy 338.235036 -436.160418) (xy 338.234655 -436.172544) (xy 338.227154 -436.195608)
			(xy 338.212894 -436.215225) (xy 338.193269 -436.229474) (xy 338.1702 -436.236962) (xy 338.158074 -436.23738)
			(xy 337.218274 -436.23738) (xy 337.20616 -436.236911) (xy 337.183119 -436.229419) (xy 337.163519 -436.215175)
			(xy 337.149278 -436.195574) (xy 337.141788 -436.172532) (xy 337.141312 -436.160418) (xy 337.141312 -435.644036)
			(xy 337.130616 -435.606393) (xy 337.119144 -435.528985) (xy 337.118452 -435.489858) (xy 334.235044 -435.489858)
			(xy 334.235044 -436.160418) (xy 334.234604 -436.172535) (xy 334.227109 -436.195582) (xy 334.21286 -436.215185)
			(xy 334.19325 -436.229426) (xy 334.1702 -436.236909) (xy 334.158082 -436.23738) (xy 333.218282 -436.23738)
			(xy 333.206168 -436.236904) (xy 333.183127 -436.229414) (xy 333.163528 -436.215172) (xy 333.149286 -436.195573)
			(xy 333.141796 -436.172532) (xy 333.14132 -436.160418) (xy 333.14132 -435.644036) (xy 333.130624 -435.606393)
			(xy 333.119152 -435.528985) (xy 333.11846 -435.489858) (xy 329.2348 -435.489858) (xy 329.2348 -436.160418)
			(xy 329.234309 -436.172505) (xy 329.226852 -436.195499) (xy 329.21267 -436.215075) (xy 329.193145 -436.229327)
			(xy 329.170177 -436.236865) (xy 329.158092 -436.23738) (xy 328.218292 -436.23738) (xy 328.206181 -436.23699)
			(xy 328.18315 -436.229486) (xy 328.163575 -436.215219) (xy 328.149381 -436.19559) (xy 328.141964 -436.172531)
			(xy 328.141584 -436.160418) (xy 328.141584 -435.644798) (xy 328.130775 -435.606979) (xy 328.119175 -435.529185)
			(xy 328.11847 -435.489858) (xy 325.234808 -435.489858) (xy 325.234808 -436.160418) (xy 325.234309 -436.172504)
			(xy 325.226853 -436.195497) (xy 325.212673 -436.215072) (xy 325.19315 -436.229324) (xy 325.170184 -436.236864)
			(xy 325.1581 -436.23738) (xy 324.2183 -436.23738) (xy 324.206189 -436.236984) (xy 324.183158 -436.229482)
			(xy 324.163583 -436.215216) (xy 324.14939 -436.195589) (xy 324.141972 -436.17253) (xy 324.141592 -436.160418)
			(xy 324.141592 -435.644798) (xy 324.130784 -435.606979) (xy 324.119183 -435.529185) (xy 324.118478 -435.489858)
			(xy 321.234816 -435.489858) (xy 321.234816 -436.160418) (xy 321.234407 -436.172513) (xy 321.22694 -436.195522)
			(xy 321.21274 -436.215105) (xy 321.193192 -436.229353) (xy 321.170202 -436.236877) (xy 321.158108 -436.23738)
			(xy 320.218308 -436.23738) (xy 320.206198 -436.236977) (xy 320.183167 -436.229477) (xy 320.163592 -436.215213)
			(xy 320.149398 -436.195587) (xy 320.14198 -436.17253) (xy 320.1416 -436.160418) (xy 320.1416 -435.644798)
			(xy 320.130792 -435.606979) (xy 320.119191 -435.529185) (xy 320.118486 -435.489858) (xy 317.234824 -435.489858)
			(xy 317.234824 -436.160418) (xy 317.234407 -436.172512) (xy 317.226941 -436.195519) (xy 317.212743 -436.215102)
			(xy 317.193197 -436.229351) (xy 317.170209 -436.236876) (xy 317.158116 -436.23738) (xy 316.218316 -436.23738)
			(xy 316.206206 -436.23697) (xy 316.183176 -436.229472) (xy 316.163601 -436.21521) (xy 316.149406 -436.195585)
			(xy 316.141989 -436.172529) (xy 316.141608 -436.160418) (xy 316.141608 -435.644798) (xy 316.1308 -435.606979)
			(xy 316.119199 -435.529185) (xy 316.118494 -435.489858) (xy 273.934286 -435.489858) (xy 273.867468 -435.573645)
			(xy 273.750836 -435.707142) (xy 273.628331 -435.835271) (xy 273.500202 -435.957776) (xy 273.366705 -436.074408)
			(xy 273.22811 -436.184934) (xy 273.084696 -436.289131) (xy 272.936752 -436.386788) (xy 272.784575 -436.477709)
			(xy 272.628472 -436.561712) (xy 272.468758 -436.638626) (xy 272.305753 -436.708298) (xy 272.139788 -436.770586)
			(xy 271.971194 -436.825365) (xy 271.800313 -436.872525) (xy 271.627488 -436.911971) (xy 271.453067 -436.943624)
			(xy 271.277402 -436.967419) (xy 271.100846 -436.98331) (xy 270.923755 -436.991263) (xy 270.746485 -436.991263)
			(xy 270.569394 -436.98331) (xy 270.392838 -436.967419) (xy 270.217173 -436.943624) (xy 270.042752 -436.911971)
			(xy 269.869927 -436.872525) (xy 269.699046 -436.825365) (xy 269.530452 -436.770586) (xy 269.364487 -436.708298)
			(xy 269.201482 -436.638626) (xy 269.041768 -436.561712) (xy 268.885665 -436.477709) (xy 268.733488 -436.386788)
			(xy 268.585544 -436.289131) (xy 268.44213 -436.184934) (xy 268.303535 -436.074408) (xy 268.170038 -435.957776)
			(xy 268.041909 -435.835271) (xy 267.919404 -435.707142) (xy 267.802772 -435.573645) (xy 267.692246 -435.43505)
			(xy 267.588049 -435.291636) (xy 267.490392 -435.143692) (xy 267.399471 -434.991515) (xy 267.315468 -434.835412)
			(xy 267.238554 -434.675698) (xy 267.168882 -434.512693) (xy 267.106594 -434.346728) (xy 267.051815 -434.178134)
			(xy 267.004655 -434.007253) (xy 266.965209 -433.834428) (xy 266.933556 -433.660007) (xy 266.909761 -433.484342)
			(xy 266.89387 -433.307786) (xy 266.885917 -433.130695) (xy 231.01554 -433.130695) (xy 231.01554 -435.063392)
			(xy 231.015024 -435.08834) (xy 231.007214 -435.137622) (xy 230.991802 -435.185079) (xy 230.969165 -435.229545)
			(xy 230.939859 -435.269929) (xy 230.922576 -435.287928) (xy 229.133908 -437.076596) (xy 229.115913 -437.093886)
			(xy 229.075537 -437.12321) (xy 229.031071 -437.145858) (xy 228.98361 -437.161272) (xy 228.934323 -437.169073)
			(xy 228.909372 -437.16956) (xy 207.503268 -437.16956) (xy 207.478319 -437.169063) (xy 207.429037 -437.161248)
			(xy 207.38158 -437.14583) (xy 207.337114 -437.123189) (xy 207.296731 -437.09388) (xy 207.278732 -437.076596)
			(xy 205.949804 -435.747668) (xy 205.932495 -435.72969) (xy 205.903173 -435.68931) (xy 205.880529 -435.64484)
			(xy 205.865119 -435.597375) (xy 205.857324 -435.548084) (xy 205.85684 -435.523132) (xy 204.057751 -435.523132)
			(xy 204.017468 -435.573645) (xy 203.900836 -435.707142) (xy 203.778331 -435.835271) (xy 203.650202 -435.957776)
			(xy 203.516705 -436.074408) (xy 203.37811 -436.184934) (xy 203.234696 -436.289131) (xy 203.086752 -436.386788)
			(xy 202.934575 -436.477709) (xy 202.778472 -436.561712) (xy 202.618758 -436.638626) (xy 202.455753 -436.708298)
			(xy 202.289788 -436.770586) (xy 202.121194 -436.825365) (xy 201.950313 -436.872525) (xy 201.777488 -436.911971)
			(xy 201.603067 -436.943624) (xy 201.427402 -436.967419) (xy 201.250846 -436.98331) (xy 201.073755 -436.991263)
			(xy 200.896485 -436.991263) (xy 200.719394 -436.98331) (xy 200.542838 -436.967419) (xy 200.367173 -436.943624)
			(xy 200.192752 -436.911971) (xy 200.019927 -436.872525) (xy 199.849046 -436.825365) (xy 199.680452 -436.770586)
			(xy 199.514487 -436.708298) (xy 199.351482 -436.638626) (xy 199.191768 -436.561712) (xy 199.035665 -436.477709)
			(xy 198.883488 -436.386788) (xy 198.735544 -436.289131) (xy 198.59213 -436.184934) (xy 198.453535 -436.074408)
			(xy 198.320038 -435.957776) (xy 198.191909 -435.835271) (xy 198.069404 -435.707142) (xy 197.952772 -435.573645)
			(xy 197.842246 -435.43505) (xy 197.738049 -435.291636) (xy 197.640392 -435.143692) (xy 197.549471 -434.991515)
			(xy 197.465468 -434.835412) (xy 197.388554 -434.675698) (xy 197.318882 -434.512693) (xy 197.256594 -434.346728)
			(xy 197.201815 -434.178134) (xy 197.154655 -434.007253) (xy 197.115209 -433.834428) (xy 197.083556 -433.660007)
			(xy 197.059761 -433.484342) (xy 197.04387 -433.307786) (xy 197.035917 -433.130695) (xy 155.334716 -433.130695)
			(xy 155.334716 -435.16042) (xy 155.334253 -435.172495) (xy 155.326786 -435.195461) (xy 155.312589 -435.214997)
			(xy 155.29305 -435.229191) (xy 155.270083 -435.236655) (xy 155.258008 -435.237128) (xy 154.318208 -435.237128)
			(xy 154.306136 -435.236629) (xy 154.283172 -435.229171) (xy 154.263637 -435.214983) (xy 154.249441 -435.195453)
			(xy 154.241975 -435.172492) (xy 154.2415 -435.16042) (xy 154.2415 -434.550058) (xy 154.239834 -434.535064)
			(xy 154.238054 -434.504946) (xy 154.237944 -434.48986) (xy 153.33472 -434.48986) (xy 153.33472 -435.489858)
			(xy 156.23794 -435.489858) (xy 156.238053 -435.474772) (xy 156.239832 -435.444654) (xy 156.241496 -435.42966)
			(xy 156.241496 -434.35016) (xy 156.23983 -434.335166) (xy 156.23805 -434.305048) (xy 156.23794 -434.289962)
			(xy 156.238053 -434.274876) (xy 156.239832 -434.244758) (xy 156.241496 -434.229764) (xy 156.241496 -433.618894)
			(xy 156.242002 -433.606809) (xy 156.249455 -433.583815) (xy 156.263633 -433.564239) (xy 156.283155 -433.549987)
			(xy 156.30612 -433.542448) (xy 156.318204 -433.541932) (xy 157.258004 -433.541932) (xy 157.270116 -433.542313)
			(xy 157.293149 -433.549818) (xy 157.312725 -433.564087) (xy 157.326918 -433.583718) (xy 157.334333 -433.60678)
			(xy 157.334712 -433.618894) (xy 157.334712 -436.160418) (xy 157.334307 -436.172513) (xy 157.32684 -436.195523)
			(xy 157.312639 -436.215106) (xy 157.293089 -436.229355) (xy 157.270098 -436.236878) (xy 157.258004 -436.23738)
			(xy 156.318204 -436.23738) (xy 156.306093 -436.23698) (xy 156.283063 -436.229479) (xy 156.263488 -436.215214)
			(xy 156.249294 -436.195588) (xy 156.241876 -436.17253) (xy 156.241496 -436.160418) (xy 156.241496 -435.550056)
			(xy 156.23983 -435.535062) (xy 156.23805 -435.504944) (xy 156.23794 -435.489858) (xy 153.33472 -435.489858)
			(xy 153.33472 -436.160418) (xy 153.334307 -436.172513) (xy 153.326841 -436.195521) (xy 153.312642 -436.215104)
			(xy 153.293094 -436.229352) (xy 153.270105 -436.236877) (xy 153.258012 -436.23738) (xy 152.318212 -436.23738)
			(xy 152.306102 -436.236973) (xy 152.283072 -436.229474) (xy 152.263497 -436.215211) (xy 152.249302 -436.195586)
			(xy 152.241885 -436.17253) (xy 152.241504 -436.160418) (xy 152.241504 -435.550056) (xy 152.239838 -435.535062)
			(xy 152.238058 -435.504944) (xy 152.237948 -435.489858) (xy 149.334728 -435.489858) (xy 149.334728 -436.160418)
			(xy 149.334308 -436.172512) (xy 149.326842 -436.195518) (xy 149.312645 -436.215101) (xy 149.293099 -436.22935)
			(xy 149.270112 -436.236876) (xy 149.25802 -436.23738) (xy 148.31822 -436.23738) (xy 148.30611 -436.236966)
			(xy 148.28308 -436.22947) (xy 148.263505 -436.215208) (xy 148.249311 -436.195585) (xy 148.241893 -436.172529)
			(xy 148.241512 -436.160418) (xy 148.241512 -435.550056) (xy 148.239846 -435.535062) (xy 148.238066 -435.504944)
			(xy 148.237956 -435.489858) (xy 145.334736 -435.489858) (xy 145.334736 -436.160418) (xy 145.334308 -436.172511)
			(xy 145.326843 -436.195516) (xy 145.312647 -436.215098) (xy 145.293104 -436.229347) (xy 145.27012 -436.236874)
			(xy 145.258028 -436.23738) (xy 144.318228 -436.23738) (xy 144.306119 -436.236959) (xy 144.283089 -436.229465)
			(xy 144.263514 -436.215206) (xy 144.249319 -436.195583) (xy 144.241901 -436.172529) (xy 144.24152 -436.160418)
			(xy 144.24152 -435.550056) (xy 144.239854 -435.535062) (xy 144.238074 -435.504944) (xy 144.237964 -435.489858)
			(xy 140.335 -435.489858) (xy 140.335 -436.160418) (xy 140.334504 -436.17253) (xy 140.327017 -436.195567)
			(xy 140.31278 -436.215165) (xy 140.293185 -436.229408) (xy 140.27015 -436.236901) (xy 140.258038 -436.23738)
			(xy 139.318238 -436.23738) (xy 139.306119 -436.236908) (xy 139.283064 -436.229428) (xy 139.26345 -436.21519)
			(xy 139.249197 -436.195586) (xy 139.241701 -436.172537) (xy 139.241276 -436.160418) (xy 139.241276 -435.548024)
			(xy 139.239728 -435.533532) (xy 139.238078 -435.504432) (xy 139.237974 -435.489858) (xy 136.335008 -435.489858)
			(xy 136.335008 -436.160418) (xy 136.334505 -436.172529) (xy 136.327018 -436.195565) (xy 136.312782 -436.215163)
			(xy 136.29319 -436.229405) (xy 136.270157 -436.2369) (xy 136.258046 -436.23738) (xy 135.318246 -436.23738)
			(xy 135.306127 -436.236901) (xy 135.283073 -436.229424) (xy 135.263459 -436.215187) (xy 135.249205 -436.195584)
			(xy 135.241709 -436.172536) (xy 135.241284 -436.160418) (xy 135.241284 -435.548024) (xy 135.239736 -435.533532)
			(xy 135.238086 -435.504432) (xy 135.237982 -435.489858) (xy 132.335016 -435.489858) (xy 132.335016 -436.160418)
			(xy 132.334654 -436.172546) (xy 132.327152 -436.195613) (xy 132.312886 -436.215232) (xy 132.293256 -436.229481)
			(xy 132.270183 -436.236965) (xy 132.258054 -436.23738) (xy 131.318254 -436.23738) (xy 131.306139 -436.236928)
			(xy 131.283097 -436.22943) (xy 131.263498 -436.215182) (xy 131.249257 -436.195578) (xy 131.241768 -436.172533)
			(xy 131.241292 -436.160418) (xy 131.241292 -435.548024) (xy 131.239744 -435.533532) (xy 131.238094 -435.504432)
			(xy 131.23799 -435.489858) (xy 128.335024 -435.489858) (xy 128.335024 -436.160418) (xy 128.334655 -436.172545)
			(xy 128.327153 -436.195611) (xy 128.312889 -436.215229) (xy 128.293261 -436.229478) (xy 128.27019 -436.236963)
			(xy 128.258062 -436.23738) (xy 127.318262 -436.23738) (xy 127.306147 -436.236921) (xy 127.283106 -436.229425)
			(xy 127.263506 -436.21518) (xy 127.249265 -436.195576) (xy 127.241776 -436.172533) (xy 127.2413 -436.160418)
			(xy 127.2413 -435.548024) (xy 127.239751 -435.533532) (xy 127.238102 -435.504432) (xy 127.237998 -435.489858)
			(xy 113.866512 -435.489858) (xy 113.892486 -435.537087) (xy 113.947862 -435.654438) (xy 113.995874 -435.77499)
			(xy 114.036336 -435.89828) (xy 114.069094 -436.023838) (xy 114.094022 -436.151181) (xy 114.111025 -436.279823)
			(xy 114.120038 -436.40927) (xy 114.121027 -436.539027) (xy 114.113986 -436.668596) (xy 114.098945 -436.797482)
			(xy 114.075959 -436.92519) (xy 114.045118 -437.051232) (xy 114.006538 -437.175125) (xy 113.960369 -437.296394)
			(xy 113.906786 -437.414574) (xy 113.845996 -437.529214) (xy 113.77823 -437.639874) (xy 113.703749 -437.74613)
			(xy 113.622838 -437.847575) (xy 113.535806 -437.943821) (xy 113.442988 -438.034499) (xy 113.378885 -438.089802)
			(xy 125.218444 -438.089802) (xy 125.218952 -438.057222) (xy 125.226926 -437.99255) (xy 125.242743 -437.929338)
			(xy 125.266166 -437.868533) (xy 125.296843 -437.811045) (xy 125.334315 -437.757736) (xy 125.378021 -437.709407)
			(xy 125.40234 -437.68772) (xy 125.482858 -437.523382) (xy 125.487557 -437.512865) (xy 125.491044 -437.490107)
			(xy 125.487561 -437.467349) (xy 125.482858 -437.456834) (xy 125.401832 -437.291734) (xy 125.377564 -437.270043)
			(xy 125.333966 -437.22171) (xy 125.296591 -437.168419) (xy 125.265998 -437.110966) (xy 125.242644 -437.050209)
			(xy 125.226877 -436.987056) (xy 125.218934 -436.922451) (xy 125.218444 -436.889906) (xy 125.219145 -436.85078)
			(xy 125.230619 -436.773373) (xy 125.241304 -436.735728) (xy 125.241304 -436.219092) (xy 125.241709 -436.206982)
			(xy 125.249212 -436.183954) (xy 125.263476 -436.164381) (xy 125.2831 -436.150186) (xy 125.306155 -436.142767)
			(xy 125.318266 -436.142384) (xy 126.258066 -436.142384) (xy 126.270158 -436.142837) (xy 126.293165 -436.15029)
			(xy 126.312749 -436.164478) (xy 126.327 -436.184018) (xy 126.334525 -436.207001) (xy 126.335028 -436.219092)
			(xy 126.335028 -438.760616) (xy 126.334598 -438.772723) (xy 126.327097 -438.795746) (xy 126.312838 -438.815316)
			(xy 126.293222 -438.829511) (xy 126.270174 -438.836937) (xy 126.258066 -438.837324) (xy 125.318266 -438.837324)
			(xy 125.306171 -438.836921) (xy 125.283163 -438.829451) (xy 125.263581 -438.815249) (xy 125.249333 -438.7957)
			(xy 125.241808 -438.77271) (xy 125.241304 -438.760616) (xy 125.241304 -438.24398) (xy 125.230617 -438.206335)
			(xy 125.21914 -438.128928) (xy 125.218444 -438.089802) (xy 113.378885 -438.089802) (xy 113.344738 -438.119261)
			(xy 113.241432 -438.197784) (xy 113.133467 -438.269766) (xy 113.021257 -438.334931) (xy 112.90523 -438.39303)
			(xy 112.785831 -438.443841) (xy 112.663518 -438.487169) (xy 112.538759 -438.522847) (xy 112.412032 -438.550739)
			(xy 112.283822 -438.570739) (xy 112.15462 -438.58277) (xy 112.024922 -438.586785) (xy 111.895224 -438.58277)
			(xy 111.766022 -438.570739) (xy 111.637812 -438.550739) (xy 111.511085 -438.522847) (xy 111.386326 -438.487169)
			(xy 111.264013 -438.443841) (xy 111.144614 -438.39303) (xy 111.028587 -438.334931) (xy 110.916377 -438.269766)
			(xy 110.808412 -438.197784) (xy 110.705106 -438.119261) (xy 110.606856 -438.034499) (xy 110.514038 -437.943821)
			(xy 110.427006 -437.847575) (xy 110.346095 -437.74613) (xy 110.271614 -437.639874) (xy 110.203848 -437.529214)
			(xy 110.143058 -437.414574) (xy 110.089475 -437.296394) (xy 110.043306 -437.175125) (xy 110.004726 -437.051232)
			(xy 109.973885 -436.92519) (xy 109.950899 -436.797482) (xy 109.935858 -436.668596) (xy 109.928817 -436.539027)
			(xy 109.929806 -436.40927) (xy 109.938819 -436.279823) (xy 109.955822 -436.151181) (xy 109.98075 -436.023838)
			(xy 110.013508 -435.89828) (xy 110.05397 -435.77499) (xy 110.101982 -435.654438) (xy 110.157358 -435.537087)
			(xy 110.219888 -435.423387) (xy 110.289331 -435.313772) (xy 110.365422 -435.208663) (xy 110.447869 -435.108462)
			(xy 110.536357 -435.013553) (xy 110.630546 -434.924299) (xy 110.679992 -434.88229) (xy 110.691093 -434.872254)
			(xy 110.707515 -434.847259) (xy 110.71599 -434.818578) (xy 110.71579 -434.788672) (xy 110.706933 -434.760107)
			(xy 110.690178 -434.735334) (xy 110.666963 -434.71648) (xy 110.653322 -434.710332) (xy 110.574304 -434.677407)
			(xy 110.419107 -434.605131) (xy 110.267499 -434.5256) (xy 110.119821 -434.438991) (xy 109.976402 -434.345497)
			(xy 109.837562 -434.245328) (xy 109.703613 -434.138709) (xy 109.574854 -434.025876) (xy 109.451573 -433.907083)
			(xy 109.334045 -433.782595) (xy 109.222533 -433.65269) (xy 109.117287 -433.517659) (xy 109.018541 -433.377804)
			(xy 108.926517 -433.233438) (xy 108.84142 -433.084883) (xy 108.763441 -432.932471) (xy 108.692754 -432.776543)
			(xy 108.629516 -432.617449) (xy 108.57387 -432.455542) (xy 108.52594 -432.291187) (xy 108.485833 -432.124749)
			(xy 108.453638 -431.956601) (xy 108.429428 -431.78712) (xy 108.413257 -431.616683) (xy 108.405161 -431.445673)
			(xy 108.40466 -431.360072) (xy 90.235024 -431.360072) (xy 90.235024 -432.560476) (xy 90.234563 -432.572581)
			(xy 90.227074 -432.595604) (xy 90.212823 -432.615175) (xy 90.193212 -432.629371) (xy 90.170168 -432.636797)
			(xy 90.158062 -432.637184) (xy 89.218262 -432.637184) (xy 89.206173 -432.636726) (xy 89.183175 -432.629261)
			(xy 89.163598 -432.615072) (xy 89.149348 -432.595538) (xy 89.141812 -432.572564) (xy 89.1413 -432.560476)
			(xy 89.1413 -431.948082) (xy 89.139756 -431.93359) (xy 89.138104 -431.90449) (xy 89.137998 -431.889916)
			(xy 86.235032 -431.889916) (xy 86.235032 -432.560476) (xy 86.234563 -432.57258) (xy 86.227075 -432.595601)
			(xy 86.212825 -432.615172) (xy 86.193217 -432.629369) (xy 86.170175 -432.636796) (xy 86.15807 -432.637184)
			(xy 85.21827 -432.637184) (xy 85.206181 -432.636719) (xy 85.183184 -432.629257) (xy 85.163606 -432.615069)
			(xy 85.149356 -432.595537) (xy 85.14182 -432.572563) (xy 85.141308 -432.560476) (xy 85.141308 -431.948082)
			(xy 85.139764 -431.93359) (xy 85.138112 -431.90449) (xy 85.138006 -431.889916) (xy 82.23504 -431.889916)
			(xy 82.23504 -432.560476) (xy 82.234564 -432.57258) (xy 82.227076 -432.595599) (xy 82.212828 -432.615169)
			(xy 82.193222 -432.629366) (xy 82.170183 -432.636795) (xy 82.158078 -432.637184) (xy 81.218278 -432.637184)
			(xy 81.20619 -432.636712) (xy 81.183192 -432.629252) (xy 81.163615 -432.615066) (xy 81.149364 -432.595535)
			(xy 81.141828 -432.572563) (xy 81.141316 -432.560476) (xy 81.141316 -431.948082) (xy 81.139772 -431.93359)
			(xy 81.13812 -431.90449) (xy 81.138014 -431.889916) (xy 78.235048 -431.889916) (xy 78.235048 -432.560476)
			(xy 78.234564 -432.572579) (xy 78.227077 -432.595597) (xy 78.212831 -432.615166) (xy 78.193227 -432.629364)
			(xy 78.17019 -432.636793) (xy 78.158086 -432.637184) (xy 77.218286 -432.637184) (xy 77.206198 -432.636705)
			(xy 77.183201 -432.629248) (xy 77.163623 -432.615063) (xy 77.149372 -432.595534) (xy 77.141836 -432.572562)
			(xy 77.141324 -432.560476) (xy 77.141324 -431.948082) (xy 77.13978 -431.93359) (xy 77.138128 -431.90449)
			(xy 77.138022 -431.889916) (xy 73.234804 -431.889916) (xy 73.234804 -432.560476) (xy 73.234367 -432.572558)
			(xy 73.226905 -432.59554) (xy 73.212706 -432.615091) (xy 73.193158 -432.629296) (xy 73.170178 -432.636764)
			(xy 73.158096 -432.637184) (xy 72.218296 -432.637184) (xy 72.206211 -432.636791) (xy 72.183224 -432.629319)
			(xy 72.163671 -432.615109) (xy 72.149468 -432.595551) (xy 72.142005 -432.572562) (xy 72.141588 -432.560476)
			(xy 72.141588 -431.950114) (xy 72.139918 -431.935121) (xy 72.138141 -431.905002) (xy 72.138032 -431.889916)
			(xy 69.234812 -431.889916) (xy 69.234812 -432.560476) (xy 69.234367 -432.572557) (xy 69.226906 -432.595538)
			(xy 69.212709 -432.615089) (xy 69.193163 -432.629294) (xy 69.170185 -432.636762) (xy 69.158104 -432.637184)
			(xy 68.218304 -432.637184) (xy 68.206219 -432.636784) (xy 68.183232 -432.629314) (xy 68.16368 -432.615106)
			(xy 68.149476 -432.59555) (xy 68.142013 -432.572561) (xy 68.141596 -432.560476) (xy 68.141596 -431.950114)
			(xy 68.139926 -431.935121) (xy 68.138149 -431.905002) (xy 68.13804 -431.889916) (xy 65.23482 -431.889916)
			(xy 65.23482 -432.560476) (xy 65.234367 -432.572556) (xy 65.226907 -432.595536) (xy 65.212711 -432.615086)
			(xy 65.193168 -432.629291) (xy 65.170192 -432.636761) (xy 65.158112 -432.637184) (xy 64.218312 -432.637184)
			(xy 64.206228 -432.636777) (xy 64.183241 -432.629309) (xy 64.163689 -432.615103) (xy 64.149485 -432.595548)
			(xy 64.142022 -432.572561) (xy 64.141604 -432.560476) (xy 64.141604 -431.950114) (xy 64.139934 -431.935121)
			(xy 64.138157 -431.905002) (xy 64.138048 -431.889916) (xy 61.234828 -431.889916) (xy 61.234828 -432.560476)
			(xy 61.234367 -432.572555) (xy 61.226909 -432.595534) (xy 61.212714 -432.615083) (xy 61.193173 -432.629288)
			(xy 61.170199 -432.63676) (xy 61.15812 -432.637184) (xy 60.21832 -432.637184) (xy 60.206236 -432.63677)
			(xy 60.18325 -432.629305) (xy 60.163697 -432.6151) (xy 60.149493 -432.595547) (xy 60.14203 -432.57256)
			(xy 60.141612 -432.560476) (xy 60.141612 -431.950114) (xy 60.139942 -431.935121) (xy 60.138165 -431.905002)
			(xy 60.138056 -431.889916) (xy 7.00913 -431.889916) (xy 7.00913 -434.48986) (xy 58.118502 -434.48986)
			(xy 58.118986 -434.457304) (xy 58.126936 -434.392678) (xy 58.142724 -434.329509) (xy 58.166114 -434.268742)
			(xy 58.196754 -434.211289) (xy 58.234185 -434.158012) (xy 58.277847 -434.109707) (xy 58.302144 -434.088032)
			(xy 58.382916 -433.923186) (xy 58.387614 -433.912668) (xy 58.391105 -433.889911) (xy 58.387621 -433.867152)
			(xy 58.382916 -433.856638) (xy 58.302144 -433.691792) (xy 58.27787 -433.670093) (xy 58.234215 -433.621788)
			(xy 58.196787 -433.568513) (xy 58.166147 -433.511064) (xy 58.142754 -433.450302) (xy 58.126959 -433.387139)
			(xy 58.118998 -433.322518) (xy 58.118502 -433.289964) (xy 58.119229 -433.250639) (xy 58.130834 -433.172849)
			(xy 58.141616 -433.135024) (xy 58.141616 -432.618896) (xy 58.142009 -432.606811) (xy 58.149481 -432.583824)
			(xy 58.163691 -432.564271) (xy 58.183249 -432.550068) (xy 58.206238 -432.542605) (xy 58.218324 -432.542188)
			(xy 59.158124 -432.542188) (xy 59.170199 -432.542644) (xy 59.193167 -432.550113) (xy 59.212703 -432.564311)
			(xy 59.226897 -432.583851) (xy 59.234359 -432.606821) (xy 59.234832 -432.618896) (xy 59.234832 -435.16042)
			(xy 59.234353 -435.172493) (xy 59.226888 -435.195457) (xy 59.212694 -435.214991) (xy 59.19316 -435.229186)
			(xy 59.170197 -435.236652) (xy 59.158124 -435.237128) (xy 58.218324 -435.237128) (xy 58.206245 -435.236667)
			(xy 58.183266 -435.229209) (xy 58.163717 -435.215014) (xy 58.149512 -435.195473) (xy 58.14204 -435.172499)
			(xy 58.141616 -435.16042) (xy 58.141616 -434.6448) (xy 58.130809 -434.606981) (xy 58.119207 -434.529187)
			(xy 58.118502 -434.48986) (xy 7.00913 -434.48986) (xy 7.00913 -435.489858) (xy 60.118498 -435.489858)
			(xy 60.118982 -435.457302) (xy 60.126932 -435.392676) (xy 60.142721 -435.329507) (xy 60.16611 -435.26874)
			(xy 60.19675 -435.211287) (xy 60.234182 -435.15801) (xy 60.277843 -435.109706) (xy 60.30214 -435.08803)
			(xy 60.382912 -434.923184) (xy 60.387612 -434.912667) (xy 60.391102 -434.889909) (xy 60.387617 -434.86715)
			(xy 60.382912 -434.856636) (xy 60.30214 -434.69179) (xy 60.277865 -434.670093) (xy 60.234209 -434.621788)
			(xy 60.196781 -434.568512) (xy 60.166142 -434.511063) (xy 60.14275 -434.450301) (xy 60.126955 -434.387137)
			(xy 60.118994 -434.322516) (xy 60.118498 -434.289962) (xy 60.119225 -434.250637) (xy 60.13083 -434.172847)
			(xy 60.141612 -434.135022) (xy 60.141612 -433.618894) (xy 60.142102 -433.606807) (xy 60.149557 -433.583811)
			(xy 60.163739 -433.564234) (xy 60.183265 -433.549982) (xy 60.206235 -433.542445) (xy 60.21832 -433.541932)
			(xy 61.15812 -433.541932) (xy 61.170233 -433.5423) (xy 61.193267 -433.549808) (xy 61.212842 -433.564081)
			(xy 61.227035 -433.583715) (xy 61.234449 -433.606779) (xy 61.234828 -433.618894) (xy 61.234828 -434.48986)
			(xy 62.118494 -434.48986) (xy 62.118947 -434.457302) (xy 62.126898 -434.392675) (xy 62.142689 -434.329503)
			(xy 62.166083 -434.268735) (xy 62.196729 -434.211283) (xy 62.234167 -434.158006) (xy 62.277836 -434.109705)
			(xy 62.302136 -434.088032) (xy 62.382908 -433.923186) (xy 62.387606 -433.912668) (xy 62.391097 -433.889911)
			(xy 62.387613 -433.867152) (xy 62.382908 -433.856638) (xy 62.302136 -433.691792) (xy 62.277861 -433.670095)
			(xy 62.234205 -433.62179) (xy 62.196778 -433.568513) (xy 62.166138 -433.511064) (xy 62.142746 -433.450303)
			(xy 62.126951 -433.387139) (xy 62.11899 -433.322518) (xy 62.118494 -433.289964) (xy 62.119221 -433.250639)
			(xy 62.130826 -433.172849) (xy 62.141608 -433.135024) (xy 62.141608 -432.618896) (xy 62.142009 -432.606811)
			(xy 62.14948 -432.583826) (xy 62.163688 -432.564274) (xy 62.183244 -432.550071) (xy 62.206231 -432.542606)
			(xy 62.218316 -432.542188) (xy 63.158116 -432.542188) (xy 63.170191 -432.542651) (xy 63.193158 -432.550117)
			(xy 63.212694 -432.564314) (xy 63.226888 -432.583853) (xy 63.234351 -432.606821) (xy 63.234824 -432.618896)
			(xy 63.234824 -435.16042) (xy 63.234353 -435.172494) (xy 63.226887 -435.195459) (xy 63.212691 -435.214994)
			(xy 63.193155 -435.229189) (xy 63.17019 -435.236654) (xy 63.158116 -435.237128) (xy 62.218316 -435.237128)
			(xy 62.206244 -435.236622) (xy 62.183281 -435.229167) (xy 62.163745 -435.21498) (xy 62.14955 -435.195451)
			(xy 62.142083 -435.172492) (xy 62.141608 -435.16042) (xy 62.141608 -434.6448) (xy 62.130801 -434.606981)
			(xy 62.119199 -434.529187) (xy 62.118494 -434.48986) (xy 61.234828 -434.48986) (xy 61.234828 -435.489858)
			(xy 64.11849 -435.489858) (xy 64.118943 -435.4573) (xy 64.126894 -435.392673) (xy 64.142685 -435.329501)
			(xy 64.166079 -435.268734) (xy 64.196725 -435.211281) (xy 64.234163 -435.158004) (xy 64.277832 -435.109703)
			(xy 64.302132 -435.08803) (xy 64.382904 -434.923184) (xy 64.387604 -434.912667) (xy 64.391095 -434.889909)
			(xy 64.387609 -434.86715) (xy 64.382904 -434.856636) (xy 64.302132 -434.69179) (xy 64.277855 -434.670095)
			(xy 64.2342 -434.621789) (xy 64.196773 -434.568512) (xy 64.166133 -434.511063) (xy 64.142741 -434.450301)
			(xy 64.126947 -434.387137) (xy 64.118986 -434.322516) (xy 64.11849 -434.289962) (xy 64.119217 -434.250637)
			(xy 64.130822 -434.172847) (xy 64.141604 -434.135022) (xy 64.141604 -433.618894) (xy 64.142102 -433.606808)
			(xy 64.149556 -433.583813) (xy 64.163736 -433.564236) (xy 64.18326 -433.549985) (xy 64.206228 -433.542447)
			(xy 64.218312 -433.541932) (xy 65.158112 -433.541932) (xy 65.170225 -433.542306) (xy 65.193258 -433.549813)
			(xy 65.212834 -433.564084) (xy 65.227027 -433.583717) (xy 65.234441 -433.60678) (xy 65.23482 -433.618894)
			(xy 65.23482 -434.48986) (xy 66.118486 -434.48986) (xy 66.118942 -434.457302) (xy 66.126893 -434.392675)
			(xy 66.142684 -434.329504) (xy 66.166077 -434.268736) (xy 66.196722 -434.211283) (xy 66.23416 -434.158007)
			(xy 66.277828 -434.109705) (xy 66.302128 -434.088032) (xy 66.3829 -433.923186) (xy 66.387599 -433.912668)
			(xy 66.39109 -433.889911) (xy 66.387605 -433.867152) (xy 66.3829 -433.856638) (xy 66.302128 -433.691792)
			(xy 66.277851 -433.670097) (xy 66.234196 -433.621791) (xy 66.196769 -433.568514) (xy 66.16613 -433.511065)
			(xy 66.142738 -433.450303) (xy 66.126943 -433.387139) (xy 66.118982 -433.322518) (xy 66.118486 -433.289964)
			(xy 66.119214 -433.250639) (xy 66.130818 -433.172849) (xy 66.1416 -433.135024) (xy 66.1416 -432.618896)
			(xy 66.142009 -432.606812) (xy 66.149479 -432.583828) (xy 66.163686 -432.564277) (xy 66.183239 -432.550073)
			(xy 66.206224 -432.542607) (xy 66.218308 -432.542188) (xy 67.158108 -432.542188) (xy 67.170183 -432.542657)
			(xy 67.193149 -432.550122) (xy 67.212686 -432.564317) (xy 67.22688 -432.583854) (xy 67.234343 -432.606821)
			(xy 67.234816 -432.618896) (xy 67.234816 -435.16042) (xy 67.234353 -435.172495) (xy 67.226886 -435.195461)
			(xy 67.212689 -435.214997) (xy 67.19315 -435.229191) (xy 67.170183 -435.236655) (xy 67.158108 -435.237128)
			(xy 66.218308 -435.237128) (xy 66.206236 -435.236629) (xy 66.183272 -435.229171) (xy 66.163737 -435.214983)
			(xy 66.149541 -435.195453) (xy 66.142075 -435.172492) (xy 66.1416 -435.16042) (xy 66.1416 -434.6448)
			(xy 66.130792 -434.606981) (xy 66.119191 -434.529187) (xy 66.118486 -434.48986) (xy 65.23482 -434.48986)
			(xy 65.23482 -435.489858) (xy 68.118482 -435.489858) (xy 68.118938 -435.457301) (xy 68.126889 -435.392673)
			(xy 68.14268 -435.329502) (xy 68.166073 -435.268734) (xy 68.196718 -435.211281) (xy 68.234156 -435.158005)
			(xy 68.277824 -435.109704) (xy 68.302124 -435.08803) (xy 68.382896 -434.923184) (xy 68.387596 -434.912667)
			(xy 68.391087 -434.889909) (xy 68.387602 -434.86715) (xy 68.382896 -434.856636) (xy 68.302124 -434.69179)
			(xy 68.277845 -434.670096) (xy 68.234191 -434.62179) (xy 68.196764 -434.568513) (xy 68.166125 -434.511064)
			(xy 68.142733 -434.450302) (xy 68.126938 -434.387137) (xy 68.118978 -434.322517) (xy 68.118482 -434.289962)
			(xy 68.119209 -434.250637) (xy 68.130814 -434.172847) (xy 68.141596 -434.135022) (xy 68.141596 -433.618894)
			(xy 68.142102 -433.606809) (xy 68.149555 -433.583815) (xy 68.163733 -433.564239) (xy 68.183255 -433.549987)
			(xy 68.20622 -433.542448) (xy 68.218304 -433.541932) (xy 69.158104 -433.541932) (xy 69.170216 -433.542313)
			(xy 69.193249 -433.549818) (xy 69.212825 -433.564087) (xy 69.227018 -433.583718) (xy 69.234433 -433.60678)
			(xy 69.234812 -433.618894) (xy 69.234812 -434.48986) (xy 70.118478 -434.48986) (xy 70.118936 -434.457303)
			(xy 70.126887 -434.392675) (xy 70.142678 -434.329504) (xy 70.166071 -434.268737) (xy 70.196716 -434.211284)
			(xy 70.234152 -434.158007) (xy 70.27782 -434.109706) (xy 70.30212 -434.088032) (xy 70.382892 -433.923186)
			(xy 70.387591 -433.912669) (xy 70.391083 -433.889911) (xy 70.387598 -433.867152) (xy 70.382892 -433.856638)
			(xy 70.30212 -433.691792) (xy 70.277841 -433.670098) (xy 70.234187 -433.621792) (xy 70.19676 -433.568515)
			(xy 70.166121 -433.511065) (xy 70.142729 -433.450303) (xy 70.126935 -433.387139) (xy 70.118974 -433.322519)
			(xy 70.118478 -433.289964) (xy 70.119206 -433.250639) (xy 70.130811 -433.172849) (xy 70.141592 -433.135024)
			(xy 70.141592 -432.618896) (xy 70.142061 -432.606821) (xy 70.149524 -432.583854) (xy 70.16372 -432.564317)
			(xy 70.183258 -432.550123) (xy 70.206225 -432.54266) (xy 70.2183 -432.542188) (xy 71.1581 -432.542188)
			(xy 71.170174 -432.542664) (xy 71.193141 -432.550126) (xy 71.212677 -432.56432) (xy 71.226872 -432.583856)
			(xy 71.234335 -432.606822) (xy 71.234808 -432.618896) (xy 71.234808 -435.16042) (xy 71.234353 -435.172496)
			(xy 71.226885 -435.195463) (xy 71.212686 -435.215) (xy 71.193145 -435.229194) (xy 71.170176 -435.236656)
			(xy 71.1581 -435.237128) (xy 70.2183 -435.237128) (xy 70.206227 -435.236636) (xy 70.183264 -435.229176)
			(xy 70.163728 -435.214986) (xy 70.149533 -435.195454) (xy 70.142067 -435.172492) (xy 70.141592 -435.16042)
			(xy 70.141592 -434.6448) (xy 70.130784 -434.606981) (xy 70.119183 -434.529187) (xy 70.118478 -434.48986)
			(xy 69.234812 -434.48986) (xy 69.234812 -435.489858) (xy 72.118474 -435.489858) (xy 72.118932 -435.457301)
			(xy 72.126884 -435.392673) (xy 72.142674 -435.329502) (xy 72.166067 -435.268735) (xy 72.196712 -435.211282)
			(xy 72.234149 -435.158005) (xy 72.277816 -435.109704) (xy 72.302116 -435.08803) (xy 72.382888 -434.923184)
			(xy 72.387589 -434.912667) (xy 72.39108 -434.889909) (xy 72.387594 -434.86715) (xy 72.382888 -434.856636)
			(xy 72.302116 -434.69179) (xy 72.277836 -434.670098) (xy 72.234182 -434.621792) (xy 72.196755 -434.568514)
			(xy 72.166116 -434.511064) (xy 72.142725 -434.450302) (xy 72.12693 -434.387137) (xy 72.11897 -434.322517)
			(xy 72.118474 -434.289962) (xy 72.119202 -434.250637) (xy 72.130806 -434.172847) (xy 72.141588 -434.135022)
			(xy 72.141588 -433.618894) (xy 72.142003 -433.606799) (xy 72.149468 -433.583791) (xy 72.163666 -433.564207)
			(xy 72.183213 -433.549958) (xy 72.206203 -433.542435) (xy 72.218296 -433.541932) (xy 73.158096 -433.541932)
			(xy 73.170208 -433.54232) (xy 73.193241 -433.549822) (xy 73.212817 -433.56409) (xy 73.22701 -433.58372)
			(xy 73.234425 -433.606781) (xy 73.234804 -433.618894) (xy 73.234804 -434.48986) (xy 75.118468 -434.48986)
			(xy 75.11893 -434.457303) (xy 75.126881 -434.392676) (xy 75.142671 -434.329505) (xy 75.166063 -434.268737)
			(xy 75.196707 -434.211285) (xy 75.234144 -434.158008) (xy 75.277811 -434.109706) (xy 75.30211 -434.088032)
			(xy 75.382882 -433.923186) (xy 75.387582 -433.912669) (xy 75.391074 -433.889911) (xy 75.387588 -433.867152)
			(xy 75.382882 -433.856638) (xy 75.30211 -433.691792) (xy 75.277829 -433.670101) (xy 75.234176 -433.621794)
			(xy 75.196749 -433.568516) (xy 75.166111 -433.511066) (xy 75.142719 -433.450304) (xy 75.126925 -433.387139)
			(xy 75.118964 -433.322519) (xy 75.118468 -433.289964) (xy 75.119159 -433.250837) (xy 75.130639 -433.173431)
			(xy 75.141328 -433.135786) (xy 75.141328 -432.618896) (xy 75.141713 -432.606784) (xy 75.149217 -432.583752)
			(xy 75.163486 -432.564176) (xy 75.183116 -432.549983) (xy 75.206177 -432.542567) (xy 75.21829 -432.542188)
			(xy 76.15809 -432.542188) (xy 76.170184 -432.542617) (xy 76.193192 -432.550077) (xy 76.212776 -432.564271)
			(xy 76.227025 -432.583816) (xy 76.234549 -432.606804) (xy 76.235052 -432.618896) (xy 76.235052 -435.16042)
			(xy 76.234601 -435.172525) (xy 76.227103 -435.195544) (xy 76.212848 -435.215112) (xy 76.193237 -435.229308)
			(xy 76.170196 -435.236737) (xy 76.15809 -435.237128) (xy 75.21829 -435.237128) (xy 75.206197 -435.2367)
			(xy 75.183191 -435.229237) (xy 75.163608 -435.215041) (xy 75.149359 -435.195498) (xy 75.141833 -435.172512)
			(xy 75.141328 -435.16042) (xy 75.141328 -434.644038) (xy 75.130633 -434.606395) (xy 75.119161 -434.528987)
			(xy 75.118468 -434.48986) (xy 73.234804 -434.48986) (xy 73.234804 -435.489858) (xy 77.118464 -435.489858)
			(xy 77.118926 -435.457301) (xy 77.126877 -435.392674) (xy 77.142667 -435.329503) (xy 77.16606 -435.268736)
			(xy 77.196704 -435.211283) (xy 77.23414 -435.158006) (xy 77.277807 -435.109704) (xy 77.302106 -435.08803)
			(xy 77.382878 -434.923184) (xy 77.387579 -434.912667) (xy 77.391071 -434.889909) (xy 77.387585 -434.86715)
			(xy 77.382878 -434.856636) (xy 77.302106 -434.69179) (xy 77.277824 -434.6701) (xy 77.23417 -434.621793)
			(xy 77.196744 -434.568515) (xy 77.166106 -434.511065) (xy 77.142714 -434.450302) (xy 77.12692 -434.387138)
			(xy 77.11896 -434.322517) (xy 77.118464 -434.289962) (xy 77.119155 -434.250835) (xy 77.130635 -434.173429)
			(xy 77.141324 -434.135784) (xy 77.141324 -433.618894) (xy 77.141807 -433.606781) (xy 77.149294 -433.58374)
			(xy 77.163534 -433.564139) (xy 77.183132 -433.549897) (xy 77.206173 -433.542408) (xy 77.218286 -433.541932)
			(xy 78.158086 -433.541932) (xy 78.170207 -433.542372) (xy 78.193265 -433.54986) (xy 78.21288 -433.564106)
			(xy 78.227131 -433.583717) (xy 78.234625 -433.606773) (xy 78.235048 -433.618894) (xy 78.235048 -434.48986)
			(xy 79.11846 -434.48986) (xy 79.118924 -434.457303) (xy 79.126875 -434.392676) (xy 79.142665 -434.329505)
			(xy 79.166057 -434.268738) (xy 79.196701 -434.211285) (xy 79.234137 -434.158008) (xy 79.277803 -434.109706)
			(xy 79.302102 -434.088032) (xy 79.382874 -433.923186) (xy 79.387574 -433.912669) (xy 79.391067 -433.889911)
			(xy 79.387581 -433.867152) (xy 79.382874 -433.856638) (xy 79.302102 -433.691792) (xy 79.27782 -433.670102)
			(xy 79.234166 -433.621795) (xy 79.19674 -433.568517) (xy 79.166102 -433.511067) (xy 79.142711 -433.450304)
			(xy 79.126916 -433.38714) (xy 79.118956 -433.322519) (xy 79.11846 -433.289964) (xy 79.119151 -433.250837)
			(xy 79.130632 -433.173431) (xy 79.14132 -433.135786) (xy 79.14132 -432.618896) (xy 79.141713 -432.606785)
			(xy 79.149216 -432.583754) (xy 79.163483 -432.564179) (xy 79.183111 -432.549985) (xy 79.206169 -432.542568)
			(xy 79.218282 -432.542188) (xy 80.158082 -432.542188) (xy 80.170175 -432.542624) (xy 80.193183 -432.550081)
			(xy 80.212768 -432.564274) (xy 80.227017 -432.583818) (xy 80.234541 -432.606804) (xy 80.235044 -432.618896)
			(xy 80.235044 -435.16042) (xy 80.234601 -435.172526) (xy 80.227102 -435.195546) (xy 80.212845 -435.215115)
			(xy 80.193232 -435.22931) (xy 80.170189 -435.236739) (xy 80.158082 -435.237128) (xy 79.218282 -435.237128)
			(xy 79.206188 -435.236708) (xy 79.183182 -435.229242) (xy 79.163599 -435.215045) (xy 79.14935 -435.195499)
			(xy 79.141824 -435.172512) (xy 79.14132 -435.16042) (xy 79.14132 -434.644038) (xy 79.130624 -434.606395)
			(xy 79.119153 -434.528987) (xy 79.11846 -434.48986) (xy 78.235048 -434.48986) (xy 78.235048 -435.489858)
			(xy 81.118456 -435.489858) (xy 81.11892 -435.457301) (xy 81.126871 -435.392674) (xy 81.142661 -435.329503)
			(xy 81.166054 -435.268736) (xy 81.196697 -435.211283) (xy 81.234133 -435.158006) (xy 81.277799 -435.109704)
			(xy 81.302098 -435.08803) (xy 81.38287 -434.923184) (xy 81.387572 -434.912667) (xy 81.391064 -434.889909)
			(xy 81.387577 -434.86715) (xy 81.38287 -434.856636) (xy 81.302098 -434.69179) (xy 81.277814 -434.670102)
			(xy 81.234161 -434.621794) (xy 81.196735 -434.568516) (xy 81.166097 -434.511066) (xy 81.142706 -434.450303)
			(xy 81.126912 -434.387138) (xy 81.118952 -434.322517) (xy 81.118456 -434.289962) (xy 81.119147 -434.250835)
			(xy 81.130628 -434.173429) (xy 81.141316 -434.135784) (xy 81.141316 -433.618894) (xy 81.141807 -433.606781)
			(xy 81.149293 -433.583742) (xy 81.163531 -433.564142) (xy 81.183127 -433.5499) (xy 81.206165 -433.542409)
			(xy 81.218278 -433.541932) (xy 82.158078 -433.541932) (xy 82.170199 -433.542379) (xy 82.193256 -433.549864)
			(xy 82.212871 -433.564109) (xy 82.227123 -433.583719) (xy 82.234617 -433.606773) (xy 82.23504 -433.618894)
			(xy 82.23504 -434.48986) (xy 83.118452 -434.48986) (xy 83.118919 -434.457303) (xy 83.12687 -434.392676)
			(xy 83.14266 -434.329506) (xy 83.166051 -434.268739) (xy 83.196694 -434.211286) (xy 83.23413 -434.158009)
			(xy 83.277795 -434.109706) (xy 83.302094 -434.088032) (xy 83.382866 -433.923186) (xy 83.387562 -433.912668)
			(xy 83.39105 -433.889911) (xy 83.387568 -433.867153) (xy 83.382866 -433.856638) (xy 83.302094 -433.691792)
			(xy 83.27781 -433.670104) (xy 83.234157 -433.621796) (xy 83.196731 -433.568518) (xy 83.166094 -433.511067)
			(xy 83.142702 -433.450305) (xy 83.126908 -433.38714) (xy 83.118948 -433.322519) (xy 83.118452 -433.289964)
			(xy 83.119144 -433.250837) (xy 83.130624 -433.173431) (xy 83.141312 -433.135786) (xy 83.141312 -432.618896)
			(xy 83.141713 -432.606786) (xy 83.149215 -432.583756) (xy 83.16348 -432.564182) (xy 83.183106 -432.549988)
			(xy 83.206162 -432.542569) (xy 83.218274 -432.542188) (xy 84.158074 -432.542188) (xy 84.170167 -432.54263)
			(xy 84.193175 -432.550086) (xy 84.212759 -432.564277) (xy 84.227009 -432.583819) (xy 84.234533 -432.606804)
			(xy 84.235036 -432.618896) (xy 84.235036 -435.16042) (xy 84.234601 -435.172526) (xy 84.227101 -435.195548)
			(xy 84.212843 -435.215118) (xy 84.193227 -435.229313) (xy 84.170182 -435.23674) (xy 84.158074 -435.237128)
			(xy 83.218274 -435.237128) (xy 83.20618 -435.236714) (xy 83.183173 -435.229247) (xy 83.163591 -435.215047)
			(xy 83.149342 -435.195501) (xy 83.141816 -435.172513) (xy 83.141312 -435.16042) (xy 83.141312 -434.644038)
			(xy 83.130616 -434.606395) (xy 83.119145 -434.528987) (xy 83.118452 -434.48986) (xy 82.23504 -434.48986)
			(xy 82.23504 -435.489858) (xy 85.118448 -435.489858) (xy 85.118915 -435.457301) (xy 85.126866 -435.392674)
			(xy 85.142656 -435.329504) (xy 85.166048 -435.268737) (xy 85.196691 -435.211284) (xy 85.234126 -435.158007)
			(xy 85.277791 -435.109704) (xy 85.30209 -435.08803) (xy 85.382862 -434.923184) (xy 85.387559 -434.912666)
			(xy 85.391047 -434.889909) (xy 85.387565 -434.867151) (xy 85.382862 -434.856636) (xy 85.30209 -434.69179)
			(xy 85.277804 -434.670104) (xy 85.234152 -434.621796) (xy 85.196726 -434.568517) (xy 85.166089 -434.511066)
			(xy 85.142698 -434.450303) (xy 85.126904 -434.387138) (xy 85.118944 -434.322517) (xy 85.118448 -434.289962)
			(xy 85.119139 -434.250835) (xy 85.13062 -434.173429) (xy 85.141308 -434.135784) (xy 85.141308 -433.618894)
			(xy 85.141806 -433.606782) (xy 85.149292 -433.583744) (xy 85.163528 -433.564145) (xy 85.183122 -433.549903)
			(xy 85.206158 -433.54241) (xy 85.21827 -433.541932) (xy 86.15807 -433.541932) (xy 86.170191 -433.542385)
			(xy 86.193247 -433.549869) (xy 86.212863 -433.564112) (xy 86.227115 -433.58372) (xy 86.234609 -433.606774)
			(xy 86.235032 -433.618894) (xy 86.235032 -434.48986) (xy 87.118444 -434.48986) (xy 87.118914 -434.457303)
			(xy 87.126865 -434.392677) (xy 87.142654 -434.329506) (xy 87.166045 -434.268739) (xy 87.196688 -434.211286)
			(xy 87.234122 -434.158009) (xy 87.277788 -434.109706) (xy 87.302086 -434.088032) (xy 87.382858 -433.923186)
			(xy 87.387554 -433.912668) (xy 87.391043 -433.889911) (xy 87.387561 -433.867153) (xy 87.382858 -433.856638)
			(xy 87.302086 -433.691792) (xy 87.277801 -433.670106) (xy 87.234148 -433.621797) (xy 87.196723 -433.568519)
			(xy 87.166085 -433.511068) (xy 87.142694 -433.450305) (xy 87.1269 -433.38714) (xy 87.11894 -433.322519)
			(xy 87.118444 -433.289964) (xy 87.119136 -433.250837) (xy 87.130616 -433.173431) (xy 87.141304 -433.135786)
			(xy 87.141304 -432.618896) (xy 87.141713 -432.606787) (xy 87.149214 -432.583758) (xy 87.163477 -432.564185)
			(xy 87.183101 -432.549991) (xy 87.206155 -432.542571) (xy 87.218266 -432.542188) (xy 88.158066 -432.542188)
			(xy 88.170159 -432.542637) (xy 88.193166 -432.55009) (xy 88.212751 -432.56428) (xy 88.227001 -432.583821)
			(xy 88.234525 -432.606805) (xy 88.235028 -432.618896) (xy 88.235028 -435.16042) (xy 88.234601 -435.172527)
			(xy 88.2271 -435.19555) (xy 88.21284 -435.215121) (xy 88.193222 -435.229316) (xy 88.170174 -435.236741)
			(xy 88.158066 -435.237128) (xy 87.218266 -435.237128) (xy 87.206171 -435.236721) (xy 87.183164 -435.229251)
			(xy 87.163582 -435.21505) (xy 87.149334 -435.195502) (xy 87.141808 -435.172513) (xy 87.141304 -435.16042)
			(xy 87.141304 -434.644038) (xy 87.130608 -434.606395) (xy 87.119137 -434.528987) (xy 87.118444 -434.48986)
			(xy 86.235032 -434.48986) (xy 86.235032 -435.489858) (xy 89.11844 -435.489858) (xy 89.11891 -435.457301)
			(xy 89.126861 -435.392675) (xy 89.14265 -435.329504) (xy 89.166042 -435.268737) (xy 89.196684 -435.211284)
			(xy 89.234119 -435.158007) (xy 89.277784 -435.109705) (xy 89.302082 -435.08803) (xy 89.382854 -434.923184)
			(xy 89.387552 -434.912666) (xy 89.39104 -434.889909) (xy 89.387557 -434.867151) (xy 89.382854 -434.856636)
			(xy 89.302082 -434.69179) (xy 89.277795 -434.670106) (xy 89.234142 -434.621797) (xy 89.196717 -434.568518)
			(xy 89.16608 -434.511067) (xy 89.14269 -434.450303) (xy 89.126896 -434.387138) (xy 89.118936 -434.322517)
			(xy 89.11844 -434.289962) (xy 89.119132 -434.250835) (xy 89.130612 -434.173429) (xy 89.1413 -434.135784)
			(xy 89.1413 -433.618894) (xy 89.141806 -433.606783) (xy 89.14929 -433.583746) (xy 89.163525 -433.564148)
			(xy 89.183117 -433.549905) (xy 89.206151 -433.542411) (xy 89.218262 -433.541932) (xy 90.158062 -433.541932)
			(xy 90.170182 -433.542392) (xy 90.193239 -433.549873) (xy 90.212854 -433.564115) (xy 90.227107 -433.583722)
			(xy 90.234601 -433.606774) (xy 90.235024 -433.618894) (xy 90.235024 -436.160418) (xy 90.234655 -436.172545)
			(xy 90.227153 -436.195611) (xy 90.212889 -436.215229) (xy 90.193261 -436.229478) (xy 90.17019 -436.236963)
			(xy 90.158062 -436.23738) (xy 89.218262 -436.23738) (xy 89.206147 -436.236921) (xy 89.183106 -436.229425)
			(xy 89.163506 -436.21518) (xy 89.149265 -436.195576) (xy 89.141776 -436.172533) (xy 89.1413 -436.160418)
			(xy 89.1413 -435.644036) (xy 89.130603 -435.606393) (xy 89.119132 -435.528985) (xy 89.11844 -435.489858)
			(xy 86.235032 -435.489858) (xy 86.235032 -436.160418) (xy 86.234655 -436.172545) (xy 86.227154 -436.195609)
			(xy 86.212892 -436.215226) (xy 86.193266 -436.229476) (xy 86.170197 -436.236962) (xy 86.15807 -436.23738)
			(xy 85.21827 -436.23738) (xy 85.206156 -436.236914) (xy 85.183114 -436.229421) (xy 85.163515 -436.215177)
			(xy 85.149274 -436.195575) (xy 85.141784 -436.172532) (xy 85.141308 -436.160418) (xy 85.141308 -435.644036)
			(xy 85.130612 -435.606393) (xy 85.11914 -435.528985) (xy 85.118448 -435.489858) (xy 82.23504 -435.489858)
			(xy 82.23504 -436.160418) (xy 82.234655 -436.172544) (xy 82.227155 -436.195607) (xy 82.212895 -436.215224)
			(xy 82.193271 -436.229473) (xy 82.170204 -436.236961) (xy 82.158078 -436.23738) (xy 81.218278 -436.23738)
			(xy 81.206164 -436.236907) (xy 81.183123 -436.229416) (xy 81.163523 -436.215174) (xy 81.149282 -436.195573)
			(xy 81.141792 -436.172532) (xy 81.141316 -436.160418) (xy 81.141316 -435.644036) (xy 81.13062 -435.606393)
			(xy 81.119148 -435.528985) (xy 81.118456 -435.489858) (xy 78.235048 -435.489858) (xy 78.235048 -436.160418)
			(xy 78.234604 -436.172535) (xy 78.22711 -436.195581) (xy 78.212861 -436.215184) (xy 78.193252 -436.229424)
			(xy 78.170203 -436.236909) (xy 78.158086 -436.23738) (xy 77.218286 -436.23738) (xy 77.206172 -436.236901)
			(xy 77.183132 -436.229412) (xy 77.163532 -436.215171) (xy 77.14929 -436.195572) (xy 77.1418 -436.172531)
			(xy 77.141324 -436.160418) (xy 77.141324 -435.644036) (xy 77.130628 -435.606393) (xy 77.119156 -435.528985)
			(xy 77.118464 -435.489858) (xy 73.234804 -435.489858) (xy 73.234804 -436.160418) (xy 73.234309 -436.172504)
			(xy 73.226853 -436.195498) (xy 73.212672 -436.215074) (xy 73.193147 -436.229325) (xy 73.17018 -436.236865)
			(xy 73.158096 -436.23738) (xy 72.218296 -436.23738) (xy 72.206185 -436.236987) (xy 72.183154 -436.229484)
			(xy 72.163579 -436.215217) (xy 72.149385 -436.195589) (xy 72.141968 -436.172531) (xy 72.141588 -436.160418)
			(xy 72.141588 -435.644798) (xy 72.13078 -435.606979) (xy 72.119179 -435.529185) (xy 72.118474 -435.489858)
			(xy 69.234812 -435.489858) (xy 69.234812 -436.160418) (xy 69.234407 -436.172513) (xy 69.22694 -436.195523)
			(xy 69.212739 -436.215106) (xy 69.193189 -436.229355) (xy 69.170198 -436.236878) (xy 69.158104 -436.23738)
			(xy 68.218304 -436.23738) (xy 68.206193 -436.23698) (xy 68.183163 -436.229479) (xy 68.163588 -436.215214)
			(xy 68.149394 -436.195588) (xy 68.141976 -436.17253) (xy 68.141596 -436.160418) (xy 68.141596 -435.644798)
			(xy 68.130788 -435.606979) (xy 68.119187 -435.529185) (xy 68.118482 -435.489858) (xy 65.23482 -435.489858)
			(xy 65.23482 -436.160418) (xy 65.234407 -436.172513) (xy 65.226941 -436.195521) (xy 65.212742 -436.215104)
			(xy 65.193194 -436.229352) (xy 65.170205 -436.236877) (xy 65.158112 -436.23738) (xy 64.218312 -436.23738)
			(xy 64.206202 -436.236973) (xy 64.183172 -436.229474) (xy 64.163597 -436.215211) (xy 64.149402 -436.195586)
			(xy 64.141985 -436.17253) (xy 64.141604 -436.160418) (xy 64.141604 -435.644798) (xy 64.130796 -435.606979)
			(xy 64.119195 -435.529185) (xy 64.11849 -435.489858) (xy 61.234828 -435.489858) (xy 61.234828 -436.160418)
			(xy 61.234408 -436.172512) (xy 61.226942 -436.195518) (xy 61.212745 -436.215101) (xy 61.193199 -436.22935)
			(xy 61.170212 -436.236876) (xy 61.15812 -436.23738) (xy 60.21832 -436.23738) (xy 60.20621 -436.236966)
			(xy 60.18318 -436.22947) (xy 60.163605 -436.215208) (xy 60.149411 -436.195585) (xy 60.141993 -436.172529)
			(xy 60.141612 -436.160418) (xy 60.141612 -435.644798) (xy 60.130804 -435.606979) (xy 60.119203 -435.529185)
			(xy 60.118498 -435.489858) (xy 7.00913 -435.489858) (xy 7.00913 -438.089802) (xy 58.13806 -438.089802)
			(xy 58.138177 -438.074717) (xy 58.139953 -438.044598) (xy 58.141616 -438.029604) (xy 58.141616 -436.950104)
			(xy 58.139946 -436.935111) (xy 58.138168 -436.904992) (xy 58.13806 -436.889906) (xy 58.138168 -436.87482)
			(xy 58.13995 -436.844702) (xy 58.141616 -436.829708) (xy 58.141616 -436.219092) (xy 58.142006 -436.207006)
			(xy 58.149479 -436.184019) (xy 58.16369 -436.164467) (xy 58.183248 -436.150264) (xy 58.206238 -436.142801)
			(xy 58.218324 -436.142384) (xy 59.158124 -436.142384) (xy 59.170199 -436.142844) (xy 59.193166 -436.150312)
			(xy 59.212701 -436.16451) (xy 59.226895 -436.184049) (xy 59.234359 -436.207017) (xy 59.234832 -436.219092)
			(xy 59.234832 -438.760616) (xy 59.23435 -438.772689) (xy 59.226886 -438.795653) (xy 59.212693 -438.815187)
			(xy 59.19316 -438.829382) (xy 59.170197 -438.836848) (xy 59.158124 -438.837324) (xy 58.218324 -438.837324)
			(xy 58.206244 -438.836867) (xy 58.183265 -438.829408) (xy 58.163716 -438.815213) (xy 58.14951 -438.795671)
			(xy 58.142039 -438.772696) (xy 58.141616 -438.760616) (xy 58.141616 -438.15) (xy 58.139945 -438.135007)
			(xy 58.138168 -438.104888) (xy 58.13806 -438.089802) (xy 7.00913 -438.089802) (xy 7.00913 -439.0898)
			(xy 60.138056 -439.0898) (xy 60.138173 -439.074715) (xy 60.139949 -439.044596) (xy 60.141612 -439.029602)
			(xy 60.141612 -437.950102) (xy 60.139941 -437.935109) (xy 60.138164 -437.90499) (xy 60.138056 -437.889904)
			(xy 60.138173 -437.874819) (xy 60.139949 -437.8447) (xy 60.141612 -437.829706) (xy 60.141612 -437.21909)
			(xy 60.142099 -437.207003) (xy 60.149555 -437.184007) (xy 60.163737 -437.164429) (xy 60.183265 -437.150178)
			(xy 60.206234 -437.142641) (xy 60.21832 -437.142128) (xy 61.15812 -437.142128) (xy 61.170233 -437.1425)
			(xy 61.193265 -437.150008) (xy 61.212841 -437.16428) (xy 61.227034 -437.183913) (xy 61.234449 -437.206976)
			(xy 61.234828 -437.21909) (xy 61.234828 -438.089802) (xy 62.138052 -438.089802) (xy 62.138169 -438.074717)
			(xy 62.139945 -438.044598) (xy 62.141608 -438.029604) (xy 62.141608 -436.950104) (xy 62.139938 -436.935111)
			(xy 62.13816 -436.904992) (xy 62.138052 -436.889906) (xy 62.13816 -436.87482) (xy 62.139942 -436.844702)
			(xy 62.141608 -436.829708) (xy 62.141608 -436.219092) (xy 62.142006 -436.207007) (xy 62.149478 -436.184021)
			(xy 62.163687 -436.16447) (xy 62.183243 -436.150267) (xy 62.206231 -436.142802) (xy 62.218316 -436.142384)
			(xy 63.158116 -436.142384) (xy 63.170191 -436.142851) (xy 63.193157 -436.150317) (xy 63.212693 -436.164513)
			(xy 63.226887 -436.18405) (xy 63.234351 -436.207017) (xy 63.234824 -436.219092) (xy 63.234824 -438.760616)
			(xy 63.23435 -438.77269) (xy 63.226885 -438.795655) (xy 63.21269 -438.81519) (xy 63.193155 -438.829385)
			(xy 63.17019 -438.83685) (xy 63.158116 -438.837324) (xy 62.218316 -438.837324) (xy 62.206244 -438.836822)
			(xy 62.18328 -438.829366) (xy 62.163744 -438.815179) (xy 62.149548 -438.795649) (xy 62.142083 -438.772688)
			(xy 62.141608 -438.760616) (xy 62.141608 -438.15) (xy 62.139937 -438.135007) (xy 62.13816 -438.104888)
			(xy 62.138052 -438.089802) (xy 61.234828 -438.089802) (xy 61.234828 -439.0898) (xy 64.138048 -439.0898)
			(xy 64.138165 -439.074715) (xy 64.139941 -439.044596) (xy 64.141604 -439.029602) (xy 64.141604 -437.950102)
			(xy 64.139933 -437.935109) (xy 64.138156 -437.90499) (xy 64.138048 -437.889904) (xy 64.138165 -437.874819)
			(xy 64.139941 -437.8447) (xy 64.141604 -437.829706) (xy 64.141604 -437.21909) (xy 64.142098 -437.207004)
			(xy 64.149553 -437.184009) (xy 64.163734 -437.164432) (xy 64.18326 -437.150181) (xy 64.206227 -437.142643)
			(xy 64.218312 -437.142128) (xy 65.158112 -437.142128) (xy 65.170224 -437.142506) (xy 65.193257 -437.150012)
			(xy 65.212832 -437.164283) (xy 65.227025 -437.183914) (xy 65.234441 -437.206976) (xy 65.23482 -437.21909)
			(xy 65.23482 -438.089802) (xy 66.138044 -438.089802) (xy 66.138161 -438.074717) (xy 66.139937 -438.044598)
			(xy 66.1416 -438.029604) (xy 66.1416 -436.950104) (xy 66.13993 -436.935111) (xy 66.138152 -436.904992)
			(xy 66.138044 -436.889906) (xy 66.138152 -436.87482) (xy 66.139934 -436.844702) (xy 66.1416 -436.829708)
			(xy 66.1416 -436.219092) (xy 66.142058 -436.207016) (xy 66.149523 -436.184047) (xy 66.163721 -436.16451)
			(xy 66.183262 -436.150316) (xy 66.206232 -436.142855) (xy 66.218308 -436.142384) (xy 67.158108 -436.142384)
			(xy 67.170182 -436.142857) (xy 67.193148 -436.150321) (xy 67.212684 -436.164516) (xy 67.226879 -436.184052)
			(xy 67.234343 -436.207018) (xy 67.234816 -436.219092) (xy 67.234816 -438.760616) (xy 67.234349 -438.772691)
			(xy 67.226883 -438.795657) (xy 67.212687 -438.815193) (xy 67.19315 -438.829387) (xy 67.170183 -438.836851)
			(xy 67.158108 -438.837324) (xy 66.218308 -438.837324) (xy 66.206235 -438.836829) (xy 66.183271 -438.829371)
			(xy 66.163735 -438.815182) (xy 66.14954 -438.79565) (xy 66.142075 -438.772688) (xy 66.1416 -438.760616)
			(xy 66.1416 -438.15) (xy 66.139929 -438.135007) (xy 66.138152 -438.104888) (xy 66.138044 -438.089802)
			(xy 65.23482 -438.089802) (xy 65.23482 -439.0898) (xy 68.13804 -439.0898) (xy 68.138157 -439.074715)
			(xy 68.139933 -439.044596) (xy 68.141596 -439.029602) (xy 68.141596 -437.950102) (xy 68.139925 -437.935109)
			(xy 68.138148 -437.90499) (xy 68.13804 -437.889904) (xy 68.138157 -437.874819) (xy 68.139933 -437.8447)
			(xy 68.141596 -437.829706) (xy 68.141596 -437.21909) (xy 68.142098 -437.207004) (xy 68.149552 -437.184011)
			(xy 68.163731 -437.164435) (xy 68.183255 -437.150183) (xy 68.20622 -437.142644) (xy 68.218304 -437.142128)
			(xy 69.158104 -437.142128) (xy 69.170216 -437.142513) (xy 69.193248 -437.150017) (xy 69.212824 -437.164286)
			(xy 69.227017 -437.183916) (xy 69.234433 -437.206977) (xy 69.234812 -437.21909) (xy 69.234812 -438.089802)
			(xy 70.138036 -438.089802) (xy 70.138153 -438.074717) (xy 70.139929 -438.044598) (xy 70.141592 -438.029604)
			(xy 70.141592 -436.950104) (xy 70.139922 -436.935111) (xy 70.138144 -436.904992) (xy 70.138036 -436.889906)
			(xy 70.138146 -436.87482) (xy 70.139928 -436.844702) (xy 70.141592 -436.829708) (xy 70.141592 -436.219092)
			(xy 70.142058 -436.207017) (xy 70.149522 -436.18405) (xy 70.163718 -436.164513) (xy 70.183257 -436.150319)
			(xy 70.206225 -436.142856) (xy 70.2183 -436.142384) (xy 71.1581 -436.142384) (xy 71.170174 -436.142864)
			(xy 71.19314 -436.150326) (xy 71.212676 -436.164518) (xy 71.226871 -436.184053) (xy 71.234335 -436.207018)
			(xy 71.234808 -436.219092) (xy 71.234808 -438.760616) (xy 71.234349 -438.772691) (xy 71.226882 -438.795659)
			(xy 71.212684 -438.815196) (xy 71.193145 -438.82939) (xy 71.170175 -438.836852) (xy 71.1581 -438.837324)
			(xy 70.2183 -438.837324) (xy 70.206227 -438.836836) (xy 70.183263 -438.829375) (xy 70.163727 -438.815184)
			(xy 70.149532 -438.795652) (xy 70.142067 -438.772689) (xy 70.141592 -438.760616) (xy 70.141592 -438.15)
			(xy 70.139921 -438.135007) (xy 70.138144 -438.104888) (xy 70.138036 -438.089802) (xy 69.234812 -438.089802)
			(xy 69.234812 -439.0898) (xy 72.138032 -439.0898) (xy 72.138151 -439.074715) (xy 72.139927 -439.044596)
			(xy 72.141588 -439.029602) (xy 72.141588 -437.950102) (xy 72.139917 -437.935109) (xy 72.13814 -437.90499)
			(xy 72.138032 -437.889904) (xy 72.138151 -437.874819) (xy 72.139927 -437.8447) (xy 72.141588 -437.829706)
			(xy 72.141588 -437.21909) (xy 72.142 -437.206995) (xy 72.149465 -437.183986) (xy 72.163664 -437.164402)
			(xy 72.183212 -437.150154) (xy 72.206202 -437.142631) (xy 72.218296 -437.142128) (xy 73.158096 -437.142128)
			(xy 73.170207 -437.14252) (xy 73.193239 -437.150022) (xy 73.212815 -437.164288) (xy 73.227009 -437.183917)
			(xy 73.234425 -437.206977) (xy 73.234804 -437.21909) (xy 73.234804 -438.089802) (xy 75.138026 -438.089802)
			(xy 75.138119 -438.075228) (xy 75.139772 -438.046127) (xy 75.141328 -438.031636) (xy 75.141328 -436.948072)
			(xy 75.139784 -436.93358) (xy 75.138131 -436.90448) (xy 75.138026 -436.889906) (xy 75.138119 -436.875332)
			(xy 75.139772 -436.846231) (xy 75.141328 -436.83174) (xy 75.141328 -436.219092) (xy 75.14171 -436.20698)
			(xy 75.149215 -436.183948) (xy 75.163484 -436.164372) (xy 75.183115 -436.150179) (xy 75.206176 -436.142763)
			(xy 75.21829 -436.142384) (xy 76.15809 -436.142384) (xy 76.170183 -436.142817) (xy 76.193191 -436.150276)
			(xy 76.212775 -436.16447) (xy 76.227024 -436.184014) (xy 76.234549 -436.207) (xy 76.235052 -436.219092)
			(xy 76.235052 -438.760616) (xy 76.234598 -438.772721) (xy 76.227101 -438.795739) (xy 76.212847 -438.815308)
			(xy 76.193237 -438.829504) (xy 76.170196 -438.836933) (xy 76.15809 -438.837324) (xy 75.21829 -438.837324)
			(xy 75.206196 -438.8369) (xy 75.183189 -438.829436) (xy 75.163607 -438.81524) (xy 75.149358 -438.795695)
			(xy 75.141832 -438.772708) (xy 75.141328 -438.760616) (xy 75.141328 -438.147968) (xy 75.139783 -438.133476)
			(xy 75.138131 -438.104376) (xy 75.138026 -438.089802) (xy 73.234804 -438.089802) (xy 73.234804 -439.0898)
			(xy 77.138022 -439.0898) (xy 77.138115 -439.075226) (xy 77.139768 -439.046125) (xy 77.141324 -439.031634)
			(xy 77.141324 -437.94807) (xy 77.139779 -437.933578) (xy 77.138127 -437.904478) (xy 77.138022 -437.889904)
			(xy 77.138115 -437.87533) (xy 77.139768 -437.846229) (xy 77.141324 -437.831738) (xy 77.141324 -437.21909)
			(xy 77.141803 -437.206976) (xy 77.149291 -437.183935) (xy 77.163532 -437.164335) (xy 77.183132 -437.150093)
			(xy 77.206172 -437.142604) (xy 77.218286 -437.142128) (xy 78.158086 -437.142128) (xy 78.170207 -437.142572)
			(xy 78.193264 -437.150059) (xy 78.212878 -437.164305) (xy 78.22713 -437.183915) (xy 78.234624 -437.206969)
			(xy 78.235048 -437.21909) (xy 78.235048 -438.089802) (xy 79.138018 -438.089802) (xy 79.138111 -438.075228)
			(xy 79.139764 -438.046127) (xy 79.14132 -438.031636) (xy 79.14132 -436.948072) (xy 79.139776 -436.93358)
			(xy 79.138123 -436.90448) (xy 79.138018 -436.889906) (xy 79.138111 -436.875332) (xy 79.139764 -436.846231)
			(xy 79.14132 -436.83174) (xy 79.14132 -436.219092) (xy 79.14171 -436.206981) (xy 79.149214 -436.18395)
			(xy 79.163481 -436.164375) (xy 79.18311 -436.150181) (xy 79.206169 -436.142764) (xy 79.218282 -436.142384)
			(xy 80.158082 -436.142384) (xy 80.170175 -436.142824) (xy 80.193182 -436.150281) (xy 80.212766 -436.164473)
			(xy 80.227016 -436.184015) (xy 80.234541 -436.207) (xy 80.235044 -436.219092) (xy 80.235044 -438.760616)
			(xy 80.234598 -438.772721) (xy 80.227099 -438.795742) (xy 80.212844 -438.815311) (xy 80.193232 -438.829506)
			(xy 80.170189 -438.836935) (xy 80.158082 -438.837324) (xy 79.218282 -438.837324) (xy 79.206188 -438.836907)
			(xy 79.183181 -438.829441) (xy 79.163598 -438.815243) (xy 79.149349 -438.795697) (xy 79.141824 -438.772709)
			(xy 79.14132 -438.760616) (xy 79.14132 -438.147968) (xy 79.139775 -438.133476) (xy 79.138123 -438.104376)
			(xy 79.138018 -438.089802) (xy 78.235048 -438.089802) (xy 78.235048 -439.0898) (xy 81.138014 -439.0898)
			(xy 81.138106 -439.075226) (xy 81.13976 -439.046125) (xy 81.141316 -439.031634) (xy 81.141316 -437.94807)
			(xy 81.139771 -437.933578) (xy 81.138119 -437.904478) (xy 81.138014 -437.889904) (xy 81.138107 -437.87533)
			(xy 81.13976 -437.846229) (xy 81.141316 -437.831738) (xy 81.141316 -437.21909) (xy 81.141803 -437.206977)
			(xy 81.14929 -437.183937) (xy 81.163529 -437.164338) (xy 81.183127 -437.150096) (xy 81.206165 -437.142605)
			(xy 81.218278 -437.142128) (xy 82.158078 -437.142128) (xy 82.170199 -437.142579) (xy 82.193255 -437.150064)
			(xy 82.21287 -437.164308) (xy 82.227122 -437.183916) (xy 82.234616 -437.20697) (xy 82.23504 -437.21909)
			(xy 82.23504 -438.089802) (xy 83.13801 -438.089802) (xy 83.138103 -438.075228) (xy 83.139756 -438.046127)
			(xy 83.141312 -438.031636) (xy 83.141312 -436.948072) (xy 83.139767 -436.93358) (xy 83.138115 -436.90448)
			(xy 83.13801 -436.889906) (xy 83.138103 -436.875332) (xy 83.139756 -436.846231) (xy 83.141312 -436.83174)
			(xy 83.141312 -436.219092) (xy 83.14171 -436.206981) (xy 83.149213 -436.183952) (xy 83.163479 -436.164378)
			(xy 83.183105 -436.150184) (xy 83.206162 -436.142765) (xy 83.218274 -436.142384) (xy 84.158074 -436.142384)
			(xy 84.170167 -436.14283) (xy 84.193174 -436.150285) (xy 84.212758 -436.164476) (xy 84.227008 -436.184017)
			(xy 84.234533 -436.207001) (xy 84.235036 -436.219092) (xy 84.235036 -438.760616) (xy 84.234598 -438.772722)
			(xy 84.227098 -438.795744) (xy 84.212841 -438.815313) (xy 84.193227 -438.829509) (xy 84.170181 -438.836936)
			(xy 84.158074 -438.837324) (xy 83.218274 -438.837324) (xy 83.206179 -438.836914) (xy 83.183172 -438.829446)
			(xy 83.163589 -438.815246) (xy 83.149341 -438.795698) (xy 83.141816 -438.772709) (xy 83.141312 -438.760616)
			(xy 83.141312 -438.147968) (xy 83.139767 -438.133476) (xy 83.138115 -438.104376) (xy 83.13801 -438.089802)
			(xy 82.23504 -438.089802) (xy 82.23504 -439.0898) (xy 85.138006 -439.0898) (xy 85.138098 -439.075226)
			(xy 85.139752 -439.046125) (xy 85.141308 -439.031634) (xy 85.141308 -437.94807) (xy 85.139763 -437.933578)
			(xy 85.138111 -437.904478) (xy 85.138006 -437.889904) (xy 85.138099 -437.87533) (xy 85.139752 -437.846229)
			(xy 85.141308 -437.831738) (xy 85.141308 -437.21909) (xy 85.141803 -437.206978) (xy 85.149289 -437.18394)
			(xy 85.163526 -437.164341) (xy 85.183122 -437.150098) (xy 85.206158 -437.142606) (xy 85.21827 -437.142128)
			(xy 86.15807 -437.142128) (xy 86.17019 -437.142585) (xy 86.193246 -437.150068) (xy 86.212861 -437.16431)
			(xy 86.227114 -437.183918) (xy 86.234608 -437.20697) (xy 86.235032 -437.21909) (xy 86.235032 -438.089802)
			(xy 87.138002 -438.089802) (xy 87.138095 -438.075228) (xy 87.139748 -438.046127) (xy 87.141304 -438.031636)
			(xy 87.141304 -436.948072) (xy 87.139759 -436.93358) (xy 87.138107 -436.90448) (xy 87.138002 -436.889906)
			(xy 87.138095 -436.875332) (xy 87.139748 -436.846231) (xy 87.141304 -436.83174) (xy 87.141304 -436.219092)
			(xy 87.141709 -436.206982) (xy 87.149212 -436.183954) (xy 87.163476 -436.164381) (xy 87.1831 -436.150186)
			(xy 87.206155 -436.142767) (xy 87.218266 -436.142384) (xy 88.158066 -436.142384) (xy 88.170158 -436.142837)
			(xy 88.193165 -436.15029) (xy 88.212749 -436.164478) (xy 88.227 -436.184018) (xy 88.234525 -436.207001)
			(xy 88.235028 -436.219092) (xy 88.235028 -438.760616) (xy 88.234598 -438.772723) (xy 88.227097 -438.795746)
			(xy 88.212838 -438.815316) (xy 88.193222 -438.829511) (xy 88.170174 -438.836937) (xy 88.158066 -438.837324)
			(xy 87.218266 -438.837324) (xy 87.206171 -438.836921) (xy 87.183163 -438.829451) (xy 87.163581 -438.815249)
			(xy 87.149333 -438.7957) (xy 87.141808 -438.77271) (xy 87.141304 -438.760616) (xy 87.141304 -438.147968)
			(xy 87.139759 -438.133476) (xy 87.138107 -438.104376) (xy 87.138002 -438.089802) (xy 86.235032 -438.089802)
			(xy 86.235032 -439.0898) (xy 89.137998 -439.0898) (xy 89.13809 -439.075226) (xy 89.139744 -439.046125)
			(xy 89.1413 -439.031634) (xy 89.1413 -437.94807) (xy 89.139755 -437.933578) (xy 89.138103 -437.904478)
			(xy 89.137998 -437.889904) (xy 89.138091 -437.87533) (xy 89.139744 -437.846229) (xy 89.1413 -437.831738)
			(xy 89.1413 -437.21909) (xy 89.141803 -437.206979) (xy 89.149288 -437.183942) (xy 89.163524 -437.164343)
			(xy 89.183117 -437.150101) (xy 89.206151 -437.142607) (xy 89.218262 -437.142128) (xy 90.158062 -437.142128)
			(xy 90.170182 -437.142592) (xy 90.193238 -437.150073) (xy 90.212853 -437.164313) (xy 90.227105 -437.183919)
			(xy 90.2346 -437.20697) (xy 90.235024 -437.21909) (xy 90.235024 -439.0898) (xy 127.21844 -439.0898)
			(xy 127.218948 -439.05722) (xy 127.226922 -438.992549) (xy 127.242739 -438.929336) (xy 127.266162 -438.868531)
			(xy 127.296839 -438.811043) (xy 127.334312 -438.757735) (xy 127.378017 -438.709405) (xy 127.402336 -438.687718)
			(xy 127.482854 -438.52338) (xy 127.487555 -438.512864) (xy 127.491042 -438.490105) (xy 127.487558 -438.467347)
			(xy 127.482854 -438.456832) (xy 127.401828 -438.291732) (xy 127.377558 -438.270043) (xy 127.33396 -438.22171)
			(xy 127.296586 -438.168418) (xy 127.265993 -438.110964) (xy 127.242639 -438.050207) (xy 127.226873 -437.987054)
			(xy 127.21893 -437.92245) (xy 127.21844 -437.889904) (xy 127.219141 -437.850778) (xy 127.230615 -437.773371)
			(xy 127.2413 -437.735726) (xy 127.2413 -437.21909) (xy 127.241803 -437.206979) (xy 127.249288 -437.183942)
			(xy 127.263524 -437.164343) (xy 127.283117 -437.150101) (xy 127.306151 -437.142607) (xy 127.318262 -437.142128)
			(xy 128.258062 -437.142128) (xy 128.270182 -437.142592) (xy 128.293238 -437.150073) (xy 128.312853 -437.164313)
			(xy 128.327105 -437.183919) (xy 128.3346 -437.20697) (xy 128.335024 -437.21909) (xy 128.335024 -438.089802)
			(xy 129.218436 -438.089802) (xy 129.218946 -438.057222) (xy 129.226921 -437.992551) (xy 129.242737 -437.929339)
			(xy 129.26616 -437.868533) (xy 129.296837 -437.811045) (xy 129.334308 -437.757737) (xy 129.378013 -437.709407)
			(xy 129.402332 -437.68772) (xy 129.48285 -437.523382) (xy 129.487549 -437.512865) (xy 129.491037 -437.490107)
			(xy 129.487554 -437.467349) (xy 129.48285 -437.456834) (xy 129.401824 -437.291734) (xy 129.377554 -437.270045)
			(xy 129.333957 -437.221711) (xy 129.296582 -437.16842) (xy 129.265989 -437.110966) (xy 129.242635 -437.050209)
			(xy 129.226869 -436.987056) (xy 129.218926 -436.922452) (xy 129.218436 -436.889906) (xy 129.219137 -436.85078)
			(xy 129.230611 -436.773373) (xy 129.241296 -436.735728) (xy 129.241296 -436.219092) (xy 129.241709 -436.206983)
			(xy 129.24921 -436.183956) (xy 129.263473 -436.164384) (xy 129.283095 -436.150189) (xy 129.306148 -436.142768)
			(xy 129.318258 -436.142384) (xy 130.258058 -436.142384) (xy 130.27015 -436.142844) (xy 130.293156 -436.150294)
			(xy 130.312741 -436.164481) (xy 130.326991 -436.184019) (xy 130.334516 -436.207002) (xy 130.33502 -436.219092)
			(xy 130.33502 -438.760616) (xy 130.334598 -438.772724) (xy 130.327096 -438.795748) (xy 130.312836 -438.815319)
			(xy 130.293217 -438.829514) (xy 130.270167 -438.836938) (xy 130.258058 -438.837324) (xy 129.318258 -438.837324)
			(xy 129.306163 -438.836928) (xy 129.283155 -438.829455) (xy 129.263572 -438.815252) (xy 129.249324 -438.795701)
			(xy 129.2418 -438.77271) (xy 129.241296 -438.760616) (xy 129.241296 -438.24398) (xy 129.230609 -438.206335)
			(xy 129.219132 -438.128928) (xy 129.218436 -438.089802) (xy 128.335024 -438.089802) (xy 128.335024 -439.0898)
			(xy 131.218432 -439.0898) (xy 131.218942 -439.05722) (xy 131.226917 -438.992549) (xy 131.242734 -438.929337)
			(xy 131.266156 -438.868531) (xy 131.296833 -438.811044) (xy 131.334304 -438.757735) (xy 131.378009 -438.709405)
			(xy 131.402328 -438.687718) (xy 131.482846 -438.52338) (xy 131.487547 -438.512864) (xy 131.491034 -438.490105)
			(xy 131.48755 -438.467347) (xy 131.482846 -438.456832) (xy 131.40182 -438.291732) (xy 131.377549 -438.270045)
			(xy 131.333951 -438.221711) (xy 131.296577 -438.168419) (xy 131.265985 -438.110965) (xy 131.242631 -438.050207)
			(xy 131.226865 -437.987054) (xy 131.218922 -437.92245) (xy 131.218432 -437.889904) (xy 131.219133 -437.850778)
			(xy 131.230607 -437.773371) (xy 131.241292 -437.735726) (xy 131.241292 -437.21909) (xy 131.241803 -437.20698)
			(xy 131.249287 -437.183944) (xy 131.263521 -437.164346) (xy 131.283112 -437.150104) (xy 131.306144 -437.142608)
			(xy 131.318254 -437.142128) (xy 132.258054 -437.142128) (xy 132.270173 -437.142599) (xy 132.293229 -437.150077)
			(xy 132.312844 -437.164316) (xy 132.327097 -437.183921) (xy 132.334592 -437.206971) (xy 132.335016 -437.21909)
			(xy 132.335016 -438.089802) (xy 133.218428 -438.089802) (xy 133.218941 -438.057222) (xy 133.226915 -437.992551)
			(xy 133.242732 -437.929339) (xy 133.266154 -437.868534) (xy 133.29683 -437.811046) (xy 133.334301 -437.757737)
			(xy 133.378005 -437.709407) (xy 133.402324 -437.68772) (xy 133.482842 -437.523382) (xy 133.487542 -437.512865)
			(xy 133.49103 -437.490107) (xy 133.487546 -437.467349) (xy 133.482842 -437.456834) (xy 133.401816 -437.291734)
			(xy 133.377545 -437.270046) (xy 133.333948 -437.221713) (xy 133.296573 -437.168421) (xy 133.265981 -437.110967)
			(xy 133.242627 -437.050209) (xy 133.226861 -436.987056) (xy 133.218918 -436.922452) (xy 133.218428 -436.889906)
			(xy 133.21913 -436.85078) (xy 133.230603 -436.773373) (xy 133.241288 -436.735728) (xy 133.241288 -436.219092)
			(xy 133.241709 -436.206984) (xy 133.249209 -436.183958) (xy 133.26347 -436.164386) (xy 133.28309 -436.150192)
			(xy 133.306141 -436.142769) (xy 133.31825 -436.142384) (xy 134.25805 -436.142384) (xy 134.270141 -436.142851)
			(xy 134.293148 -436.150299) (xy 134.312732 -436.164484) (xy 134.326983 -436.184021) (xy 134.334508 -436.207002)
			(xy 134.335012 -436.219092) (xy 134.335012 -438.760616) (xy 134.334598 -438.772725) (xy 134.327095 -438.79575)
			(xy 134.312833 -438.815322) (xy 134.293212 -438.829517) (xy 134.27016 -438.836939) (xy 134.25805 -438.837324)
			(xy 133.31825 -438.837324) (xy 133.306159 -438.836849) (xy 133.283154 -438.829402) (xy 133.26357 -438.815219)
			(xy 133.249319 -438.795684) (xy 133.241793 -438.772705) (xy 133.241288 -438.760616) (xy 133.241288 -438.24398)
			(xy 133.230601 -438.206335) (xy 133.219124 -438.128928) (xy 133.218428 -438.089802) (xy 132.335016 -438.089802)
			(xy 132.335016 -439.0898) (xy 135.218424 -439.0898) (xy 135.218937 -439.05722) (xy 135.226911 -438.992549)
			(xy 135.242728 -438.929337) (xy 135.26615 -438.868532) (xy 135.296826 -438.811044) (xy 135.334297 -438.757736)
			(xy 135.378001 -438.709405) (xy 135.40232 -438.687718) (xy 135.482838 -438.52338) (xy 135.487539 -438.512864)
			(xy 135.491027 -438.490105) (xy 135.487543 -438.467347) (xy 135.482838 -438.456832) (xy 135.401812 -438.291732)
			(xy 135.377539 -438.270046) (xy 135.333942 -438.221712) (xy 135.296568 -438.16842) (xy 135.265976 -438.110965)
			(xy 135.242623 -438.050208) (xy 135.226857 -437.987055) (xy 135.218914 -437.92245) (xy 135.218424 -437.889904)
			(xy 135.219125 -437.850778) (xy 135.230599 -437.773371) (xy 135.241284 -437.735726) (xy 135.241284 -437.21909)
			(xy 135.241652 -437.206962) (xy 135.249153 -437.183895) (xy 135.263416 -437.164276) (xy 135.283045 -437.150027)
			(xy 135.306118 -437.142544) (xy 135.318246 -437.142128) (xy 136.258046 -437.142128) (xy 136.270162 -437.142572)
			(xy 136.293205 -437.150071) (xy 136.312805 -437.164321) (xy 136.327045 -437.183927) (xy 136.334533 -437.206974)
			(xy 136.335008 -437.21909) (xy 136.335008 -438.089802) (xy 137.21842 -438.089802) (xy 137.218936 -438.057222)
			(xy 137.22691 -437.992551) (xy 137.242726 -437.92934) (xy 137.266148 -437.868534) (xy 137.296824 -437.811047)
			(xy 137.334294 -437.757738) (xy 137.377998 -437.709407) (xy 137.402316 -437.68772) (xy 137.482834 -437.523382)
			(xy 137.487534 -437.512865) (xy 137.491023 -437.490107) (xy 137.487539 -437.467349) (xy 137.482834 -437.456834)
			(xy 137.401808 -437.291734) (xy 137.377535 -437.270048) (xy 137.333938 -437.221714) (xy 137.296565 -437.168422)
			(xy 137.265972 -437.110967) (xy 137.242619 -437.05021) (xy 137.226853 -436.987057) (xy 137.21891 -436.922452)
			(xy 137.21842 -436.889906) (xy 137.219122 -436.85078) (xy 137.230595 -436.773373) (xy 137.24128 -436.735728)
			(xy 137.24128 -436.219092) (xy 137.241709 -436.206985) (xy 137.249208 -436.183961) (xy 137.263467 -436.164389)
			(xy 137.283085 -436.150194) (xy 137.306133 -436.14277) (xy 137.318242 -436.142384) (xy 138.258042 -436.142384)
			(xy 138.270138 -436.142772) (xy 138.293148 -436.150246) (xy 138.312731 -436.164451) (xy 138.326978 -436.184004)
			(xy 138.334501 -436.206997) (xy 138.335004 -436.219092) (xy 138.335004 -438.760616) (xy 138.334597 -438.772725)
			(xy 138.327094 -438.795752) (xy 138.31283 -438.815325) (xy 138.293207 -438.829519) (xy 138.270153 -438.83694)
			(xy 138.258042 -438.837324) (xy 137.318242 -438.837324) (xy 137.306151 -438.836856) (xy 137.283146 -438.829407)
			(xy 137.263562 -438.815222) (xy 137.249311 -438.795686) (xy 137.241785 -438.772705) (xy 137.24128 -438.760616)
			(xy 137.24128 -438.24398) (xy 137.230592 -438.206335) (xy 137.219116 -438.128928) (xy 137.21842 -438.089802)
			(xy 136.335008 -438.089802) (xy 136.335008 -439.0898) (xy 139.218416 -439.0898) (xy 139.218931 -439.05722)
			(xy 139.226905 -438.992549) (xy 139.242722 -438.929338) (xy 139.266144 -438.868532) (xy 139.296819 -438.811045)
			(xy 139.33429 -438.757736) (xy 139.377993 -438.709405) (xy 139.402312 -438.687718) (xy 139.48283 -438.52338)
			(xy 139.487532 -438.512864) (xy 139.49102 -438.490105) (xy 139.487535 -438.467347) (xy 139.48283 -438.456832)
			(xy 139.401804 -438.291732) (xy 139.377529 -438.270048) (xy 139.333933 -438.221713) (xy 139.296559 -438.168421)
			(xy 139.265967 -438.110966) (xy 139.242614 -438.050208) (xy 139.226849 -437.987055) (xy 139.218906 -437.92245)
			(xy 139.218416 -437.889904) (xy 139.219114 -437.850778) (xy 139.230589 -437.773371) (xy 139.241276 -437.735726)
			(xy 139.241276 -437.21909) (xy 139.241652 -437.206963) (xy 139.249152 -437.183897) (xy 139.263413 -437.164279)
			(xy 139.28304 -437.15003) (xy 139.306111 -437.142545) (xy 139.318238 -437.142128) (xy 140.258038 -437.142128)
			(xy 140.270154 -437.142579) (xy 140.293196 -437.150076) (xy 140.312797 -437.164323) (xy 140.327037 -437.183929)
			(xy 140.334525 -437.206974) (xy 140.335 -437.21909) (xy 140.335 -438.089802) (xy 142.21841 -438.089802)
			(xy 142.218929 -438.057222) (xy 142.226903 -437.992552) (xy 142.242719 -437.92934) (xy 142.26614 -437.868535)
			(xy 142.296815 -437.811047) (xy 142.334285 -437.757738) (xy 142.377988 -437.709407) (xy 142.402306 -437.68772)
			(xy 142.482824 -437.523382) (xy 142.487525 -437.512865) (xy 142.491014 -437.490107) (xy 142.487529 -437.467348)
			(xy 142.482824 -437.456834) (xy 142.401798 -437.291734) (xy 142.377523 -437.27005) (xy 142.333927 -437.221716)
			(xy 142.296554 -437.168423) (xy 142.265962 -437.110968) (xy 142.242609 -437.05021) (xy 142.226843 -436.987057)
			(xy 142.2189 -436.922452) (xy 142.21841 -436.889906) (xy 142.219146 -436.850581) (xy 142.230745 -436.772791)
			(xy 142.241524 -436.734966) (xy 142.241524 -436.219092) (xy 142.241906 -436.207006) (xy 142.24938 -436.184017)
			(xy 142.263593 -436.164464) (xy 142.283153 -436.150262) (xy 142.306145 -436.1428) (xy 142.318232 -436.142384)
			(xy 143.258032 -436.142384) (xy 143.270107 -436.142837) (xy 143.293074 -436.150307) (xy 143.31261 -436.164507)
			(xy 143.326804 -436.184047) (xy 143.334267 -436.207016) (xy 143.33474 -436.219092) (xy 143.33474 -438.760616)
			(xy 143.33425 -438.772688) (xy 143.326787 -438.79565) (xy 143.312596 -438.815184) (xy 143.293065 -438.829379)
			(xy 143.270104 -438.836847) (xy 143.258032 -438.837324) (xy 142.318232 -438.837324) (xy 142.306153 -438.83686)
			(xy 142.283174 -438.829403) (xy 142.263624 -438.81521) (xy 142.249418 -438.795669) (xy 142.241947 -438.772695)
			(xy 142.241524 -438.760616) (xy 142.241524 -438.244742) (xy 142.230726 -438.20692) (xy 142.219118 -438.129129)
			(xy 142.21841 -438.089802) (xy 140.335 -438.089802) (xy 140.335 -439.0898) (xy 144.218406 -439.0898)
			(xy 144.218925 -439.05722) (xy 144.226899 -438.99255) (xy 144.242715 -438.929338) (xy 144.266136 -438.868533)
			(xy 144.296811 -438.811045) (xy 144.334281 -438.757736) (xy 144.377984 -438.709405) (xy 144.402302 -438.687718)
			(xy 144.48282 -438.52338) (xy 144.487522 -438.512864) (xy 144.491011 -438.490105) (xy 144.487526 -438.467346)
			(xy 144.48282 -438.456832) (xy 144.401794 -438.291732) (xy 144.377517 -438.27005) (xy 144.333921 -438.221715)
			(xy 144.296548 -438.168422) (xy 144.265957 -438.110967) (xy 144.242604 -438.050209) (xy 144.226839 -437.987055)
			(xy 144.218896 -437.92245) (xy 144.218406 -437.889904) (xy 144.219142 -437.850579) (xy 144.230741 -437.772789)
			(xy 144.24152 -437.734964) (xy 144.24152 -437.21909) (xy 144.241999 -437.207002) (xy 144.249456 -437.184004)
			(xy 144.26364 -437.164426) (xy 144.28317 -437.150176) (xy 144.306142 -437.14264) (xy 144.318228 -437.142128)
			(xy 145.258028 -437.142128) (xy 145.270141 -437.142493) (xy 145.293174 -437.150003) (xy 145.312749 -437.164277)
			(xy 145.326942 -437.183911) (xy 145.334357 -437.206975) (xy 145.334736 -437.21909) (xy 145.334736 -438.089802)
			(xy 146.218402 -438.089802) (xy 146.218924 -438.057222) (xy 146.226897 -437.992552) (xy 146.242713 -437.929341)
			(xy 146.266134 -437.868536) (xy 146.296809 -437.811048) (xy 146.334278 -437.757739) (xy 146.37798 -437.709407)
			(xy 146.402298 -437.68772) (xy 146.482816 -437.523382) (xy 146.487517 -437.512865) (xy 146.491007 -437.490107)
			(xy 146.487522 -437.467348) (xy 146.482816 -437.456834) (xy 146.40179 -437.291734) (xy 146.377514 -437.270052)
			(xy 146.333918 -437.221717) (xy 146.296545 -437.168424) (xy 146.265953 -437.110969) (xy 146.2426 -437.05021)
			(xy 146.226835 -436.987057) (xy 146.218892 -436.922452) (xy 146.218402 -436.889906) (xy 146.219138 -436.850581)
			(xy 146.230737 -436.772791) (xy 146.241516 -436.734966) (xy 146.241516 -436.219092) (xy 146.241906 -436.207006)
			(xy 146.249379 -436.184019) (xy 146.26359 -436.164467) (xy 146.283148 -436.150264) (xy 146.306138 -436.142801)
			(xy 146.318224 -436.142384) (xy 147.258024 -436.142384) (xy 147.270099 -436.142844) (xy 147.293066 -436.150312)
			(xy 147.312601 -436.16451) (xy 147.326795 -436.184049) (xy 147.334259 -436.207017) (xy 147.334732 -436.219092)
			(xy 147.334732 -438.760616) (xy 147.33425 -438.772689) (xy 147.326786 -438.795653) (xy 147.312593 -438.815187)
			(xy 147.29306 -438.829382) (xy 147.270097 -438.836848) (xy 147.258024 -438.837324) (xy 146.318224 -438.837324)
			(xy 146.306144 -438.836867) (xy 146.283165 -438.829408) (xy 146.263616 -438.815213) (xy 146.24941 -438.795671)
			(xy 146.241939 -438.772696) (xy 146.241516 -438.760616) (xy 146.241516 -438.244742) (xy 146.230718 -438.20692)
			(xy 146.21911 -438.129129) (xy 146.218402 -438.089802) (xy 145.334736 -438.089802) (xy 145.334736 -439.0898)
			(xy 148.218398 -439.0898) (xy 148.21892 -439.05722) (xy 148.226893 -438.99255) (xy 148.242709 -438.929339)
			(xy 148.26613 -438.868534) (xy 148.296805 -438.811046) (xy 148.334274 -438.757737) (xy 148.377976 -438.709405)
			(xy 148.402294 -438.687718) (xy 148.482812 -438.52338) (xy 148.487515 -438.512864) (xy 148.491004 -438.490105)
			(xy 148.487518 -438.467346) (xy 148.482812 -438.456832) (xy 148.401786 -438.291732) (xy 148.377508 -438.270052)
			(xy 148.333912 -438.221716) (xy 148.296539 -438.168423) (xy 148.265948 -438.110967) (xy 148.242596 -438.050209)
			(xy 148.22683 -437.987055) (xy 148.218888 -437.92245) (xy 148.218398 -437.889904) (xy 148.219134 -437.850579)
			(xy 148.230733 -437.772789) (xy 148.241512 -437.734964) (xy 148.241512 -437.21909) (xy 148.241999 -437.207003)
			(xy 148.249455 -437.184007) (xy 148.263637 -437.164429) (xy 148.283165 -437.150178) (xy 148.306134 -437.142641)
			(xy 148.31822 -437.142128) (xy 149.25802 -437.142128) (xy 149.270133 -437.1425) (xy 149.293165 -437.150008)
			(xy 149.312741 -437.16428) (xy 149.326934 -437.183913) (xy 149.334349 -437.206976) (xy 149.334728 -437.21909)
			(xy 149.334728 -438.089802) (xy 150.218394 -438.089802) (xy 150.218918 -438.057222) (xy 150.226892 -437.992552)
			(xy 150.242707 -437.929341) (xy 150.266128 -437.868536) (xy 150.296802 -437.811048) (xy 150.334271 -437.757739)
			(xy 150.377972 -437.709407) (xy 150.40229 -437.68772) (xy 150.482808 -437.523382) (xy 150.487509 -437.512865)
			(xy 150.490999 -437.490107) (xy 150.487514 -437.467348) (xy 150.482808 -437.456834) (xy 150.401782 -437.291734)
			(xy 150.377504 -437.270054) (xy 150.333908 -437.221718) (xy 150.296536 -437.168424) (xy 150.265945 -437.110969)
			(xy 150.242592 -437.050211) (xy 150.226827 -436.987057) (xy 150.218884 -436.922452) (xy 150.218394 -436.889906)
			(xy 150.21913 -436.850581) (xy 150.230729 -436.772791) (xy 150.241508 -436.734966) (xy 150.241508 -436.219092)
			(xy 150.241906 -436.207007) (xy 150.249378 -436.184021) (xy 150.263587 -436.16447) (xy 150.283143 -436.150267)
			(xy 150.306131 -436.142802) (xy 150.318216 -436.142384) (xy 151.258016 -436.142384) (xy 151.270091 -436.142851)
			(xy 151.293057 -436.150317) (xy 151.312593 -436.164513) (xy 151.326787 -436.18405) (xy 151.334251 -436.207017)
			(xy 151.334724 -436.219092) (xy 151.334724 -438.760616) (xy 151.33425 -438.77269) (xy 151.326785 -438.795655)
			(xy 151.31259 -438.81519) (xy 151.293055 -438.829385) (xy 151.27009 -438.83685) (xy 151.258016 -438.837324)
			(xy 150.318216 -438.837324) (xy 150.306144 -438.836822) (xy 150.28318 -438.829366) (xy 150.263644 -438.815179)
			(xy 150.249448 -438.795649) (xy 150.241983 -438.772688) (xy 150.241508 -438.760616) (xy 150.241508 -438.244742)
			(xy 150.23071 -438.20692) (xy 150.219102 -438.129129) (xy 150.218394 -438.089802) (xy 149.334728 -438.089802)
			(xy 149.334728 -439.0898) (xy 152.21839 -439.0898) (xy 152.218914 -439.05722) (xy 152.226888 -438.99255)
			(xy 152.242704 -438.929339) (xy 152.266124 -438.868534) (xy 152.296798 -438.811046) (xy 152.334267 -438.757737)
			(xy 152.377968 -438.709405) (xy 152.402286 -438.687718) (xy 152.482804 -438.52338) (xy 152.487507 -438.512864)
			(xy 152.490996 -438.490105) (xy 152.48751 -438.467346) (xy 152.482804 -438.456832) (xy 152.401778 -438.291732)
			(xy 152.377498 -438.270054) (xy 152.333903 -438.221718) (xy 152.296531 -438.168423) (xy 152.26594 -438.110968)
			(xy 152.242587 -438.050209) (xy 152.226822 -437.987055) (xy 152.21888 -437.92245) (xy 152.21839 -437.889904)
			(xy 152.219126 -437.850579) (xy 152.230725 -437.772789) (xy 152.241504 -437.734964) (xy 152.241504 -437.21909)
			(xy 152.241998 -437.207004) (xy 152.249453 -437.184009) (xy 152.263634 -437.164432) (xy 152.28316 -437.150181)
			(xy 152.306127 -437.142643) (xy 152.318212 -437.142128) (xy 153.258012 -437.142128) (xy 153.270124 -437.142506)
			(xy 153.293157 -437.150012) (xy 153.312732 -437.164283) (xy 153.326925 -437.183914) (xy 153.334341 -437.206976)
			(xy 153.33472 -437.21909) (xy 153.33472 -438.089802) (xy 154.218386 -438.089802) (xy 154.218913 -438.057222)
			(xy 154.226886 -437.992553) (xy 154.242702 -437.929342) (xy 154.266122 -437.868537) (xy 154.296796 -437.811049)
			(xy 154.334264 -437.757739) (xy 154.377965 -437.709408) (xy 154.402282 -437.68772) (xy 154.4828 -437.523382)
			(xy 154.487502 -437.512866) (xy 154.490992 -437.490107) (xy 154.487506 -437.467348) (xy 154.4828 -437.456834)
			(xy 154.401774 -437.291734) (xy 154.377494 -437.270056) (xy 154.333899 -437.221719) (xy 154.296527 -437.168425)
			(xy 154.265936 -437.11097) (xy 154.242584 -437.050211) (xy 154.226819 -436.987057) (xy 154.218876 -436.922452)
			(xy 154.218386 -436.889906) (xy 154.219123 -436.850581) (xy 154.230721 -436.772791) (xy 154.2415 -436.734966)
			(xy 154.2415 -436.219092) (xy 154.241958 -436.207016) (xy 154.249423 -436.184047) (xy 154.263621 -436.16451)
			(xy 154.283162 -436.150316) (xy 154.306132 -436.142855) (xy 154.318208 -436.142384) (xy 155.258008 -436.142384)
			(xy 155.270082 -436.142857) (xy 155.293048 -436.150321) (xy 155.312584 -436.164516) (xy 155.326779 -436.184052)
			(xy 155.334243 -436.207018) (xy 155.334716 -436.219092) (xy 155.334716 -438.760616) (xy 155.334249 -438.772691)
			(xy 155.326783 -438.795657) (xy 155.312587 -438.815193) (xy 155.29305 -438.829387) (xy 155.270083 -438.836851)
			(xy 155.258008 -438.837324) (xy 154.318208 -438.837324) (xy 154.306135 -438.836829) (xy 154.283171 -438.829371)
			(xy 154.263635 -438.815182) (xy 154.24944 -438.79565) (xy 154.241975 -438.772688) (xy 154.2415 -438.760616)
			(xy 154.2415 -438.244742) (xy 154.230701 -438.20692) (xy 154.219094 -438.129129) (xy 154.218386 -438.089802)
			(xy 153.33472 -438.089802) (xy 153.33472 -439.0898) (xy 156.218382 -439.0898) (xy 156.218909 -439.05722)
			(xy 156.226883 -438.992551) (xy 156.242698 -438.92934) (xy 156.266118 -438.868535) (xy 156.296792 -438.811047)
			(xy 156.33426 -438.757738) (xy 156.377961 -438.709406) (xy 156.402278 -438.687718) (xy 156.482796 -438.52338)
			(xy 156.487499 -438.512864) (xy 156.490989 -438.490105) (xy 156.487502 -438.467346) (xy 156.482796 -438.456832)
			(xy 156.40177 -438.291732) (xy 156.377509 -438.270033) (xy 156.333909 -438.221703) (xy 156.296532 -438.168413)
			(xy 156.265938 -438.110961) (xy 156.242583 -438.050205) (xy 156.226815 -437.987053) (xy 156.218872 -437.922449)
			(xy 156.218382 -437.889904) (xy 156.219119 -437.850579) (xy 156.230717 -437.772789) (xy 156.241496 -437.734964)
			(xy 156.241496 -437.21909) (xy 156.241998 -437.207004) (xy 156.249452 -437.184011) (xy 156.263631 -437.164435)
			(xy 156.283155 -437.150183) (xy 156.30612 -437.142644) (xy 156.318204 -437.142128) (xy 157.258004 -437.142128)
			(xy 157.270116 -437.142513) (xy 157.293148 -437.150017) (xy 157.312724 -437.164286) (xy 157.326917 -437.183916)
			(xy 157.334333 -437.206977) (xy 157.334712 -437.21909) (xy 157.334712 -438.089802) (xy 314.138056 -438.089802)
			(xy 314.138173 -438.074717) (xy 314.139949 -438.044598) (xy 314.141612 -438.029604) (xy 314.141612 -436.950104)
			(xy 314.139942 -436.935111) (xy 314.138164 -436.904992) (xy 314.138056 -436.889906) (xy 314.138164 -436.87482)
			(xy 314.139946 -436.844702) (xy 314.141612 -436.829708) (xy 314.141612 -436.219092) (xy 314.142006 -436.207007)
			(xy 314.149478 -436.18402) (xy 314.163688 -436.164469) (xy 314.183246 -436.150265) (xy 314.206235 -436.142802)
			(xy 314.21832 -436.142384) (xy 315.15812 -436.142384) (xy 315.170195 -436.142847) (xy 315.193161 -436.150314)
			(xy 315.212697 -436.164511) (xy 315.226891 -436.18405) (xy 315.234355 -436.207017) (xy 315.234828 -436.219092)
			(xy 315.234828 -438.760616) (xy 315.23435 -438.772689) (xy 315.226885 -438.795654) (xy 315.212691 -438.815189)
			(xy 315.193157 -438.829383) (xy 315.170193 -438.836849) (xy 315.15812 -438.837324) (xy 314.21832 -438.837324)
			(xy 314.20624 -438.83687) (xy 314.183261 -438.82941) (xy 314.163711 -438.815214) (xy 314.149506 -438.795672)
			(xy 314.142035 -438.772696) (xy 314.141612 -438.760616) (xy 314.141612 -438.15) (xy 314.139941 -438.135007)
			(xy 314.138164 -438.104888) (xy 314.138056 -438.089802) (xy 157.334712 -438.089802) (xy 157.334712 -439.0898)
			(xy 316.138052 -439.0898) (xy 316.138169 -439.074715) (xy 316.139945 -439.044596) (xy 316.141608 -439.029602)
			(xy 316.141608 -437.950102) (xy 316.139937 -437.935109) (xy 316.13816 -437.90499) (xy 316.138052 -437.889904)
			(xy 316.138169 -437.874819) (xy 316.139945 -437.8447) (xy 316.141608 -437.829706) (xy 316.141608 -437.21909)
			(xy 316.142098 -437.207003) (xy 316.149554 -437.184008) (xy 316.163736 -437.164431) (xy 316.183262 -437.150179)
			(xy 316.206231 -437.142642) (xy 316.218316 -437.142128) (xy 317.158116 -437.142128) (xy 317.170229 -437.142503)
			(xy 317.193261 -437.15001) (xy 317.212836 -437.164281) (xy 317.227029 -437.183914) (xy 317.234445 -437.206976)
			(xy 317.234824 -437.21909) (xy 317.234824 -438.089802) (xy 318.138048 -438.089802) (xy 318.138165 -438.074717)
			(xy 318.139941 -438.044598) (xy 318.141604 -438.029604) (xy 318.141604 -436.950104) (xy 318.139934 -436.935111)
			(xy 318.138156 -436.904992) (xy 318.138048 -436.889906) (xy 318.138156 -436.87482) (xy 318.139938 -436.844702)
			(xy 318.141604 -436.829708) (xy 318.141604 -436.219092) (xy 318.142006 -436.207008) (xy 318.149477 -436.184023)
			(xy 318.163686 -436.164471) (xy 318.183241 -436.150268) (xy 318.206228 -436.142803) (xy 318.218312 -436.142384)
			(xy 319.158112 -436.142384) (xy 319.170186 -436.142854) (xy 319.193153 -436.150319) (xy 319.212689 -436.164514)
			(xy 319.226883 -436.184051) (xy 319.234347 -436.207018) (xy 319.23482 -436.219092) (xy 319.23482 -438.760616)
			(xy 319.234349 -438.77269) (xy 319.226884 -438.795656) (xy 319.212689 -438.815191) (xy 319.193152 -438.829386)
			(xy 319.170186 -438.83685) (xy 319.158112 -438.837324) (xy 318.218312 -438.837324) (xy 318.20624 -438.836826)
			(xy 318.183276 -438.829369) (xy 318.16374 -438.81518) (xy 318.149544 -438.79565) (xy 318.142079 -438.772688)
			(xy 318.141604 -438.760616) (xy 318.141604 -438.15) (xy 318.139933 -438.135007) (xy 318.138156 -438.104888)
			(xy 318.138048 -438.089802) (xy 317.234824 -438.089802) (xy 317.234824 -439.0898) (xy 320.138044 -439.0898)
			(xy 320.138161 -439.074715) (xy 320.139937 -439.044596) (xy 320.1416 -439.029602) (xy 320.1416 -437.950102)
			(xy 320.139929 -437.935109) (xy 320.138152 -437.90499) (xy 320.138044 -437.889904) (xy 320.138161 -437.874819)
			(xy 320.139937 -437.8447) (xy 320.1416 -437.829706) (xy 320.1416 -437.21909) (xy 320.142098 -437.207004)
			(xy 320.149553 -437.18401) (xy 320.163733 -437.164434) (xy 320.183257 -437.150182) (xy 320.206224 -437.142643)
			(xy 320.218308 -437.142128) (xy 321.158108 -437.142128) (xy 321.17022 -437.14251) (xy 321.193252 -437.150015)
			(xy 321.212828 -437.164284) (xy 321.227021 -437.183915) (xy 321.234437 -437.206976) (xy 321.234816 -437.21909)
			(xy 321.234816 -438.089802) (xy 322.13804 -438.089802) (xy 322.138157 -438.074717) (xy 322.139933 -438.044598)
			(xy 322.141596 -438.029604) (xy 322.141596 -436.950104) (xy 322.139926 -436.935111) (xy 322.138148 -436.904992)
			(xy 322.13804 -436.889906) (xy 322.13815 -436.87482) (xy 322.139932 -436.844702) (xy 322.141596 -436.829708)
			(xy 322.141596 -436.219092) (xy 322.142058 -436.207017) (xy 322.149523 -436.184049) (xy 322.16372 -436.164511)
			(xy 322.183259 -436.150317) (xy 322.206229 -436.142856) (xy 322.218304 -436.142384) (xy 323.158104 -436.142384)
			(xy 323.170178 -436.142861) (xy 323.193144 -436.150323) (xy 323.21268 -436.164517) (xy 323.226875 -436.184053)
			(xy 323.234339 -436.207018) (xy 323.234812 -436.219092) (xy 323.234812 -438.760616) (xy 323.234349 -438.772691)
			(xy 323.226883 -438.795658) (xy 323.212686 -438.815194) (xy 323.193147 -438.829388) (xy 323.170179 -438.836851)
			(xy 323.158104 -438.837324) (xy 322.218304 -438.837324) (xy 322.206231 -438.836833) (xy 322.183267 -438.829373)
			(xy 322.163731 -438.815183) (xy 322.149536 -438.795651) (xy 322.142071 -438.772689) (xy 322.141596 -438.760616)
			(xy 322.141596 -438.15) (xy 322.139925 -438.135007) (xy 322.138148 -438.104888) (xy 322.13804 -438.089802)
			(xy 321.234816 -438.089802) (xy 321.234816 -439.0898) (xy 324.138036 -439.0898) (xy 324.138153 -439.074715)
			(xy 324.139929 -439.044596) (xy 324.141592 -439.029602) (xy 324.141592 -437.950102) (xy 324.139921 -437.935109)
			(xy 324.138144 -437.90499) (xy 324.138036 -437.889904) (xy 324.138153 -437.874819) (xy 324.139929 -437.8447)
			(xy 324.141592 -437.829706) (xy 324.141592 -437.21909) (xy 324.142098 -437.207005) (xy 324.149552 -437.184012)
			(xy 324.16373 -437.164436) (xy 324.183252 -437.150184) (xy 324.206217 -437.142644) (xy 324.2183 -437.142128)
			(xy 325.1581 -437.142128) (xy 325.170212 -437.142516) (xy 325.193244 -437.150019) (xy 325.212819 -437.164287)
			(xy 325.227013 -437.183916) (xy 325.234429 -437.206977) (xy 325.234808 -437.21909) (xy 325.234808 -438.089802)
			(xy 326.138032 -438.089802) (xy 326.138151 -438.074717) (xy 326.139927 -438.044598) (xy 326.141588 -438.029604)
			(xy 326.141588 -436.950104) (xy 326.139917 -436.935111) (xy 326.13814 -436.904992) (xy 326.138032 -436.889906)
			(xy 326.138142 -436.87482) (xy 326.139924 -436.844702) (xy 326.141588 -436.829708) (xy 326.141588 -436.219092)
			(xy 326.142057 -436.207017) (xy 326.149522 -436.184051) (xy 326.163717 -436.164514) (xy 326.183254 -436.15032)
			(xy 326.206221 -436.142857) (xy 326.218296 -436.142384) (xy 327.158096 -436.142384) (xy 327.17017 -436.142868)
			(xy 327.193135 -436.150328) (xy 327.212672 -436.16452) (xy 327.226867 -436.184054) (xy 327.234331 -436.207019)
			(xy 327.234804 -436.219092) (xy 327.234804 -438.760616) (xy 327.234349 -438.772692) (xy 327.226882 -438.79566)
			(xy 327.212683 -438.815197) (xy 327.193142 -438.829391) (xy 327.170172 -438.836852) (xy 327.158096 -438.837324)
			(xy 326.218296 -438.837324) (xy 326.206223 -438.836839) (xy 326.183258 -438.829378) (xy 326.163723 -438.815186)
			(xy 326.149528 -438.795652) (xy 326.142063 -438.772689) (xy 326.141588 -438.760616) (xy 326.141588 -438.15)
			(xy 326.139917 -438.135007) (xy 326.13814 -438.104888) (xy 326.138032 -438.089802) (xy 325.234808 -438.089802)
			(xy 325.234808 -439.0898) (xy 328.138028 -439.0898) (xy 328.138147 -439.074715) (xy 328.139923 -439.044596)
			(xy 328.141584 -439.029602) (xy 328.141584 -437.950102) (xy 328.139913 -437.935109) (xy 328.138136 -437.90499)
			(xy 328.138028 -437.889904) (xy 328.138147 -437.874819) (xy 328.139923 -437.8447) (xy 328.141584 -437.829706)
			(xy 328.141584 -437.21909) (xy 328.142 -437.206996) (xy 328.149465 -437.183987) (xy 328.163663 -437.164404)
			(xy 328.18321 -437.150155) (xy 328.206199 -437.142631) (xy 328.218292 -437.142128) (xy 329.158092 -437.142128)
			(xy 329.170203 -437.142523) (xy 329.193235 -437.150024) (xy 329.212811 -437.16429) (xy 329.227005 -437.183918)
			(xy 329.234421 -437.206977) (xy 329.2348 -437.21909) (xy 329.2348 -438.089802) (xy 331.138022 -438.089802)
			(xy 331.138115 -438.075228) (xy 331.139768 -438.046127) (xy 331.141324 -438.031636) (xy 331.141324 -436.948072)
			(xy 331.13978 -436.93358) (xy 331.138127 -436.90448) (xy 331.138022 -436.889906) (xy 331.138115 -436.875332)
			(xy 331.139768 -436.846231) (xy 331.141324 -436.83174) (xy 331.141324 -436.219092) (xy 331.14171 -436.20698)
			(xy 331.149214 -436.183949) (xy 331.163483 -436.164374) (xy 331.183112 -436.15018) (xy 331.206173 -436.142764)
			(xy 331.218286 -436.142384) (xy 332.158086 -436.142384) (xy 332.170179 -436.14282) (xy 332.193187 -436.150278)
			(xy 332.212771 -436.164471) (xy 332.22702 -436.184014) (xy 332.234545 -436.207) (xy 332.235048 -436.219092)
			(xy 332.235048 -438.760616) (xy 332.234598 -438.772721) (xy 332.2271 -438.795741) (xy 332.212845 -438.815309)
			(xy 332.193234 -438.829505) (xy 332.170192 -438.836934) (xy 332.158086 -438.837324) (xy 331.218286 -438.837324)
			(xy 331.206192 -438.836904) (xy 331.183185 -438.829439) (xy 331.163602 -438.815242) (xy 331.149353 -438.795696)
			(xy 331.141828 -438.772709) (xy 331.141324 -438.760616) (xy 331.141324 -438.147968) (xy 331.139779 -438.133476)
			(xy 331.138127 -438.104376) (xy 331.138022 -438.089802) (xy 329.2348 -438.089802) (xy 329.2348 -439.0898)
			(xy 333.138018 -439.0898) (xy 333.138111 -439.075226) (xy 333.139764 -439.046125) (xy 333.14132 -439.031634)
			(xy 333.14132 -437.94807) (xy 333.139775 -437.933578) (xy 333.138123 -437.904478) (xy 333.138018 -437.889904)
			(xy 333.138111 -437.87533) (xy 333.139764 -437.846229) (xy 333.14132 -437.831738) (xy 333.14132 -437.21909)
			(xy 333.141803 -437.206977) (xy 333.149291 -437.183936) (xy 333.163531 -437.164336) (xy 333.183129 -437.150095)
			(xy 333.206169 -437.142604) (xy 333.218282 -437.142128) (xy 334.158082 -437.142128) (xy 334.170203 -437.142575)
			(xy 334.193259 -437.150061) (xy 334.212874 -437.164306) (xy 334.227126 -437.183916) (xy 334.23462 -437.206969)
			(xy 334.235044 -437.21909) (xy 334.235044 -438.089802) (xy 335.138014 -438.089802) (xy 335.138106 -438.075228)
			(xy 335.13976 -438.046127) (xy 335.141316 -438.031636) (xy 335.141316 -436.948072) (xy 335.139772 -436.93358)
			(xy 335.138119 -436.90448) (xy 335.138014 -436.889906) (xy 335.138107 -436.875332) (xy 335.13976 -436.846231)
			(xy 335.141316 -436.83174) (xy 335.141316 -436.219092) (xy 335.14171 -436.206981) (xy 335.149213 -436.183951)
			(xy 335.16348 -436.164376) (xy 335.183107 -436.150183) (xy 335.206166 -436.142765) (xy 335.218278 -436.142384)
			(xy 336.158078 -436.142384) (xy 336.170171 -436.142827) (xy 336.193178 -436.150283) (xy 336.212762 -436.164474)
			(xy 336.227012 -436.184016) (xy 336.234537 -436.207001) (xy 336.23504 -436.219092) (xy 336.23504 -438.760616)
			(xy 336.234598 -438.772722) (xy 336.227099 -438.795743) (xy 336.212843 -438.815312) (xy 336.193229 -438.829508)
			(xy 336.170185 -438.836935) (xy 336.158078 -438.837324) (xy 335.218278 -438.837324) (xy 335.206184 -438.836911)
			(xy 335.183176 -438.829444) (xy 335.163594 -438.815245) (xy 335.149345 -438.795698) (xy 335.14182 -438.772709)
			(xy 335.141316 -438.760616) (xy 335.141316 -438.147968) (xy 335.139771 -438.133476) (xy 335.138119 -438.104376)
			(xy 335.138014 -438.089802) (xy 334.235044 -438.089802) (xy 334.235044 -439.0898) (xy 337.13801 -439.0898)
			(xy 337.138102 -439.075226) (xy 337.139756 -439.046125) (xy 337.141312 -439.031634) (xy 337.141312 -437.94807)
			(xy 337.139767 -437.933578) (xy 337.138115 -437.904478) (xy 337.13801 -437.889904) (xy 337.138103 -437.87533)
			(xy 337.139756 -437.846229) (xy 337.141312 -437.831738) (xy 337.141312 -437.21909) (xy 337.141803 -437.206978)
			(xy 337.14929 -437.183938) (xy 337.163528 -437.164339) (xy 337.183124 -437.150097) (xy 337.206162 -437.142606)
			(xy 337.218274 -437.142128) (xy 338.158074 -437.142128) (xy 338.170194 -437.142582) (xy 338.193251 -437.150066)
			(xy 338.212865 -437.164309) (xy 338.227118 -437.183917) (xy 338.234612 -437.20697) (xy 338.235036 -437.21909)
			(xy 338.235036 -438.089802) (xy 339.138006 -438.089802) (xy 339.138099 -438.075228) (xy 339.139752 -438.046127)
			(xy 339.141308 -438.031636) (xy 339.141308 -436.948072) (xy 339.139763 -436.93358) (xy 339.138111 -436.90448)
			(xy 339.138006 -436.889906) (xy 339.138099 -436.875332) (xy 339.139752 -436.846231) (xy 339.141308 -436.83174)
			(xy 339.141308 -436.219092) (xy 339.141709 -436.206982) (xy 339.149212 -436.183953) (xy 339.163477 -436.164379)
			(xy 339.183102 -436.150185) (xy 339.206158 -436.142766) (xy 339.21827 -436.142384) (xy 340.15807 -436.142384)
			(xy 340.170162 -436.142834) (xy 340.193169 -436.150288) (xy 340.212754 -436.164477) (xy 340.227004 -436.184017)
			(xy 340.234529 -436.207001) (xy 340.235032 -436.219092) (xy 340.235032 -438.760616) (xy 340.234598 -438.772723)
			(xy 340.227098 -438.795745) (xy 340.21284 -438.815315) (xy 340.193224 -438.82951) (xy 340.170178 -438.836936)
			(xy 340.15807 -438.837324) (xy 339.21827 -438.837324) (xy 339.206175 -438.836918) (xy 339.183168 -438.829448)
			(xy 339.163585 -438.815247) (xy 339.149337 -438.795699) (xy 339.141812 -438.77271) (xy 339.141308 -438.760616)
			(xy 339.141308 -438.147968) (xy 339.139763 -438.133476) (xy 339.138111 -438.104376) (xy 339.138006 -438.089802)
			(xy 338.235036 -438.089802) (xy 338.235036 -439.0898) (xy 341.138002 -439.0898) (xy 341.138094 -439.075226)
			(xy 341.139748 -439.046125) (xy 341.141304 -439.031634) (xy 341.141304 -437.94807) (xy 341.139759 -437.933578)
			(xy 341.138107 -437.904478) (xy 341.138002 -437.889904) (xy 341.138095 -437.87533) (xy 341.139748 -437.846229)
			(xy 341.141304 -437.831738) (xy 341.141304 -437.21909) (xy 341.141803 -437.206978) (xy 341.149289 -437.183941)
			(xy 341.163525 -437.164342) (xy 341.183119 -437.1501) (xy 341.206154 -437.142607) (xy 341.218266 -437.142128)
			(xy 342.158066 -437.142128) (xy 342.170186 -437.142589) (xy 342.193242 -437.15007) (xy 342.212857 -437.164312)
			(xy 342.22711 -437.183918) (xy 342.234604 -437.20697) (xy 342.235028 -437.21909) (xy 342.235028 -438.089802)
			(xy 343.137998 -438.089802) (xy 343.138091 -438.075228) (xy 343.139744 -438.046127) (xy 343.1413 -438.031636)
			(xy 343.1413 -436.948072) (xy 343.139755 -436.93358) (xy 343.138103 -436.90448) (xy 343.137998 -436.889906)
			(xy 343.138091 -436.875332) (xy 343.139744 -436.846231) (xy 343.1413 -436.83174) (xy 343.1413 -436.219092)
			(xy 343.141709 -436.206983) (xy 343.149211 -436.183955) (xy 343.163474 -436.164382) (xy 343.183097 -436.150188)
			(xy 343.206151 -436.142767) (xy 343.218262 -436.142384) (xy 344.158062 -436.142384) (xy 344.170154 -436.142841)
			(xy 344.193161 -436.150292) (xy 344.212745 -436.16448) (xy 344.226995 -436.184019) (xy 344.234521 -436.207002)
			(xy 344.235024 -436.219092) (xy 344.235024 -438.760616) (xy 344.234598 -438.772723) (xy 344.227097 -438.795747)
			(xy 344.212837 -438.815318) (xy 344.193219 -438.829513) (xy 344.170171 -438.836937) (xy 344.158062 -438.837324)
			(xy 343.218262 -438.837324) (xy 343.206167 -438.836924) (xy 343.183159 -438.829453) (xy 343.163577 -438.81525)
			(xy 343.149329 -438.795701) (xy 343.141804 -438.77271) (xy 343.1413 -438.760616) (xy 343.1413 -438.147968)
			(xy 343.139755 -438.133476) (xy 343.138103 -438.104376) (xy 343.137998 -438.089802) (xy 342.235028 -438.089802)
			(xy 342.235028 -439.0898) (xy 345.137994 -439.0898) (xy 345.138086 -439.075226) (xy 345.13974 -439.046125)
			(xy 345.141296 -439.031634) (xy 345.141296 -437.94807) (xy 345.139752 -437.933578) (xy 345.138099 -437.904478)
			(xy 345.137994 -437.889904) (xy 345.138087 -437.87533) (xy 345.13974 -437.846229) (xy 345.141296 -437.831738)
			(xy 345.141296 -437.21909) (xy 345.141803 -437.206979) (xy 345.149288 -437.183943) (xy 345.163522 -437.164345)
			(xy 345.183114 -437.150102) (xy 345.206147 -437.142608) (xy 345.218258 -437.142128) (xy 346.158058 -437.142128)
			(xy 346.170178 -437.142595) (xy 346.193233 -437.150075) (xy 346.212848 -437.164315) (xy 346.227101 -437.18392)
			(xy 346.234596 -437.206971) (xy 346.23502 -437.21909) (xy 346.23502 -439.0898) (xy 383.218436 -439.0898)
			(xy 383.218945 -439.05722) (xy 383.226919 -438.992549) (xy 383.242736 -438.929337) (xy 383.266159 -438.868531)
			(xy 383.296836 -438.811043) (xy 383.334308 -438.757735) (xy 383.378013 -438.709405) (xy 383.402332 -438.687718)
			(xy 383.48285 -438.52338) (xy 383.487551 -438.512864) (xy 383.491038 -438.490105) (xy 383.487554 -438.467347)
			(xy 383.48285 -438.456832) (xy 383.401824 -438.291732) (xy 383.377553 -438.270044) (xy 383.333956 -438.22171)
			(xy 383.296582 -438.168418) (xy 383.265989 -438.110965) (xy 383.242635 -438.050207) (xy 383.226869 -437.987054)
			(xy 383.218926 -437.92245) (xy 383.218436 -437.889904) (xy 383.219137 -437.850778) (xy 383.230611 -437.773371)
			(xy 383.241296 -437.735726) (xy 383.241296 -437.21909) (xy 383.241803 -437.206979) (xy 383.249288 -437.183943)
			(xy 383.263522 -437.164345) (xy 383.283114 -437.150102) (xy 383.306147 -437.142608) (xy 383.318258 -437.142128)
			(xy 384.258058 -437.142128) (xy 384.270178 -437.142595) (xy 384.293233 -437.150075) (xy 384.312848 -437.164315)
			(xy 384.327101 -437.18392) (xy 384.334596 -437.206971) (xy 384.33502 -437.21909) (xy 384.33502 -438.089802)
			(xy 385.218432 -438.089802) (xy 385.218944 -438.057222) (xy 385.226918 -437.992551) (xy 385.242735 -437.929339)
			(xy 385.266157 -437.868534) (xy 385.296833 -437.811046) (xy 385.334305 -437.757737) (xy 385.378009 -437.709407)
			(xy 385.402328 -437.68772) (xy 385.482846 -437.523382) (xy 385.487546 -437.512865) (xy 385.491034 -437.490107)
			(xy 385.48755 -437.467349) (xy 385.482846 -437.456834) (xy 385.40182 -437.291734) (xy 385.37755 -437.270046)
			(xy 385.333952 -437.221712) (xy 385.296578 -437.16842) (xy 385.265985 -437.110966) (xy 385.242631 -437.050209)
			(xy 385.226865 -436.987056) (xy 385.218922 -436.922452) (xy 385.218432 -436.889906) (xy 385.219133 -436.85078)
			(xy 385.230607 -436.773373) (xy 385.241292 -436.735728) (xy 385.241292 -436.219092) (xy 385.241709 -436.206983)
			(xy 385.24921 -436.183957) (xy 385.263472 -436.164385) (xy 385.283092 -436.15019) (xy 385.306144 -436.142768)
			(xy 385.318254 -436.142384) (xy 386.258054 -436.142384) (xy 386.270146 -436.142847) (xy 386.293152 -436.150297)
			(xy 386.312737 -436.164483) (xy 386.326987 -436.18402) (xy 386.334512 -436.207002) (xy 386.335016 -436.219092)
			(xy 386.335016 -438.760616) (xy 386.334598 -438.772724) (xy 386.327096 -438.795749) (xy 386.312834 -438.815321)
			(xy 386.293214 -438.829515) (xy 386.270163 -438.836939) (xy 386.258054 -438.837324) (xy 385.318254 -438.837324)
			(xy 385.306158 -438.836931) (xy 385.28315 -438.829457) (xy 385.263568 -438.815253) (xy 385.24932 -438.795702)
			(xy 385.241796 -438.77271) (xy 385.241292 -438.760616) (xy 385.241292 -438.24398) (xy 385.230605 -438.206335)
			(xy 385.219128 -438.128928) (xy 385.218432 -438.089802) (xy 384.33502 -438.089802) (xy 384.33502 -439.0898)
			(xy 387.218428 -439.0898) (xy 387.21894 -439.05722) (xy 387.226914 -438.992549) (xy 387.242731 -438.929337)
			(xy 387.266153 -438.868532) (xy 387.29683 -438.811044) (xy 387.334301 -438.757735) (xy 387.378005 -438.709405)
			(xy 387.402324 -438.687718) (xy 387.482842 -438.52338) (xy 387.487543 -438.512864) (xy 387.491031 -438.490105)
			(xy 387.487546 -438.467347) (xy 387.482842 -438.456832) (xy 387.401816 -438.291732) (xy 387.377544 -438.270045)
			(xy 387.333947 -438.221712) (xy 387.296573 -438.168419) (xy 387.26598 -438.110965) (xy 387.242627 -438.050208)
			(xy 387.226861 -437.987055) (xy 387.218918 -437.92245) (xy 387.218428 -437.889904) (xy 387.219129 -437.850778)
			(xy 387.230603 -437.773371) (xy 387.241288 -437.735726) (xy 387.241288 -437.21909) (xy 387.241803 -437.20698)
			(xy 387.249287 -437.183945) (xy 387.263519 -437.164348) (xy 387.283109 -437.150105) (xy 387.30614 -437.142609)
			(xy 387.31825 -437.142128) (xy 388.25805 -437.142128) (xy 388.270166 -437.142569) (xy 388.293209 -437.150069)
			(xy 388.312809 -437.164319) (xy 388.32705 -437.183927) (xy 388.334537 -437.206974) (xy 388.335012 -437.21909)
			(xy 388.335012 -438.089802) (xy 389.218424 -438.089802) (xy 389.218939 -438.057222) (xy 389.226913 -437.992551)
			(xy 389.242729 -437.92934) (xy 389.266151 -437.868534) (xy 389.296827 -437.811046) (xy 389.334298 -437.757738)
			(xy 389.378002 -437.709407) (xy 389.40232 -437.68772) (xy 389.482838 -437.523382) (xy 389.487538 -437.512865)
			(xy 389.491026 -437.490107) (xy 389.487542 -437.467349) (xy 389.482838 -437.456834) (xy 389.401812 -437.291734)
			(xy 389.37754 -437.270047) (xy 389.333943 -437.221713) (xy 389.296569 -437.168421) (xy 389.265977 -437.110967)
			(xy 389.242623 -437.050209) (xy 389.226857 -436.987056) (xy 389.218914 -436.922452) (xy 389.218424 -436.889906)
			(xy 389.219126 -436.85078) (xy 389.230599 -436.773373) (xy 389.241284 -436.735728) (xy 389.241284 -436.219092)
			(xy 389.241709 -436.206984) (xy 389.249209 -436.183959) (xy 389.263469 -436.164388) (xy 389.283087 -436.150193)
			(xy 389.306137 -436.142769) (xy 389.318246 -436.142384) (xy 390.258046 -436.142384) (xy 390.270142 -436.142769)
			(xy 390.293152 -436.150244) (xy 390.312735 -436.16445) (xy 390.326982 -436.184003) (xy 390.334505 -436.206997)
			(xy 390.335008 -436.219092) (xy 390.335008 -438.760616) (xy 390.334598 -438.772725) (xy 390.327095 -438.795751)
			(xy 390.312831 -438.815324) (xy 390.293209 -438.829518) (xy 390.270156 -438.83694) (xy 390.258046 -438.837324)
			(xy 389.318246 -438.837324) (xy 389.306155 -438.836853) (xy 389.28315 -438.829404) (xy 389.263566 -438.81522)
			(xy 389.249315 -438.795685) (xy 389.241789 -438.772705) (xy 389.241284 -438.760616) (xy 389.241284 -438.24398)
			(xy 389.230596 -438.206335) (xy 389.21912 -438.128928) (xy 389.218424 -438.089802) (xy 388.335012 -438.089802)
			(xy 388.335012 -439.0898) (xy 391.21842 -439.0898) (xy 391.218935 -439.05722) (xy 391.226909 -438.992549)
			(xy 391.242725 -438.929338) (xy 391.266147 -438.868532) (xy 391.296823 -438.811044) (xy 391.334294 -438.757736)
			(xy 391.377998 -438.709405) (xy 391.402316 -438.687718) (xy 391.482834 -438.52338) (xy 391.487536 -438.512864)
			(xy 391.491024 -438.490105) (xy 391.487539 -438.467347) (xy 391.482834 -438.456832) (xy 391.401808 -438.291732)
			(xy 391.377534 -438.270047) (xy 391.333937 -438.221713) (xy 391.296564 -438.16842) (xy 391.265972 -438.110966)
			(xy 391.242618 -438.050208) (xy 391.226853 -437.987055) (xy 391.21891 -437.92245) (xy 391.21842 -437.889904)
			(xy 391.219121 -437.850778) (xy 391.230595 -437.773371) (xy 391.24128 -437.735726) (xy 391.24128 -437.21909)
			(xy 391.241652 -437.206963) (xy 391.249152 -437.183896) (xy 391.263415 -437.164278) (xy 391.283043 -437.150029)
			(xy 391.306114 -437.142544) (xy 391.318242 -437.142128) (xy 392.258042 -437.142128) (xy 392.270158 -437.142576)
			(xy 392.293201 -437.150073) (xy 392.312801 -437.164322) (xy 392.327041 -437.183928) (xy 392.334529 -437.206974)
			(xy 392.335004 -437.21909) (xy 392.335004 -438.089802) (xy 393.218416 -438.089802) (xy 393.218933 -438.057222)
			(xy 393.226907 -437.992552) (xy 393.242723 -437.92934) (xy 393.266145 -437.868535) (xy 393.29682 -437.811047)
			(xy 393.334291 -437.757738) (xy 393.377994 -437.709407) (xy 393.402312 -437.68772) (xy 393.48283 -437.523382)
			(xy 393.48753 -437.512865) (xy 393.491019 -437.490107) (xy 393.487535 -437.467349) (xy 393.48283 -437.456834)
			(xy 393.401804 -437.291734) (xy 393.37753 -437.270049) (xy 393.333934 -437.221715) (xy 393.29656 -437.168422)
			(xy 393.265968 -437.110968) (xy 393.242615 -437.05021) (xy 393.226849 -436.987057) (xy 393.218906 -436.922452)
			(xy 393.218416 -436.889906) (xy 393.219114 -436.85078) (xy 393.23059 -436.773373) (xy 393.241276 -436.735728)
			(xy 393.241276 -436.219092) (xy 393.241709 -436.206985) (xy 393.249208 -436.183962) (xy 393.263466 -436.164391)
			(xy 393.283082 -436.150195) (xy 393.30613 -436.142771) (xy 393.318238 -436.142384) (xy 394.258038 -436.142384)
			(xy 394.270134 -436.142776) (xy 394.293143 -436.150248) (xy 394.312726 -436.164453) (xy 394.326974 -436.184004)
			(xy 394.334497 -436.206997) (xy 394.335 -436.219092) (xy 394.335 -438.760616) (xy 394.334597 -438.772726)
			(xy 394.327094 -438.795754) (xy 394.312828 -438.815326) (xy 394.293204 -438.82952) (xy 394.270149 -438.836941)
			(xy 394.258038 -438.837324) (xy 393.318238 -438.837324) (xy 393.306147 -438.83686) (xy 393.283141 -438.829409)
			(xy 393.263558 -438.815223) (xy 393.249307 -438.795686) (xy 393.241781 -438.772706) (xy 393.241276 -438.760616)
			(xy 393.241276 -438.24398) (xy 393.230588 -438.206335) (xy 393.219112 -438.128928) (xy 393.218416 -438.089802)
			(xy 392.335004 -438.089802) (xy 392.335004 -439.0898) (xy 395.218412 -439.0898) (xy 395.218929 -439.05722)
			(xy 395.226903 -438.99255) (xy 395.242719 -438.929338) (xy 395.266141 -438.868533) (xy 395.296816 -438.811045)
			(xy 395.334286 -438.757736) (xy 395.37799 -438.709405) (xy 395.402308 -438.687718) (xy 395.482826 -438.52338)
			(xy 395.487528 -438.512864) (xy 395.491017 -438.490105) (xy 395.487531 -438.467346) (xy 395.482826 -438.456832)
			(xy 395.4018 -438.291732) (xy 395.377525 -438.270049) (xy 395.333928 -438.221714) (xy 395.296555 -438.168421)
			(xy 395.265963 -438.110966) (xy 395.24261 -438.050208) (xy 395.226845 -437.987055) (xy 395.218902 -437.92245)
			(xy 395.218412 -437.889904) (xy 395.21911 -437.850778) (xy 395.230586 -437.773371) (xy 395.241272 -437.735726)
			(xy 395.241272 -437.21909) (xy 395.241652 -437.206963) (xy 395.249151 -437.183898) (xy 395.263412 -437.164281)
			(xy 395.283038 -437.150031) (xy 395.306107 -437.142545) (xy 395.318234 -437.142128) (xy 396.258034 -437.142128)
			(xy 396.270149 -437.142583) (xy 396.293192 -437.150078) (xy 396.312792 -437.164325) (xy 396.327033 -437.18393)
			(xy 396.334521 -437.206975) (xy 396.334996 -437.21909) (xy 396.334996 -438.089802) (xy 398.218406 -438.089802)
			(xy 398.218926 -438.057222) (xy 398.2269 -437.992552) (xy 398.242716 -437.92934) (xy 398.266137 -437.868535)
			(xy 398.296812 -437.811047) (xy 398.334281 -437.757738) (xy 398.377984 -437.709407) (xy 398.402302 -437.68772)
			(xy 398.48282 -437.523382) (xy 398.487521 -437.512865) (xy 398.49101 -437.490107) (xy 398.487525 -437.467348)
			(xy 398.48282 -437.456834) (xy 398.401794 -437.291734) (xy 398.377518 -437.270051) (xy 398.333922 -437.221716)
			(xy 398.296549 -437.168423) (xy 398.265957 -437.110968) (xy 398.242604 -437.05021) (xy 398.226839 -436.987057)
			(xy 398.218896 -436.922452) (xy 398.218406 -436.889906) (xy 398.219142 -436.850581) (xy 398.230741 -436.772791)
			(xy 398.24152 -436.734966) (xy 398.24152 -436.219092) (xy 398.241906 -436.207006) (xy 398.249379 -436.184018)
			(xy 398.263591 -436.164466) (xy 398.283151 -436.150263) (xy 398.306142 -436.1428) (xy 398.318228 -436.142384)
			(xy 399.258028 -436.142384) (xy 399.270103 -436.14284) (xy 399.29307 -436.150309) (xy 399.312606 -436.164508)
			(xy 399.3268 -436.184048) (xy 399.334263 -436.207017) (xy 399.334736 -436.219092) (xy 399.334736 -438.760616)
			(xy 399.33425 -438.772689) (xy 399.326786 -438.795651) (xy 399.312594 -438.815186) (xy 399.293062 -438.829381)
			(xy 399.270101 -438.836848) (xy 399.258028 -438.837324) (xy 398.318228 -438.837324) (xy 398.306148 -438.836864)
			(xy 398.283169 -438.829406) (xy 398.26362 -438.815211) (xy 398.249414 -438.79567) (xy 398.241943 -438.772695)
			(xy 398.24152 -438.760616) (xy 398.24152 -438.244742) (xy 398.230722 -438.20692) (xy 398.219114 -438.129129)
			(xy 398.218406 -438.089802) (xy 396.334996 -438.089802) (xy 396.334996 -439.0898) (xy 400.218402 -439.0898)
			(xy 400.218922 -439.05722) (xy 400.226896 -438.99255) (xy 400.242712 -438.929339) (xy 400.266133 -438.868533)
			(xy 400.296808 -438.811046) (xy 400.334278 -438.757736) (xy 400.37798 -438.709405) (xy 400.402298 -438.687718)
			(xy 400.482816 -438.52338) (xy 400.487519 -438.512864) (xy 400.491008 -438.490105) (xy 400.487522 -438.467346)
			(xy 400.482816 -438.456832) (xy 400.40179 -438.291732) (xy 400.377513 -438.270051) (xy 400.333917 -438.221716)
			(xy 400.296544 -438.168422) (xy 400.265953 -438.110967) (xy 400.2426 -438.050209) (xy 400.226834 -437.987055)
			(xy 400.218892 -437.92245) (xy 400.218402 -437.889904) (xy 400.219138 -437.850579) (xy 400.230737 -437.772789)
			(xy 400.241516 -437.734964) (xy 400.241516 -437.21909) (xy 400.241999 -437.207002) (xy 400.249455 -437.184006)
			(xy 400.263639 -437.164428) (xy 400.283167 -437.150177) (xy 400.306138 -437.142641) (xy 400.318224 -437.142128)
			(xy 401.258024 -437.142128) (xy 401.270137 -437.142496) (xy 401.29317 -437.150006) (xy 401.312745 -437.164279)
			(xy 401.326938 -437.183912) (xy 401.334353 -437.206975) (xy 401.334732 -437.21909) (xy 401.334732 -438.089802)
			(xy 402.218398 -438.089802) (xy 402.218921 -438.057222) (xy 402.226895 -437.992552) (xy 402.24271 -437.929341)
			(xy 402.266131 -437.868536) (xy 402.296805 -437.811048) (xy 402.334274 -437.757739) (xy 402.377976 -437.709407)
			(xy 402.402294 -437.68772) (xy 402.482812 -437.523382) (xy 402.487513 -437.512866) (xy 402.491003 -437.490107)
			(xy 402.487518 -437.467348) (xy 402.482812 -437.456834) (xy 402.401786 -437.291734) (xy 402.377509 -437.270053)
			(xy 402.333913 -437.221717) (xy 402.29654 -437.168424) (xy 402.265949 -437.110969) (xy 402.242596 -437.050211)
			(xy 402.226831 -436.987057) (xy 402.218888 -436.922452) (xy 402.218398 -436.889906) (xy 402.219134 -436.850581)
			(xy 402.230733 -436.772791) (xy 402.241512 -436.734966) (xy 402.241512 -436.219092) (xy 402.241906 -436.207007)
			(xy 402.249378 -436.18402) (xy 402.263588 -436.164469) (xy 402.283146 -436.150265) (xy 402.306135 -436.142802)
			(xy 402.31822 -436.142384) (xy 403.25802 -436.142384) (xy 403.270095 -436.142847) (xy 403.293061 -436.150314)
			(xy 403.312597 -436.164511) (xy 403.326791 -436.18405) (xy 403.334255 -436.207017) (xy 403.334728 -436.219092)
			(xy 403.334728 -438.760616) (xy 403.33425 -438.772689) (xy 403.326785 -438.795654) (xy 403.312591 -438.815189)
			(xy 403.293057 -438.829383) (xy 403.270093 -438.836849) (xy 403.25802 -438.837324) (xy 402.31822 -438.837324)
			(xy 402.30614 -438.83687) (xy 402.283161 -438.82941) (xy 402.263611 -438.815214) (xy 402.249406 -438.795672)
			(xy 402.241935 -438.772696) (xy 402.241512 -438.760616) (xy 402.241512 -438.244742) (xy 402.230714 -438.20692)
			(xy 402.219106 -438.129129) (xy 402.218398 -438.089802) (xy 401.334732 -438.089802) (xy 401.334732 -439.0898)
			(xy 404.218394 -439.0898) (xy 404.218917 -439.05722) (xy 404.226891 -438.99255) (xy 404.242706 -438.929339)
			(xy 404.266127 -438.868534) (xy 404.296802 -438.811046) (xy 404.334271 -438.757737) (xy 404.377972 -438.709405)
			(xy 404.40229 -438.687718) (xy 404.482808 -438.52338) (xy 404.487511 -438.512864) (xy 404.491 -438.490105)
			(xy 404.487514 -438.467346) (xy 404.482808 -438.456832) (xy 404.401782 -438.291732) (xy 404.377503 -438.270053)
			(xy 404.333907 -438.221717) (xy 404.296535 -438.168423) (xy 404.265944 -438.110968) (xy 404.242591 -438.050209)
			(xy 404.226826 -437.987055) (xy 404.218884 -437.92245) (xy 404.218394 -437.889904) (xy 404.21913 -437.850579)
			(xy 404.230729 -437.772789) (xy 404.241508 -437.734964) (xy 404.241508 -437.21909) (xy 404.241998 -437.207003)
			(xy 404.249454 -437.184008) (xy 404.263636 -437.164431) (xy 404.283162 -437.150179) (xy 404.306131 -437.142642)
			(xy 404.318216 -437.142128) (xy 405.258016 -437.142128) (xy 405.270129 -437.142503) (xy 405.293161 -437.15001)
			(xy 405.312736 -437.164281) (xy 405.326929 -437.183914) (xy 405.334345 -437.206976) (xy 405.334724 -437.21909)
			(xy 405.334724 -438.089802) (xy 406.21839 -438.089802) (xy 406.218916 -438.057222) (xy 406.226889 -437.992553)
			(xy 406.242704 -437.929341) (xy 406.266125 -437.868536) (xy 406.296799 -437.811048) (xy 406.334267 -437.757739)
			(xy 406.377969 -437.709407) (xy 406.402286 -437.68772) (xy 406.482804 -437.523382) (xy 406.487505 -437.512865)
			(xy 406.490995 -437.490107) (xy 406.48751 -437.467348) (xy 406.482804 -437.456834) (xy 406.401778 -437.291734)
			(xy 406.377499 -437.270055) (xy 406.333904 -437.221719) (xy 406.296531 -437.168425) (xy 406.26594 -437.110969)
			(xy 406.242588 -437.050211) (xy 406.226823 -436.987057) (xy 406.21888 -436.922452) (xy 406.21839 -436.889906)
			(xy 406.219127 -436.850581) (xy 406.230725 -436.772791) (xy 406.241504 -436.734966) (xy 406.241504 -436.219092)
			(xy 406.241906 -436.207008) (xy 406.249377 -436.184023) (xy 406.263586 -436.164471) (xy 406.283141 -436.150268)
			(xy 406.306128 -436.142803) (xy 406.318212 -436.142384) (xy 407.258012 -436.142384) (xy 407.270086 -436.142854)
			(xy 407.293053 -436.150319) (xy 407.312589 -436.164514) (xy 407.326783 -436.184051) (xy 407.334247 -436.207018)
			(xy 407.33472 -436.219092) (xy 407.33472 -438.760616) (xy 407.334249 -438.77269) (xy 407.326784 -438.795656)
			(xy 407.312589 -438.815191) (xy 407.293052 -438.829386) (xy 407.270086 -438.83685) (xy 407.258012 -438.837324)
			(xy 406.318212 -438.837324) (xy 406.30614 -438.836826) (xy 406.283176 -438.829369) (xy 406.26364 -438.81518)
			(xy 406.249444 -438.79565) (xy 406.241979 -438.772688) (xy 406.241504 -438.760616) (xy 406.241504 -438.244742)
			(xy 406.230705 -438.20692) (xy 406.219098 -438.129129) (xy 406.21839 -438.089802) (xy 405.334724 -438.089802)
			(xy 405.334724 -439.0898) (xy 408.218386 -439.0898) (xy 408.218912 -439.05722) (xy 408.226885 -438.992551)
			(xy 408.242701 -438.92934) (xy 408.266121 -438.868535) (xy 408.296795 -438.811047) (xy 408.334263 -438.757737)
			(xy 408.377965 -438.709406) (xy 408.402282 -438.687718) (xy 408.4828 -438.52338) (xy 408.487503 -438.512864)
			(xy 408.490993 -438.490105) (xy 408.487506 -438.467346) (xy 408.4828 -438.456832) (xy 408.401774 -438.291732)
			(xy 408.377493 -438.270055) (xy 408.333898 -438.221718) (xy 408.296526 -438.168424) (xy 408.265935 -438.110968)
			(xy 408.242583 -438.050209) (xy 408.226818 -437.987055) (xy 408.218876 -437.92245) (xy 408.218386 -437.889904)
			(xy 408.219122 -437.850579) (xy 408.230721 -437.772789) (xy 408.2415 -437.734964) (xy 408.2415 -437.21909)
			(xy 408.241998 -437.207004) (xy 408.249453 -437.18401) (xy 408.263633 -437.164434) (xy 408.283157 -437.150182)
			(xy 408.306124 -437.142643) (xy 408.318208 -437.142128) (xy 409.258008 -437.142128) (xy 409.27012 -437.14251)
			(xy 409.293152 -437.150015) (xy 409.312728 -437.164284) (xy 409.326921 -437.183915) (xy 409.334337 -437.206976)
			(xy 409.334716 -437.21909) (xy 409.334716 -438.089802) (xy 410.218382 -438.089802) (xy 410.21891 -438.057222)
			(xy 410.226884 -437.992553) (xy 410.242699 -437.929342) (xy 410.266119 -437.868537) (xy 410.296792 -437.811049)
			(xy 410.33426 -437.75774) (xy 410.377961 -437.709408) (xy 410.402278 -437.68772) (xy 410.482796 -437.523382)
			(xy 410.487498 -437.512866) (xy 410.490988 -437.490107) (xy 410.487502 -437.467348) (xy 410.482796 -437.456834)
			(xy 410.40177 -437.291734) (xy 410.37751 -437.270034) (xy 410.33391 -437.221704) (xy 410.296533 -437.168415)
			(xy 410.265939 -437.110963) (xy 410.242583 -437.050207) (xy 410.226816 -436.987055) (xy 410.218872 -436.922451)
			(xy 410.218382 -436.889906) (xy 410.219119 -436.850581) (xy 410.230717 -436.772791) (xy 410.241496 -436.734966)
			(xy 410.241496 -436.219092) (xy 410.241958 -436.207017) (xy 410.249423 -436.184049) (xy 410.26362 -436.164511)
			(xy 410.283159 -436.150317) (xy 410.306129 -436.142856) (xy 410.318204 -436.142384) (xy 411.258004 -436.142384)
			(xy 411.270078 -436.142861) (xy 411.293044 -436.150323) (xy 411.31258 -436.164517) (xy 411.326775 -436.184053)
			(xy 411.334239 -436.207018) (xy 411.334712 -436.219092) (xy 411.334712 -438.760616) (xy 411.334249 -438.772691)
			(xy 411.326783 -438.795658) (xy 411.312586 -438.815194) (xy 411.293047 -438.829388) (xy 411.270079 -438.836851)
			(xy 411.258004 -438.837324) (xy 410.318204 -438.837324) (xy 410.306131 -438.836833) (xy 410.283167 -438.829373)
			(xy 410.263631 -438.815183) (xy 410.249436 -438.795651) (xy 410.241971 -438.772689) (xy 410.241496 -438.760616)
			(xy 410.241496 -438.244742) (xy 410.230697 -438.20692) (xy 410.21909 -438.129129) (xy 410.218382 -438.089802)
			(xy 409.334716 -438.089802) (xy 409.334716 -439.0898) (xy 412.218378 -439.0898) (xy 412.218906 -439.05722)
			(xy 412.22688 -438.992551) (xy 412.242695 -438.92934) (xy 412.266115 -438.868535) (xy 412.296789 -438.811047)
			(xy 412.334256 -438.757738) (xy 412.377957 -438.709406) (xy 412.402274 -438.687718) (xy 412.482792 -438.52338)
			(xy 412.487495 -438.512864) (xy 412.490985 -438.490105) (xy 412.487499 -438.467346) (xy 412.482792 -438.456832)
			(xy 412.401766 -438.291732) (xy 412.377504 -438.270034) (xy 412.333904 -438.221704) (xy 412.296528 -438.168414)
			(xy 412.265934 -438.110962) (xy 412.242578 -438.050205) (xy 412.226811 -437.987053) (xy 412.218868 -437.922449)
			(xy 412.218378 -437.889904) (xy 412.219115 -437.850579) (xy 412.230713 -437.772789) (xy 412.241492 -437.734964)
			(xy 412.241492 -437.21909) (xy 412.241998 -437.207005) (xy 412.249452 -437.184012) (xy 412.26363 -437.164436)
			(xy 412.283152 -437.150184) (xy 412.306117 -437.142644) (xy 412.3182 -437.142128) (xy 413.258 -437.142128)
			(xy 413.270112 -437.142516) (xy 413.293144 -437.150019) (xy 413.312719 -437.164287) (xy 413.326913 -437.183916)
			(xy 413.334329 -437.206977) (xy 413.334708 -437.21909) (xy 413.334708 -439.760614) (xy 413.334206 -439.7727)
			(xy 413.326751 -439.795693) (xy 413.312572 -439.815268) (xy 413.293049 -439.82952) (xy 413.270084 -439.83706)
			(xy 413.258 -439.837576) (xy 412.3182 -439.837576) (xy 412.306089 -439.837184) (xy 412.283057 -439.829681)
			(xy 412.263482 -439.815414) (xy 412.249288 -439.795786) (xy 412.241872 -439.772727) (xy 412.241492 -439.760614)
			(xy 412.241492 -439.24474) (xy 412.230693 -439.206919) (xy 412.219086 -439.129127) (xy 412.218378 -439.0898)
			(xy 409.334716 -439.0898) (xy 409.334716 -439.760614) (xy 409.334304 -439.772709) (xy 409.326838 -439.795717)
			(xy 409.312639 -439.815301) (xy 409.293091 -439.829549) (xy 409.270101 -439.837073) (xy 409.258008 -439.837576)
			(xy 408.318208 -439.837576) (xy 408.306097 -439.837177) (xy 408.283066 -439.829677) (xy 408.263491 -439.815412)
			(xy 408.249296 -439.795785) (xy 408.24188 -439.772726) (xy 408.2415 -439.760614) (xy 408.2415 -439.24474)
			(xy 408.230701 -439.206918) (xy 408.219094 -439.129127) (xy 408.218386 -439.0898) (xy 405.334724 -439.0898)
			(xy 405.334724 -439.760614) (xy 405.334304 -439.772708) (xy 405.326839 -439.795715) (xy 405.312642 -439.815298)
			(xy 405.293096 -439.829547) (xy 405.270109 -439.837072) (xy 405.258016 -439.837576) (xy 404.318216 -439.837576)
			(xy 404.306106 -439.83717) (xy 404.283075 -439.829672) (xy 404.263499 -439.815408) (xy 404.249305 -439.795783)
			(xy 404.241888 -439.772726) (xy 404.241508 -439.760614) (xy 404.241508 -439.24474) (xy 404.230709 -439.206918)
			(xy 404.219102 -439.129127) (xy 404.218394 -439.0898) (xy 401.334732 -439.0898) (xy 401.334732 -439.760614)
			(xy 401.334304 -439.772707) (xy 401.32684 -439.795713) (xy 401.312645 -439.815295) (xy 401.293101 -439.829544)
			(xy 401.270116 -439.837071) (xy 401.258024 -439.837576) (xy 400.318224 -439.837576) (xy 400.306114 -439.837163)
			(xy 400.283083 -439.829667) (xy 400.263508 -439.815406) (xy 400.249313 -439.795781) (xy 400.241896 -439.772725)
			(xy 400.241516 -439.760614) (xy 400.241516 -439.24474) (xy 400.230717 -439.206918) (xy 400.21911 -439.129127)
			(xy 400.218402 -439.0898) (xy 396.334996 -439.0898) (xy 396.334996 -439.760614) (xy 396.334501 -439.772726)
			(xy 396.327014 -439.795764) (xy 396.312777 -439.815363) (xy 396.293182 -439.829605) (xy 396.270146 -439.837098)
			(xy 396.258034 -439.837576) (xy 395.318234 -439.837576) (xy 395.306114 -439.837111) (xy 395.283059 -439.82963)
			(xy 395.263445 -439.81539) (xy 395.249192 -439.795784) (xy 395.241696 -439.772733) (xy 395.241272 -439.760614)
			(xy 395.241272 -439.243978) (xy 395.230584 -439.206333) (xy 395.219107 -439.128926) (xy 395.218412 -439.0898)
			(xy 392.335004 -439.0898) (xy 392.335004 -439.760614) (xy 392.334501 -439.772725) (xy 392.327015 -439.795762)
			(xy 392.31278 -439.81536) (xy 392.293187 -439.829602) (xy 392.270153 -439.837097) (xy 392.258042 -439.837576)
			(xy 391.318242 -439.837576) (xy 391.306123 -439.837105) (xy 391.283068 -439.829626) (xy 391.263453 -439.815387)
			(xy 391.2492 -439.795783) (xy 391.241704 -439.772733) (xy 391.24128 -439.760614) (xy 391.24128 -439.243978)
			(xy 391.230592 -439.206333) (xy 391.219115 -439.128926) (xy 391.21842 -439.0898) (xy 388.335012 -439.0898)
			(xy 388.335012 -439.760614) (xy 388.334501 -439.772724) (xy 388.327016 -439.79576) (xy 388.312782 -439.815357)
			(xy 388.293192 -439.8296) (xy 388.27016 -439.837096) (xy 388.25805 -439.837576) (xy 387.31825 -439.837576)
			(xy 387.306134 -439.837131) (xy 387.283092 -439.829632) (xy 387.263492 -439.815382) (xy 387.249252 -439.795776)
			(xy 387.241763 -439.77273) (xy 387.241288 -439.760614) (xy 387.241288 -439.243978) (xy 387.2306 -439.206333)
			(xy 387.219123 -439.128926) (xy 387.218428 -439.0898) (xy 384.33502 -439.0898) (xy 384.33502 -439.760614)
			(xy 384.334651 -439.772742) (xy 384.32715 -439.795808) (xy 384.312886 -439.815426) (xy 384.293258 -439.829675)
			(xy 384.270186 -439.83716) (xy 384.258058 -439.837576) (xy 383.318258 -439.837576) (xy 383.306143 -439.837124)
			(xy 383.2831 -439.829627) (xy 383.263501 -439.815379) (xy 383.24926 -439.795774) (xy 383.241771 -439.77273)
			(xy 383.241296 -439.760614) (xy 383.241296 -439.243978) (xy 383.230608 -439.206333) (xy 383.219131 -439.128926)
			(xy 383.218436 -439.0898) (xy 346.23502 -439.0898) (xy 346.23502 -439.760614) (xy 346.234651 -439.772742)
			(xy 346.22715 -439.795808) (xy 346.212886 -439.815426) (xy 346.193258 -439.829675) (xy 346.170186 -439.83716)
			(xy 346.158058 -439.837576) (xy 345.218258 -439.837576) (xy 345.206143 -439.837124) (xy 345.1831 -439.829627)
			(xy 345.163501 -439.815379) (xy 345.14926 -439.795774) (xy 345.141771 -439.77273) (xy 345.141296 -439.760614)
			(xy 345.141296 -439.147966) (xy 345.139751 -439.133474) (xy 345.138099 -439.104374) (xy 345.137994 -439.0898)
			(xy 342.235028 -439.0898) (xy 342.235028 -439.760614) (xy 342.234651 -439.772741) (xy 342.227151 -439.795806)
			(xy 342.212889 -439.815424) (xy 342.193263 -439.829673) (xy 342.170193 -439.837159) (xy 342.158066 -439.837576)
			(xy 341.218266 -439.837576) (xy 341.206151 -439.837118) (xy 341.183109 -439.829623) (xy 341.163509 -439.815377)
			(xy 341.149268 -439.795773) (xy 341.141779 -439.772729) (xy 341.141304 -439.760614) (xy 341.141304 -439.147966)
			(xy 341.139759 -439.133474) (xy 341.138107 -439.104374) (xy 341.138002 -439.0898) (xy 338.235036 -439.0898)
			(xy 338.235036 -439.760614) (xy 338.234651 -439.77274) (xy 338.227152 -439.795804) (xy 338.212892 -439.815421)
			(xy 338.193268 -439.82967) (xy 338.1702 -439.837158) (xy 338.158074 -439.837576) (xy 337.218274 -439.837576)
			(xy 337.206159 -439.837111) (xy 337.183118 -439.829618) (xy 337.163518 -439.815374) (xy 337.149276 -439.795772)
			(xy 337.141787 -439.772729) (xy 337.141312 -439.760614) (xy 337.141312 -439.147966) (xy 337.139767 -439.133474)
			(xy 337.138115 -439.104374) (xy 337.13801 -439.0898) (xy 334.235044 -439.0898) (xy 334.235044 -439.760614)
			(xy 334.234651 -439.772739) (xy 334.227153 -439.795802) (xy 334.212895 -439.815418) (xy 334.193273 -439.829668)
			(xy 334.170207 -439.837157) (xy 334.158082 -439.837576) (xy 333.218282 -439.837576) (xy 333.206168 -439.837104)
			(xy 333.183126 -439.829614) (xy 333.163526 -439.815371) (xy 333.149285 -439.79577) (xy 333.141795 -439.772728)
			(xy 333.14132 -439.760614) (xy 333.14132 -439.147966) (xy 333.139775 -439.133474) (xy 333.138123 -439.104374)
			(xy 333.138018 -439.0898) (xy 329.2348 -439.0898) (xy 329.2348 -439.760614) (xy 329.234306 -439.7727)
			(xy 329.22685 -439.795695) (xy 329.212669 -439.815271) (xy 329.193144 -439.829523) (xy 329.170177 -439.837061)
			(xy 329.158092 -439.837576) (xy 328.218292 -439.837576) (xy 328.20618 -439.83719) (xy 328.183149 -439.829686)
			(xy 328.163574 -439.815417) (xy 328.14938 -439.795788) (xy 328.141964 -439.772727) (xy 328.141584 -439.760614)
			(xy 328.141584 -439.149998) (xy 328.139913 -439.135005) (xy 328.138136 -439.104886) (xy 328.138028 -439.0898)
			(xy 325.234808 -439.0898) (xy 325.234808 -439.760614) (xy 325.234306 -439.7727) (xy 325.226851 -439.795693)
			(xy 325.212672 -439.815268) (xy 325.193149 -439.82952) (xy 325.170184 -439.83706) (xy 325.1581 -439.837576)
			(xy 324.2183 -439.837576) (xy 324.206189 -439.837184) (xy 324.183157 -439.829681) (xy 324.163582 -439.815414)
			(xy 324.149388 -439.795786) (xy 324.141972 -439.772727) (xy 324.141592 -439.760614) (xy 324.141592 -439.149998)
			(xy 324.139921 -439.135005) (xy 324.138144 -439.104886) (xy 324.138036 -439.0898) (xy 321.234816 -439.0898)
			(xy 321.234816 -439.760614) (xy 321.234404 -439.772709) (xy 321.226938 -439.795717) (xy 321.212739 -439.815301)
			(xy 321.193191 -439.829549) (xy 321.170201 -439.837073) (xy 321.158108 -439.837576) (xy 320.218308 -439.837576)
			(xy 320.206197 -439.837177) (xy 320.183166 -439.829677) (xy 320.163591 -439.815412) (xy 320.149396 -439.795785)
			(xy 320.14198 -439.772726) (xy 320.1416 -439.760614) (xy 320.1416 -439.149998) (xy 320.139929 -439.135005)
			(xy 320.138152 -439.104886) (xy 320.138044 -439.0898) (xy 317.234824 -439.0898) (xy 317.234824 -439.760614)
			(xy 317.234404 -439.772708) (xy 317.226939 -439.795715) (xy 317.212742 -439.815298) (xy 317.193196 -439.829547)
			(xy 317.170209 -439.837072) (xy 317.158116 -439.837576) (xy 316.218316 -439.837576) (xy 316.206206 -439.83717)
			(xy 316.183175 -439.829672) (xy 316.163599 -439.815408) (xy 316.149405 -439.795783) (xy 316.141988 -439.772726)
			(xy 316.141608 -439.760614) (xy 316.141608 -439.149998) (xy 316.139937 -439.135005) (xy 316.13816 -439.104886)
			(xy 316.138052 -439.0898) (xy 157.334712 -439.0898) (xy 157.334712 -439.760614) (xy 157.334304 -439.772709)
			(xy 157.326838 -439.795718) (xy 157.312637 -439.815302) (xy 157.293089 -439.829551) (xy 157.270098 -439.837074)
			(xy 157.258004 -439.837576) (xy 156.318204 -439.837576) (xy 156.306093 -439.83718) (xy 156.283062 -439.829679)
			(xy 156.263486 -439.815413) (xy 156.249292 -439.795785) (xy 156.241876 -439.772727) (xy 156.241496 -439.760614)
			(xy 156.241496 -439.24474) (xy 156.230697 -439.206918) (xy 156.21909 -439.129127) (xy 156.218382 -439.0898)
			(xy 153.33472 -439.0898) (xy 153.33472 -439.760614) (xy 153.334304 -439.772708) (xy 153.326839 -439.795716)
			(xy 153.31264 -439.815299) (xy 153.293094 -439.829548) (xy 153.270105 -439.837073) (xy 153.258012 -439.837576)
			(xy 152.318212 -439.837576) (xy 152.306101 -439.837173) (xy 152.28307 -439.829674) (xy 152.263495 -439.81541)
			(xy 152.249301 -439.795784) (xy 152.241884 -439.772726) (xy 152.241504 -439.760614) (xy 152.241504 -439.24474)
			(xy 152.230705 -439.206918) (xy 152.219098 -439.129127) (xy 152.21839 -439.0898) (xy 149.334728 -439.0898)
			(xy 149.334728 -439.760614) (xy 149.334304 -439.772708) (xy 149.32684 -439.795714) (xy 149.312643 -439.815297)
			(xy 149.293099 -439.829546) (xy 149.270112 -439.837072) (xy 149.25802 -439.837576) (xy 148.31822 -439.837576)
			(xy 148.30611 -439.837166) (xy 148.283079 -439.829669) (xy 148.263504 -439.815407) (xy 148.249309 -439.795782)
			(xy 148.241892 -439.772726) (xy 148.241512 -439.760614) (xy 148.241512 -439.24474) (xy 148.230713 -439.206918)
			(xy 148.219106 -439.129127) (xy 148.218398 -439.0898) (xy 145.334736 -439.0898) (xy 145.334736 -439.760614)
			(xy 145.334304 -439.772707) (xy 145.326841 -439.795712) (xy 145.312646 -439.815294) (xy 145.293104 -439.829543)
			(xy 145.270119 -439.83707) (xy 145.258028 -439.837576) (xy 144.318228 -439.837576) (xy 144.306118 -439.837159)
			(xy 144.283088 -439.829665) (xy 144.263512 -439.815404) (xy 144.249317 -439.795781) (xy 144.2419 -439.772725)
			(xy 144.24152 -439.760614) (xy 144.24152 -439.24474) (xy 144.230721 -439.206918) (xy 144.219114 -439.129127)
			(xy 144.218406 -439.0898) (xy 140.335 -439.0898) (xy 140.335 -439.760614) (xy 140.334501 -439.772726)
			(xy 140.327015 -439.795763) (xy 140.312778 -439.815361) (xy 140.293184 -439.829604) (xy 140.270149 -439.837097)
			(xy 140.258038 -439.837576) (xy 139.318238 -439.837576) (xy 139.306119 -439.837108) (xy 139.283063 -439.829628)
			(xy 139.263449 -439.815388) (xy 139.249196 -439.795783) (xy 139.2417 -439.772733) (xy 139.241276 -439.760614)
			(xy 139.241276 -439.243978) (xy 139.230588 -439.206333) (xy 139.219111 -439.128926) (xy 139.218416 -439.0898)
			(xy 136.335008 -439.0898) (xy 136.335008 -439.760614) (xy 136.334501 -439.772725) (xy 136.327016 -439.795761)
			(xy 136.312781 -439.815358) (xy 136.293189 -439.829601) (xy 136.270157 -439.837096) (xy 136.258046 -439.837576)
			(xy 135.318246 -439.837576) (xy 135.306127 -439.837101) (xy 135.283072 -439.829623) (xy 135.263457 -439.815385)
			(xy 135.249204 -439.795782) (xy 135.241708 -439.772733) (xy 135.241284 -439.760614) (xy 135.241284 -439.243978)
			(xy 135.230596 -439.206333) (xy 135.219119 -439.128926) (xy 135.218424 -439.0898) (xy 132.335016 -439.0898)
			(xy 132.335016 -439.760614) (xy 132.334651 -439.772742) (xy 132.327149 -439.795809) (xy 132.312885 -439.815428)
			(xy 132.293255 -439.829677) (xy 132.270182 -439.83716) (xy 132.258054 -439.837576) (xy 131.318254 -439.837576)
			(xy 131.306138 -439.837128) (xy 131.283096 -439.82963) (xy 131.263496 -439.815381) (xy 131.249256 -439.795775)
			(xy 131.241767 -439.77273) (xy 131.241292 -439.760614) (xy 131.241292 -439.243978) (xy 131.230604 -439.206333)
			(xy 131.219127 -439.128926) (xy 131.218432 -439.0898) (xy 128.335024 -439.0898) (xy 128.335024 -439.760614)
			(xy 128.334651 -439.772741) (xy 128.32715 -439.795807) (xy 128.312888 -439.815425) (xy 128.29326 -439.829674)
			(xy 128.27019 -439.837159) (xy 128.258062 -439.837576) (xy 127.318262 -439.837576) (xy 127.306147 -439.837121)
			(xy 127.283105 -439.829625) (xy 127.263505 -439.815378) (xy 127.249264 -439.795774) (xy 127.241775 -439.772729)
			(xy 127.2413 -439.760614) (xy 127.2413 -439.243978) (xy 127.230612 -439.206333) (xy 127.219135 -439.128926)
			(xy 127.21844 -439.0898) (xy 90.235024 -439.0898) (xy 90.235024 -439.760614) (xy 90.234651 -439.772741)
			(xy 90.22715 -439.795807) (xy 90.212888 -439.815425) (xy 90.19326 -439.829674) (xy 90.17019 -439.837159)
			(xy 90.158062 -439.837576) (xy 89.218262 -439.837576) (xy 89.206147 -439.837121) (xy 89.183105 -439.829625)
			(xy 89.163505 -439.815378) (xy 89.149264 -439.795774) (xy 89.141775 -439.772729) (xy 89.1413 -439.760614)
			(xy 89.1413 -439.147966) (xy 89.139755 -439.133474) (xy 89.138103 -439.104374) (xy 89.137998 -439.0898)
			(xy 86.235032 -439.0898) (xy 86.235032 -439.760614) (xy 86.234651 -439.77274) (xy 86.227152 -439.795805)
			(xy 86.212891 -439.815422) (xy 86.193265 -439.829672) (xy 86.170197 -439.837158) (xy 86.15807 -439.837576)
			(xy 85.21827 -439.837576) (xy 85.206155 -439.837114) (xy 85.183113 -439.82962) (xy 85.163513 -439.815375)
			(xy 85.149272 -439.795772) (xy 85.141783 -439.772729) (xy 85.141308 -439.760614) (xy 85.141308 -439.147966)
			(xy 85.139763 -439.133474) (xy 85.138111 -439.104374) (xy 85.138006 -439.0898) (xy 82.23504 -439.0898)
			(xy 82.23504 -439.760614) (xy 82.234651 -439.77274) (xy 82.227153 -439.795803) (xy 82.212894 -439.815419)
			(xy 82.19327 -439.829669) (xy 82.170204 -439.837157) (xy 82.158078 -439.837576) (xy 81.218278 -439.837576)
			(xy 81.206164 -439.837107) (xy 81.183122 -439.829616) (xy 81.163522 -439.815372) (xy 81.149281 -439.795771)
			(xy 81.141791 -439.772728) (xy 81.141316 -439.760614) (xy 81.141316 -439.147966) (xy 81.139771 -439.133474)
			(xy 81.138119 -439.104374) (xy 81.138014 -439.0898) (xy 78.235048 -439.0898) (xy 78.235048 -439.760614)
			(xy 78.2346 -439.772731) (xy 78.227107 -439.795777) (xy 78.21286 -439.81538) (xy 78.193252 -439.82962)
			(xy 78.170203 -439.837105) (xy 78.158086 -439.837576) (xy 77.218286 -439.837576) (xy 77.206172 -439.837101)
			(xy 77.183131 -439.829611) (xy 77.16353 -439.81537) (xy 77.149289 -439.795769) (xy 77.141799 -439.772728)
			(xy 77.141324 -439.760614) (xy 77.141324 -439.147966) (xy 77.139779 -439.133474) (xy 77.138127 -439.104374)
			(xy 77.138022 -439.0898) (xy 73.234804 -439.0898) (xy 73.234804 -439.760614) (xy 73.234306 -439.7727)
			(xy 73.22685 -439.795694) (xy 73.21267 -439.81527) (xy 73.193146 -439.829521) (xy 73.17018 -439.837061)
			(xy 73.158096 -439.837576) (xy 72.218296 -439.837576) (xy 72.206185 -439.837187) (xy 72.183153 -439.829683)
			(xy 72.163578 -439.815416) (xy 72.149384 -439.795787) (xy 72.141968 -439.772727) (xy 72.141588 -439.760614)
			(xy 72.141588 -439.149998) (xy 72.139917 -439.135005) (xy 72.13814 -439.104886) (xy 72.138032 -439.0898)
			(xy 69.234812 -439.0898) (xy 69.234812 -439.760614) (xy 69.234404 -439.772709) (xy 69.226938 -439.795718)
			(xy 69.212737 -439.815302) (xy 69.193189 -439.829551) (xy 69.170198 -439.837074) (xy 69.158104 -439.837576)
			(xy 68.218304 -439.837576) (xy 68.206193 -439.83718) (xy 68.183162 -439.829679) (xy 68.163586 -439.815413)
			(xy 68.149392 -439.795785) (xy 68.141976 -439.772727) (xy 68.141596 -439.760614) (xy 68.141596 -439.149998)
			(xy 68.139925 -439.135005) (xy 68.138148 -439.104886) (xy 68.13804 -439.0898) (xy 65.23482 -439.0898)
			(xy 65.23482 -439.760614) (xy 65.234404 -439.772708) (xy 65.226939 -439.795716) (xy 65.21274 -439.815299)
			(xy 65.193194 -439.829548) (xy 65.170205 -439.837073) (xy 65.158112 -439.837576) (xy 64.218312 -439.837576)
			(xy 64.206201 -439.837173) (xy 64.18317 -439.829674) (xy 64.163595 -439.81541) (xy 64.149401 -439.795784)
			(xy 64.141984 -439.772726) (xy 64.141604 -439.760614) (xy 64.141604 -439.149998) (xy 64.139933 -439.135005)
			(xy 64.138156 -439.104886) (xy 64.138048 -439.0898) (xy 61.234828 -439.0898) (xy 61.234828 -439.760614)
			(xy 61.234404 -439.772708) (xy 61.22694 -439.795714) (xy 61.212743 -439.815297) (xy 61.193199 -439.829546)
			(xy 61.170212 -439.837072) (xy 61.15812 -439.837576) (xy 60.21832 -439.837576) (xy 60.20621 -439.837166)
			(xy 60.183179 -439.829669) (xy 60.163604 -439.815407) (xy 60.149409 -439.795782) (xy 60.141992 -439.772726)
			(xy 60.141612 -439.760614) (xy 60.141612 -439.149998) (xy 60.139941 -439.135005) (xy 60.138164 -439.104886)
			(xy 60.138056 -439.0898) (xy 7.00913 -439.0898) (xy 7.00913 -439.989976) (xy 7.009638 -440.045746)
			(xy 7.017973 -440.156973) (xy 7.034597 -440.267266) (xy 7.059417 -440.376009) (xy 7.092293 -440.482593)
			(xy 7.133043 -440.586422) (xy 7.181438 -440.686915) (xy 7.237207 -440.783511) (xy 7.300039 -440.87567)
			(xy 7.369583 -440.962874) (xy 7.445449 -441.044639) (xy 7.527212 -441.120505) (xy 7.614417 -441.190048)
			(xy 7.706575 -441.252881) (xy 7.803171 -441.30865) (xy 7.903664 -441.357045) (xy 8.007493 -441.397795)
			(xy 8.114077 -441.430672) (xy 8.22282 -441.455492) (xy 8.333113 -441.472116) (xy 8.44434 -441.480451)
			(xy 8.50011 -441.480956) (xy 194.495928 -441.480956)
		)
		(stroke
			(width 0)
			(type solid)
		)
		(fill yes)
		(layer "In5.Cu")
		(net "GND")
	)
	(gr_line
		(start 206.17434 -435.523132)
		(end 207.503268 -436.85206)
		(stroke
			(width 0.635)
			(type default)
		)
		(layer "In5.Cu")
	)
	(gr_line
		(start 206.17434 -415.567368)
		(end 206.17434 -435.523132)
		(stroke
			(width 0.635)
			(type default)
		)
		(layer "In5.Cu")
	)
	(gr_line
		(start 207.213708 -414.528)
		(end 206.17434 -415.567368)
		(stroke
			(width 0.635)
			(type default)
		)
		(layer "In5.Cu")
	)
	(gr_line
		(start 207.503268 -436.85206)
		(end 228.909372 -436.85206)
		(stroke
			(width 0.635)
			(type default)
		)
		(layer "In5.Cu")
	)
	(gr_line
		(start 228.909372 -436.85206)
		(end 230.69804 -435.063392)
		(stroke
			(width 0.635)
			(type default)
		)
		(layer "In5.Cu")
	)
	(gr_line
		(start 230.69804 -423.43578)
		(end 230.69804 -435.063392)
		(stroke
			(width 0.635)
			(type default)
		)
		(layer "In5.Cu")
	)
	(gr_line
		(start 232.938828 -414.528)
		(end 207.213708 -414.528)
		(stroke
			(width 0.635)
			(type default)
		)
		(layer "In5.Cu")
	)
	(gr_line
		(start 233.18978 -420.94404)
		(end 230.69804 -423.43578)
		(stroke
			(width 0.635)
			(type default)
		)
		(layer "In5.Cu")
	)
	(gr_line
		(start 239.67694 -402.10994)
		(end 239.86236 -402.29536)
		(stroke
			(width 0.508)
			(type default)
		)
		(layer "In5.Cu")
	)
	(gr_line
		(start 239.67694 -397.53286)
		(end 239.67694 -402.10994)
		(stroke
			(width 0.508)
			(type default)
		)
		(layer "In5.Cu")
	)
	(gr_line
		(start 239.713008 -407.75382)
		(end 232.938828 -414.528)
		(stroke
			(width 0.635)
			(type default)
		)
		(layer "In5.Cu")
	)
	(gr_line
		(start 239.81918 -401.97786)
		(end 239.81918 -397.5608)
		(stroke
			(width 0.2)
			(type default)
		)
		(layer "In5.Cu")
	)
	(gr_line
		(start 239.81918 -397.5608)
		(end 240.07826 -397.30172)
		(stroke
			(width 0.2)
			(type default)
		)
		(layer "In5.Cu")
	)
	(gr_line
		(start 239.86236 -402.29536)
		(end 275.44522 -402.29536)
		(stroke
			(width 0.508)
			(type default)
		)
		(layer "In5.Cu")
	)
	(gr_line
		(start 239.96904 -402.12772)
		(end 239.81918 -401.97786)
		(stroke
			(width 0.2)
			(type default)
		)
		(layer "In5.Cu")
	)
	(gr_line
		(start 240.06556 -397.14424)
		(end 239.67694 -397.53286)
		(stroke
			(width 0.508)
			(type default)
		)
		(layer "In5.Cu")
	)
	(gr_line
		(start 240.07826 -397.30172)
		(end 280.16454 -397.30172)
		(stroke
			(width 0.2)
			(type default)
		)
		(layer "In5.Cu")
	)
	(gr_line
		(start 270.496792 -420.94404)
		(end 233.18978 -420.94404)
		(stroke
			(width 0.635)
			(type default)
		)
		(layer "In5.Cu")
	)
	(gr_line
		(start 275.44522 -402.29536)
		(end 280.32202 -402.29536)
		(stroke
			(width 0.508)
			(type default)
		)
		(layer "In5.Cu")
	)
	(gr_line
		(start 275.680932 -415.7599)
		(end 270.496792 -420.94404)
		(stroke
			(width 0.635)
			(type default)
		)
		(layer "In5.Cu")
	)
	(gr_line
		(start 279.927812 -415.7599)
		(end 275.680932 -415.7599)
		(stroke
			(width 0.635)
			(type default)
		)
		(layer "In5.Cu")
	)
	(gr_line
		(start 279.927812 -415.7599)
		(end 280.51506 -415.172652)
		(stroke
			(width 0.635)
			(type default)
		)
		(layer "In5.Cu")
	)
	(gr_line
		(start 280.100532 -407.75382)
		(end 239.713008 -407.75382)
		(stroke
			(width 0.635)
			(type default)
		)
		(layer "In5.Cu")
	)
	(gr_line
		(start 280.16454 -397.30172)
		(end 280.34742 -397.4846)
		(stroke
			(width 0.2)
			(type default)
		)
		(layer "In5.Cu")
	)
	(gr_line
		(start 280.17978 -402.12772)
		(end 239.96904 -402.12772)
		(stroke
			(width 0.2)
			(type default)
		)
		(layer "In5.Cu")
	)
	(gr_line
		(start 280.24074 -397.14424)
		(end 240.06556 -397.14424)
		(stroke
			(width 0.508)
			(type default)
		)
		(layer "In5.Cu")
	)
	(gr_line
		(start 280.32202 -402.29536)
		(end 280.50998 -402.1074)
		(stroke
			(width 0.508)
			(type default)
		)
		(layer "In5.Cu")
	)
	(gr_line
		(start 280.34742 -401.96008)
		(end 280.17978 -402.12772)
		(stroke
			(width 0.2)
			(type default)
		)
		(layer "In5.Cu")
	)
	(gr_line
		(start 280.34742 -397.4846)
		(end 280.34742 -401.96008)
		(stroke
			(width 0.2)
			(type default)
		)
		(layer "In5.Cu")
	)
	(gr_line
		(start 280.50998 -402.1074)
		(end 280.50998 -397.41348)
		(stroke
			(width 0.508)
			(type default)
		)
		(layer "In5.Cu")
	)
	(gr_line
		(start 280.50998 -397.41348)
		(end 280.24074 -397.14424)
		(stroke
			(width 0.508)
			(type default)
		)
		(layer "In5.Cu")
	)
	(gr_line
		(start 280.51506 -415.172652)
		(end 280.51506 -408.168348)
		(stroke
			(width 0.635)
			(type default)
		)
		(layer "In5.Cu")
	)
	(gr_line
		(start 280.51506 -408.168348)
		(end 280.100532 -407.75382)
		(stroke
			(width 0.635)
			(type default)
		)
		(layer "In5.Cu")
	)
	(gr_poly
		(pts
			(xy 84.469224 -234.78998) (xy 84.476844 -234.746546) (xy 84.126832 -234.68457) (xy 84.118958 -234.728258)
			(xy 84.13877 -234.8865) (xy 84.39658 -234.931966)
		)
		(stroke
			(width 0)
			(type solid)
		)
		(fill yes)
		(layer "In6.Cu")
		(net "M_C_CPU1_SB_DQ<13>")
	)
	(gr_poly
		(pts
			(xy 84.55533 -244.940582) (xy 84.50834 -244.788182) (xy 84.24672 -244.788182) (xy 84.19973 -244.940582)
			(xy 84.19973 -244.985032) (xy 84.55533 -244.985032)
		)
		(stroke
			(width 0)
			(type solid)
		)
		(fill yes)
		(layer "In6.Cu")
		(net "M_D_CPU1_SB_CS_N<1>")
	)
	(gr_poly
		(pts
			(xy 84.563712 -244.53215) (xy 84.563712 -244.487954) (xy 84.208112 -244.487954) (xy 84.208112 -244.53215)
			(xy 84.255102 -244.68455) (xy 84.516722 -244.68455)
		)
		(stroke
			(width 0)
			(type solid)
		)
		(fill yes)
		(layer "In6.Cu")
		(net "M_C_CPU1_SB_DQ<0>")
	)
	(gr_poly
		(pts
			(xy 84.563966 -246.16029) (xy 84.563966 -246.11584) (xy 84.208366 -246.11584) (xy 84.208366 -246.16029)
			(xy 84.255356 -246.31269) (xy 84.516976 -246.31269)
		)
		(stroke
			(width 0)
			(type solid)
		)
		(fill yes)
		(layer "In6.Cu")
		(net "M_D_CPU1_SB_CS_N<2>")
	)
	(gr_poly
		(pts
			(xy 84.563966 -231.510078) (xy 84.563966 -231.465882) (xy 84.208366 -231.465882) (xy 84.208366 -231.510078)
			(xy 84.255356 -231.662478) (xy 84.516976 -231.662478)
		)
		(stroke
			(width 0)
			(type solid)
		)
		(fill yes)
		(layer "In6.Cu")
		(net "M_D_CPU1_SB_DQS_DP<2>")
	)
	(gr_poly
		(pts
			(xy 84.570062 -236.802422) (xy 84.523072 -236.650022) (xy 84.261452 -236.650022) (xy 84.214462 -236.802422)
			(xy 84.214462 -236.846618) (xy 84.570062 -236.846618)
		)
		(stroke
			(width 0)
			(type solid)
		)
		(fill yes)
		(layer "In6.Cu")
		(net "M_C_CPU1_SB_DQS_DN<1>")
	)
	(gr_poly
		(pts
			(xy 84.572348 -243.31295) (xy 84.525358 -243.16055) (xy 84.263738 -243.16055) (xy 84.216748 -243.31295)
			(xy 84.216748 -243.3574) (xy 84.572348 -243.3574)
		)
		(stroke
			(width 0)
			(type solid)
		)
		(fill yes)
		(layer "In6.Cu")
		(net "M_C_CPU1_SB_DQ<3>")
	)
	(gr_poly
		(pts
			(xy 84.572348 -242.905026) (xy 84.572348 -242.860576) (xy 84.216748 -242.860576) (xy 84.216748 -242.905026)
			(xy 84.263738 -243.057426) (xy 84.525358 -243.057426)
		)
		(stroke
			(width 0)
			(type solid)
		)
		(fill yes)
		(layer "In6.Cu")
		(net "M_C_CPU1_SB_DQS_DP<0>")
	)
	(gr_poly
		(pts
			(xy 84.673694 -261.449058) (xy 84.626704 -261.296658) (xy 84.365084 -261.296658) (xy 84.318094 -261.449058)
			(xy 84.318094 -261.493508) (xy 84.673694 -261.493508)
		)
		(stroke
			(width 0)
			(type solid)
		)
		(fill yes)
		(layer "In6.Cu")
		(net "M_C_CPU1_SA_CB<1>")
	)
	(gr_poly
		(pts
			(xy 84.673694 -261.040626) (xy 84.673694 -260.996176) (xy 84.318094 -260.996176) (xy 84.318094 -261.040626)
			(xy 84.365084 -261.193026) (xy 84.626704 -261.193026)
		)
		(stroke
			(width 0)
			(type solid)
		)
		(fill yes)
		(layer "In6.Cu")
		(net "M_C_CPU1_SA_DQS_DN<9>")
	)
	(gr_poly
		(pts
			(xy 84.673694 -259.821426) (xy 84.626704 -259.669026) (xy 84.365084 -259.669026) (xy 84.318094 -259.821426)
			(xy 84.318094 -259.865622) (xy 84.673694 -259.865622)
		)
		(stroke
			(width 0)
			(type solid)
		)
		(fill yes)
		(layer "In6.Cu")
		(net "M_C_CPU1_SA_DQS_DN<4>")
	)
	(gr_poly
		(pts
			(xy 84.673694 -256.565654) (xy 84.626704 -256.413254) (xy 84.365084 -256.413254) (xy 84.318094 -256.565654)
			(xy 84.318094 -256.610104) (xy 84.673694 -256.610104)
		)
		(stroke
			(width 0)
			(type solid)
		)
		(fill yes)
		(layer "In6.Cu")
		(net "M_D_CPU1_SB_RSP<0>")
	)
	(gr_poly
		(pts
			(xy 84.673694 -256.157222) (xy 84.673694 -256.112772) (xy 84.318094 -256.112772) (xy 84.318094 -256.157222)
			(xy 84.365084 -256.309622) (xy 84.626704 -256.309622)
		)
		(stroke
			(width 0)
			(type solid)
		)
		(fill yes)
		(layer "In6.Cu")
		(net "M_D_CPU1_SA_RSP<1>")
	)
	(gr_poly
		(pts
			(xy 84.890356 -232.993184) (xy 84.92871 -232.971086) (xy 84.75091 -232.663238) (xy 84.712556 -232.685336)
			(xy 84.604098 -232.802176) (xy 84.734908 -233.028744)
		)
		(stroke
			(width 0)
			(type solid)
		)
		(fill yes)
		(layer "In6.Cu")
		(net "M_D_CPU1_SB_DQ<17>")
	)
	(gr_poly
		(pts
			(xy 84.890356 -223.226376) (xy 84.92871 -223.204278) (xy 84.75091 -222.89643) (xy 84.712556 -222.918528)
			(xy 84.604098 -223.035368) (xy 84.734908 -223.261936)
		)
		(stroke
			(width 0)
			(type solid)
		)
		(fill yes)
		(layer "In6.Cu")
		(net "M_C_CPU1_SB_DQ<31>")
	)
	(gr_poly
		(pts
			(xy 84.89061 -239.504728) (xy 84.928964 -239.48263) (xy 84.751164 -239.174782) (xy 84.71281 -239.19688)
			(xy 84.604352 -239.31372) (xy 84.735162 -239.540288)
		)
		(stroke
			(width 0)
			(type solid)
		)
		(fill yes)
		(layer "In6.Cu")
		(net "M_C_CPU1_SB_DQ<8>")
	)
	(gr_poly
		(pts
			(xy 85.000338 -238.88446) (xy 85.108796 -238.76762) (xy 84.977986 -238.541052) (xy 84.822538 -238.576612)
			(xy 84.784184 -238.59871) (xy 84.961984 -238.906558)
		)
		(stroke
			(width 0)
			(type solid)
		)
		(fill yes)
		(layer "In6.Cu")
		(net "M_C_CPU1_SB_DQ<10>")
	)
	(gr_poly
		(pts
			(xy 85.022944 -225.812858) (xy 85.022944 -225.768408) (xy 84.667344 -225.768408) (xy 84.667344 -225.812858)
			(xy 84.714334 -225.965258) (xy 84.975954 -225.965258)
		)
		(stroke
			(width 0)
			(type solid)
		)
		(fill yes)
		(layer "In6.Cu")
		(net "M_C_CPU1_SB_DQS_DP<3>")
	)
	(gr_poly
		(pts
			(xy 85.02523 -243.718842) (xy 85.02523 -243.674392) (xy 84.66963 -243.674392) (xy 84.66963 -243.718842)
			(xy 84.71662 -243.871242) (xy 84.97824 -243.871242)
		)
		(stroke
			(width 0)
			(type solid)
		)
		(fill yes)
		(layer "In6.Cu")
		(net "M_C_CPU1_SB_DQ<1>")
	)
	(gr_poly
		(pts
			(xy 85.02523 -242.499134) (xy 84.97824 -242.346734) (xy 84.71662 -242.346734) (xy 84.66963 -242.499134)
			(xy 84.66963 -242.54333) (xy 85.02523 -242.54333)
		)
		(stroke
			(width 0)
			(type solid)
		)
		(fill yes)
		(layer "In6.Cu")
		(net "M_C_CPU1_SB_DQS_DN<0>")
	)
	(gr_poly
		(pts
			(xy 85.02523 -237.207806) (xy 85.02523 -237.163356) (xy 84.66963 -237.163356) (xy 84.66963 -237.207806)
			(xy 84.71662 -237.360206) (xy 84.97824 -237.360206)
		)
		(stroke
			(width 0)
			(type solid)
		)
		(fill yes)
		(layer "In6.Cu")
		(net "M_C_CPU1_SB_DQS_DP<1>")
	)
	(gr_poly
		(pts
			(xy 85.025484 -237.61573) (xy 84.978494 -237.46333) (xy 84.716874 -237.46333) (xy 84.669884 -237.61573)
			(xy 84.669884 -237.66018) (xy 85.025484 -237.66018)
		)
		(stroke
			(width 0)
			(type solid)
		)
		(fill yes)
		(layer "In6.Cu")
		(net "M_C_CPU1_SB_DQ<11>")
	)
	(gr_poly
		(pts
			(xy 85.025992 -229.477062) (xy 84.979002 -229.324662) (xy 84.717382 -229.324662) (xy 84.670392 -229.477062)
			(xy 84.670392 -229.521512) (xy 85.025992 -229.521512)
		)
		(stroke
			(width 0)
			(type solid)
		)
		(fill yes)
		(layer "In6.Cu")
		(net "M_D_CPU1_SB_DQ<22>")
	)
	(gr_poly
		(pts
			(xy 85.026246 -240.46307) (xy 85.026246 -240.418874) (xy 84.670646 -240.418874) (xy 84.670646 -240.46307)
			(xy 84.717636 -240.61547) (xy 84.979256 -240.61547)
		)
		(stroke
			(width 0)
			(type solid)
		)
		(fill yes)
		(layer "In6.Cu")
		(net "M_C_CPU1_SB_DQ<5>")
	)
	(gr_poly
		(pts
			(xy 85.02777 -230.69677) (xy 85.02777 -230.65232) (xy 84.67217 -230.65232) (xy 84.67217 -230.69677)
			(xy 84.71916 -230.84917) (xy 84.98078 -230.84917)
		)
		(stroke
			(width 0)
			(type solid)
		)
		(fill yes)
		(layer "In6.Cu")
		(net "M_D_CPU1_SB_DQS_DN<7>")
	)
	(gr_poly
		(pts
			(xy 85.028024 -233.952542) (xy 85.028024 -233.908092) (xy 84.672424 -233.908092) (xy 84.672424 -233.952542)
			(xy 84.719414 -234.104942) (xy 84.981034 -234.104942)
		)
		(stroke
			(width 0)
			(type solid)
		)
		(fill yes)
		(layer "In6.Cu")
		(net "M_D_CPU1_SB_DQ<16>")
	)
	(gr_poly
		(pts
			(xy 85.033612 -244.127274) (xy 84.986622 -243.974874) (xy 84.725002 -243.974874) (xy 84.678012 -244.127274)
			(xy 84.678012 -244.17147) (xy 85.033612 -244.17147)
		)
		(stroke
			(width 0)
			(type solid)
		)
		(fill yes)
		(layer "In6.Cu")
		(net "M_C_CPU1_SB_DQ<2>")
	)
	(gr_poly
		(pts
			(xy 85.033866 -247.382538) (xy 84.986876 -247.230138) (xy 84.725256 -247.230138) (xy 84.678266 -247.382538)
			(xy 84.678266 -247.426988) (xy 85.033866 -247.426988)
		)
		(stroke
			(width 0)
			(type solid)
		)
		(fill yes)
		(layer "In6.Cu")
		(net "M_A_CPU1_SB_RSP<1>")
	)
	(gr_poly
		(pts
			(xy 85.033866 -245.754906) (xy 84.986876 -245.602506) (xy 84.725256 -245.602506) (xy 84.678266 -245.754906)
			(xy 84.678266 -245.799356) (xy 85.033866 -245.799356)
		)
		(stroke
			(width 0)
			(type solid)
		)
		(fill yes)
		(layer "In6.Cu")
		(net "M_D_CPU1_SB_CS_N<3>")
	)
	(gr_poly
		(pts
			(xy 85.033866 -235.988098) (xy 84.986876 -235.835698) (xy 84.725256 -235.835698) (xy 84.678266 -235.988098)
			(xy 84.678266 -236.032548) (xy 85.033866 -236.032548)
		)
		(stroke
			(width 0)
			(type solid)
		)
		(fill yes)
		(layer "In6.Cu")
		(net "M_C_CPU1_SB_DQS_DP<6>")
	)
	(gr_poly
		(pts
			(xy 85.033866 -231.104694) (xy 84.986876 -230.952294) (xy 84.725256 -230.952294) (xy 84.678266 -231.104694)
			(xy 84.678266 -231.149144) (xy 85.033866 -231.149144)
		)
		(stroke
			(width 0)
			(type solid)
		)
		(fill yes)
		(layer "In6.Cu")
		(net "M_D_CPU1_SB_DQS_DN<2>")
	)
	(gr_poly
		(pts
			(xy 85.033866 -229.06863) (xy 85.033866 -229.024434) (xy 84.678266 -229.024434) (xy 84.678266 -229.06863)
			(xy 84.725256 -229.22103) (xy 84.986876 -229.22103)
		)
		(stroke
			(width 0)
			(type solid)
		)
		(fill yes)
		(layer "In6.Cu")
		(net "M_D_CPU1_SB_DQ<21>")
	)
	(gr_poly
		(pts
			(xy 85.037168 -234.360466) (xy 84.990178 -234.208066) (xy 84.728558 -234.208066) (xy 84.681568 -234.360466)
			(xy 84.681568 -234.404916) (xy 85.037168 -234.404916)
		)
		(stroke
			(width 0)
			(type solid)
		)
		(fill yes)
		(layer "In6.Cu")
		(net "M_C_CPU1_SB_DQ<15>")
	)
	(gr_poly
		(pts
			(xy 85.037676 -264.873486) (xy 84.999322 -264.851388) (xy 84.843874 -264.815828) (xy 84.713064 -265.042396)
			(xy 84.821522 -265.159236) (xy 84.859876 -265.181334)
		)
		(stroke
			(width 0)
			(type solid)
		)
		(fill yes)
		(layer "In6.Cu")
		(net "M_C_CPU1_SA_DQS_DP<8>")
	)
	(gr_poly
		(pts
			(xy 85.039708 -235.580174) (xy 85.039708 -235.535724) (xy 84.684108 -235.535724) (xy 84.684108 -235.580174)
			(xy 84.731098 -235.732574) (xy 84.992718 -235.732574)
		)
		(stroke
			(width 0)
			(type solid)
		)
		(fill yes)
		(layer "In6.Cu")
		(net "M_C_CPU1_SB_DQ<12>")
	)
	(gr_poly
		(pts
			(xy 85.039708 -227.44049) (xy 85.039708 -227.396294) (xy 84.684108 -227.396294) (xy 84.684108 -227.44049)
			(xy 84.731098 -227.59289) (xy 84.992718 -227.59289)
		)
		(stroke
			(width 0)
			(type solid)
		)
		(fill yes)
		(layer "In6.Cu")
		(net "M_C_CPU1_SB_DQ<26>")
	)
	(gr_poly
		(pts
			(xy 85.039962 -224.185226) (xy 85.039962 -224.140776) (xy 84.684362 -224.140776) (xy 84.684362 -224.185226)
			(xy 84.731352 -224.337626) (xy 84.992972 -224.337626)
		)
		(stroke
			(width 0)
			(type solid)
		)
		(fill yes)
		(layer "In6.Cu")
		(net "M_C_CPU1_SB_DQ<28>")
	)
	(gr_poly
		(pts
			(xy 85.042248 -245.346474) (xy 85.042248 -245.302278) (xy 84.686648 -245.302278) (xy 84.686648 -245.346474)
			(xy 84.733638 -245.498874) (xy 84.995258 -245.498874)
		)
		(stroke
			(width 0)
			(type solid)
		)
		(fill yes)
		(layer "In6.Cu")
		(net "M_D_CPU1_SB_CS_N<0>")
	)
	(gr_poly
		(pts
			(xy 85.143594 -263.891014) (xy 85.096604 -263.738614) (xy 84.834984 -263.738614) (xy 84.787994 -263.891014)
			(xy 84.787994 -263.93521) (xy 85.143594 -263.93521)
		)
		(stroke
			(width 0)
			(type solid)
		)
		(fill yes)
		(layer "In6.Cu")
		(net "M_C_CPU1_SA_DQ<30>")
	)
	(gr_poly
		(pts
			(xy 85.143594 -263.482074) (xy 85.143594 -263.437878) (xy 84.787994 -263.437878) (xy 84.787994 -263.482074)
			(xy 84.834984 -263.634474) (xy 85.096604 -263.634474)
		)
		(stroke
			(width 0)
			(type solid)
		)
		(fill yes)
		(layer "In6.Cu")
		(net "M_C_CPU1_SA_DQ<29>")
	)
	(gr_poly
		(pts
			(xy 85.143594 -262.262874) (xy 85.096604 -262.110474) (xy 84.834984 -262.110474) (xy 84.787994 -262.262874)
			(xy 84.787994 -262.307324) (xy 85.143594 -262.307324)
		)
		(stroke
			(width 0)
			(type solid)
		)
		(fill yes)
		(layer "In6.Cu")
		(net "M_C_CPU1_SA_CB<0>")
	)
	(gr_poly
		(pts
			(xy 85.143594 -261.854442) (xy 85.143594 -261.809992) (xy 84.787994 -261.809992) (xy 84.787994 -261.854442)
			(xy 84.834984 -262.006842) (xy 85.096604 -262.006842)
		)
		(stroke
			(width 0)
			(type solid)
		)
		(fill yes)
		(layer "In6.Cu")
		(net "M_C_CPU1_SA_CB<3>")
	)
	(gr_poly
		(pts
			(xy 85.143594 -260.635242) (xy 85.096604 -260.482842) (xy 84.834984 -260.482842) (xy 84.787994 -260.635242)
			(xy 84.787994 -260.679438) (xy 85.143594 -260.679438)
		)
		(stroke
			(width 0)
			(type solid)
		)
		(fill yes)
		(layer "In6.Cu")
		(net "M_C_CPU1_SA_DQS_DP<9>")
	)
	(gr_poly
		(pts
			(xy 85.143594 -260.226302) (xy 85.143594 -260.182106) (xy 84.787994 -260.182106) (xy 84.787994 -260.226302)
			(xy 84.834984 -260.378702) (xy 85.096604 -260.378702)
		)
		(stroke
			(width 0)
			(type solid)
		)
		(fill yes)
		(layer "In6.Cu")
		(net "M_C_CPU1_SA_DQS_DP<4>")
	)
	(gr_poly
		(pts
			(xy 85.143594 -259.00761) (xy 85.096604 -258.85521) (xy 84.834984 -258.85521) (xy 84.787994 -259.00761)
			(xy 84.787994 -259.051806) (xy 85.143594 -259.051806)
		)
		(stroke
			(width 0)
			(type solid)
		)
		(fill yes)
		(layer "In6.Cu")
		(net "M_C_CPU1_SA_CB<4>")
	)
	(gr_poly
		(pts
			(xy 85.143594 -258.59867) (xy 85.143594 -258.554474) (xy 84.787994 -258.554474) (xy 84.787994 -258.59867)
			(xy 84.834984 -258.75107) (xy 85.096604 -258.75107)
		)
		(stroke
			(width 0)
			(type solid)
		)
		(fill yes)
		(layer "In6.Cu")
		(net "M_C_CPU1_SA_CB<7>")
	)
	(gr_poly
		(pts
			(xy 85.143594 -256.971038) (xy 85.143594 -256.926588) (xy 84.787994 -256.926588) (xy 84.787994 -256.971038)
			(xy 84.834984 -257.123438) (xy 85.096604 -257.123438)
		)
		(stroke
			(width 0)
			(type solid)
		)
		(fill yes)
		(layer "In6.Cu")
		(net "M_D_CPU1_SA_RSP<0>")
	)
	(gr_poly
		(pts
			(xy 85.143594 -255.751838) (xy 85.096604 -255.599438) (xy 84.834984 -255.599438) (xy 84.787994 -255.751838)
			(xy 84.787994 -255.796288) (xy 85.143594 -255.796288)
		)
		(stroke
			(width 0)
			(type solid)
		)
		(fill yes)
		(layer "In6.Cu")
		(net "M_D_CPU1_SB_RSP<1>")
	)
	(gr_poly
		(pts
			(xy 85.216492 -267.217652) (xy 85.108034 -267.100812) (xy 85.06968 -267.078714) (xy 84.89188 -267.386562)
			(xy 84.930234 -267.40866) (xy 85.085682 -267.44422)
		)
		(stroke
			(width 0)
			(type solid)
		)
		(fill yes)
		(layer "In6.Cu")
		(net "M_C_CPU1_SA_DQ<25>")
	)
	(gr_poly
		(pts
			(xy 85.36051 -232.179876) (xy 85.398864 -232.157778) (xy 85.221064 -231.84993) (xy 85.18271 -231.872028)
			(xy 85.074252 -231.988868) (xy 85.205062 -232.215436)
		)
		(stroke
			(width 0)
			(type solid)
		)
		(fill yes)
		(layer "In6.Cu")
		(net "M_D_CPU1_SB_DQS_DP<2>")
	)
	(gr_poly
		(pts
			(xy 85.468206 -231.555544) (xy 85.576664 -231.438704) (xy 85.445854 -231.212136) (xy 85.290406 -231.247696)
			(xy 85.252052 -231.269794) (xy 85.429852 -231.577642)
		)
		(stroke
			(width 0)
			(type solid)
		)
		(fill yes)
		(layer "In6.Cu")
		(net "M_D_CPU1_SB_DQS_DN<2>")
	)
	(gr_poly
		(pts
			(xy 85.47481 -238.077756) (xy 85.583268 -237.960916) (xy 85.452458 -237.734348) (xy 85.29701 -237.769908)
			(xy 85.258656 -237.792006) (xy 85.436456 -238.099854)
		)
		(stroke
			(width 0)
			(type solid)
		)
		(fill yes)
		(layer "In6.Cu")
		(net "M_C_CPU1_SB_DQ<11>")
	)
	(gr_poly
		(pts
			(xy 85.489542 -241.685318) (xy 85.442552 -241.532918) (xy 85.180932 -241.532918) (xy 85.133942 -241.685318)
			(xy 85.133942 -241.729514) (xy 85.489542 -241.729514)
		)
		(stroke
			(width 0)
			(type solid)
		)
		(fill yes)
		(layer "In6.Cu")
		(net "M_C_CPU1_SB_DQS_DP<5>")
	)
	(gr_poly
		(pts
			(xy 85.49513 -244.940582) (xy 85.44814 -244.788182) (xy 85.18652 -244.788182) (xy 85.13953 -244.940582)
			(xy 85.13953 -244.985032) (xy 85.49513 -244.985032)
		)
		(stroke
			(width 0)
			(type solid)
		)
		(fill yes)
		(layer "In6.Cu")
		(net "M_D_CPU1_SB_CS_N<1>")
	)
	(gr_poly
		(pts
			(xy 85.49513 -241.276886) (xy 85.49513 -241.23269) (xy 85.13953 -241.23269) (xy 85.13953 -241.276886)
			(xy 85.18652 -241.429286) (xy 85.44814 -241.429286)
		)
		(stroke
			(width 0)
			(type solid)
		)
		(fill yes)
		(layer "In6.Cu")
		(net "M_C_CPU1_SB_DQ<4>")
	)
	(gr_poly
		(pts
			(xy 85.49513 -239.649254) (xy 85.49513 -239.604804) (xy 85.13953 -239.604804) (xy 85.13953 -239.649254)
			(xy 85.18652 -239.801654) (xy 85.44814 -239.801654)
		)
		(stroke
			(width 0)
			(type solid)
		)
		(fill yes)
		(layer "In6.Cu")
		(net "M_C_CPU1_SB_DQ<8>")
	)
	(gr_poly
		(pts
			(xy 85.495384 -236.39399) (xy 85.495384 -236.34954) (xy 85.139784 -236.34954) (xy 85.139784 -236.39399)
			(xy 85.186774 -236.54639) (xy 85.448394 -236.54639)
		)
		(stroke
			(width 0)
			(type solid)
		)
		(fill yes)
		(layer "In6.Cu")
		(net "M_C_CPU1_SB_DQS_DN<6>")
	)
	(gr_poly
		(pts
			(xy 85.497924 -235.174282) (xy 85.450934 -235.021882) (xy 85.189314 -235.021882) (xy 85.142324 -235.174282)
			(xy 85.142324 -235.218732) (xy 85.497924 -235.218732)
		)
		(stroke
			(width 0)
			(type solid)
		)
		(fill yes)
		(layer "In6.Cu")
		(net "M_C_CPU1_SB_DQ<14>")
	)
	(gr_poly
		(pts
			(xy 85.497924 -234.766358) (xy 85.497924 -234.721908) (xy 85.142324 -234.721908) (xy 85.142324 -234.766358)
			(xy 85.189314 -234.918758) (xy 85.450934 -234.918758)
		)
		(stroke
			(width 0)
			(type solid)
		)
		(fill yes)
		(layer "In6.Cu")
		(net "M_C_CPU1_SB_DQ<13>")
	)
	(gr_poly
		(pts
			(xy 85.503512 -244.53215) (xy 85.503512 -244.487954) (xy 85.147912 -244.487954) (xy 85.147912 -244.53215)
			(xy 85.194902 -244.68455) (xy 85.456522 -244.68455)
		)
		(stroke
			(width 0)
			(type solid)
		)
		(fill yes)
		(layer "In6.Cu")
		(net "M_C_CPU1_SB_DQ<0>")
	)
	(gr_poly
		(pts
			(xy 85.503766 -247.787922) (xy 85.503766 -247.743472) (xy 85.148166 -247.743472) (xy 85.148166 -247.787922)
			(xy 85.195156 -247.940322) (xy 85.456776 -247.940322)
		)
		(stroke
			(width 0)
			(type solid)
		)
		(fill yes)
		(layer "In6.Cu")
		(net "M_A_CPU1_SA_RSP<1>")
	)
	(gr_poly
		(pts
			(xy 85.503766 -246.16029) (xy 85.503766 -246.11584) (xy 85.148166 -246.11584) (xy 85.148166 -246.16029)
			(xy 85.195156 -246.31269) (xy 85.456776 -246.31269)
		)
		(stroke
			(width 0)
			(type solid)
		)
		(fill yes)
		(layer "In6.Cu")
		(net "M_D_CPU1_SB_CS_N<2>")
	)
	(gr_poly
		(pts
			(xy 85.503766 -230.291386) (xy 85.456776 -230.138986) (xy 85.195156 -230.138986) (xy 85.148166 -230.291386)
			(xy 85.148166 -230.335582) (xy 85.503766 -230.335582)
		)
		(stroke
			(width 0)
			(type solid)
		)
		(fill yes)
		(layer "In6.Cu")
		(net "M_D_CPU1_SB_DQS_DP<7>")
	)
	(gr_poly
		(pts
			(xy 85.503766 -229.882446) (xy 85.503766 -229.83825) (xy 85.148166 -229.83825) (xy 85.148166 -229.882446)
			(xy 85.195156 -230.034846) (xy 85.456776 -230.034846)
		)
		(stroke
			(width 0)
			(type solid)
		)
		(fill yes)
		(layer "In6.Cu")
		(net "M_D_CPU1_SB_DQ<20>")
	)
	(gr_poly
		(pts
			(xy 85.503766 -228.663754) (xy 85.456776 -228.511354) (xy 85.195156 -228.511354) (xy 85.148166 -228.663754)
			(xy 85.148166 -228.70795) (xy 85.503766 -228.70795)
		)
		(stroke
			(width 0)
			(type solid)
		)
		(fill yes)
		(layer "In6.Cu")
		(net "M_D_CPU1_SB_DQ<23>")
	)
	(gr_poly
		(pts
			(xy 85.508338 -240.057178) (xy 85.461348 -239.904778) (xy 85.199728 -239.904778) (xy 85.152738 -240.057178)
			(xy 85.152738 -240.101628) (xy 85.508338 -240.101628)
		)
		(stroke
			(width 0)
			(type solid)
		)
		(fill yes)
		(layer "In6.Cu")
		(net "M_C_CPU1_SB_DQ<7>")
	)
	(gr_poly
		(pts
			(xy 85.5091 -233.54665) (xy 85.46211 -233.39425) (xy 85.20049 -233.39425) (xy 85.1535 -233.54665)
			(xy 85.1535 -233.5911) (xy 85.5091 -233.5911)
		)
		(stroke
			(width 0)
			(type solid)
		)
		(fill yes)
		(layer "In6.Cu")
		(net "M_D_CPU1_SB_DQ<18>")
	)
	(gr_poly
		(pts
			(xy 85.509608 -267.311124) (xy 85.471254 -267.289026) (xy 85.315806 -267.253466) (xy 85.184996 -267.480034)
			(xy 85.293454 -267.596874) (xy 85.331808 -267.618972)
		)
		(stroke
			(width 0)
			(type solid)
		)
		(fill yes)
		(layer "In6.Cu")
		(net "M_C_CPU1_SA_DQ<26>")
	)
	(gr_poly
		(pts
			(xy 85.509608 -233.138218) (xy 85.509608 -233.093768) (xy 85.154008 -233.093768) (xy 85.154008 -233.138218)
			(xy 85.200998 -233.290618) (xy 85.462618 -233.290618)
		)
		(stroke
			(width 0)
			(type solid)
		)
		(fill yes)
		(layer "In6.Cu")
		(net "M_D_CPU1_SB_DQ<17>")
	)
	(gr_poly
		(pts
			(xy 85.509608 -227.035106) (xy 85.462618 -226.882706) (xy 85.200998 -226.882706) (xy 85.154008 -227.035106)
			(xy 85.154008 -227.079556) (xy 85.509608 -227.079556)
		)
		(stroke
			(width 0)
			(type solid)
		)
		(fill yes)
		(layer "In6.Cu")
		(net "M_C_CPU1_SB_DQ<24>")
	)
	(gr_poly
		(pts
			(xy 85.509608 -226.627182) (xy 85.509608 -226.582732) (xy 85.154008 -226.582732) (xy 85.154008 -226.627182)
			(xy 85.200998 -226.779582) (xy 85.462618 -226.779582)
		)
		(stroke
			(width 0)
			(type solid)
		)
		(fill yes)
		(layer "In6.Cu")
		(net "M_C_CPU1_SB_DQ<25>")
	)
	(gr_poly
		(pts
			(xy 85.512148 -243.31295) (xy 85.465158 -243.16055) (xy 85.203538 -243.16055) (xy 85.156548 -243.31295)
			(xy 85.156548 -243.3574) (xy 85.512148 -243.3574)
		)
		(stroke
			(width 0)
			(type solid)
		)
		(fill yes)
		(layer "In6.Cu")
		(net "M_C_CPU1_SB_DQ<3>")
	)
	(gr_poly
		(pts
			(xy 85.512148 -242.905026) (xy 85.512148 -242.860576) (xy 85.156548 -242.860576) (xy 85.156548 -242.905026)
			(xy 85.203538 -243.057426) (xy 85.465158 -243.057426)
		)
		(stroke
			(width 0)
			(type solid)
		)
		(fill yes)
		(layer "In6.Cu")
		(net "M_C_CPU1_SB_DQS_DP<0>")
	)
	(gr_poly
		(pts
			(xy 85.512148 -236.801914) (xy 85.465158 -236.649514) (xy 85.203538 -236.649514) (xy 85.156548 -236.801914)
			(xy 85.156548 -236.846364) (xy 85.512148 -236.846364)
		)
		(stroke
			(width 0)
			(type solid)
		)
		(fill yes)
		(layer "In6.Cu")
		(net "M_C_CPU1_SB_DQS_DN<1>")
	)
	(gr_poly
		(pts
			(xy 85.512148 -225.407474) (xy 85.465158 -225.255074) (xy 85.203538 -225.255074) (xy 85.156548 -225.407474)
			(xy 85.156548 -225.45167) (xy 85.512148 -225.45167)
		)
		(stroke
			(width 0)
			(type solid)
		)
		(fill yes)
		(layer "In6.Cu")
		(net "M_C_CPU1_SB_DQS_DN<3>")
	)
	(gr_poly
		(pts
			(xy 85.512148 -224.999042) (xy 85.512148 -224.954846) (xy 85.156548 -224.954846) (xy 85.156548 -224.999042)
			(xy 85.203538 -225.151442) (xy 85.465158 -225.151442)
		)
		(stroke
			(width 0)
			(type solid)
		)
		(fill yes)
		(layer "In6.Cu")
		(net "M_C_CPU1_SB_DQS_DN<8>")
	)
	(gr_poly
		(pts
			(xy 85.512148 -223.779842) (xy 85.465158 -223.627442) (xy 85.203538 -223.627442) (xy 85.156548 -223.779842)
			(xy 85.156548 -223.824038) (xy 85.512148 -223.824038)
		)
		(stroke
			(width 0)
			(type solid)
		)
		(fill yes)
		(layer "In6.Cu")
		(net "M_C_CPU1_SB_DQ<30>")
	)
	(gr_poly
		(pts
			(xy 85.512148 -223.37141) (xy 85.512148 -223.327214) (xy 85.156548 -223.327214) (xy 85.156548 -223.37141)
			(xy 85.203538 -223.52381) (xy 85.465158 -223.52381)
		)
		(stroke
			(width 0)
			(type solid)
		)
		(fill yes)
		(layer "In6.Cu")
		(net "M_C_CPU1_SB_DQ<31>")
	)
	(gr_poly
		(pts
			(xy 85.607652 -272.843498) (xy 85.560662 -272.691098) (xy 85.299042 -272.691098) (xy 85.252052 -272.843498)
			(xy 85.252052 -272.887948) (xy 85.607652 -272.887948)
		)
		(stroke
			(width 0)
			(type solid)
		)
		(fill yes)
		(layer "In6.Cu")
		(net "M_C_CPU1_SA_DQ<11>")
	)
	(gr_poly
		(pts
			(xy 85.613494 -264.70483) (xy 85.566504 -264.55243) (xy 85.304884 -264.55243) (xy 85.257894 -264.70483)
			(xy 85.257894 -264.749026) (xy 85.613494 -264.749026)
		)
		(stroke
			(width 0)
			(type solid)
		)
		(fill yes)
		(layer "In6.Cu")
		(net "M_C_CPU1_SA_DQS_DP<8>")
	)
	(gr_poly
		(pts
			(xy 85.613494 -264.29589) (xy 85.613494 -264.251694) (xy 85.257894 -264.251694) (xy 85.257894 -264.29589)
			(xy 85.304884 -264.44829) (xy 85.566504 -264.44829)
		)
		(stroke
			(width 0)
			(type solid)
		)
		(fill yes)
		(layer "In6.Cu")
		(net "M_C_CPU1_SA_DQ<28>")
	)
	(gr_poly
		(pts
			(xy 85.613494 -263.07669) (xy 85.566504 -262.92429) (xy 85.304884 -262.92429) (xy 85.257894 -263.07669)
			(xy 85.257894 -263.12114) (xy 85.613494 -263.12114)
		)
		(stroke
			(width 0)
			(type solid)
		)
		(fill yes)
		(layer "In6.Cu")
		(net "M_C_CPU1_SA_DQ<31>")
	)
	(gr_poly
		(pts
			(xy 85.613494 -262.668258) (xy 85.613494 -262.623808) (xy 85.257894 -262.623808) (xy 85.257894 -262.668258)
			(xy 85.304884 -262.820658) (xy 85.566504 -262.820658)
		)
		(stroke
			(width 0)
			(type solid)
		)
		(fill yes)
		(layer "In6.Cu")
		(net "M_C_CPU1_SA_CB<2>")
	)
	(gr_poly
		(pts
			(xy 85.613494 -261.449058) (xy 85.566504 -261.296658) (xy 85.304884 -261.296658) (xy 85.257894 -261.449058)
			(xy 85.257894 -261.493508) (xy 85.613494 -261.493508)
		)
		(stroke
			(width 0)
			(type solid)
		)
		(fill yes)
		(layer "In6.Cu")
		(net "M_C_CPU1_SA_CB<1>")
	)
	(gr_poly
		(pts
			(xy 85.613494 -261.040626) (xy 85.613494 -260.996176) (xy 85.257894 -260.996176) (xy 85.257894 -261.040626)
			(xy 85.304884 -261.193026) (xy 85.566504 -261.193026)
		)
		(stroke
			(width 0)
			(type solid)
		)
		(fill yes)
		(layer "In6.Cu")
		(net "M_C_CPU1_SA_DQS_DN<9>")
	)
	(gr_poly
		(pts
			(xy 85.613494 -259.821426) (xy 85.566504 -259.669026) (xy 85.304884 -259.669026) (xy 85.257894 -259.821426)
			(xy 85.257894 -259.865622) (xy 85.613494 -259.865622)
		)
		(stroke
			(width 0)
			(type solid)
		)
		(fill yes)
		(layer "In6.Cu")
		(net "M_C_CPU1_SA_DQS_DN<4>")
	)
	(gr_poly
		(pts
			(xy 85.613494 -259.412486) (xy 85.613494 -259.36829) (xy 85.257894 -259.36829) (xy 85.257894 -259.412486)
			(xy 85.304884 -259.564886) (xy 85.566504 -259.564886)
		)
		(stroke
			(width 0)
			(type solid)
		)
		(fill yes)
		(layer "In6.Cu")
		(net "M_C_CPU1_SA_CB<6>")
	)
	(gr_poly
		(pts
			(xy 85.613494 -258.193286) (xy 85.566504 -258.040886) (xy 85.304884 -258.040886) (xy 85.257894 -258.193286)
			(xy 85.257894 -258.237736) (xy 85.613494 -258.237736)
		)
		(stroke
			(width 0)
			(type solid)
		)
		(fill yes)
		(layer "In6.Cu")
		(net "M_C_CPU1_SA_CB<5>")
	)
	(gr_poly
		(pts
			(xy 85.613494 -256.565654) (xy 85.566504 -256.413254) (xy 85.304884 -256.413254) (xy 85.257894 -256.565654)
			(xy 85.257894 -256.610104) (xy 85.613494 -256.610104)
		)
		(stroke
			(width 0)
			(type solid)
		)
		(fill yes)
		(layer "In6.Cu")
		(net "M_D_CPU1_SB_RSP<0>")
	)
	(gr_poly
		(pts
			(xy 85.613494 -256.157222) (xy 85.613494 -256.112772) (xy 85.257894 -256.112772) (xy 85.257894 -256.157222)
			(xy 85.304884 -256.309622) (xy 85.566504 -256.309622)
		)
		(stroke
			(width 0)
			(type solid)
		)
		(fill yes)
		(layer "In6.Cu")
		(net "M_D_CPU1_SA_RSP<1>")
	)
	(gr_poly
		(pts
			(xy 85.688424 -271.283176) (xy 85.579966 -271.166336) (xy 85.541612 -271.144238) (xy 85.363812 -271.452086)
			(xy 85.402166 -271.474184) (xy 85.557614 -271.509744)
		)
		(stroke
			(width 0)
			(type solid)
		)
		(fill yes)
		(layer "In6.Cu")
		(net "M_C_CPU1_SA_DQS_DN<6>")
	)
	(gr_poly
		(pts
			(xy 85.688424 -268.027658) (xy 85.579966 -267.910818) (xy 85.541612 -267.88872) (xy 85.363812 -268.196568)
			(xy 85.402166 -268.218666) (xy 85.557614 -268.254226)
		)
		(stroke
			(width 0)
			(type solid)
		)
		(fill yes)
		(layer "In6.Cu")
		(net "M_C_CPU1_SA_DQ<24>")
	)
	(gr_poly
		(pts
			(xy 85.822028 -237.862364) (xy 85.860382 -237.840266) (xy 85.682582 -237.532418) (xy 85.644228 -237.554516)
			(xy 85.53577 -237.671356) (xy 85.66658 -237.897924)
		)
		(stroke
			(width 0)
			(type solid)
		)
		(fill yes)
		(layer "In6.Cu")
		(net "M_C_CPU1_SB_DQS_DP<1>")
	)
	(gr_poly
		(pts
			(xy 85.829394 -231.36352) (xy 85.867748 -231.341422) (xy 85.689948 -231.033574) (xy 85.651594 -231.055672)
			(xy 85.543136 -231.172512) (xy 85.673946 -231.39908)
		)
		(stroke
			(width 0)
			(type solid)
		)
		(fill yes)
		(layer "In6.Cu")
		(net "M_D_CPU1_SB_DQS_DN<7>")
	)
	(gr_poly
		(pts
			(xy 85.940138 -230.745792) (xy 86.048596 -230.628952) (xy 85.917786 -230.402384) (xy 85.762338 -230.437944)
			(xy 85.723984 -230.460042) (xy 85.901784 -230.76789)
		)
		(stroke
			(width 0)
			(type solid)
		)
		(fill yes)
		(layer "In6.Cu")
		(net "M_D_CPU1_SB_DQS_DP<7>")
	)
	(gr_poly
		(pts
			(xy 85.94725 -237.26902) (xy 86.055708 -237.15218) (xy 85.924898 -236.925612) (xy 85.76945 -236.961172)
			(xy 85.731096 -236.98327) (xy 85.908896 -237.291118)
		)
		(stroke
			(width 0)
			(type solid)
		)
		(fill yes)
		(layer "In6.Cu")
		(net "M_C_CPU1_SB_DQS_DN<1>")
	)
	(gr_poly
		(pts
			(xy 85.96503 -243.718842) (xy 85.96503 -243.674392) (xy 85.60943 -243.674392) (xy 85.60943 -243.718842)
			(xy 85.65642 -243.871242) (xy 85.91804 -243.871242)
		)
		(stroke
			(width 0)
			(type solid)
		)
		(fill yes)
		(layer "In6.Cu")
		(net "M_C_CPU1_SB_DQ<1>")
	)
	(gr_poly
		(pts
			(xy 85.965284 -238.835438) (xy 85.965284 -238.790988) (xy 85.609684 -238.790988) (xy 85.609684 -238.835438)
			(xy 85.656674 -238.987838) (xy 85.918294 -238.987838)
		)
		(stroke
			(width 0)
			(type solid)
		)
		(fill yes)
		(layer "In6.Cu")
		(net "M_C_CPU1_SB_DQ<9>")
	)
	(gr_poly
		(pts
			(xy 85.9663 -240.46307) (xy 85.9663 -240.418874) (xy 85.6107 -240.418874) (xy 85.6107 -240.46307)
			(xy 85.65769 -240.61547) (xy 85.91931 -240.61547)
		)
		(stroke
			(width 0)
			(type solid)
		)
		(fill yes)
		(layer "In6.Cu")
		(net "M_C_CPU1_SB_DQ<5>")
	)
	(gr_poly
		(pts
			(xy 85.96757 -242.499134) (xy 85.92058 -242.346734) (xy 85.65896 -242.346734) (xy 85.61197 -242.499134)
			(xy 85.61197 -242.54333) (xy 85.96757 -242.54333)
		)
		(stroke
			(width 0)
			(type solid)
		)
		(fill yes)
		(layer "In6.Cu")
		(net "M_C_CPU1_SB_DQS_DN<0>")
	)
	(gr_poly
		(pts
			(xy 85.96757 -232.324402) (xy 85.96757 -232.279952) (xy 85.61197 -232.279952) (xy 85.61197 -232.324402)
			(xy 85.65896 -232.476802) (xy 85.92058 -232.476802)
		)
		(stroke
			(width 0)
			(type solid)
		)
		(fill yes)
		(layer "In6.Cu")
		(net "M_D_CPU1_SB_DQS_DP<2>")
	)
	(gr_poly
		(pts
			(xy 85.96757 -227.440998) (xy 85.96757 -227.396548) (xy 85.61197 -227.396548) (xy 85.61197 -227.440998)
			(xy 85.65896 -227.593398) (xy 85.92058 -227.593398)
		)
		(stroke
			(width 0)
			(type solid)
		)
		(fill yes)
		(layer "In6.Cu")
		(net "M_C_CPU1_SB_DQ<26>")
	)
	(gr_poly
		(pts
			(xy 85.96757 -226.22129) (xy 85.92058 -226.06889) (xy 85.65896 -226.06889) (xy 85.61197 -226.22129)
			(xy 85.61197 -226.26574) (xy 85.96757 -226.26574)
		)
		(stroke
			(width 0)
			(type solid)
		)
		(fill yes)
		(layer "In6.Cu")
		(net "M_C_CPU1_SB_DQ<27>")
	)
	(gr_poly
		(pts
			(xy 85.96757 -225.813366) (xy 85.96757 -225.768916) (xy 85.61197 -225.768916) (xy 85.61197 -225.813366)
			(xy 85.65896 -225.965766) (xy 85.92058 -225.965766)
		)
		(stroke
			(width 0)
			(type solid)
		)
		(fill yes)
		(layer "In6.Cu")
		(net "M_C_CPU1_SB_DQS_DP<3>")
	)
	(gr_poly
		(pts
			(xy 85.96757 -224.593658) (xy 85.92058 -224.441258) (xy 85.65896 -224.441258) (xy 85.61197 -224.593658)
			(xy 85.61197 -224.637854) (xy 85.96757 -224.637854)
		)
		(stroke
			(width 0)
			(type solid)
		)
		(fill yes)
		(layer "In6.Cu")
		(net "M_C_CPU1_SB_DQS_DP<8>")
	)
	(gr_poly
		(pts
			(xy 85.96757 -224.185226) (xy 85.96757 -224.14103) (xy 85.61197 -224.14103) (xy 85.61197 -224.185226)
			(xy 85.65896 -224.337626) (xy 85.92058 -224.337626)
		)
		(stroke
			(width 0)
			(type solid)
		)
		(fill yes)
		(layer "In6.Cu")
		(net "M_C_CPU1_SB_DQ<28>")
	)
	(gr_poly
		(pts
			(xy 85.96757 -222.965518) (xy 85.92058 -222.813118) (xy 85.65896 -222.813118) (xy 85.61197 -222.965518)
			(xy 85.61197 -223.009968) (xy 85.96757 -223.009968)
		)
		(stroke
			(width 0)
			(type solid)
		)
		(fill yes)
		(layer "In6.Cu")
		(net "M_C_CPU1_SB_DQ<29>")
	)
	(gr_poly
		(pts
			(xy 85.968332 -233.952034) (xy 85.968332 -233.907838) (xy 85.612732 -233.907838) (xy 85.612732 -233.952034)
			(xy 85.659722 -234.104434) (xy 85.921342 -234.104434)
		)
		(stroke
			(width 0)
			(type solid)
		)
		(fill yes)
		(layer "In6.Cu")
		(net "M_D_CPU1_SB_DQ<16>")
	)
	(gr_poly
		(pts
			(xy 85.972904 -274.647152) (xy 85.93455 -274.625054) (xy 85.779102 -274.589494) (xy 85.648292 -274.816062)
			(xy 85.75675 -274.932902) (xy 85.795104 -274.955)
		)
		(stroke
			(width 0)
			(type solid)
		)
		(fill yes)
		(layer "In6.Cu")
		(net "M_D_CPU1_SA_DQ<7>")
	)
	(gr_poly
		(pts
			(xy 85.973412 -244.127274) (xy 85.926422 -243.974874) (xy 85.664802 -243.974874) (xy 85.617812 -244.127274)
			(xy 85.617812 -244.17147) (xy 85.973412 -244.17147)
		)
		(stroke
			(width 0)
			(type solid)
		)
		(fill yes)
		(layer "In6.Cu")
		(net "M_C_CPU1_SB_DQ<2>")
	)
	(gr_poly
		(pts
			(xy 85.973666 -247.382538) (xy 85.926676 -247.230138) (xy 85.665056 -247.230138) (xy 85.618066 -247.382538)
			(xy 85.618066 -247.426988) (xy 85.973666 -247.426988)
		)
		(stroke
			(width 0)
			(type solid)
		)
		(fill yes)
		(layer "In6.Cu")
		(net "M_A_CPU1_SB_RSP<1>")
	)
	(gr_poly
		(pts
			(xy 85.973666 -245.754906) (xy 85.926676 -245.602506) (xy 85.665056 -245.602506) (xy 85.618066 -245.754906)
			(xy 85.618066 -245.799356) (xy 85.973666 -245.799356)
		)
		(stroke
			(width 0)
			(type solid)
		)
		(fill yes)
		(layer "In6.Cu")
		(net "M_D_CPU1_SB_CS_N<3>")
	)
	(gr_poly
		(pts
			(xy 85.973666 -229.47757) (xy 85.926676 -229.32517) (xy 85.665056 -229.32517) (xy 85.618066 -229.47757)
			(xy 85.618066 -229.521766) (xy 85.973666 -229.521766)
		)
		(stroke
			(width 0)
			(type solid)
		)
		(fill yes)
		(layer "In6.Cu")
		(net "M_D_CPU1_SB_DQ<22>")
	)
	(gr_poly
		(pts
			(xy 85.973666 -229.06863) (xy 85.973666 -229.024434) (xy 85.618066 -229.024434) (xy 85.618066 -229.06863)
			(xy 85.665056 -229.22103) (xy 85.926676 -229.22103)
		)
		(stroke
			(width 0)
			(type solid)
		)
		(fill yes)
		(layer "In6.Cu")
		(net "M_D_CPU1_SB_DQ<21>")
	)
	(gr_poly
		(pts
			(xy 85.97392 -235.579666) (xy 85.97392 -235.53547) (xy 85.61832 -235.53547) (xy 85.61832 -235.579666)
			(xy 85.66531 -235.732066) (xy 85.92693 -235.732066)
		)
		(stroke
			(width 0)
			(type solid)
		)
		(fill yes)
		(layer "In6.Cu")
		(net "M_C_CPU1_SB_DQ<12>")
	)
	(gr_poly
		(pts
			(xy 85.977476 -279.523444) (xy 85.939122 -279.501346) (xy 85.783674 -279.465786) (xy 85.652864 -279.692354)
			(xy 85.761322 -279.809194) (xy 85.799676 -279.831292)
		)
		(stroke
			(width 0)
			(type solid)
		)
		(fill yes)
		(layer "In6.Cu")
		(net "M_D_CPU1_SA_DQ<3>")
	)
	(gr_poly
		(pts
			(xy 85.977476 -268.129004) (xy 85.939122 -268.106906) (xy 85.783674 -268.071346) (xy 85.652864 -268.297914)
			(xy 85.761322 -268.414754) (xy 85.799676 -268.436852)
		)
		(stroke
			(width 0)
			(type solid)
		)
		(fill yes)
		(layer "In6.Cu")
		(net "M_C_CPU1_SA_DQ<15>")
	)
	(gr_poly
		(pts
			(xy 85.978492 -271.382744) (xy 85.940138 -271.360646) (xy 85.78469 -271.325086) (xy 85.65388 -271.551654)
			(xy 85.762338 -271.668494) (xy 85.800692 -271.690592)
		)
		(stroke
			(width 0)
			(type solid)
		)
		(fill yes)
		(layer "In6.Cu")
		(net "M_C_CPU1_SA_DQS_DN<1>")
	)
	(gr_poly
		(pts
			(xy 85.979 -234.360466) (xy 85.93201 -234.208066) (xy 85.67039 -234.208066) (xy 85.6234 -234.360466)
			(xy 85.6234 -234.404916) (xy 85.979 -234.404916)
		)
		(stroke
			(width 0)
			(type solid)
		)
		(fill yes)
		(layer "In6.Cu")
		(net "M_C_CPU1_SB_DQ<15>")
	)
	(gr_poly
		(pts
			(xy 85.979508 -232.732326) (xy 85.932518 -232.579926) (xy 85.670898 -232.579926) (xy 85.623908 -232.732326)
			(xy 85.623908 -232.776776) (xy 85.979508 -232.776776)
		)
		(stroke
			(width 0)
			(type solid)
		)
		(fill yes)
		(layer "In6.Cu")
		(net "M_D_CPU1_SB_DQ<19>")
	)
	(gr_poly
		(pts
			(xy 85.98154 -242.090702) (xy 85.98154 -242.046506) (xy 85.62594 -242.046506) (xy 85.62594 -242.090702)
			(xy 85.67293 -242.243102) (xy 85.93455 -242.243102)
		)
		(stroke
			(width 0)
			(type solid)
		)
		(fill yes)
		(layer "In6.Cu")
		(net "M_C_CPU1_SB_DQS_DN<5>")
	)
	(gr_poly
		(pts
			(xy 85.982048 -249.01017) (xy 85.935058 -248.85777) (xy 85.673438 -248.85777) (xy 85.626448 -249.01017)
			(xy 85.626448 -249.05462) (xy 85.982048 -249.05462)
		)
		(stroke
			(width 0)
			(type solid)
		)
		(fill yes)
		(layer "In6.Cu")
		(net "M_A_CPU1_SA_RSP<0>")
	)
	(gr_poly
		(pts
			(xy 85.982048 -245.346474) (xy 85.982048 -245.302278) (xy 85.626448 -245.302278) (xy 85.626448 -245.346474)
			(xy 85.673438 -245.498874) (xy 85.935058 -245.498874)
		)
		(stroke
			(width 0)
			(type solid)
		)
		(fill yes)
		(layer "In6.Cu")
		(net "M_D_CPU1_SB_CS_N<0>")
	)
	(gr_poly
		(pts
			(xy 85.982048 -240.871502) (xy 85.935058 -240.719102) (xy 85.673438 -240.719102) (xy 85.626448 -240.871502)
			(xy 85.626448 -240.915698) (xy 85.982048 -240.915698)
		)
		(stroke
			(width 0)
			(type solid)
		)
		(fill yes)
		(layer "In6.Cu")
		(net "M_C_CPU1_SB_DQ<6>")
	)
	(gr_poly
		(pts
			(xy 85.982048 -239.243362) (xy 85.935058 -239.090962) (xy 85.673438 -239.090962) (xy 85.626448 -239.243362)
			(xy 85.626448 -239.287812) (xy 85.982048 -239.287812)
		)
		(stroke
			(width 0)
			(type solid)
		)
		(fill yes)
		(layer "In6.Cu")
		(net "M_C_CPU1_SB_DQ<10>")
	)
	(gr_poly
		(pts
			(xy 85.982302 -235.988098) (xy 85.935312 -235.835698) (xy 85.673692 -235.835698) (xy 85.626702 -235.988098)
			(xy 85.626702 -236.032548) (xy 85.982302 -236.032548)
		)
		(stroke
			(width 0)
			(type solid)
		)
		(fill yes)
		(layer "In6.Cu")
		(net "M_C_CPU1_SB_DQS_DP<6>")
	)
	(gr_poly
		(pts
			(xy 86.083394 -267.146278) (xy 86.036404 -266.993878) (xy 85.774784 -266.993878) (xy 85.727794 -267.146278)
			(xy 85.727794 -267.190474) (xy 86.083394 -267.190474)
		)
		(stroke
			(width 0)
			(type solid)
		)
		(fill yes)
		(layer "In6.Cu")
		(net "M_C_CPU1_SA_DQ<26>")
	)
	(gr_poly
		(pts
			(xy 86.083394 -266.737846) (xy 86.083394 -266.693396) (xy 85.727794 -266.693396) (xy 85.727794 -266.737846)
			(xy 85.774784 -266.890246) (xy 86.036404 -266.890246)
		)
		(stroke
			(width 0)
			(type solid)
		)
		(fill yes)
		(layer "In6.Cu")
		(net "M_C_CPU1_SA_DQ<25>")
	)
	(gr_poly
		(pts
			(xy 86.083394 -265.518646) (xy 86.036404 -265.366246) (xy 85.774784 -265.366246) (xy 85.727794 -265.518646)
			(xy 85.727794 -265.562842) (xy 86.083394 -265.562842)
		)
		(stroke
			(width 0)
			(type solid)
		)
		(fill yes)
		(layer "In6.Cu")
		(net "M_C_CPU1_SA_DQS_DN<3>")
	)
	(gr_poly
		(pts
			(xy 86.083394 -265.109706) (xy 86.083394 -265.06551) (xy 85.727794 -265.06551) (xy 85.727794 -265.109706)
			(xy 85.774784 -265.262106) (xy 86.036404 -265.262106)
		)
		(stroke
			(width 0)
			(type solid)
		)
		(fill yes)
		(layer "In6.Cu")
		(net "M_C_CPU1_SA_DQS_DN<8>")
	)
	(gr_poly
		(pts
			(xy 86.083394 -263.891014) (xy 86.036404 -263.738614) (xy 85.774784 -263.738614) (xy 85.727794 -263.891014)
			(xy 85.727794 -263.93521) (xy 86.083394 -263.93521)
		)
		(stroke
			(width 0)
			(type solid)
		)
		(fill yes)
		(layer "In6.Cu")
		(net "M_C_CPU1_SA_DQ<30>")
	)
	(gr_poly
		(pts
			(xy 86.083394 -263.482074) (xy 86.083394 -263.437878) (xy 85.727794 -263.437878) (xy 85.727794 -263.482074)
			(xy 85.774784 -263.634474) (xy 86.036404 -263.634474)
		)
		(stroke
			(width 0)
			(type solid)
		)
		(fill yes)
		(layer "In6.Cu")
		(net "M_C_CPU1_SA_DQ<29>")
	)
	(gr_poly
		(pts
			(xy 86.083394 -262.262874) (xy 86.036404 -262.110474) (xy 85.774784 -262.110474) (xy 85.727794 -262.262874)
			(xy 85.727794 -262.307324) (xy 86.083394 -262.307324)
		)
		(stroke
			(width 0)
			(type solid)
		)
		(fill yes)
		(layer "In6.Cu")
		(net "M_C_CPU1_SA_CB<0>")
	)
	(gr_poly
		(pts
			(xy 86.083394 -261.854442) (xy 86.083394 -261.809992) (xy 85.727794 -261.809992) (xy 85.727794 -261.854442)
			(xy 85.774784 -262.006842) (xy 86.036404 -262.006842)
		)
		(stroke
			(width 0)
			(type solid)
		)
		(fill yes)
		(layer "In6.Cu")
		(net "M_C_CPU1_SA_CB<3>")
	)
	(gr_poly
		(pts
			(xy 86.083394 -260.635242) (xy 86.036404 -260.482842) (xy 85.774784 -260.482842) (xy 85.727794 -260.635242)
			(xy 85.727794 -260.679438) (xy 86.083394 -260.679438)
		)
		(stroke
			(width 0)
			(type solid)
		)
		(fill yes)
		(layer "In6.Cu")
		(net "M_C_CPU1_SA_DQS_DP<9>")
	)
	(gr_poly
		(pts
			(xy 86.083394 -260.226302) (xy 86.083394 -260.182106) (xy 85.727794 -260.182106) (xy 85.727794 -260.226302)
			(xy 85.774784 -260.378702) (xy 86.036404 -260.378702)
		)
		(stroke
			(width 0)
			(type solid)
		)
		(fill yes)
		(layer "In6.Cu")
		(net "M_C_CPU1_SA_DQS_DP<4>")
	)
	(gr_poly
		(pts
			(xy 86.083394 -259.00761) (xy 86.036404 -258.85521) (xy 85.774784 -258.85521) (xy 85.727794 -259.00761)
			(xy 85.727794 -259.051806) (xy 86.083394 -259.051806)
		)
		(stroke
			(width 0)
			(type solid)
		)
		(fill yes)
		(layer "In6.Cu")
		(net "M_C_CPU1_SA_CB<4>")
	)
	(gr_poly
		(pts
			(xy 86.083394 -258.59867) (xy 86.083394 -258.554474) (xy 85.727794 -258.554474) (xy 85.727794 -258.59867)
			(xy 85.774784 -258.75107) (xy 86.036404 -258.75107)
		)
		(stroke
			(width 0)
			(type solid)
		)
		(fill yes)
		(layer "In6.Cu")
		(net "M_C_CPU1_SA_CB<7>")
	)
	(gr_poly
		(pts
			(xy 86.083394 -256.971038) (xy 86.083394 -256.926588) (xy 85.727794 -256.926588) (xy 85.727794 -256.971038)
			(xy 85.774784 -257.123438) (xy 86.036404 -257.123438)
		)
		(stroke
			(width 0)
			(type solid)
		)
		(fill yes)
		(layer "In6.Cu")
		(net "M_D_CPU1_SA_RSP<0>")
	)
	(gr_poly
		(pts
			(xy 86.083394 -255.751838) (xy 86.036404 -255.599438) (xy 85.774784 -255.599438) (xy 85.727794 -255.751838)
			(xy 85.727794 -255.796288) (xy 86.083394 -255.796288)
		)
		(stroke
			(width 0)
			(type solid)
		)
		(fill yes)
		(layer "In6.Cu")
		(net "M_D_CPU1_SB_RSP<1>")
	)
	(gr_poly
		(pts
			(xy 86.083394 -255.343406) (xy 86.083394 -255.298956) (xy 85.727794 -255.298956) (xy 85.727794 -255.343406)
			(xy 85.774784 -255.495806) (xy 86.036404 -255.495806)
		)
		(stroke
			(width 0)
			(type solid)
		)
		(fill yes)
		(layer "In6.Cu")
		(net "M_C_CPU1_SA_RSP<0>")
	)
	(gr_poly
		(pts
			(xy 86.091776 -276.5044) (xy 86.091776 -276.460204) (xy 85.736176 -276.460204) (xy 85.736176 -276.5044)
			(xy 85.783166 -276.6568) (xy 86.044786 -276.6568)
		)
		(stroke
			(width 0)
			(type solid)
		)
		(fill yes)
		(layer "In6.Cu")
		(net "M_D_CPU1_SA_DQ<4>")
	)
	(gr_poly
		(pts
			(xy 86.09203 -273.657314) (xy 86.04504 -273.504914) (xy 85.78342 -273.504914) (xy 85.73643 -273.657314)
			(xy 85.73643 -273.70151) (xy 86.09203 -273.70151)
		)
		(stroke
			(width 0)
			(type solid)
		)
		(fill yes)
		(layer "In6.Cu")
		(net "M_C_CPU1_SA_DQ<10>")
	)
	(gr_poly
		(pts
			(xy 86.09203 -273.248882) (xy 86.09203 -273.204686) (xy 85.73643 -273.204686) (xy 85.73643 -273.248882)
			(xy 85.78342 -273.401282) (xy 86.04504 -273.401282)
		)
		(stroke
			(width 0)
			(type solid)
		)
		(fill yes)
		(layer "In6.Cu")
		(net "M_C_CPU1_SA_DQ<9>")
	)
	(gr_poly
		(pts
			(xy 86.156038 -275.356574) (xy 86.04758 -275.239734) (xy 86.009226 -275.217636) (xy 85.831426 -275.525484)
			(xy 85.86978 -275.547582) (xy 86.025228 -275.583142)
		)
		(stroke
			(width 0)
			(type solid)
		)
		(fill yes)
		(layer "In6.Cu")
		(net "M_D_CPU1_SA_DQ<5>")
	)
	(gr_poly
		(pts
			(xy 86.156292 -280.239978) (xy 86.047834 -280.123138) (xy 86.00948 -280.10104) (xy 85.83168 -280.408888)
			(xy 85.870034 -280.430986) (xy 86.025482 -280.466546)
		)
		(stroke
			(width 0)
			(type solid)
		)
		(fill yes)
		(layer "In6.Cu")
		(net "M_D_CPU1_SA_DQ<1>")
	)
	(gr_poly
		(pts
			(xy 86.158324 -268.841474) (xy 86.049866 -268.724634) (xy 86.011512 -268.702536) (xy 85.833712 -269.010384)
			(xy 85.872066 -269.032482) (xy 86.027514 -269.068042)
		)
		(stroke
			(width 0)
			(type solid)
		)
		(fill yes)
		(layer "In6.Cu")
		(net "M_C_CPU1_SA_DQ<13>")
	)
	(gr_poly
		(pts
			(xy 86.162896 -272.089626) (xy 86.054438 -271.972786) (xy 86.016084 -271.950688) (xy 85.838284 -272.258536)
			(xy 85.876638 -272.280634) (xy 86.032086 -272.316194)
		)
		(stroke
			(width 0)
			(type solid)
		)
		(fill yes)
		(layer "In6.Cu")
		(net "M_C_CPU1_SA_DQS_DP<1>")
	)
	(gr_poly
		(pts
			(xy 86.299294 -237.06074) (xy 86.337648 -237.038642) (xy 86.159848 -236.730794) (xy 86.121494 -236.752892)
			(xy 86.013036 -236.869732) (xy 86.143846 -237.0963)
		)
		(stroke
			(width 0)
			(type solid)
		)
		(fill yes)
		(layer "In6.Cu")
		(net "M_C_CPU1_SB_DQS_DN<6>")
	)
	(gr_poly
		(pts
			(xy 86.30031 -230.551736) (xy 86.338664 -230.529638) (xy 86.160864 -230.22179) (xy 86.12251 -230.243888)
			(xy 86.014052 -230.360728) (xy 86.144862 -230.587296)
		)
		(stroke
			(width 0)
			(type solid)
		)
		(fill yes)
		(layer "In6.Cu")
		(net "M_D_CPU1_SB_DQ<20>")
	)
	(gr_poly
		(pts
			(xy 86.410038 -236.443012) (xy 86.518496 -236.326172) (xy 86.387686 -236.099604) (xy 86.232238 -236.135164)
			(xy 86.193884 -236.157262) (xy 86.371684 -236.46511)
		)
		(stroke
			(width 0)
			(type solid)
		)
		(fill yes)
		(layer "In6.Cu")
		(net "M_C_CPU1_SB_DQS_DP<6>")
	)
	(gr_poly
		(pts
			(xy 86.410038 -229.931722) (xy 86.518496 -229.814882) (xy 86.387686 -229.588314) (xy 86.232238 -229.623874)
			(xy 86.193884 -229.645972) (xy 86.371684 -229.95382)
		)
		(stroke
			(width 0)
			(type solid)
		)
		(fill yes)
		(layer "In6.Cu")
		(net "M_D_CPU1_SB_DQ<22>")
	)
	(gr_poly
		(pts
			(xy 86.43493 -249.416062) (xy 86.43493 -249.371612) (xy 86.07933 -249.371612) (xy 86.07933 -249.416062)
			(xy 86.12632 -249.568462) (xy 86.38794 -249.568462)
		)
		(stroke
			(width 0)
			(type solid)
		)
		(fill yes)
		(layer "In6.Cu")
		(net "M_A_CPU1_SB_RSP<0>")
	)
	(gr_poly
		(pts
			(xy 86.43493 -244.940582) (xy 86.38794 -244.788182) (xy 86.12632 -244.788182) (xy 86.07933 -244.940582)
			(xy 86.07933 -244.985032) (xy 86.43493 -244.985032)
		)
		(stroke
			(width 0)
			(type solid)
		)
		(fill yes)
		(layer "In6.Cu")
		(net "M_D_CPU1_SB_CS_N<1>")
	)
	(gr_poly
		(pts
			(xy 86.43493 -241.685318) (xy 86.38794 -241.532918) (xy 86.12632 -241.532918) (xy 86.07933 -241.685318)
			(xy 86.07933 -241.729514) (xy 86.43493 -241.729514)
		)
		(stroke
			(width 0)
			(type solid)
		)
		(fill yes)
		(layer "In6.Cu")
		(net "M_C_CPU1_SB_DQS_DP<5>")
	)
	(gr_poly
		(pts
			(xy 86.43493 -239.649254) (xy 86.43493 -239.604804) (xy 86.07933 -239.604804) (xy 86.07933 -239.649254)
			(xy 86.12632 -239.801654) (xy 86.38794 -239.801654)
		)
		(stroke
			(width 0)
			(type solid)
		)
		(fill yes)
		(layer "In6.Cu")
		(net "M_C_CPU1_SB_DQ<8>")
	)
	(gr_poly
		(pts
			(xy 86.43747 -241.276886) (xy 86.43747 -241.23269) (xy 86.08187 -241.23269) (xy 86.08187 -241.276886)
			(xy 86.12886 -241.429286) (xy 86.39048 -241.429286)
		)
		(stroke
			(width 0)
			(type solid)
		)
		(fill yes)
		(layer "In6.Cu")
		(net "M_C_CPU1_SB_DQ<4>")
	)
	(gr_poly
		(pts
			(xy 86.43747 -233.138218) (xy 86.43747 -233.094022) (xy 86.08187 -233.094022) (xy 86.08187 -233.138218)
			(xy 86.12886 -233.290618) (xy 86.39048 -233.290618)
		)
		(stroke
			(width 0)
			(type solid)
		)
		(fill yes)
		(layer "In6.Cu")
		(net "M_D_CPU1_SB_DQ<17>")
	)
	(gr_poly
		(pts
			(xy 86.43747 -227.035614) (xy 86.39048 -226.883214) (xy 86.12886 -226.883214) (xy 86.08187 -227.035614)
			(xy 86.08187 -227.07981) (xy 86.43747 -227.07981)
		)
		(stroke
			(width 0)
			(type solid)
		)
		(fill yes)
		(layer "In6.Cu")
		(net "M_C_CPU1_SB_DQ<24>")
	)
	(gr_poly
		(pts
			(xy 86.43747 -226.626674) (xy 86.43747 -226.582478) (xy 86.08187 -226.582478) (xy 86.08187 -226.626674)
			(xy 86.12886 -226.779074) (xy 86.39048 -226.779074)
		)
		(stroke
			(width 0)
			(type solid)
		)
		(fill yes)
		(layer "In6.Cu")
		(net "M_C_CPU1_SB_DQ<25>")
	)
	(gr_poly
		(pts
			(xy 86.438232 -234.76585) (xy 86.438232 -234.721654) (xy 86.082632 -234.721654) (xy 86.082632 -234.76585)
			(xy 86.129622 -234.91825) (xy 86.391242 -234.91825)
		)
		(stroke
			(width 0)
			(type solid)
		)
		(fill yes)
		(layer "In6.Cu")
		(net "M_C_CPU1_SB_DQ<13>")
	)
	(gr_poly
		(pts
			(xy 86.443312 -244.53215) (xy 86.443312 -244.487954) (xy 86.087712 -244.487954) (xy 86.087712 -244.53215)
			(xy 86.134702 -244.68455) (xy 86.396322 -244.68455)
		)
		(stroke
			(width 0)
			(type solid)
		)
		(fill yes)
		(layer "In6.Cu")
		(net "M_C_CPU1_SB_DQ<0>")
	)
	(gr_poly
		(pts
			(xy 86.443566 -247.787922) (xy 86.443566 -247.743472) (xy 86.087966 -247.743472) (xy 86.087966 -247.787922)
			(xy 86.134956 -247.940322) (xy 86.396576 -247.940322)
		)
		(stroke
			(width 0)
			(type solid)
		)
		(fill yes)
		(layer "In6.Cu")
		(net "M_A_CPU1_SA_RSP<1>")
	)
	(gr_poly
		(pts
			(xy 86.443566 -246.16029) (xy 86.443566 -246.11584) (xy 86.087966 -246.11584) (xy 86.087966 -246.16029)
			(xy 86.134956 -246.31269) (xy 86.396576 -246.31269)
		)
		(stroke
			(width 0)
			(type solid)
		)
		(fill yes)
		(layer "In6.Cu")
		(net "M_D_CPU1_SB_CS_N<2>")
	)
	(gr_poly
		(pts
			(xy 86.443566 -242.904518) (xy 86.443566 -242.860322) (xy 86.087966 -242.860322) (xy 86.087966 -242.904518)
			(xy 86.134956 -243.056918) (xy 86.396576 -243.056918)
		)
		(stroke
			(width 0)
			(type solid)
		)
		(fill yes)
		(layer "In6.Cu")
		(net "M_C_CPU1_SB_DQS_DP<0>")
	)
	(gr_poly
		(pts
			(xy 86.443566 -238.021114) (xy 86.443566 -237.976918) (xy 86.087966 -237.976918) (xy 86.087966 -238.021114)
			(xy 86.134956 -238.173514) (xy 86.396576 -238.173514)
		)
		(stroke
			(width 0)
			(type solid)
		)
		(fill yes)
		(layer "In6.Cu")
		(net "M_C_CPU1_SB_DQS_DP<1>")
	)
	(gr_poly
		(pts
			(xy 86.443566 -231.919018) (xy 86.396576 -231.766618) (xy 86.134956 -231.766618) (xy 86.087966 -231.919018)
			(xy 86.087966 -231.963214) (xy 86.443566 -231.963214)
		)
		(stroke
			(width 0)
			(type solid)
		)
		(fill yes)
		(layer "In6.Cu")
		(net "M_D_CPU1_SB_DQS_DN<2>")
	)
	(gr_poly
		(pts
			(xy 86.443566 -231.510078) (xy 86.443566 -231.465882) (xy 86.087966 -231.465882) (xy 86.087966 -231.510078)
			(xy 86.134956 -231.662478) (xy 86.396576 -231.662478)
		)
		(stroke
			(width 0)
			(type solid)
		)
		(fill yes)
		(layer "In6.Cu")
		(net "M_D_CPU1_SB_DQS_DN<7>")
	)
	(gr_poly
		(pts
			(xy 86.443566 -228.663754) (xy 86.396576 -228.511354) (xy 86.134956 -228.511354) (xy 86.087966 -228.663754)
			(xy 86.087966 -228.70795) (xy 86.443566 -228.70795)
		)
		(stroke
			(width 0)
			(type solid)
		)
		(fill yes)
		(layer "In6.Cu")
		(net "M_D_CPU1_SB_DQ<23>")
	)
	(gr_poly
		(pts
			(xy 86.443566 -225.407474) (xy 86.396576 -225.255074) (xy 86.134956 -225.255074) (xy 86.087966 -225.407474)
			(xy 86.087966 -225.451924) (xy 86.443566 -225.451924)
		)
		(stroke
			(width 0)
			(type solid)
		)
		(fill yes)
		(layer "In6.Cu")
		(net "M_C_CPU1_SB_DQS_DN<3>")
	)
	(gr_poly
		(pts
			(xy 86.443566 -224.999042) (xy 86.443566 -224.954592) (xy 86.087966 -224.954592) (xy 86.087966 -224.999042)
			(xy 86.134956 -225.151442) (xy 86.396576 -225.151442)
		)
		(stroke
			(width 0)
			(type solid)
		)
		(fill yes)
		(layer "In6.Cu")
		(net "M_C_CPU1_SB_DQS_DN<8>")
	)
	(gr_poly
		(pts
			(xy 86.443566 -223.779842) (xy 86.396576 -223.627442) (xy 86.134956 -223.627442) (xy 86.087966 -223.779842)
			(xy 86.087966 -223.824292) (xy 86.443566 -223.824292)
		)
		(stroke
			(width 0)
			(type solid)
		)
		(fill yes)
		(layer "In6.Cu")
		(net "M_C_CPU1_SB_DQ<30>")
	)
	(gr_poly
		(pts
			(xy 86.443566 -223.37141) (xy 86.443566 -223.32696) (xy 86.087966 -223.32696) (xy 86.087966 -223.37141)
			(xy 86.134956 -223.52381) (xy 86.396576 -223.52381)
		)
		(stroke
			(width 0)
			(type solid)
		)
		(fill yes)
		(layer "In6.Cu")
		(net "M_C_CPU1_SB_DQ<31>")
	)
	(gr_poly
		(pts
			(xy 86.447376 -278.709628) (xy 86.409022 -278.68753) (xy 86.253574 -278.65197) (xy 86.122764 -278.878538)
			(xy 86.231222 -278.995378) (xy 86.269576 -279.017476)
		)
		(stroke
			(width 0)
			(type solid)
		)
		(fill yes)
		(layer "In6.Cu")
		(net "M_D_CPU1_SA_DQ<3>")
	)
	(gr_poly
		(pts
			(xy 86.447376 -268.94282) (xy 86.409022 -268.920722) (xy 86.253574 -268.885162) (xy 86.122764 -269.11173)
			(xy 86.231222 -269.22857) (xy 86.269576 -269.250668)
		)
		(stroke
			(width 0)
			(type solid)
		)
		(fill yes)
		(layer "In6.Cu")
		(net "M_C_CPU1_SA_DQ<14>")
	)
	(gr_poly
		(pts
			(xy 86.448392 -272.19656) (xy 86.410038 -272.174462) (xy 86.25459 -272.138902) (xy 86.12378 -272.36547)
			(xy 86.232238 -272.48231) (xy 86.270592 -272.504408)
		)
		(stroke
			(width 0)
			(type solid)
		)
		(fill yes)
		(layer "In6.Cu")
		(net "M_C_CPU1_SA_DQ<11>")
	)
	(gr_poly
		(pts
			(xy 86.4489 -235.174282) (xy 86.40191 -235.021882) (xy 86.14029 -235.021882) (xy 86.0933 -235.174282)
			(xy 86.0933 -235.218732) (xy 86.4489 -235.218732)
		)
		(stroke
			(width 0)
			(type solid)
		)
		(fill yes)
		(layer "In6.Cu")
		(net "M_C_CPU1_SB_DQ<14>")
	)
	(gr_poly
		(pts
			(xy 86.449154 -275.450046) (xy 86.4108 -275.427948) (xy 86.255352 -275.392388) (xy 86.124542 -275.618956)
			(xy 86.233 -275.735796) (xy 86.271354 -275.757894)
		)
		(stroke
			(width 0)
			(type solid)
		)
		(fill yes)
		(layer "In6.Cu")
		(net "M_D_CPU1_SA_DQ<6>")
	)
	(gr_poly
		(pts
			(xy 86.449408 -280.33345) (xy 86.411054 -280.311352) (xy 86.255606 -280.275792) (xy 86.124796 -280.50236)
			(xy 86.233254 -280.6192) (xy 86.271608 -280.641298)
		)
		(stroke
			(width 0)
			(type solid)
		)
		(fill yes)
		(layer "In6.Cu")
		(net "M_D_CPU1_SA_DQ<2>")
	)
	(gr_poly
		(pts
			(xy 86.449408 -233.54665) (xy 86.402418 -233.39425) (xy 86.140798 -233.39425) (xy 86.093808 -233.54665)
			(xy 86.093808 -233.590846) (xy 86.449408 -233.590846)
		)
		(stroke
			(width 0)
			(type solid)
		)
		(fill yes)
		(layer "In6.Cu")
		(net "M_D_CPU1_SB_DQ<18>")
	)
	(gr_poly
		(pts
			(xy 86.450932 -240.057178) (xy 86.403942 -239.904778) (xy 86.142322 -239.904778) (xy 86.095332 -240.057178)
			(xy 86.095332 -240.101628) (xy 86.450932 -240.101628)
		)
		(stroke
			(width 0)
			(type solid)
		)
		(fill yes)
		(layer "In6.Cu")
		(net "M_C_CPU1_SB_DQ<7>")
	)
	(gr_poly
		(pts
			(xy 86.451948 -243.31295) (xy 86.404958 -243.16055) (xy 86.143338 -243.16055) (xy 86.096348 -243.31295)
			(xy 86.096348 -243.3574) (xy 86.451948 -243.3574)
		)
		(stroke
			(width 0)
			(type solid)
		)
		(fill yes)
		(layer "In6.Cu")
		(net "M_C_CPU1_SB_DQ<3>")
	)
	(gr_poly
		(pts
			(xy 86.452202 -238.429546) (xy 86.405212 -238.277146) (xy 86.143592 -238.277146) (xy 86.096602 -238.429546)
			(xy 86.096602 -238.473996) (xy 86.452202 -238.473996)
		)
		(stroke
			(width 0)
			(type solid)
		)
		(fill yes)
		(layer "In6.Cu")
		(net "M_C_CPU1_SB_DQ<11>")
	)
	(gr_poly
		(pts
			(xy 86.544658 -277.726902) (xy 86.497668 -277.574502) (xy 86.236048 -277.574502) (xy 86.189058 -277.726902)
			(xy 86.189058 -277.771098) (xy 86.544658 -277.771098)
		)
		(stroke
			(width 0)
			(type solid)
		)
		(fill yes)
		(layer "In6.Cu")
		(net "M_D_CPU1_SA_DQS_DN<0>")
	)
	(gr_poly
		(pts
			(xy 86.544658 -277.31847) (xy 86.544658 -277.274274) (xy 86.189058 -277.274274) (xy 86.189058 -277.31847)
			(xy 86.236048 -277.47087) (xy 86.497668 -277.47087)
		)
		(stroke
			(width 0)
			(type solid)
		)
		(fill yes)
		(layer "In6.Cu")
		(net "M_D_CPU1_SA_DQS_DN<5>")
	)
	(gr_poly
		(pts
			(xy 86.544912 -274.062698) (xy 86.544912 -274.018502) (xy 86.189312 -274.018502) (xy 86.189312 -274.062698)
			(xy 86.236302 -274.215098) (xy 86.497922 -274.215098)
		)
		(stroke
			(width 0)
			(type solid)
		)
		(fill yes)
		(layer "In6.Cu")
		(net "M_C_CPU1_SA_DQ<8>")
	)
	(gr_poly
		(pts
			(xy 86.547452 -271.215358) (xy 86.500462 -271.062958) (xy 86.238842 -271.062958) (xy 86.191852 -271.215358)
			(xy 86.191852 -271.259808) (xy 86.547452 -271.259808)
		)
		(stroke
			(width 0)
			(type solid)
		)
		(fill yes)
		(layer "In6.Cu")
		(net "M_C_CPU1_SA_DQS_DN<1>")
	)
	(gr_poly
		(pts
			(xy 86.553294 -270.806926) (xy 86.553294 -270.76273) (xy 86.197694 -270.76273) (xy 86.197694 -270.806926)
			(xy 86.244684 -270.959326) (xy 86.506304 -270.959326)
		)
		(stroke
			(width 0)
			(type solid)
		)
		(fill yes)
		(layer "In6.Cu")
		(net "M_C_CPU1_SA_DQS_DN<6>")
	)
	(gr_poly
		(pts
			(xy 86.553294 -267.960094) (xy 86.506304 -267.807694) (xy 86.244684 -267.807694) (xy 86.197694 -267.960094)
			(xy 86.197694 -268.004544) (xy 86.553294 -268.004544)
		)
		(stroke
			(width 0)
			(type solid)
		)
		(fill yes)
		(layer "In6.Cu")
		(net "M_C_CPU1_SA_DQ<15>")
	)
	(gr_poly
		(pts
			(xy 86.553294 -267.551662) (xy 86.553294 -267.507212) (xy 86.197694 -267.507212) (xy 86.197694 -267.551662)
			(xy 86.244684 -267.704062) (xy 86.506304 -267.704062)
		)
		(stroke
			(width 0)
			(type solid)
		)
		(fill yes)
		(layer "In6.Cu")
		(net "M_C_CPU1_SA_DQ<24>")
	)
	(gr_poly
		(pts
			(xy 86.553294 -266.332462) (xy 86.506304 -266.180062) (xy 86.244684 -266.180062) (xy 86.197694 -266.332462)
			(xy 86.197694 -266.376658) (xy 86.553294 -266.376658)
		)
		(stroke
			(width 0)
			(type solid)
		)
		(fill yes)
		(layer "In6.Cu")
		(net "M_C_CPU1_SA_DQ<27>")
	)
	(gr_poly
		(pts
			(xy 86.553294 -265.92403) (xy 86.553294 -265.87958) (xy 86.197694 -265.87958) (xy 86.197694 -265.92403)
			(xy 86.244684 -266.07643) (xy 86.506304 -266.07643)
		)
		(stroke
			(width 0)
			(type solid)
		)
		(fill yes)
		(layer "In6.Cu")
		(net "M_C_CPU1_SA_DQS_DP<3>")
	)
	(gr_poly
		(pts
			(xy 86.553294 -264.70483) (xy 86.506304 -264.55243) (xy 86.244684 -264.55243) (xy 86.197694 -264.70483)
			(xy 86.197694 -264.749026) (xy 86.553294 -264.749026)
		)
		(stroke
			(width 0)
			(type solid)
		)
		(fill yes)
		(layer "In6.Cu")
		(net "M_C_CPU1_SA_DQS_DP<8>")
	)
	(gr_poly
		(pts
			(xy 86.553294 -264.29589) (xy 86.553294 -264.251694) (xy 86.197694 -264.251694) (xy 86.197694 -264.29589)
			(xy 86.244684 -264.44829) (xy 86.506304 -264.44829)
		)
		(stroke
			(width 0)
			(type solid)
		)
		(fill yes)
		(layer "In6.Cu")
		(net "M_C_CPU1_SA_DQ<28>")
	)
	(gr_poly
		(pts
			(xy 86.553294 -263.07669) (xy 86.506304 -262.92429) (xy 86.244684 -262.92429) (xy 86.197694 -263.07669)
			(xy 86.197694 -263.12114) (xy 86.553294 -263.12114)
		)
		(stroke
			(width 0)
			(type solid)
		)
		(fill yes)
		(layer "In6.Cu")
		(net "M_C_CPU1_SA_DQ<31>")
	)
	(gr_poly
		(pts
			(xy 86.553294 -262.668258) (xy 86.553294 -262.623808) (xy 86.197694 -262.623808) (xy 86.197694 -262.668258)
			(xy 86.244684 -262.820658) (xy 86.506304 -262.820658)
		)
		(stroke
			(width 0)
			(type solid)
		)
		(fill yes)
		(layer "In6.Cu")
		(net "M_C_CPU1_SA_CB<2>")
	)
	(gr_poly
		(pts
			(xy 86.553294 -261.449058) (xy 86.506304 -261.296658) (xy 86.244684 -261.296658) (xy 86.197694 -261.449058)
			(xy 86.197694 -261.493508) (xy 86.553294 -261.493508)
		)
		(stroke
			(width 0)
			(type solid)
		)
		(fill yes)
		(layer "In6.Cu")
		(net "M_C_CPU1_SA_CB<1>")
	)
	(gr_poly
		(pts
			(xy 86.553294 -261.040626) (xy 86.553294 -260.996176) (xy 86.197694 -260.996176) (xy 86.197694 -261.040626)
			(xy 86.244684 -261.193026) (xy 86.506304 -261.193026)
		)
		(stroke
			(width 0)
			(type solid)
		)
		(fill yes)
		(layer "In6.Cu")
		(net "M_C_CPU1_SA_DQS_DN<9>")
	)
	(gr_poly
		(pts
			(xy 86.553294 -259.821426) (xy 86.506304 -259.669026) (xy 86.244684 -259.669026) (xy 86.197694 -259.821426)
			(xy 86.197694 -259.865622) (xy 86.553294 -259.865622)
		)
		(stroke
			(width 0)
			(type solid)
		)
		(fill yes)
		(layer "In6.Cu")
		(net "M_C_CPU1_SA_DQS_DN<4>")
	)
	(gr_poly
		(pts
			(xy 86.553294 -259.412486) (xy 86.553294 -259.36829) (xy 86.197694 -259.36829) (xy 86.197694 -259.412486)
			(xy 86.244684 -259.564886) (xy 86.506304 -259.564886)
		)
		(stroke
			(width 0)
			(type solid)
		)
		(fill yes)
		(layer "In6.Cu")
		(net "M_C_CPU1_SA_CB<6>")
	)
	(gr_poly
		(pts
			(xy 86.553294 -258.193286) (xy 86.506304 -258.040886) (xy 86.244684 -258.040886) (xy 86.197694 -258.193286)
			(xy 86.197694 -258.237736) (xy 86.553294 -258.237736)
		)
		(stroke
			(width 0)
			(type solid)
		)
		(fill yes)
		(layer "In6.Cu")
		(net "M_C_CPU1_SA_CB<5>")
	)
	(gr_poly
		(pts
			(xy 86.553294 -256.565654) (xy 86.506304 -256.413254) (xy 86.244684 -256.413254) (xy 86.197694 -256.565654)
			(xy 86.197694 -256.610104) (xy 86.553294 -256.610104)
		)
		(stroke
			(width 0)
			(type solid)
		)
		(fill yes)
		(layer "In6.Cu")
		(net "M_D_CPU1_SB_RSP<0>")
	)
	(gr_poly
		(pts
			(xy 86.553294 -256.157222) (xy 86.553294 -256.112772) (xy 86.197694 -256.112772) (xy 86.197694 -256.157222)
			(xy 86.244684 -256.309622) (xy 86.506304 -256.309622)
		)
		(stroke
			(width 0)
			(type solid)
		)
		(fill yes)
		(layer "In6.Cu")
		(net "M_D_CPU1_SA_RSP<1>")
	)
	(gr_poly
		(pts
			(xy 86.553294 -254.938022) (xy 86.506304 -254.785622) (xy 86.244684 -254.785622) (xy 86.197694 -254.938022)
			(xy 86.197694 -254.982218) (xy 86.553294 -254.982218)
		)
		(stroke
			(width 0)
			(type solid)
		)
		(fill yes)
		(layer "In6.Cu")
		(net "M_C_CPU1_SB_RSP<0>")
	)
	(gr_poly
		(pts
			(xy 86.553294 -254.529082) (xy 86.553294 -254.484886) (xy 86.197694 -254.484886) (xy 86.197694 -254.529082)
			(xy 86.244684 -254.681482) (xy 86.506304 -254.681482)
		)
		(stroke
			(width 0)
			(type solid)
		)
		(fill yes)
		(layer "In6.Cu")
		(net "M_C_CPU1_SA_RSP<1>")
	)
	(gr_poly
		(pts
			(xy 86.561676 -274.47113) (xy 86.514686 -274.31873) (xy 86.253066 -274.31873) (xy 86.206076 -274.47113)
			(xy 86.206076 -274.515326) (xy 86.561676 -274.515326)
		)
		(stroke
			(width 0)
			(type solid)
		)
		(fill yes)
		(layer "In6.Cu")
		(net "M_D_CPU1_SA_DQ<7>")
	)
	(gr_poly
		(pts
			(xy 86.626192 -269.659354) (xy 86.517734 -269.542514) (xy 86.47938 -269.520416) (xy 86.30158 -269.828264)
			(xy 86.339934 -269.850362) (xy 86.495382 -269.885922)
		)
		(stroke
			(width 0)
			(type solid)
		)
		(fill yes)
		(layer "In6.Cu")
		(net "M_C_CPU1_SA_DQ<12>")
	)
	(gr_poly
		(pts
			(xy 86.626954 -276.16912) (xy 86.518496 -276.05228) (xy 86.480142 -276.030182) (xy 86.302342 -276.33803)
			(xy 86.340696 -276.360128) (xy 86.496144 -276.395688)
		)
		(stroke
			(width 0)
			(type solid)
		)
		(fill yes)
		(layer "In6.Cu")
		(net "M_D_CPU1_SA_DQ<4>")
	)
	(gr_poly
		(pts
			(xy 86.628224 -281.049984) (xy 86.519766 -280.933144) (xy 86.481412 -280.911046) (xy 86.303612 -281.218894)
			(xy 86.341966 -281.240992) (xy 86.497414 -281.276552)
		)
		(stroke
			(width 0)
			(type solid)
		)
		(fill yes)
		(layer "In6.Cu")
		(net "M_D_CPU1_SA_DQ<0>")
	)
	(gr_poly
		(pts
			(xy 86.628224 -279.422098) (xy 86.519766 -279.305258) (xy 86.481412 -279.28316) (xy 86.303612 -279.591008)
			(xy 86.341966 -279.613106) (xy 86.497414 -279.648666)
		)
		(stroke
			(width 0)
			(type solid)
		)
		(fill yes)
		(layer "In6.Cu")
		(net "M_D_CPU1_SA_DQ<1>")
	)
	(gr_poly
		(pts
			(xy 86.632796 -272.903696) (xy 86.524338 -272.786856) (xy 86.485984 -272.764758) (xy 86.308184 -273.072606)
			(xy 86.346538 -273.094704) (xy 86.501986 -273.130264)
		)
		(stroke
			(width 0)
			(type solid)
		)
		(fill yes)
		(layer "In6.Cu")
		(net "M_C_CPU1_SA_DQ<9>")
	)
	(gr_poly
		(pts
			(xy 86.76894 -229.735888) (xy 86.807294 -229.71379) (xy 86.629494 -229.405942) (xy 86.59114 -229.42804)
			(xy 86.482682 -229.54488) (xy 86.613492 -229.771448)
		)
		(stroke
			(width 0)
			(type solid)
		)
		(fill yes)
		(layer "In6.Cu")
		(net "M_D_CPU1_SB_DQ<21>")
	)
	(gr_poly
		(pts
			(xy 86.769194 -236.246924) (xy 86.807548 -236.224826) (xy 86.629748 -235.916978) (xy 86.591394 -235.939076)
			(xy 86.482936 -236.055916) (xy 86.613746 -236.282484)
		)
		(stroke
			(width 0)
			(type solid)
		)
		(fill yes)
		(layer "In6.Cu")
		(net "M_C_CPU1_SB_DQ<12>")
	)
	(gr_poly
		(pts
			(xy 86.769956 -228.10978) (xy 86.80831 -228.087682) (xy 86.63051 -227.779834) (xy 86.592156 -227.801932)
			(xy 86.483698 -227.918772) (xy 86.614508 -228.14534)
		)
		(stroke
			(width 0)
			(type solid)
		)
		(fill yes)
		(layer "In6.Cu")
		(net "M_C_CPU1_SB_DQ<26>")
	)
	(gr_poly
		(pts
			(xy 86.80958 -248.361454) (xy 86.771226 -248.339356) (xy 86.615778 -248.303796) (xy 86.484968 -248.530364)
			(xy 86.593426 -248.647204) (xy 86.63178 -248.669302)
		)
		(stroke
			(width 0)
			(type solid)
		)
		(fill yes)
		(layer "In6.Cu")
		(net "M_A_CPU1_SA_RSP<0>")
	)
	(gr_poly
		(pts
			(xy 86.879176 -235.627164) (xy 86.987634 -235.510324) (xy 86.856824 -235.283756) (xy 86.701376 -235.319316)
			(xy 86.663022 -235.341414) (xy 86.840822 -235.649262)
		)
		(stroke
			(width 0)
			(type solid)
		)
		(fill yes)
		(layer "In6.Cu")
		(net "M_C_CPU1_SB_DQ<14>")
	)
	(gr_poly
		(pts
			(xy 86.879938 -229.117906) (xy 86.988396 -229.001066) (xy 86.857586 -228.774498) (xy 86.702138 -228.810058)
			(xy 86.663784 -228.832156) (xy 86.841584 -229.140004)
		)
		(stroke
			(width 0)
			(type solid)
		)
		(fill yes)
		(layer "In6.Cu")
		(net "M_D_CPU1_SB_DQ<23>")
	)
	(gr_poly
		(pts
			(xy 86.884256 -227.497132) (xy 86.992714 -227.380292) (xy 86.861904 -227.153724) (xy 86.706456 -227.189284)
			(xy 86.668102 -227.211382) (xy 86.845902 -227.51923)
		)
		(stroke
			(width 0)
			(type solid)
		)
		(fill yes)
		(layer "In6.Cu")
		(net "M_C_CPU1_SB_DQ<24>")
	)
	(gr_poly
		(pts
			(xy 86.900766 -240.46307) (xy 86.900766 -240.418874) (xy 86.545166 -240.418874) (xy 86.545166 -240.46307)
			(xy 86.592156 -240.61547) (xy 86.853776 -240.61547)
		)
		(stroke
			(width 0)
			(type solid)
		)
		(fill yes)
		(layer "In6.Cu")
		(net "M_C_CPU1_SB_DQ<5>")
	)
	(gr_poly
		(pts
			(xy 86.90483 -243.718842) (xy 86.90483 -243.674392) (xy 86.54923 -243.674392) (xy 86.54923 -243.718842)
			(xy 86.59622 -243.871242) (xy 86.85784 -243.871242)
		)
		(stroke
			(width 0)
			(type solid)
		)
		(fill yes)
		(layer "In6.Cu")
		(net "M_C_CPU1_SB_DQ<1>")
	)
	(gr_poly
		(pts
			(xy 86.905084 -238.835438) (xy 86.905084 -238.790988) (xy 86.549484 -238.790988) (xy 86.549484 -238.835438)
			(xy 86.596474 -238.987838) (xy 86.858094 -238.987838)
		)
		(stroke
			(width 0)
			(type solid)
		)
		(fill yes)
		(layer "In6.Cu")
		(net "M_C_CPU1_SB_DQ<9>")
	)
	(gr_poly
		(pts
			(xy 86.90737 -242.499134) (xy 86.86038 -242.346734) (xy 86.59876 -242.346734) (xy 86.55177 -242.499134)
			(xy 86.55177 -242.543584) (xy 86.90737 -242.543584)
		)
		(stroke
			(width 0)
			(type solid)
		)
		(fill yes)
		(layer "In6.Cu")
		(net "M_C_CPU1_SB_DQS_DN<0>")
	)
	(gr_poly
		(pts
			(xy 86.90737 -242.090702) (xy 86.90737 -242.046252) (xy 86.55177 -242.046252) (xy 86.55177 -242.090702)
			(xy 86.59876 -242.243102) (xy 86.86038 -242.243102)
		)
		(stroke
			(width 0)
			(type solid)
		)
		(fill yes)
		(layer "In6.Cu")
		(net "M_C_CPU1_SB_DQS_DN<5>")
	)
	(gr_poly
		(pts
			(xy 86.90737 -237.207298) (xy 86.90737 -237.163102) (xy 86.55177 -237.163102) (xy 86.55177 -237.207298)
			(xy 86.59876 -237.359698) (xy 86.86038 -237.359698)
		)
		(stroke
			(width 0)
			(type solid)
		)
		(fill yes)
		(layer "In6.Cu")
		(net "M_C_CPU1_SB_DQS_DN<6>")
	)
	(gr_poly
		(pts
			(xy 86.90737 -233.952542) (xy 86.90737 -233.908092) (xy 86.55177 -233.908092) (xy 86.55177 -233.952542)
			(xy 86.59876 -234.104942) (xy 86.86038 -234.104942)
		)
		(stroke
			(width 0)
			(type solid)
		)
		(fill yes)
		(layer "In6.Cu")
		(net "M_D_CPU1_SB_DQ<16>")
	)
	(gr_poly
		(pts
			(xy 86.90737 -225.812858) (xy 86.90737 -225.768662) (xy 86.55177 -225.768662) (xy 86.55177 -225.812858)
			(xy 86.59876 -225.965258) (xy 86.86038 -225.965258)
		)
		(stroke
			(width 0)
			(type solid)
		)
		(fill yes)
		(layer "In6.Cu")
		(net "M_C_CPU1_SB_DQS_DP<3>")
	)
	(gr_poly
		(pts
			(xy 86.912958 -273.01952) (xy 86.874604 -272.997422) (xy 86.719156 -272.961862) (xy 86.588346 -273.18843)
			(xy 86.696804 -273.30527) (xy 86.735158 -273.327368)
		)
		(stroke
			(width 0)
			(type solid)
		)
		(fill yes)
		(layer "In6.Cu")
		(net "M_C_CPU1_SA_DQ<10>")
	)
	(gr_poly
		(pts
			(xy 86.913212 -244.127274) (xy 86.866222 -243.974874) (xy 86.604602 -243.974874) (xy 86.557612 -244.127274)
			(xy 86.557612 -244.17147) (xy 86.913212 -244.17147)
		)
		(stroke
			(width 0)
			(type solid)
		)
		(fill yes)
		(layer "In6.Cu")
		(net "M_C_CPU1_SB_DQ<2>")
	)
	(gr_poly
		(pts
			(xy 86.913466 -247.382538) (xy 86.866476 -247.230138) (xy 86.604856 -247.230138) (xy 86.557866 -247.382538)
			(xy 86.557866 -247.426988) (xy 86.913466 -247.426988)
		)
		(stroke
			(width 0)
			(type solid)
		)
		(fill yes)
		(layer "In6.Cu")
		(net "M_A_CPU1_SB_RSP<1>")
	)
	(gr_poly
		(pts
			(xy 86.913466 -245.754906) (xy 86.866476 -245.602506) (xy 86.604856 -245.602506) (xy 86.557866 -245.754906)
			(xy 86.557866 -245.799356) (xy 86.913466 -245.799356)
		)
		(stroke
			(width 0)
			(type solid)
		)
		(fill yes)
		(layer "In6.Cu")
		(net "M_D_CPU1_SB_CS_N<3>")
	)
	(gr_poly
		(pts
			(xy 86.913466 -240.871502) (xy 86.866476 -240.719102) (xy 86.604856 -240.719102) (xy 86.557866 -240.871502)
			(xy 86.557866 -240.915952) (xy 86.913466 -240.915952)
		)
		(stroke
			(width 0)
			(type solid)
		)
		(fill yes)
		(layer "In6.Cu")
		(net "M_C_CPU1_SB_DQ<6>")
	)
	(gr_poly
		(pts
			(xy 86.913466 -232.732834) (xy 86.866476 -232.580434) (xy 86.604856 -232.580434) (xy 86.557866 -232.732834)
			(xy 86.557866 -232.777284) (xy 86.913466 -232.777284)
		)
		(stroke
			(width 0)
			(type solid)
		)
		(fill yes)
		(layer "In6.Cu")
		(net "M_D_CPU1_SB_DQ<19>")
	)
	(gr_poly
		(pts
			(xy 86.913466 -232.323894) (xy 86.913466 -232.279698) (xy 86.557866 -232.279698) (xy 86.557866 -232.323894)
			(xy 86.604856 -232.476294) (xy 86.866476 -232.476294)
		)
		(stroke
			(width 0)
			(type solid)
		)
		(fill yes)
		(layer "In6.Cu")
		(net "M_D_CPU1_SB_DQS_DP<2>")
	)
	(gr_poly
		(pts
			(xy 86.913466 -231.105202) (xy 86.866476 -230.952802) (xy 86.604856 -230.952802) (xy 86.557866 -231.105202)
			(xy 86.557866 -231.149398) (xy 86.913466 -231.149398)
		)
		(stroke
			(width 0)
			(type solid)
		)
		(fill yes)
		(layer "In6.Cu")
		(net "M_D_CPU1_SB_DQS_DP<7>")
	)
	(gr_poly
		(pts
			(xy 86.913466 -224.593658) (xy 86.866476 -224.441258) (xy 86.604856 -224.441258) (xy 86.557866 -224.593658)
			(xy 86.557866 -224.638108) (xy 86.913466 -224.638108)
		)
		(stroke
			(width 0)
			(type solid)
		)
		(fill yes)
		(layer "In6.Cu")
		(net "M_C_CPU1_SB_DQS_DP<8>")
	)
	(gr_poly
		(pts
			(xy 86.913466 -224.185226) (xy 86.913466 -224.140776) (xy 86.557866 -224.140776) (xy 86.557866 -224.185226)
			(xy 86.604856 -224.337626) (xy 86.866476 -224.337626)
		)
		(stroke
			(width 0)
			(type solid)
		)
		(fill yes)
		(layer "In6.Cu")
		(net "M_C_CPU1_SB_DQ<28>")
	)
	(gr_poly
		(pts
			(xy 86.913466 -222.966026) (xy 86.866476 -222.813626) (xy 86.604856 -222.813626) (xy 86.557866 -222.966026)
			(xy 86.557866 -223.010222) (xy 86.913466 -223.010222)
		)
		(stroke
			(width 0)
			(type solid)
		)
		(fill yes)
		(layer "In6.Cu")
		(net "M_C_CPU1_SB_DQ<29>")
	)
	(gr_poly
		(pts
			(xy 86.917276 -279.523444) (xy 86.878922 -279.501346) (xy 86.723474 -279.465786) (xy 86.592664 -279.692354)
			(xy 86.701122 -279.809194) (xy 86.739476 -279.831292)
		)
		(stroke
			(width 0)
			(type solid)
		)
		(fill yes)
		(layer "In6.Cu")
		(net "M_D_CPU1_SA_DQ<2>")
	)
	(gr_poly
		(pts
			(xy 86.918292 -276.265386) (xy 86.879938 -276.243288) (xy 86.72449 -276.207728) (xy 86.59368 -276.434296)
			(xy 86.702138 -276.551136) (xy 86.740492 -276.573234)
		)
		(stroke
			(width 0)
			(type solid)
		)
		(fill yes)
		(layer "In6.Cu")
		(net "M_D_CPU1_SA_DQS_DP<5>")
	)
	(gr_poly
		(pts
			(xy 86.919308 -269.752826) (xy 86.880954 -269.730728) (xy 86.725506 -269.695168) (xy 86.594696 -269.921736)
			(xy 86.703154 -270.038576) (xy 86.741508 -270.060674)
		)
		(stroke
			(width 0)
			(type solid)
		)
		(fill yes)
		(layer "In6.Cu")
		(net "M_C_CPU1_SA_DQS_DP<6>")
	)
	(gr_poly
		(pts
			(xy 86.919308 -237.616238) (xy 86.872318 -237.463838) (xy 86.610698 -237.463838) (xy 86.563708 -237.616238)
			(xy 86.563708 -237.660434) (xy 86.919308 -237.660434)
		)
		(stroke
			(width 0)
			(type solid)
		)
		(fill yes)
		(layer "In6.Cu")
		(net "M_C_CPU1_SB_DQS_DN<1>")
	)
	(gr_poly
		(pts
			(xy 86.919308 -234.360466) (xy 86.872318 -234.208066) (xy 86.610698 -234.208066) (xy 86.563708 -234.360466)
			(xy 86.563708 -234.404662) (xy 86.919308 -234.404662)
		)
		(stroke
			(width 0)
			(type solid)
		)
		(fill yes)
		(layer "In6.Cu")
		(net "M_C_CPU1_SB_DQ<15>")
	)
	(gr_poly
		(pts
			(xy 86.919308 -226.221798) (xy 86.872318 -226.069398) (xy 86.610698 -226.069398) (xy 86.563708 -226.221798)
			(xy 86.563708 -226.265994) (xy 86.919308 -226.265994)
		)
		(stroke
			(width 0)
			(type solid)
		)
		(fill yes)
		(layer "In6.Cu")
		(net "M_C_CPU1_SB_DQ<27>")
	)
	(gr_poly
		(pts
			(xy 86.921848 -245.346474) (xy 86.921848 -245.302278) (xy 86.566248 -245.302278) (xy 86.566248 -245.346474)
			(xy 86.613238 -245.498874) (xy 86.874858 -245.498874)
		)
		(stroke
			(width 0)
			(type solid)
		)
		(fill yes)
		(layer "In6.Cu")
		(net "M_D_CPU1_SB_CS_N<0>")
	)
	(gr_poly
		(pts
			(xy 86.921848 -239.243362) (xy 86.874858 -239.090962) (xy 86.613238 -239.090962) (xy 86.566248 -239.243362)
			(xy 86.566248 -239.287812) (xy 86.921848 -239.287812)
		)
		(stroke
			(width 0)
			(type solid)
		)
		(fill yes)
		(layer "In6.Cu")
		(net "M_C_CPU1_SB_DQ<10>")
	)
	(gr_poly
		(pts
			(xy 86.921848 -230.69677) (xy 86.921848 -230.65232) (xy 86.566248 -230.65232) (xy 86.566248 -230.69677)
			(xy 86.613238 -230.84917) (xy 86.874858 -230.84917)
		)
		(stroke
			(width 0)
			(type solid)
		)
		(fill yes)
		(layer "In6.Cu")
		(net "M_D_CPU1_SB_DQ<20>")
	)
	(gr_poly
		(pts
			(xy 86.992714 -249.070876) (xy 86.884256 -248.954036) (xy 86.845902 -248.931938) (xy 86.668102 -249.239786)
			(xy 86.706456 -249.261884) (xy 86.861904 -249.297444)
		)
		(stroke
			(width 0)
			(type solid)
		)
		(fill yes)
		(layer "In6.Cu")
		(net "M_A_CPU1_SB_RSP<0>")
	)
	(gr_poly
		(pts
			(xy 87.014558 -274.876514) (xy 87.014558 -274.832318) (xy 86.658958 -274.832318) (xy 86.658958 -274.876514)
			(xy 86.705948 -275.028914) (xy 86.967568 -275.028914)
		)
		(stroke
			(width 0)
			(type solid)
		)
		(fill yes)
		(layer "In6.Cu")
		(net "M_D_CPU1_SA_DQ<5>")
	)
	(gr_poly
		(pts
			(xy 87.014812 -272.029174) (xy 86.967822 -271.876774) (xy 86.706202 -271.876774) (xy 86.659212 -272.029174)
			(xy 86.659212 -272.073624) (xy 87.014812 -272.073624)
		)
		(stroke
			(width 0)
			(type solid)
		)
		(fill yes)
		(layer "In6.Cu")
		(net "M_C_CPU1_SA_DQ<11>")
	)
	(gr_poly
		(pts
			(xy 87.02294 -275.284946) (xy 86.97595 -275.132546) (xy 86.71433 -275.132546) (xy 86.66734 -275.284946)
			(xy 86.66734 -275.329396) (xy 87.02294 -275.329396)
		)
		(stroke
			(width 0)
			(type solid)
		)
		(fill yes)
		(layer "In6.Cu")
		(net "M_D_CPU1_SA_DQ<6>")
	)
	(gr_poly
		(pts
			(xy 87.023194 -278.540718) (xy 86.976204 -278.388318) (xy 86.714584 -278.388318) (xy 86.667594 -278.540718)
			(xy 86.667594 -278.585168) (xy 87.023194 -278.585168)
		)
		(stroke
			(width 0)
			(type solid)
		)
		(fill yes)
		(layer "In6.Cu")
		(net "M_D_CPU1_SA_DQ<3>")
	)
	(gr_poly
		(pts
			(xy 87.023194 -268.77391) (xy 86.976204 -268.62151) (xy 86.714584 -268.62151) (xy 86.667594 -268.77391)
			(xy 86.667594 -268.81836) (xy 87.023194 -268.81836)
		)
		(stroke
			(width 0)
			(type solid)
		)
		(fill yes)
		(layer "In6.Cu")
		(net "M_C_CPU1_SA_DQ<14>")
	)
	(gr_poly
		(pts
			(xy 87.023194 -268.365478) (xy 87.023194 -268.321028) (xy 86.667594 -268.321028) (xy 86.667594 -268.365478)
			(xy 86.714584 -268.517878) (xy 86.976204 -268.517878)
		)
		(stroke
			(width 0)
			(type solid)
		)
		(fill yes)
		(layer "In6.Cu")
		(net "M_C_CPU1_SA_DQ<13>")
	)
	(gr_poly
		(pts
			(xy 87.023194 -267.146278) (xy 86.976204 -266.993878) (xy 86.714584 -266.993878) (xy 86.667594 -267.146278)
			(xy 86.667594 -267.190474) (xy 87.023194 -267.190474)
		)
		(stroke
			(width 0)
			(type solid)
		)
		(fill yes)
		(layer "In6.Cu")
		(net "M_C_CPU1_SA_DQ<26>")
	)
	(gr_poly
		(pts
			(xy 87.023194 -266.737846) (xy 87.023194 -266.693396) (xy 86.667594 -266.693396) (xy 86.667594 -266.737846)
			(xy 86.714584 -266.890246) (xy 86.976204 -266.890246)
		)
		(stroke
			(width 0)
			(type solid)
		)
		(fill yes)
		(layer "In6.Cu")
		(net "M_C_CPU1_SA_DQ<25>")
	)
	(gr_poly
		(pts
			(xy 87.023194 -265.518646) (xy 86.976204 -265.366246) (xy 86.714584 -265.366246) (xy 86.667594 -265.518646)
			(xy 86.667594 -265.562842) (xy 87.023194 -265.562842)
		)
		(stroke
			(width 0)
			(type solid)
		)
		(fill yes)
		(layer "In6.Cu")
		(net "M_C_CPU1_SA_DQS_DN<3>")
	)
	(gr_poly
		(pts
			(xy 87.023194 -265.109706) (xy 87.023194 -265.06551) (xy 86.667594 -265.06551) (xy 86.667594 -265.109706)
			(xy 86.714584 -265.262106) (xy 86.976204 -265.262106)
		)
		(stroke
			(width 0)
			(type solid)
		)
		(fill yes)
		(layer "In6.Cu")
		(net "M_C_CPU1_SA_DQS_DN<8>")
	)
	(gr_poly
		(pts
			(xy 87.023194 -263.891014) (xy 86.976204 -263.738614) (xy 86.714584 -263.738614) (xy 86.667594 -263.891014)
			(xy 86.667594 -263.93521) (xy 87.023194 -263.93521)
		)
		(stroke
			(width 0)
			(type solid)
		)
		(fill yes)
		(layer "In6.Cu")
		(net "M_C_CPU1_SA_DQ<30>")
	)
	(gr_poly
		(pts
			(xy 87.023194 -263.482074) (xy 87.023194 -263.437878) (xy 86.667594 -263.437878) (xy 86.667594 -263.482074)
			(xy 86.714584 -263.634474) (xy 86.976204 -263.634474)
		)
		(stroke
			(width 0)
			(type solid)
		)
		(fill yes)
		(layer "In6.Cu")
		(net "M_C_CPU1_SA_DQ<29>")
	)
	(gr_poly
		(pts
			(xy 87.023194 -262.262874) (xy 86.976204 -262.110474) (xy 86.714584 -262.110474) (xy 86.667594 -262.262874)
			(xy 86.667594 -262.307324) (xy 87.023194 -262.307324)
		)
		(stroke
			(width 0)
			(type solid)
		)
		(fill yes)
		(layer "In6.Cu")
		(net "M_C_CPU1_SA_CB<0>")
	)
	(gr_poly
		(pts
			(xy 87.023194 -261.854442) (xy 87.023194 -261.809992) (xy 86.667594 -261.809992) (xy 86.667594 -261.854442)
			(xy 86.714584 -262.006842) (xy 86.976204 -262.006842)
		)
		(stroke
			(width 0)
			(type solid)
		)
		(fill yes)
		(layer "In6.Cu")
		(net "M_C_CPU1_SA_CB<3>")
	)
	(gr_poly
		(pts
			(xy 87.023194 -260.635242) (xy 86.976204 -260.482842) (xy 86.714584 -260.482842) (xy 86.667594 -260.635242)
			(xy 86.667594 -260.679438) (xy 87.023194 -260.679438)
		)
		(stroke
			(width 0)
			(type solid)
		)
		(fill yes)
		(layer "In6.Cu")
		(net "M_C_CPU1_SA_DQS_DP<9>")
	)
	(gr_poly
		(pts
			(xy 87.023194 -260.226302) (xy 87.023194 -260.182106) (xy 86.667594 -260.182106) (xy 86.667594 -260.226302)
			(xy 86.714584 -260.378702) (xy 86.976204 -260.378702)
		)
		(stroke
			(width 0)
			(type solid)
		)
		(fill yes)
		(layer "In6.Cu")
		(net "M_C_CPU1_SA_DQS_DP<4>")
	)
	(gr_poly
		(pts
			(xy 87.023194 -259.00761) (xy 86.976204 -258.85521) (xy 86.714584 -258.85521) (xy 86.667594 -259.00761)
			(xy 86.667594 -259.051806) (xy 87.023194 -259.051806)
		)
		(stroke
			(width 0)
			(type solid)
		)
		(fill yes)
		(layer "In6.Cu")
		(net "M_C_CPU1_SA_CB<4>")
	)
	(gr_poly
		(pts
			(xy 87.023194 -258.59867) (xy 87.023194 -258.554474) (xy 86.667594 -258.554474) (xy 86.667594 -258.59867)
			(xy 86.714584 -258.75107) (xy 86.976204 -258.75107)
		)
		(stroke
			(width 0)
			(type solid)
		)
		(fill yes)
		(layer "In6.Cu")
		(net "M_C_CPU1_SA_CB<7>")
	)
	(gr_poly
		(pts
			(xy 87.023194 -256.971038) (xy 87.023194 -256.926588) (xy 86.667594 -256.926588) (xy 86.667594 -256.971038)
			(xy 86.714584 -257.123438) (xy 86.976204 -257.123438)
		)
		(stroke
			(width 0)
			(type solid)
		)
		(fill yes)
		(layer "In6.Cu")
		(net "M_D_CPU1_SA_RSP<0>")
	)
	(gr_poly
		(pts
			(xy 87.023194 -255.751838) (xy 86.976204 -255.599438) (xy 86.714584 -255.599438) (xy 86.667594 -255.751838)
			(xy 86.667594 -255.796288) (xy 87.023194 -255.796288)
		)
		(stroke
			(width 0)
			(type solid)
		)
		(fill yes)
		(layer "In6.Cu")
		(net "M_D_CPU1_SB_RSP<1>")
	)
	(gr_poly
		(pts
			(xy 87.023194 -255.343406) (xy 87.023194 -255.298956) (xy 86.667594 -255.298956) (xy 86.667594 -255.343406)
			(xy 86.714584 -255.495806) (xy 86.976204 -255.495806)
		)
		(stroke
			(width 0)
			(type solid)
		)
		(fill yes)
		(layer "In6.Cu")
		(net "M_C_CPU1_SA_RSP<0>")
	)
	(gr_poly
		(pts
			(xy 87.023194 -254.124206) (xy 86.976204 -253.971806) (xy 86.714584 -253.971806) (xy 86.667594 -254.124206)
			(xy 86.667594 -254.168402) (xy 87.023194 -254.168402)
		)
		(stroke
			(width 0)
			(type solid)
		)
		(fill yes)
		(layer "In6.Cu")
		(net "M_C_CPU1_SB_RSP<1>")
	)
	(gr_poly
		(pts
			(xy 87.031576 -278.132286) (xy 87.031576 -278.08809) (xy 86.675976 -278.08809) (xy 86.675976 -278.132286)
			(xy 86.722966 -278.284686) (xy 86.984586 -278.284686)
		)
		(stroke
			(width 0)
			(type solid)
		)
		(fill yes)
		(layer "In6.Cu")
		(net "M_D_CPU1_SA_DQS_DP<0>")
	)
	(gr_poly
		(pts
			(xy 87.031576 -271.620996) (xy 87.031576 -271.5768) (xy 86.675976 -271.5768) (xy 86.675976 -271.620996)
			(xy 86.722966 -271.773396) (xy 86.984586 -271.773396)
		)
		(stroke
			(width 0)
			(type solid)
		)
		(fill yes)
		(layer "In6.Cu")
		(net "M_C_CPU1_SA_DQS_DP<1>")
	)
	(gr_poly
		(pts
			(xy 87.096092 -280.239978) (xy 86.987634 -280.123138) (xy 86.94928 -280.10104) (xy 86.77148 -280.408888)
			(xy 86.809834 -280.430986) (xy 86.965282 -280.466546)
		)
		(stroke
			(width 0)
			(type solid)
		)
		(fill yes)
		(layer "In6.Cu")
		(net "M_D_CPU1_SA_DQ<0>")
	)
	(gr_poly
		(pts
			(xy 87.098124 -270.46936) (xy 86.989666 -270.35252) (xy 86.951312 -270.330422) (xy 86.773512 -270.63827)
			(xy 86.811866 -270.660368) (xy 86.967314 -270.695928)
		)
		(stroke
			(width 0)
			(type solid)
		)
		(fill yes)
		(layer "In6.Cu")
		(net "M_C_CPU1_SA_DQS_DN<6>")
	)
	(gr_poly
		(pts
			(xy 87.102696 -273.717766) (xy 86.994238 -273.600926) (xy 86.955884 -273.578828) (xy 86.778084 -273.886676)
			(xy 86.816438 -273.908774) (xy 86.971886 -273.944334)
		)
		(stroke
			(width 0)
			(type solid)
		)
		(fill yes)
		(layer "In6.Cu")
		(net "M_C_CPU1_SA_DQ<8>")
	)
	(gr_poly
		(pts
			(xy 87.232744 -235.422694) (xy 87.271098 -235.400596) (xy 87.093298 -235.092748) (xy 87.054944 -235.114846)
			(xy 86.946486 -235.231686) (xy 87.077296 -235.458254)
		)
		(stroke
			(width 0)
			(type solid)
		)
		(fill yes)
		(layer "In6.Cu")
		(net "M_C_CPU1_SB_DQ<13>")
	)
	(gr_poly
		(pts
			(xy 87.234522 -227.286566) (xy 87.272876 -227.264468) (xy 87.095076 -226.95662) (xy 87.056722 -226.978718)
			(xy 86.948264 -227.095558) (xy 87.079074 -227.322126)
		)
		(stroke
			(width 0)
			(type solid)
		)
		(fill yes)
		(layer "In6.Cu")
		(net "M_C_CPU1_SB_DQ<25>")
	)
	(gr_poly
		(pts
			(xy 87.240364 -228.924358) (xy 87.278718 -228.90226) (xy 87.100918 -228.594412) (xy 87.062564 -228.61651)
			(xy 86.954106 -228.73335) (xy 87.084916 -228.959918)
		)
		(stroke
			(width 0)
			(type solid)
		)
		(fill yes)
		(layer "In6.Cu")
		(net "M_C_CPU1_SB_DQ<26>")
	)
	(gr_poly
		(pts
			(xy 87.348568 -228.302058) (xy 87.457026 -228.185218) (xy 87.326216 -227.95865) (xy 87.170768 -227.99421)
			(xy 87.132414 -228.016308) (xy 87.310214 -228.324156)
		)
		(stroke
			(width 0)
			(type solid)
		)
		(fill yes)
		(layer "In6.Cu")
		(net "M_C_CPU1_SB_DQ<24>")
	)
	(gr_poly
		(pts
			(xy 87.354156 -234.822492) (xy 87.462614 -234.705652) (xy 87.331804 -234.479084) (xy 87.176356 -234.514644)
			(xy 87.138002 -234.536742) (xy 87.315802 -234.84459)
		)
		(stroke
			(width 0)
			(type solid)
		)
		(fill yes)
		(layer "In6.Cu")
		(net "M_C_CPU1_SB_DQ<15>")
	)
	(gr_poly
		(pts
			(xy 87.355934 -226.686364) (xy 87.464392 -226.569524) (xy 87.333582 -226.342956) (xy 87.178134 -226.378516)
			(xy 87.13978 -226.400614) (xy 87.31758 -226.708462)
		)
		(stroke
			(width 0)
			(type solid)
		)
		(fill yes)
		(layer "In6.Cu")
		(net "M_C_CPU1_SB_DQ<27>")
	)
	(gr_poly
		(pts
			(xy 87.373206 -230.290878) (xy 87.326216 -230.138478) (xy 87.064596 -230.138478) (xy 87.017606 -230.290878)
			(xy 87.017606 -230.335074) (xy 87.373206 -230.335074)
		)
		(stroke
			(width 0)
			(type solid)
		)
		(fill yes)
		(layer "In6.Cu")
		(net "M_D_CPU1_SB_DQ<22>")
	)
	(gr_poly
		(pts
			(xy 87.37473 -244.940582) (xy 87.32774 -244.788182) (xy 87.06612 -244.788182) (xy 87.01913 -244.940582)
			(xy 87.01913 -244.985032) (xy 87.37473 -244.985032)
		)
		(stroke
			(width 0)
			(type solid)
		)
		(fill yes)
		(layer "In6.Cu")
		(net "M_D_CPU1_SB_CS_N<1>")
	)
	(gr_poly
		(pts
			(xy 87.37473 -239.649254) (xy 87.37473 -239.604804) (xy 87.01913 -239.604804) (xy 87.01913 -239.649254)
			(xy 87.06612 -239.801654) (xy 87.32774 -239.801654)
		)
		(stroke
			(width 0)
			(type solid)
		)
		(fill yes)
		(layer "In6.Cu")
		(net "M_C_CPU1_SB_DQ<8>")
	)
	(gr_poly
		(pts
			(xy 87.375492 -233.138218) (xy 87.375492 -233.093768) (xy 87.019892 -233.093768) (xy 87.019892 -233.138218)
			(xy 87.066882 -233.290618) (xy 87.328502 -233.290618)
		)
		(stroke
			(width 0)
			(type solid)
		)
		(fill yes)
		(layer "In6.Cu")
		(net "M_D_CPU1_SB_DQ<17>")
	)
	(gr_poly
		(pts
			(xy 87.383112 -244.53215) (xy 87.383112 -244.487954) (xy 87.027512 -244.487954) (xy 87.027512 -244.53215)
			(xy 87.074502 -244.68455) (xy 87.336122 -244.68455)
		)
		(stroke
			(width 0)
			(type solid)
		)
		(fill yes)
		(layer "In6.Cu")
		(net "M_C_CPU1_SB_DQ<0>")
	)
	(gr_poly
		(pts
			(xy 87.383366 -248.196354) (xy 87.336376 -248.043954) (xy 87.074756 -248.043954) (xy 87.027766 -248.196354)
			(xy 87.027766 -248.240804) (xy 87.383366 -248.240804)
		)
		(stroke
			(width 0)
			(type solid)
		)
		(fill yes)
		(layer "In6.Cu")
		(net "M_A_CPU1_SA_RSP<0>")
	)
	(gr_poly
		(pts
			(xy 87.383366 -247.787922) (xy 87.383366 -247.743472) (xy 87.027766 -247.743472) (xy 87.027766 -247.787922)
			(xy 87.074756 -247.940322) (xy 87.336376 -247.940322)
		)
		(stroke
			(width 0)
			(type solid)
		)
		(fill yes)
		(layer "In6.Cu")
		(net "M_A_CPU1_SA_RSP<1>")
	)
	(gr_poly
		(pts
			(xy 87.383366 -246.16029) (xy 87.383366 -246.11584) (xy 87.027766 -246.11584) (xy 87.027766 -246.16029)
			(xy 87.074756 -246.31269) (xy 87.336376 -246.31269)
		)
		(stroke
			(width 0)
			(type solid)
		)
		(fill yes)
		(layer "In6.Cu")
		(net "M_D_CPU1_SB_CS_N<2>")
	)
	(gr_poly
		(pts
			(xy 87.383366 -241.276886) (xy 87.383366 -241.232436) (xy 87.027766 -241.232436) (xy 87.027766 -241.276886)
			(xy 87.074756 -241.429286) (xy 87.336376 -241.429286)
		)
		(stroke
			(width 0)
			(type solid)
		)
		(fill yes)
		(layer "In6.Cu")
		(net "M_C_CPU1_SB_DQ<4>")
	)
	(gr_poly
		(pts
			(xy 87.383366 -236.393482) (xy 87.383366 -236.349286) (xy 87.027766 -236.349286) (xy 87.027766 -236.393482)
			(xy 87.074756 -236.545882) (xy 87.336376 -236.545882)
		)
		(stroke
			(width 0)
			(type solid)
		)
		(fill yes)
		(layer "In6.Cu")
		(net "M_C_CPU1_SB_DQ<12>")
	)
	(gr_poly
		(pts
			(xy 87.383366 -231.919018) (xy 87.336376 -231.766618) (xy 87.074756 -231.766618) (xy 87.027766 -231.919018)
			(xy 87.027766 -231.963214) (xy 87.383366 -231.963214)
		)
		(stroke
			(width 0)
			(type solid)
		)
		(fill yes)
		(layer "In6.Cu")
		(net "M_D_CPU1_SB_DQS_DN<2>")
	)
	(gr_poly
		(pts
			(xy 87.383366 -231.510078) (xy 87.383366 -231.465882) (xy 87.027766 -231.465882) (xy 87.027766 -231.510078)
			(xy 87.074756 -231.662478) (xy 87.336376 -231.662478)
		)
		(stroke
			(width 0)
			(type solid)
		)
		(fill yes)
		(layer "In6.Cu")
		(net "M_D_CPU1_SB_DQS_DN<7>")
	)
	(gr_poly
		(pts
			(xy 87.383366 -224.999042) (xy 87.383366 -224.954592) (xy 87.027766 -224.954592) (xy 87.027766 -224.999042)
			(xy 87.074756 -225.151442) (xy 87.336376 -225.151442)
		)
		(stroke
			(width 0)
			(type solid)
		)
		(fill yes)
		(layer "In6.Cu")
		(net "M_C_CPU1_SB_DQS_DN<8>")
	)
	(gr_poly
		(pts
			(xy 87.383366 -223.779842) (xy 87.336376 -223.627442) (xy 87.074756 -223.627442) (xy 87.027766 -223.779842)
			(xy 87.027766 -223.824292) (xy 87.383366 -223.824292)
		)
		(stroke
			(width 0)
			(type solid)
		)
		(fill yes)
		(layer "In6.Cu")
		(net "M_C_CPU1_SB_DQ<30>")
	)
	(gr_poly
		(pts
			(xy 87.383366 -223.37141) (xy 87.383366 -223.32696) (xy 87.027766 -223.32696) (xy 87.027766 -223.37141)
			(xy 87.074756 -223.52381) (xy 87.336376 -223.52381)
		)
		(stroke
			(width 0)
			(type solid)
		)
		(fill yes)
		(layer "In6.Cu")
		(net "M_C_CPU1_SB_DQ<31>")
	)
	(gr_poly
		(pts
			(xy 87.387176 -273.826224) (xy 87.348822 -273.804126) (xy 87.193374 -273.768566) (xy 87.062564 -273.995134)
			(xy 87.171022 -274.111974) (xy 87.209376 -274.134072)
		)
		(stroke
			(width 0)
			(type solid)
		)
		(fill yes)
		(layer "In6.Cu")
		(net "M_D_CPU1_SA_DQ<7>")
	)
	(gr_poly
		(pts
			(xy 87.387176 -270.570706) (xy 87.348822 -270.548608) (xy 87.193374 -270.513048) (xy 87.062564 -270.739616)
			(xy 87.171022 -270.856456) (xy 87.209376 -270.878554)
		)
		(stroke
			(width 0)
			(type solid)
		)
		(fill yes)
		(layer "In6.Cu")
		(net "M_C_CPU1_SA_DQS_DN<1>")
	)
	(gr_poly
		(pts
			(xy 87.389208 -238.021622) (xy 87.389208 -237.977172) (xy 87.033608 -237.977172) (xy 87.033608 -238.021622)
			(xy 87.080598 -238.174022) (xy 87.342218 -238.174022)
		)
		(stroke
			(width 0)
			(type solid)
		)
		(fill yes)
		(layer "In6.Cu")
		(net "M_C_CPU1_SB_DQS_DP<1>")
	)
	(gr_poly
		(pts
			(xy 87.389462 -238.430054) (xy 87.342472 -238.277654) (xy 87.080852 -238.277654) (xy 87.033862 -238.430054)
			(xy 87.033862 -238.47425) (xy 87.389462 -238.47425)
		)
		(stroke
			(width 0)
			(type solid)
		)
		(fill yes)
		(layer "In6.Cu")
		(net "M_C_CPU1_SB_DQ<11>")
	)
	(gr_poly
		(pts
			(xy 87.39124 -233.54665) (xy 87.34425 -233.39425) (xy 87.08263 -233.39425) (xy 87.03564 -233.54665)
			(xy 87.03564 -233.5911) (xy 87.39124 -233.5911)
		)
		(stroke
			(width 0)
			(type solid)
		)
		(fill yes)
		(layer "In6.Cu")
		(net "M_D_CPU1_SB_DQ<18>")
	)
	(gr_poly
		(pts
			(xy 87.391748 -243.31295) (xy 87.344758 -243.16055) (xy 87.083138 -243.16055) (xy 87.036148 -243.31295)
			(xy 87.036148 -243.3574) (xy 87.391748 -243.3574)
		)
		(stroke
			(width 0)
			(type solid)
		)
		(fill yes)
		(layer "In6.Cu")
		(net "M_C_CPU1_SB_DQ<3>")
	)
	(gr_poly
		(pts
			(xy 87.391748 -242.905026) (xy 87.391748 -242.860576) (xy 87.036148 -242.860576) (xy 87.036148 -242.905026)
			(xy 87.083138 -243.057426) (xy 87.344758 -243.057426)
		)
		(stroke
			(width 0)
			(type solid)
		)
		(fill yes)
		(layer "In6.Cu")
		(net "M_C_CPU1_SB_DQS_DP<0>")
	)
	(gr_poly
		(pts
			(xy 87.391748 -241.685318) (xy 87.344758 -241.532918) (xy 87.083138 -241.532918) (xy 87.036148 -241.685318)
			(xy 87.036148 -241.729514) (xy 87.391748 -241.729514)
		)
		(stroke
			(width 0)
			(type solid)
		)
		(fill yes)
		(layer "In6.Cu")
		(net "M_C_CPU1_SB_DQS_DP<5>")
	)
	(gr_poly
		(pts
			(xy 87.391748 -236.801914) (xy 87.344758 -236.649514) (xy 87.083138 -236.649514) (xy 87.036148 -236.801914)
			(xy 87.036148 -236.846364) (xy 87.391748 -236.846364)
		)
		(stroke
			(width 0)
			(type solid)
		)
		(fill yes)
		(layer "In6.Cu")
		(net "M_C_CPU1_SB_DQS_DP<6>")
	)
	(gr_poly
		(pts
			(xy 87.391748 -225.407474) (xy 87.344758 -225.255074) (xy 87.083138 -225.255074) (xy 87.036148 -225.407474)
			(xy 87.036148 -225.45167) (xy 87.391748 -225.45167)
		)
		(stroke
			(width 0)
			(type solid)
		)
		(fill yes)
		(layer "In6.Cu")
		(net "M_C_CPU1_SB_DQS_DN<3>")
	)
	(gr_poly
		(pts
			(xy 87.393018 -240.057686) (xy 87.346028 -239.905286) (xy 87.084408 -239.905286) (xy 87.037418 -240.057686)
			(xy 87.037418 -240.101882) (xy 87.393018 -240.101882)
		)
		(stroke
			(width 0)
			(type solid)
		)
		(fill yes)
		(layer "In6.Cu")
		(net "M_C_CPU1_SB_DQ<7>")
	)
	(gr_poly
		(pts
			(xy 87.393272 -229.882954) (xy 87.393272 -229.838504) (xy 87.037672 -229.838504) (xy 87.037672 -229.882954)
			(xy 87.084662 -230.035354) (xy 87.346282 -230.035354)
		)
		(stroke
			(width 0)
			(type solid)
		)
		(fill yes)
		(layer "In6.Cu")
		(net "M_D_CPU1_SB_DQ<21>")
	)
	(gr_poly
		(pts
			(xy 87.484458 -277.726902) (xy 87.437468 -277.574502) (xy 87.175848 -277.574502) (xy 87.128858 -277.726902)
			(xy 87.128858 -277.771098) (xy 87.484458 -277.771098)
		)
		(stroke
			(width 0)
			(type solid)
		)
		(fill yes)
		(layer "In6.Cu")
		(net "M_D_CPU1_SA_DQS_DN<0>")
	)
	(gr_poly
		(pts
			(xy 87.484458 -276.098762) (xy 87.437468 -275.946362) (xy 87.175848 -275.946362) (xy 87.128858 -276.098762)
			(xy 87.128858 -276.143212) (xy 87.484458 -276.143212)
		)
		(stroke
			(width 0)
			(type solid)
		)
		(fill yes)
		(layer "In6.Cu")
		(net "M_D_CPU1_SA_DQS_DP<5>")
	)
	(gr_poly
		(pts
			(xy 87.49284 -275.690584) (xy 87.49284 -275.646134) (xy 87.13724 -275.646134) (xy 87.13724 -275.690584)
			(xy 87.18423 -275.842984) (xy 87.44585 -275.842984)
		)
		(stroke
			(width 0)
			(type solid)
		)
		(fill yes)
		(layer "In6.Cu")
		(net "M_D_CPU1_SA_DQ<4>")
	)
	(gr_poly
		(pts
			(xy 87.493094 -279.354788) (xy 87.446104 -279.202388) (xy 87.184484 -279.202388) (xy 87.137494 -279.354788)
			(xy 87.137494 -279.398984) (xy 87.493094 -279.398984)
		)
		(stroke
			(width 0)
			(type solid)
		)
		(fill yes)
		(layer "In6.Cu")
		(net "M_D_CPU1_SA_DQ<2>")
	)
	(gr_poly
		(pts
			(xy 87.493094 -278.945848) (xy 87.493094 -278.901652) (xy 87.137494 -278.901652) (xy 87.137494 -278.945848)
			(xy 87.184484 -279.098248) (xy 87.446104 -279.098248)
		)
		(stroke
			(width 0)
			(type solid)
		)
		(fill yes)
		(layer "In6.Cu")
		(net "M_D_CPU1_SA_DQ<1>")
	)
	(gr_poly
		(pts
			(xy 87.493094 -269.587726) (xy 87.446104 -269.435326) (xy 87.184484 -269.435326) (xy 87.137494 -269.587726)
			(xy 87.137494 -269.632176) (xy 87.493094 -269.632176)
		)
		(stroke
			(width 0)
			(type solid)
		)
		(fill yes)
		(layer "In6.Cu")
		(net "M_C_CPU1_SA_DQS_DP<6>")
	)
	(gr_poly
		(pts
			(xy 87.493094 -269.179294) (xy 87.493094 -269.134844) (xy 87.137494 -269.134844) (xy 87.137494 -269.179294)
			(xy 87.184484 -269.331694) (xy 87.446104 -269.331694)
		)
		(stroke
			(width 0)
			(type solid)
		)
		(fill yes)
		(layer "In6.Cu")
		(net "M_C_CPU1_SA_DQ<12>")
	)
	(gr_poly
		(pts
			(xy 87.493094 -267.960094) (xy 87.446104 -267.807694) (xy 87.184484 -267.807694) (xy 87.137494 -267.960094)
			(xy 87.137494 -268.004544) (xy 87.493094 -268.004544)
		)
		(stroke
			(width 0)
			(type solid)
		)
		(fill yes)
		(layer "In6.Cu")
		(net "M_C_CPU1_SA_DQ<15>")
	)
	(gr_poly
		(pts
			(xy 87.493094 -267.551662) (xy 87.493094 -267.507212) (xy 87.137494 -267.507212) (xy 87.137494 -267.551662)
			(xy 87.184484 -267.704062) (xy 87.446104 -267.704062)
		)
		(stroke
			(width 0)
			(type solid)
		)
		(fill yes)
		(layer "In6.Cu")
		(net "M_C_CPU1_SA_DQ<24>")
	)
	(gr_poly
		(pts
			(xy 87.493094 -266.332462) (xy 87.446104 -266.180062) (xy 87.184484 -266.180062) (xy 87.137494 -266.332462)
			(xy 87.137494 -266.376658) (xy 87.493094 -266.376658)
		)
		(stroke
			(width 0)
			(type solid)
		)
		(fill yes)
		(layer "In6.Cu")
		(net "M_C_CPU1_SA_DQ<27>")
	)
	(gr_poly
		(pts
			(xy 87.493094 -265.92403) (xy 87.493094 -265.87958) (xy 87.137494 -265.87958) (xy 87.137494 -265.92403)
			(xy 87.184484 -266.07643) (xy 87.446104 -266.07643)
		)
		(stroke
			(width 0)
			(type solid)
		)
		(fill yes)
		(layer "In6.Cu")
		(net "M_C_CPU1_SA_DQS_DP<3>")
	)
	(gr_poly
		(pts
			(xy 87.493094 -264.70483) (xy 87.446104 -264.55243) (xy 87.184484 -264.55243) (xy 87.137494 -264.70483)
			(xy 87.137494 -264.749026) (xy 87.493094 -264.749026)
		)
		(stroke
			(width 0)
			(type solid)
		)
		(fill yes)
		(layer "In6.Cu")
		(net "M_C_CPU1_SA_DQS_DP<8>")
	)
	(gr_poly
		(pts
			(xy 87.493094 -264.29589) (xy 87.493094 -264.251694) (xy 87.137494 -264.251694) (xy 87.137494 -264.29589)
			(xy 87.184484 -264.44829) (xy 87.446104 -264.44829)
		)
		(stroke
			(width 0)
			(type solid)
		)
		(fill yes)
		(layer "In6.Cu")
		(net "M_C_CPU1_SA_DQ<28>")
	)
	(gr_poly
		(pts
			(xy 87.493094 -263.07669) (xy 87.446104 -262.92429) (xy 87.184484 -262.92429) (xy 87.137494 -263.07669)
			(xy 87.137494 -263.12114) (xy 87.493094 -263.12114)
		)
		(stroke
			(width 0)
			(type solid)
		)
		(fill yes)
		(layer "In6.Cu")
		(net "M_C_CPU1_SA_DQ<31>")
	)
	(gr_poly
		(pts
			(xy 87.493094 -262.668258) (xy 87.493094 -262.623808) (xy 87.137494 -262.623808) (xy 87.137494 -262.668258)
			(xy 87.184484 -262.820658) (xy 87.446104 -262.820658)
		)
		(stroke
			(width 0)
			(type solid)
		)
		(fill yes)
		(layer "In6.Cu")
		(net "M_C_CPU1_SA_CB<2>")
	)
	(gr_poly
		(pts
			(xy 87.493094 -261.449058) (xy 87.446104 -261.296658) (xy 87.184484 -261.296658) (xy 87.137494 -261.449058)
			(xy 87.137494 -261.493508) (xy 87.493094 -261.493508)
		)
		(stroke
			(width 0)
			(type solid)
		)
		(fill yes)
		(layer "In6.Cu")
		(net "M_C_CPU1_SA_CB<1>")
	)
	(gr_poly
		(pts
			(xy 87.493094 -261.040626) (xy 87.493094 -260.996176) (xy 87.137494 -260.996176) (xy 87.137494 -261.040626)
			(xy 87.184484 -261.193026) (xy 87.446104 -261.193026)
		)
		(stroke
			(width 0)
			(type solid)
		)
		(fill yes)
		(layer "In6.Cu")
		(net "M_C_CPU1_SA_DQS_DN<9>")
	)
	(gr_poly
		(pts
			(xy 87.493094 -259.821426) (xy 87.446104 -259.669026) (xy 87.184484 -259.669026) (xy 87.137494 -259.821426)
			(xy 87.137494 -259.865622) (xy 87.493094 -259.865622)
		)
		(stroke
			(width 0)
			(type solid)
		)
		(fill yes)
		(layer "In6.Cu")
		(net "M_C_CPU1_SA_DQS_DN<4>")
	)
	(gr_poly
		(pts
			(xy 87.493094 -259.412486) (xy 87.493094 -259.36829) (xy 87.137494 -259.36829) (xy 87.137494 -259.412486)
			(xy 87.184484 -259.564886) (xy 87.446104 -259.564886)
		)
		(stroke
			(width 0)
			(type solid)
		)
		(fill yes)
		(layer "In6.Cu")
		(net "M_C_CPU1_SA_CB<6>")
	)
	(gr_poly
		(pts
			(xy 87.493094 -258.193286) (xy 87.446104 -258.040886) (xy 87.184484 -258.040886) (xy 87.137494 -258.193286)
			(xy 87.137494 -258.237736) (xy 87.493094 -258.237736)
		)
		(stroke
			(width 0)
			(type solid)
		)
		(fill yes)
		(layer "In6.Cu")
		(net "M_C_CPU1_SA_CB<5>")
	)
	(gr_poly
		(pts
			(xy 87.493094 -256.565654) (xy 87.446104 -256.413254) (xy 87.184484 -256.413254) (xy 87.137494 -256.565654)
			(xy 87.137494 -256.610104) (xy 87.493094 -256.610104)
		)
		(stroke
			(width 0)
			(type solid)
		)
		(fill yes)
		(layer "In6.Cu")
		(net "M_D_CPU1_SB_RSP<0>")
	)
	(gr_poly
		(pts
			(xy 87.493094 -256.157222) (xy 87.493094 -256.112772) (xy 87.137494 -256.112772) (xy 87.137494 -256.157222)
			(xy 87.184484 -256.309622) (xy 87.446104 -256.309622)
		)
		(stroke
			(width 0)
			(type solid)
		)
		(fill yes)
		(layer "In6.Cu")
		(net "M_D_CPU1_SA_RSP<1>")
	)
	(gr_poly
		(pts
			(xy 87.493094 -254.938022) (xy 87.446104 -254.785622) (xy 87.184484 -254.785622) (xy 87.137494 -254.938022)
			(xy 87.137494 -254.982218) (xy 87.493094 -254.982218)
		)
		(stroke
			(width 0)
			(type solid)
		)
		(fill yes)
		(layer "In6.Cu")
		(net "M_C_CPU1_SB_RSP<0>")
	)
	(gr_poly
		(pts
			(xy 87.493094 -254.529082) (xy 87.493094 -254.484886) (xy 87.137494 -254.484886) (xy 87.137494 -254.529082)
			(xy 87.184484 -254.681482) (xy 87.446104 -254.681482)
		)
		(stroke
			(width 0)
			(type solid)
		)
		(fill yes)
		(layer "In6.Cu")
		(net "M_C_CPU1_SA_RSP<1>")
	)
	(gr_poly
		(pts
			(xy 87.49919 -272.843498) (xy 87.4522 -272.691098) (xy 87.19058 -272.691098) (xy 87.14359 -272.843498)
			(xy 87.14359 -272.887948) (xy 87.49919 -272.887948)
		)
		(stroke
			(width 0)
			(type solid)
		)
		(fill yes)
		(layer "In6.Cu")
		(net "M_C_CPU1_SA_DQ<10>")
	)
	(gr_poly
		(pts
			(xy 87.49919 -272.435066) (xy 87.49919 -272.390616) (xy 87.14359 -272.390616) (xy 87.14359 -272.435066)
			(xy 87.19058 -272.587466) (xy 87.4522 -272.587466)
		)
		(stroke
			(width 0)
			(type solid)
		)
		(fill yes)
		(layer "In6.Cu")
		(net "M_C_CPU1_SA_DQ<9>")
	)
	(gr_poly
		(pts
			(xy 87.572342 -274.531582) (xy 87.463884 -274.414742) (xy 87.42553 -274.392644) (xy 87.24773 -274.700492)
			(xy 87.286084 -274.72259) (xy 87.441532 -274.75815)
		)
		(stroke
			(width 0)
			(type solid)
		)
		(fill yes)
		(layer "In6.Cu")
		(net "M_D_CPU1_SA_DQ<5>")
	)
	(gr_poly
		(pts
			(xy 87.572342 -271.27581) (xy 87.463884 -271.15897) (xy 87.42553 -271.136872) (xy 87.24773 -271.44472)
			(xy 87.286084 -271.466818) (xy 87.441532 -271.502378)
		)
		(stroke
			(width 0)
			(type solid)
		)
		(fill yes)
		(layer "In6.Cu")
		(net "M_C_CPU1_SA_DQS_DP<1>")
	)
	(gr_poly
		(pts
			(xy 87.702644 -226.469956) (xy 87.740998 -226.447858) (xy 87.563198 -226.14001) (xy 87.524844 -226.162108)
			(xy 87.416386 -226.278948) (xy 87.547196 -226.505516)
		)
		(stroke
			(width 0)
			(type solid)
		)
		(fill yes)
		(layer "In6.Cu")
		(net "M_C_CPU1_SB_DQS_DP<3>")
	)
	(gr_poly
		(pts
			(xy 87.708232 -228.106986) (xy 87.746586 -228.084888) (xy 87.568786 -227.77704) (xy 87.530432 -227.799138)
			(xy 87.421974 -227.915978) (xy 87.552784 -228.142546)
		)
		(stroke
			(width 0)
			(type solid)
		)
		(fill yes)
		(layer "In6.Cu")
		(net "M_C_CPU1_SB_DQ<25>")
	)
	(gr_poly
		(pts
			(xy 87.711026 -234.623102) (xy 87.74938 -234.601004) (xy 87.57158 -234.293156) (xy 87.533226 -234.315254)
			(xy 87.424768 -234.432094) (xy 87.555578 -234.658662)
		)
		(stroke
			(width 0)
			(type solid)
		)
		(fill yes)
		(layer "In6.Cu")
		(net "M_D_CPU1_SB_DQ<16>")
	)
	(gr_poly
		(pts
			(xy 87.817706 -233.9975) (xy 87.926164 -233.88066) (xy 87.795354 -233.654092) (xy 87.639906 -233.689652)
			(xy 87.601552 -233.71175) (xy 87.779352 -234.019598)
		)
		(stroke
			(width 0)
			(type solid)
		)
		(fill yes)
		(layer "In6.Cu")
		(net "M_D_CPU1_SB_DQ<18>")
	)
	(gr_poly
		(pts
			(xy 87.818722 -225.860356) (xy 87.92718 -225.743516) (xy 87.79637 -225.516948) (xy 87.640922 -225.552508)
			(xy 87.602568 -225.574606) (xy 87.780368 -225.882454)
		)
		(stroke
			(width 0)
			(type solid)
		)
		(fill yes)
		(layer "In6.Cu")
		(net "M_C_CPU1_SB_DQS_DN<3>")
	)
	(gr_poly
		(pts
			(xy 87.824056 -227.497386) (xy 87.932514 -227.380546) (xy 87.801704 -227.153978) (xy 87.646256 -227.189538)
			(xy 87.607902 -227.211636) (xy 87.785702 -227.519484)
		)
		(stroke
			(width 0)
			(type solid)
		)
		(fill yes)
		(layer "In6.Cu")
		(net "M_C_CPU1_SB_DQ<27>")
	)
	(gr_poly
		(pts
			(xy 87.84717 -243.718842) (xy 87.84717 -243.674392) (xy 87.49157 -243.674392) (xy 87.49157 -243.718842)
			(xy 87.53856 -243.871242) (xy 87.80018 -243.871242)
		)
		(stroke
			(width 0)
			(type solid)
		)
		(fill yes)
		(layer "In6.Cu")
		(net "M_C_CPU1_SB_DQ<1>")
	)
	(gr_poly
		(pts
			(xy 87.84717 -237.207806) (xy 87.84717 -237.163356) (xy 87.49157 -237.163356) (xy 87.49157 -237.207806)
			(xy 87.53856 -237.360206) (xy 87.80018 -237.360206)
		)
		(stroke
			(width 0)
			(type solid)
		)
		(fill yes)
		(layer "In6.Cu")
		(net "M_C_CPU1_SB_DQS_DN<6>")
	)
	(gr_poly
		(pts
			(xy 87.84717 -229.477062) (xy 87.80018 -229.324662) (xy 87.53856 -229.324662) (xy 87.49157 -229.477062)
			(xy 87.49157 -229.521258) (xy 87.84717 -229.521258)
		)
		(stroke
			(width 0)
			(type solid)
		)
		(fill yes)
		(layer "In6.Cu")
		(net "M_D_CPU1_SB_DQ<23>")
	)
	(gr_poly
		(pts
			(xy 87.84717 -229.06863) (xy 87.84717 -229.024434) (xy 87.49157 -229.024434) (xy 87.49157 -229.06863)
			(xy 87.53856 -229.22103) (xy 87.80018 -229.22103)
		)
		(stroke
			(width 0)
			(type solid)
		)
		(fill yes)
		(layer "In6.Cu")
		(net "M_C_CPU1_SB_DQ<26>")
	)
	(gr_poly
		(pts
			(xy 87.850726 -274.6502) (xy 87.812372 -274.628102) (xy 87.656924 -274.592542) (xy 87.526114 -274.81911)
			(xy 87.634572 -274.93595) (xy 87.672926 -274.958048)
		)
		(stroke
			(width 0)
			(type solid)
		)
		(fill yes)
		(layer "In6.Cu")
		(net "M_D_CPU1_SA_DQ<6>")
	)
	(gr_poly
		(pts
			(xy 87.853266 -248.601738) (xy 87.853266 -248.557542) (xy 87.497666 -248.557542) (xy 87.497666 -248.601738)
			(xy 87.544656 -248.754138) (xy 87.806276 -248.754138)
		)
		(stroke
			(width 0)
			(type solid)
		)
		(fill yes)
		(layer "In6.Cu")
		(net "M_A_CPU1_SB_RSP<0>")
	)
	(gr_poly
		(pts
			(xy 87.853266 -247.382538) (xy 87.806276 -247.230138) (xy 87.544656 -247.230138) (xy 87.497666 -247.382538)
			(xy 87.497666 -247.426988) (xy 87.853266 -247.426988)
		)
		(stroke
			(width 0)
			(type solid)
		)
		(fill yes)
		(layer "In6.Cu")
		(net "M_A_CPU1_SB_RSP<1>")
	)
	(gr_poly
		(pts
			(xy 87.853266 -245.754906) (xy 87.806276 -245.602506) (xy 87.544656 -245.602506) (xy 87.497666 -245.754906)
			(xy 87.497666 -245.799356) (xy 87.853266 -245.799356)
		)
		(stroke
			(width 0)
			(type solid)
		)
		(fill yes)
		(layer "In6.Cu")
		(net "M_D_CPU1_SB_CS_N<3>")
	)
	(gr_poly
		(pts
			(xy 87.853266 -242.499134) (xy 87.806276 -242.346734) (xy 87.544656 -242.346734) (xy 87.497666 -242.499134)
			(xy 87.497666 -242.54333) (xy 87.853266 -242.54333)
		)
		(stroke
			(width 0)
			(type solid)
		)
		(fill yes)
		(layer "In6.Cu")
		(net "M_C_CPU1_SB_DQS_DN<0>")
	)
	(gr_poly
		(pts
			(xy 87.853266 -242.090702) (xy 87.853266 -242.046506) (xy 87.497666 -242.046506) (xy 87.497666 -242.090702)
			(xy 87.544656 -242.243102) (xy 87.806276 -242.243102)
		)
		(stroke
			(width 0)
			(type solid)
		)
		(fill yes)
		(layer "In6.Cu")
		(net "M_C_CPU1_SB_DQS_DN<5>")
	)
	(gr_poly
		(pts
			(xy 87.853266 -240.871502) (xy 87.806276 -240.719102) (xy 87.544656 -240.719102) (xy 87.497666 -240.871502)
			(xy 87.497666 -240.915952) (xy 87.853266 -240.915952)
		)
		(stroke
			(width 0)
			(type solid)
		)
		(fill yes)
		(layer "In6.Cu")
		(net "M_C_CPU1_SB_DQ<6>")
	)
	(gr_poly
		(pts
			(xy 87.853266 -238.83493) (xy 87.853266 -238.790734) (xy 87.497666 -238.790734) (xy 87.497666 -238.83493)
			(xy 87.544656 -238.98733) (xy 87.806276 -238.98733)
		)
		(stroke
			(width 0)
			(type solid)
		)
		(fill yes)
		(layer "In6.Cu")
		(net "M_C_CPU1_SB_DQ<9>")
	)
	(gr_poly
		(pts
			(xy 87.853266 -235.579666) (xy 87.853266 -235.53547) (xy 87.497666 -235.53547) (xy 87.497666 -235.579666)
			(xy 87.544656 -235.732066) (xy 87.806276 -235.732066)
		)
		(stroke
			(width 0)
			(type solid)
		)
		(fill yes)
		(layer "In6.Cu")
		(net "M_C_CPU1_SB_DQ<13>")
	)
	(gr_poly
		(pts
			(xy 87.853266 -232.732834) (xy 87.806276 -232.580434) (xy 87.544656 -232.580434) (xy 87.497666 -232.732834)
			(xy 87.497666 -232.77703) (xy 87.853266 -232.77703)
		)
		(stroke
			(width 0)
			(type solid)
		)
		(fill yes)
		(layer "In6.Cu")
		(net "M_D_CPU1_SB_DQ<19>")
	)
	(gr_poly
		(pts
			(xy 87.853266 -232.323894) (xy 87.853266 -232.279698) (xy 87.497666 -232.279698) (xy 87.497666 -232.323894)
			(xy 87.544656 -232.476294) (xy 87.806276 -232.476294)
		)
		(stroke
			(width 0)
			(type solid)
		)
		(fill yes)
		(layer "In6.Cu")
		(net "M_D_CPU1_SB_DQS_DP<2>")
	)
	(gr_poly
		(pts
			(xy 87.853266 -230.696262) (xy 87.853266 -230.652066) (xy 87.497666 -230.652066) (xy 87.497666 -230.696262)
			(xy 87.544656 -230.848662) (xy 87.806276 -230.848662)
		)
		(stroke
			(width 0)
			(type solid)
		)
		(fill yes)
		(layer "In6.Cu")
		(net "M_D_CPU1_SB_DQ<20>")
	)
	(gr_poly
		(pts
			(xy 87.853266 -224.593658) (xy 87.806276 -224.441258) (xy 87.544656 -224.441258) (xy 87.497666 -224.593658)
			(xy 87.497666 -224.638108) (xy 87.853266 -224.638108)
		)
		(stroke
			(width 0)
			(type solid)
		)
		(fill yes)
		(layer "In6.Cu")
		(net "M_C_CPU1_SB_DQS_DP<8>")
	)
	(gr_poly
		(pts
			(xy 87.853266 -224.185226) (xy 87.853266 -224.140776) (xy 87.497666 -224.140776) (xy 87.497666 -224.185226)
			(xy 87.544656 -224.337626) (xy 87.806276 -224.337626)
		)
		(stroke
			(width 0)
			(type solid)
		)
		(fill yes)
		(layer "In6.Cu")
		(net "M_C_CPU1_SB_DQ<28>")
	)
	(gr_poly
		(pts
			(xy 87.857076 -271.384522) (xy 87.818722 -271.362424) (xy 87.663274 -271.326864) (xy 87.532464 -271.553432)
			(xy 87.640922 -271.670272) (xy 87.679276 -271.69237)
		)
		(stroke
			(width 0)
			(type solid)
		)
		(fill yes)
		(layer "In6.Cu")
		(net "M_C_CPU1_SA_DQ<11>")
	)
	(gr_poly
		(pts
			(xy 87.858346 -237.61573) (xy 87.811356 -237.46333) (xy 87.549736 -237.46333) (xy 87.502746 -237.61573)
			(xy 87.502746 -237.66018) (xy 87.858346 -237.66018)
		)
		(stroke
			(width 0)
			(type solid)
		)
		(fill yes)
		(layer "In6.Cu")
		(net "M_C_CPU1_SB_DQS_DN<1>")
	)
	(gr_poly
		(pts
			(xy 87.8586 -240.46307) (xy 87.8586 -240.418874) (xy 87.503 -240.418874) (xy 87.503 -240.46307) (xy 87.54999 -240.61547)
			(xy 87.81161 -240.61547)
		)
		(stroke
			(width 0)
			(type solid)
		)
		(fill yes)
		(layer "In6.Cu")
		(net "M_C_CPU1_SB_DQ<5>")
	)
	(gr_poly
		(pts
			(xy 87.859108 -244.126766) (xy 87.812118 -243.974366) (xy 87.550498 -243.974366) (xy 87.503508 -244.126766)
			(xy 87.503508 -244.171216) (xy 87.859108 -244.171216)
		)
		(stroke
			(width 0)
			(type solid)
		)
		(fill yes)
		(layer "In6.Cu")
		(net "M_C_CPU1_SB_DQ<2>")
	)
	(gr_poly
		(pts
			(xy 87.859362 -222.965518) (xy 87.812372 -222.813118) (xy 87.550752 -222.813118) (xy 87.503762 -222.965518)
			(xy 87.503762 -223.009968) (xy 87.859362 -223.009968)
		)
		(stroke
			(width 0)
			(type solid)
		)
		(fill yes)
		(layer "In6.Cu")
		(net "M_C_CPU1_SB_DQ<29>")
	)
	(gr_poly
		(pts
			(xy 87.86114 -235.988098) (xy 87.81415 -235.835698) (xy 87.55253 -235.835698) (xy 87.50554 -235.988098)
			(xy 87.50554 -236.032548) (xy 87.86114 -236.032548)
		)
		(stroke
			(width 0)
			(type solid)
		)
		(fill yes)
		(layer "In6.Cu")
		(net "M_C_CPU1_SB_DQ<14>")
	)
	(gr_poly
		(pts
			(xy 87.86114 -231.104694) (xy 87.81415 -230.952294) (xy 87.55253 -230.952294) (xy 87.50554 -231.104694)
			(xy 87.50554 -231.149144) (xy 87.86114 -231.149144)
		)
		(stroke
			(width 0)
			(type solid)
		)
		(fill yes)
		(layer "In6.Cu")
		(net "M_D_CPU1_SB_DQS_DP<7>")
	)
	(gr_poly
		(pts
			(xy 87.861648 -245.346474) (xy 87.861648 -245.302278) (xy 87.506048 -245.302278) (xy 87.506048 -245.346474)
			(xy 87.553038 -245.498874) (xy 87.814658 -245.498874)
		)
		(stroke
			(width 0)
			(type solid)
		)
		(fill yes)
		(layer "In6.Cu")
		(net "M_D_CPU1_SB_CS_N<0>")
	)
	(gr_poly
		(pts
			(xy 87.861648 -239.243362) (xy 87.814658 -239.090962) (xy 87.553038 -239.090962) (xy 87.506048 -239.243362)
			(xy 87.506048 -239.287812) (xy 87.861648 -239.287812)
		)
		(stroke
			(width 0)
			(type solid)
		)
		(fill yes)
		(layer "In6.Cu")
		(net "M_C_CPU1_SB_DQ<10>")
	)
	(gr_poly
		(pts
			(xy 87.962994 -279.759664) (xy 87.962994 -279.715468) (xy 87.607394 -279.715468) (xy 87.607394 -279.759664)
			(xy 87.654384 -279.912064) (xy 87.916004 -279.912064)
		)
		(stroke
			(width 0)
			(type solid)
		)
		(fill yes)
		(layer "In6.Cu")
		(net "M_D_CPU1_SA_DQ<0>")
	)
	(gr_poly
		(pts
			(xy 87.962994 -278.540718) (xy 87.916004 -278.388318) (xy 87.654384 -278.388318) (xy 87.607394 -278.540718)
			(xy 87.607394 -278.585168) (xy 87.962994 -278.585168)
		)
		(stroke
			(width 0)
			(type solid)
		)
		(fill yes)
		(layer "In6.Cu")
		(net "M_D_CPU1_SA_DQ<3>")
	)
	(gr_poly
		(pts
			(xy 87.962994 -273.657314) (xy 87.916004 -273.504914) (xy 87.654384 -273.504914) (xy 87.607394 -273.657314)
			(xy 87.607394 -273.701764) (xy 87.962994 -273.701764)
		)
		(stroke
			(width 0)
			(type solid)
		)
		(fill yes)
		(layer "In6.Cu")
		(net "M_D_CPU1_SA_DQ<7>")
	)
	(gr_poly
		(pts
			(xy 87.962994 -273.248882) (xy 87.962994 -273.204432) (xy 87.607394 -273.204432) (xy 87.607394 -273.248882)
			(xy 87.654384 -273.401282) (xy 87.916004 -273.401282)
		)
		(stroke
			(width 0)
			(type solid)
		)
		(fill yes)
		(layer "In6.Cu")
		(net "M_C_CPU1_SA_DQ<8>")
	)
	(gr_poly
		(pts
			(xy 87.962994 -270.40205) (xy 87.916004 -270.24965) (xy 87.654384 -270.24965) (xy 87.607394 -270.40205)
			(xy 87.607394 -270.446246) (xy 87.962994 -270.446246)
		)
		(stroke
			(width 0)
			(type solid)
		)
		(fill yes)
		(layer "In6.Cu")
		(net "M_C_CPU1_SA_DQS_DN<1>")
	)
	(gr_poly
		(pts
			(xy 87.962994 -269.99311) (xy 87.962994 -269.948914) (xy 87.607394 -269.948914) (xy 87.607394 -269.99311)
			(xy 87.654384 -270.14551) (xy 87.916004 -270.14551)
		)
		(stroke
			(width 0)
			(type solid)
		)
		(fill yes)
		(layer "In6.Cu")
		(net "M_C_CPU1_SA_DQS_DN<6>")
	)
	(gr_poly
		(pts
			(xy 87.962994 -268.77391) (xy 87.916004 -268.62151) (xy 87.654384 -268.62151) (xy 87.607394 -268.77391)
			(xy 87.607394 -268.81836) (xy 87.962994 -268.81836)
		)
		(stroke
			(width 0)
			(type solid)
		)
		(fill yes)
		(layer "In6.Cu")
		(net "M_C_CPU1_SA_DQ<14>")
	)
	(gr_poly
		(pts
			(xy 87.962994 -268.365478) (xy 87.962994 -268.321028) (xy 87.607394 -268.321028) (xy 87.607394 -268.365478)
			(xy 87.654384 -268.517878) (xy 87.916004 -268.517878)
		)
		(stroke
			(width 0)
			(type solid)
		)
		(fill yes)
		(layer "In6.Cu")
		(net "M_C_CPU1_SA_DQ<13>")
	)
	(gr_poly
		(pts
			(xy 87.962994 -267.146278) (xy 87.916004 -266.993878) (xy 87.654384 -266.993878) (xy 87.607394 -267.146278)
			(xy 87.607394 -267.190474) (xy 87.962994 -267.190474)
		)
		(stroke
			(width 0)
			(type solid)
		)
		(fill yes)
		(layer "In6.Cu")
		(net "M_C_CPU1_SA_DQ<26>")
	)
	(gr_poly
		(pts
			(xy 87.962994 -266.737846) (xy 87.962994 -266.693396) (xy 87.607394 -266.693396) (xy 87.607394 -266.737846)
			(xy 87.654384 -266.890246) (xy 87.916004 -266.890246)
		)
		(stroke
			(width 0)
			(type solid)
		)
		(fill yes)
		(layer "In6.Cu")
		(net "M_C_CPU1_SA_DQ<25>")
	)
	(gr_poly
		(pts
			(xy 87.962994 -265.518646) (xy 87.916004 -265.366246) (xy 87.654384 -265.366246) (xy 87.607394 -265.518646)
			(xy 87.607394 -265.562842) (xy 87.962994 -265.562842)
		)
		(stroke
			(width 0)
			(type solid)
		)
		(fill yes)
		(layer "In6.Cu")
		(net "M_C_CPU1_SA_DQS_DN<3>")
	)
	(gr_poly
		(pts
			(xy 87.962994 -265.109706) (xy 87.962994 -265.06551) (xy 87.607394 -265.06551) (xy 87.607394 -265.109706)
			(xy 87.654384 -265.262106) (xy 87.916004 -265.262106)
		)
		(stroke
			(width 0)
			(type solid)
		)
		(fill yes)
		(layer "In6.Cu")
		(net "M_C_CPU1_SA_DQS_DN<8>")
	)
	(gr_poly
		(pts
			(xy 87.962994 -263.891014) (xy 87.916004 -263.738614) (xy 87.654384 -263.738614) (xy 87.607394 -263.891014)
			(xy 87.607394 -263.93521) (xy 87.962994 -263.93521)
		)
		(stroke
			(width 0)
			(type solid)
		)
		(fill yes)
		(layer "In6.Cu")
		(net "M_C_CPU1_SA_DQ<30>")
	)
	(gr_poly
		(pts
			(xy 87.962994 -263.482074) (xy 87.962994 -263.437878) (xy 87.607394 -263.437878) (xy 87.607394 -263.482074)
			(xy 87.654384 -263.634474) (xy 87.916004 -263.634474)
		)
		(stroke
			(width 0)
			(type solid)
		)
		(fill yes)
		(layer "In6.Cu")
		(net "M_C_CPU1_SA_DQ<29>")
	)
	(gr_poly
		(pts
			(xy 87.962994 -262.262874) (xy 87.916004 -262.110474) (xy 87.654384 -262.110474) (xy 87.607394 -262.262874)
			(xy 87.607394 -262.307324) (xy 87.962994 -262.307324)
		)
		(stroke
			(width 0)
			(type solid)
		)
		(fill yes)
		(layer "In6.Cu")
		(net "M_C_CPU1_SA_CB<0>")
	)
	(gr_poly
		(pts
			(xy 87.962994 -261.854442) (xy 87.962994 -261.809992) (xy 87.607394 -261.809992) (xy 87.607394 -261.854442)
			(xy 87.654384 -262.006842) (xy 87.916004 -262.006842)
		)
		(stroke
			(width 0)
			(type solid)
		)
		(fill yes)
		(layer "In6.Cu")
		(net "M_C_CPU1_SA_CB<3>")
	)
	(gr_poly
		(pts
			(xy 87.962994 -260.635242) (xy 87.916004 -260.482842) (xy 87.654384 -260.482842) (xy 87.607394 -260.635242)
			(xy 87.607394 -260.679438) (xy 87.962994 -260.679438)
		)
		(stroke
			(width 0)
			(type solid)
		)
		(fill yes)
		(layer "In6.Cu")
		(net "M_C_CPU1_SA_DQS_DP<9>")
	)
	(gr_poly
		(pts
			(xy 87.962994 -260.226302) (xy 87.962994 -260.182106) (xy 87.607394 -260.182106) (xy 87.607394 -260.226302)
			(xy 87.654384 -260.378702) (xy 87.916004 -260.378702)
		)
		(stroke
			(width 0)
			(type solid)
		)
		(fill yes)
		(layer "In6.Cu")
		(net "M_C_CPU1_SA_DQS_DP<4>")
	)
	(gr_poly
		(pts
			(xy 87.962994 -259.00761) (xy 87.916004 -258.85521) (xy 87.654384 -258.85521) (xy 87.607394 -259.00761)
			(xy 87.607394 -259.051806) (xy 87.962994 -259.051806)
		)
		(stroke
			(width 0)
			(type solid)
		)
		(fill yes)
		(layer "In6.Cu")
		(net "M_C_CPU1_SA_CB<4>")
	)
	(gr_poly
		(pts
			(xy 87.962994 -258.59867) (xy 87.962994 -258.554474) (xy 87.607394 -258.554474) (xy 87.607394 -258.59867)
			(xy 87.654384 -258.75107) (xy 87.916004 -258.75107)
		)
		(stroke
			(width 0)
			(type solid)
		)
		(fill yes)
		(layer "In6.Cu")
		(net "M_C_CPU1_SA_CB<7>")
	)
	(gr_poly
		(pts
			(xy 87.962994 -256.971038) (xy 87.962994 -256.926588) (xy 87.607394 -256.926588) (xy 87.607394 -256.971038)
			(xy 87.654384 -257.123438) (xy 87.916004 -257.123438)
		)
		(stroke
			(width 0)
			(type solid)
		)
		(fill yes)
		(layer "In6.Cu")
		(net "M_D_CPU1_SA_RSP<0>")
	)
	(gr_poly
		(pts
			(xy 87.962994 -255.751838) (xy 87.916004 -255.599438) (xy 87.654384 -255.599438) (xy 87.607394 -255.751838)
			(xy 87.607394 -255.796288) (xy 87.962994 -255.796288)
		)
		(stroke
			(width 0)
			(type solid)
		)
		(fill yes)
		(layer "In6.Cu")
		(net "M_D_CPU1_SB_RSP<1>")
	)
	(gr_poly
		(pts
			(xy 87.962994 -255.343406) (xy 87.962994 -255.298956) (xy 87.607394 -255.298956) (xy 87.607394 -255.343406)
			(xy 87.654384 -255.495806) (xy 87.916004 -255.495806)
		)
		(stroke
			(width 0)
			(type solid)
		)
		(fill yes)
		(layer "In6.Cu")
		(net "M_C_CPU1_SA_RSP<0>")
	)
	(gr_poly
		(pts
			(xy 87.962994 -254.124206) (xy 87.916004 -253.971806) (xy 87.654384 -253.971806) (xy 87.607394 -254.124206)
			(xy 87.607394 -254.168402) (xy 87.962994 -254.168402)
		)
		(stroke
			(width 0)
			(type solid)
		)
		(fill yes)
		(layer "In6.Cu")
		(net "M_C_CPU1_SB_RSP<1>")
	)
	(gr_poly
		(pts
			(xy 87.971376 -278.132286) (xy 87.971376 -278.08809) (xy 87.615776 -278.08809) (xy 87.615776 -278.132286)
			(xy 87.662766 -278.284686) (xy 87.924386 -278.284686)
		)
		(stroke
			(width 0)
			(type solid)
		)
		(fill yes)
		(layer "In6.Cu")
		(net "M_D_CPU1_SA_DQS_DP<0>")
	)
	(gr_poly
		(pts
			(xy 87.971376 -276.5044) (xy 87.971376 -276.460204) (xy 87.615776 -276.460204) (xy 87.615776 -276.5044)
			(xy 87.662766 -276.6568) (xy 87.924386 -276.6568)
		)
		(stroke
			(width 0)
			(type solid)
		)
		(fill yes)
		(layer "In6.Cu")
		(net "M_D_CPU1_SA_DQS_DN<5>")
	)
	(gr_poly
		(pts
			(xy 88.035892 -272.101056) (xy 87.927434 -271.984216) (xy 87.88908 -271.962118) (xy 87.71128 -272.269966)
			(xy 87.749634 -272.292064) (xy 87.905082 -272.327624)
		)
		(stroke
			(width 0)
			(type solid)
		)
		(fill yes)
		(layer "In6.Cu")
		(net "M_C_CPU1_SA_DQ<9>")
	)
	(gr_poly
		(pts
			(xy 88.038432 -275.351748) (xy 87.929974 -275.234908) (xy 87.89162 -275.21281) (xy 87.71382 -275.520658)
			(xy 87.752174 -275.542756) (xy 87.907622 -275.578316)
		)
		(stroke
			(width 0)
			(type solid)
		)
		(fill yes)
		(layer "In6.Cu")
		(net "M_D_CPU1_SA_DQ<4>")
	)
	(gr_poly
		(pts
			(xy 88.174322 -227.28682) (xy 88.212676 -227.264722) (xy 88.034876 -226.956874) (xy 87.996522 -226.978972)
			(xy 87.888064 -227.095812) (xy 88.018874 -227.32238)
		)
		(stroke
			(width 0)
			(type solid)
		)
		(fill yes)
		(layer "In6.Cu")
		(net "M_C_CPU1_SB_DQS_DP<3>")
	)
	(gr_poly
		(pts
			(xy 88.179656 -233.807) (xy 88.21801 -233.784902) (xy 88.04021 -233.477054) (xy 88.001856 -233.499152)
			(xy 87.893398 -233.615992) (xy 88.024208 -233.84256)
		)
		(stroke
			(width 0)
			(type solid)
		)
		(fill yes)
		(layer "In6.Cu")
		(net "M_D_CPU1_SB_DQ<17>")
	)
	(gr_poly
		(pts
			(xy 88.180926 -225.67011) (xy 88.21928 -225.648012) (xy 88.04148 -225.340164) (xy 88.003126 -225.362262)
			(xy 87.894668 -225.479102) (xy 88.025478 -225.70567)
		)
		(stroke
			(width 0)
			(type solid)
		)
		(fill yes)
		(layer "In6.Cu")
		(net "M_C_CPU1_SB_DQS_DN<8>")
	)
	(gr_poly
		(pts
			(xy 88.289638 -233.18724) (xy 88.398096 -233.0704) (xy 88.267286 -232.843832) (xy 88.111838 -232.879392)
			(xy 88.073484 -232.90149) (xy 88.251284 -233.209338)
		)
		(stroke
			(width 0)
			(type solid)
		)
		(fill yes)
		(layer "In6.Cu")
		(net "M_D_CPU1_SB_DQ<19>")
	)
	(gr_poly
		(pts
			(xy 88.289638 -226.676204) (xy 88.398096 -226.559364) (xy 88.267286 -226.332796) (xy 88.111838 -226.368356)
			(xy 88.073484 -226.390454) (xy 88.251284 -226.698302)
		)
		(stroke
			(width 0)
			(type solid)
		)
		(fill yes)
		(layer "In6.Cu")
		(net "M_C_CPU1_SB_DQS_DN<3>")
	)
	(gr_poly
		(pts
			(xy 88.289638 -225.048318) (xy 88.398096 -224.931478) (xy 88.267286 -224.70491) (xy 88.111838 -224.74047)
			(xy 88.073484 -224.762568) (xy 88.251284 -225.070416)
		)
		(stroke
			(width 0)
			(type solid)
		)
		(fill yes)
		(layer "In6.Cu")
		(net "M_C_CPU1_SB_DQS_DP<8>")
	)
	(gr_poly
		(pts
			(xy 88.312498 -240.057178) (xy 88.265508 -239.904778) (xy 88.003888 -239.904778) (xy 87.956898 -240.057178)
			(xy 87.956898 -240.101628) (xy 88.312498 -240.101628)
		)
		(stroke
			(width 0)
			(type solid)
		)
		(fill yes)
		(layer "In6.Cu")
		(net "M_C_CPU1_SB_DQ<7>")
	)
	(gr_poly
		(pts
			(xy 88.31326 -234.76585) (xy 88.31326 -234.721654) (xy 87.95766 -234.721654) (xy 87.95766 -234.76585)
			(xy 88.00465 -234.91825) (xy 88.26627 -234.91825)
		)
		(stroke
			(width 0)
			(type solid)
		)
		(fill yes)
		(layer "In6.Cu")
		(net "M_D_CPU1_SB_DQ<16>")
	)
	(gr_poly
		(pts
			(xy 88.31326 -229.882446) (xy 88.31326 -229.83825) (xy 87.95766 -229.83825) (xy 87.95766 -229.882446)
			(xy 88.00465 -230.034846) (xy 88.26627 -230.034846)
		)
		(stroke
			(width 0)
			(type solid)
		)
		(fill yes)
		(layer "In6.Cu")
		(net "M_D_CPU1_SB_DQ<21>")
	)
	(gr_poly
		(pts
			(xy 88.31453 -244.940582) (xy 88.26754 -244.788182) (xy 88.00592 -244.788182) (xy 87.95893 -244.940582)
			(xy 87.95893 -244.985032) (xy 88.31453 -244.985032)
		)
		(stroke
			(width 0)
			(type solid)
		)
		(fill yes)
		(layer "In6.Cu")
		(net "M_D_CPU1_SB_CS_N<1>")
	)
	(gr_poly
		(pts
			(xy 88.31453 -244.532658) (xy 88.31453 -244.488208) (xy 87.95893 -244.488208) (xy 87.95893 -244.532658)
			(xy 88.00592 -244.685058) (xy 88.26754 -244.685058)
		)
		(stroke
			(width 0)
			(type solid)
		)
		(fill yes)
		(layer "In6.Cu")
		(net "M_C_CPU1_SB_DQ<0>")
	)
	(gr_poly
		(pts
			(xy 88.31453 -239.649254) (xy 88.31453 -239.604804) (xy 87.95893 -239.604804) (xy 87.95893 -239.649254)
			(xy 88.00592 -239.801654) (xy 88.26754 -239.801654)
		)
		(stroke
			(width 0)
			(type solid)
		)
		(fill yes)
		(layer "In6.Cu")
		(net "M_C_CPU1_SB_DQ<8>")
	)
	(gr_poly
		(pts
			(xy 88.314784 -241.685318) (xy 88.267794 -241.532918) (xy 88.006174 -241.532918) (xy 87.959184 -241.685318)
			(xy 87.959184 -241.729514) (xy 88.314784 -241.729514)
		)
		(stroke
			(width 0)
			(type solid)
		)
		(fill yes)
		(layer "In6.Cu")
		(net "M_C_CPU1_SB_DQS_DP<5>")
	)
	(gr_poly
		(pts
			(xy 88.314784 -223.37141) (xy 88.314784 -223.327214) (xy 87.959184 -223.327214) (xy 87.959184 -223.37141)
			(xy 88.006174 -223.52381) (xy 88.267794 -223.52381)
		)
		(stroke
			(width 0)
			(type solid)
		)
		(fill yes)
		(layer "In6.Cu")
		(net "M_C_CPU1_SB_DQ<31>")
	)
	(gr_poly
		(pts
			(xy 88.31707 -248.196354) (xy 88.27008 -248.043954) (xy 88.00846 -248.043954) (xy 87.96147 -248.196354)
			(xy 87.96147 -248.240804) (xy 88.31707 -248.240804)
		)
		(stroke
			(width 0)
			(type solid)
		)
		(fill yes)
		(layer "In6.Cu")
		(net "M_A_CPU1_SA_RSP<0>")
	)
	(gr_poly
		(pts
			(xy 88.31707 -247.787922) (xy 88.31707 -247.743472) (xy 87.96147 -247.743472) (xy 87.96147 -247.787922)
			(xy 88.00846 -247.940322) (xy 88.27008 -247.940322)
		)
		(stroke
			(width 0)
			(type solid)
		)
		(fill yes)
		(layer "In6.Cu")
		(net "M_A_CPU1_SA_RSP<1>")
	)
	(gr_poly
		(pts
			(xy 88.31707 -246.16029) (xy 88.31707 -246.11584) (xy 87.96147 -246.11584) (xy 87.96147 -246.16029)
			(xy 88.00846 -246.31269) (xy 88.27008 -246.31269)
		)
		(stroke
			(width 0)
			(type solid)
		)
		(fill yes)
		(layer "In6.Cu")
		(net "M_D_CPU1_SB_CS_N<2>")
	)
	(gr_poly
		(pts
			(xy 88.31707 -243.313458) (xy 88.27008 -243.161058) (xy 88.00846 -243.161058) (xy 87.96147 -243.313458)
			(xy 87.96147 -243.357654) (xy 88.31707 -243.357654)
		)
		(stroke
			(width 0)
			(type solid)
		)
		(fill yes)
		(layer "In6.Cu")
		(net "M_C_CPU1_SB_DQ<3>")
	)
	(gr_poly
		(pts
			(xy 88.31707 -242.904518) (xy 88.31707 -242.860322) (xy 87.96147 -242.860322) (xy 87.96147 -242.904518)
			(xy 88.00846 -243.056918) (xy 88.27008 -243.056918)
		)
		(stroke
			(width 0)
			(type solid)
		)
		(fill yes)
		(layer "In6.Cu")
		(net "M_C_CPU1_SB_DQS_DP<0>")
	)
	(gr_poly
		(pts
			(xy 88.31707 -241.276886) (xy 88.31707 -241.232436) (xy 87.96147 -241.232436) (xy 87.96147 -241.276886)
			(xy 88.00846 -241.429286) (xy 88.27008 -241.429286)
		)
		(stroke
			(width 0)
			(type solid)
		)
		(fill yes)
		(layer "In6.Cu")
		(net "M_C_CPU1_SB_DQ<4>")
	)
	(gr_poly
		(pts
			(xy 88.31707 -238.430054) (xy 88.27008 -238.277654) (xy 88.00846 -238.277654) (xy 87.96147 -238.430054)
			(xy 87.96147 -238.47425) (xy 88.31707 -238.47425)
		)
		(stroke
			(width 0)
			(type solid)
		)
		(fill yes)
		(layer "In6.Cu")
		(net "M_C_CPU1_SB_DQ<11>")
	)
	(gr_poly
		(pts
			(xy 88.31707 -238.021114) (xy 88.31707 -237.976918) (xy 87.96147 -237.976918) (xy 87.96147 -238.021114)
			(xy 88.00846 -238.173514) (xy 88.27008 -238.173514)
		)
		(stroke
			(width 0)
			(type solid)
		)
		(fill yes)
		(layer "In6.Cu")
		(net "M_C_CPU1_SB_DQS_DP<1>")
	)
	(gr_poly
		(pts
			(xy 88.31707 -235.174282) (xy 88.27008 -235.021882) (xy 88.00846 -235.021882) (xy 87.96147 -235.174282)
			(xy 87.96147 -235.218732) (xy 88.31707 -235.218732)
		)
		(stroke
			(width 0)
			(type solid)
		)
		(fill yes)
		(layer "In6.Cu")
		(net "M_C_CPU1_SB_DQ<15>")
	)
	(gr_poly
		(pts
			(xy 88.31707 -231.919018) (xy 88.27008 -231.766618) (xy 88.00846 -231.766618) (xy 87.96147 -231.919018)
			(xy 87.96147 -231.963214) (xy 88.31707 -231.963214)
		)
		(stroke
			(width 0)
			(type solid)
		)
		(fill yes)
		(layer "In6.Cu")
		(net "M_D_CPU1_SB_DQS_DN<2>")
	)
	(gr_poly
		(pts
			(xy 88.31707 -231.510078) (xy 88.31707 -231.465882) (xy 87.96147 -231.465882) (xy 87.96147 -231.510078)
			(xy 88.00846 -231.662478) (xy 88.27008 -231.662478)
		)
		(stroke
			(width 0)
			(type solid)
		)
		(fill yes)
		(layer "In6.Cu")
		(net "M_D_CPU1_SB_DQS_DN<7>")
	)
	(gr_poly
		(pts
			(xy 88.31707 -230.290878) (xy 88.27008 -230.138478) (xy 88.00846 -230.138478) (xy 87.96147 -230.290878)
			(xy 87.96147 -230.335328) (xy 88.31707 -230.335328)
		)
		(stroke
			(width 0)
			(type solid)
		)
		(fill yes)
		(layer "In6.Cu")
		(net "M_D_CPU1_SB_DQ<22>")
	)
	(gr_poly
		(pts
			(xy 88.31707 -228.663246) (xy 88.27008 -228.510846) (xy 88.00846 -228.510846) (xy 87.96147 -228.663246)
			(xy 87.96147 -228.707696) (xy 88.31707 -228.707696)
		)
		(stroke
			(width 0)
			(type solid)
		)
		(fill yes)
		(layer "In6.Cu")
		(net "M_C_CPU1_SB_DQ<24>")
	)
	(gr_poly
		(pts
			(xy 88.31707 -228.254814) (xy 88.31707 -228.210364) (xy 87.96147 -228.210364) (xy 87.96147 -228.254814)
			(xy 88.00846 -228.407214) (xy 88.27008 -228.407214)
		)
		(stroke
			(width 0)
			(type solid)
		)
		(fill yes)
		(layer "In6.Cu")
		(net "M_C_CPU1_SB_DQ<25>")
	)
	(gr_poly
		(pts
			(xy 88.31707 -223.779842) (xy 88.27008 -223.627442) (xy 88.00846 -223.627442) (xy 87.96147 -223.779842)
			(xy 87.96147 -223.824292) (xy 88.31707 -223.824292)
		)
		(stroke
			(width 0)
			(type solid)
		)
		(fill yes)
		(layer "In6.Cu")
		(net "M_C_CPU1_SB_DQ<30>")
	)
	(gr_poly
		(pts
			(xy 88.323166 -236.801914) (xy 88.276176 -236.649514) (xy 88.014556 -236.649514) (xy 87.967566 -236.801914)
			(xy 87.967566 -236.846364) (xy 88.323166 -236.846364)
		)
		(stroke
			(width 0)
			(type solid)
		)
		(fill yes)
		(layer "In6.Cu")
		(net "M_C_CPU1_SB_DQS_DP<6>")
	)
	(gr_poly
		(pts
			(xy 88.323166 -236.393482) (xy 88.323166 -236.349286) (xy 87.967566 -236.349286) (xy 87.967566 -236.393482)
			(xy 88.014556 -236.545882) (xy 88.276176 -236.545882)
		)
		(stroke
			(width 0)
			(type solid)
		)
		(fill yes)
		(layer "In6.Cu")
		(net "M_C_CPU1_SB_DQ<12>")
	)
	(gr_poly
		(pts
			(xy 88.327992 -272.19656) (xy 88.289638 -272.174462) (xy 88.13419 -272.138902) (xy 88.00338 -272.36547)
			(xy 88.111838 -272.48231) (xy 88.150192 -272.504408)
		)
		(stroke
			(width 0)
			(type solid)
		)
		(fill yes)
		(layer "In6.Cu")
		(net "M_C_CPU1_SA_DQ<10>")
	)
	(gr_poly
		(pts
			(xy 88.424258 -277.726902) (xy 88.377268 -277.574502) (xy 88.115648 -277.574502) (xy 88.068658 -277.726902)
			(xy 88.068658 -277.771098) (xy 88.424258 -277.771098)
		)
		(stroke
			(width 0)
			(type solid)
		)
		(fill yes)
		(layer "In6.Cu")
		(net "M_D_CPU1_SA_DQS_DN<0>")
	)
	(gr_poly
		(pts
			(xy 88.426798 -276.098762) (xy 88.379808 -275.946362) (xy 88.118188 -275.946362) (xy 88.071198 -276.098762)
			(xy 88.071198 -276.143212) (xy 88.426798 -276.143212)
		)
		(stroke
			(width 0)
			(type solid)
		)
		(fill yes)
		(layer "In6.Cu")
		(net "M_D_CPU1_SA_DQS_DP<5>")
	)
	(gr_poly
		(pts
			(xy 88.432894 -279.354788) (xy 88.385904 -279.202388) (xy 88.124284 -279.202388) (xy 88.077294 -279.354788)
			(xy 88.077294 -279.398984) (xy 88.432894 -279.398984)
		)
		(stroke
			(width 0)
			(type solid)
		)
		(fill yes)
		(layer "In6.Cu")
		(net "M_D_CPU1_SA_DQ<2>")
	)
	(gr_poly
		(pts
			(xy 88.432894 -278.945848) (xy 88.432894 -278.901652) (xy 88.077294 -278.901652) (xy 88.077294 -278.945848)
			(xy 88.124284 -279.098248) (xy 88.385904 -279.098248)
		)
		(stroke
			(width 0)
			(type solid)
		)
		(fill yes)
		(layer "In6.Cu")
		(net "M_D_CPU1_SA_DQ<1>")
	)
	(gr_poly
		(pts
			(xy 88.432894 -274.47113) (xy 88.385904 -274.31873) (xy 88.124284 -274.31873) (xy 88.077294 -274.47113)
			(xy 88.077294 -274.51558) (xy 88.432894 -274.51558)
		)
		(stroke
			(width 0)
			(type solid)
		)
		(fill yes)
		(layer "In6.Cu")
		(net "M_D_CPU1_SA_DQ<6>")
	)
	(gr_poly
		(pts
			(xy 88.432894 -274.062698) (xy 88.432894 -274.018248) (xy 88.077294 -274.018248) (xy 88.077294 -274.062698)
			(xy 88.124284 -274.215098) (xy 88.385904 -274.215098)
		)
		(stroke
			(width 0)
			(type solid)
		)
		(fill yes)
		(layer "In6.Cu")
		(net "M_D_CPU1_SA_DQ<5>")
	)
	(gr_poly
		(pts
			(xy 88.432894 -271.215866) (xy 88.385904 -271.063466) (xy 88.124284 -271.063466) (xy 88.077294 -271.215866)
			(xy 88.077294 -271.260062) (xy 88.432894 -271.260062)
		)
		(stroke
			(width 0)
			(type solid)
		)
		(fill yes)
		(layer "In6.Cu")
		(net "M_C_CPU1_SA_DQ<11>")
	)
	(gr_poly
		(pts
			(xy 88.432894 -270.806926) (xy 88.432894 -270.76273) (xy 88.077294 -270.76273) (xy 88.077294 -270.806926)
			(xy 88.124284 -270.959326) (xy 88.385904 -270.959326)
		)
		(stroke
			(width 0)
			(type solid)
		)
		(fill yes)
		(layer "In6.Cu")
		(net "M_C_CPU1_SA_DQS_DP<1>")
	)
	(gr_poly
		(pts
			(xy 88.432894 -269.587726) (xy 88.385904 -269.435326) (xy 88.124284 -269.435326) (xy 88.077294 -269.587726)
			(xy 88.077294 -269.632176) (xy 88.432894 -269.632176)
		)
		(stroke
			(width 0)
			(type solid)
		)
		(fill yes)
		(layer "In6.Cu")
		(net "M_C_CPU1_SA_DQS_DP<6>")
	)
	(gr_poly
		(pts
			(xy 88.432894 -269.179294) (xy 88.432894 -269.134844) (xy 88.077294 -269.134844) (xy 88.077294 -269.179294)
			(xy 88.124284 -269.331694) (xy 88.385904 -269.331694)
		)
		(stroke
			(width 0)
			(type solid)
		)
		(fill yes)
		(layer "In6.Cu")
		(net "M_C_CPU1_SA_DQ<12>")
	)
	(gr_poly
		(pts
			(xy 88.432894 -267.960094) (xy 88.385904 -267.807694) (xy 88.124284 -267.807694) (xy 88.077294 -267.960094)
			(xy 88.077294 -268.004544) (xy 88.432894 -268.004544)
		)
		(stroke
			(width 0)
			(type solid)
		)
		(fill yes)
		(layer "In6.Cu")
		(net "M_C_CPU1_SA_DQ<15>")
	)
	(gr_poly
		(pts
			(xy 88.432894 -267.551662) (xy 88.432894 -267.507212) (xy 88.077294 -267.507212) (xy 88.077294 -267.551662)
			(xy 88.124284 -267.704062) (xy 88.385904 -267.704062)
		)
		(stroke
			(width 0)
			(type solid)
		)
		(fill yes)
		(layer "In6.Cu")
		(net "M_C_CPU1_SA_DQ<24>")
	)
	(gr_poly
		(pts
			(xy 88.432894 -266.332462) (xy 88.385904 -266.180062) (xy 88.124284 -266.180062) (xy 88.077294 -266.332462)
			(xy 88.077294 -266.376658) (xy 88.432894 -266.376658)
		)
		(stroke
			(width 0)
			(type solid)
		)
		(fill yes)
		(layer "In6.Cu")
		(net "M_C_CPU1_SA_DQ<27>")
	)
	(gr_poly
		(pts
			(xy 88.432894 -265.92403) (xy 88.432894 -265.87958) (xy 88.077294 -265.87958) (xy 88.077294 -265.92403)
			(xy 88.124284 -266.07643) (xy 88.385904 -266.07643)
		)
		(stroke
			(width 0)
			(type solid)
		)
		(fill yes)
		(layer "In6.Cu")
		(net "M_C_CPU1_SA_DQS_DP<3>")
	)
	(gr_poly
		(pts
			(xy 88.432894 -264.70483) (xy 88.385904 -264.55243) (xy 88.124284 -264.55243) (xy 88.077294 -264.70483)
			(xy 88.077294 -264.749026) (xy 88.432894 -264.749026)
		)
		(stroke
			(width 0)
			(type solid)
		)
		(fill yes)
		(layer "In6.Cu")
		(net "M_C_CPU1_SA_DQS_DP<8>")
	)
	(gr_poly
		(pts
			(xy 88.432894 -264.29589) (xy 88.432894 -264.251694) (xy 88.077294 -264.251694) (xy 88.077294 -264.29589)
			(xy 88.124284 -264.44829) (xy 88.385904 -264.44829)
		)
		(stroke
			(width 0)
			(type solid)
		)
		(fill yes)
		(layer "In6.Cu")
		(net "M_C_CPU1_SA_DQ<28>")
	)
	(gr_poly
		(pts
			(xy 88.432894 -263.07669) (xy 88.385904 -262.92429) (xy 88.124284 -262.92429) (xy 88.077294 -263.07669)
			(xy 88.077294 -263.12114) (xy 88.432894 -263.12114)
		)
		(stroke
			(width 0)
			(type solid)
		)
		(fill yes)
		(layer "In6.Cu")
		(net "M_C_CPU1_SA_DQ<31>")
	)
	(gr_poly
		(pts
			(xy 88.432894 -262.668258) (xy 88.432894 -262.623808) (xy 88.077294 -262.623808) (xy 88.077294 -262.668258)
			(xy 88.124284 -262.820658) (xy 88.385904 -262.820658)
		)
		(stroke
			(width 0)
			(type solid)
		)
		(fill yes)
		(layer "In6.Cu")
		(net "M_C_CPU1_SA_CB<2>")
	)
	(gr_poly
		(pts
			(xy 88.432894 -261.449058) (xy 88.385904 -261.296658) (xy 88.124284 -261.296658) (xy 88.077294 -261.449058)
			(xy 88.077294 -261.493508) (xy 88.432894 -261.493508)
		)
		(stroke
			(width 0)
			(type solid)
		)
		(fill yes)
		(layer "In6.Cu")
		(net "M_C_CPU1_SA_CB<1>")
	)
	(gr_poly
		(pts
			(xy 88.432894 -261.040626) (xy 88.432894 -260.996176) (xy 88.077294 -260.996176) (xy 88.077294 -261.040626)
			(xy 88.124284 -261.193026) (xy 88.385904 -261.193026)
		)
		(stroke
			(width 0)
			(type solid)
		)
		(fill yes)
		(layer "In6.Cu")
		(net "M_C_CPU1_SA_DQS_DN<9>")
	)
	(gr_poly
		(pts
			(xy 88.432894 -259.821426) (xy 88.385904 -259.669026) (xy 88.124284 -259.669026) (xy 88.077294 -259.821426)
			(xy 88.077294 -259.865622) (xy 88.432894 -259.865622)
		)
		(stroke
			(width 0)
			(type solid)
		)
		(fill yes)
		(layer "In6.Cu")
		(net "M_C_CPU1_SA_DQS_DN<4>")
	)
	(gr_poly
		(pts
			(xy 88.432894 -259.412486) (xy 88.432894 -259.36829) (xy 88.077294 -259.36829) (xy 88.077294 -259.412486)
			(xy 88.124284 -259.564886) (xy 88.385904 -259.564886)
		)
		(stroke
			(width 0)
			(type solid)
		)
		(fill yes)
		(layer "In6.Cu")
		(net "M_C_CPU1_SA_CB<6>")
	)
	(gr_poly
		(pts
			(xy 88.432894 -258.193286) (xy 88.385904 -258.040886) (xy 88.124284 -258.040886) (xy 88.077294 -258.193286)
			(xy 88.077294 -258.237736) (xy 88.432894 -258.237736)
		)
		(stroke
			(width 0)
			(type solid)
		)
		(fill yes)
		(layer "In6.Cu")
		(net "M_C_CPU1_SA_CB<5>")
	)
	(gr_poly
		(pts
			(xy 88.432894 -256.565654) (xy 88.385904 -256.413254) (xy 88.124284 -256.413254) (xy 88.077294 -256.565654)
			(xy 88.077294 -256.610104) (xy 88.432894 -256.610104)
		)
		(stroke
			(width 0)
			(type solid)
		)
		(fill yes)
		(layer "In6.Cu")
		(net "M_D_CPU1_SB_RSP<0>")
	)
	(gr_poly
		(pts
			(xy 88.432894 -256.157222) (xy 88.432894 -256.112772) (xy 88.077294 -256.112772) (xy 88.077294 -256.157222)
			(xy 88.124284 -256.309622) (xy 88.385904 -256.309622)
		)
		(stroke
			(width 0)
			(type solid)
		)
		(fill yes)
		(layer "In6.Cu")
		(net "M_D_CPU1_SA_RSP<1>")
	)
	(gr_poly
		(pts
			(xy 88.432894 -254.938022) (xy 88.385904 -254.785622) (xy 88.124284 -254.785622) (xy 88.077294 -254.938022)
			(xy 88.077294 -254.982218) (xy 88.432894 -254.982218)
		)
		(stroke
			(width 0)
			(type solid)
		)
		(fill yes)
		(layer "In6.Cu")
		(net "M_C_CPU1_SB_RSP<0>")
	)
	(gr_poly
		(pts
			(xy 88.432894 -254.529082) (xy 88.432894 -254.484886) (xy 88.077294 -254.484886) (xy 88.077294 -254.529082)
			(xy 88.124284 -254.681482) (xy 88.385904 -254.681482)
		)
		(stroke
			(width 0)
			(type solid)
		)
		(fill yes)
		(layer "In6.Cu")
		(net "M_C_CPU1_SA_RSP<1>")
	)
	(gr_poly
		(pts
			(xy 88.514174 -272.900902) (xy 88.405716 -272.784062) (xy 88.367362 -272.761964) (xy 88.189562 -273.069812)
			(xy 88.227916 -273.09191) (xy 88.383364 -273.12747)
		)
		(stroke
			(width 0)
			(type solid)
		)
		(fill yes)
		(layer "In6.Cu")
		(net "M_C_CPU1_SA_DQ<8>")
	)
	(gr_poly
		(pts
			(xy 88.648794 -224.85223) (xy 88.687148 -224.830132) (xy 88.509348 -224.522284) (xy 88.470994 -224.544382)
			(xy 88.362536 -224.661222) (xy 88.493346 -224.88779)
		)
		(stroke
			(width 0)
			(type solid)
		)
		(fill yes)
		(layer "In6.Cu")
		(net "M_C_CPU1_SB_DQ<28>")
	)
	(gr_poly
		(pts
			(xy 88.64981 -226.482656) (xy 88.688164 -226.460558) (xy 88.510364 -226.15271) (xy 88.47201 -226.174808)
			(xy 88.363552 -226.291648) (xy 88.494362 -226.518216)
		)
		(stroke
			(width 0)
			(type solid)
		)
		(fill yes)
		(layer "In6.Cu")
		(net "M_C_CPU1_SB_DQS_DN<8>")
	)
	(gr_poly
		(pts
			(xy 88.757506 -225.858324) (xy 88.865964 -225.741484) (xy 88.735154 -225.514916) (xy 88.579706 -225.550476)
			(xy 88.541352 -225.572574) (xy 88.719152 -225.880422)
		)
		(stroke
			(width 0)
			(type solid)
		)
		(fill yes)
		(layer "In6.Cu")
		(net "M_C_CPU1_SB_DQS_DP<8>")
	)
	(gr_poly
		(pts
			(xy 88.790272 -243.718334) (xy 88.790272 -243.674138) (xy 88.434672 -243.674138) (xy 88.434672 -243.718334)
			(xy 88.481662 -243.870734) (xy 88.743282 -243.870734)
		)
		(stroke
			(width 0)
			(type solid)
		)
		(fill yes)
		(layer "In6.Cu")
		(net "M_C_CPU1_SB_DQ<1>")
	)
	(gr_poly
		(pts
			(xy 88.792558 -273.01952) (xy 88.754204 -272.997422) (xy 88.598756 -272.961862) (xy 88.467946 -273.18843)
			(xy 88.576404 -273.30527) (xy 88.614758 -273.327368)
		)
		(stroke
			(width 0)
			(type solid)
		)
		(fill yes)
		(layer "In6.Cu")
		(net "M_D_CPU1_SA_DQ<7>")
	)
	(gr_poly
		(pts
			(xy 88.792558 -242.499642) (xy 88.745568 -242.347242) (xy 88.483948 -242.347242) (xy 88.436958 -242.499642)
			(xy 88.436958 -242.543838) (xy 88.792558 -242.543838)
		)
		(stroke
			(width 0)
			(type solid)
		)
		(fill yes)
		(layer "In6.Cu")
		(net "M_C_CPU1_SB_DQS_DN<0>")
	)
	(gr_poly
		(pts
			(xy 88.793066 -237.207298) (xy 88.793066 -237.163102) (xy 88.437466 -237.163102) (xy 88.437466 -237.207298)
			(xy 88.484456 -237.359698) (xy 88.746076 -237.359698)
		)
		(stroke
			(width 0)
			(type solid)
		)
		(fill yes)
		(layer "In6.Cu")
		(net "M_C_CPU1_SB_DQS_DN<6>")
	)
	(gr_poly
		(pts
			(xy 88.793066 -235.988098) (xy 88.746076 -235.835698) (xy 88.484456 -235.835698) (xy 88.437466 -235.988098)
			(xy 88.437466 -236.032548) (xy 88.793066 -236.032548)
		)
		(stroke
			(width 0)
			(type solid)
		)
		(fill yes)
		(layer "In6.Cu")
		(net "M_C_CPU1_SB_DQ<14>")
	)
	(gr_poly
		(pts
			(xy 88.801448 -248.602246) (xy 88.801448 -248.557796) (xy 88.445848 -248.557796) (xy 88.445848 -248.602246)
			(xy 88.492838 -248.754646) (xy 88.754458 -248.754646)
		)
		(stroke
			(width 0)
			(type solid)
		)
		(fill yes)
		(layer "In6.Cu")
		(net "M_A_CPU1_SB_RSP<0>")
	)
	(gr_poly
		(pts
			(xy 88.801448 -247.382538) (xy 88.754458 -247.230138) (xy 88.492838 -247.230138) (xy 88.445848 -247.382538)
			(xy 88.445848 -247.426734) (xy 88.801448 -247.426734)
		)
		(stroke
			(width 0)
			(type solid)
		)
		(fill yes)
		(layer "In6.Cu")
		(net "M_A_CPU1_SB_RSP<1>")
	)
	(gr_poly
		(pts
			(xy 88.801448 -245.754906) (xy 88.754458 -245.602506) (xy 88.492838 -245.602506) (xy 88.445848 -245.754906)
			(xy 88.445848 -245.799102) (xy 88.801448 -245.799102)
		)
		(stroke
			(width 0)
			(type solid)
		)
		(fill yes)
		(layer "In6.Cu")
		(net "M_D_CPU1_SB_CS_N<3>")
	)
	(gr_poly
		(pts
			(xy 88.801448 -245.346474) (xy 88.801448 -245.302278) (xy 88.445848 -245.302278) (xy 88.445848 -245.346474)
			(xy 88.492838 -245.498874) (xy 88.754458 -245.498874)
		)
		(stroke
			(width 0)
			(type solid)
		)
		(fill yes)
		(layer "In6.Cu")
		(net "M_D_CPU1_SB_CS_N<0>")
	)
	(gr_poly
		(pts
			(xy 88.801448 -244.126766) (xy 88.754458 -243.974366) (xy 88.492838 -243.974366) (xy 88.445848 -244.126766)
			(xy 88.445848 -244.171216) (xy 88.801448 -244.171216)
		)
		(stroke
			(width 0)
			(type solid)
		)
		(fill yes)
		(layer "In6.Cu")
		(net "M_C_CPU1_SB_DQ<2>")
	)
	(gr_poly
		(pts
			(xy 88.801448 -242.090702) (xy 88.801448 -242.046506) (xy 88.445848 -242.046506) (xy 88.445848 -242.090702)
			(xy 88.492838 -242.243102) (xy 88.754458 -242.243102)
		)
		(stroke
			(width 0)
			(type solid)
		)
		(fill yes)
		(layer "In6.Cu")
		(net "M_C_CPU1_SB_DQS_DN<5>")
	)
	(gr_poly
		(pts
			(xy 88.801448 -240.871502) (xy 88.754458 -240.719102) (xy 88.492838 -240.719102) (xy 88.445848 -240.871502)
			(xy 88.445848 -240.915698) (xy 88.801448 -240.915698)
		)
		(stroke
			(width 0)
			(type solid)
		)
		(fill yes)
		(layer "In6.Cu")
		(net "M_C_CPU1_SB_DQ<6>")
	)
	(gr_poly
		(pts
			(xy 88.801448 -240.46307) (xy 88.801448 -240.418874) (xy 88.445848 -240.418874) (xy 88.445848 -240.46307)
			(xy 88.492838 -240.61547) (xy 88.754458 -240.61547)
		)
		(stroke
			(width 0)
			(type solid)
		)
		(fill yes)
		(layer "In6.Cu")
		(net "M_C_CPU1_SB_DQ<5>")
	)
	(gr_poly
		(pts
			(xy 88.801448 -239.243362) (xy 88.754458 -239.090962) (xy 88.492838 -239.090962) (xy 88.445848 -239.243362)
			(xy 88.445848 -239.287812) (xy 88.801448 -239.287812)
		)
		(stroke
			(width 0)
			(type solid)
		)
		(fill yes)
		(layer "In6.Cu")
		(net "M_C_CPU1_SB_DQ<10>")
	)
	(gr_poly
		(pts
			(xy 88.801448 -238.835438) (xy 88.801448 -238.790988) (xy 88.445848 -238.790988) (xy 88.445848 -238.835438)
			(xy 88.492838 -238.987838) (xy 88.754458 -238.987838)
		)
		(stroke
			(width 0)
			(type solid)
		)
		(fill yes)
		(layer "In6.Cu")
		(net "M_C_CPU1_SB_DQ<9>")
	)
	(gr_poly
		(pts
			(xy 88.801448 -237.61573) (xy 88.754458 -237.46333) (xy 88.492838 -237.46333) (xy 88.445848 -237.61573)
			(xy 88.445848 -237.659926) (xy 88.801448 -237.659926)
		)
		(stroke
			(width 0)
			(type solid)
		)
		(fill yes)
		(layer "In6.Cu")
		(net "M_C_CPU1_SB_DQS_DN<1>")
	)
	(gr_poly
		(pts
			(xy 88.801448 -235.579666) (xy 88.801448 -235.53547) (xy 88.445848 -235.53547) (xy 88.445848 -235.579666)
			(xy 88.492838 -235.732066) (xy 88.754458 -235.732066)
		)
		(stroke
			(width 0)
			(type solid)
		)
		(fill yes)
		(layer "In6.Cu")
		(net "M_C_CPU1_SB_DQ<13>")
	)
	(gr_poly
		(pts
			(xy 88.801448 -234.360466) (xy 88.754458 -234.208066) (xy 88.492838 -234.208066) (xy 88.445848 -234.360466)
			(xy 88.445848 -234.404662) (xy 88.801448 -234.404662)
		)
		(stroke
			(width 0)
			(type solid)
		)
		(fill yes)
		(layer "In6.Cu")
		(net "M_D_CPU1_SB_DQ<18>")
	)
	(gr_poly
		(pts
			(xy 88.801448 -233.952034) (xy 88.801448 -233.907838) (xy 88.445848 -233.907838) (xy 88.445848 -233.952034)
			(xy 88.492838 -234.104434) (xy 88.754458 -234.104434)
		)
		(stroke
			(width 0)
			(type solid)
		)
		(fill yes)
		(layer "In6.Cu")
		(net "M_D_CPU1_SB_DQ<17>")
	)
	(gr_poly
		(pts
			(xy 88.801448 -232.324402) (xy 88.801448 -232.279952) (xy 88.445848 -232.279952) (xy 88.445848 -232.324402)
			(xy 88.492838 -232.476802) (xy 88.754458 -232.476802)
		)
		(stroke
			(width 0)
			(type solid)
		)
		(fill yes)
		(layer "In6.Cu")
		(net "M_D_CPU1_SB_DQS_DP<2>")
	)
	(gr_poly
		(pts
			(xy 88.801448 -231.104694) (xy 88.754458 -230.952294) (xy 88.492838 -230.952294) (xy 88.445848 -231.104694)
			(xy 88.445848 -231.14889) (xy 88.801448 -231.14889)
		)
		(stroke
			(width 0)
			(type solid)
		)
		(fill yes)
		(layer "In6.Cu")
		(net "M_D_CPU1_SB_DQS_DP<7>")
	)
	(gr_poly
		(pts
			(xy 88.801448 -230.696262) (xy 88.801448 -230.652066) (xy 88.445848 -230.652066) (xy 88.445848 -230.696262)
			(xy 88.492838 -230.848662) (xy 88.754458 -230.848662)
		)
		(stroke
			(width 0)
			(type solid)
		)
		(fill yes)
		(layer "In6.Cu")
		(net "M_D_CPU1_SB_DQ<20>")
	)
	(gr_poly
		(pts
			(xy 88.801448 -229.477062) (xy 88.754458 -229.324662) (xy 88.492838 -229.324662) (xy 88.445848 -229.477062)
			(xy 88.445848 -229.521258) (xy 88.801448 -229.521258)
		)
		(stroke
			(width 0)
			(type solid)
		)
		(fill yes)
		(layer "In6.Cu")
		(net "M_D_CPU1_SB_DQ<23>")
	)
	(gr_poly
		(pts
			(xy 88.801448 -229.06863) (xy 88.801448 -229.024434) (xy 88.445848 -229.024434) (xy 88.445848 -229.06863)
			(xy 88.492838 -229.22103) (xy 88.754458 -229.22103)
		)
		(stroke
			(width 0)
			(type solid)
		)
		(fill yes)
		(layer "In6.Cu")
		(net "M_C_CPU1_SB_DQ<26>")
	)
	(gr_poly
		(pts
			(xy 88.801448 -227.848922) (xy 88.754458 -227.696522) (xy 88.492838 -227.696522) (xy 88.445848 -227.848922)
			(xy 88.445848 -227.893372) (xy 88.801448 -227.893372)
		)
		(stroke
			(width 0)
			(type solid)
		)
		(fill yes)
		(layer "In6.Cu")
		(net "M_C_CPU1_SB_DQ<27>")
	)
	(gr_poly
		(pts
			(xy 88.801448 -227.440998) (xy 88.801448 -227.396548) (xy 88.445848 -227.396548) (xy 88.445848 -227.440998)
			(xy 88.492838 -227.593398) (xy 88.754458 -227.593398)
		)
		(stroke
			(width 0)
			(type solid)
		)
		(fill yes)
		(layer "In6.Cu")
		(net "M_C_CPU1_SB_DQS_DP<3>")
	)
	(gr_poly
		(pts
			(xy 88.801448 -222.965518) (xy 88.754458 -222.813118) (xy 88.492838 -222.813118) (xy 88.445848 -222.965518)
			(xy 88.445848 -223.009968) (xy 88.801448 -223.009968)
		)
		(stroke
			(width 0)
			(type solid)
		)
		(fill yes)
		(layer "In6.Cu")
		(net "M_C_CPU1_SB_DQ<29>")
	)
	(gr_poly
		(pts
			(xy 88.896952 -272.029174) (xy 88.849962 -271.876774) (xy 88.588342 -271.876774) (xy 88.541352 -272.029174)
			(xy 88.541352 -272.073624) (xy 88.896952 -272.073624)
		)
		(stroke
			(width 0)
			(type solid)
		)
		(fill yes)
		(layer "In6.Cu")
		(net "M_C_CPU1_SA_DQ<10>")
	)
	(gr_poly
		(pts
			(xy 88.899492 -263.482074) (xy 88.899492 -263.437624) (xy 88.543892 -263.437624) (xy 88.543892 -263.482074)
			(xy 88.590882 -263.634474) (xy 88.852502 -263.634474)
		)
		(stroke
			(width 0)
			(type solid)
		)
		(fill yes)
		(layer "In6.Cu")
		(net "M_C_CPU1_SA_DQ<29>")
	)
	(gr_poly
		(pts
			(xy 88.902794 -279.759664) (xy 88.902794 -279.715468) (xy 88.547194 -279.715468) (xy 88.547194 -279.759664)
			(xy 88.594184 -279.912064) (xy 88.855804 -279.912064)
		)
		(stroke
			(width 0)
			(type solid)
		)
		(fill yes)
		(layer "In6.Cu")
		(net "M_D_CPU1_SA_DQ<0>")
	)
	(gr_poly
		(pts
			(xy 88.902794 -278.540718) (xy 88.855804 -278.388318) (xy 88.594184 -278.388318) (xy 88.547194 -278.540718)
			(xy 88.547194 -278.585168) (xy 88.902794 -278.585168)
		)
		(stroke
			(width 0)
			(type solid)
		)
		(fill yes)
		(layer "In6.Cu")
		(net "M_D_CPU1_SA_DQ<3>")
	)
	(gr_poly
		(pts
			(xy 88.902794 -276.504146) (xy 88.902794 -276.45995) (xy 88.547194 -276.45995) (xy 88.547194 -276.504146)
			(xy 88.594184 -276.656546) (xy 88.855804 -276.656546)
		)
		(stroke
			(width 0)
			(type solid)
		)
		(fill yes)
		(layer "In6.Cu")
		(net "M_D_CPU1_SA_DQS_DN<5>")
	)
	(gr_poly
		(pts
			(xy 88.902794 -274.876514) (xy 88.902794 -274.832064) (xy 88.547194 -274.832064) (xy 88.547194 -274.876514)
			(xy 88.594184 -275.028914) (xy 88.855804 -275.028914)
		)
		(stroke
			(width 0)
			(type solid)
		)
		(fill yes)
		(layer "In6.Cu")
		(net "M_D_CPU1_SA_DQ<4>")
	)
	(gr_poly
		(pts
			(xy 88.902794 -270.40205) (xy 88.855804 -270.24965) (xy 88.594184 -270.24965) (xy 88.547194 -270.40205)
			(xy 88.547194 -270.446246) (xy 88.902794 -270.446246)
		)
		(stroke
			(width 0)
			(type solid)
		)
		(fill yes)
		(layer "In6.Cu")
		(net "M_C_CPU1_SA_DQS_DN<1>")
	)
	(gr_poly
		(pts
			(xy 88.902794 -269.99311) (xy 88.902794 -269.948914) (xy 88.547194 -269.948914) (xy 88.547194 -269.99311)
			(xy 88.594184 -270.14551) (xy 88.855804 -270.14551)
		)
		(stroke
			(width 0)
			(type solid)
		)
		(fill yes)
		(layer "In6.Cu")
		(net "M_C_CPU1_SA_DQS_DN<6>")
	)
	(gr_poly
		(pts
			(xy 88.902794 -268.77391) (xy 88.855804 -268.62151) (xy 88.594184 -268.62151) (xy 88.547194 -268.77391)
			(xy 88.547194 -268.81836) (xy 88.902794 -268.81836)
		)
		(stroke
			(width 0)
			(type solid)
		)
		(fill yes)
		(layer "In6.Cu")
		(net "M_C_CPU1_SA_DQ<14>")
	)
	(gr_poly
		(pts
			(xy 88.902794 -268.365478) (xy 88.902794 -268.321028) (xy 88.547194 -268.321028) (xy 88.547194 -268.365478)
			(xy 88.594184 -268.517878) (xy 88.855804 -268.517878)
		)
		(stroke
			(width 0)
			(type solid)
		)
		(fill yes)
		(layer "In6.Cu")
		(net "M_C_CPU1_SA_DQ<13>")
	)
	(gr_poly
		(pts
			(xy 88.902794 -267.146278) (xy 88.855804 -266.993878) (xy 88.594184 -266.993878) (xy 88.547194 -267.146278)
			(xy 88.547194 -267.190474) (xy 88.902794 -267.190474)
		)
		(stroke
			(width 0)
			(type solid)
		)
		(fill yes)
		(layer "In6.Cu")
		(net "M_C_CPU1_SA_DQ<26>")
	)
	(gr_poly
		(pts
			(xy 88.902794 -266.737846) (xy 88.902794 -266.693396) (xy 88.547194 -266.693396) (xy 88.547194 -266.737846)
			(xy 88.594184 -266.890246) (xy 88.855804 -266.890246)
		)
		(stroke
			(width 0)
			(type solid)
		)
		(fill yes)
		(layer "In6.Cu")
		(net "M_C_CPU1_SA_DQ<25>")
	)
	(gr_poly
		(pts
			(xy 88.902794 -265.518646) (xy 88.855804 -265.366246) (xy 88.594184 -265.366246) (xy 88.547194 -265.518646)
			(xy 88.547194 -265.562842) (xy 88.902794 -265.562842)
		)
		(stroke
			(width 0)
			(type solid)
		)
		(fill yes)
		(layer "In6.Cu")
		(net "M_C_CPU1_SA_DQS_DN<3>")
	)
	(gr_poly
		(pts
			(xy 88.902794 -265.109706) (xy 88.902794 -265.06551) (xy 88.547194 -265.06551) (xy 88.547194 -265.109706)
			(xy 88.594184 -265.262106) (xy 88.855804 -265.262106)
		)
		(stroke
			(width 0)
			(type solid)
		)
		(fill yes)
		(layer "In6.Cu")
		(net "M_C_CPU1_SA_DQS_DN<8>")
	)
	(gr_poly
		(pts
			(xy 88.902794 -263.891014) (xy 88.855804 -263.738614) (xy 88.594184 -263.738614) (xy 88.547194 -263.891014)
			(xy 88.547194 -263.93521) (xy 88.902794 -263.93521)
		)
		(stroke
			(width 0)
			(type solid)
		)
		(fill yes)
		(layer "In6.Cu")
		(net "M_C_CPU1_SA_DQ<30>")
	)
	(gr_poly
		(pts
			(xy 88.902794 -259.00761) (xy 88.855804 -258.85521) (xy 88.594184 -258.85521) (xy 88.547194 -259.00761)
			(xy 88.547194 -259.051806) (xy 88.902794 -259.051806)
		)
		(stroke
			(width 0)
			(type solid)
		)
		(fill yes)
		(layer "In6.Cu")
		(net "M_C_CPU1_SA_CB<4>")
	)
	(gr_poly
		(pts
			(xy 88.902794 -258.59867) (xy 88.902794 -258.554474) (xy 88.547194 -258.554474) (xy 88.547194 -258.59867)
			(xy 88.594184 -258.75107) (xy 88.855804 -258.75107)
		)
		(stroke
			(width 0)
			(type solid)
		)
		(fill yes)
		(layer "In6.Cu")
		(net "M_C_CPU1_SA_CB<7>")
	)
	(gr_poly
		(pts
			(xy 88.902794 -256.971038) (xy 88.902794 -256.926588) (xy 88.547194 -256.926588) (xy 88.547194 -256.971038)
			(xy 88.594184 -257.123438) (xy 88.855804 -257.123438)
		)
		(stroke
			(width 0)
			(type solid)
		)
		(fill yes)
		(layer "In6.Cu")
		(net "M_D_CPU1_SA_RSP<0>")
	)
	(gr_poly
		(pts
			(xy 88.902794 -254.124206) (xy 88.855804 -253.971806) (xy 88.594184 -253.971806) (xy 88.547194 -254.124206)
			(xy 88.547194 -254.168402) (xy 88.902794 -254.168402)
		)
		(stroke
			(width 0)
			(type solid)
		)
		(fill yes)
		(layer "In6.Cu")
		(net "M_C_CPU1_SB_RSP<1>")
	)
	(gr_poly
		(pts
			(xy 88.90889 -271.62125) (xy 88.90889 -271.5768) (xy 88.55329 -271.5768) (xy 88.55329 -271.62125)
			(xy 88.60028 -271.77365) (xy 88.8619 -271.77365)
		)
		(stroke
			(width 0)
			(type solid)
		)
		(fill yes)
		(layer "In6.Cu")
		(net "M_C_CPU1_SA_DQ<9>")
	)
	(gr_poly
		(pts
			(xy 88.90889 -262.262874) (xy 88.8619 -262.110474) (xy 88.60028 -262.110474) (xy 88.55329 -262.262874)
			(xy 88.55329 -262.30707) (xy 88.90889 -262.30707)
		)
		(stroke
			(width 0)
			(type solid)
		)
		(fill yes)
		(layer "In6.Cu")
		(net "M_C_CPU1_SA_CB<0>")
	)
	(gr_poly
		(pts
			(xy 88.90889 -261.854442) (xy 88.90889 -261.810246) (xy 88.55329 -261.810246) (xy 88.55329 -261.854442)
			(xy 88.60028 -262.006842) (xy 88.8619 -262.006842)
		)
		(stroke
			(width 0)
			(type solid)
		)
		(fill yes)
		(layer "In6.Cu")
		(net "M_C_CPU1_SA_CB<3>")
	)
	(gr_poly
		(pts
			(xy 88.90889 -260.634734) (xy 88.8619 -260.482334) (xy 88.60028 -260.482334) (xy 88.55329 -260.634734)
			(xy 88.55329 -260.679184) (xy 88.90889 -260.679184)
		)
		(stroke
			(width 0)
			(type solid)
		)
		(fill yes)
		(layer "In6.Cu")
		(net "M_C_CPU1_SA_DQS_DP<9>")
	)
	(gr_poly
		(pts
			(xy 88.90889 -260.22681) (xy 88.90889 -260.18236) (xy 88.55329 -260.18236) (xy 88.55329 -260.22681)
			(xy 88.60028 -260.37921) (xy 88.8619 -260.37921)
		)
		(stroke
			(width 0)
			(type solid)
		)
		(fill yes)
		(layer "In6.Cu")
		(net "M_C_CPU1_SA_DQS_DP<4>")
	)
	(gr_poly
		(pts
			(xy 88.90889 -255.751838) (xy 88.8619 -255.599438) (xy 88.60028 -255.599438) (xy 88.55329 -255.751838)
			(xy 88.55329 -255.796034) (xy 88.90889 -255.796034)
		)
		(stroke
			(width 0)
			(type solid)
		)
		(fill yes)
		(layer "In6.Cu")
		(net "M_D_CPU1_SB_RSP<1>")
	)
	(gr_poly
		(pts
			(xy 88.90889 -255.343406) (xy 88.90889 -255.29921) (xy 88.55329 -255.29921) (xy 88.55329 -255.343406)
			(xy 88.60028 -255.495806) (xy 88.8619 -255.495806)
		)
		(stroke
			(width 0)
			(type solid)
		)
		(fill yes)
		(layer "In6.Cu")
		(net "M_C_CPU1_SA_RSP<0>")
	)
	(gr_poly
		(pts
			(xy 88.911176 -278.132286) (xy 88.911176 -278.08809) (xy 88.555576 -278.08809) (xy 88.555576 -278.132286)
			(xy 88.602566 -278.284686) (xy 88.864186 -278.284686)
		)
		(stroke
			(width 0)
			(type solid)
		)
		(fill yes)
		(layer "In6.Cu")
		(net "M_D_CPU1_SA_DQS_DP<0>")
	)
	(gr_poly
		(pts
			(xy 88.977724 -273.724878) (xy 88.869266 -273.608038) (xy 88.830912 -273.58594) (xy 88.653112 -273.893788)
			(xy 88.691466 -273.915886) (xy 88.846914 -273.951446)
		)
		(stroke
			(width 0)
			(type solid)
		)
		(fill yes)
		(layer "In6.Cu")
		(net "M_D_CPU1_SA_DQ<5>")
	)
	(gr_poly
		(pts
			(xy 89.111074 -224.025714) (xy 89.149428 -224.003616) (xy 88.971628 -223.695768) (xy 88.933274 -223.717866)
			(xy 88.824816 -223.834706) (xy 88.955626 -224.061274)
		)
		(stroke
			(width 0)
			(type solid)
		)
		(fill yes)
		(layer "In6.Cu")
		(net "M_C_CPU1_SB_DQ<31>")
	)
	(gr_poly
		(pts
			(xy 89.119456 -225.668078) (xy 89.15781 -225.64598) (xy 88.98001 -225.338132) (xy 88.941656 -225.36023)
			(xy 88.833198 -225.47707) (xy 88.964008 -225.703638)
		)
		(stroke
			(width 0)
			(type solid)
		)
		(fill yes)
		(layer "In6.Cu")
		(net "M_C_CPU1_SB_DQ<28>")
	)
	(gr_poly
		(pts
			(xy 89.229438 -225.048318) (xy 89.337896 -224.931478) (xy 89.207086 -224.70491) (xy 89.051638 -224.74047)
			(xy 89.013284 -224.762568) (xy 89.191084 -225.070416)
		)
		(stroke
			(width 0)
			(type solid)
		)
		(fill yes)
		(layer "In6.Cu")
		(net "M_C_CPU1_SB_DQ<30>")
	)
	(gr_poly
		(pts
			(xy 89.25433 -246.16029) (xy 89.25433 -246.116094) (xy 88.89873 -246.116094) (xy 88.89873 -246.16029)
			(xy 88.94572 -246.31269) (xy 89.20734 -246.31269)
		)
		(stroke
			(width 0)
			(type solid)
		)
		(fill yes)
		(layer "In6.Cu")
		(net "M_D_CPU1_SB_CS_N<2>")
	)
	(gr_poly
		(pts
			(xy 89.25433 -244.940582) (xy 89.20734 -244.788182) (xy 88.94572 -244.788182) (xy 88.89873 -244.940582)
			(xy 88.89873 -244.985032) (xy 89.25433 -244.985032)
		)
		(stroke
			(width 0)
			(type solid)
		)
		(fill yes)
		(layer "In6.Cu")
		(net "M_D_CPU1_SB_CS_N<1>")
	)
	(gr_poly
		(pts
			(xy 89.25433 -244.532658) (xy 89.25433 -244.488208) (xy 88.89873 -244.488208) (xy 88.89873 -244.532658)
			(xy 88.94572 -244.685058) (xy 89.20734 -244.685058)
		)
		(stroke
			(width 0)
			(type solid)
		)
		(fill yes)
		(layer "In6.Cu")
		(net "M_C_CPU1_SB_DQ<0>")
	)
	(gr_poly
		(pts
			(xy 89.25433 -242.905026) (xy 89.25433 -242.860576) (xy 88.89873 -242.860576) (xy 88.89873 -242.905026)
			(xy 88.94572 -243.057426) (xy 89.20734 -243.057426)
		)
		(stroke
			(width 0)
			(type solid)
		)
		(fill yes)
		(layer "In6.Cu")
		(net "M_C_CPU1_SB_DQS_DP<0>")
	)
	(gr_poly
		(pts
			(xy 89.25433 -241.685318) (xy 89.20734 -241.532918) (xy 88.94572 -241.532918) (xy 88.89873 -241.685318)
			(xy 88.89873 -241.729514) (xy 89.25433 -241.729514)
		)
		(stroke
			(width 0)
			(type solid)
		)
		(fill yes)
		(layer "In6.Cu")
		(net "M_C_CPU1_SB_DQS_DP<5>")
	)
	(gr_poly
		(pts
			(xy 89.25433 -241.276886) (xy 89.25433 -241.23269) (xy 88.89873 -241.23269) (xy 88.89873 -241.276886)
			(xy 88.94572 -241.429286) (xy 89.20734 -241.429286)
		)
		(stroke
			(width 0)
			(type solid)
		)
		(fill yes)
		(layer "In6.Cu")
		(net "M_C_CPU1_SB_DQ<4>")
	)
	(gr_poly
		(pts
			(xy 89.25433 -240.057178) (xy 89.20734 -239.904778) (xy 88.94572 -239.904778) (xy 88.89873 -240.057178)
			(xy 88.89873 -240.101628) (xy 89.25433 -240.101628)
		)
		(stroke
			(width 0)
			(type solid)
		)
		(fill yes)
		(layer "In6.Cu")
		(net "M_C_CPU1_SB_DQ<7>")
	)
	(gr_poly
		(pts
			(xy 89.25433 -239.649254) (xy 89.25433 -239.604804) (xy 88.89873 -239.604804) (xy 88.89873 -239.649254)
			(xy 88.94572 -239.801654) (xy 89.20734 -239.801654)
		)
		(stroke
			(width 0)
			(type solid)
		)
		(fill yes)
		(layer "In6.Cu")
		(net "M_C_CPU1_SB_DQ<8>")
	)
	(gr_poly
		(pts
			(xy 89.25433 -238.429546) (xy 89.20734 -238.277146) (xy 88.94572 -238.277146) (xy 88.89873 -238.429546)
			(xy 88.89873 -238.473996) (xy 89.25433 -238.473996)
		)
		(stroke
			(width 0)
			(type solid)
		)
		(fill yes)
		(layer "In6.Cu")
		(net "M_C_CPU1_SB_DQ<11>")
	)
	(gr_poly
		(pts
			(xy 89.25433 -238.021622) (xy 89.25433 -237.977172) (xy 88.89873 -237.977172) (xy 88.89873 -238.021622)
			(xy 88.94572 -238.174022) (xy 89.20734 -238.174022)
		)
		(stroke
			(width 0)
			(type solid)
		)
		(fill yes)
		(layer "In6.Cu")
		(net "M_C_CPU1_SB_DQS_DP<1>")
	)
	(gr_poly
		(pts
			(xy 89.25433 -235.174282) (xy 89.20734 -235.021882) (xy 88.94572 -235.021882) (xy 88.89873 -235.174282)
			(xy 88.89873 -235.218478) (xy 89.25433 -235.218478)
		)
		(stroke
			(width 0)
			(type solid)
		)
		(fill yes)
		(layer "In6.Cu")
		(net "M_C_CPU1_SB_DQ<15>")
	)
	(gr_poly
		(pts
			(xy 89.25433 -234.76585) (xy 89.25433 -234.721654) (xy 88.89873 -234.721654) (xy 88.89873 -234.76585)
			(xy 88.94572 -234.91825) (xy 89.20734 -234.91825)
		)
		(stroke
			(width 0)
			(type solid)
		)
		(fill yes)
		(layer "In6.Cu")
		(net "M_D_CPU1_SB_DQ<16>")
	)
	(gr_poly
		(pts
			(xy 89.25433 -233.546142) (xy 89.20734 -233.393742) (xy 88.94572 -233.393742) (xy 88.89873 -233.546142)
			(xy 88.89873 -233.590592) (xy 89.25433 -233.590592)
		)
		(stroke
			(width 0)
			(type solid)
		)
		(fill yes)
		(layer "In6.Cu")
		(net "M_D_CPU1_SB_DQ<19>")
	)
	(gr_poly
		(pts
			(xy 89.25433 -231.91851) (xy 89.20734 -231.76611) (xy 88.94572 -231.76611) (xy 88.89873 -231.91851)
			(xy 88.89873 -231.96296) (xy 89.25433 -231.96296)
		)
		(stroke
			(width 0)
			(type solid)
		)
		(fill yes)
		(layer "In6.Cu")
		(net "M_D_CPU1_SB_DQS_DN<2>")
	)
	(gr_poly
		(pts
			(xy 89.25433 -231.510586) (xy 89.25433 -231.466136) (xy 88.89873 -231.466136) (xy 88.89873 -231.510586)
			(xy 88.94572 -231.662986) (xy 89.20734 -231.662986)
		)
		(stroke
			(width 0)
			(type solid)
		)
		(fill yes)
		(layer "In6.Cu")
		(net "M_D_CPU1_SB_DQS_DN<7>")
	)
	(gr_poly
		(pts
			(xy 89.25433 -230.290878) (xy 89.20734 -230.138478) (xy 88.94572 -230.138478) (xy 88.89873 -230.290878)
			(xy 88.89873 -230.335074) (xy 89.25433 -230.335074)
		)
		(stroke
			(width 0)
			(type solid)
		)
		(fill yes)
		(layer "In6.Cu")
		(net "M_D_CPU1_SB_DQ<22>")
	)
	(gr_poly
		(pts
			(xy 89.25433 -229.882446) (xy 89.25433 -229.83825) (xy 88.89873 -229.83825) (xy 88.89873 -229.882446)
			(xy 88.94572 -230.034846) (xy 89.20734 -230.034846)
		)
		(stroke
			(width 0)
			(type solid)
		)
		(fill yes)
		(layer "In6.Cu")
		(net "M_D_CPU1_SB_DQ<21>")
	)
	(gr_poly
		(pts
			(xy 89.25433 -228.663246) (xy 89.20734 -228.510846) (xy 88.94572 -228.510846) (xy 88.89873 -228.663246)
			(xy 88.89873 -228.707442) (xy 89.25433 -228.707442)
		)
		(stroke
			(width 0)
			(type solid)
		)
		(fill yes)
		(layer "In6.Cu")
		(net "M_C_CPU1_SB_DQ<24>")
	)
	(gr_poly
		(pts
			(xy 89.25433 -228.254814) (xy 89.25433 -228.210618) (xy 88.89873 -228.210618) (xy 88.89873 -228.254814)
			(xy 88.94572 -228.407214) (xy 89.20734 -228.407214)
		)
		(stroke
			(width 0)
			(type solid)
		)
		(fill yes)
		(layer "In6.Cu")
		(net "M_C_CPU1_SB_DQ<25>")
	)
	(gr_poly
		(pts
			(xy 89.25433 -227.035106) (xy 89.20734 -226.882706) (xy 88.94572 -226.882706) (xy 88.89873 -227.035106)
			(xy 88.89873 -227.079556) (xy 89.25433 -227.079556)
		)
		(stroke
			(width 0)
			(type solid)
		)
		(fill yes)
		(layer "In6.Cu")
		(net "M_C_CPU1_SB_DQS_DN<3>")
	)
	(gr_poly
		(pts
			(xy 89.25433 -226.627182) (xy 89.25433 -226.582732) (xy 88.89873 -226.582732) (xy 88.89873 -226.627182)
			(xy 88.94572 -226.779582) (xy 89.20734 -226.779582)
		)
		(stroke
			(width 0)
			(type solid)
		)
		(fill yes)
		(layer "In6.Cu")
		(net "M_C_CPU1_SB_DQS_DN<8>")
	)
	(gr_poly
		(pts
			(xy 89.25687 -248.196354) (xy 89.20988 -248.043954) (xy 88.94826 -248.043954) (xy 88.90127 -248.196354)
			(xy 88.90127 -248.24055) (xy 89.25687 -248.24055)
		)
		(stroke
			(width 0)
			(type solid)
		)
		(fill yes)
		(layer "In6.Cu")
		(net "M_A_CPU1_SA_RSP<0>")
	)
	(gr_poly
		(pts
			(xy 89.25687 -247.787922) (xy 89.25687 -247.743726) (xy 88.90127 -247.743726) (xy 88.90127 -247.787922)
			(xy 88.94826 -247.940322) (xy 89.20988 -247.940322)
		)
		(stroke
			(width 0)
			(type solid)
		)
		(fill yes)
		(layer "In6.Cu")
		(net "M_A_CPU1_SA_RSP<1>")
	)
	(gr_poly
		(pts
			(xy 89.25687 -236.801914) (xy 89.20988 -236.649514) (xy 88.94826 -236.649514) (xy 88.90127 -236.801914)
			(xy 88.90127 -236.846364) (xy 89.25687 -236.846364)
		)
		(stroke
			(width 0)
			(type solid)
		)
		(fill yes)
		(layer "In6.Cu")
		(net "M_C_CPU1_SB_DQS_DP<6>")
	)
	(gr_poly
		(pts
			(xy 89.25687 -236.393482) (xy 89.25687 -236.349286) (xy 88.90127 -236.349286) (xy 88.90127 -236.393482)
			(xy 88.94826 -236.545882) (xy 89.20988 -236.545882)
		)
		(stroke
			(width 0)
			(type solid)
		)
		(fill yes)
		(layer "In6.Cu")
		(net "M_C_CPU1_SB_DQ<12>")
	)
	(gr_poly
		(pts
			(xy 89.260426 -277.092156) (xy 89.222072 -277.070058) (xy 89.066624 -277.034498) (xy 88.935814 -277.261066)
			(xy 89.044272 -277.377906) (xy 89.082626 -277.400004)
		)
		(stroke
			(width 0)
			(type solid)
		)
		(fill yes)
		(layer "In6.Cu")
		(net "M_D_CPU1_SA_DQS_DN<0>")
	)
	(gr_poly
		(pts
			(xy 89.266268 -243.313458) (xy 89.219278 -243.161058) (xy 88.957658 -243.161058) (xy 88.910668 -243.313458)
			(xy 88.910668 -243.357654) (xy 89.266268 -243.357654)
		)
		(stroke
			(width 0)
			(type solid)
		)
		(fill yes)
		(layer "In6.Cu")
		(net "M_C_CPU1_SB_DQ<3>")
	)
	(gr_poly
		(pts
			(xy 89.266776 -273.826224) (xy 89.228422 -273.804126) (xy 89.072974 -273.768566) (xy 88.942164 -273.995134)
			(xy 89.050622 -274.111974) (xy 89.088976 -274.134072)
		)
		(stroke
			(width 0)
			(type solid)
		)
		(fill yes)
		(layer "In6.Cu")
		(net "M_D_CPU1_SA_DQ<6>")
	)
	(gr_poly
		(pts
			(xy 89.268808 -275.450046) (xy 89.230454 -275.427948) (xy 89.075006 -275.392388) (xy 88.944196 -275.618956)
			(xy 89.052654 -275.735796) (xy 89.091008 -275.757894)
		)
		(stroke
			(width 0)
			(type solid)
		)
		(fill yes)
		(layer "In6.Cu")
		(net "M_D_CPU1_SA_DQS_DP<5>")
	)
	(gr_poly
		(pts
			(xy 89.364312 -271.215358) (xy 89.317322 -271.062958) (xy 89.055702 -271.062958) (xy 89.008712 -271.215358)
			(xy 89.008712 -271.259808) (xy 89.364312 -271.259808)
		)
		(stroke
			(width 0)
			(type solid)
		)
		(fill yes)
		(layer "In6.Cu")
		(net "M_C_CPU1_SA_DQ<11>")
	)
	(gr_poly
		(pts
			(xy 89.364312 -261.44855) (xy 89.317322 -261.29615) (xy 89.055702 -261.29615) (xy 89.008712 -261.44855)
			(xy 89.008712 -261.493) (xy 89.364312 -261.493)
		)
		(stroke
			(width 0)
			(type solid)
		)
		(fill yes)
		(layer "In6.Cu")
		(net "M_C_CPU1_SA_CB<1>")
	)
	(gr_poly
		(pts
			(xy 89.364312 -261.040626) (xy 89.364312 -260.99643) (xy 89.008712 -260.99643) (xy 89.008712 -261.040626)
			(xy 89.055702 -261.193026) (xy 89.317322 -261.193026)
		)
		(stroke
			(width 0)
			(type solid)
		)
		(fill yes)
		(layer "In6.Cu")
		(net "M_C_CPU1_SA_DQS_DN<9>")
	)
	(gr_poly
		(pts
			(xy 89.364312 -259.820918) (xy 89.317322 -259.668518) (xy 89.055702 -259.668518) (xy 89.008712 -259.820918)
			(xy 89.008712 -259.865368) (xy 89.364312 -259.865368)
		)
		(stroke
			(width 0)
			(type solid)
		)
		(fill yes)
		(layer "In6.Cu")
		(net "M_C_CPU1_SA_DQS_DN<4>")
	)
	(gr_poly
		(pts
			(xy 89.364312 -256.157222) (xy 89.364312 -256.113026) (xy 89.008712 -256.113026) (xy 89.008712 -256.157222)
			(xy 89.055702 -256.309622) (xy 89.317322 -256.309622)
		)
		(stroke
			(width 0)
			(type solid)
		)
		(fill yes)
		(layer "In6.Cu")
		(net "M_D_CPU1_SA_RSP<1>")
	)
	(gr_poly
		(pts
			(xy 89.364312 -254.937514) (xy 89.317322 -254.785114) (xy 89.055702 -254.785114) (xy 89.008712 -254.937514)
			(xy 89.008712 -254.981964) (xy 89.364312 -254.981964)
		)
		(stroke
			(width 0)
			(type solid)
		)
		(fill yes)
		(layer "In6.Cu")
		(net "M_C_CPU1_SB_RSP<0>")
	)
	(gr_poly
		(pts
			(xy 89.366852 -272.435066) (xy 89.366852 -272.390616) (xy 89.011252 -272.390616) (xy 89.011252 -272.435066)
			(xy 89.058242 -272.587466) (xy 89.319862 -272.587466)
		)
		(stroke
			(width 0)
			(type solid)
		)
		(fill yes)
		(layer "In6.Cu")
		(net "M_C_CPU1_SA_DQ<8>")
	)
	(gr_poly
		(pts
			(xy 89.372694 -279.354788) (xy 89.325704 -279.202388) (xy 89.064084 -279.202388) (xy 89.017094 -279.354788)
			(xy 89.017094 -279.398984) (xy 89.372694 -279.398984)
		)
		(stroke
			(width 0)
			(type solid)
		)
		(fill yes)
		(layer "In6.Cu")
		(net "M_D_CPU1_SA_DQ<2>")
	)
	(gr_poly
		(pts
			(xy 89.372694 -278.945848) (xy 89.372694 -278.901652) (xy 89.017094 -278.901652) (xy 89.017094 -278.945848)
			(xy 89.064084 -279.098248) (xy 89.325704 -279.098248)
		)
		(stroke
			(width 0)
			(type solid)
		)
		(fill yes)
		(layer "In6.Cu")
		(net "M_D_CPU1_SA_DQ<1>")
	)
	(gr_poly
		(pts
			(xy 89.372694 -270.806926) (xy 89.372694 -270.76273) (xy 89.017094 -270.76273) (xy 89.017094 -270.806926)
			(xy 89.064084 -270.959326) (xy 89.325704 -270.959326)
		)
		(stroke
			(width 0)
			(type solid)
		)
		(fill yes)
		(layer "In6.Cu")
		(net "M_C_CPU1_SA_DQS_DP<1>")
	)
	(gr_poly
		(pts
			(xy 89.372694 -269.587726) (xy 89.325704 -269.435326) (xy 89.064084 -269.435326) (xy 89.017094 -269.587726)
			(xy 89.017094 -269.632176) (xy 89.372694 -269.632176)
		)
		(stroke
			(width 0)
			(type solid)
		)
		(fill yes)
		(layer "In6.Cu")
		(net "M_C_CPU1_SA_DQS_DP<6>")
	)
	(gr_poly
		(pts
			(xy 89.372694 -269.179294) (xy 89.372694 -269.134844) (xy 89.017094 -269.134844) (xy 89.017094 -269.179294)
			(xy 89.064084 -269.331694) (xy 89.325704 -269.331694)
		)
		(stroke
			(width 0)
			(type solid)
		)
		(fill yes)
		(layer "In6.Cu")
		(net "M_C_CPU1_SA_DQ<12>")
	)
	(gr_poly
		(pts
			(xy 89.372694 -267.960094) (xy 89.325704 -267.807694) (xy 89.064084 -267.807694) (xy 89.017094 -267.960094)
			(xy 89.017094 -268.004544) (xy 89.372694 -268.004544)
		)
		(stroke
			(width 0)
			(type solid)
		)
		(fill yes)
		(layer "In6.Cu")
		(net "M_C_CPU1_SA_DQ<15>")
	)
	(gr_poly
		(pts
			(xy 89.372694 -267.551662) (xy 89.372694 -267.507212) (xy 89.017094 -267.507212) (xy 89.017094 -267.551662)
			(xy 89.064084 -267.704062) (xy 89.325704 -267.704062)
		)
		(stroke
			(width 0)
			(type solid)
		)
		(fill yes)
		(layer "In6.Cu")
		(net "M_C_CPU1_SA_DQ<24>")
	)
	(gr_poly
		(pts
			(xy 89.372694 -266.332462) (xy 89.325704 -266.180062) (xy 89.064084 -266.180062) (xy 89.017094 -266.332462)
			(xy 89.017094 -266.376658) (xy 89.372694 -266.376658)
		)
		(stroke
			(width 0)
			(type solid)
		)
		(fill yes)
		(layer "In6.Cu")
		(net "M_C_CPU1_SA_DQ<27>")
	)
	(gr_poly
		(pts
			(xy 89.372694 -265.923522) (xy 89.372694 -265.879326) (xy 89.017094 -265.879326) (xy 89.017094 -265.923522)
			(xy 89.064084 -266.075922) (xy 89.325704 -266.075922)
		)
		(stroke
			(width 0)
			(type solid)
		)
		(fill yes)
		(layer "In6.Cu")
		(net "M_C_CPU1_SA_DQS_DP<3>")
	)
	(gr_poly
		(pts
			(xy 89.372694 -264.70483) (xy 89.325704 -264.55243) (xy 89.064084 -264.55243) (xy 89.017094 -264.70483)
			(xy 89.017094 -264.749026) (xy 89.372694 -264.749026)
		)
		(stroke
			(width 0)
			(type solid)
		)
		(fill yes)
		(layer "In6.Cu")
		(net "M_C_CPU1_SA_DQS_DP<8>")
	)
	(gr_poly
		(pts
			(xy 89.372694 -264.29589) (xy 89.372694 -264.251694) (xy 89.017094 -264.251694) (xy 89.017094 -264.29589)
			(xy 89.064084 -264.44829) (xy 89.325704 -264.44829)
		)
		(stroke
			(width 0)
			(type solid)
		)
		(fill yes)
		(layer "In6.Cu")
		(net "M_C_CPU1_SA_DQ<28>")
	)
	(gr_poly
		(pts
			(xy 89.372694 -262.668258) (xy 89.372694 -262.623808) (xy 89.017094 -262.623808) (xy 89.017094 -262.668258)
			(xy 89.064084 -262.820658) (xy 89.325704 -262.820658)
		)
		(stroke
			(width 0)
			(type solid)
		)
		(fill yes)
		(layer "In6.Cu")
		(net "M_C_CPU1_SA_CB<2>")
	)
	(gr_poly
		(pts
			(xy 89.372694 -259.412486) (xy 89.372694 -259.36829) (xy 89.017094 -259.36829) (xy 89.017094 -259.412486)
			(xy 89.064084 -259.564886) (xy 89.325704 -259.564886)
		)
		(stroke
			(width 0)
			(type solid)
		)
		(fill yes)
		(layer "In6.Cu")
		(net "M_C_CPU1_SA_CB<6>")
	)
	(gr_poly
		(pts
			(xy 89.372694 -258.193286) (xy 89.325704 -258.040886) (xy 89.064084 -258.040886) (xy 89.017094 -258.193286)
			(xy 89.017094 -258.237736) (xy 89.372694 -258.237736)
		)
		(stroke
			(width 0)
			(type solid)
		)
		(fill yes)
		(layer "In6.Cu")
		(net "M_C_CPU1_SA_CB<5>")
	)
	(gr_poly
		(pts
			(xy 89.372694 -256.565654) (xy 89.325704 -256.413254) (xy 89.064084 -256.413254) (xy 89.017094 -256.565654)
			(xy 89.017094 -256.610104) (xy 89.372694 -256.610104)
		)
		(stroke
			(width 0)
			(type solid)
		)
		(fill yes)
		(layer "In6.Cu")
		(net "M_D_CPU1_SB_RSP<0>")
	)
	(gr_poly
		(pts
			(xy 89.372694 -254.529082) (xy 89.372694 -254.484886) (xy 89.017094 -254.484886) (xy 89.017094 -254.529082)
			(xy 89.064084 -254.681482) (xy 89.325704 -254.681482)
		)
		(stroke
			(width 0)
			(type solid)
		)
		(fill yes)
		(layer "In6.Cu")
		(net "M_C_CPU1_SA_RSP<1>")
	)
	(gr_poly
		(pts
			(xy 89.375488 -263.07669) (xy 89.328498 -262.92429) (xy 89.066878 -262.92429) (xy 89.019888 -263.07669)
			(xy 89.019888 -263.12114) (xy 89.375488 -263.12114)
		)
		(stroke
			(width 0)
			(type solid)
		)
		(fill yes)
		(layer "In6.Cu")
		(net "M_C_CPU1_SA_DQ<31>")
	)
	(gr_poly
		(pts
			(xy 89.37879 -272.843498) (xy 89.3318 -272.691098) (xy 89.07018 -272.691098) (xy 89.02319 -272.843498)
			(xy 89.02319 -272.887948) (xy 89.37879 -272.887948)
		)
		(stroke
			(width 0)
			(type solid)
		)
		(fill yes)
		(layer "In6.Cu")
		(net "M_D_CPU1_SA_DQ<7>")
	)
	(gr_poly
		(pts
			(xy 89.447624 -276.16658) (xy 89.339166 -276.04974) (xy 89.300812 -276.027642) (xy 89.123012 -276.33549)
			(xy 89.161366 -276.357588) (xy 89.316814 -276.393148)
		)
		(stroke
			(width 0)
			(type solid)
		)
		(fill yes)
		(layer "In6.Cu")
		(net "M_D_CPU1_SA_DQS_DN<5>")
	)
	(gr_poly
		(pts
			(xy 89.447624 -274.538694) (xy 89.339166 -274.421854) (xy 89.300812 -274.399756) (xy 89.123012 -274.707604)
			(xy 89.161366 -274.729702) (xy 89.316814 -274.765262)
		)
		(stroke
			(width 0)
			(type solid)
		)
		(fill yes)
		(layer "In6.Cu")
		(net "M_D_CPU1_SA_DQ<4>")
	)
	(gr_poly
		(pts
			(xy 89.451942 -277.7871) (xy 89.343484 -277.67026) (xy 89.30513 -277.648162) (xy 89.12733 -277.95601)
			(xy 89.165684 -277.978108) (xy 89.321132 -278.013668)
		)
		(stroke
			(width 0)
			(type solid)
		)
		(fill yes)
		(layer "In6.Cu")
		(net "M_D_CPU1_SA_DQS_DP<0>")
	)
	(gr_poly
		(pts
			(xy 89.58834 -224.85223) (xy 89.626694 -224.830132) (xy 89.448894 -224.522284) (xy 89.41054 -224.544382)
			(xy 89.302082 -224.661222) (xy 89.432892 -224.88779)
		)
		(stroke
			(width 0)
			(type solid)
		)
		(fill yes)
		(layer "In6.Cu")
		(net "M_C_CPU1_SB_DQ<31>")
	)
	(gr_poly
		(pts
			(xy 89.58961 -232.993692) (xy 89.627964 -232.971594) (xy 89.450164 -232.663746) (xy 89.41181 -232.685844)
			(xy 89.303352 -232.802684) (xy 89.434162 -233.029252)
		)
		(stroke
			(width 0)
			(type solid)
		)
		(fill yes)
		(layer "In6.Cu")
		(net "M_D_CPU1_SB_DQS_DP<2>")
	)
	(gr_poly
		(pts
			(xy 89.699338 -224.234502) (xy 89.807796 -224.117662) (xy 89.676986 -223.891094) (xy 89.521538 -223.926654)
			(xy 89.483184 -223.948752) (xy 89.660984 -224.2566)
		)
		(stroke
			(width 0)
			(type solid)
		)
		(fill yes)
		(layer "In6.Cu")
		(net "M_C_CPU1_SB_DQ<29>")
	)
	(gr_poly
		(pts
			(xy 89.703656 -232.380536) (xy 89.812114 -232.263696) (xy 89.681304 -232.037128) (xy 89.525856 -232.072688)
			(xy 89.487502 -232.094786) (xy 89.665302 -232.402634)
		)
		(stroke
			(width 0)
			(type solid)
		)
		(fill yes)
		(layer "In6.Cu")
		(net "M_D_CPU1_SB_DQS_DN<2>")
	)
	(gr_poly
		(pts
			(xy 89.72677 -247.382538) (xy 89.67978 -247.230138) (xy 89.41816 -247.230138) (xy 89.37117 -247.382538)
			(xy 89.37117 -247.426988) (xy 89.72677 -247.426988)
		)
		(stroke
			(width 0)
			(type solid)
		)
		(fill yes)
		(layer "In6.Cu")
		(net "M_A_CPU1_SB_RSP<1>")
	)
	(gr_poly
		(pts
			(xy 89.72931 -243.718334) (xy 89.72931 -243.674138) (xy 89.37371 -243.674138) (xy 89.37371 -243.718334)
			(xy 89.4207 -243.870734) (xy 89.68232 -243.870734)
		)
		(stroke
			(width 0)
			(type solid)
		)
		(fill yes)
		(layer "In6.Cu")
		(net "M_C_CPU1_SB_DQ<1>")
	)
	(gr_poly
		(pts
			(xy 89.732358 -242.499642) (xy 89.685368 -242.347242) (xy 89.423748 -242.347242) (xy 89.376758 -242.499642)
			(xy 89.376758 -242.543838) (xy 89.732358 -242.543838)
		)
		(stroke
			(width 0)
			(type solid)
		)
		(fill yes)
		(layer "In6.Cu")
		(net "M_C_CPU1_SB_DQS_DN<0>")
	)
	(gr_poly
		(pts
			(xy 89.732866 -248.601738) (xy 89.732866 -248.557542) (xy 89.377266 -248.557542) (xy 89.377266 -248.601738)
			(xy 89.424256 -248.754138) (xy 89.685876 -248.754138)
		)
		(stroke
			(width 0)
			(type solid)
		)
		(fill yes)
		(layer "In6.Cu")
		(net "M_A_CPU1_SB_RSP<0>")
	)
	(gr_poly
		(pts
			(xy 89.736676 -276.267926) (xy 89.698322 -276.245828) (xy 89.542874 -276.210268) (xy 89.412064 -276.436836)
			(xy 89.520522 -276.553676) (xy 89.558876 -276.575774)
		)
		(stroke
			(width 0)
			(type solid)
		)
		(fill yes)
		(layer "In6.Cu")
		(net "M_D_CPU1_SA_DQS_DN<0>")
	)
	(gr_poly
		(pts
			(xy 89.736676 -274.64004) (xy 89.698322 -274.617942) (xy 89.542874 -274.582382) (xy 89.412064 -274.80895)
			(xy 89.520522 -274.92579) (xy 89.558876 -274.947888)
		)
		(stroke
			(width 0)
			(type solid)
		)
		(fill yes)
		(layer "In6.Cu")
		(net "M_D_CPU1_SA_DQS_DP<5>")
	)
	(gr_poly
		(pts
			(xy 89.738708 -277.891748) (xy 89.700354 -277.86965) (xy 89.544906 -277.83409) (xy 89.414096 -278.060658)
			(xy 89.522554 -278.177498) (xy 89.560908 -278.199596)
		)
		(stroke
			(width 0)
			(type solid)
		)
		(fill yes)
		(layer "In6.Cu")
		(net "M_D_CPU1_SA_DQ<3>")
	)
	(gr_poly
		(pts
			(xy 89.741248 -245.754906) (xy 89.694258 -245.602506) (xy 89.432638 -245.602506) (xy 89.385648 -245.754906)
			(xy 89.385648 -245.799102) (xy 89.741248 -245.799102)
		)
		(stroke
			(width 0)
			(type solid)
		)
		(fill yes)
		(layer "In6.Cu")
		(net "M_D_CPU1_SB_CS_N<3>")
	)
	(gr_poly
		(pts
			(xy 89.741248 -245.346474) (xy 89.741248 -245.302278) (xy 89.385648 -245.302278) (xy 89.385648 -245.346474)
			(xy 89.432638 -245.498874) (xy 89.694258 -245.498874)
		)
		(stroke
			(width 0)
			(type solid)
		)
		(fill yes)
		(layer "In6.Cu")
		(net "M_D_CPU1_SB_CS_N<0>")
	)
	(gr_poly
		(pts
			(xy 89.741248 -244.126766) (xy 89.694258 -243.974366) (xy 89.432638 -243.974366) (xy 89.385648 -244.126766)
			(xy 89.385648 -244.171216) (xy 89.741248 -244.171216)
		)
		(stroke
			(width 0)
			(type solid)
		)
		(fill yes)
		(layer "In6.Cu")
		(net "M_C_CPU1_SB_DQ<2>")
	)
	(gr_poly
		(pts
			(xy 89.741248 -242.090702) (xy 89.741248 -242.046506) (xy 89.385648 -242.046506) (xy 89.385648 -242.090702)
			(xy 89.432638 -242.243102) (xy 89.694258 -242.243102)
		)
		(stroke
			(width 0)
			(type solid)
		)
		(fill yes)
		(layer "In6.Cu")
		(net "M_C_CPU1_SB_DQS_DN<5>")
	)
	(gr_poly
		(pts
			(xy 89.741248 -240.871502) (xy 89.694258 -240.719102) (xy 89.432638 -240.719102) (xy 89.385648 -240.871502)
			(xy 89.385648 -240.915698) (xy 89.741248 -240.915698)
		)
		(stroke
			(width 0)
			(type solid)
		)
		(fill yes)
		(layer "In6.Cu")
		(net "M_C_CPU1_SB_DQ<6>")
	)
	(gr_poly
		(pts
			(xy 89.741248 -240.46307) (xy 89.741248 -240.418874) (xy 89.385648 -240.418874) (xy 89.385648 -240.46307)
			(xy 89.432638 -240.61547) (xy 89.694258 -240.61547)
		)
		(stroke
			(width 0)
			(type solid)
		)
		(fill yes)
		(layer "In6.Cu")
		(net "M_C_CPU1_SB_DQ<5>")
	)
	(gr_poly
		(pts
			(xy 89.741248 -239.243362) (xy 89.694258 -239.090962) (xy 89.432638 -239.090962) (xy 89.385648 -239.243362)
			(xy 89.385648 -239.287812) (xy 89.741248 -239.287812)
		)
		(stroke
			(width 0)
			(type solid)
		)
		(fill yes)
		(layer "In6.Cu")
		(net "M_C_CPU1_SB_DQ<10>")
	)
	(gr_poly
		(pts
			(xy 89.741248 -238.835438) (xy 89.741248 -238.790988) (xy 89.385648 -238.790988) (xy 89.385648 -238.835438)
			(xy 89.432638 -238.987838) (xy 89.694258 -238.987838)
		)
		(stroke
			(width 0)
			(type solid)
		)
		(fill yes)
		(layer "In6.Cu")
		(net "M_C_CPU1_SB_DQ<9>")
	)
	(gr_poly
		(pts
			(xy 89.741248 -237.61573) (xy 89.694258 -237.46333) (xy 89.432638 -237.46333) (xy 89.385648 -237.61573)
			(xy 89.385648 -237.659926) (xy 89.741248 -237.659926)
		)
		(stroke
			(width 0)
			(type solid)
		)
		(fill yes)
		(layer "In6.Cu")
		(net "M_C_CPU1_SB_DQS_DN<1>")
	)
	(gr_poly
		(pts
			(xy 89.741248 -237.207806) (xy 89.741248 -237.163356) (xy 89.385648 -237.163356) (xy 89.385648 -237.207806)
			(xy 89.432638 -237.360206) (xy 89.694258 -237.360206)
		)
		(stroke
			(width 0)
			(type solid)
		)
		(fill yes)
		(layer "In6.Cu")
		(net "M_C_CPU1_SB_DQS_DN<6>")
	)
	(gr_poly
		(pts
			(xy 89.741248 -235.988098) (xy 89.694258 -235.835698) (xy 89.432638 -235.835698) (xy 89.385648 -235.988098)
			(xy 89.385648 -236.032294) (xy 89.741248 -236.032294)
		)
		(stroke
			(width 0)
			(type solid)
		)
		(fill yes)
		(layer "In6.Cu")
		(net "M_C_CPU1_SB_DQ<14>")
	)
	(gr_poly
		(pts
			(xy 89.741248 -235.579666) (xy 89.741248 -235.53547) (xy 89.385648 -235.53547) (xy 89.385648 -235.579666)
			(xy 89.432638 -235.732066) (xy 89.694258 -235.732066)
		)
		(stroke
			(width 0)
			(type solid)
		)
		(fill yes)
		(layer "In6.Cu")
		(net "M_C_CPU1_SB_DQ<13>")
	)
	(gr_poly
		(pts
			(xy 89.741248 -234.360466) (xy 89.694258 -234.208066) (xy 89.432638 -234.208066) (xy 89.385648 -234.360466)
			(xy 89.385648 -234.404662) (xy 89.741248 -234.404662)
		)
		(stroke
			(width 0)
			(type solid)
		)
		(fill yes)
		(layer "In6.Cu")
		(net "M_D_CPU1_SB_DQ<18>")
	)
	(gr_poly
		(pts
			(xy 89.741248 -233.952034) (xy 89.741248 -233.907838) (xy 89.385648 -233.907838) (xy 89.385648 -233.952034)
			(xy 89.432638 -234.104434) (xy 89.694258 -234.104434)
		)
		(stroke
			(width 0)
			(type solid)
		)
		(fill yes)
		(layer "In6.Cu")
		(net "M_D_CPU1_SB_DQ<17>")
	)
	(gr_poly
		(pts
			(xy 89.741248 -231.104694) (xy 89.694258 -230.952294) (xy 89.432638 -230.952294) (xy 89.385648 -231.104694)
			(xy 89.385648 -231.14889) (xy 89.741248 -231.14889)
		)
		(stroke
			(width 0)
			(type solid)
		)
		(fill yes)
		(layer "In6.Cu")
		(net "M_D_CPU1_SB_DQS_DP<7>")
	)
	(gr_poly
		(pts
			(xy 89.741248 -230.696262) (xy 89.741248 -230.652066) (xy 89.385648 -230.652066) (xy 89.385648 -230.696262)
			(xy 89.432638 -230.848662) (xy 89.694258 -230.848662)
		)
		(stroke
			(width 0)
			(type solid)
		)
		(fill yes)
		(layer "In6.Cu")
		(net "M_D_CPU1_SB_DQ<20>")
	)
	(gr_poly
		(pts
			(xy 89.741248 -229.477062) (xy 89.694258 -229.324662) (xy 89.432638 -229.324662) (xy 89.385648 -229.477062)
			(xy 89.385648 -229.521258) (xy 89.741248 -229.521258)
		)
		(stroke
			(width 0)
			(type solid)
		)
		(fill yes)
		(layer "In6.Cu")
		(net "M_D_CPU1_SB_DQ<23>")
	)
	(gr_poly
		(pts
			(xy 89.741248 -229.06863) (xy 89.741248 -229.024434) (xy 89.385648 -229.024434) (xy 89.385648 -229.06863)
			(xy 89.432638 -229.22103) (xy 89.694258 -229.22103)
		)
		(stroke
			(width 0)
			(type solid)
		)
		(fill yes)
		(layer "In6.Cu")
		(net "M_C_CPU1_SB_DQ<26>")
	)
	(gr_poly
		(pts
			(xy 89.741248 -227.848922) (xy 89.694258 -227.696522) (xy 89.432638 -227.696522) (xy 89.385648 -227.848922)
			(xy 89.385648 -227.893372) (xy 89.741248 -227.893372)
		)
		(stroke
			(width 0)
			(type solid)
		)
		(fill yes)
		(layer "In6.Cu")
		(net "M_C_CPU1_SB_DQ<27>")
	)
	(gr_poly
		(pts
			(xy 89.741248 -227.440998) (xy 89.741248 -227.396548) (xy 89.385648 -227.396548) (xy 89.385648 -227.440998)
			(xy 89.432638 -227.593398) (xy 89.694258 -227.593398)
		)
		(stroke
			(width 0)
			(type solid)
		)
		(fill yes)
		(layer "In6.Cu")
		(net "M_C_CPU1_SB_DQS_DP<3>")
	)
	(gr_poly
		(pts
			(xy 89.741248 -226.22129) (xy 89.694258 -226.06889) (xy 89.432638 -226.06889) (xy 89.385648 -226.22129)
			(xy 89.385648 -226.26574) (xy 89.741248 -226.26574)
		)
		(stroke
			(width 0)
			(type solid)
		)
		(fill yes)
		(layer "In6.Cu")
		(net "M_C_CPU1_SB_DQS_DP<8>")
	)
	(gr_poly
		(pts
			(xy 89.741248 -225.813366) (xy 89.741248 -225.768916) (xy 89.385648 -225.768916) (xy 89.385648 -225.813366)
			(xy 89.432638 -225.965766) (xy 89.694258 -225.965766)
		)
		(stroke
			(width 0)
			(type solid)
		)
		(fill yes)
		(layer "In6.Cu")
		(net "M_C_CPU1_SB_DQ<28>")
	)
	(gr_poly
		(pts
			(xy 89.842594 -273.657314) (xy 89.795604 -273.504914) (xy 89.533984 -273.504914) (xy 89.486994 -273.657314)
			(xy 89.486994 -273.701764) (xy 89.842594 -273.701764)
		)
		(stroke
			(width 0)
			(type solid)
		)
		(fill yes)
		(layer "In6.Cu")
		(net "M_D_CPU1_SA_DQ<6>")
	)
	(gr_poly
		(pts
			(xy 89.842594 -273.248882) (xy 89.842594 -273.204432) (xy 89.486994 -273.204432) (xy 89.486994 -273.248882)
			(xy 89.533984 -273.401282) (xy 89.795604 -273.401282)
		)
		(stroke
			(width 0)
			(type solid)
		)
		(fill yes)
		(layer "In6.Cu")
		(net "M_D_CPU1_SA_DQ<5>")
	)
	(gr_poly
		(pts
			(xy 89.842594 -270.40205) (xy 89.795604 -270.24965) (xy 89.533984 -270.24965) (xy 89.486994 -270.40205)
			(xy 89.486994 -270.446246) (xy 89.842594 -270.446246)
		)
		(stroke
			(width 0)
			(type solid)
		)
		(fill yes)
		(layer "In6.Cu")
		(net "M_C_CPU1_SA_DQS_DN<1>")
	)
	(gr_poly
		(pts
			(xy 89.842594 -269.99311) (xy 89.842594 -269.948914) (xy 89.486994 -269.948914) (xy 89.486994 -269.99311)
			(xy 89.533984 -270.14551) (xy 89.795604 -270.14551)
		)
		(stroke
			(width 0)
			(type solid)
		)
		(fill yes)
		(layer "In6.Cu")
		(net "M_C_CPU1_SA_DQS_DN<6>")
	)
	(gr_poly
		(pts
			(xy 89.842594 -268.77391) (xy 89.795604 -268.62151) (xy 89.533984 -268.62151) (xy 89.486994 -268.77391)
			(xy 89.486994 -268.81836) (xy 89.842594 -268.81836)
		)
		(stroke
			(width 0)
			(type solid)
		)
		(fill yes)
		(layer "In6.Cu")
		(net "M_C_CPU1_SA_DQ<14>")
	)
	(gr_poly
		(pts
			(xy 89.842594 -268.365478) (xy 89.842594 -268.321028) (xy 89.486994 -268.321028) (xy 89.486994 -268.365478)
			(xy 89.533984 -268.517878) (xy 89.795604 -268.517878)
		)
		(stroke
			(width 0)
			(type solid)
		)
		(fill yes)
		(layer "In6.Cu")
		(net "M_C_CPU1_SA_DQ<13>")
	)
	(gr_poly
		(pts
			(xy 89.842594 -266.737846) (xy 89.842594 -266.693396) (xy 89.486994 -266.693396) (xy 89.486994 -266.737846)
			(xy 89.533984 -266.890246) (xy 89.795604 -266.890246)
		)
		(stroke
			(width 0)
			(type solid)
		)
		(fill yes)
		(layer "In6.Cu")
		(net "M_C_CPU1_SA_DQ<25>")
	)
	(gr_poly
		(pts
			(xy 89.842594 -265.518646) (xy 89.795604 -265.366246) (xy 89.533984 -265.366246) (xy 89.486994 -265.518646)
			(xy 89.486994 -265.562842) (xy 89.842594 -265.562842)
		)
		(stroke
			(width 0)
			(type solid)
		)
		(fill yes)
		(layer "In6.Cu")
		(net "M_C_CPU1_SA_DQS_DN<3>")
	)
	(gr_poly
		(pts
			(xy 89.842594 -265.109706) (xy 89.842594 -265.06551) (xy 89.486994 -265.06551) (xy 89.486994 -265.109706)
			(xy 89.533984 -265.262106) (xy 89.795604 -265.262106)
		)
		(stroke
			(width 0)
			(type solid)
		)
		(fill yes)
		(layer "In6.Cu")
		(net "M_C_CPU1_SA_DQS_DN<8>")
	)
	(gr_poly
		(pts
			(xy 89.842594 -263.891014) (xy 89.795604 -263.738614) (xy 89.533984 -263.738614) (xy 89.486994 -263.891014)
			(xy 89.486994 -263.93521) (xy 89.842594 -263.93521)
		)
		(stroke
			(width 0)
			(type solid)
		)
		(fill yes)
		(layer "In6.Cu")
		(net "M_C_CPU1_SA_DQ<30>")
	)
	(gr_poly
		(pts
			(xy 89.842594 -262.262874) (xy 89.795604 -262.110474) (xy 89.533984 -262.110474) (xy 89.486994 -262.262874)
			(xy 89.486994 -262.307324) (xy 89.842594 -262.307324)
		)
		(stroke
			(width 0)
			(type solid)
		)
		(fill yes)
		(layer "In6.Cu")
		(net "M_C_CPU1_SA_CB<0>")
	)
	(gr_poly
		(pts
			(xy 89.842594 -259.00761) (xy 89.795604 -258.85521) (xy 89.533984 -258.85521) (xy 89.486994 -259.00761)
			(xy 89.486994 -259.051806) (xy 89.842594 -259.051806)
		)
		(stroke
			(width 0)
			(type solid)
		)
		(fill yes)
		(layer "In6.Cu")
		(net "M_C_CPU1_SA_CB<4>")
	)
	(gr_poly
		(pts
			(xy 89.842594 -258.59867) (xy 89.842594 -258.554474) (xy 89.486994 -258.554474) (xy 89.486994 -258.59867)
			(xy 89.533984 -258.75107) (xy 89.795604 -258.75107)
		)
		(stroke
			(width 0)
			(type solid)
		)
		(fill yes)
		(layer "In6.Cu")
		(net "M_C_CPU1_SA_CB<7>")
	)
	(gr_poly
		(pts
			(xy 89.842594 -256.971038) (xy 89.842594 -256.926588) (xy 89.486994 -256.926588) (xy 89.486994 -256.971038)
			(xy 89.533984 -257.123438) (xy 89.795604 -257.123438)
		)
		(stroke
			(width 0)
			(type solid)
		)
		(fill yes)
		(layer "In6.Cu")
		(net "M_D_CPU1_SA_RSP<0>")
	)
	(gr_poly
		(pts
			(xy 89.842594 -254.124206) (xy 89.795604 -253.971806) (xy 89.533984 -253.971806) (xy 89.486994 -254.124206)
			(xy 89.486994 -254.168402) (xy 89.842594 -254.168402)
		)
		(stroke
			(width 0)
			(type solid)
		)
		(fill yes)
		(layer "In6.Cu")
		(net "M_C_CPU1_SB_RSP<1>")
	)
	(gr_poly
		(pts
			(xy 89.842848 -263.482074) (xy 89.842848 -263.437624) (xy 89.487248 -263.437624) (xy 89.487248 -263.482074)
			(xy 89.534238 -263.634474) (xy 89.795858 -263.634474)
		)
		(stroke
			(width 0)
			(type solid)
		)
		(fill yes)
		(layer "In6.Cu")
		(net "M_C_CPU1_SA_DQ<29>")
	)
	(gr_poly
		(pts
			(xy 89.84869 -272.029682) (xy 89.8017 -271.877282) (xy 89.54008 -271.877282) (xy 89.49309 -272.029682)
			(xy 89.49309 -272.073878) (xy 89.84869 -272.073878)
		)
		(stroke
			(width 0)
			(type solid)
		)
		(fill yes)
		(layer "In6.Cu")
		(net "M_C_CPU1_SA_DQ<10>")
	)
	(gr_poly
		(pts
			(xy 89.84869 -271.620742) (xy 89.84869 -271.576546) (xy 89.49309 -271.576546) (xy 89.49309 -271.620742)
			(xy 89.54008 -271.773142) (xy 89.8017 -271.773142)
		)
		(stroke
			(width 0)
			(type solid)
		)
		(fill yes)
		(layer "In6.Cu")
		(net "M_C_CPU1_SA_DQ<9>")
	)
	(gr_poly
		(pts
			(xy 89.84869 -267.146278) (xy 89.8017 -266.993878) (xy 89.54008 -266.993878) (xy 89.49309 -267.146278)
			(xy 89.49309 -267.190474) (xy 89.84869 -267.190474)
		)
		(stroke
			(width 0)
			(type solid)
		)
		(fill yes)
		(layer "In6.Cu")
		(net "M_C_CPU1_SA_DQ<26>")
	)
	(gr_poly
		(pts
			(xy 89.84869 -261.854442) (xy 89.84869 -261.809992) (xy 89.49309 -261.809992) (xy 89.49309 -261.854442)
			(xy 89.54008 -262.006842) (xy 89.8017 -262.006842)
		)
		(stroke
			(width 0)
			(type solid)
		)
		(fill yes)
		(layer "In6.Cu")
		(net "M_C_CPU1_SA_CB<3>")
	)
	(gr_poly
		(pts
			(xy 89.84869 -255.751838) (xy 89.8017 -255.599438) (xy 89.54008 -255.599438) (xy 89.49309 -255.751838)
			(xy 89.49309 -255.796288) (xy 89.84869 -255.796288)
		)
		(stroke
			(width 0)
			(type solid)
		)
		(fill yes)
		(layer "In6.Cu")
		(net "M_D_CPU1_SB_RSP<1>")
	)
	(gr_poly
		(pts
			(xy 89.84869 -255.343406) (xy 89.84869 -255.298956) (xy 89.49309 -255.298956) (xy 89.49309 -255.343406)
			(xy 89.54008 -255.495806) (xy 89.8017 -255.495806)
		)
		(stroke
			(width 0)
			(type solid)
		)
		(fill yes)
		(layer "In6.Cu")
		(net "M_C_CPU1_SA_RSP<0>")
	)
	(gr_poly
		(pts
			(xy 89.85123 -260.634734) (xy 89.80424 -260.482334) (xy 89.54262 -260.482334) (xy 89.49563 -260.634734)
			(xy 89.49563 -260.679184) (xy 89.85123 -260.679184)
		)
		(stroke
			(width 0)
			(type solid)
		)
		(fill yes)
		(layer "In6.Cu")
		(net "M_C_CPU1_SA_DQS_DP<9>")
	)
	(gr_poly
		(pts
			(xy 89.85123 -260.22681) (xy 89.85123 -260.18236) (xy 89.49563 -260.18236) (xy 89.49563 -260.22681)
			(xy 89.54262 -260.37921) (xy 89.80424 -260.37921)
		)
		(stroke
			(width 0)
			(type solid)
		)
		(fill yes)
		(layer "In6.Cu")
		(net "M_C_CPU1_SA_DQS_DP<4>")
	)
	(gr_poly
		(pts
			(xy 89.915492 -275.356574) (xy 89.807034 -275.239734) (xy 89.76868 -275.217636) (xy 89.59088 -275.525484)
			(xy 89.629234 -275.547582) (xy 89.784682 -275.583142)
		)
		(stroke
			(width 0)
			(type solid)
		)
		(fill yes)
		(layer "In6.Cu")
		(net "M_D_CPU1_SA_DQS_DN<5>")
	)
	(gr_poly
		(pts
			(xy 89.917524 -278.608282) (xy 89.809066 -278.491442) (xy 89.770712 -278.469344) (xy 89.592912 -278.777192)
			(xy 89.631266 -278.79929) (xy 89.786714 -278.83485)
		)
		(stroke
			(width 0)
			(type solid)
		)
		(fill yes)
		(layer "In6.Cu")
		(net "M_D_CPU1_SA_DQ<1>")
	)
	(gr_poly
		(pts
			(xy 89.917524 -276.980396) (xy 89.809066 -276.863556) (xy 89.770712 -276.841458) (xy 89.592912 -277.149306)
			(xy 89.631266 -277.171404) (xy 89.786714 -277.206964)
		)
		(stroke
			(width 0)
			(type solid)
		)
		(fill yes)
		(layer "In6.Cu")
		(net "M_D_CPU1_SA_DQS_DP<0>")
	)
	(gr_poly
		(pts
			(xy 90.053922 -232.170224) (xy 90.092276 -232.148126) (xy 89.914476 -231.840278) (xy 89.876122 -231.862376)
			(xy 89.767664 -231.979216) (xy 89.898474 -232.205784)
		)
		(stroke
			(width 0)
			(type solid)
		)
		(fill yes)
		(layer "In6.Cu")
		(net "M_D_CPU1_SB_DQS_DN<7>")
	)
	(gr_poly
		(pts
			(xy 90.16619 -231.555544) (xy 90.274648 -231.438704) (xy 90.143838 -231.212136) (xy 89.98839 -231.247696)
			(xy 89.950036 -231.269794) (xy 90.127836 -231.577642)
		)
		(stroke
			(width 0)
			(type solid)
		)
		(fill yes)
		(layer "In6.Cu")
		(net "M_D_CPU1_SB_DQS_DP<7>")
	)
	(gr_poly
		(pts
			(xy 90.19413 -246.16029) (xy 90.19413 -246.116094) (xy 89.83853 -246.116094) (xy 89.83853 -246.16029)
			(xy 89.88552 -246.31269) (xy 90.14714 -246.31269)
		)
		(stroke
			(width 0)
			(type solid)
		)
		(fill yes)
		(layer "In6.Cu")
		(net "M_D_CPU1_SB_CS_N<2>")
	)
	(gr_poly
		(pts
			(xy 90.19413 -242.905026) (xy 90.19413 -242.860576) (xy 89.83853 -242.860576) (xy 89.83853 -242.905026)
			(xy 89.88552 -243.057426) (xy 90.14714 -243.057426)
		)
		(stroke
			(width 0)
			(type solid)
		)
		(fill yes)
		(layer "In6.Cu")
		(net "M_C_CPU1_SB_DQS_DP<0>")
	)
	(gr_poly
		(pts
			(xy 90.19413 -241.685318) (xy 90.14714 -241.532918) (xy 89.88552 -241.532918) (xy 89.83853 -241.685318)
			(xy 89.83853 -241.729514) (xy 90.19413 -241.729514)
		)
		(stroke
			(width 0)
			(type solid)
		)
		(fill yes)
		(layer "In6.Cu")
		(net "M_C_CPU1_SB_DQS_DP<5>")
	)
	(gr_poly
		(pts
			(xy 90.19413 -241.276886) (xy 90.19413 -241.23269) (xy 89.83853 -241.23269) (xy 89.83853 -241.276886)
			(xy 89.88552 -241.429286) (xy 90.14714 -241.429286)
		)
		(stroke
			(width 0)
			(type solid)
		)
		(fill yes)
		(layer "In6.Cu")
		(net "M_C_CPU1_SB_DQ<4>")
	)
	(gr_poly
		(pts
			(xy 90.19413 -238.429546) (xy 90.14714 -238.277146) (xy 89.88552 -238.277146) (xy 89.83853 -238.429546)
			(xy 89.83853 -238.473996) (xy 90.19413 -238.473996)
		)
		(stroke
			(width 0)
			(type solid)
		)
		(fill yes)
		(layer "In6.Cu")
		(net "M_C_CPU1_SB_DQ<11>")
	)
	(gr_poly
		(pts
			(xy 90.19413 -238.021622) (xy 90.19413 -237.977172) (xy 89.83853 -237.977172) (xy 89.83853 -238.021622)
			(xy 89.88552 -238.174022) (xy 90.14714 -238.174022)
		)
		(stroke
			(width 0)
			(type solid)
		)
		(fill yes)
		(layer "In6.Cu")
		(net "M_C_CPU1_SB_DQS_DP<1>")
	)
	(gr_poly
		(pts
			(xy 90.19413 -236.801914) (xy 90.14714 -236.649514) (xy 89.88552 -236.649514) (xy 89.83853 -236.801914)
			(xy 89.83853 -236.84611) (xy 90.19413 -236.84611)
		)
		(stroke
			(width 0)
			(type solid)
		)
		(fill yes)
		(layer "In6.Cu")
		(net "M_C_CPU1_SB_DQS_DP<6>")
	)
	(gr_poly
		(pts
			(xy 90.19413 -236.39399) (xy 90.19413 -236.34954) (xy 89.83853 -236.34954) (xy 89.83853 -236.39399)
			(xy 89.88552 -236.54639) (xy 90.14714 -236.54639)
		)
		(stroke
			(width 0)
			(type solid)
		)
		(fill yes)
		(layer "In6.Cu")
		(net "M_C_CPU1_SB_DQ<12>")
	)
	(gr_poly
		(pts
			(xy 90.19413 -233.546142) (xy 90.14714 -233.393742) (xy 89.88552 -233.393742) (xy 89.83853 -233.546142)
			(xy 89.83853 -233.590592) (xy 90.19413 -233.590592)
		)
		(stroke
			(width 0)
			(type solid)
		)
		(fill yes)
		(layer "In6.Cu")
		(net "M_D_CPU1_SB_DQ<19>")
	)
	(gr_poly
		(pts
			(xy 90.19413 -233.138218) (xy 90.19413 -233.093768) (xy 89.83853 -233.093768) (xy 89.83853 -233.138218)
			(xy 89.88552 -233.290618) (xy 90.14714 -233.290618)
		)
		(stroke
			(width 0)
			(type solid)
		)
		(fill yes)
		(layer "In6.Cu")
		(net "M_D_CPU1_SB_DQS_DP<2>")
	)
	(gr_poly
		(pts
			(xy 90.19413 -228.663246) (xy 90.14714 -228.510846) (xy 89.88552 -228.510846) (xy 89.83853 -228.663246)
			(xy 89.83853 -228.707442) (xy 90.19413 -228.707442)
		)
		(stroke
			(width 0)
			(type solid)
		)
		(fill yes)
		(layer "In6.Cu")
		(net "M_C_CPU1_SB_DQ<24>")
	)
	(gr_poly
		(pts
			(xy 90.19413 -228.254814) (xy 90.19413 -228.210618) (xy 89.83853 -228.210618) (xy 89.83853 -228.254814)
			(xy 89.88552 -228.407214) (xy 90.14714 -228.407214)
		)
		(stroke
			(width 0)
			(type solid)
		)
		(fill yes)
		(layer "In6.Cu")
		(net "M_C_CPU1_SB_DQ<25>")
	)
	(gr_poly
		(pts
			(xy 90.19413 -227.035106) (xy 90.14714 -226.882706) (xy 89.88552 -226.882706) (xy 89.83853 -227.035106)
			(xy 89.83853 -227.079556) (xy 90.19413 -227.079556)
		)
		(stroke
			(width 0)
			(type solid)
		)
		(fill yes)
		(layer "In6.Cu")
		(net "M_C_CPU1_SB_DQS_DN<3>")
	)
	(gr_poly
		(pts
			(xy 90.19413 -226.627182) (xy 90.19413 -226.582732) (xy 89.83853 -226.582732) (xy 89.83853 -226.627182)
			(xy 89.88552 -226.779582) (xy 90.14714 -226.779582)
		)
		(stroke
			(width 0)
			(type solid)
		)
		(fill yes)
		(layer "In6.Cu")
		(net "M_C_CPU1_SB_DQS_DN<8>")
	)
	(gr_poly
		(pts
			(xy 90.19413 -225.407474) (xy 90.14714 -225.255074) (xy 89.88552 -225.255074) (xy 89.83853 -225.407474)
			(xy 89.83853 -225.45167) (xy 90.19413 -225.45167)
		)
		(stroke
			(width 0)
			(type solid)
		)
		(fill yes)
		(layer "In6.Cu")
		(net "M_C_CPU1_SB_DQ<30>")
	)
	(gr_poly
		(pts
			(xy 90.19667 -248.196354) (xy 90.14968 -248.043954) (xy 89.88806 -248.043954) (xy 89.84107 -248.196354)
			(xy 89.84107 -248.240804) (xy 90.19667 -248.240804)
		)
		(stroke
			(width 0)
			(type solid)
		)
		(fill yes)
		(layer "In6.Cu")
		(net "M_A_CPU1_SA_RSP<0>")
	)
	(gr_poly
		(pts
			(xy 90.19667 -244.940582) (xy 90.14968 -244.788182) (xy 89.88806 -244.788182) (xy 89.84107 -244.940582)
			(xy 89.84107 -244.985032) (xy 90.19667 -244.985032)
		)
		(stroke
			(width 0)
			(type solid)
		)
		(fill yes)
		(layer "In6.Cu")
		(net "M_D_CPU1_SB_CS_N<1>")
	)
	(gr_poly
		(pts
			(xy 90.19667 -244.532658) (xy 90.19667 -244.488208) (xy 89.84107 -244.488208) (xy 89.84107 -244.532658)
			(xy 89.88806 -244.685058) (xy 90.14968 -244.685058)
		)
		(stroke
			(width 0)
			(type solid)
		)
		(fill yes)
		(layer "In6.Cu")
		(net "M_C_CPU1_SB_DQ<0>")
	)
	(gr_poly
		(pts
			(xy 90.19667 -240.057178) (xy 90.14968 -239.904778) (xy 89.88806 -239.904778) (xy 89.84107 -240.057178)
			(xy 89.84107 -240.101628) (xy 90.19667 -240.101628)
		)
		(stroke
			(width 0)
			(type solid)
		)
		(fill yes)
		(layer "In6.Cu")
		(net "M_C_CPU1_SB_DQ<7>")
	)
	(gr_poly
		(pts
			(xy 90.19667 -239.649254) (xy 90.19667 -239.604804) (xy 89.84107 -239.604804) (xy 89.84107 -239.649254)
			(xy 89.88806 -239.801654) (xy 90.14968 -239.801654)
		)
		(stroke
			(width 0)
			(type solid)
		)
		(fill yes)
		(layer "In6.Cu")
		(net "M_C_CPU1_SB_DQ<8>")
	)
	(gr_poly
		(pts
			(xy 90.19667 -235.174282) (xy 90.14968 -235.021882) (xy 89.88806 -235.021882) (xy 89.84107 -235.174282)
			(xy 89.84107 -235.218478) (xy 90.19667 -235.218478)
		)
		(stroke
			(width 0)
			(type solid)
		)
		(fill yes)
		(layer "In6.Cu")
		(net "M_C_CPU1_SB_DQ<15>")
	)
	(gr_poly
		(pts
			(xy 90.19667 -234.76585) (xy 90.19667 -234.721654) (xy 89.84107 -234.721654) (xy 89.84107 -234.76585)
			(xy 89.88806 -234.91825) (xy 90.14968 -234.91825)
		)
		(stroke
			(width 0)
			(type solid)
		)
		(fill yes)
		(layer "In6.Cu")
		(net "M_D_CPU1_SB_DQ<16>")
	)
	(gr_poly
		(pts
			(xy 90.19667 -230.290878) (xy 90.14968 -230.138478) (xy 89.88806 -230.138478) (xy 89.84107 -230.290878)
			(xy 89.84107 -230.335074) (xy 90.19667 -230.335074)
		)
		(stroke
			(width 0)
			(type solid)
		)
		(fill yes)
		(layer "In6.Cu")
		(net "M_D_CPU1_SB_DQ<22>")
	)
	(gr_poly
		(pts
			(xy 90.19667 -229.882446) (xy 90.19667 -229.83825) (xy 89.84107 -229.83825) (xy 89.84107 -229.882446)
			(xy 89.88806 -230.034846) (xy 90.14968 -230.034846)
		)
		(stroke
			(width 0)
			(type solid)
		)
		(fill yes)
		(layer "In6.Cu")
		(net "M_D_CPU1_SB_DQ<21>")
	)
	(gr_poly
		(pts
			(xy 90.202258 -277.089108) (xy 90.163904 -277.06701) (xy 90.008456 -277.03145) (xy 89.877646 -277.258018)
			(xy 89.986104 -277.374858) (xy 90.024458 -277.396956)
		)
		(stroke
			(width 0)
			(type solid)
		)
		(fill yes)
		(layer "In6.Cu")
		(net "M_D_CPU1_SA_DQ<3>")
	)
	(gr_poly
		(pts
			(xy 90.206068 -243.313458) (xy 90.159078 -243.161058) (xy 89.897458 -243.161058) (xy 89.850468 -243.313458)
			(xy 89.850468 -243.357654) (xy 90.206068 -243.357654)
		)
		(stroke
			(width 0)
			(type solid)
		)
		(fill yes)
		(layer "In6.Cu")
		(net "M_C_CPU1_SB_DQ<3>")
	)
	(gr_poly
		(pts
			(xy 90.206576 -278.709628) (xy 90.168222 -278.68753) (xy 90.012774 -278.65197) (xy 89.881964 -278.878538)
			(xy 89.990422 -278.995378) (xy 90.028776 -279.017476)
		)
		(stroke
			(width 0)
			(type solid)
		)
		(fill yes)
		(layer "In6.Cu")
		(net "M_D_CPU1_SA_DQ<2>")
	)
	(gr_poly
		(pts
			(xy 90.208608 -275.450046) (xy 90.170254 -275.427948) (xy 90.014806 -275.392388) (xy 89.883996 -275.618956)
			(xy 89.992454 -275.735796) (xy 90.030808 -275.757894)
		)
		(stroke
			(width 0)
			(type solid)
		)
		(fill yes)
		(layer "In6.Cu")
		(net "M_D_CPU1_SA_DQS_DN<0>")
	)
	(gr_poly
		(pts
			(xy 90.208608 -247.787922) (xy 90.208608 -247.743472) (xy 89.853008 -247.743472) (xy 89.853008 -247.787922)
			(xy 89.899998 -247.940322) (xy 90.161618 -247.940322)
		)
		(stroke
			(width 0)
			(type solid)
		)
		(fill yes)
		(layer "In6.Cu")
		(net "M_A_CPU1_SA_RSP<1>")
	)
	(gr_poly
		(pts
			(xy 90.304112 -261.040626) (xy 90.304112 -260.99643) (xy 89.948512 -260.99643) (xy 89.948512 -261.040626)
			(xy 89.995502 -261.193026) (xy 90.257122 -261.193026)
		)
		(stroke
			(width 0)
			(type solid)
		)
		(fill yes)
		(layer "In6.Cu")
		(net "M_C_CPU1_SA_DQS_DN<9>")
	)
	(gr_poly
		(pts
			(xy 90.304112 -259.820918) (xy 90.257122 -259.668518) (xy 89.995502 -259.668518) (xy 89.948512 -259.820918)
			(xy 89.948512 -259.865368) (xy 90.304112 -259.865368)
		)
		(stroke
			(width 0)
			(type solid)
		)
		(fill yes)
		(layer "In6.Cu")
		(net "M_C_CPU1_SA_DQS_DN<4>")
	)
	(gr_poly
		(pts
			(xy 90.312494 -274.47113) (xy 90.265504 -274.31873) (xy 90.003884 -274.31873) (xy 89.956894 -274.47113)
			(xy 89.956894 -274.51558) (xy 90.312494 -274.51558)
		)
		(stroke
			(width 0)
			(type solid)
		)
		(fill yes)
		(layer "In6.Cu")
		(net "M_D_CPU1_SA_DQS_DP<5>")
	)
	(gr_poly
		(pts
			(xy 90.312494 -274.062698) (xy 90.312494 -274.018248) (xy 89.956894 -274.018248) (xy 89.956894 -274.062698)
			(xy 90.003884 -274.215098) (xy 90.265504 -274.215098)
		)
		(stroke
			(width 0)
			(type solid)
		)
		(fill yes)
		(layer "In6.Cu")
		(net "M_D_CPU1_SA_DQ<4>")
	)
	(gr_poly
		(pts
			(xy 90.312494 -271.215866) (xy 90.265504 -271.063466) (xy 90.003884 -271.063466) (xy 89.956894 -271.215866)
			(xy 89.956894 -271.260062) (xy 90.312494 -271.260062)
		)
		(stroke
			(width 0)
			(type solid)
		)
		(fill yes)
		(layer "In6.Cu")
		(net "M_C_CPU1_SA_DQ<11>")
	)
	(gr_poly
		(pts
			(xy 90.312494 -270.806926) (xy 90.312494 -270.76273) (xy 89.956894 -270.76273) (xy 89.956894 -270.806926)
			(xy 90.003884 -270.959326) (xy 90.265504 -270.959326)
		)
		(stroke
			(width 0)
			(type solid)
		)
		(fill yes)
		(layer "In6.Cu")
		(net "M_C_CPU1_SA_DQS_DP<1>")
	)
	(gr_poly
		(pts
			(xy 90.312494 -269.587726) (xy 90.265504 -269.435326) (xy 90.003884 -269.435326) (xy 89.956894 -269.587726)
			(xy 89.956894 -269.632176) (xy 90.312494 -269.632176)
		)
		(stroke
			(width 0)
			(type solid)
		)
		(fill yes)
		(layer "In6.Cu")
		(net "M_C_CPU1_SA_DQS_DP<6>")
	)
	(gr_poly
		(pts
			(xy 90.312494 -269.179294) (xy 90.312494 -269.134844) (xy 89.956894 -269.134844) (xy 89.956894 -269.179294)
			(xy 90.003884 -269.331694) (xy 90.265504 -269.331694)
		)
		(stroke
			(width 0)
			(type solid)
		)
		(fill yes)
		(layer "In6.Cu")
		(net "M_C_CPU1_SA_DQ<12>")
	)
	(gr_poly
		(pts
			(xy 90.312494 -266.332462) (xy 90.265504 -266.180062) (xy 90.003884 -266.180062) (xy 89.956894 -266.332462)
			(xy 89.956894 -266.376658) (xy 90.312494 -266.376658)
		)
		(stroke
			(width 0)
			(type solid)
		)
		(fill yes)
		(layer "In6.Cu")
		(net "M_C_CPU1_SA_DQ<27>")
	)
	(gr_poly
		(pts
			(xy 90.312494 -265.923522) (xy 90.312494 -265.879326) (xy 89.956894 -265.879326) (xy 89.956894 -265.923522)
			(xy 90.003884 -266.075922) (xy 90.265504 -266.075922)
		)
		(stroke
			(width 0)
			(type solid)
		)
		(fill yes)
		(layer "In6.Cu")
		(net "M_C_CPU1_SA_DQS_DP<3>")
	)
	(gr_poly
		(pts
			(xy 90.312494 -264.70483) (xy 90.265504 -264.55243) (xy 90.003884 -264.55243) (xy 89.956894 -264.70483)
			(xy 89.956894 -264.749026) (xy 90.312494 -264.749026)
		)
		(stroke
			(width 0)
			(type solid)
		)
		(fill yes)
		(layer "In6.Cu")
		(net "M_C_CPU1_SA_DQS_DP<8>")
	)
	(gr_poly
		(pts
			(xy 90.312494 -264.29589) (xy 90.312494 -264.251694) (xy 89.956894 -264.251694) (xy 89.956894 -264.29589)
			(xy 90.003884 -264.44829) (xy 90.265504 -264.44829)
		)
		(stroke
			(width 0)
			(type solid)
		)
		(fill yes)
		(layer "In6.Cu")
		(net "M_C_CPU1_SA_DQ<28>")
	)
	(gr_poly
		(pts
			(xy 90.312494 -261.449058) (xy 90.265504 -261.296658) (xy 90.003884 -261.296658) (xy 89.956894 -261.449058)
			(xy 89.956894 -261.493508) (xy 90.312494 -261.493508)
		)
		(stroke
			(width 0)
			(type solid)
		)
		(fill yes)
		(layer "In6.Cu")
		(net "M_C_CPU1_SA_CB<1>")
	)
	(gr_poly
		(pts
			(xy 90.312494 -259.412486) (xy 90.312494 -259.36829) (xy 89.956894 -259.36829) (xy 89.956894 -259.412486)
			(xy 90.003884 -259.564886) (xy 90.265504 -259.564886)
		)
		(stroke
			(width 0)
			(type solid)
		)
		(fill yes)
		(layer "In6.Cu")
		(net "M_C_CPU1_SA_CB<6>")
	)
	(gr_poly
		(pts
			(xy 90.312494 -256.565654) (xy 90.265504 -256.413254) (xy 90.003884 -256.413254) (xy 89.956894 -256.565654)
			(xy 89.956894 -256.610104) (xy 90.312494 -256.610104)
		)
		(stroke
			(width 0)
			(type solid)
		)
		(fill yes)
		(layer "In6.Cu")
		(net "M_D_CPU1_SB_RSP<0>")
	)
	(gr_poly
		(pts
			(xy 90.312494 -256.157222) (xy 90.312494 -256.112772) (xy 89.956894 -256.112772) (xy 89.956894 -256.157222)
			(xy 90.003884 -256.309622) (xy 90.265504 -256.309622)
		)
		(stroke
			(width 0)
			(type solid)
		)
		(fill yes)
		(layer "In6.Cu")
		(net "M_D_CPU1_SA_RSP<1>")
	)
	(gr_poly
		(pts
			(xy 90.312494 -254.938022) (xy 90.265504 -254.785622) (xy 90.003884 -254.785622) (xy 89.956894 -254.938022)
			(xy 89.956894 -254.982218) (xy 90.312494 -254.982218)
		)
		(stroke
			(width 0)
			(type solid)
		)
		(fill yes)
		(layer "In6.Cu")
		(net "M_C_CPU1_SB_RSP<0>")
	)
	(gr_poly
		(pts
			(xy 90.312494 -254.529082) (xy 90.312494 -254.484886) (xy 89.956894 -254.484886) (xy 89.956894 -254.529082)
			(xy 90.003884 -254.681482) (xy 90.265504 -254.681482)
		)
		(stroke
			(width 0)
			(type solid)
		)
		(fill yes)
		(layer "In6.Cu")
		(net "M_C_CPU1_SA_RSP<1>")
	)
	(gr_poly
		(pts
			(xy 90.31478 -263.07669) (xy 90.26779 -262.92429) (xy 90.00617 -262.92429) (xy 89.95918 -263.07669)
			(xy 89.95918 -263.12114) (xy 90.31478 -263.12114)
		)
		(stroke
			(width 0)
			(type solid)
		)
		(fill yes)
		(layer "In6.Cu")
		(net "M_C_CPU1_SA_DQ<31>")
	)
	(gr_poly
		(pts
			(xy 90.31859 -272.843498) (xy 90.2716 -272.691098) (xy 90.00998 -272.691098) (xy 89.96299 -272.843498)
			(xy 89.96299 -272.887694) (xy 90.31859 -272.887694)
		)
		(stroke
			(width 0)
			(type solid)
		)
		(fill yes)
		(layer "In6.Cu")
		(net "M_D_CPU1_SA_DQ<7>")
	)
	(gr_poly
		(pts
			(xy 90.31859 -272.435066) (xy 90.31859 -272.39087) (xy 89.96299 -272.39087) (xy 89.96299 -272.435066)
			(xy 90.00998 -272.587466) (xy 90.2716 -272.587466)
		)
		(stroke
			(width 0)
			(type solid)
		)
		(fill yes)
		(layer "In6.Cu")
		(net "M_C_CPU1_SA_DQ<8>")
	)
	(gr_poly
		(pts
			(xy 90.31859 -267.960094) (xy 90.2716 -267.807694) (xy 90.00998 -267.807694) (xy 89.96299 -267.960094)
			(xy 89.96299 -268.00429) (xy 90.31859 -268.00429)
		)
		(stroke
			(width 0)
			(type solid)
		)
		(fill yes)
		(layer "In6.Cu")
		(net "M_C_CPU1_SA_DQ<15>")
	)
	(gr_poly
		(pts
			(xy 90.31859 -267.551662) (xy 90.31859 -267.507466) (xy 89.96299 -267.507466) (xy 89.96299 -267.551662)
			(xy 90.00998 -267.704062) (xy 90.2716 -267.704062)
		)
		(stroke
			(width 0)
			(type solid)
		)
		(fill yes)
		(layer "In6.Cu")
		(net "M_C_CPU1_SA_DQ<24>")
	)
	(gr_poly
		(pts
			(xy 90.31859 -262.668258) (xy 90.31859 -262.624062) (xy 89.96299 -262.624062) (xy 89.96299 -262.668258)
			(xy 90.00998 -262.820658) (xy 90.2716 -262.820658)
		)
		(stroke
			(width 0)
			(type solid)
		)
		(fill yes)
		(layer "In6.Cu")
		(net "M_C_CPU1_SA_CB<2>")
	)
	(gr_poly
		(pts
			(xy 90.31859 -258.193286) (xy 90.2716 -258.040886) (xy 90.00998 -258.040886) (xy 89.96299 -258.193286)
			(xy 89.96299 -258.237482) (xy 90.31859 -258.237482)
		)
		(stroke
			(width 0)
			(type solid)
		)
		(fill yes)
		(layer "In6.Cu")
		(net "M_C_CPU1_SA_CB<5>")
	)
	(gr_poly
		(pts
			(xy 90.387424 -279.422098) (xy 90.278966 -279.305258) (xy 90.240612 -279.28316) (xy 90.062812 -279.591008)
			(xy 90.101166 -279.613106) (xy 90.256614 -279.648666)
		)
		(stroke
			(width 0)
			(type solid)
		)
		(fill yes)
		(layer "In6.Cu")
		(net "M_D_CPU1_SA_DQ<0>")
	)
	(gr_poly
		(pts
			(xy 90.387424 -276.16658) (xy 90.278966 -276.04974) (xy 90.240612 -276.027642) (xy 90.062812 -276.33549)
			(xy 90.101166 -276.357588) (xy 90.256614 -276.393148)
		)
		(stroke
			(width 0)
			(type solid)
		)
		(fill yes)
		(layer "In6.Cu")
		(net "M_D_CPU1_SA_DQS_DP<0>")
	)
	(gr_poly
		(pts
			(xy 90.388186 -277.79345) (xy 90.279728 -277.67661) (xy 90.241374 -277.654512) (xy 90.063574 -277.96236)
			(xy 90.101928 -277.984458) (xy 90.257376 -278.020018)
		)
		(stroke
			(width 0)
			(type solid)
		)
		(fill yes)
		(layer "In6.Cu")
		(net "M_D_CPU1_SA_DQ<1>")
	)
	(gr_poly
		(pts
			(xy 90.530172 -231.36733) (xy 90.568526 -231.345232) (xy 90.390726 -231.037384) (xy 90.352372 -231.059482)
			(xy 90.243914 -231.176322) (xy 90.374724 -231.40289)
		)
		(stroke
			(width 0)
			(type solid)
		)
		(fill yes)
		(layer "In6.Cu")
		(net "M_D_CPU1_SB_DQ<20>")
	)
	(gr_poly
		(pts
			(xy 90.566494 -223.948752) (xy 90.52814 -223.926654) (xy 90.372692 -223.891094) (xy 90.241882 -224.117662)
			(xy 90.35034 -224.234502) (xy 90.388694 -224.2566)
		)
		(stroke
			(width 0)
			(type solid)
		)
		(fill yes)
		(layer "In6.Cu")
		(net "M_C_CPU1_SB_DQ<29>")
	)
	(gr_poly
		(pts
			(xy 90.639138 -230.745538) (xy 90.747596 -230.628698) (xy 90.616786 -230.40213) (xy 90.461338 -230.43769)
			(xy 90.422984 -230.459788) (xy 90.600784 -230.767636)
		)
		(stroke
			(width 0)
			(type solid)
		)
		(fill yes)
		(layer "In6.Cu")
		(net "M_D_CPU1_SB_DQ<22>")
	)
	(gr_poly
		(pts
			(xy 90.66657 -245.346474) (xy 90.66657 -245.302024) (xy 90.31097 -245.302024) (xy 90.31097 -245.346474)
			(xy 90.35796 -245.498874) (xy 90.61958 -245.498874)
		)
		(stroke
			(width 0)
			(type solid)
		)
		(fill yes)
		(layer "In6.Cu")
		(net "M_D_CPU1_SB_CS_N<0>")
	)
	(gr_poly
		(pts
			(xy 90.66657 -240.46307) (xy 90.66657 -240.41862) (xy 90.31097 -240.41862) (xy 90.31097 -240.46307)
			(xy 90.35796 -240.61547) (xy 90.61958 -240.61547)
		)
		(stroke
			(width 0)
			(type solid)
		)
		(fill yes)
		(layer "In6.Cu")
		(net "M_C_CPU1_SB_DQ<5>")
	)
	(gr_poly
		(pts
			(xy 90.66657 -235.579666) (xy 90.66657 -235.535216) (xy 90.31097 -235.535216) (xy 90.31097 -235.579666)
			(xy 90.35796 -235.732066) (xy 90.61958 -235.732066)
		)
		(stroke
			(width 0)
			(type solid)
		)
		(fill yes)
		(layer "In6.Cu")
		(net "M_C_CPU1_SB_DQ<13>")
	)
	(gr_poly
		(pts
			(xy 90.66911 -243.718334) (xy 90.66911 -243.674138) (xy 90.31351 -243.674138) (xy 90.31351 -243.718334)
			(xy 90.3605 -243.870734) (xy 90.62212 -243.870734)
		)
		(stroke
			(width 0)
			(type solid)
		)
		(fill yes)
		(layer "In6.Cu")
		(net "M_C_CPU1_SB_DQ<1>")
	)
	(gr_poly
		(pts
			(xy 90.671904 -242.499642) (xy 90.624914 -242.347242) (xy 90.363294 -242.347242) (xy 90.316304 -242.499642)
			(xy 90.316304 -242.543838) (xy 90.671904 -242.543838)
		)
		(stroke
			(width 0)
			(type solid)
		)
		(fill yes)
		(layer "In6.Cu")
		(net "M_C_CPU1_SB_DQS_DN<0>")
	)
	(gr_poly
		(pts
			(xy 90.672666 -244.127274) (xy 90.625676 -243.974874) (xy 90.364056 -243.974874) (xy 90.317066 -244.127274)
			(xy 90.317066 -244.17147) (xy 90.672666 -244.17147)
		)
		(stroke
			(width 0)
			(type solid)
		)
		(fill yes)
		(layer "In6.Cu")
		(net "M_C_CPU1_SB_DQ<2>")
	)
	(gr_poly
		(pts
			(xy 90.672666 -239.24387) (xy 90.625676 -239.09147) (xy 90.364056 -239.09147) (xy 90.317066 -239.24387)
			(xy 90.317066 -239.288066) (xy 90.672666 -239.288066)
		)
		(stroke
			(width 0)
			(type solid)
		)
		(fill yes)
		(layer "In6.Cu")
		(net "M_C_CPU1_SB_DQ<10>")
	)
	(gr_poly
		(pts
			(xy 90.672666 -234.360466) (xy 90.625676 -234.208066) (xy 90.364056 -234.208066) (xy 90.317066 -234.360466)
			(xy 90.317066 -234.404916) (xy 90.672666 -234.404916)
		)
		(stroke
			(width 0)
			(type solid)
		)
		(fill yes)
		(layer "In6.Cu")
		(net "M_D_CPU1_SB_DQ<18>")
	)
	(gr_poly
		(pts
			(xy 90.672666 -229.477062) (xy 90.625676 -229.324662) (xy 90.364056 -229.324662) (xy 90.317066 -229.477062)
			(xy 90.317066 -229.521512) (xy 90.672666 -229.521512)
		)
		(stroke
			(width 0)
			(type solid)
		)
		(fill yes)
		(layer "In6.Cu")
		(net "M_D_CPU1_SB_DQ<23>")
	)
	(gr_poly
		(pts
			(xy 90.676476 -276.267926) (xy 90.638122 -276.245828) (xy 90.482674 -276.210268) (xy 90.351864 -276.436836)
			(xy 90.460322 -276.553676) (xy 90.498676 -276.575774)
		)
		(stroke
			(width 0)
			(type solid)
		)
		(fill yes)
		(layer "In6.Cu")
		(net "M_D_CPU1_SA_DQ<3>")
	)
	(gr_poly
		(pts
			(xy 90.677492 -277.89378) (xy 90.639138 -277.871682) (xy 90.48369 -277.836122) (xy 90.35288 -278.06269)
			(xy 90.461338 -278.17953) (xy 90.499692 -278.201628)
		)
		(stroke
			(width 0)
			(type solid)
		)
		(fill yes)
		(layer "In6.Cu")
		(net "M_D_CPU1_SA_DQ<2>")
	)
	(gr_poly
		(pts
			(xy 90.678508 -247.382538) (xy 90.631518 -247.230138) (xy 90.369898 -247.230138) (xy 90.322908 -247.382538)
			(xy 90.322908 -247.426734) (xy 90.678508 -247.426734)
		)
		(stroke
			(width 0)
			(type solid)
		)
		(fill yes)
		(layer "In6.Cu")
		(net "M_A_CPU1_SB_RSP<1>")
	)
	(gr_poly
		(pts
			(xy 90.678508 -245.754906) (xy 90.631518 -245.602506) (xy 90.369898 -245.602506) (xy 90.322908 -245.754906)
			(xy 90.322908 -245.799356) (xy 90.678508 -245.799356)
		)
		(stroke
			(width 0)
			(type solid)
		)
		(fill yes)
		(layer "In6.Cu")
		(net "M_D_CPU1_SB_CS_N<3>")
	)
	(gr_poly
		(pts
			(xy 90.678508 -240.871502) (xy 90.631518 -240.719102) (xy 90.369898 -240.719102) (xy 90.322908 -240.871502)
			(xy 90.322908 -240.915952) (xy 90.678508 -240.915952)
		)
		(stroke
			(width 0)
			(type solid)
		)
		(fill yes)
		(layer "In6.Cu")
		(net "M_C_CPU1_SB_DQ<6>")
	)
	(gr_poly
		(pts
			(xy 90.678508 -235.988098) (xy 90.631518 -235.835698) (xy 90.369898 -235.835698) (xy 90.322908 -235.988098)
			(xy 90.322908 -236.032548) (xy 90.678508 -236.032548)
		)
		(stroke
			(width 0)
			(type solid)
		)
		(fill yes)
		(layer "In6.Cu")
		(net "M_C_CPU1_SB_DQ<14>")
	)
	(gr_poly
		(pts
			(xy 90.678508 -226.221798) (xy 90.631518 -226.069398) (xy 90.369898 -226.069398) (xy 90.322908 -226.221798)
			(xy 90.322908 -226.265994) (xy 90.678508 -226.265994)
		)
		(stroke
			(width 0)
			(type solid)
		)
		(fill yes)
		(layer "In6.Cu")
		(net "M_C_CPU1_SB_DQS_DP<8>")
	)
	(gr_poly
		(pts
			(xy 90.678508 -225.812858) (xy 90.678508 -225.768662) (xy 90.322908 -225.768662) (xy 90.322908 -225.812858)
			(xy 90.369898 -225.965258) (xy 90.631518 -225.965258)
		)
		(stroke
			(width 0)
			(type solid)
		)
		(fill yes)
		(layer "In6.Cu")
		(net "M_C_CPU1_SB_DQ<28>")
	)
	(gr_poly
		(pts
			(xy 90.681048 -248.602246) (xy 90.681048 -248.557796) (xy 90.325448 -248.557796) (xy 90.325448 -248.602246)
			(xy 90.372438 -248.754646) (xy 90.634058 -248.754646)
		)
		(stroke
			(width 0)
			(type solid)
		)
		(fill yes)
		(layer "In6.Cu")
		(net "M_A_CPU1_SB_RSP<0>")
	)
	(gr_poly
		(pts
			(xy 90.681048 -242.090702) (xy 90.681048 -242.046506) (xy 90.325448 -242.046506) (xy 90.325448 -242.090702)
			(xy 90.372438 -242.243102) (xy 90.634058 -242.243102)
		)
		(stroke
			(width 0)
			(type solid)
		)
		(fill yes)
		(layer "In6.Cu")
		(net "M_C_CPU1_SB_DQS_DN<5>")
	)
	(gr_poly
		(pts
			(xy 90.681048 -238.835438) (xy 90.681048 -238.790988) (xy 90.325448 -238.790988) (xy 90.325448 -238.835438)
			(xy 90.372438 -238.987838) (xy 90.634058 -238.987838)
		)
		(stroke
			(width 0)
			(type solid)
		)
		(fill yes)
		(layer "In6.Cu")
		(net "M_C_CPU1_SB_DQ<9>")
	)
	(gr_poly
		(pts
			(xy 90.681048 -237.61573) (xy 90.634058 -237.46333) (xy 90.372438 -237.46333) (xy 90.325448 -237.61573)
			(xy 90.325448 -237.66018) (xy 90.681048 -237.66018)
		)
		(stroke
			(width 0)
			(type solid)
		)
		(fill yes)
		(layer "In6.Cu")
		(net "M_C_CPU1_SB_DQS_DN<1>")
	)
	(gr_poly
		(pts
			(xy 90.681048 -237.207806) (xy 90.681048 -237.163356) (xy 90.325448 -237.163356) (xy 90.325448 -237.207806)
			(xy 90.372438 -237.360206) (xy 90.634058 -237.360206)
		)
		(stroke
			(width 0)
			(type solid)
		)
		(fill yes)
		(layer "In6.Cu")
		(net "M_C_CPU1_SB_DQS_DN<6>")
	)
	(gr_poly
		(pts
			(xy 90.681048 -233.952034) (xy 90.681048 -233.907838) (xy 90.325448 -233.907838) (xy 90.325448 -233.952034)
			(xy 90.372438 -234.104434) (xy 90.634058 -234.104434)
		)
		(stroke
			(width 0)
			(type solid)
		)
		(fill yes)
		(layer "In6.Cu")
		(net "M_D_CPU1_SB_DQ<17>")
	)
	(gr_poly
		(pts
			(xy 90.681048 -232.732326) (xy 90.634058 -232.579926) (xy 90.372438 -232.579926) (xy 90.325448 -232.732326)
			(xy 90.325448 -232.776776) (xy 90.681048 -232.776776)
		)
		(stroke
			(width 0)
			(type solid)
		)
		(fill yes)
		(layer "In6.Cu")
		(net "M_D_CPU1_SB_DQS_DN<2>")
	)
	(gr_poly
		(pts
			(xy 90.681048 -232.324402) (xy 90.681048 -232.279952) (xy 90.325448 -232.279952) (xy 90.325448 -232.324402)
			(xy 90.372438 -232.476802) (xy 90.634058 -232.476802)
		)
		(stroke
			(width 0)
			(type solid)
		)
		(fill yes)
		(layer "In6.Cu")
		(net "M_D_CPU1_SB_DQS_DN<7>")
	)
	(gr_poly
		(pts
			(xy 90.681048 -229.06863) (xy 90.681048 -229.024434) (xy 90.325448 -229.024434) (xy 90.325448 -229.06863)
			(xy 90.372438 -229.22103) (xy 90.634058 -229.22103)
		)
		(stroke
			(width 0)
			(type solid)
		)
		(fill yes)
		(layer "In6.Cu")
		(net "M_C_CPU1_SB_DQ<26>")
	)
	(gr_poly
		(pts
			(xy 90.681048 -227.848922) (xy 90.634058 -227.696522) (xy 90.372438 -227.696522) (xy 90.325448 -227.848922)
			(xy 90.325448 -227.893372) (xy 90.681048 -227.893372)
		)
		(stroke
			(width 0)
			(type solid)
		)
		(fill yes)
		(layer "In6.Cu")
		(net "M_C_CPU1_SB_DQ<27>")
	)
	(gr_poly
		(pts
			(xy 90.681048 -227.440998) (xy 90.681048 -227.396548) (xy 90.325448 -227.396548) (xy 90.325448 -227.440998)
			(xy 90.372438 -227.593398) (xy 90.634058 -227.593398)
		)
		(stroke
			(width 0)
			(type solid)
		)
		(fill yes)
		(layer "In6.Cu")
		(net "M_C_CPU1_SB_DQS_DP<3>")
	)
	(gr_poly
		(pts
			(xy 90.751914 -224.65411) (xy 90.643456 -224.53727) (xy 90.605102 -224.515172) (xy 90.427302 -224.82302)
			(xy 90.465656 -224.845118) (xy 90.621104 -224.880678)
		)
		(stroke
			(width 0)
			(type solid)
		)
		(fill yes)
		(layer "In6.Cu")
		(net "M_C_CPU1_SB_DQ<31>")
	)
	(gr_poly
		(pts
			(xy 90.774012 -272.029174) (xy 90.727022 -271.876774) (xy 90.465402 -271.876774) (xy 90.418412 -272.029174)
			(xy 90.418412 -272.073624) (xy 90.774012 -272.073624)
		)
		(stroke
			(width 0)
			(type solid)
		)
		(fill yes)
		(layer "In6.Cu")
		(net "M_C_CPU1_SA_DQ<10>")
	)
	(gr_poly
		(pts
			(xy 90.774012 -267.14577) (xy 90.727022 -266.99337) (xy 90.465402 -266.99337) (xy 90.418412 -267.14577)
			(xy 90.418412 -267.19022) (xy 90.774012 -267.19022)
		)
		(stroke
			(width 0)
			(type solid)
		)
		(fill yes)
		(layer "In6.Cu")
		(net "M_C_CPU1_SA_DQ<26>")
	)
	(gr_poly
		(pts
			(xy 90.774012 -262.262874) (xy 90.727022 -262.110474) (xy 90.465402 -262.110474) (xy 90.418412 -262.262874)
			(xy 90.418412 -262.30707) (xy 90.774012 -262.30707)
		)
		(stroke
			(width 0)
			(type solid)
		)
		(fill yes)
		(layer "In6.Cu")
		(net "M_C_CPU1_SA_CB<0>")
	)
	(gr_poly
		(pts
			(xy 90.776552 -273.248882) (xy 90.776552 -273.204686) (xy 90.420952 -273.204686) (xy 90.420952 -273.248882)
			(xy 90.467942 -273.401282) (xy 90.729562 -273.401282)
		)
		(stroke
			(width 0)
			(type solid)
		)
		(fill yes)
		(layer "In6.Cu")
		(net "M_D_CPU1_SA_DQ<5>")
	)
	(gr_poly
		(pts
			(xy 90.776552 -268.365478) (xy 90.776552 -268.321282) (xy 90.420952 -268.321282) (xy 90.420952 -268.365478)
			(xy 90.467942 -268.517878) (xy 90.729562 -268.517878)
		)
		(stroke
			(width 0)
			(type solid)
		)
		(fill yes)
		(layer "In6.Cu")
		(net "M_C_CPU1_SA_DQ<13>")
	)
	(gr_poly
		(pts
			(xy 90.776552 -258.599178) (xy 90.776552 -258.554728) (xy 90.420952 -258.554728) (xy 90.420952 -258.599178)
			(xy 90.467942 -258.751578) (xy 90.729562 -258.751578)
		)
		(stroke
			(width 0)
			(type solid)
		)
		(fill yes)
		(layer "In6.Cu")
		(net "M_C_CPU1_SA_CB<7>")
	)
	(gr_poly
		(pts
			(xy 90.779092 -263.482074) (xy 90.779092 -263.437624) (xy 90.423492 -263.437624) (xy 90.423492 -263.482074)
			(xy 90.470482 -263.634474) (xy 90.732102 -263.634474)
		)
		(stroke
			(width 0)
			(type solid)
		)
		(fill yes)
		(layer "In6.Cu")
		(net "M_C_CPU1_SA_DQ<29>")
	)
	(gr_poly
		(pts
			(xy 90.782394 -271.620742) (xy 90.782394 -271.576546) (xy 90.426794 -271.576546) (xy 90.426794 -271.620742)
			(xy 90.473784 -271.773142) (xy 90.735404 -271.773142)
		)
		(stroke
			(width 0)
			(type solid)
		)
		(fill yes)
		(layer "In6.Cu")
		(net "M_C_CPU1_SA_DQ<9>")
	)
	(gr_poly
		(pts
			(xy 90.782394 -266.737846) (xy 90.782394 -266.693396) (xy 90.426794 -266.693396) (xy 90.426794 -266.737846)
			(xy 90.473784 -266.890246) (xy 90.735404 -266.890246)
		)
		(stroke
			(width 0)
			(type solid)
		)
		(fill yes)
		(layer "In6.Cu")
		(net "M_C_CPU1_SA_DQ<25>")
	)
	(gr_poly
		(pts
			(xy 90.782394 -261.854442) (xy 90.782394 -261.809992) (xy 90.426794 -261.809992) (xy 90.426794 -261.854442)
			(xy 90.473784 -262.006842) (xy 90.735404 -262.006842)
		)
		(stroke
			(width 0)
			(type solid)
		)
		(fill yes)
		(layer "In6.Cu")
		(net "M_C_CPU1_SA_CB<3>")
	)
	(gr_poly
		(pts
			(xy 90.782394 -256.971038) (xy 90.782394 -256.926588) (xy 90.426794 -256.926588) (xy 90.426794 -256.971038)
			(xy 90.473784 -257.123438) (xy 90.735404 -257.123438)
		)
		(stroke
			(width 0)
			(type solid)
		)
		(fill yes)
		(layer "In6.Cu")
		(net "M_D_CPU1_SA_RSP<0>")
	)
	(gr_poly
		(pts
			(xy 90.78849 -275.284946) (xy 90.7415 -275.132546) (xy 90.47988 -275.132546) (xy 90.43289 -275.284946)
			(xy 90.43289 -275.329142) (xy 90.78849 -275.329142)
		)
		(stroke
			(width 0)
			(type solid)
		)
		(fill yes)
		(layer "In6.Cu")
		(net "M_D_CPU1_SA_DQS_DN<0>")
	)
	(gr_poly
		(pts
			(xy 90.78849 -274.876514) (xy 90.78849 -274.832318) (xy 90.43289 -274.832318) (xy 90.43289 -274.876514)
			(xy 90.47988 -275.028914) (xy 90.7415 -275.028914)
		)
		(stroke
			(width 0)
			(type solid)
		)
		(fill yes)
		(layer "In6.Cu")
		(net "M_D_CPU1_SA_DQS_DN<5>")
	)
	(gr_poly
		(pts
			(xy 90.78849 -273.657314) (xy 90.7415 -273.504914) (xy 90.47988 -273.504914) (xy 90.43289 -273.657314)
			(xy 90.43289 -273.70151) (xy 90.78849 -273.70151)
		)
		(stroke
			(width 0)
			(type solid)
		)
		(fill yes)
		(layer "In6.Cu")
		(net "M_D_CPU1_SA_DQ<6>")
	)
	(gr_poly
		(pts
			(xy 90.78849 -270.401542) (xy 90.7415 -270.249142) (xy 90.47988 -270.249142) (xy 90.43289 -270.401542)
			(xy 90.43289 -270.445992) (xy 90.78849 -270.445992)
		)
		(stroke
			(width 0)
			(type solid)
		)
		(fill yes)
		(layer "In6.Cu")
		(net "M_C_CPU1_SA_DQS_DN<1>")
	)
	(gr_poly
		(pts
			(xy 90.78849 -269.993618) (xy 90.78849 -269.949168) (xy 90.43289 -269.949168) (xy 90.43289 -269.993618)
			(xy 90.47988 -270.146018) (xy 90.7415 -270.146018)
		)
		(stroke
			(width 0)
			(type solid)
		)
		(fill yes)
		(layer "In6.Cu")
		(net "M_C_CPU1_SA_DQS_DN<6>")
	)
	(gr_poly
		(pts
			(xy 90.78849 -268.77391) (xy 90.7415 -268.62151) (xy 90.47988 -268.62151) (xy 90.43289 -268.77391)
			(xy 90.43289 -268.818106) (xy 90.78849 -268.818106)
		)
		(stroke
			(width 0)
			(type solid)
		)
		(fill yes)
		(layer "In6.Cu")
		(net "M_C_CPU1_SA_DQ<14>")
	)
	(gr_poly
		(pts
			(xy 90.78849 -265.518138) (xy 90.7415 -265.365738) (xy 90.47988 -265.365738) (xy 90.43289 -265.518138)
			(xy 90.43289 -265.562588) (xy 90.78849 -265.562588)
		)
		(stroke
			(width 0)
			(type solid)
		)
		(fill yes)
		(layer "In6.Cu")
		(net "M_C_CPU1_SA_DQS_DN<3>")
	)
	(gr_poly
		(pts
			(xy 90.78849 -265.110214) (xy 90.78849 -265.065764) (xy 90.43289 -265.065764) (xy 90.43289 -265.110214)
			(xy 90.47988 -265.262614) (xy 90.7415 -265.262614)
		)
		(stroke
			(width 0)
			(type solid)
		)
		(fill yes)
		(layer "In6.Cu")
		(net "M_C_CPU1_SA_DQS_DN<8>")
	)
	(gr_poly
		(pts
			(xy 90.78849 -263.890506) (xy 90.7415 -263.738106) (xy 90.47988 -263.738106) (xy 90.43289 -263.890506)
			(xy 90.43289 -263.934956) (xy 90.78849 -263.934956)
		)
		(stroke
			(width 0)
			(type solid)
		)
		(fill yes)
		(layer "In6.Cu")
		(net "M_C_CPU1_SA_DQ<30>")
	)
	(gr_poly
		(pts
			(xy 90.78849 -259.007102) (xy 90.7415 -258.854702) (xy 90.47988 -258.854702) (xy 90.43289 -259.007102)
			(xy 90.43289 -259.051552) (xy 90.78849 -259.051552)
		)
		(stroke
			(width 0)
			(type solid)
		)
		(fill yes)
		(layer "In6.Cu")
		(net "M_C_CPU1_SA_CB<4>")
	)
	(gr_poly
		(pts
			(xy 90.78849 -255.751838) (xy 90.7415 -255.599438) (xy 90.47988 -255.599438) (xy 90.43289 -255.751838)
			(xy 90.43289 -255.796034) (xy 90.78849 -255.796034)
		)
		(stroke
			(width 0)
			(type solid)
		)
		(fill yes)
		(layer "In6.Cu")
		(net "M_D_CPU1_SB_RSP<1>")
	)
	(gr_poly
		(pts
			(xy 90.78849 -255.343406) (xy 90.78849 -255.29921) (xy 90.43289 -255.29921) (xy 90.43289 -255.343406)
			(xy 90.47988 -255.495806) (xy 90.7415 -255.495806)
		)
		(stroke
			(width 0)
			(type solid)
		)
		(fill yes)
		(layer "In6.Cu")
		(net "M_C_CPU1_SA_RSP<0>")
	)
	(gr_poly
		(pts
			(xy 90.78849 -254.123698) (xy 90.7415 -253.971298) (xy 90.47988 -253.971298) (xy 90.43289 -254.123698)
			(xy 90.43289 -254.168148) (xy 90.78849 -254.168148)
		)
		(stroke
			(width 0)
			(type solid)
		)
		(fill yes)
		(layer "In6.Cu")
		(net "M_C_CPU1_SB_RSP<1>")
	)
	(gr_poly
		(pts
			(xy 90.79103 -260.634734) (xy 90.74404 -260.482334) (xy 90.48242 -260.482334) (xy 90.43543 -260.634734)
			(xy 90.43543 -260.679184) (xy 90.79103 -260.679184)
		)
		(stroke
			(width 0)
			(type solid)
		)
		(fill yes)
		(layer "In6.Cu")
		(net "M_C_CPU1_SA_DQS_DP<9>")
	)
	(gr_poly
		(pts
			(xy 90.79103 -260.22681) (xy 90.79103 -260.18236) (xy 90.43543 -260.18236) (xy 90.43543 -260.22681)
			(xy 90.48242 -260.37921) (xy 90.74404 -260.37921)
		)
		(stroke
			(width 0)
			(type solid)
		)
		(fill yes)
		(layer "In6.Cu")
		(net "M_C_CPU1_SA_DQS_DP<4>")
	)
	(gr_poly
		(pts
			(xy 90.856308 -276.982936) (xy 90.74785 -276.866096) (xy 90.709496 -276.843998) (xy 90.531696 -277.151846)
			(xy 90.57005 -277.173944) (xy 90.725498 -277.209504)
		)
		(stroke
			(width 0)
			(type solid)
		)
		(fill yes)
		(layer "In6.Cu")
		(net "M_D_CPU1_SA_DQ<1>")
	)
	(gr_poly
		(pts
			(xy 90.857324 -278.608282) (xy 90.748866 -278.491442) (xy 90.710512 -278.469344) (xy 90.532712 -278.777192)
			(xy 90.571066 -278.79929) (xy 90.726514 -278.83485)
		)
		(stroke
			(width 0)
			(type solid)
		)
		(fill yes)
		(layer "In6.Cu")
		(net "M_D_CPU1_SA_DQ<0>")
	)
	(gr_poly
		(pts
			(xy 90.99804 -230.54945) (xy 91.036394 -230.527352) (xy 90.858594 -230.219504) (xy 90.82024 -230.241602)
			(xy 90.711782 -230.358442) (xy 90.842592 -230.58501)
		)
		(stroke
			(width 0)
			(type solid)
		)
		(fill yes)
		(layer "In6.Cu")
		(net "M_D_CPU1_SB_DQ<21>")
	)
	(gr_poly
		(pts
			(xy 91.109038 -229.931722) (xy 91.217496 -229.814882) (xy 91.086686 -229.588314) (xy 90.931238 -229.623874)
			(xy 90.892884 -229.645972) (xy 91.070684 -229.95382)
		)
		(stroke
			(width 0)
			(type solid)
		)
		(fill yes)
		(layer "In6.Cu")
		(net "M_D_CPU1_SB_DQ<23>")
	)
	(gr_poly
		(pts
			(xy 91.13393 -241.685318) (xy 91.08694 -241.532918) (xy 90.82532 -241.532918) (xy 90.77833 -241.685318)
			(xy 90.77833 -241.729514) (xy 91.13393 -241.729514)
		)
		(stroke
			(width 0)
			(type solid)
		)
		(fill yes)
		(layer "In6.Cu")
		(net "M_C_CPU1_SB_DQS_DP<5>")
	)
	(gr_poly
		(pts
			(xy 91.13393 -236.801914) (xy 91.08694 -236.649514) (xy 90.82532 -236.649514) (xy 90.77833 -236.801914)
			(xy 90.77833 -236.84611) (xy 91.13393 -236.84611)
		)
		(stroke
			(width 0)
			(type solid)
		)
		(fill yes)
		(layer "In6.Cu")
		(net "M_C_CPU1_SB_DQS_DP<6>")
	)
	(gr_poly
		(pts
			(xy 91.13393 -231.91851) (xy 91.08694 -231.76611) (xy 90.82532 -231.76611) (xy 90.77833 -231.91851)
			(xy 90.77833 -231.96296) (xy 91.13393 -231.96296)
		)
		(stroke
			(width 0)
			(type solid)
		)
		(fill yes)
		(layer "In6.Cu")
		(net "M_D_CPU1_SB_DQS_DP<7>")
	)
	(gr_poly
		(pts
			(xy 91.13647 -248.196354) (xy 91.08948 -248.043954) (xy 90.82786 -248.043954) (xy 90.78087 -248.196354)
			(xy 90.78087 -248.24055) (xy 91.13647 -248.24055)
		)
		(stroke
			(width 0)
			(type solid)
		)
		(fill yes)
		(layer "In6.Cu")
		(net "M_A_CPU1_SA_RSP<0>")
	)
	(gr_poly
		(pts
			(xy 91.13647 -247.787922) (xy 91.13647 -247.743726) (xy 90.78087 -247.743726) (xy 90.78087 -247.787922)
			(xy 90.82786 -247.940322) (xy 91.08948 -247.940322)
		)
		(stroke
			(width 0)
			(type solid)
		)
		(fill yes)
		(layer "In6.Cu")
		(net "M_A_CPU1_SA_RSP<1>")
	)
	(gr_poly
		(pts
			(xy 91.13647 -244.53215) (xy 91.13647 -244.487954) (xy 90.78087 -244.487954) (xy 90.78087 -244.53215)
			(xy 90.82786 -244.68455) (xy 91.08948 -244.68455)
		)
		(stroke
			(width 0)
			(type solid)
		)
		(fill yes)
		(layer "In6.Cu")
		(net "M_C_CPU1_SB_DQ<0>")
	)
	(gr_poly
		(pts
			(xy 91.13647 -242.905026) (xy 91.13647 -242.860576) (xy 90.78087 -242.860576) (xy 90.78087 -242.905026)
			(xy 90.82786 -243.057426) (xy 91.08948 -243.057426)
		)
		(stroke
			(width 0)
			(type solid)
		)
		(fill yes)
		(layer "In6.Cu")
		(net "M_C_CPU1_SB_DQS_DP<0>")
	)
	(gr_poly
		(pts
			(xy 91.13647 -239.648746) (xy 91.13647 -239.60455) (xy 90.78087 -239.60455) (xy 90.78087 -239.648746)
			(xy 90.82786 -239.801146) (xy 91.08948 -239.801146)
		)
		(stroke
			(width 0)
			(type solid)
		)
		(fill yes)
		(layer "In6.Cu")
		(net "M_C_CPU1_SB_DQ<8>")
	)
	(gr_poly
		(pts
			(xy 91.13647 -238.429546) (xy 91.08948 -238.277146) (xy 90.82786 -238.277146) (xy 90.78087 -238.429546)
			(xy 90.78087 -238.473996) (xy 91.13647 -238.473996)
		)
		(stroke
			(width 0)
			(type solid)
		)
		(fill yes)
		(layer "In6.Cu")
		(net "M_C_CPU1_SB_DQ<11>")
	)
	(gr_poly
		(pts
			(xy 91.13647 -238.021622) (xy 91.13647 -237.977172) (xy 90.78087 -237.977172) (xy 90.78087 -238.021622)
			(xy 90.82786 -238.174022) (xy 91.08948 -238.174022)
		)
		(stroke
			(width 0)
			(type solid)
		)
		(fill yes)
		(layer "In6.Cu")
		(net "M_C_CPU1_SB_DQS_DP<1>")
	)
	(gr_poly
		(pts
			(xy 91.13647 -234.76585) (xy 91.13647 -234.7214) (xy 90.78087 -234.7214) (xy 90.78087 -234.76585)
			(xy 90.82786 -234.91825) (xy 91.08948 -234.91825)
		)
		(stroke
			(width 0)
			(type solid)
		)
		(fill yes)
		(layer "In6.Cu")
		(net "M_D_CPU1_SB_DQ<16>")
	)
	(gr_poly
		(pts
			(xy 91.13647 -233.546142) (xy 91.08948 -233.393742) (xy 90.82786 -233.393742) (xy 90.78087 -233.546142)
			(xy 90.78087 -233.590592) (xy 91.13647 -233.590592)
		)
		(stroke
			(width 0)
			(type solid)
		)
		(fill yes)
		(layer "In6.Cu")
		(net "M_D_CPU1_SB_DQ<19>")
	)
	(gr_poly
		(pts
			(xy 91.13647 -233.138218) (xy 91.13647 -233.093768) (xy 90.78087 -233.093768) (xy 90.78087 -233.138218)
			(xy 90.82786 -233.290618) (xy 91.08948 -233.290618)
		)
		(stroke
			(width 0)
			(type solid)
		)
		(fill yes)
		(layer "In6.Cu")
		(net "M_D_CPU1_SB_DQS_DP<2>")
	)
	(gr_poly
		(pts
			(xy 91.13647 -228.663246) (xy 91.08948 -228.510846) (xy 90.82786 -228.510846) (xy 90.78087 -228.663246)
			(xy 90.78087 -228.707442) (xy 91.13647 -228.707442)
		)
		(stroke
			(width 0)
			(type solid)
		)
		(fill yes)
		(layer "In6.Cu")
		(net "M_C_CPU1_SB_DQ<24>")
	)
	(gr_poly
		(pts
			(xy 91.13647 -228.254814) (xy 91.13647 -228.210618) (xy 90.78087 -228.210618) (xy 90.78087 -228.254814)
			(xy 90.82786 -228.407214) (xy 91.08948 -228.407214)
		)
		(stroke
			(width 0)
			(type solid)
		)
		(fill yes)
		(layer "In6.Cu")
		(net "M_C_CPU1_SB_DQ<25>")
	)
	(gr_poly
		(pts
			(xy 91.13647 -227.035106) (xy 91.08948 -226.882706) (xy 90.82786 -226.882706) (xy 90.78087 -227.035106)
			(xy 90.78087 -227.079556) (xy 91.13647 -227.079556)
		)
		(stroke
			(width 0)
			(type solid)
		)
		(fill yes)
		(layer "In6.Cu")
		(net "M_C_CPU1_SB_DQS_DN<3>")
	)
	(gr_poly
		(pts
			(xy 91.142312 -246.16029) (xy 91.142312 -246.11584) (xy 90.786712 -246.11584) (xy 90.786712 -246.16029)
			(xy 90.833702 -246.31269) (xy 91.095322 -246.31269)
		)
		(stroke
			(width 0)
			(type solid)
		)
		(fill yes)
		(layer "In6.Cu")
		(net "M_D_CPU1_SB_CS_N<2>")
	)
	(gr_poly
		(pts
			(xy 91.142312 -241.276886) (xy 91.142312 -241.232436) (xy 90.786712 -241.232436) (xy 90.786712 -241.276886)
			(xy 90.833702 -241.429286) (xy 91.095322 -241.429286)
		)
		(stroke
			(width 0)
			(type solid)
		)
		(fill yes)
		(layer "In6.Cu")
		(net "M_C_CPU1_SB_DQ<4>")
	)
	(gr_poly
		(pts
			(xy 91.142312 -236.393482) (xy 91.142312 -236.349286) (xy 90.786712 -236.349286) (xy 90.786712 -236.393482)
			(xy 90.833702 -236.545882) (xy 91.095322 -236.545882)
		)
		(stroke
			(width 0)
			(type solid)
		)
		(fill yes)
		(layer "In6.Cu")
		(net "M_C_CPU1_SB_DQ<12>")
	)
	(gr_poly
		(pts
			(xy 91.142312 -231.510078) (xy 91.142312 -231.465882) (xy 90.786712 -231.465882) (xy 90.786712 -231.510078)
			(xy 90.833702 -231.662478) (xy 91.095322 -231.662478)
		)
		(stroke
			(width 0)
			(type solid)
		)
		(fill yes)
		(layer "In6.Cu")
		(net "M_D_CPU1_SB_DQ<20>")
	)
	(gr_poly
		(pts
			(xy 91.142312 -225.407474) (xy 91.095322 -225.255074) (xy 90.833702 -225.255074) (xy 90.786712 -225.407474)
			(xy 90.786712 -225.451924) (xy 91.142312 -225.451924)
		)
		(stroke
			(width 0)
			(type solid)
		)
		(fill yes)
		(layer "In6.Cu")
		(net "M_C_CPU1_SB_DQ<30>")
	)
	(gr_poly
		(pts
			(xy 91.145868 -243.313458) (xy 91.098878 -243.161058) (xy 90.837258 -243.161058) (xy 90.790268 -243.313458)
			(xy 90.790268 -243.357654) (xy 91.145868 -243.357654)
		)
		(stroke
			(width 0)
			(type solid)
		)
		(fill yes)
		(layer "In6.Cu")
		(net "M_C_CPU1_SB_DQ<3>")
	)
	(gr_poly
		(pts
			(xy 91.146376 -277.081742) (xy 91.108022 -277.059644) (xy 90.952574 -277.024084) (xy 90.821764 -277.250652)
			(xy 90.930222 -277.367492) (xy 90.968576 -277.38959)
		)
		(stroke
			(width 0)
			(type solid)
		)
		(fill yes)
		(layer "In6.Cu")
		(net "M_D_CPU1_SA_DQ<2>")
	)
	(gr_poly
		(pts
			(xy 91.148408 -244.94109) (xy 91.101418 -244.78869) (xy 90.839798 -244.78869) (xy 90.792808 -244.94109)
			(xy 90.792808 -244.985286) (xy 91.148408 -244.985286)
		)
		(stroke
			(width 0)
			(type solid)
		)
		(fill yes)
		(layer "In6.Cu")
		(net "M_D_CPU1_SB_CS_N<1>")
	)
	(gr_poly
		(pts
			(xy 91.148408 -240.057686) (xy 91.101418 -239.905286) (xy 90.839798 -239.905286) (xy 90.792808 -240.057686)
			(xy 90.792808 -240.101882) (xy 91.148408 -240.101882)
		)
		(stroke
			(width 0)
			(type solid)
		)
		(fill yes)
		(layer "In6.Cu")
		(net "M_C_CPU1_SB_DQ<7>")
	)
	(gr_poly
		(pts
			(xy 91.148408 -235.174282) (xy 91.101418 -235.021882) (xy 90.839798 -235.021882) (xy 90.792808 -235.174282)
			(xy 90.792808 -235.218732) (xy 91.148408 -235.218732)
		)
		(stroke
			(width 0)
			(type solid)
		)
		(fill yes)
		(layer "In6.Cu")
		(net "M_C_CPU1_SB_DQ<15>")
	)
	(gr_poly
		(pts
			(xy 91.148408 -226.627182) (xy 91.148408 -226.582732) (xy 90.792808 -226.582732) (xy 90.792808 -226.627182)
			(xy 90.839798 -226.779582) (xy 91.101418 -226.779582)
		)
		(stroke
			(width 0)
			(type solid)
		)
		(fill yes)
		(layer "In6.Cu")
		(net "M_C_CPU1_SB_DQS_DN<8>")
	)
	(gr_poly
		(pts
			(xy 91.243912 -275.690584) (xy 91.243912 -275.646134) (xy 90.888312 -275.646134) (xy 90.888312 -275.690584)
			(xy 90.935302 -275.842984) (xy 91.196922 -275.842984)
		)
		(stroke
			(width 0)
			(type solid)
		)
		(fill yes)
		(layer "In6.Cu")
		(net "M_D_CPU1_SA_DQS_DP<0>")
	)
	(gr_poly
		(pts
			(xy 91.243912 -270.807434) (xy 91.243912 -270.762984) (xy 90.888312 -270.762984) (xy 90.888312 -270.807434)
			(xy 90.935302 -270.959834) (xy 91.196922 -270.959834)
		)
		(stroke
			(width 0)
			(type solid)
		)
		(fill yes)
		(layer "In6.Cu")
		(net "M_C_CPU1_SA_DQS_DP<1>")
	)
	(gr_poly
		(pts
			(xy 91.243912 -265.92403) (xy 91.243912 -265.87958) (xy 90.888312 -265.87958) (xy 90.888312 -265.92403)
			(xy 90.935302 -266.07643) (xy 91.196922 -266.07643)
		)
		(stroke
			(width 0)
			(type solid)
		)
		(fill yes)
		(layer "In6.Cu")
		(net "M_C_CPU1_SA_DQS_DP<3>")
	)
	(gr_poly
		(pts
			(xy 91.243912 -261.040626) (xy 91.243912 -260.99643) (xy 90.888312 -260.99643) (xy 90.888312 -261.040626)
			(xy 90.935302 -261.193026) (xy 91.196922 -261.193026)
		)
		(stroke
			(width 0)
			(type solid)
		)
		(fill yes)
		(layer "In6.Cu")
		(net "M_C_CPU1_SA_DQS_DN<9>")
	)
	(gr_poly
		(pts
			(xy 91.243912 -256.157222) (xy 91.243912 -256.113026) (xy 90.888312 -256.113026) (xy 90.888312 -256.157222)
			(xy 90.935302 -256.309622) (xy 91.196922 -256.309622)
		)
		(stroke
			(width 0)
			(type solid)
		)
		(fill yes)
		(layer "In6.Cu")
		(net "M_D_CPU1_SA_RSP<1>")
	)
	(gr_poly
		(pts
			(xy 91.246452 -274.47113) (xy 91.199462 -274.31873) (xy 90.937842 -274.31873) (xy 90.890852 -274.47113)
			(xy 90.890852 -274.515326) (xy 91.246452 -274.515326)
		)
		(stroke
			(width 0)
			(type solid)
		)
		(fill yes)
		(layer "In6.Cu")
		(net "M_D_CPU1_SA_DQS_DP<5>")
	)
	(gr_poly
		(pts
			(xy 91.246452 -274.062698) (xy 91.246452 -274.018502) (xy 90.890852 -274.018502) (xy 90.890852 -274.062698)
			(xy 90.937842 -274.215098) (xy 91.199462 -274.215098)
		)
		(stroke
			(width 0)
			(type solid)
		)
		(fill yes)
		(layer "In6.Cu")
		(net "M_D_CPU1_SA_DQ<4>")
	)
	(gr_poly
		(pts
			(xy 91.246452 -272.843498) (xy 91.199462 -272.691098) (xy 90.937842 -272.691098) (xy 90.890852 -272.843498)
			(xy 90.890852 -272.887948) (xy 91.246452 -272.887948)
		)
		(stroke
			(width 0)
			(type solid)
		)
		(fill yes)
		(layer "In6.Cu")
		(net "M_D_CPU1_SA_DQ<7>")
	)
	(gr_poly
		(pts
			(xy 91.246452 -269.587726) (xy 91.199462 -269.435326) (xy 90.937842 -269.435326) (xy 90.890852 -269.587726)
			(xy 90.890852 -269.631922) (xy 91.246452 -269.631922)
		)
		(stroke
			(width 0)
			(type solid)
		)
		(fill yes)
		(layer "In6.Cu")
		(net "M_C_CPU1_SA_DQS_DP<6>")
	)
	(gr_poly
		(pts
			(xy 91.246452 -269.179294) (xy 91.246452 -269.135098) (xy 90.890852 -269.135098) (xy 90.890852 -269.179294)
			(xy 90.937842 -269.331694) (xy 91.199462 -269.331694)
		)
		(stroke
			(width 0)
			(type solid)
		)
		(fill yes)
		(layer "In6.Cu")
		(net "M_C_CPU1_SA_DQ<12>")
	)
	(gr_poly
		(pts
			(xy 91.246452 -267.960094) (xy 91.199462 -267.807694) (xy 90.937842 -267.807694) (xy 90.890852 -267.960094)
			(xy 90.890852 -268.004544) (xy 91.246452 -268.004544)
		)
		(stroke
			(width 0)
			(type solid)
		)
		(fill yes)
		(layer "In6.Cu")
		(net "M_C_CPU1_SA_DQ<15>")
	)
	(gr_poly
		(pts
			(xy 91.246452 -264.704322) (xy 91.199462 -264.551922) (xy 90.937842 -264.551922) (xy 90.890852 -264.704322)
			(xy 90.890852 -264.748772) (xy 91.246452 -264.748772)
		)
		(stroke
			(width 0)
			(type solid)
		)
		(fill yes)
		(layer "In6.Cu")
		(net "M_C_CPU1_SA_DQS_DP<8>")
	)
	(gr_poly
		(pts
			(xy 91.246452 -264.296398) (xy 91.246452 -264.251948) (xy 90.890852 -264.251948) (xy 90.890852 -264.296398)
			(xy 90.937842 -264.448798) (xy 91.199462 -264.448798)
		)
		(stroke
			(width 0)
			(type solid)
		)
		(fill yes)
		(layer "In6.Cu")
		(net "M_C_CPU1_SA_DQ<28>")
	)
	(gr_poly
		(pts
			(xy 91.246452 -259.820918) (xy 91.199462 -259.668518) (xy 90.937842 -259.668518) (xy 90.890852 -259.820918)
			(xy 90.890852 -259.865368) (xy 91.246452 -259.865368)
		)
		(stroke
			(width 0)
			(type solid)
		)
		(fill yes)
		(layer "In6.Cu")
		(net "M_C_CPU1_SA_DQS_DN<4>")
	)
	(gr_poly
		(pts
			(xy 91.246452 -259.412994) (xy 91.246452 -259.368544) (xy 90.890852 -259.368544) (xy 90.890852 -259.412994)
			(xy 90.937842 -259.565394) (xy 91.199462 -259.565394)
		)
		(stroke
			(width 0)
			(type solid)
		)
		(fill yes)
		(layer "In6.Cu")
		(net "M_C_CPU1_SA_CB<6>")
	)
	(gr_poly
		(pts
			(xy 91.246452 -258.193286) (xy 91.199462 -258.040886) (xy 90.937842 -258.040886) (xy 90.890852 -258.193286)
			(xy 90.890852 -258.237736) (xy 91.246452 -258.237736)
		)
		(stroke
			(width 0)
			(type solid)
		)
		(fill yes)
		(layer "In6.Cu")
		(net "M_C_CPU1_SA_CB<5>")
	)
	(gr_poly
		(pts
			(xy 91.246452 -254.937514) (xy 91.199462 -254.785114) (xy 90.937842 -254.785114) (xy 90.890852 -254.937514)
			(xy 90.890852 -254.981964) (xy 91.246452 -254.981964)
		)
		(stroke
			(width 0)
			(type solid)
		)
		(fill yes)
		(layer "In6.Cu")
		(net "M_C_CPU1_SB_RSP<0>")
	)
	(gr_poly
		(pts
			(xy 91.246452 -254.52959) (xy 91.246452 -254.48514) (xy 90.890852 -254.48514) (xy 90.890852 -254.52959)
			(xy 90.937842 -254.68199) (xy 91.199462 -254.68199)
		)
		(stroke
			(width 0)
			(type solid)
		)
		(fill yes)
		(layer "In6.Cu")
		(net "M_C_CPU1_SA_RSP<1>")
	)
	(gr_poly
		(pts
			(xy 91.252294 -276.09927) (xy 91.205304 -275.94687) (xy 90.943684 -275.94687) (xy 90.896694 -276.09927)
			(xy 90.896694 -276.143466) (xy 91.252294 -276.143466)
		)
		(stroke
			(width 0)
			(type solid)
		)
		(fill yes)
		(layer "In6.Cu")
		(net "M_D_CPU1_SA_DQ<3>")
	)
	(gr_poly
		(pts
			(xy 91.252294 -271.215866) (xy 91.205304 -271.063466) (xy 90.943684 -271.063466) (xy 90.896694 -271.215866)
			(xy 90.896694 -271.260062) (xy 91.252294 -271.260062)
		)
		(stroke
			(width 0)
			(type solid)
		)
		(fill yes)
		(layer "In6.Cu")
		(net "M_C_CPU1_SA_DQ<11>")
	)
	(gr_poly
		(pts
			(xy 91.252294 -266.332462) (xy 91.205304 -266.180062) (xy 90.943684 -266.180062) (xy 90.896694 -266.332462)
			(xy 90.896694 -266.376658) (xy 91.252294 -266.376658)
		)
		(stroke
			(width 0)
			(type solid)
		)
		(fill yes)
		(layer "In6.Cu")
		(net "M_C_CPU1_SA_DQ<27>")
	)
	(gr_poly
		(pts
			(xy 91.252294 -261.449058) (xy 91.205304 -261.296658) (xy 90.943684 -261.296658) (xy 90.896694 -261.449058)
			(xy 90.896694 -261.493508) (xy 91.252294 -261.493508)
		)
		(stroke
			(width 0)
			(type solid)
		)
		(fill yes)
		(layer "In6.Cu")
		(net "M_C_CPU1_SA_CB<1>")
	)
	(gr_poly
		(pts
			(xy 91.252294 -256.565654) (xy 91.205304 -256.413254) (xy 90.943684 -256.413254) (xy 90.896694 -256.565654)
			(xy 90.896694 -256.610104) (xy 91.252294 -256.610104)
		)
		(stroke
			(width 0)
			(type solid)
		)
		(fill yes)
		(layer "In6.Cu")
		(net "M_D_CPU1_SB_RSP<0>")
	)
	(gr_poly
		(pts
			(xy 91.25585 -263.077198) (xy 91.20886 -262.924798) (xy 90.94724 -262.924798) (xy 90.90025 -263.077198)
			(xy 90.90025 -263.121394) (xy 91.25585 -263.121394)
		)
		(stroke
			(width 0)
			(type solid)
		)
		(fill yes)
		(layer "In6.Cu")
		(net "M_C_CPU1_SA_DQ<31>")
	)
	(gr_poly
		(pts
			(xy 91.25839 -272.435066) (xy 91.25839 -272.390616) (xy 90.90279 -272.390616) (xy 90.90279 -272.435066)
			(xy 90.94978 -272.587466) (xy 91.2114 -272.587466)
		)
		(stroke
			(width 0)
			(type solid)
		)
		(fill yes)
		(layer "In6.Cu")
		(net "M_C_CPU1_SA_DQ<8>")
	)
	(gr_poly
		(pts
			(xy 91.25839 -267.551662) (xy 91.25839 -267.507212) (xy 90.90279 -267.507212) (xy 90.90279 -267.551662)
			(xy 90.94978 -267.704062) (xy 91.2114 -267.704062)
		)
		(stroke
			(width 0)
			(type solid)
		)
		(fill yes)
		(layer "In6.Cu")
		(net "M_C_CPU1_SA_DQ<24>")
	)
	(gr_poly
		(pts
			(xy 91.25839 -262.668258) (xy 91.25839 -262.623808) (xy 90.90279 -262.623808) (xy 90.90279 -262.668258)
			(xy 90.94978 -262.820658) (xy 91.2114 -262.820658)
		)
		(stroke
			(width 0)
			(type solid)
		)
		(fill yes)
		(layer "In6.Cu")
		(net "M_C_CPU1_SA_CB<2>")
	)
	(gr_poly
		(pts
			(xy 91.326462 -277.796244) (xy 91.218004 -277.679404) (xy 91.17965 -277.657306) (xy 91.00185 -277.965154)
			(xy 91.040204 -277.987252) (xy 91.195652 -278.022812)
		)
		(stroke
			(width 0)
			(type solid)
		)
		(fill yes)
		(layer "In6.Cu")
		(net "M_D_CPU1_SA_DQ<0>")
	)
	(gr_poly
		(pts
			(xy 91.46794 -224.85223) (xy 91.506294 -224.830132) (xy 91.328494 -224.522284) (xy 91.29014 -224.544382)
			(xy 91.181682 -224.661222) (xy 91.312492 -224.88779)
		)
		(stroke
			(width 0)
			(type solid)
		)
		(fill yes)
		(layer "In6.Cu")
		(net "M_C_CPU1_SB_DQ<31>")
	)
	(gr_poly
		(pts
			(xy 91.46921 -229.738174) (xy 91.507564 -229.716076) (xy 91.329764 -229.408228) (xy 91.29141 -229.430326)
			(xy 91.182952 -229.547166) (xy 91.313762 -229.773734)
		)
		(stroke
			(width 0)
			(type solid)
		)
		(fill yes)
		(layer "In6.Cu")
		(net "M_C_CPU1_SB_DQ<26>")
	)
	(gr_poly
		(pts
			(xy 91.578938 -229.117906) (xy 91.687396 -229.001066) (xy 91.556586 -228.774498) (xy 91.401138 -228.810058)
			(xy 91.362784 -228.832156) (xy 91.540584 -229.140004)
		)
		(stroke
			(width 0)
			(type solid)
		)
		(fill yes)
		(layer "In6.Cu")
		(net "M_C_CPU1_SB_DQ<24>")
	)
	(gr_poly
		(pts
			(xy 91.578938 -224.234502) (xy 91.687396 -224.117662) (xy 91.556586 -223.891094) (xy 91.401138 -223.926654)
			(xy 91.362784 -223.948752) (xy 91.540584 -224.2566)
		)
		(stroke
			(width 0)
			(type solid)
		)
		(fill yes)
		(layer "In6.Cu")
		(net "M_C_CPU1_SB_DQ<29>")
	)
	(gr_poly
		(pts
			(xy 91.60637 -247.382538) (xy 91.55938 -247.230138) (xy 91.29776 -247.230138) (xy 91.25077 -247.382538)
			(xy 91.25077 -247.426988) (xy 91.60637 -247.426988)
		)
		(stroke
			(width 0)
			(type solid)
		)
		(fill yes)
		(layer "In6.Cu")
		(net "M_A_CPU1_SB_RSP<1>")
	)
	(gr_poly
		(pts
			(xy 91.60637 -237.616238) (xy 91.55938 -237.463838) (xy 91.29776 -237.463838) (xy 91.25077 -237.616238)
			(xy 91.25077 -237.660434) (xy 91.60637 -237.660434)
		)
		(stroke
			(width 0)
			(type solid)
		)
		(fill yes)
		(layer "In6.Cu")
		(net "M_C_CPU1_SB_DQS_DN<1>")
	)
	(gr_poly
		(pts
			(xy 91.60637 -232.732834) (xy 91.55938 -232.580434) (xy 91.29776 -232.580434) (xy 91.25077 -232.732834)
			(xy 91.25077 -232.77703) (xy 91.60637 -232.77703)
		)
		(stroke
			(width 0)
			(type solid)
		)
		(fill yes)
		(layer "In6.Cu")
		(net "M_D_CPU1_SB_DQS_DN<2>")
	)
	(gr_poly
		(pts
			(xy 91.60637 -227.84943) (xy 91.55938 -227.69703) (xy 91.29776 -227.69703) (xy 91.25077 -227.84943)
			(xy 91.25077 -227.893626) (xy 91.60637 -227.893626)
		)
		(stroke
			(width 0)
			(type solid)
		)
		(fill yes)
		(layer "In6.Cu")
		(net "M_C_CPU1_SB_DQ<27>")
	)
	(gr_poly
		(pts
			(xy 91.60637 -227.44049) (xy 91.60637 -227.396294) (xy 91.25077 -227.396294) (xy 91.25077 -227.44049)
			(xy 91.29776 -227.59289) (xy 91.55938 -227.59289)
		)
		(stroke
			(width 0)
			(type solid)
		)
		(fill yes)
		(layer "In6.Cu")
		(net "M_C_CPU1_SB_DQS_DP<3>")
	)
	(gr_poly
		(pts
			(xy 91.60637 -226.22129) (xy 91.55938 -226.06889) (xy 91.29776 -226.06889) (xy 91.25077 -226.22129)
			(xy 91.25077 -226.26574) (xy 91.60637 -226.26574)
		)
		(stroke
			(width 0)
			(type solid)
		)
		(fill yes)
		(layer "In6.Cu")
		(net "M_C_CPU1_SB_DQS_DP<8>")
	)
	(gr_poly
		(pts
			(xy 91.60891 -243.718334) (xy 91.60891 -243.674138) (xy 91.25331 -243.674138) (xy 91.25331 -243.718334)
			(xy 91.3003 -243.870734) (xy 91.56192 -243.870734)
		)
		(stroke
			(width 0)
			(type solid)
		)
		(fill yes)
		(layer "In6.Cu")
		(net "M_C_CPU1_SB_DQ<1>")
	)
	(gr_poly
		(pts
			(xy 91.612212 -242.499642) (xy 91.565222 -242.347242) (xy 91.303602 -242.347242) (xy 91.256612 -242.499642)
			(xy 91.256612 -242.543838) (xy 91.612212 -242.543838)
		)
		(stroke
			(width 0)
			(type solid)
		)
		(fill yes)
		(layer "In6.Cu")
		(net "M_C_CPU1_SB_DQS_DN<0>")
	)
	(gr_poly
		(pts
			(xy 91.612466 -248.601738) (xy 91.612466 -248.557542) (xy 91.256866 -248.557542) (xy 91.256866 -248.601738)
			(xy 91.303856 -248.754138) (xy 91.565476 -248.754138)
		)
		(stroke
			(width 0)
			(type solid)
		)
		(fill yes)
		(layer "In6.Cu")
		(net "M_A_CPU1_SB_RSP<0>")
	)
	(gr_poly
		(pts
			(xy 91.612466 -238.83493) (xy 91.612466 -238.790734) (xy 91.256866 -238.790734) (xy 91.256866 -238.83493)
			(xy 91.303856 -238.98733) (xy 91.565476 -238.98733)
		)
		(stroke
			(width 0)
			(type solid)
		)
		(fill yes)
		(layer "In6.Cu")
		(net "M_C_CPU1_SB_DQ<9>")
	)
	(gr_poly
		(pts
			(xy 91.612466 -233.952034) (xy 91.612466 -233.907584) (xy 91.256866 -233.907584) (xy 91.256866 -233.952034)
			(xy 91.303856 -234.104434) (xy 91.565476 -234.104434)
		)
		(stroke
			(width 0)
			(type solid)
		)
		(fill yes)
		(layer "In6.Cu")
		(net "M_D_CPU1_SB_DQ<17>")
	)
	(gr_poly
		(pts
			(xy 91.618308 -245.754906) (xy 91.571318 -245.602506) (xy 91.309698 -245.602506) (xy 91.262708 -245.754906)
			(xy 91.262708 -245.799102) (xy 91.618308 -245.799102)
		)
		(stroke
			(width 0)
			(type solid)
		)
		(fill yes)
		(layer "In6.Cu")
		(net "M_D_CPU1_SB_CS_N<3>")
	)
	(gr_poly
		(pts
			(xy 91.618308 -245.346474) (xy 91.618308 -245.302278) (xy 91.262708 -245.302278) (xy 91.262708 -245.346474)
			(xy 91.309698 -245.498874) (xy 91.571318 -245.498874)
		)
		(stroke
			(width 0)
			(type solid)
		)
		(fill yes)
		(layer "In6.Cu")
		(net "M_D_CPU1_SB_CS_N<0>")
	)
	(gr_poly
		(pts
			(xy 91.618308 -240.871502) (xy 91.571318 -240.719102) (xy 91.309698 -240.719102) (xy 91.262708 -240.871502)
			(xy 91.262708 -240.915698) (xy 91.618308 -240.915698)
		)
		(stroke
			(width 0)
			(type solid)
		)
		(fill yes)
		(layer "In6.Cu")
		(net "M_C_CPU1_SB_DQ<6>")
	)
	(gr_poly
		(pts
			(xy 91.618308 -240.46307) (xy 91.618308 -240.418874) (xy 91.262708 -240.418874) (xy 91.262708 -240.46307)
			(xy 91.309698 -240.61547) (xy 91.571318 -240.61547)
		)
		(stroke
			(width 0)
			(type solid)
		)
		(fill yes)
		(layer "In6.Cu")
		(net "M_C_CPU1_SB_DQ<5>")
	)
	(gr_poly
		(pts
			(xy 91.618308 -237.207298) (xy 91.618308 -237.163102) (xy 91.262708 -237.163102) (xy 91.262708 -237.207298)
			(xy 91.309698 -237.359698) (xy 91.571318 -237.359698)
		)
		(stroke
			(width 0)
			(type solid)
		)
		(fill yes)
		(layer "In6.Cu")
		(net "M_C_CPU1_SB_DQS_DN<6>")
	)
	(gr_poly
		(pts
			(xy 91.618308 -235.988098) (xy 91.571318 -235.835698) (xy 91.309698 -235.835698) (xy 91.262708 -235.988098)
			(xy 91.262708 -236.032294) (xy 91.618308 -236.032294)
		)
		(stroke
			(width 0)
			(type solid)
		)
		(fill yes)
		(layer "In6.Cu")
		(net "M_C_CPU1_SB_DQ<14>")
	)
	(gr_poly
		(pts
			(xy 91.618308 -235.579666) (xy 91.618308 -235.53547) (xy 91.262708 -235.53547) (xy 91.262708 -235.579666)
			(xy 91.309698 -235.732066) (xy 91.571318 -235.732066)
		)
		(stroke
			(width 0)
			(type solid)
		)
		(fill yes)
		(layer "In6.Cu")
		(net "M_C_CPU1_SB_DQ<13>")
	)
	(gr_poly
		(pts
			(xy 91.618308 -232.323894) (xy 91.618308 -232.279698) (xy 91.262708 -232.279698) (xy 91.262708 -232.323894)
			(xy 91.309698 -232.476294) (xy 91.571318 -232.476294)
		)
		(stroke
			(width 0)
			(type solid)
		)
		(fill yes)
		(layer "In6.Cu")
		(net "M_D_CPU1_SB_DQS_DN<7>")
	)
	(gr_poly
		(pts
			(xy 91.618308 -231.104694) (xy 91.571318 -230.952294) (xy 91.309698 -230.952294) (xy 91.262708 -231.104694)
			(xy 91.262708 -231.14889) (xy 91.618308 -231.14889)
		)
		(stroke
			(width 0)
			(type solid)
		)
		(fill yes)
		(layer "In6.Cu")
		(net "M_D_CPU1_SB_DQ<22>")
	)
	(gr_poly
		(pts
			(xy 91.618308 -230.696262) (xy 91.618308 -230.652066) (xy 91.262708 -230.652066) (xy 91.262708 -230.696262)
			(xy 91.309698 -230.848662) (xy 91.571318 -230.848662)
		)
		(stroke
			(width 0)
			(type solid)
		)
		(fill yes)
		(layer "In6.Cu")
		(net "M_D_CPU1_SB_DQ<21>")
	)
	(gr_poly
		(pts
			(xy 91.618308 -225.813366) (xy 91.618308 -225.768916) (xy 91.262708 -225.768916) (xy 91.262708 -225.813366)
			(xy 91.309698 -225.965766) (xy 91.571318 -225.965766)
		)
		(stroke
			(width 0)
			(type solid)
		)
		(fill yes)
		(layer "In6.Cu")
		(net "M_C_CPU1_SB_DQ<28>")
	)
	(gr_poly
		(pts
			(xy 91.620848 -244.126766) (xy 91.573858 -243.974366) (xy 91.312238 -243.974366) (xy 91.265248 -244.126766)
			(xy 91.265248 -244.171216) (xy 91.620848 -244.171216)
		)
		(stroke
			(width 0)
			(type solid)
		)
		(fill yes)
		(layer "In6.Cu")
		(net "M_C_CPU1_SB_DQ<2>")
	)
	(gr_poly
		(pts
			(xy 91.620848 -242.090702) (xy 91.620848 -242.046506) (xy 91.265248 -242.046506) (xy 91.265248 -242.090702)
			(xy 91.312238 -242.243102) (xy 91.573858 -242.243102)
		)
		(stroke
			(width 0)
			(type solid)
		)
		(fill yes)
		(layer "In6.Cu")
		(net "M_C_CPU1_SB_DQS_DN<5>")
	)
	(gr_poly
		(pts
			(xy 91.620848 -239.243362) (xy 91.573858 -239.090962) (xy 91.312238 -239.090962) (xy 91.265248 -239.243362)
			(xy 91.265248 -239.287812) (xy 91.620848 -239.287812)
		)
		(stroke
			(width 0)
			(type solid)
		)
		(fill yes)
		(layer "In6.Cu")
		(net "M_C_CPU1_SB_DQ<10>")
	)
	(gr_poly
		(pts
			(xy 91.620848 -234.360466) (xy 91.573858 -234.208066) (xy 91.312238 -234.208066) (xy 91.265248 -234.360466)
			(xy 91.265248 -234.404662) (xy 91.620848 -234.404662)
		)
		(stroke
			(width 0)
			(type solid)
		)
		(fill yes)
		(layer "In6.Cu")
		(net "M_D_CPU1_SB_DQ<18>")
	)
	(gr_poly
		(pts
			(xy 91.716352 -274.876514) (xy 91.716352 -274.832064) (xy 91.360752 -274.832064) (xy 91.360752 -274.876514)
			(xy 91.407742 -275.028914) (xy 91.669362 -275.028914)
		)
		(stroke
			(width 0)
			(type solid)
		)
		(fill yes)
		(layer "In6.Cu")
		(net "M_D_CPU1_SA_DQS_DN<5>")
	)
	(gr_poly
		(pts
			(xy 91.716352 -269.99311) (xy 91.716352 -269.948914) (xy 91.360752 -269.948914) (xy 91.360752 -269.99311)
			(xy 91.407742 -270.14551) (xy 91.669362 -270.14551)
		)
		(stroke
			(width 0)
			(type solid)
		)
		(fill yes)
		(layer "In6.Cu")
		(net "M_C_CPU1_SA_DQS_DN<6>")
	)
	(gr_poly
		(pts
			(xy 91.716352 -265.109706) (xy 91.716352 -265.06551) (xy 91.360752 -265.06551) (xy 91.360752 -265.109706)
			(xy 91.407742 -265.262106) (xy 91.669362 -265.262106)
		)
		(stroke
			(width 0)
			(type solid)
		)
		(fill yes)
		(layer "In6.Cu")
		(net "M_C_CPU1_SA_DQS_DN<8>")
	)
	(gr_poly
		(pts
			(xy 91.716352 -260.226302) (xy 91.716352 -260.182106) (xy 91.360752 -260.182106) (xy 91.360752 -260.226302)
			(xy 91.407742 -260.378702) (xy 91.669362 -260.378702)
		)
		(stroke
			(width 0)
			(type solid)
		)
		(fill yes)
		(layer "In6.Cu")
		(net "M_C_CPU1_SA_DQS_DP<4>")
	)
	(gr_poly
		(pts
			(xy 91.716352 -255.343406) (xy 91.716352 -255.298956) (xy 91.360752 -255.298956) (xy 91.360752 -255.343406)
			(xy 91.407742 -255.495806) (xy 91.669362 -255.495806)
		)
		(stroke
			(width 0)
			(type solid)
		)
		(fill yes)
		(layer "In6.Cu")
		(net "M_C_CPU1_SA_RSP<0>")
	)
	(gr_poly
		(pts
			(xy 91.718892 -263.482074) (xy 91.718892 -263.437624) (xy 91.363292 -263.437624) (xy 91.363292 -263.482074)
			(xy 91.410282 -263.634474) (xy 91.671902 -263.634474)
		)
		(stroke
			(width 0)
			(type solid)
		)
		(fill yes)
		(layer "In6.Cu")
		(net "M_C_CPU1_SA_DQ<29>")
	)
	(gr_poly
		(pts
			(xy 91.722448 -273.657314) (xy 91.675458 -273.504914) (xy 91.413838 -273.504914) (xy 91.366848 -273.657314)
			(xy 91.366848 -273.701764) (xy 91.722448 -273.701764)
		)
		(stroke
			(width 0)
			(type solid)
		)
		(fill yes)
		(layer "In6.Cu")
		(net "M_D_CPU1_SA_DQ<6>")
	)
	(gr_poly
		(pts
			(xy 91.722448 -268.77391) (xy 91.675458 -268.62151) (xy 91.413838 -268.62151) (xy 91.366848 -268.77391)
			(xy 91.366848 -268.81836) (xy 91.722448 -268.81836)
		)
		(stroke
			(width 0)
			(type solid)
		)
		(fill yes)
		(layer "In6.Cu")
		(net "M_C_CPU1_SA_DQ<14>")
	)
	(gr_poly
		(pts
			(xy 91.722448 -263.891014) (xy 91.675458 -263.738614) (xy 91.413838 -263.738614) (xy 91.366848 -263.891014)
			(xy 91.366848 -263.93521) (xy 91.722448 -263.93521)
		)
		(stroke
			(width 0)
			(type solid)
		)
		(fill yes)
		(layer "In6.Cu")
		(net "M_C_CPU1_SA_DQ<30>")
	)
	(gr_poly
		(pts
			(xy 91.722448 -259.00761) (xy 91.675458 -258.85521) (xy 91.413838 -258.85521) (xy 91.366848 -259.00761)
			(xy 91.366848 -259.051806) (xy 91.722448 -259.051806)
		)
		(stroke
			(width 0)
			(type solid)
		)
		(fill yes)
		(layer "In6.Cu")
		(net "M_C_CPU1_SA_CB<4>")
	)
	(gr_poly
		(pts
			(xy 91.722448 -254.124206) (xy 91.675458 -253.971806) (xy 91.413838 -253.971806) (xy 91.366848 -254.124206)
			(xy 91.366848 -254.168402) (xy 91.722448 -254.168402)
		)
		(stroke
			(width 0)
			(type solid)
		)
		(fill yes)
		(layer "In6.Cu")
		(net "M_C_CPU1_SB_RSP<1>")
	)
	(gr_poly
		(pts
			(xy 91.72829 -276.912578) (xy 91.6813 -276.760178) (xy 91.41968 -276.760178) (xy 91.37269 -276.912578)
			(xy 91.37269 -276.957028) (xy 91.72829 -276.957028)
		)
		(stroke
			(width 0)
			(type solid)
		)
		(fill yes)
		(layer "In6.Cu")
		(net "M_D_CPU1_SA_DQ<2>")
	)
	(gr_poly
		(pts
			(xy 91.72829 -276.5044) (xy 91.72829 -276.460204) (xy 91.37269 -276.460204) (xy 91.37269 -276.5044)
			(xy 91.41968 -276.6568) (xy 91.6813 -276.6568)
		)
		(stroke
			(width 0)
			(type solid)
		)
		(fill yes)
		(layer "In6.Cu")
		(net "M_D_CPU1_SA_DQ<1>")
	)
	(gr_poly
		(pts
			(xy 91.72829 -275.284946) (xy 91.6813 -275.132546) (xy 91.41968 -275.132546) (xy 91.37269 -275.284946)
			(xy 91.37269 -275.329396) (xy 91.72829 -275.329396)
		)
		(stroke
			(width 0)
			(type solid)
		)
		(fill yes)
		(layer "In6.Cu")
		(net "M_D_CPU1_SA_DQS_DN<0>")
	)
	(gr_poly
		(pts
			(xy 91.72829 -272.029174) (xy 91.6813 -271.876774) (xy 91.41968 -271.876774) (xy 91.37269 -272.029174)
			(xy 91.37269 -272.073624) (xy 91.72829 -272.073624)
		)
		(stroke
			(width 0)
			(type solid)
		)
		(fill yes)
		(layer "In6.Cu")
		(net "M_C_CPU1_SA_DQ<10>")
	)
	(gr_poly
		(pts
			(xy 91.72829 -271.62125) (xy 91.72829 -271.5768) (xy 91.37269 -271.5768) (xy 91.37269 -271.62125)
			(xy 91.41968 -271.77365) (xy 91.6813 -271.77365)
		)
		(stroke
			(width 0)
			(type solid)
		)
		(fill yes)
		(layer "In6.Cu")
		(net "M_C_CPU1_SA_DQ<9>")
	)
	(gr_poly
		(pts
			(xy 91.72829 -270.40205) (xy 91.6813 -270.24965) (xy 91.41968 -270.24965) (xy 91.37269 -270.40205)
			(xy 91.37269 -270.446246) (xy 91.72829 -270.446246)
		)
		(stroke
			(width 0)
			(type solid)
		)
		(fill yes)
		(layer "In6.Cu")
		(net "M_C_CPU1_SA_DQS_DN<1>")
	)
	(gr_poly
		(pts
			(xy 91.72829 -267.14577) (xy 91.6813 -266.99337) (xy 91.41968 -266.99337) (xy 91.37269 -267.14577)
			(xy 91.37269 -267.19022) (xy 91.72829 -267.19022)
		)
		(stroke
			(width 0)
			(type solid)
		)
		(fill yes)
		(layer "In6.Cu")
		(net "M_C_CPU1_SA_DQ<26>")
	)
	(gr_poly
		(pts
			(xy 91.72829 -266.737846) (xy 91.72829 -266.69365) (xy 91.37269 -266.69365) (xy 91.37269 -266.737846)
			(xy 91.41968 -266.890246) (xy 91.6813 -266.890246)
		)
		(stroke
			(width 0)
			(type solid)
		)
		(fill yes)
		(layer "In6.Cu")
		(net "M_C_CPU1_SA_DQ<25>")
	)
	(gr_poly
		(pts
			(xy 91.72829 -265.518646) (xy 91.6813 -265.366246) (xy 91.41968 -265.366246) (xy 91.37269 -265.518646)
			(xy 91.37269 -265.562842) (xy 91.72829 -265.562842)
		)
		(stroke
			(width 0)
			(type solid)
		)
		(fill yes)
		(layer "In6.Cu")
		(net "M_C_CPU1_SA_DQS_DN<3>")
	)
	(gr_poly
		(pts
			(xy 91.72829 -262.262874) (xy 91.6813 -262.110474) (xy 91.41968 -262.110474) (xy 91.37269 -262.262874)
			(xy 91.37269 -262.30707) (xy 91.72829 -262.30707)
		)
		(stroke
			(width 0)
			(type solid)
		)
		(fill yes)
		(layer "In6.Cu")
		(net "M_C_CPU1_SA_CB<0>")
	)
	(gr_poly
		(pts
			(xy 91.72829 -261.854442) (xy 91.72829 -261.810246) (xy 91.37269 -261.810246) (xy 91.37269 -261.854442)
			(xy 91.41968 -262.006842) (xy 91.6813 -262.006842)
		)
		(stroke
			(width 0)
			(type solid)
		)
		(fill yes)
		(layer "In6.Cu")
		(net "M_C_CPU1_SA_CB<3>")
	)
	(gr_poly
		(pts
			(xy 91.72829 -260.635242) (xy 91.6813 -260.482842) (xy 91.41968 -260.482842) (xy 91.37269 -260.635242)
			(xy 91.37269 -260.679438) (xy 91.72829 -260.679438)
		)
		(stroke
			(width 0)
			(type solid)
		)
		(fill yes)
		(layer "In6.Cu")
		(net "M_C_CPU1_SA_DQS_DP<9>")
	)
	(gr_poly
		(pts
			(xy 91.72829 -256.971038) (xy 91.72829 -256.926842) (xy 91.37269 -256.926842) (xy 91.37269 -256.971038)
			(xy 91.41968 -257.123438) (xy 91.6813 -257.123438)
		)
		(stroke
			(width 0)
			(type solid)
		)
		(fill yes)
		(layer "In6.Cu")
		(net "M_D_CPU1_SA_RSP<0>")
	)
	(gr_poly
		(pts
			(xy 91.72829 -255.751838) (xy 91.6813 -255.599438) (xy 91.41968 -255.599438) (xy 91.37269 -255.751838)
			(xy 91.37269 -255.796288) (xy 91.72829 -255.796288)
		)
		(stroke
			(width 0)
			(type solid)
		)
		(fill yes)
		(layer "In6.Cu")
		(net "M_D_CPU1_SB_RSP<1>")
	)
	(gr_poly
		(pts
			(xy 91.73083 -273.248882) (xy 91.73083 -273.204686) (xy 91.37523 -273.204686) (xy 91.37523 -273.248882)
			(xy 91.42222 -273.401282) (xy 91.68384 -273.401282)
		)
		(stroke
			(width 0)
			(type solid)
		)
		(fill yes)
		(layer "In6.Cu")
		(net "M_D_CPU1_SA_DQ<5>")
	)
	(gr_poly
		(pts
			(xy 91.73083 -268.365478) (xy 91.73083 -268.321282) (xy 91.37523 -268.321282) (xy 91.37523 -268.365478)
			(xy 91.42222 -268.517878) (xy 91.68384 -268.517878)
		)
		(stroke
			(width 0)
			(type solid)
		)
		(fill yes)
		(layer "In6.Cu")
		(net "M_C_CPU1_SA_DQ<13>")
	)
	(gr_poly
		(pts
			(xy 91.73083 -258.599178) (xy 91.73083 -258.554728) (xy 91.37523 -258.554728) (xy 91.37523 -258.599178)
			(xy 91.42222 -258.751578) (xy 91.68384 -258.751578)
		)
		(stroke
			(width 0)
			(type solid)
		)
		(fill yes)
		(layer "In6.Cu")
		(net "M_C_CPU1_SA_CB<7>")
	)
	(gr_poly
		(pts
			(xy 91.933522 -228.914706) (xy 91.971876 -228.892608) (xy 91.794076 -228.58476) (xy 91.755722 -228.606858)
			(xy 91.647264 -228.723698) (xy 91.778074 -228.950266)
		)
		(stroke
			(width 0)
			(type solid)
		)
		(fill yes)
		(layer "In6.Cu")
		(net "M_C_CPU1_SB_DQ<25>")
	)
	(gr_poly
		(pts
			(xy 92.047822 -228.302058) (xy 92.15628 -228.185218) (xy 92.02547 -227.95865) (xy 91.870022 -227.99421)
			(xy 91.831668 -228.016308) (xy 92.009468 -228.324156)
		)
		(stroke
			(width 0)
			(type solid)
		)
		(fill yes)
		(layer "In6.Cu")
		(net "M_C_CPU1_SB_DQ<27>")
	)
	(gr_poly
		(pts
			(xy 92.07373 -246.16029) (xy 92.07373 -246.116094) (xy 91.71813 -246.116094) (xy 91.71813 -246.16029)
			(xy 91.76512 -246.31269) (xy 92.02674 -246.31269)
		)
		(stroke
			(width 0)
			(type solid)
		)
		(fill yes)
		(layer "In6.Cu")
		(net "M_D_CPU1_SB_CS_N<2>")
	)
	(gr_poly
		(pts
			(xy 92.07373 -241.685318) (xy 92.02674 -241.532918) (xy 91.76512 -241.532918) (xy 91.71813 -241.685318)
			(xy 91.71813 -241.729514) (xy 92.07373 -241.729514)
		)
		(stroke
			(width 0)
			(type solid)
		)
		(fill yes)
		(layer "In6.Cu")
		(net "M_C_CPU1_SB_DQS_DP<5>")
	)
	(gr_poly
		(pts
			(xy 92.07373 -241.276886) (xy 92.07373 -241.23269) (xy 91.71813 -241.23269) (xy 91.71813 -241.276886)
			(xy 91.76512 -241.429286) (xy 92.02674 -241.429286)
		)
		(stroke
			(width 0)
			(type solid)
		)
		(fill yes)
		(layer "In6.Cu")
		(net "M_C_CPU1_SB_DQ<4>")
	)
	(gr_poly
		(pts
			(xy 92.07373 -240.057178) (xy 92.02674 -239.904778) (xy 91.76512 -239.904778) (xy 91.71813 -240.057178)
			(xy 91.71813 -240.101628) (xy 92.07373 -240.101628)
		)
		(stroke
			(width 0)
			(type solid)
		)
		(fill yes)
		(layer "In6.Cu")
		(net "M_C_CPU1_SB_DQ<7>")
	)
	(gr_poly
		(pts
			(xy 92.07373 -239.649254) (xy 92.07373 -239.604804) (xy 91.71813 -239.604804) (xy 91.71813 -239.649254)
			(xy 91.76512 -239.801654) (xy 92.02674 -239.801654)
		)
		(stroke
			(width 0)
			(type solid)
		)
		(fill yes)
		(layer "In6.Cu")
		(net "M_C_CPU1_SB_DQ<8>")
	)
	(gr_poly
		(pts
			(xy 92.07373 -236.39399) (xy 92.07373 -236.34954) (xy 91.71813 -236.34954) (xy 91.71813 -236.39399)
			(xy 91.76512 -236.54639) (xy 92.02674 -236.54639)
		)
		(stroke
			(width 0)
			(type solid)
		)
		(fill yes)
		(layer "In6.Cu")
		(net "M_C_CPU1_SB_DQ<12>")
	)
	(gr_poly
		(pts
			(xy 92.07373 -235.174282) (xy 92.02674 -235.021882) (xy 91.76512 -235.021882) (xy 91.71813 -235.174282)
			(xy 91.71813 -235.218478) (xy 92.07373 -235.218478)
		)
		(stroke
			(width 0)
			(type solid)
		)
		(fill yes)
		(layer "In6.Cu")
		(net "M_C_CPU1_SB_DQ<15>")
	)
	(gr_poly
		(pts
			(xy 92.07373 -234.76585) (xy 92.07373 -234.721654) (xy 91.71813 -234.721654) (xy 91.71813 -234.76585)
			(xy 91.76512 -234.91825) (xy 92.02674 -234.91825)
		)
		(stroke
			(width 0)
			(type solid)
		)
		(fill yes)
		(layer "In6.Cu")
		(net "M_D_CPU1_SB_DQ<16>")
	)
	(gr_poly
		(pts
			(xy 92.07373 -231.510586) (xy 92.07373 -231.466136) (xy 91.71813 -231.466136) (xy 91.71813 -231.510586)
			(xy 91.76512 -231.662986) (xy 92.02674 -231.662986)
		)
		(stroke
			(width 0)
			(type solid)
		)
		(fill yes)
		(layer "In6.Cu")
		(net "M_D_CPU1_SB_DQ<20>")
	)
	(gr_poly
		(pts
			(xy 92.07373 -230.290878) (xy 92.02674 -230.138478) (xy 91.76512 -230.138478) (xy 91.71813 -230.290878)
			(xy 91.71813 -230.335074) (xy 92.07373 -230.335074)
		)
		(stroke
			(width 0)
			(type solid)
		)
		(fill yes)
		(layer "In6.Cu")
		(net "M_D_CPU1_SB_DQ<23>")
	)
	(gr_poly
		(pts
			(xy 92.07373 -229.882446) (xy 92.07373 -229.83825) (xy 91.71813 -229.83825) (xy 91.71813 -229.882446)
			(xy 91.76512 -230.034846) (xy 92.02674 -230.034846)
		)
		(stroke
			(width 0)
			(type solid)
		)
		(fill yes)
		(layer "In6.Cu")
		(net "M_C_CPU1_SB_DQ<26>")
	)
	(gr_poly
		(pts
			(xy 92.07373 -225.407474) (xy 92.02674 -225.255074) (xy 91.76512 -225.255074) (xy 91.71813 -225.407474)
			(xy 91.71813 -225.45167) (xy 92.07373 -225.45167)
		)
		(stroke
			(width 0)
			(type solid)
		)
		(fill yes)
		(layer "In6.Cu")
		(net "M_C_CPU1_SB_DQ<30>")
	)
	(gr_poly
		(pts
			(xy 92.07627 -248.196354) (xy 92.02928 -248.043954) (xy 91.76766 -248.043954) (xy 91.72067 -248.196354)
			(xy 91.72067 -248.240804) (xy 92.07627 -248.240804)
		)
		(stroke
			(width 0)
			(type solid)
		)
		(fill yes)
		(layer "In6.Cu")
		(net "M_A_CPU1_SA_RSP<0>")
	)
	(gr_poly
		(pts
			(xy 92.07627 -244.940582) (xy 92.02928 -244.788182) (xy 91.76766 -244.788182) (xy 91.72067 -244.940582)
			(xy 91.72067 -244.985032) (xy 92.07627 -244.985032)
		)
		(stroke
			(width 0)
			(type solid)
		)
		(fill yes)
		(layer "In6.Cu")
		(net "M_D_CPU1_SB_CS_N<1>")
	)
	(gr_poly
		(pts
			(xy 92.07627 -244.532658) (xy 92.07627 -244.488208) (xy 91.72067 -244.488208) (xy 91.72067 -244.532658)
			(xy 91.76766 -244.685058) (xy 92.02928 -244.685058)
		)
		(stroke
			(width 0)
			(type solid)
		)
		(fill yes)
		(layer "In6.Cu")
		(net "M_C_CPU1_SB_DQ<0>")
	)
	(gr_poly
		(pts
			(xy 92.07627 -238.430054) (xy 92.02928 -238.277654) (xy 91.76766 -238.277654) (xy 91.72067 -238.430054)
			(xy 91.72067 -238.47425) (xy 92.07627 -238.47425)
		)
		(stroke
			(width 0)
			(type solid)
		)
		(fill yes)
		(layer "In6.Cu")
		(net "M_C_CPU1_SB_DQ<11>")
	)
	(gr_poly
		(pts
			(xy 92.07627 -233.54665) (xy 92.02928 -233.39425) (xy 91.76766 -233.39425) (xy 91.72067 -233.54665)
			(xy 91.72067 -233.590846) (xy 92.07627 -233.590846)
		)
		(stroke
			(width 0)
			(type solid)
		)
		(fill yes)
		(layer "In6.Cu")
		(net "M_D_CPU1_SB_DQ<19>")
	)
	(gr_poly
		(pts
			(xy 92.082112 -236.801914) (xy 92.035122 -236.649514) (xy 91.773502 -236.649514) (xy 91.726512 -236.801914)
			(xy 91.726512 -236.846364) (xy 92.082112 -236.846364)
		)
		(stroke
			(width 0)
			(type solid)
		)
		(fill yes)
		(layer "In6.Cu")
		(net "M_C_CPU1_SB_DQS_DP<6>")
	)
	(gr_poly
		(pts
			(xy 92.082112 -231.919018) (xy 92.035122 -231.766618) (xy 91.773502 -231.766618) (xy 91.726512 -231.919018)
			(xy 91.726512 -231.963214) (xy 92.082112 -231.963214)
		)
		(stroke
			(width 0)
			(type solid)
		)
		(fill yes)
		(layer "In6.Cu")
		(net "M_D_CPU1_SB_DQS_DP<7>")
	)
	(gr_poly
		(pts
			(xy 92.082366 -226.626674) (xy 92.082366 -226.582478) (xy 91.726766 -226.582478) (xy 91.726766 -226.626674)
			(xy 91.773756 -226.779074) (xy 92.035376 -226.779074)
		)
		(stroke
			(width 0)
			(type solid)
		)
		(fill yes)
		(layer "In6.Cu")
		(net "M_C_CPU1_SB_DQS_DN<8>")
	)
	(gr_poly
		(pts
			(xy 92.085668 -243.313458) (xy 92.038678 -243.161058) (xy 91.777058 -243.161058) (xy 91.730068 -243.313458)
			(xy 91.730068 -243.357654) (xy 92.085668 -243.357654)
		)
		(stroke
			(width 0)
			(type solid)
		)
		(fill yes)
		(layer "In6.Cu")
		(net "M_C_CPU1_SB_DQ<3>")
	)
	(gr_poly
		(pts
			(xy 92.088208 -247.787922) (xy 92.088208 -247.743472) (xy 91.732608 -247.743472) (xy 91.732608 -247.787922)
			(xy 91.779598 -247.940322) (xy 92.041218 -247.940322)
		)
		(stroke
			(width 0)
			(type solid)
		)
		(fill yes)
		(layer "In6.Cu")
		(net "M_A_CPU1_SA_RSP<1>")
	)
	(gr_poly
		(pts
			(xy 92.088208 -242.904518) (xy 92.088208 -242.860322) (xy 91.732608 -242.860322) (xy 91.732608 -242.904518)
			(xy 91.779598 -243.056918) (xy 92.041218 -243.056918)
		)
		(stroke
			(width 0)
			(type solid)
		)
		(fill yes)
		(layer "In6.Cu")
		(net "M_C_CPU1_SB_DQS_DP<0>")
	)
	(gr_poly
		(pts
			(xy 92.088208 -238.021114) (xy 92.088208 -237.976918) (xy 91.732608 -237.976918) (xy 91.732608 -238.021114)
			(xy 91.779598 -238.173514) (xy 92.041218 -238.173514)
		)
		(stroke
			(width 0)
			(type solid)
		)
		(fill yes)
		(layer "In6.Cu")
		(net "M_C_CPU1_SB_DQS_DP<1>")
	)
	(gr_poly
		(pts
			(xy 92.088208 -233.13771) (xy 92.088208 -233.093514) (xy 91.732608 -233.093514) (xy 91.732608 -233.13771)
			(xy 91.779598 -233.29011) (xy 92.041218 -233.29011)
		)
		(stroke
			(width 0)
			(type solid)
		)
		(fill yes)
		(layer "In6.Cu")
		(net "M_D_CPU1_SB_DQS_DP<2>")
	)
	(gr_poly
		(pts
			(xy 92.090748 -227.035106) (xy 92.043758 -226.882706) (xy 91.782138 -226.882706) (xy 91.735148 -227.035106)
			(xy 91.735148 -227.079556) (xy 92.090748 -227.079556)
		)
		(stroke
			(width 0)
			(type solid)
		)
		(fill yes)
		(layer "In6.Cu")
		(net "M_C_CPU1_SB_DQS_DN<3>")
	)
	(gr_poly
		(pts
			(xy 92.183712 -277.318216) (xy 92.183712 -277.27402) (xy 91.828112 -277.27402) (xy 91.828112 -277.318216)
			(xy 91.875102 -277.470616) (xy 92.136722 -277.470616)
		)
		(stroke
			(width 0)
			(type solid)
		)
		(fill yes)
		(layer "In6.Cu")
		(net "M_D_CPU1_SA_DQ<0>")
	)
	(gr_poly
		(pts
			(xy 92.183712 -276.098762) (xy 92.136722 -275.946362) (xy 91.875102 -275.946362) (xy 91.828112 -276.098762)
			(xy 91.828112 -276.143212) (xy 92.183712 -276.143212)
		)
		(stroke
			(width 0)
			(type solid)
		)
		(fill yes)
		(layer "In6.Cu")
		(net "M_D_CPU1_SA_DQ<3>")
	)
	(gr_poly
		(pts
			(xy 92.183712 -272.843498) (xy 92.136722 -272.691098) (xy 91.875102 -272.691098) (xy 91.828112 -272.843498)
			(xy 91.828112 -272.887694) (xy 92.183712 -272.887694)
		)
		(stroke
			(width 0)
			(type solid)
		)
		(fill yes)
		(layer "In6.Cu")
		(net "M_D_CPU1_SA_DQ<7>")
	)
	(gr_poly
		(pts
			(xy 92.183712 -272.435066) (xy 92.183712 -272.39087) (xy 91.828112 -272.39087) (xy 91.828112 -272.435066)
			(xy 91.875102 -272.587466) (xy 92.136722 -272.587466)
		)
		(stroke
			(width 0)
			(type solid)
		)
		(fill yes)
		(layer "In6.Cu")
		(net "M_C_CPU1_SA_DQ<8>")
	)
	(gr_poly
		(pts
			(xy 92.183712 -271.215358) (xy 92.136722 -271.062958) (xy 91.875102 -271.062958) (xy 91.828112 -271.215358)
			(xy 91.828112 -271.259808) (xy 92.183712 -271.259808)
		)
		(stroke
			(width 0)
			(type solid)
		)
		(fill yes)
		(layer "In6.Cu")
		(net "M_C_CPU1_SA_DQ<11>")
	)
	(gr_poly
		(pts
			(xy 92.183712 -267.960094) (xy 92.136722 -267.807694) (xy 91.875102 -267.807694) (xy 91.828112 -267.960094)
			(xy 91.828112 -268.00429) (xy 92.183712 -268.00429)
		)
		(stroke
			(width 0)
			(type solid)
		)
		(fill yes)
		(layer "In6.Cu")
		(net "M_C_CPU1_SA_DQ<15>")
	)
	(gr_poly
		(pts
			(xy 92.183712 -267.551662) (xy 92.183712 -267.507466) (xy 91.828112 -267.507466) (xy 91.828112 -267.551662)
			(xy 91.875102 -267.704062) (xy 92.136722 -267.704062)
		)
		(stroke
			(width 0)
			(type solid)
		)
		(fill yes)
		(layer "In6.Cu")
		(net "M_C_CPU1_SA_DQ<24>")
	)
	(gr_poly
		(pts
			(xy 92.183712 -266.331954) (xy 92.136722 -266.179554) (xy 91.875102 -266.179554) (xy 91.828112 -266.331954)
			(xy 91.828112 -266.376404) (xy 92.183712 -266.376404)
		)
		(stroke
			(width 0)
			(type solid)
		)
		(fill yes)
		(layer "In6.Cu")
		(net "M_C_CPU1_SA_DQ<27>")
	)
	(gr_poly
		(pts
			(xy 92.183712 -262.668258) (xy 92.183712 -262.624062) (xy 91.828112 -262.624062) (xy 91.828112 -262.668258)
			(xy 91.875102 -262.820658) (xy 92.136722 -262.820658)
		)
		(stroke
			(width 0)
			(type solid)
		)
		(fill yes)
		(layer "In6.Cu")
		(net "M_C_CPU1_SA_CB<2>")
	)
	(gr_poly
		(pts
			(xy 92.183712 -261.449058) (xy 92.136722 -261.296658) (xy 91.875102 -261.296658) (xy 91.828112 -261.449058)
			(xy 91.828112 -261.493254) (xy 92.183712 -261.493254)
		)
		(stroke
			(width 0)
			(type solid)
		)
		(fill yes)
		(layer "In6.Cu")
		(net "M_C_CPU1_SA_CB<1>")
	)
	(gr_poly
		(pts
			(xy 92.183712 -256.565654) (xy 92.136722 -256.413254) (xy 91.875102 -256.413254) (xy 91.828112 -256.565654)
			(xy 91.828112 -256.60985) (xy 92.183712 -256.60985)
		)
		(stroke
			(width 0)
			(type solid)
		)
		(fill yes)
		(layer "In6.Cu")
		(net "M_D_CPU1_SB_RSP<0>")
	)
	(gr_poly
		(pts
			(xy 92.186252 -274.062698) (xy 92.186252 -274.018248) (xy 91.830652 -274.018248) (xy 91.830652 -274.062698)
			(xy 91.877642 -274.215098) (xy 92.139262 -274.215098)
		)
		(stroke
			(width 0)
			(type solid)
		)
		(fill yes)
		(layer "In6.Cu")
		(net "M_D_CPU1_SA_DQ<4>")
	)
	(gr_poly
		(pts
			(xy 92.186252 -269.179294) (xy 92.186252 -269.134844) (xy 91.830652 -269.134844) (xy 91.830652 -269.179294)
			(xy 91.877642 -269.331694) (xy 92.139262 -269.331694)
		)
		(stroke
			(width 0)
			(type solid)
		)
		(fill yes)
		(layer "In6.Cu")
		(net "M_C_CPU1_SA_DQ<12>")
	)
	(gr_poly
		(pts
			(xy 92.186252 -264.29589) (xy 92.186252 -264.251694) (xy 91.830652 -264.251694) (xy 91.830652 -264.29589)
			(xy 91.877642 -264.44829) (xy 92.139262 -264.44829)
		)
		(stroke
			(width 0)
			(type solid)
		)
		(fill yes)
		(layer "In6.Cu")
		(net "M_C_CPU1_SA_DQ<28>")
	)
	(gr_poly
		(pts
			(xy 92.186252 -259.412486) (xy 92.186252 -259.36829) (xy 91.830652 -259.36829) (xy 91.830652 -259.412486)
			(xy 91.877642 -259.564886) (xy 92.139262 -259.564886)
		)
		(stroke
			(width 0)
			(type solid)
		)
		(fill yes)
		(layer "In6.Cu")
		(net "M_C_CPU1_SA_CB<6>")
	)
	(gr_poly
		(pts
			(xy 92.186252 -258.193286) (xy 92.139262 -258.040886) (xy 91.877642 -258.040886) (xy 91.830652 -258.193286)
			(xy 91.830652 -258.237482) (xy 92.186252 -258.237482)
		)
		(stroke
			(width 0)
			(type solid)
		)
		(fill yes)
		(layer "In6.Cu")
		(net "M_C_CPU1_SA_CB<5>")
	)
	(gr_poly
		(pts
			(xy 92.186252 -254.529082) (xy 92.186252 -254.484886) (xy 91.830652 -254.484886) (xy 91.830652 -254.529082)
			(xy 91.877642 -254.681482) (xy 92.139262 -254.681482)
		)
		(stroke
			(width 0)
			(type solid)
		)
		(fill yes)
		(layer "In6.Cu")
		(net "M_C_CPU1_SA_RSP<1>")
	)
	(gr_poly
		(pts
			(xy 92.192094 -275.69033) (xy 92.192094 -275.64588) (xy 91.836494 -275.64588) (xy 91.836494 -275.69033)
			(xy 91.883484 -275.84273) (xy 92.145104 -275.84273)
		)
		(stroke
			(width 0)
			(type solid)
		)
		(fill yes)
		(layer "In6.Cu")
		(net "M_D_CPU1_SA_DQS_DP<0>")
	)
	(gr_poly
		(pts
			(xy 92.192094 -270.806926) (xy 92.192094 -270.76273) (xy 91.836494 -270.76273) (xy 91.836494 -270.806926)
			(xy 91.883484 -270.959326) (xy 92.145104 -270.959326)
		)
		(stroke
			(width 0)
			(type solid)
		)
		(fill yes)
		(layer "In6.Cu")
		(net "M_C_CPU1_SA_DQS_DP<1>")
	)
	(gr_poly
		(pts
			(xy 92.192094 -265.923522) (xy 92.192094 -265.879326) (xy 91.836494 -265.879326) (xy 91.836494 -265.923522)
			(xy 91.883484 -266.075922) (xy 92.145104 -266.075922)
		)
		(stroke
			(width 0)
			(type solid)
		)
		(fill yes)
		(layer "In6.Cu")
		(net "M_C_CPU1_SA_DQS_DP<3>")
	)
	(gr_poly
		(pts
			(xy 92.192094 -261.040626) (xy 92.192094 -260.996176) (xy 91.836494 -260.996176) (xy 91.836494 -261.040626)
			(xy 91.883484 -261.193026) (xy 92.145104 -261.193026)
		)
		(stroke
			(width 0)
			(type solid)
		)
		(fill yes)
		(layer "In6.Cu")
		(net "M_C_CPU1_SA_DQS_DN<9>")
	)
	(gr_poly
		(pts
			(xy 92.192094 -256.157222) (xy 92.192094 -256.112772) (xy 91.836494 -256.112772) (xy 91.836494 -256.157222)
			(xy 91.883484 -256.309622) (xy 92.145104 -256.309622)
		)
		(stroke
			(width 0)
			(type solid)
		)
		(fill yes)
		(layer "In6.Cu")
		(net "M_D_CPU1_SA_RSP<1>")
	)
	(gr_poly
		(pts
			(xy 92.19565 -263.077198) (xy 92.14866 -262.924798) (xy 91.88704 -262.924798) (xy 91.84005 -263.077198)
			(xy 91.84005 -263.121394) (xy 92.19565 -263.121394)
		)
		(stroke
			(width 0)
			(type solid)
		)
		(fill yes)
		(layer "In6.Cu")
		(net "M_C_CPU1_SA_DQ<31>")
	)
	(gr_poly
		(pts
			(xy 92.19819 -274.47113) (xy 92.1512 -274.31873) (xy 91.88958 -274.31873) (xy 91.84259 -274.47113)
			(xy 91.84259 -274.51558) (xy 92.19819 -274.51558)
		)
		(stroke
			(width 0)
			(type solid)
		)
		(fill yes)
		(layer "In6.Cu")
		(net "M_D_CPU1_SA_DQS_DP<5>")
	)
	(gr_poly
		(pts
			(xy 92.19819 -269.587726) (xy 92.1512 -269.435326) (xy 91.88958 -269.435326) (xy 91.84259 -269.587726)
			(xy 91.84259 -269.632176) (xy 92.19819 -269.632176)
		)
		(stroke
			(width 0)
			(type solid)
		)
		(fill yes)
		(layer "In6.Cu")
		(net "M_C_CPU1_SA_DQS_DP<6>")
	)
	(gr_poly
		(pts
			(xy 92.19819 -264.70483) (xy 92.1512 -264.55243) (xy 91.88958 -264.55243) (xy 91.84259 -264.70483)
			(xy 91.84259 -264.749026) (xy 92.19819 -264.749026)
		)
		(stroke
			(width 0)
			(type solid)
		)
		(fill yes)
		(layer "In6.Cu")
		(net "M_C_CPU1_SA_DQS_DP<8>")
	)
	(gr_poly
		(pts
			(xy 92.19819 -259.821426) (xy 92.1512 -259.669026) (xy 91.88958 -259.669026) (xy 91.84259 -259.821426)
			(xy 91.84259 -259.865622) (xy 92.19819 -259.865622)
		)
		(stroke
			(width 0)
			(type solid)
		)
		(fill yes)
		(layer "In6.Cu")
		(net "M_C_CPU1_SA_DQS_DN<4>")
	)
	(gr_poly
		(pts
			(xy 92.19819 -254.938022) (xy 92.1512 -254.785622) (xy 91.88958 -254.785622) (xy 91.84259 -254.938022)
			(xy 91.84259 -254.982218) (xy 92.19819 -254.982218)
		)
		(stroke
			(width 0)
			(type solid)
		)
		(fill yes)
		(layer "In6.Cu")
		(net "M_C_CPU1_SB_RSP<0>")
	)
	(gr_poly
		(pts
			(xy 92.408756 -228.10978) (xy 92.44711 -228.087682) (xy 92.26931 -227.779834) (xy 92.230956 -227.801932)
			(xy 92.122498 -227.918772) (xy 92.253308 -228.14534)
		)
		(stroke
			(width 0)
			(type solid)
		)
		(fill yes)
		(layer "In6.Cu")
		(net "M_C_CPU1_SB_DQS_DP<3>")
	)
	(gr_poly
		(pts
			(xy 92.446094 -223.948752) (xy 92.40774 -223.926654) (xy 92.252292 -223.891094) (xy 92.121482 -224.117662)
			(xy 92.22994 -224.234502) (xy 92.268294 -224.2566)
		)
		(stroke
			(width 0)
			(type solid)
		)
		(fill yes)
		(layer "In6.Cu")
		(net "M_C_CPU1_SB_DQ<29>")
	)
	(gr_poly
		(pts
			(xy 92.523056 -227.497386) (xy 92.631514 -227.380546) (xy 92.500704 -227.153978) (xy 92.345256 -227.189538)
			(xy 92.306902 -227.211636) (xy 92.484702 -227.519484)
		)
		(stroke
			(width 0)
			(type solid)
		)
		(fill yes)
		(layer "In6.Cu")
		(net "M_C_CPU1_SB_DQS_DN<3>")
	)
	(gr_poly
		(pts
			(xy 92.545916 -237.616238) (xy 92.498926 -237.463838) (xy 92.237306 -237.463838) (xy 92.190316 -237.616238)
			(xy 92.190316 -237.660434) (xy 92.545916 -237.660434)
		)
		(stroke
			(width 0)
			(type solid)
		)
		(fill yes)
		(layer "In6.Cu")
		(net "M_C_CPU1_SB_DQS_DN<1>")
	)
	(gr_poly
		(pts
			(xy 92.54617 -245.346474) (xy 92.54617 -245.302024) (xy 92.19057 -245.302024) (xy 92.19057 -245.346474)
			(xy 92.23756 -245.498874) (xy 92.49918 -245.498874)
		)
		(stroke
			(width 0)
			(type solid)
		)
		(fill yes)
		(layer "In6.Cu")
		(net "M_D_CPU1_SB_CS_N<0>")
	)
	(gr_poly
		(pts
			(xy 92.54871 -243.718334) (xy 92.54871 -243.674138) (xy 92.19311 -243.674138) (xy 92.19311 -243.718334)
			(xy 92.2401 -243.870734) (xy 92.50172 -243.870734)
		)
		(stroke
			(width 0)
			(type solid)
		)
		(fill yes)
		(layer "In6.Cu")
		(net "M_C_CPU1_SB_DQ<1>")
	)
	(gr_poly
		(pts
			(xy 92.552266 -244.127274) (xy 92.505276 -243.974874) (xy 92.243656 -243.974874) (xy 92.196666 -244.127274)
			(xy 92.196666 -244.17147) (xy 92.552266 -244.17147)
		)
		(stroke
			(width 0)
			(type solid)
		)
		(fill yes)
		(layer "In6.Cu")
		(net "M_C_CPU1_SB_DQ<2>")
	)
	(gr_poly
		(pts
			(xy 92.552266 -226.221798) (xy 92.505276 -226.069398) (xy 92.243656 -226.069398) (xy 92.196666 -226.221798)
			(xy 92.196666 -226.265994) (xy 92.552266 -226.265994)
		)
		(stroke
			(width 0)
			(type solid)
		)
		(fill yes)
		(layer "In6.Cu")
		(net "M_C_CPU1_SB_DQS_DP<8>")
	)
	(gr_poly
		(pts
			(xy 92.558108 -247.382538) (xy 92.511118 -247.230138) (xy 92.249498 -247.230138) (xy 92.202508 -247.382538)
			(xy 92.202508 -247.426734) (xy 92.558108 -247.426734)
		)
		(stroke
			(width 0)
			(type solid)
		)
		(fill yes)
		(layer "In6.Cu")
		(net "M_A_CPU1_SB_RSP<1>")
	)
	(gr_poly
		(pts
			(xy 92.558108 -245.754906) (xy 92.511118 -245.602506) (xy 92.249498 -245.602506) (xy 92.202508 -245.754906)
			(xy 92.202508 -245.799356) (xy 92.558108 -245.799356)
		)
		(stroke
			(width 0)
			(type solid)
		)
		(fill yes)
		(layer "In6.Cu")
		(net "M_D_CPU1_SB_CS_N<3>")
	)
	(gr_poly
		(pts
			(xy 92.558108 -237.207806) (xy 92.558108 -237.163356) (xy 92.202508 -237.163356) (xy 92.202508 -237.207806)
			(xy 92.249498 -237.360206) (xy 92.511118 -237.360206)
		)
		(stroke
			(width 0)
			(type solid)
		)
		(fill yes)
		(layer "In6.Cu")
		(net "M_C_CPU1_SB_DQS_DN<6>")
	)
	(gr_poly
		(pts
			(xy 92.558108 -232.732326) (xy 92.511118 -232.579926) (xy 92.249498 -232.579926) (xy 92.202508 -232.732326)
			(xy 92.202508 -232.776776) (xy 92.558108 -232.776776)
		)
		(stroke
			(width 0)
			(type solid)
		)
		(fill yes)
		(layer "In6.Cu")
		(net "M_D_CPU1_SB_DQS_DN<2>")
	)
	(gr_poly
		(pts
			(xy 92.558108 -232.324402) (xy 92.558108 -232.279952) (xy 92.202508 -232.279952) (xy 92.202508 -232.324402)
			(xy 92.249498 -232.476802) (xy 92.511118 -232.476802)
		)
		(stroke
			(width 0)
			(type solid)
		)
		(fill yes)
		(layer "In6.Cu")
		(net "M_D_CPU1_SB_DQS_DN<7>")
	)
	(gr_poly
		(pts
			(xy 92.560648 -248.602246) (xy 92.560648 -248.557796) (xy 92.205048 -248.557796) (xy 92.205048 -248.602246)
			(xy 92.252038 -248.754646) (xy 92.513658 -248.754646)
		)
		(stroke
			(width 0)
			(type solid)
		)
		(fill yes)
		(layer "In6.Cu")
		(net "M_A_CPU1_SB_RSP<0>")
	)
	(gr_poly
		(pts
			(xy 92.560648 -242.499134) (xy 92.513658 -242.346734) (xy 92.252038 -242.346734) (xy 92.205048 -242.499134)
			(xy 92.205048 -242.54333) (xy 92.560648 -242.54333)
		)
		(stroke
			(width 0)
			(type solid)
		)
		(fill yes)
		(layer "In6.Cu")
		(net "M_C_CPU1_SB_DQS_DN<0>")
	)
	(gr_poly
		(pts
			(xy 92.560648 -242.090702) (xy 92.560648 -242.046506) (xy 92.205048 -242.046506) (xy 92.205048 -242.090702)
			(xy 92.252038 -242.243102) (xy 92.513658 -242.243102)
		)
		(stroke
			(width 0)
			(type solid)
		)
		(fill yes)
		(layer "In6.Cu")
		(net "M_C_CPU1_SB_DQS_DN<5>")
	)
	(gr_poly
		(pts
			(xy 92.560648 -240.871502) (xy 92.513658 -240.719102) (xy 92.252038 -240.719102) (xy 92.205048 -240.871502)
			(xy 92.205048 -240.915698) (xy 92.560648 -240.915698)
		)
		(stroke
			(width 0)
			(type solid)
		)
		(fill yes)
		(layer "In6.Cu")
		(net "M_C_CPU1_SB_DQ<6>")
	)
	(gr_poly
		(pts
			(xy 92.560648 -240.46307) (xy 92.560648 -240.418874) (xy 92.205048 -240.418874) (xy 92.205048 -240.46307)
			(xy 92.252038 -240.61547) (xy 92.513658 -240.61547)
		)
		(stroke
			(width 0)
			(type solid)
		)
		(fill yes)
		(layer "In6.Cu")
		(net "M_C_CPU1_SB_DQ<5>")
	)
	(gr_poly
		(pts
			(xy 92.560648 -239.243362) (xy 92.513658 -239.090962) (xy 92.252038 -239.090962) (xy 92.205048 -239.243362)
			(xy 92.205048 -239.287812) (xy 92.560648 -239.287812)
		)
		(stroke
			(width 0)
			(type solid)
		)
		(fill yes)
		(layer "In6.Cu")
		(net "M_C_CPU1_SB_DQ<10>")
	)
	(gr_poly
		(pts
			(xy 92.560648 -238.835438) (xy 92.560648 -238.790988) (xy 92.205048 -238.790988) (xy 92.205048 -238.835438)
			(xy 92.252038 -238.987838) (xy 92.513658 -238.987838)
		)
		(stroke
			(width 0)
			(type solid)
		)
		(fill yes)
		(layer "In6.Cu")
		(net "M_C_CPU1_SB_DQ<9>")
	)
	(gr_poly
		(pts
			(xy 92.560648 -235.988098) (xy 92.513658 -235.835698) (xy 92.252038 -235.835698) (xy 92.205048 -235.988098)
			(xy 92.205048 -236.032294) (xy 92.560648 -236.032294)
		)
		(stroke
			(width 0)
			(type solid)
		)
		(fill yes)
		(layer "In6.Cu")
		(net "M_C_CPU1_SB_DQ<14>")
	)
	(gr_poly
		(pts
			(xy 92.560648 -235.579666) (xy 92.560648 -235.53547) (xy 92.205048 -235.53547) (xy 92.205048 -235.579666)
			(xy 92.252038 -235.732066) (xy 92.513658 -235.732066)
		)
		(stroke
			(width 0)
			(type solid)
		)
		(fill yes)
		(layer "In6.Cu")
		(net "M_C_CPU1_SB_DQ<13>")
	)
	(gr_poly
		(pts
			(xy 92.560648 -234.360466) (xy 92.513658 -234.208066) (xy 92.252038 -234.208066) (xy 92.205048 -234.360466)
			(xy 92.205048 -234.404662) (xy 92.560648 -234.404662)
		)
		(stroke
			(width 0)
			(type solid)
		)
		(fill yes)
		(layer "In6.Cu")
		(net "M_D_CPU1_SB_DQ<18>")
	)
	(gr_poly
		(pts
			(xy 92.560648 -233.952034) (xy 92.560648 -233.907838) (xy 92.205048 -233.907838) (xy 92.205048 -233.952034)
			(xy 92.252038 -234.104434) (xy 92.513658 -234.104434)
		)
		(stroke
			(width 0)
			(type solid)
		)
		(fill yes)
		(layer "In6.Cu")
		(net "M_D_CPU1_SB_DQ<17>")
	)
	(gr_poly
		(pts
			(xy 92.560648 -231.104694) (xy 92.513658 -230.952294) (xy 92.252038 -230.952294) (xy 92.205048 -231.104694)
			(xy 92.205048 -231.14889) (xy 92.560648 -231.14889)
		)
		(stroke
			(width 0)
			(type solid)
		)
		(fill yes)
		(layer "In6.Cu")
		(net "M_D_CPU1_SB_DQ<22>")
	)
	(gr_poly
		(pts
			(xy 92.560648 -230.696262) (xy 92.560648 -230.652066) (xy 92.205048 -230.652066) (xy 92.205048 -230.696262)
			(xy 92.252038 -230.848662) (xy 92.513658 -230.848662)
		)
		(stroke
			(width 0)
			(type solid)
		)
		(fill yes)
		(layer "In6.Cu")
		(net "M_D_CPU1_SB_DQ<21>")
	)
	(gr_poly
		(pts
			(xy 92.560648 -229.477062) (xy 92.513658 -229.324662) (xy 92.252038 -229.324662) (xy 92.205048 -229.477062)
			(xy 92.205048 -229.521258) (xy 92.560648 -229.521258)
		)
		(stroke
			(width 0)
			(type solid)
		)
		(fill yes)
		(layer "In6.Cu")
		(net "M_C_CPU1_SB_DQ<24>")
	)
	(gr_poly
		(pts
			(xy 92.560648 -229.06863) (xy 92.560648 -229.024434) (xy 92.205048 -229.024434) (xy 92.205048 -229.06863)
			(xy 92.252038 -229.22103) (xy 92.513658 -229.22103)
		)
		(stroke
			(width 0)
			(type solid)
		)
		(fill yes)
		(layer "In6.Cu")
		(net "M_C_CPU1_SB_DQ<25>")
	)
	(gr_poly
		(pts
			(xy 92.560648 -225.813366) (xy 92.560648 -225.768916) (xy 92.205048 -225.768916) (xy 92.205048 -225.813366)
			(xy 92.252038 -225.965766) (xy 92.513658 -225.965766)
		)
		(stroke
			(width 0)
			(type solid)
		)
		(fill yes)
		(layer "In6.Cu")
		(net "M_C_CPU1_SB_DQ<28>")
	)
	(gr_poly
		(pts
			(xy 92.631514 -224.65411) (xy 92.523056 -224.53727) (xy 92.484702 -224.515172) (xy 92.306902 -224.82302)
			(xy 92.345256 -224.845118) (xy 92.500704 -224.880678)
		)
		(stroke
			(width 0)
			(type solid)
		)
		(fill yes)
		(layer "In6.Cu")
		(net "M_C_CPU1_SB_DQ<31>")
	)
	(gr_poly
		(pts
			(xy 92.658692 -263.482074) (xy 92.658692 -263.437624) (xy 92.303092 -263.437624) (xy 92.303092 -263.482074)
			(xy 92.350082 -263.634474) (xy 92.611702 -263.634474)
		)
		(stroke
			(width 0)
			(type solid)
		)
		(fill yes)
		(layer "In6.Cu")
		(net "M_C_CPU1_SA_DQ<29>")
	)
	(gr_poly
		(pts
			(xy 92.662248 -258.59867) (xy 92.662248 -258.554474) (xy 92.306648 -258.554474) (xy 92.306648 -258.59867)
			(xy 92.353638 -258.75107) (xy 92.615258 -258.75107)
		)
		(stroke
			(width 0)
			(type solid)
		)
		(fill yes)
		(layer "In6.Cu")
		(net "M_C_CPU1_SA_CB<7>")
	)
	(gr_poly
		(pts
			(xy 92.66809 -275.284946) (xy 92.6211 -275.132546) (xy 92.35948 -275.132546) (xy 92.31249 -275.284946)
			(xy 92.31249 -275.329142) (xy 92.66809 -275.329142)
		)
		(stroke
			(width 0)
			(type solid)
		)
		(fill yes)
		(layer "In6.Cu")
		(net "M_D_CPU1_SA_DQS_DN<0>")
	)
	(gr_poly
		(pts
			(xy 92.66809 -274.876514) (xy 92.66809 -274.832318) (xy 92.31249 -274.832318) (xy 92.31249 -274.876514)
			(xy 92.35948 -275.028914) (xy 92.6211 -275.028914)
		)
		(stroke
			(width 0)
			(type solid)
		)
		(fill yes)
		(layer "In6.Cu")
		(net "M_D_CPU1_SA_DQS_DN<5>")
	)
	(gr_poly
		(pts
			(xy 92.66809 -270.401542) (xy 92.6211 -270.249142) (xy 92.35948 -270.249142) (xy 92.31249 -270.401542)
			(xy 92.31249 -270.445992) (xy 92.66809 -270.445992)
		)
		(stroke
			(width 0)
			(type solid)
		)
		(fill yes)
		(layer "In6.Cu")
		(net "M_C_CPU1_SA_DQS_DN<1>")
	)
	(gr_poly
		(pts
			(xy 92.66809 -269.993618) (xy 92.66809 -269.949168) (xy 92.31249 -269.949168) (xy 92.31249 -269.993618)
			(xy 92.35948 -270.146018) (xy 92.6211 -270.146018)
		)
		(stroke
			(width 0)
			(type solid)
		)
		(fill yes)
		(layer "In6.Cu")
		(net "M_C_CPU1_SA_DQS_DN<6>")
	)
	(gr_poly
		(pts
			(xy 92.66809 -265.518138) (xy 92.6211 -265.365738) (xy 92.35948 -265.365738) (xy 92.31249 -265.518138)
			(xy 92.31249 -265.562588) (xy 92.66809 -265.562588)
		)
		(stroke
			(width 0)
			(type solid)
		)
		(fill yes)
		(layer "In6.Cu")
		(net "M_C_CPU1_SA_DQS_DN<3>")
	)
	(gr_poly
		(pts
			(xy 92.66809 -265.110214) (xy 92.66809 -265.065764) (xy 92.31249 -265.065764) (xy 92.31249 -265.110214)
			(xy 92.35948 -265.262614) (xy 92.6211 -265.262614)
		)
		(stroke
			(width 0)
			(type solid)
		)
		(fill yes)
		(layer "In6.Cu")
		(net "M_C_CPU1_SA_DQS_DN<8>")
	)
	(gr_poly
		(pts
			(xy 92.66809 -260.634734) (xy 92.6211 -260.482334) (xy 92.35948 -260.482334) (xy 92.31249 -260.634734)
			(xy 92.31249 -260.679184) (xy 92.66809 -260.679184)
		)
		(stroke
			(width 0)
			(type solid)
		)
		(fill yes)
		(layer "In6.Cu")
		(net "M_C_CPU1_SA_DQS_DP<9>")
	)
	(gr_poly
		(pts
			(xy 92.66809 -260.22681) (xy 92.66809 -260.18236) (xy 92.31249 -260.18236) (xy 92.31249 -260.22681)
			(xy 92.35948 -260.37921) (xy 92.6211 -260.37921)
		)
		(stroke
			(width 0)
			(type solid)
		)
		(fill yes)
		(layer "In6.Cu")
		(net "M_C_CPU1_SA_DQS_DP<4>")
	)
	(gr_poly
		(pts
			(xy 92.66809 -256.971038) (xy 92.66809 -256.926588) (xy 92.31249 -256.926588) (xy 92.31249 -256.971038)
			(xy 92.35948 -257.123438) (xy 92.6211 -257.123438)
		)
		(stroke
			(width 0)
			(type solid)
		)
		(fill yes)
		(layer "In6.Cu")
		(net "M_D_CPU1_SA_RSP<0>")
	)
	(gr_poly
		(pts
			(xy 92.66809 -255.751838) (xy 92.6211 -255.599438) (xy 92.35948 -255.599438) (xy 92.31249 -255.751838)
			(xy 92.31249 -255.796034) (xy 92.66809 -255.796034)
		)
		(stroke
			(width 0)
			(type solid)
		)
		(fill yes)
		(layer "In6.Cu")
		(net "M_D_CPU1_SB_RSP<1>")
	)
	(gr_poly
		(pts
			(xy 92.66809 -255.343406) (xy 92.66809 -255.29921) (xy 92.31249 -255.29921) (xy 92.31249 -255.343406)
			(xy 92.35948 -255.495806) (xy 92.6211 -255.495806)
		)
		(stroke
			(width 0)
			(type solid)
		)
		(fill yes)
		(layer "In6.Cu")
		(net "M_C_CPU1_SA_RSP<0>")
	)
	(gr_poly
		(pts
			(xy 92.67063 -276.912578) (xy 92.62364 -276.760178) (xy 92.36202 -276.760178) (xy 92.31503 -276.912578)
			(xy 92.31503 -276.957028) (xy 92.67063 -276.957028)
		)
		(stroke
			(width 0)
			(type solid)
		)
		(fill yes)
		(layer "In6.Cu")
		(net "M_D_CPU1_SA_DQ<2>")
	)
	(gr_poly
		(pts
			(xy 92.67063 -276.5044) (xy 92.67063 -276.460204) (xy 92.31503 -276.460204) (xy 92.31503 -276.5044)
			(xy 92.36202 -276.6568) (xy 92.62364 -276.6568)
		)
		(stroke
			(width 0)
			(type solid)
		)
		(fill yes)
		(layer "In6.Cu")
		(net "M_D_CPU1_SA_DQ<1>")
	)
	(gr_poly
		(pts
			(xy 92.67063 -273.657314) (xy 92.62364 -273.504914) (xy 92.36202 -273.504914) (xy 92.31503 -273.657314)
			(xy 92.31503 -273.70151) (xy 92.67063 -273.70151)
		)
		(stroke
			(width 0)
			(type solid)
		)
		(fill yes)
		(layer "In6.Cu")
		(net "M_D_CPU1_SA_DQ<6>")
	)
	(gr_poly
		(pts
			(xy 92.67063 -273.248882) (xy 92.67063 -273.204686) (xy 92.31503 -273.204686) (xy 92.31503 -273.248882)
			(xy 92.36202 -273.401282) (xy 92.62364 -273.401282)
		)
		(stroke
			(width 0)
			(type solid)
		)
		(fill yes)
		(layer "In6.Cu")
		(net "M_D_CPU1_SA_DQ<5>")
	)
	(gr_poly
		(pts
			(xy 92.67063 -272.029174) (xy 92.62364 -271.876774) (xy 92.36202 -271.876774) (xy 92.31503 -272.029174)
			(xy 92.31503 -272.073624) (xy 92.67063 -272.073624)
		)
		(stroke
			(width 0)
			(type solid)
		)
		(fill yes)
		(layer "In6.Cu")
		(net "M_C_CPU1_SA_DQ<10>")
	)
	(gr_poly
		(pts
			(xy 92.67063 -271.62125) (xy 92.67063 -271.5768) (xy 92.31503 -271.5768) (xy 92.31503 -271.62125)
			(xy 92.36202 -271.77365) (xy 92.62364 -271.77365)
		)
		(stroke
			(width 0)
			(type solid)
		)
		(fill yes)
		(layer "In6.Cu")
		(net "M_C_CPU1_SA_DQ<9>")
	)
	(gr_poly
		(pts
			(xy 92.67063 -268.77391) (xy 92.62364 -268.62151) (xy 92.36202 -268.62151) (xy 92.31503 -268.77391)
			(xy 92.31503 -268.818106) (xy 92.67063 -268.818106)
		)
		(stroke
			(width 0)
			(type solid)
		)
		(fill yes)
		(layer "In6.Cu")
		(net "M_C_CPU1_SA_DQ<14>")
	)
	(gr_poly
		(pts
			(xy 92.67063 -268.365478) (xy 92.67063 -268.321282) (xy 92.31503 -268.321282) (xy 92.31503 -268.365478)
			(xy 92.36202 -268.517878) (xy 92.62364 -268.517878)
		)
		(stroke
			(width 0)
			(type solid)
		)
		(fill yes)
		(layer "In6.Cu")
		(net "M_C_CPU1_SA_DQ<13>")
	)
	(gr_poly
		(pts
			(xy 92.67063 -267.14577) (xy 92.62364 -266.99337) (xy 92.36202 -266.99337) (xy 92.31503 -267.14577)
			(xy 92.31503 -267.19022) (xy 92.67063 -267.19022)
		)
		(stroke
			(width 0)
			(type solid)
		)
		(fill yes)
		(layer "In6.Cu")
		(net "M_C_CPU1_SA_DQ<26>")
	)
	(gr_poly
		(pts
			(xy 92.67063 -266.737846) (xy 92.67063 -266.69365) (xy 92.31503 -266.69365) (xy 92.31503 -266.737846)
			(xy 92.36202 -266.890246) (xy 92.62364 -266.890246)
		)
		(stroke
			(width 0)
			(type solid)
		)
		(fill yes)
		(layer "In6.Cu")
		(net "M_C_CPU1_SA_DQ<25>")
	)
	(gr_poly
		(pts
			(xy 92.67063 -263.890506) (xy 92.62364 -263.738106) (xy 92.36202 -263.738106) (xy 92.31503 -263.890506)
			(xy 92.31503 -263.934956) (xy 92.67063 -263.934956)
		)
		(stroke
			(width 0)
			(type solid)
		)
		(fill yes)
		(layer "In6.Cu")
		(net "M_C_CPU1_SA_DQ<30>")
	)
	(gr_poly
		(pts
			(xy 92.67063 -262.262874) (xy 92.62364 -262.110474) (xy 92.36202 -262.110474) (xy 92.31503 -262.262874)
			(xy 92.31503 -262.30707) (xy 92.67063 -262.30707)
		)
		(stroke
			(width 0)
			(type solid)
		)
		(fill yes)
		(layer "In6.Cu")
		(net "M_C_CPU1_SA_CB<0>")
	)
	(gr_poly
		(pts
			(xy 92.67063 -261.854442) (xy 92.67063 -261.810246) (xy 92.31503 -261.810246) (xy 92.31503 -261.854442)
			(xy 92.36202 -262.006842) (xy 92.62364 -262.006842)
		)
		(stroke
			(width 0)
			(type solid)
		)
		(fill yes)
		(layer "In6.Cu")
		(net "M_C_CPU1_SA_CB<3>")
	)
	(gr_poly
		(pts
			(xy 92.67063 -259.007102) (xy 92.62364 -258.854702) (xy 92.36202 -258.854702) (xy 92.31503 -259.007102)
			(xy 92.31503 -259.051552) (xy 92.67063 -259.051552)
		)
		(stroke
			(width 0)
			(type solid)
		)
		(fill yes)
		(layer "In6.Cu")
		(net "M_C_CPU1_SA_CB<4>")
	)
	(gr_poly
		(pts
			(xy 92.67063 -254.123698) (xy 92.62364 -253.971298) (xy 92.36202 -253.971298) (xy 92.31503 -254.123698)
			(xy 92.31503 -254.168148) (xy 92.67063 -254.168148)
		)
		(stroke
			(width 0)
			(type solid)
		)
		(fill yes)
		(layer "In6.Cu")
		(net "M_C_CPU1_SB_RSP<1>")
	)
	(gr_poly
		(pts
			(xy 92.877894 -227.293932) (xy 92.916248 -227.271834) (xy 92.738448 -226.963986) (xy 92.700094 -226.986084)
			(xy 92.591636 -227.102924) (xy 92.722446 -227.329492)
		)
		(stroke
			(width 0)
			(type solid)
		)
		(fill yes)
		(layer "In6.Cu")
		(net "M_C_CPU1_SB_DQS_DN<8>")
	)
	(gr_poly
		(pts
			(xy 92.988638 -226.676204) (xy 93.097096 -226.559364) (xy 92.966286 -226.332796) (xy 92.810838 -226.368356)
			(xy 92.772484 -226.390454) (xy 92.950284 -226.698302)
		)
		(stroke
			(width 0)
			(type solid)
		)
		(fill yes)
		(layer "In6.Cu")
		(net "M_C_CPU1_SB_DQS_DP<8>")
	)
	(gr_poly
		(pts
			(xy 93.01353 -248.196354) (xy 92.96654 -248.043954) (xy 92.70492 -248.043954) (xy 92.65793 -248.196354)
			(xy 92.65793 -248.24055) (xy 93.01353 -248.24055)
		)
		(stroke
			(width 0)
			(type solid)
		)
		(fill yes)
		(layer "In6.Cu")
		(net "M_A_CPU1_SA_RSP<0>")
	)
	(gr_poly
		(pts
			(xy 93.01353 -247.787922) (xy 93.01353 -247.743726) (xy 92.65793 -247.743726) (xy 92.65793 -247.787922)
			(xy 92.70492 -247.940322) (xy 92.96654 -247.940322)
		)
		(stroke
			(width 0)
			(type solid)
		)
		(fill yes)
		(layer "In6.Cu")
		(net "M_A_CPU1_SA_RSP<1>")
	)
	(gr_poly
		(pts
			(xy 93.01353 -242.905026) (xy 93.01353 -242.860576) (xy 92.65793 -242.860576) (xy 92.65793 -242.905026)
			(xy 92.70492 -243.057426) (xy 92.96654 -243.057426)
		)
		(stroke
			(width 0)
			(type solid)
		)
		(fill yes)
		(layer "In6.Cu")
		(net "M_C_CPU1_SB_DQS_DP<0>")
	)
	(gr_poly
		(pts
			(xy 93.01353 -241.685318) (xy 92.96654 -241.532918) (xy 92.70492 -241.532918) (xy 92.65793 -241.685318)
			(xy 92.65793 -241.729514) (xy 93.01353 -241.729514)
		)
		(stroke
			(width 0)
			(type solid)
		)
		(fill yes)
		(layer "In6.Cu")
		(net "M_C_CPU1_SB_DQS_DP<5>")
	)
	(gr_poly
		(pts
			(xy 93.01353 -241.276886) (xy 93.01353 -241.23269) (xy 92.65793 -241.23269) (xy 92.65793 -241.276886)
			(xy 92.70492 -241.429286) (xy 92.96654 -241.429286)
		)
		(stroke
			(width 0)
			(type solid)
		)
		(fill yes)
		(layer "In6.Cu")
		(net "M_C_CPU1_SB_DQ<4>")
	)
	(gr_poly
		(pts
			(xy 93.01353 -240.057178) (xy 92.96654 -239.904778) (xy 92.70492 -239.904778) (xy 92.65793 -240.057178)
			(xy 92.65793 -240.101628) (xy 93.01353 -240.101628)
		)
		(stroke
			(width 0)
			(type solid)
		)
		(fill yes)
		(layer "In6.Cu")
		(net "M_C_CPU1_SB_DQ<7>")
	)
	(gr_poly
		(pts
			(xy 93.01353 -239.649254) (xy 93.01353 -239.604804) (xy 92.65793 -239.604804) (xy 92.65793 -239.649254)
			(xy 92.70492 -239.801654) (xy 92.96654 -239.801654)
		)
		(stroke
			(width 0)
			(type solid)
		)
		(fill yes)
		(layer "In6.Cu")
		(net "M_C_CPU1_SB_DQ<8>")
	)
	(gr_poly
		(pts
			(xy 93.01353 -238.429546) (xy 92.96654 -238.277146) (xy 92.70492 -238.277146) (xy 92.65793 -238.429546)
			(xy 92.65793 -238.473996) (xy 93.01353 -238.473996)
		)
		(stroke
			(width 0)
			(type solid)
		)
		(fill yes)
		(layer "In6.Cu")
		(net "M_C_CPU1_SB_DQ<11>")
	)
	(gr_poly
		(pts
			(xy 93.01353 -238.021622) (xy 93.01353 -237.977172) (xy 92.65793 -237.977172) (xy 92.65793 -238.021622)
			(xy 92.70492 -238.174022) (xy 92.96654 -238.174022)
		)
		(stroke
			(width 0)
			(type solid)
		)
		(fill yes)
		(layer "In6.Cu")
		(net "M_C_CPU1_SB_DQS_DP<1>")
	)
	(gr_poly
		(pts
			(xy 93.01353 -236.801914) (xy 92.96654 -236.649514) (xy 92.70492 -236.649514) (xy 92.65793 -236.801914)
			(xy 92.65793 -236.84611) (xy 93.01353 -236.84611)
		)
		(stroke
			(width 0)
			(type solid)
		)
		(fill yes)
		(layer "In6.Cu")
		(net "M_C_CPU1_SB_DQS_DP<6>")
	)
	(gr_poly
		(pts
			(xy 93.01353 -236.39399) (xy 93.01353 -236.34954) (xy 92.65793 -236.34954) (xy 92.65793 -236.39399)
			(xy 92.70492 -236.54639) (xy 92.96654 -236.54639)
		)
		(stroke
			(width 0)
			(type solid)
		)
		(fill yes)
		(layer "In6.Cu")
		(net "M_C_CPU1_SB_DQ<12>")
	)
	(gr_poly
		(pts
			(xy 93.01353 -235.174282) (xy 92.96654 -235.021882) (xy 92.70492 -235.021882) (xy 92.65793 -235.174282)
			(xy 92.65793 -235.218478) (xy 93.01353 -235.218478)
		)
		(stroke
			(width 0)
			(type solid)
		)
		(fill yes)
		(layer "In6.Cu")
		(net "M_C_CPU1_SB_DQ<15>")
	)
	(gr_poly
		(pts
			(xy 93.01353 -234.76585) (xy 93.01353 -234.721654) (xy 92.65793 -234.721654) (xy 92.65793 -234.76585)
			(xy 92.70492 -234.91825) (xy 92.96654 -234.91825)
		)
		(stroke
			(width 0)
			(type solid)
		)
		(fill yes)
		(layer "In6.Cu")
		(net "M_D_CPU1_SB_DQ<16>")
	)
	(gr_poly
		(pts
			(xy 93.01353 -233.546142) (xy 92.96654 -233.393742) (xy 92.70492 -233.393742) (xy 92.65793 -233.546142)
			(xy 92.65793 -233.590592) (xy 93.01353 -233.590592)
		)
		(stroke
			(width 0)
			(type solid)
		)
		(fill yes)
		(layer "In6.Cu")
		(net "M_D_CPU1_SB_DQ<19>")
	)
	(gr_poly
		(pts
			(xy 93.01353 -233.138218) (xy 93.01353 -233.093768) (xy 92.65793 -233.093768) (xy 92.65793 -233.138218)
			(xy 92.70492 -233.290618) (xy 92.96654 -233.290618)
		)
		(stroke
			(width 0)
			(type solid)
		)
		(fill yes)
		(layer "In6.Cu")
		(net "M_D_CPU1_SB_DQS_DP<2>")
	)
	(gr_poly
		(pts
			(xy 93.01353 -231.91851) (xy 92.96654 -231.76611) (xy 92.70492 -231.76611) (xy 92.65793 -231.91851)
			(xy 92.65793 -231.96296) (xy 93.01353 -231.96296)
		)
		(stroke
			(width 0)
			(type solid)
		)
		(fill yes)
		(layer "In6.Cu")
		(net "M_D_CPU1_SB_DQS_DP<7>")
	)
	(gr_poly
		(pts
			(xy 93.01353 -231.510586) (xy 93.01353 -231.466136) (xy 92.65793 -231.466136) (xy 92.65793 -231.510586)
			(xy 92.70492 -231.662986) (xy 92.96654 -231.662986)
		)
		(stroke
			(width 0)
			(type solid)
		)
		(fill yes)
		(layer "In6.Cu")
		(net "M_D_CPU1_SB_DQ<20>")
	)
	(gr_poly
		(pts
			(xy 93.01353 -230.290878) (xy 92.96654 -230.138478) (xy 92.70492 -230.138478) (xy 92.65793 -230.290878)
			(xy 92.65793 -230.335074) (xy 93.01353 -230.335074)
		)
		(stroke
			(width 0)
			(type solid)
		)
		(fill yes)
		(layer "In6.Cu")
		(net "M_D_CPU1_SB_DQ<23>")
	)
	(gr_poly
		(pts
			(xy 93.01353 -229.882446) (xy 93.01353 -229.83825) (xy 92.65793 -229.83825) (xy 92.65793 -229.882446)
			(xy 92.70492 -230.034846) (xy 92.96654 -230.034846)
		)
		(stroke
			(width 0)
			(type solid)
		)
		(fill yes)
		(layer "In6.Cu")
		(net "M_C_CPU1_SB_DQ<26>")
	)
	(gr_poly
		(pts
			(xy 93.01353 -228.663246) (xy 92.96654 -228.510846) (xy 92.70492 -228.510846) (xy 92.65793 -228.663246)
			(xy 92.65793 -228.707442) (xy 93.01353 -228.707442)
		)
		(stroke
			(width 0)
			(type solid)
		)
		(fill yes)
		(layer "In6.Cu")
		(net "M_C_CPU1_SB_DQ<27>")
	)
	(gr_poly
		(pts
			(xy 93.01353 -228.254814) (xy 93.01353 -228.210618) (xy 92.65793 -228.210618) (xy 92.65793 -228.254814)
			(xy 92.70492 -228.407214) (xy 92.96654 -228.407214)
		)
		(stroke
			(width 0)
			(type solid)
		)
		(fill yes)
		(layer "In6.Cu")
		(net "M_C_CPU1_SB_DQS_DP<3>")
	)
	(gr_poly
		(pts
			(xy 93.01353 -225.407474) (xy 92.96654 -225.255074) (xy 92.70492 -225.255074) (xy 92.65793 -225.407474)
			(xy 92.65793 -225.45167) (xy 93.01353 -225.45167)
		)
		(stroke
			(width 0)
			(type solid)
		)
		(fill yes)
		(layer "In6.Cu")
		(net "M_C_CPU1_SB_DQ<30>")
	)
	(gr_poly
		(pts
			(xy 93.01607 -244.53215) (xy 93.01607 -244.487954) (xy 92.66047 -244.487954) (xy 92.66047 -244.53215)
			(xy 92.70746 -244.68455) (xy 92.96908 -244.68455)
		)
		(stroke
			(width 0)
			(type solid)
		)
		(fill yes)
		(layer "In6.Cu")
		(net "M_C_CPU1_SB_DQ<0>")
	)
	(gr_poly
		(pts
			(xy 93.021912 -246.16029) (xy 93.021912 -246.11584) (xy 92.666312 -246.11584) (xy 92.666312 -246.16029)
			(xy 92.713302 -246.31269) (xy 92.974922 -246.31269)
		)
		(stroke
			(width 0)
			(type solid)
		)
		(fill yes)
		(layer "In6.Cu")
		(net "M_D_CPU1_SB_CS_N<2>")
	)
	(gr_poly
		(pts
			(xy 93.025468 -243.313458) (xy 92.978478 -243.161058) (xy 92.716858 -243.161058) (xy 92.669868 -243.313458)
			(xy 92.669868 -243.357654) (xy 93.025468 -243.357654)
		)
		(stroke
			(width 0)
			(type solid)
		)
		(fill yes)
		(layer "In6.Cu")
		(net "M_C_CPU1_SB_DQ<3>")
	)
	(gr_poly
		(pts
			(xy 93.028008 -244.94109) (xy 92.981018 -244.78869) (xy 92.719398 -244.78869) (xy 92.672408 -244.94109)
			(xy 92.672408 -244.985286) (xy 93.028008 -244.985286)
		)
		(stroke
			(width 0)
			(type solid)
		)
		(fill yes)
		(layer "In6.Cu")
		(net "M_D_CPU1_SB_CS_N<1>")
	)
	(gr_poly
		(pts
			(xy 93.123512 -277.318216) (xy 93.123512 -277.27402) (xy 92.767912 -277.27402) (xy 92.767912 -277.318216)
			(xy 92.814902 -277.470616) (xy 93.076522 -277.470616)
		)
		(stroke
			(width 0)
			(type solid)
		)
		(fill yes)
		(layer "In6.Cu")
		(net "M_D_CPU1_SA_DQ<0>")
	)
	(gr_poly
		(pts
			(xy 93.123512 -276.098762) (xy 93.076522 -275.946362) (xy 92.814902 -275.946362) (xy 92.767912 -276.098762)
			(xy 92.767912 -276.143212) (xy 93.123512 -276.143212)
		)
		(stroke
			(width 0)
			(type solid)
		)
		(fill yes)
		(layer "In6.Cu")
		(net "M_D_CPU1_SA_DQ<3>")
	)
	(gr_poly
		(pts
			(xy 93.123512 -275.690584) (xy 93.123512 -275.646388) (xy 92.767912 -275.646388) (xy 92.767912 -275.690584)
			(xy 92.814902 -275.842984) (xy 93.076522 -275.842984)
		)
		(stroke
			(width 0)
			(type solid)
		)
		(fill yes)
		(layer "In6.Cu")
		(net "M_D_CPU1_SA_DQS_DP<0>")
	)
	(gr_poly
		(pts
			(xy 93.123512 -274.47113) (xy 93.076522 -274.31873) (xy 92.814902 -274.31873) (xy 92.767912 -274.47113)
			(xy 92.767912 -274.515326) (xy 93.123512 -274.515326)
		)
		(stroke
			(width 0)
			(type solid)
		)
		(fill yes)
		(layer "In6.Cu")
		(net "M_D_CPU1_SA_DQS_DP<5>")
	)
	(gr_poly
		(pts
			(xy 93.123512 -274.062698) (xy 93.123512 -274.018502) (xy 92.767912 -274.018502) (xy 92.767912 -274.062698)
			(xy 92.814902 -274.215098) (xy 93.076522 -274.215098)
		)
		(stroke
			(width 0)
			(type solid)
		)
		(fill yes)
		(layer "In6.Cu")
		(net "M_D_CPU1_SA_DQ<4>")
	)
	(gr_poly
		(pts
			(xy 93.123512 -272.843498) (xy 93.076522 -272.691098) (xy 92.814902 -272.691098) (xy 92.767912 -272.843498)
			(xy 92.767912 -272.887694) (xy 93.123512 -272.887694)
		)
		(stroke
			(width 0)
			(type solid)
		)
		(fill yes)
		(layer "In6.Cu")
		(net "M_D_CPU1_SA_DQ<7>")
	)
	(gr_poly
		(pts
			(xy 93.123512 -272.435066) (xy 93.123512 -272.39087) (xy 92.767912 -272.39087) (xy 92.767912 -272.435066)
			(xy 92.814902 -272.587466) (xy 93.076522 -272.587466)
		)
		(stroke
			(width 0)
			(type solid)
		)
		(fill yes)
		(layer "In6.Cu")
		(net "M_C_CPU1_SA_DQ<8>")
	)
	(gr_poly
		(pts
			(xy 93.123512 -271.215358) (xy 93.076522 -271.062958) (xy 92.814902 -271.062958) (xy 92.767912 -271.215358)
			(xy 92.767912 -271.259808) (xy 93.123512 -271.259808)
		)
		(stroke
			(width 0)
			(type solid)
		)
		(fill yes)
		(layer "In6.Cu")
		(net "M_C_CPU1_SA_DQ<11>")
	)
	(gr_poly
		(pts
			(xy 93.123512 -270.807434) (xy 93.123512 -270.762984) (xy 92.767912 -270.762984) (xy 92.767912 -270.807434)
			(xy 92.814902 -270.959834) (xy 93.076522 -270.959834)
		)
		(stroke
			(width 0)
			(type solid)
		)
		(fill yes)
		(layer "In6.Cu")
		(net "M_C_CPU1_SA_DQS_DP<1>")
	)
	(gr_poly
		(pts
			(xy 93.123512 -269.587726) (xy 93.076522 -269.435326) (xy 92.814902 -269.435326) (xy 92.767912 -269.587726)
			(xy 92.767912 -269.631922) (xy 93.123512 -269.631922)
		)
		(stroke
			(width 0)
			(type solid)
		)
		(fill yes)
		(layer "In6.Cu")
		(net "M_C_CPU1_SA_DQS_DP<6>")
	)
	(gr_poly
		(pts
			(xy 93.123512 -269.179294) (xy 93.123512 -269.135098) (xy 92.767912 -269.135098) (xy 92.767912 -269.179294)
			(xy 92.814902 -269.331694) (xy 93.076522 -269.331694)
		)
		(stroke
			(width 0)
			(type solid)
		)
		(fill yes)
		(layer "In6.Cu")
		(net "M_C_CPU1_SA_DQ<12>")
	)
	(gr_poly
		(pts
			(xy 93.123512 -267.960094) (xy 93.076522 -267.807694) (xy 92.814902 -267.807694) (xy 92.767912 -267.960094)
			(xy 92.767912 -268.00429) (xy 93.123512 -268.00429)
		)
		(stroke
			(width 0)
			(type solid)
		)
		(fill yes)
		(layer "In6.Cu")
		(net "M_C_CPU1_SA_DQ<15>")
	)
	(gr_poly
		(pts
			(xy 93.123512 -267.551662) (xy 93.123512 -267.507466) (xy 92.767912 -267.507466) (xy 92.767912 -267.551662)
			(xy 92.814902 -267.704062) (xy 93.076522 -267.704062)
		)
		(stroke
			(width 0)
			(type solid)
		)
		(fill yes)
		(layer "In6.Cu")
		(net "M_C_CPU1_SA_DQ<24>")
	)
	(gr_poly
		(pts
			(xy 93.123512 -266.331954) (xy 93.076522 -266.179554) (xy 92.814902 -266.179554) (xy 92.767912 -266.331954)
			(xy 92.767912 -266.376404) (xy 93.123512 -266.376404)
		)
		(stroke
			(width 0)
			(type solid)
		)
		(fill yes)
		(layer "In6.Cu")
		(net "M_C_CPU1_SA_DQ<27>")
	)
	(gr_poly
		(pts
			(xy 93.123512 -265.92403) (xy 93.123512 -265.879834) (xy 92.767912 -265.879834) (xy 92.767912 -265.92403)
			(xy 92.814902 -266.07643) (xy 93.076522 -266.07643)
		)
		(stroke
			(width 0)
			(type solid)
		)
		(fill yes)
		(layer "In6.Cu")
		(net "M_C_CPU1_SA_DQS_DP<3>")
	)
	(gr_poly
		(pts
			(xy 93.123512 -264.704322) (xy 93.076522 -264.551922) (xy 92.814902 -264.551922) (xy 92.767912 -264.704322)
			(xy 92.767912 -264.748772) (xy 93.123512 -264.748772)
		)
		(stroke
			(width 0)
			(type solid)
		)
		(fill yes)
		(layer "In6.Cu")
		(net "M_C_CPU1_SA_DQS_DP<8>")
	)
	(gr_poly
		(pts
			(xy 93.123512 -264.296398) (xy 93.123512 -264.251948) (xy 92.767912 -264.251948) (xy 92.767912 -264.296398)
			(xy 92.814902 -264.448798) (xy 93.076522 -264.448798)
		)
		(stroke
			(width 0)
			(type solid)
		)
		(fill yes)
		(layer "In6.Cu")
		(net "M_C_CPU1_SA_DQ<28>")
	)
	(gr_poly
		(pts
			(xy 93.123512 -262.668258) (xy 93.123512 -262.624062) (xy 92.767912 -262.624062) (xy 92.767912 -262.668258)
			(xy 92.814902 -262.820658) (xy 93.076522 -262.820658)
		)
		(stroke
			(width 0)
			(type solid)
		)
		(fill yes)
		(layer "In6.Cu")
		(net "M_C_CPU1_SA_CB<2>")
	)
	(gr_poly
		(pts
			(xy 93.123512 -261.449058) (xy 93.076522 -261.296658) (xy 92.814902 -261.296658) (xy 92.767912 -261.449058)
			(xy 92.767912 -261.493254) (xy 93.123512 -261.493254)
		)
		(stroke
			(width 0)
			(type solid)
		)
		(fill yes)
		(layer "In6.Cu")
		(net "M_C_CPU1_SA_CB<1>")
	)
	(gr_poly
		(pts
			(xy 93.123512 -261.040626) (xy 93.123512 -260.99643) (xy 92.767912 -260.99643) (xy 92.767912 -261.040626)
			(xy 92.814902 -261.193026) (xy 93.076522 -261.193026)
		)
		(stroke
			(width 0)
			(type solid)
		)
		(fill yes)
		(layer "In6.Cu")
		(net "M_C_CPU1_SA_DQS_DN<9>")
	)
	(gr_poly
		(pts
			(xy 93.123512 -259.820918) (xy 93.076522 -259.668518) (xy 92.814902 -259.668518) (xy 92.767912 -259.820918)
			(xy 92.767912 -259.865368) (xy 93.123512 -259.865368)
		)
		(stroke
			(width 0)
			(type solid)
		)
		(fill yes)
		(layer "In6.Cu")
		(net "M_C_CPU1_SA_DQS_DN<4>")
	)
	(gr_poly
		(pts
			(xy 93.123512 -259.412994) (xy 93.123512 -259.368544) (xy 92.767912 -259.368544) (xy 92.767912 -259.412994)
			(xy 92.814902 -259.565394) (xy 93.076522 -259.565394)
		)
		(stroke
			(width 0)
			(type solid)
		)
		(fill yes)
		(layer "In6.Cu")
		(net "M_C_CPU1_SA_CB<6>")
	)
	(gr_poly
		(pts
			(xy 93.123512 -256.157222) (xy 93.123512 -256.113026) (xy 92.767912 -256.113026) (xy 92.767912 -256.157222)
			(xy 92.814902 -256.309622) (xy 93.076522 -256.309622)
		)
		(stroke
			(width 0)
			(type solid)
		)
		(fill yes)
		(layer "In6.Cu")
		(net "M_D_CPU1_SA_RSP<1>")
	)
	(gr_poly
		(pts
			(xy 93.123512 -254.937514) (xy 93.076522 -254.785114) (xy 92.814902 -254.785114) (xy 92.767912 -254.937514)
			(xy 92.767912 -254.981964) (xy 93.123512 -254.981964)
		)
		(stroke
			(width 0)
			(type solid)
		)
		(fill yes)
		(layer "In6.Cu")
		(net "M_C_CPU1_SB_RSP<0>")
	)
	(gr_poly
		(pts
			(xy 93.123512 -254.52959) (xy 93.123512 -254.48514) (xy 92.767912 -254.48514) (xy 92.767912 -254.52959)
			(xy 92.814902 -254.68199) (xy 93.076522 -254.68199)
		)
		(stroke
			(width 0)
			(type solid)
		)
		(fill yes)
		(layer "In6.Cu")
		(net "M_C_CPU1_SA_RSP<1>")
	)
	(gr_poly
		(pts
			(xy 93.126052 -258.193286) (xy 93.079062 -258.040886) (xy 92.817442 -258.040886) (xy 92.770452 -258.193286)
			(xy 92.770452 -258.237736) (xy 93.126052 -258.237736)
		)
		(stroke
			(width 0)
			(type solid)
		)
		(fill yes)
		(layer "In6.Cu")
		(net "M_C_CPU1_SA_CB<5>")
	)
	(gr_poly
		(pts
			(xy 93.131894 -256.565654) (xy 93.084904 -256.413254) (xy 92.823284 -256.413254) (xy 92.776294 -256.565654)
			(xy 92.776294 -256.610104) (xy 93.131894 -256.610104)
		)
		(stroke
			(width 0)
			(type solid)
		)
		(fill yes)
		(layer "In6.Cu")
		(net "M_D_CPU1_SB_RSP<0>")
	)
	(gr_poly
		(pts
			(xy 93.13545 -263.077198) (xy 93.08846 -262.924798) (xy 92.82684 -262.924798) (xy 92.77985 -263.077198)
			(xy 92.77985 -263.121394) (xy 93.13545 -263.121394)
		)
		(stroke
			(width 0)
			(type solid)
		)
		(fill yes)
		(layer "In6.Cu")
		(net "M_C_CPU1_SA_DQ<31>")
	)
	(gr_poly
		(pts
			(xy 93.347794 -226.480116) (xy 93.386148 -226.458018) (xy 93.208348 -226.15017) (xy 93.169994 -226.172268)
			(xy 93.061536 -226.289108) (xy 93.192346 -226.515676)
		)
		(stroke
			(width 0)
			(type solid)
		)
		(fill yes)
		(layer "In6.Cu")
		(net "M_C_CPU1_SB_DQ<28>")
	)
	(gr_poly
		(pts
			(xy 93.34881 -224.85477) (xy 93.387164 -224.832672) (xy 93.209364 -224.524824) (xy 93.17101 -224.546922)
			(xy 93.062552 -224.663762) (xy 93.193362 -224.89033)
		)
		(stroke
			(width 0)
			(type solid)
		)
		(fill yes)
		(layer "In6.Cu")
		(net "M_C_CPU1_SB_DQ<31>")
	)
	(gr_poly
		(pts
			(xy 93.457522 -225.860356) (xy 93.56598 -225.743516) (xy 93.43517 -225.516948) (xy 93.279722 -225.552508)
			(xy 93.241368 -225.574606) (xy 93.419168 -225.882454)
		)
		(stroke
			(width 0)
			(type solid)
		)
		(fill yes)
		(layer "In6.Cu")
		(net "M_C_CPU1_SB_DQ<30>")
	)
	(gr_poly
		(pts
			(xy 93.457522 -224.231962) (xy 93.56598 -224.115122) (xy 93.43517 -223.888554) (xy 93.279722 -223.924114)
			(xy 93.241368 -223.946212) (xy 93.419168 -224.25406)
		)
		(stroke
			(width 0)
			(type solid)
		)
		(fill yes)
		(layer "In6.Cu")
		(net "M_C_CPU1_SB_DQ<29>")
	)
	(gr_poly
		(pts
			(xy 93.48851 -243.718334) (xy 93.48851 -243.674138) (xy 93.13291 -243.674138) (xy 93.13291 -243.718334)
			(xy 93.1799 -243.870734) (xy 93.44152 -243.870734)
		)
		(stroke
			(width 0)
			(type solid)
		)
		(fill yes)
		(layer "In6.Cu")
		(net "M_C_CPU1_SB_DQ<1>")
	)
	(gr_poly
		(pts
			(xy 93.497908 -245.754906) (xy 93.450918 -245.602506) (xy 93.189298 -245.602506) (xy 93.142308 -245.754906)
			(xy 93.142308 -245.799102) (xy 93.497908 -245.799102)
		)
		(stroke
			(width 0)
			(type solid)
		)
		(fill yes)
		(layer "In6.Cu")
		(net "M_D_CPU1_SB_CS_N<3>")
	)
	(gr_poly
		(pts
			(xy 93.497908 -245.346474) (xy 93.497908 -245.302278) (xy 93.142308 -245.302278) (xy 93.142308 -245.346474)
			(xy 93.189298 -245.498874) (xy 93.450918 -245.498874)
		)
		(stroke
			(width 0)
			(type solid)
		)
		(fill yes)
		(layer "In6.Cu")
		(net "M_D_CPU1_SB_CS_N<0>")
	)
	(gr_poly
		(pts
			(xy 93.500448 -248.602246) (xy 93.500448 -248.557796) (xy 93.144848 -248.557796) (xy 93.144848 -248.602246)
			(xy 93.191838 -248.754646) (xy 93.453458 -248.754646)
		)
		(stroke
			(width 0)
			(type solid)
		)
		(fill yes)
		(layer "In6.Cu")
		(net "M_A_CPU1_SB_RSP<0>")
	)
	(gr_poly
		(pts
			(xy 93.500448 -247.382538) (xy 93.453458 -247.230138) (xy 93.191838 -247.230138) (xy 93.144848 -247.382538)
			(xy 93.144848 -247.426734) (xy 93.500448 -247.426734)
		)
		(stroke
			(width 0)
			(type solid)
		)
		(fill yes)
		(layer "In6.Cu")
		(net "M_A_CPU1_SB_RSP<1>")
	)
	(gr_poly
		(pts
			(xy 93.500448 -244.126766) (xy 93.453458 -243.974366) (xy 93.191838 -243.974366) (xy 93.144848 -244.126766)
			(xy 93.144848 -244.171216) (xy 93.500448 -244.171216)
		)
		(stroke
			(width 0)
			(type solid)
		)
		(fill yes)
		(layer "In6.Cu")
		(net "M_C_CPU1_SB_DQ<2>")
	)
	(gr_poly
		(pts
			(xy 93.500448 -242.499134) (xy 93.453458 -242.346734) (xy 93.191838 -242.346734) (xy 93.144848 -242.499134)
			(xy 93.144848 -242.54333) (xy 93.500448 -242.54333)
		)
		(stroke
			(width 0)
			(type solid)
		)
		(fill yes)
		(layer "In6.Cu")
		(net "M_C_CPU1_SB_DQS_DN<0>")
	)
	(gr_poly
		(pts
			(xy 93.500448 -242.090702) (xy 93.500448 -242.046506) (xy 93.144848 -242.046506) (xy 93.144848 -242.090702)
			(xy 93.191838 -242.243102) (xy 93.453458 -242.243102)
		)
		(stroke
			(width 0)
			(type solid)
		)
		(fill yes)
		(layer "In6.Cu")
		(net "M_C_CPU1_SB_DQS_DN<5>")
	)
	(gr_poly
		(pts
			(xy 93.500448 -240.871502) (xy 93.453458 -240.719102) (xy 93.191838 -240.719102) (xy 93.144848 -240.871502)
			(xy 93.144848 -240.915698) (xy 93.500448 -240.915698)
		)
		(stroke
			(width 0)
			(type solid)
		)
		(fill yes)
		(layer "In6.Cu")
		(net "M_C_CPU1_SB_DQ<6>")
	)
	(gr_poly
		(pts
			(xy 93.500448 -240.46307) (xy 93.500448 -240.418874) (xy 93.144848 -240.418874) (xy 93.144848 -240.46307)
			(xy 93.191838 -240.61547) (xy 93.453458 -240.61547)
		)
		(stroke
			(width 0)
			(type solid)
		)
		(fill yes)
		(layer "In6.Cu")
		(net "M_C_CPU1_SB_DQ<5>")
	)
	(gr_poly
		(pts
			(xy 93.500448 -239.243362) (xy 93.453458 -239.090962) (xy 93.191838 -239.090962) (xy 93.144848 -239.243362)
			(xy 93.144848 -239.287812) (xy 93.500448 -239.287812)
		)
		(stroke
			(width 0)
			(type solid)
		)
		(fill yes)
		(layer "In6.Cu")
		(net "M_C_CPU1_SB_DQ<10>")
	)
	(gr_poly
		(pts
			(xy 93.500448 -238.835438) (xy 93.500448 -238.790988) (xy 93.144848 -238.790988) (xy 93.144848 -238.835438)
			(xy 93.191838 -238.987838) (xy 93.453458 -238.987838)
		)
		(stroke
			(width 0)
			(type solid)
		)
		(fill yes)
		(layer "In6.Cu")
		(net "M_C_CPU1_SB_DQ<9>")
	)
	(gr_poly
		(pts
			(xy 93.500448 -237.61573) (xy 93.453458 -237.46333) (xy 93.191838 -237.46333) (xy 93.144848 -237.61573)
			(xy 93.144848 -237.659926) (xy 93.500448 -237.659926)
		)
		(stroke
			(width 0)
			(type solid)
		)
		(fill yes)
		(layer "In6.Cu")
		(net "M_C_CPU1_SB_DQS_DN<1>")
	)
	(gr_poly
		(pts
			(xy 93.500448 -237.207806) (xy 93.500448 -237.163356) (xy 93.144848 -237.163356) (xy 93.144848 -237.207806)
			(xy 93.191838 -237.360206) (xy 93.453458 -237.360206)
		)
		(stroke
			(width 0)
			(type solid)
		)
		(fill yes)
		(layer "In6.Cu")
		(net "M_C_CPU1_SB_DQS_DN<6>")
	)
	(gr_poly
		(pts
			(xy 93.500448 -235.988098) (xy 93.453458 -235.835698) (xy 93.191838 -235.835698) (xy 93.144848 -235.988098)
			(xy 93.144848 -236.032294) (xy 93.500448 -236.032294)
		)
		(stroke
			(width 0)
			(type solid)
		)
		(fill yes)
		(layer "In6.Cu")
		(net "M_C_CPU1_SB_DQ<14>")
	)
	(gr_poly
		(pts
			(xy 93.500448 -235.579666) (xy 93.500448 -235.53547) (xy 93.144848 -235.53547) (xy 93.144848 -235.579666)
			(xy 93.191838 -235.732066) (xy 93.453458 -235.732066)
		)
		(stroke
			(width 0)
			(type solid)
		)
		(fill yes)
		(layer "In6.Cu")
		(net "M_C_CPU1_SB_DQ<13>")
	)
	(gr_poly
		(pts
			(xy 93.500448 -234.360466) (xy 93.453458 -234.208066) (xy 93.191838 -234.208066) (xy 93.144848 -234.360466)
			(xy 93.144848 -234.404662) (xy 93.500448 -234.404662)
		)
		(stroke
			(width 0)
			(type solid)
		)
		(fill yes)
		(layer "In6.Cu")
		(net "M_D_CPU1_SB_DQ<18>")
	)
	(gr_poly
		(pts
			(xy 93.500448 -233.952034) (xy 93.500448 -233.907838) (xy 93.144848 -233.907838) (xy 93.144848 -233.952034)
			(xy 93.191838 -234.104434) (xy 93.453458 -234.104434)
		)
		(stroke
			(width 0)
			(type solid)
		)
		(fill yes)
		(layer "In6.Cu")
		(net "M_D_CPU1_SB_DQ<17>")
	)
	(gr_poly
		(pts
			(xy 93.500448 -232.732326) (xy 93.453458 -232.579926) (xy 93.191838 -232.579926) (xy 93.144848 -232.732326)
			(xy 93.144848 -232.776776) (xy 93.500448 -232.776776)
		)
		(stroke
			(width 0)
			(type solid)
		)
		(fill yes)
		(layer "In6.Cu")
		(net "M_D_CPU1_SB_DQS_DN<2>")
	)
	(gr_poly
		(pts
			(xy 93.500448 -232.324402) (xy 93.500448 -232.279952) (xy 93.144848 -232.279952) (xy 93.144848 -232.324402)
			(xy 93.191838 -232.476802) (xy 93.453458 -232.476802)
		)
		(stroke
			(width 0)
			(type solid)
		)
		(fill yes)
		(layer "In6.Cu")
		(net "M_D_CPU1_SB_DQS_DN<7>")
	)
	(gr_poly
		(pts
			(xy 93.500448 -231.104694) (xy 93.453458 -230.952294) (xy 93.191838 -230.952294) (xy 93.144848 -231.104694)
			(xy 93.144848 -231.14889) (xy 93.500448 -231.14889)
		)
		(stroke
			(width 0)
			(type solid)
		)
		(fill yes)
		(layer "In6.Cu")
		(net "M_D_CPU1_SB_DQ<22>")
	)
	(gr_poly
		(pts
			(xy 93.500448 -230.696262) (xy 93.500448 -230.652066) (xy 93.144848 -230.652066) (xy 93.144848 -230.696262)
			(xy 93.191838 -230.848662) (xy 93.453458 -230.848662)
		)
		(stroke
			(width 0)
			(type solid)
		)
		(fill yes)
		(layer "In6.Cu")
		(net "M_D_CPU1_SB_DQ<21>")
	)
	(gr_poly
		(pts
			(xy 93.500448 -229.477062) (xy 93.453458 -229.324662) (xy 93.191838 -229.324662) (xy 93.144848 -229.477062)
			(xy 93.144848 -229.521258) (xy 93.500448 -229.521258)
		)
		(stroke
			(width 0)
			(type solid)
		)
		(fill yes)
		(layer "In6.Cu")
		(net "M_C_CPU1_SB_DQ<24>")
	)
	(gr_poly
		(pts
			(xy 93.500448 -229.06863) (xy 93.500448 -229.024434) (xy 93.144848 -229.024434) (xy 93.144848 -229.06863)
			(xy 93.191838 -229.22103) (xy 93.453458 -229.22103)
		)
		(stroke
			(width 0)
			(type solid)
		)
		(fill yes)
		(layer "In6.Cu")
		(net "M_C_CPU1_SB_DQ<25>")
	)
	(gr_poly
		(pts
			(xy 93.500448 -227.848922) (xy 93.453458 -227.696522) (xy 93.191838 -227.696522) (xy 93.144848 -227.848922)
			(xy 93.144848 -227.893372) (xy 93.500448 -227.893372)
		)
		(stroke
			(width 0)
			(type solid)
		)
		(fill yes)
		(layer "In6.Cu")
		(net "M_C_CPU1_SB_DQS_DN<3>")
	)
	(gr_poly
		(pts
			(xy 93.500448 -227.440998) (xy 93.500448 -227.396548) (xy 93.144848 -227.396548) (xy 93.144848 -227.440998)
			(xy 93.191838 -227.593398) (xy 93.453458 -227.593398)
		)
		(stroke
			(width 0)
			(type solid)
		)
		(fill yes)
		(layer "In6.Cu")
		(net "M_C_CPU1_SB_DQS_DN<8>")
	)
	(gr_poly
		(pts
			(xy 93.598492 -263.482074) (xy 93.598492 -263.437624) (xy 93.242892 -263.437624) (xy 93.242892 -263.482074)
			(xy 93.289882 -263.634474) (xy 93.551502 -263.634474)
		)
		(stroke
			(width 0)
			(type solid)
		)
		(fill yes)
		(layer "In6.Cu")
		(net "M_C_CPU1_SA_DQ<29>")
	)
	(gr_poly
		(pts
			(xy 93.60789 -256.971038) (xy 93.60789 -256.926842) (xy 93.25229 -256.926842) (xy 93.25229 -256.971038)
			(xy 93.29928 -257.123438) (xy 93.5609 -257.123438)
		)
		(stroke
			(width 0)
			(type solid)
		)
		(fill yes)
		(layer "In6.Cu")
		(net "M_D_CPU1_SA_RSP<0>")
	)
	(gr_poly
		(pts
			(xy 93.61043 -276.912578) (xy 93.56344 -276.760178) (xy 93.30182 -276.760178) (xy 93.25483 -276.912578)
			(xy 93.25483 -276.957028) (xy 93.61043 -276.957028)
		)
		(stroke
			(width 0)
			(type solid)
		)
		(fill yes)
		(layer "In6.Cu")
		(net "M_D_CPU1_SA_DQ<2>")
	)
	(gr_poly
		(pts
			(xy 93.61043 -276.5044) (xy 93.61043 -276.460204) (xy 93.25483 -276.460204) (xy 93.25483 -276.5044)
			(xy 93.30182 -276.6568) (xy 93.56344 -276.6568)
		)
		(stroke
			(width 0)
			(type solid)
		)
		(fill yes)
		(layer "In6.Cu")
		(net "M_D_CPU1_SA_DQ<1>")
	)
	(gr_poly
		(pts
			(xy 93.61043 -275.284946) (xy 93.56344 -275.132546) (xy 93.30182 -275.132546) (xy 93.25483 -275.284946)
			(xy 93.25483 -275.329142) (xy 93.61043 -275.329142)
		)
		(stroke
			(width 0)
			(type solid)
		)
		(fill yes)
		(layer "In6.Cu")
		(net "M_D_CPU1_SA_DQS_DN<0>")
	)
	(gr_poly
		(pts
			(xy 93.61043 -274.876514) (xy 93.61043 -274.832318) (xy 93.25483 -274.832318) (xy 93.25483 -274.876514)
			(xy 93.30182 -275.028914) (xy 93.56344 -275.028914)
		)
		(stroke
			(width 0)
			(type solid)
		)
		(fill yes)
		(layer "In6.Cu")
		(net "M_D_CPU1_SA_DQS_DN<5>")
	)
	(gr_poly
		(pts
			(xy 93.61043 -273.657314) (xy 93.56344 -273.504914) (xy 93.30182 -273.504914) (xy 93.25483 -273.657314)
			(xy 93.25483 -273.70151) (xy 93.61043 -273.70151)
		)
		(stroke
			(width 0)
			(type solid)
		)
		(fill yes)
		(layer "In6.Cu")
		(net "M_D_CPU1_SA_DQ<6>")
	)
	(gr_poly
		(pts
			(xy 93.61043 -273.248882) (xy 93.61043 -273.204686) (xy 93.25483 -273.204686) (xy 93.25483 -273.248882)
			(xy 93.30182 -273.401282) (xy 93.56344 -273.401282)
		)
		(stroke
			(width 0)
			(type solid)
		)
		(fill yes)
		(layer "In6.Cu")
		(net "M_D_CPU1_SA_DQ<5>")
	)
	(gr_poly
		(pts
			(xy 93.61043 -272.029174) (xy 93.56344 -271.876774) (xy 93.30182 -271.876774) (xy 93.25483 -272.029174)
			(xy 93.25483 -272.073624) (xy 93.61043 -272.073624)
		)
		(stroke
			(width 0)
			(type solid)
		)
		(fill yes)
		(layer "In6.Cu")
		(net "M_C_CPU1_SA_DQ<10>")
	)
	(gr_poly
		(pts
			(xy 93.61043 -271.62125) (xy 93.61043 -271.5768) (xy 93.25483 -271.5768) (xy 93.25483 -271.62125)
			(xy 93.30182 -271.77365) (xy 93.56344 -271.77365)
		)
		(stroke
			(width 0)
			(type solid)
		)
		(fill yes)
		(layer "In6.Cu")
		(net "M_C_CPU1_SA_DQ<9>")
	)
	(gr_poly
		(pts
			(xy 93.61043 -270.401542) (xy 93.56344 -270.249142) (xy 93.30182 -270.249142) (xy 93.25483 -270.401542)
			(xy 93.25483 -270.445992) (xy 93.61043 -270.445992)
		)
		(stroke
			(width 0)
			(type solid)
		)
		(fill yes)
		(layer "In6.Cu")
		(net "M_C_CPU1_SA_DQS_DN<1>")
	)
	(gr_poly
		(pts
			(xy 93.61043 -269.993618) (xy 93.61043 -269.949168) (xy 93.25483 -269.949168) (xy 93.25483 -269.993618)
			(xy 93.30182 -270.146018) (xy 93.56344 -270.146018)
		)
		(stroke
			(width 0)
			(type solid)
		)
		(fill yes)
		(layer "In6.Cu")
		(net "M_C_CPU1_SA_DQS_DN<6>")
	)
	(gr_poly
		(pts
			(xy 93.61043 -268.77391) (xy 93.56344 -268.62151) (xy 93.30182 -268.62151) (xy 93.25483 -268.77391)
			(xy 93.25483 -268.818106) (xy 93.61043 -268.818106)
		)
		(stroke
			(width 0)
			(type solid)
		)
		(fill yes)
		(layer "In6.Cu")
		(net "M_C_CPU1_SA_DQ<14>")
	)
	(gr_poly
		(pts
			(xy 93.61043 -268.365478) (xy 93.61043 -268.321282) (xy 93.25483 -268.321282) (xy 93.25483 -268.365478)
			(xy 93.30182 -268.517878) (xy 93.56344 -268.517878)
		)
		(stroke
			(width 0)
			(type solid)
		)
		(fill yes)
		(layer "In6.Cu")
		(net "M_C_CPU1_SA_DQ<13>")
	)
	(gr_poly
		(pts
			(xy 93.61043 -267.14577) (xy 93.56344 -266.99337) (xy 93.30182 -266.99337) (xy 93.25483 -267.14577)
			(xy 93.25483 -267.19022) (xy 93.61043 -267.19022)
		)
		(stroke
			(width 0)
			(type solid)
		)
		(fill yes)
		(layer "In6.Cu")
		(net "M_C_CPU1_SA_DQ<26>")
	)
	(gr_poly
		(pts
			(xy 93.61043 -266.737846) (xy 93.61043 -266.69365) (xy 93.25483 -266.69365) (xy 93.25483 -266.737846)
			(xy 93.30182 -266.890246) (xy 93.56344 -266.890246)
		)
		(stroke
			(width 0)
			(type solid)
		)
		(fill yes)
		(layer "In6.Cu")
		(net "M_C_CPU1_SA_DQ<25>")
	)
	(gr_poly
		(pts
			(xy 93.61043 -265.518138) (xy 93.56344 -265.365738) (xy 93.30182 -265.365738) (xy 93.25483 -265.518138)
			(xy 93.25483 -265.562588) (xy 93.61043 -265.562588)
		)
		(stroke
			(width 0)
			(type solid)
		)
		(fill yes)
		(layer "In6.Cu")
		(net "M_C_CPU1_SA_DQS_DN<3>")
	)
	(gr_poly
		(pts
			(xy 93.61043 -265.110214) (xy 93.61043 -265.065764) (xy 93.25483 -265.065764) (xy 93.25483 -265.110214)
			(xy 93.30182 -265.262614) (xy 93.56344 -265.262614)
		)
		(stroke
			(width 0)
			(type solid)
		)
		(fill yes)
		(layer "In6.Cu")
		(net "M_C_CPU1_SA_DQS_DN<8>")
	)
	(gr_poly
		(pts
			(xy 93.61043 -263.890506) (xy 93.56344 -263.738106) (xy 93.30182 -263.738106) (xy 93.25483 -263.890506)
			(xy 93.25483 -263.934956) (xy 93.61043 -263.934956)
		)
		(stroke
			(width 0)
			(type solid)
		)
		(fill yes)
		(layer "In6.Cu")
		(net "M_C_CPU1_SA_DQ<30>")
	)
	(gr_poly
		(pts
			(xy 93.61043 -262.262874) (xy 93.56344 -262.110474) (xy 93.30182 -262.110474) (xy 93.25483 -262.262874)
			(xy 93.25483 -262.30707) (xy 93.61043 -262.30707)
		)
		(stroke
			(width 0)
			(type solid)
		)
		(fill yes)
		(layer "In6.Cu")
		(net "M_C_CPU1_SA_CB<0>")
	)
	(gr_poly
		(pts
			(xy 93.61043 -261.854442) (xy 93.61043 -261.810246) (xy 93.25483 -261.810246) (xy 93.25483 -261.854442)
			(xy 93.30182 -262.006842) (xy 93.56344 -262.006842)
		)
		(stroke
			(width 0)
			(type solid)
		)
		(fill yes)
		(layer "In6.Cu")
		(net "M_C_CPU1_SA_CB<3>")
	)
	(gr_poly
		(pts
			(xy 93.61043 -260.634734) (xy 93.56344 -260.482334) (xy 93.30182 -260.482334) (xy 93.25483 -260.634734)
			(xy 93.25483 -260.679184) (xy 93.61043 -260.679184)
		)
		(stroke
			(width 0)
			(type solid)
		)
		(fill yes)
		(layer "In6.Cu")
		(net "M_C_CPU1_SA_DQS_DP<9>")
	)
	(gr_poly
		(pts
			(xy 93.61043 -260.22681) (xy 93.61043 -260.18236) (xy 93.25483 -260.18236) (xy 93.25483 -260.22681)
			(xy 93.30182 -260.37921) (xy 93.56344 -260.37921)
		)
		(stroke
			(width 0)
			(type solid)
		)
		(fill yes)
		(layer "In6.Cu")
		(net "M_C_CPU1_SA_DQS_DP<4>")
	)
	(gr_poly
		(pts
			(xy 93.61043 -259.007102) (xy 93.56344 -258.854702) (xy 93.30182 -258.854702) (xy 93.25483 -259.007102)
			(xy 93.25483 -259.051552) (xy 93.61043 -259.051552)
		)
		(stroke
			(width 0)
			(type solid)
		)
		(fill yes)
		(layer "In6.Cu")
		(net "M_C_CPU1_SA_CB<4>")
	)
	(gr_poly
		(pts
			(xy 93.61043 -258.599178) (xy 93.61043 -258.554728) (xy 93.25483 -258.554728) (xy 93.25483 -258.599178)
			(xy 93.30182 -258.751578) (xy 93.56344 -258.751578)
		)
		(stroke
			(width 0)
			(type solid)
		)
		(fill yes)
		(layer "In6.Cu")
		(net "M_C_CPU1_SA_CB<7>")
	)
	(gr_poly
		(pts
			(xy 93.61043 -255.751838) (xy 93.56344 -255.599438) (xy 93.30182 -255.599438) (xy 93.25483 -255.751838)
			(xy 93.25483 -255.796034) (xy 93.61043 -255.796034)
		)
		(stroke
			(width 0)
			(type solid)
		)
		(fill yes)
		(layer "In6.Cu")
		(net "M_D_CPU1_SB_RSP<1>")
	)
	(gr_poly
		(pts
			(xy 93.61043 -255.343406) (xy 93.61043 -255.29921) (xy 93.25483 -255.29921) (xy 93.25483 -255.343406)
			(xy 93.30182 -255.495806) (xy 93.56344 -255.495806)
		)
		(stroke
			(width 0)
			(type solid)
		)
		(fill yes)
		(layer "In6.Cu")
		(net "M_C_CPU1_SA_RSP<0>")
	)
	(gr_poly
		(pts
			(xy 93.61043 -254.123698) (xy 93.56344 -253.971298) (xy 93.30182 -253.971298) (xy 93.25483 -254.123698)
			(xy 93.25483 -254.168148) (xy 93.61043 -254.168148)
		)
		(stroke
			(width 0)
			(type solid)
		)
		(fill yes)
		(layer "In6.Cu")
		(net "M_C_CPU1_SB_RSP<1>")
	)
	(gr_poly
		(pts
			(xy 93.818456 -225.668078) (xy 93.85681 -225.64598) (xy 93.67901 -225.338132) (xy 93.640656 -225.36023)
			(xy 93.532198 -225.47707) (xy 93.663008 -225.703638)
		)
		(stroke
			(width 0)
			(type solid)
		)
		(fill yes)
		(layer "In6.Cu")
		(net "M_C_CPU1_SB_DQ<31>")
	)
	(gr_poly
		(pts
			(xy 93.927168 -225.045778) (xy 94.035626 -224.928938) (xy 93.904816 -224.70237) (xy 93.749368 -224.73793)
			(xy 93.711014 -224.760028) (xy 93.888814 -225.067876)
		)
		(stroke
			(width 0)
			(type solid)
		)
		(fill yes)
		(layer "In6.Cu")
		(net "M_C_CPU1_SB_DQ<29>")
	)
	(gr_poly
		(pts
			(xy 93.95333 -248.196354) (xy 93.90634 -248.043954) (xy 93.64472 -248.043954) (xy 93.59773 -248.196354)
			(xy 93.59773 -248.24055) (xy 93.95333 -248.24055)
		)
		(stroke
			(width 0)
			(type solid)
		)
		(fill yes)
		(layer "In6.Cu")
		(net "M_A_CPU1_SA_RSP<0>")
	)
	(gr_poly
		(pts
			(xy 93.95333 -247.787922) (xy 93.95333 -247.743726) (xy 93.59773 -247.743726) (xy 93.59773 -247.787922)
			(xy 93.64472 -247.940322) (xy 93.90634 -247.940322)
		)
		(stroke
			(width 0)
			(type solid)
		)
		(fill yes)
		(layer "In6.Cu")
		(net "M_A_CPU1_SA_RSP<1>")
	)
	(gr_poly
		(pts
			(xy 93.95333 -244.940582) (xy 93.90634 -244.788182) (xy 93.64472 -244.788182) (xy 93.59773 -244.940582)
			(xy 93.59773 -244.985032) (xy 93.95333 -244.985032)
		)
		(stroke
			(width 0)
			(type solid)
		)
		(fill yes)
		(layer "In6.Cu")
		(net "M_D_CPU1_SB_CS_N<1>")
	)
	(gr_poly
		(pts
			(xy 93.95333 -244.532658) (xy 93.95333 -244.488208) (xy 93.59773 -244.488208) (xy 93.59773 -244.532658)
			(xy 93.64472 -244.685058) (xy 93.90634 -244.685058)
		)
		(stroke
			(width 0)
			(type solid)
		)
		(fill yes)
		(layer "In6.Cu")
		(net "M_C_CPU1_SB_DQ<0>")
	)
	(gr_poly
		(pts
			(xy 93.95333 -240.057178) (xy 93.90634 -239.904778) (xy 93.64472 -239.904778) (xy 93.59773 -240.057178)
			(xy 93.59773 -240.101628) (xy 93.95333 -240.101628)
		)
		(stroke
			(width 0)
			(type solid)
		)
		(fill yes)
		(layer "In6.Cu")
		(net "M_C_CPU1_SB_DQ<7>")
	)
	(gr_poly
		(pts
			(xy 93.95333 -239.649254) (xy 93.95333 -239.604804) (xy 93.59773 -239.604804) (xy 93.59773 -239.649254)
			(xy 93.64472 -239.801654) (xy 93.90634 -239.801654)
		)
		(stroke
			(width 0)
			(type solid)
		)
		(fill yes)
		(layer "In6.Cu")
		(net "M_C_CPU1_SB_DQ<8>")
	)
	(gr_poly
		(pts
			(xy 93.95333 -238.429546) (xy 93.90634 -238.277146) (xy 93.64472 -238.277146) (xy 93.59773 -238.429546)
			(xy 93.59773 -238.473996) (xy 93.95333 -238.473996)
		)
		(stroke
			(width 0)
			(type solid)
		)
		(fill yes)
		(layer "In6.Cu")
		(net "M_C_CPU1_SB_DQ<11>")
	)
	(gr_poly
		(pts
			(xy 93.95333 -235.174282) (xy 93.90634 -235.021882) (xy 93.64472 -235.021882) (xy 93.59773 -235.174282)
			(xy 93.59773 -235.218478) (xy 93.95333 -235.218478)
		)
		(stroke
			(width 0)
			(type solid)
		)
		(fill yes)
		(layer "In6.Cu")
		(net "M_C_CPU1_SB_DQ<15>")
	)
	(gr_poly
		(pts
			(xy 93.95333 -234.76585) (xy 93.95333 -234.721654) (xy 93.59773 -234.721654) (xy 93.59773 -234.76585)
			(xy 93.64472 -234.91825) (xy 93.90634 -234.91825)
		)
		(stroke
			(width 0)
			(type solid)
		)
		(fill yes)
		(layer "In6.Cu")
		(net "M_D_CPU1_SB_DQ<16>")
	)
	(gr_poly
		(pts
			(xy 93.95333 -233.546142) (xy 93.90634 -233.393742) (xy 93.64472 -233.393742) (xy 93.59773 -233.546142)
			(xy 93.59773 -233.590592) (xy 93.95333 -233.590592)
		)
		(stroke
			(width 0)
			(type solid)
		)
		(fill yes)
		(layer "In6.Cu")
		(net "M_D_CPU1_SB_DQ<19>")
	)
	(gr_poly
		(pts
			(xy 93.95333 -233.138218) (xy 93.95333 -233.093768) (xy 93.59773 -233.093768) (xy 93.59773 -233.138218)
			(xy 93.64472 -233.290618) (xy 93.90634 -233.290618)
		)
		(stroke
			(width 0)
			(type solid)
		)
		(fill yes)
		(layer "In6.Cu")
		(net "M_D_CPU1_SB_DQS_DP<2>")
	)
	(gr_poly
		(pts
			(xy 93.95333 -230.290878) (xy 93.90634 -230.138478) (xy 93.64472 -230.138478) (xy 93.59773 -230.290878)
			(xy 93.59773 -230.335074) (xy 93.95333 -230.335074)
		)
		(stroke
			(width 0)
			(type solid)
		)
		(fill yes)
		(layer "In6.Cu")
		(net "M_D_CPU1_SB_DQ<23>")
	)
	(gr_poly
		(pts
			(xy 93.95333 -229.882446) (xy 93.95333 -229.83825) (xy 93.59773 -229.83825) (xy 93.59773 -229.882446)
			(xy 93.64472 -230.034846) (xy 93.90634 -230.034846)
		)
		(stroke
			(width 0)
			(type solid)
		)
		(fill yes)
		(layer "In6.Cu")
		(net "M_C_CPU1_SB_DQ<26>")
	)
	(gr_poly
		(pts
			(xy 93.95333 -228.663246) (xy 93.90634 -228.510846) (xy 93.64472 -228.510846) (xy 93.59773 -228.663246)
			(xy 93.59773 -228.707442) (xy 93.95333 -228.707442)
		)
		(stroke
			(width 0)
			(type solid)
		)
		(fill yes)
		(layer "In6.Cu")
		(net "M_C_CPU1_SB_DQ<27>")
	)
	(gr_poly
		(pts
			(xy 93.95333 -227.035106) (xy 93.90634 -226.882706) (xy 93.64472 -226.882706) (xy 93.59773 -227.035106)
			(xy 93.59773 -227.079556) (xy 93.95333 -227.079556)
		)
		(stroke
			(width 0)
			(type solid)
		)
		(fill yes)
		(layer "In6.Cu")
		(net "M_C_CPU1_SB_DQS_DP<8>")
	)
	(gr_poly
		(pts
			(xy 93.95333 -226.627182) (xy 93.95333 -226.582732) (xy 93.59773 -226.582732) (xy 93.59773 -226.627182)
			(xy 93.64472 -226.779582) (xy 93.90634 -226.779582)
		)
		(stroke
			(width 0)
			(type solid)
		)
		(fill yes)
		(layer "In6.Cu")
		(net "M_C_CPU1_SB_DQ<28>")
	)
	(gr_poly
		(pts
			(xy 93.953838 -242.904518) (xy 93.953838 -242.860322) (xy 93.598238 -242.860322) (xy 93.598238 -242.904518)
			(xy 93.645228 -243.056918) (xy 93.906848 -243.056918)
		)
		(stroke
			(width 0)
			(type solid)
		)
		(fill yes)
		(layer "In6.Cu")
		(net "M_C_CPU1_SB_DQS_DP<0>")
	)
	(gr_poly
		(pts
			(xy 93.953838 -238.021114) (xy 93.953838 -237.976918) (xy 93.598238 -237.976918) (xy 93.598238 -238.021114)
			(xy 93.645228 -238.173514) (xy 93.906848 -238.173514)
		)
		(stroke
			(width 0)
			(type solid)
		)
		(fill yes)
		(layer "In6.Cu")
		(net "M_C_CPU1_SB_DQS_DP<1>")
	)
	(gr_poly
		(pts
			(xy 93.95587 -246.16029) (xy 93.95587 -246.116094) (xy 93.60027 -246.116094) (xy 93.60027 -246.16029)
			(xy 93.64726 -246.31269) (xy 93.90888 -246.31269)
		)
		(stroke
			(width 0)
			(type solid)
		)
		(fill yes)
		(layer "In6.Cu")
		(net "M_D_CPU1_SB_CS_N<2>")
	)
	(gr_poly
		(pts
			(xy 93.95587 -241.685318) (xy 93.90888 -241.532918) (xy 93.64726 -241.532918) (xy 93.60027 -241.685318)
			(xy 93.60027 -241.729514) (xy 93.95587 -241.729514)
		)
		(stroke
			(width 0)
			(type solid)
		)
		(fill yes)
		(layer "In6.Cu")
		(net "M_C_CPU1_SB_DQS_DP<5>")
	)
	(gr_poly
		(pts
			(xy 93.95587 -241.276886) (xy 93.95587 -241.23269) (xy 93.60027 -241.23269) (xy 93.60027 -241.276886)
			(xy 93.64726 -241.429286) (xy 93.90888 -241.429286)
		)
		(stroke
			(width 0)
			(type solid)
		)
		(fill yes)
		(layer "In6.Cu")
		(net "M_C_CPU1_SB_DQ<4>")
	)
	(gr_poly
		(pts
			(xy 93.95587 -236.801914) (xy 93.90888 -236.649514) (xy 93.64726 -236.649514) (xy 93.60027 -236.801914)
			(xy 93.60027 -236.84611) (xy 93.95587 -236.84611)
		)
		(stroke
			(width 0)
			(type solid)
		)
		(fill yes)
		(layer "In6.Cu")
		(net "M_C_CPU1_SB_DQS_DP<6>")
	)
	(gr_poly
		(pts
			(xy 93.95587 -236.39399) (xy 93.95587 -236.34954) (xy 93.60027 -236.34954) (xy 93.60027 -236.39399)
			(xy 93.64726 -236.54639) (xy 93.90888 -236.54639)
		)
		(stroke
			(width 0)
			(type solid)
		)
		(fill yes)
		(layer "In6.Cu")
		(net "M_C_CPU1_SB_DQ<12>")
	)
	(gr_poly
		(pts
			(xy 93.95587 -231.91851) (xy 93.90888 -231.76611) (xy 93.64726 -231.76611) (xy 93.60027 -231.91851)
			(xy 93.60027 -231.96296) (xy 93.95587 -231.96296)
		)
		(stroke
			(width 0)
			(type solid)
		)
		(fill yes)
		(layer "In6.Cu")
		(net "M_D_CPU1_SB_DQS_DP<7>")
	)
	(gr_poly
		(pts
			(xy 93.95587 -231.510586) (xy 93.95587 -231.466136) (xy 93.60027 -231.466136) (xy 93.60027 -231.510586)
			(xy 93.64726 -231.662986) (xy 93.90888 -231.662986)
		)
		(stroke
			(width 0)
			(type solid)
		)
		(fill yes)
		(layer "In6.Cu")
		(net "M_D_CPU1_SB_DQ<20>")
	)
	(gr_poly
		(pts
			(xy 93.965268 -243.313458) (xy 93.918278 -243.161058) (xy 93.656658 -243.161058) (xy 93.609668 -243.313458)
			(xy 93.609668 -243.357654) (xy 93.965268 -243.357654)
		)
		(stroke
			(width 0)
			(type solid)
		)
		(fill yes)
		(layer "In6.Cu")
		(net "M_C_CPU1_SB_DQ<3>")
	)
	(gr_poly
		(pts
			(xy 94.063312 -277.318216) (xy 94.063312 -277.27402) (xy 93.707712 -277.27402) (xy 93.707712 -277.318216)
			(xy 93.754702 -277.470616) (xy 94.016322 -277.470616)
		)
		(stroke
			(width 0)
			(type solid)
		)
		(fill yes)
		(layer "In6.Cu")
		(net "M_D_CPU1_SA_DQ<0>")
	)
	(gr_poly
		(pts
			(xy 94.063312 -274.47113) (xy 94.016322 -274.31873) (xy 93.754702 -274.31873) (xy 93.707712 -274.47113)
			(xy 93.707712 -274.515326) (xy 94.063312 -274.515326)
		)
		(stroke
			(width 0)
			(type solid)
		)
		(fill yes)
		(layer "In6.Cu")
		(net "M_D_CPU1_SA_DQS_DP<5>")
	)
	(gr_poly
		(pts
			(xy 94.063312 -274.062698) (xy 94.063312 -274.018502) (xy 93.707712 -274.018502) (xy 93.707712 -274.062698)
			(xy 93.754702 -274.215098) (xy 94.016322 -274.215098)
		)
		(stroke
			(width 0)
			(type solid)
		)
		(fill yes)
		(layer "In6.Cu")
		(net "M_D_CPU1_SA_DQ<4>")
	)
	(gr_poly
		(pts
			(xy 94.063312 -272.843498) (xy 94.016322 -272.691098) (xy 93.754702 -272.691098) (xy 93.707712 -272.843498)
			(xy 93.707712 -272.887694) (xy 94.063312 -272.887694)
		)
		(stroke
			(width 0)
			(type solid)
		)
		(fill yes)
		(layer "In6.Cu")
		(net "M_D_CPU1_SA_DQ<7>")
	)
	(gr_poly
		(pts
			(xy 94.063312 -272.435066) (xy 94.063312 -272.39087) (xy 93.707712 -272.39087) (xy 93.707712 -272.435066)
			(xy 93.754702 -272.587466) (xy 94.016322 -272.587466)
		)
		(stroke
			(width 0)
			(type solid)
		)
		(fill yes)
		(layer "In6.Cu")
		(net "M_C_CPU1_SA_DQ<8>")
	)
	(gr_poly
		(pts
			(xy 94.063312 -269.587726) (xy 94.016322 -269.435326) (xy 93.754702 -269.435326) (xy 93.707712 -269.587726)
			(xy 93.707712 -269.631922) (xy 94.063312 -269.631922)
		)
		(stroke
			(width 0)
			(type solid)
		)
		(fill yes)
		(layer "In6.Cu")
		(net "M_C_CPU1_SA_DQS_DP<6>")
	)
	(gr_poly
		(pts
			(xy 94.063312 -269.179294) (xy 94.063312 -269.135098) (xy 93.707712 -269.135098) (xy 93.707712 -269.179294)
			(xy 93.754702 -269.331694) (xy 94.016322 -269.331694)
		)
		(stroke
			(width 0)
			(type solid)
		)
		(fill yes)
		(layer "In6.Cu")
		(net "M_C_CPU1_SA_DQ<12>")
	)
	(gr_poly
		(pts
			(xy 94.063312 -267.960094) (xy 94.016322 -267.807694) (xy 93.754702 -267.807694) (xy 93.707712 -267.960094)
			(xy 93.707712 -268.00429) (xy 94.063312 -268.00429)
		)
		(stroke
			(width 0)
			(type solid)
		)
		(fill yes)
		(layer "In6.Cu")
		(net "M_C_CPU1_SA_DQ<15>")
	)
	(gr_poly
		(pts
			(xy 94.063312 -267.551662) (xy 94.063312 -267.507466) (xy 93.707712 -267.507466) (xy 93.707712 -267.551662)
			(xy 93.754702 -267.704062) (xy 94.016322 -267.704062)
		)
		(stroke
			(width 0)
			(type solid)
		)
		(fill yes)
		(layer "In6.Cu")
		(net "M_C_CPU1_SA_DQ<24>")
	)
	(gr_poly
		(pts
			(xy 94.063312 -266.331954) (xy 94.016322 -266.179554) (xy 93.754702 -266.179554) (xy 93.707712 -266.331954)
			(xy 93.707712 -266.376404) (xy 94.063312 -266.376404)
		)
		(stroke
			(width 0)
			(type solid)
		)
		(fill yes)
		(layer "In6.Cu")
		(net "M_C_CPU1_SA_DQ<27>")
	)
	(gr_poly
		(pts
			(xy 94.063312 -264.704322) (xy 94.016322 -264.551922) (xy 93.754702 -264.551922) (xy 93.707712 -264.704322)
			(xy 93.707712 -264.748772) (xy 94.063312 -264.748772)
		)
		(stroke
			(width 0)
			(type solid)
		)
		(fill yes)
		(layer "In6.Cu")
		(net "M_C_CPU1_SA_DQS_DP<8>")
	)
	(gr_poly
		(pts
			(xy 94.063312 -264.296398) (xy 94.063312 -264.251948) (xy 93.707712 -264.251948) (xy 93.707712 -264.296398)
			(xy 93.754702 -264.448798) (xy 94.016322 -264.448798)
		)
		(stroke
			(width 0)
			(type solid)
		)
		(fill yes)
		(layer "In6.Cu")
		(net "M_C_CPU1_SA_DQ<28>")
	)
	(gr_poly
		(pts
			(xy 94.063312 -262.668258) (xy 94.063312 -262.624062) (xy 93.707712 -262.624062) (xy 93.707712 -262.668258)
			(xy 93.754702 -262.820658) (xy 94.016322 -262.820658)
		)
		(stroke
			(width 0)
			(type solid)
		)
		(fill yes)
		(layer "In6.Cu")
		(net "M_C_CPU1_SA_CB<2>")
	)
	(gr_poly
		(pts
			(xy 94.063312 -261.449058) (xy 94.016322 -261.296658) (xy 93.754702 -261.296658) (xy 93.707712 -261.449058)
			(xy 93.707712 -261.493254) (xy 94.063312 -261.493254)
		)
		(stroke
			(width 0)
			(type solid)
		)
		(fill yes)
		(layer "In6.Cu")
		(net "M_C_CPU1_SA_CB<1>")
	)
	(gr_poly
		(pts
			(xy 94.063312 -261.040626) (xy 94.063312 -260.99643) (xy 93.707712 -260.99643) (xy 93.707712 -261.040626)
			(xy 93.754702 -261.193026) (xy 94.016322 -261.193026)
		)
		(stroke
			(width 0)
			(type solid)
		)
		(fill yes)
		(layer "In6.Cu")
		(net "M_C_CPU1_SA_DQS_DN<9>")
	)
	(gr_poly
		(pts
			(xy 94.063312 -259.412994) (xy 94.063312 -259.368544) (xy 93.707712 -259.368544) (xy 93.707712 -259.412994)
			(xy 93.754702 -259.565394) (xy 94.016322 -259.565394)
		)
		(stroke
			(width 0)
			(type solid)
		)
		(fill yes)
		(layer "In6.Cu")
		(net "M_C_CPU1_SA_CB<6>")
	)
	(gr_poly
		(pts
			(xy 94.063312 -258.193286) (xy 94.016322 -258.040886) (xy 93.754702 -258.040886) (xy 93.707712 -258.193286)
			(xy 93.707712 -258.237482) (xy 94.063312 -258.237482)
		)
		(stroke
			(width 0)
			(type solid)
		)
		(fill yes)
		(layer "In6.Cu")
		(net "M_C_CPU1_SA_CB<5>")
	)
	(gr_poly
		(pts
			(xy 94.063312 -254.937514) (xy 94.016322 -254.785114) (xy 93.754702 -254.785114) (xy 93.707712 -254.937514)
			(xy 93.707712 -254.981964) (xy 94.063312 -254.981964)
		)
		(stroke
			(width 0)
			(type solid)
		)
		(fill yes)
		(layer "In6.Cu")
		(net "M_C_CPU1_SB_RSP<0>")
	)
	(gr_poly
		(pts
			(xy 94.063312 -254.52959) (xy 94.063312 -254.48514) (xy 93.707712 -254.48514) (xy 93.707712 -254.52959)
			(xy 93.754702 -254.68199) (xy 94.016322 -254.68199)
		)
		(stroke
			(width 0)
			(type solid)
		)
		(fill yes)
		(layer "In6.Cu")
		(net "M_C_CPU1_SA_RSP<1>")
	)
	(gr_poly
		(pts
			(xy 94.06382 -275.690584) (xy 94.06382 -275.646134) (xy 93.70822 -275.646134) (xy 93.70822 -275.690584)
			(xy 93.75521 -275.842984) (xy 94.01683 -275.842984)
		)
		(stroke
			(width 0)
			(type solid)
		)
		(fill yes)
		(layer "In6.Cu")
		(net "M_D_CPU1_SA_DQS_DP<0>")
	)
	(gr_poly
		(pts
			(xy 94.06382 -270.807434) (xy 94.06382 -270.762984) (xy 93.70822 -270.762984) (xy 93.70822 -270.807434)
			(xy 93.75521 -270.959834) (xy 94.01683 -270.959834)
		)
		(stroke
			(width 0)
			(type solid)
		)
		(fill yes)
		(layer "In6.Cu")
		(net "M_C_CPU1_SA_DQS_DP<1>")
	)
	(gr_poly
		(pts
			(xy 94.06382 -265.92403) (xy 94.06382 -265.87958) (xy 93.70822 -265.87958) (xy 93.70822 -265.92403)
			(xy 93.75521 -266.07643) (xy 94.01683 -266.07643)
		)
		(stroke
			(width 0)
			(type solid)
		)
		(fill yes)
		(layer "In6.Cu")
		(net "M_C_CPU1_SA_DQS_DP<3>")
	)
	(gr_poly
		(pts
			(xy 94.065852 -276.098762) (xy 94.018862 -275.946362) (xy 93.757242 -275.946362) (xy 93.710252 -276.098762)
			(xy 93.710252 -276.143212) (xy 94.065852 -276.143212)
		)
		(stroke
			(width 0)
			(type solid)
		)
		(fill yes)
		(layer "In6.Cu")
		(net "M_D_CPU1_SA_DQ<3>")
	)
	(gr_poly
		(pts
			(xy 94.065852 -271.215358) (xy 94.018862 -271.062958) (xy 93.757242 -271.062958) (xy 93.710252 -271.215358)
			(xy 93.710252 -271.259808) (xy 94.065852 -271.259808)
		)
		(stroke
			(width 0)
			(type solid)
		)
		(fill yes)
		(layer "In6.Cu")
		(net "M_C_CPU1_SA_DQ<11>")
	)
	(gr_poly
		(pts
			(xy 94.065852 -256.565654) (xy 94.018862 -256.413254) (xy 93.757242 -256.413254) (xy 93.710252 -256.565654)
			(xy 93.710252 -256.60985) (xy 94.065852 -256.60985)
		)
		(stroke
			(width 0)
			(type solid)
		)
		(fill yes)
		(layer "In6.Cu")
		(net "M_D_CPU1_SB_RSP<0>")
	)
	(gr_poly
		(pts
			(xy 94.065852 -256.157222) (xy 94.065852 -256.113026) (xy 93.710252 -256.113026) (xy 93.710252 -256.157222)
			(xy 93.757242 -256.309622) (xy 94.018862 -256.309622)
		)
		(stroke
			(width 0)
			(type solid)
		)
		(fill yes)
		(layer "In6.Cu")
		(net "M_D_CPU1_SA_RSP<1>")
	)
	(gr_poly
		(pts
			(xy 94.07525 -263.077198) (xy 94.02826 -262.924798) (xy 93.76664 -262.924798) (xy 93.71965 -263.077198)
			(xy 93.71965 -263.121394) (xy 94.07525 -263.121394)
		)
		(stroke
			(width 0)
			(type solid)
		)
		(fill yes)
		(layer "In6.Cu")
		(net "M_C_CPU1_SA_DQ<31>")
	)
	(gr_poly
		(pts
			(xy 94.42831 -243.718334) (xy 94.42831 -243.674138) (xy 94.07271 -243.674138) (xy 94.07271 -243.718334)
			(xy 94.1197 -243.870734) (xy 94.38132 -243.870734)
		)
		(stroke
			(width 0)
			(type solid)
		)
		(fill yes)
		(layer "In6.Cu")
		(net "M_C_CPU1_SB_DQ<1>")
	)
	(gr_poly
		(pts
			(xy 94.431866 -245.754906) (xy 94.384876 -245.602506) (xy 94.123256 -245.602506) (xy 94.076266 -245.754906)
			(xy 94.076266 -245.799356) (xy 94.431866 -245.799356)
		)
		(stroke
			(width 0)
			(type solid)
		)
		(fill yes)
		(layer "In6.Cu")
		(net "M_D_CPU1_SB_CS_N<3>")
	)
	(gr_poly
		(pts
			(xy 94.431866 -242.090702) (xy 94.431866 -242.046252) (xy 94.076266 -242.046252) (xy 94.076266 -242.090702)
			(xy 94.123256 -242.243102) (xy 94.384876 -242.243102)
		)
		(stroke
			(width 0)
			(type solid)
		)
		(fill yes)
		(layer "In6.Cu")
		(net "M_C_CPU1_SB_DQS_DN<5>")
	)
	(gr_poly
		(pts
			(xy 94.431866 -240.871502) (xy 94.384876 -240.719102) (xy 94.123256 -240.719102) (xy 94.076266 -240.871502)
			(xy 94.076266 -240.915952) (xy 94.431866 -240.915952)
		)
		(stroke
			(width 0)
			(type solid)
		)
		(fill yes)
		(layer "In6.Cu")
		(net "M_C_CPU1_SB_DQ<6>")
	)
	(gr_poly
		(pts
			(xy 94.431866 -237.207298) (xy 94.431866 -237.163102) (xy 94.076266 -237.163102) (xy 94.076266 -237.207298)
			(xy 94.123256 -237.359698) (xy 94.384876 -237.359698)
		)
		(stroke
			(width 0)
			(type solid)
		)
		(fill yes)
		(layer "In6.Cu")
		(net "M_C_CPU1_SB_DQS_DN<6>")
	)
	(gr_poly
		(pts
			(xy 94.431866 -235.988098) (xy 94.384876 -235.835698) (xy 94.123256 -235.835698) (xy 94.076266 -235.988098)
			(xy 94.076266 -236.032548) (xy 94.431866 -236.032548)
		)
		(stroke
			(width 0)
			(type solid)
		)
		(fill yes)
		(layer "In6.Cu")
		(net "M_C_CPU1_SB_DQ<14>")
	)
	(gr_poly
		(pts
			(xy 94.431866 -232.323894) (xy 94.431866 -232.279698) (xy 94.076266 -232.279698) (xy 94.076266 -232.323894)
			(xy 94.123256 -232.476294) (xy 94.384876 -232.476294)
		)
		(stroke
			(width 0)
			(type solid)
		)
		(fill yes)
		(layer "In6.Cu")
		(net "M_D_CPU1_SB_DQS_DN<7>")
	)
	(gr_poly
		(pts
			(xy 94.431866 -231.104694) (xy 94.384876 -230.952294) (xy 94.123256 -230.952294) (xy 94.076266 -231.104694)
			(xy 94.076266 -231.149144) (xy 94.431866 -231.149144)
		)
		(stroke
			(width 0)
			(type solid)
		)
		(fill yes)
		(layer "In6.Cu")
		(net "M_D_CPU1_SB_DQ<22>")
	)
	(gr_poly
		(pts
			(xy 94.436692 -253.476506) (xy 94.398338 -253.454408) (xy 94.24289 -253.418848) (xy 94.11208 -253.645416)
			(xy 94.220538 -253.762256) (xy 94.258892 -253.784354)
		)
		(stroke
			(width 0)
			(type solid)
		)
		(fill yes)
		(layer "In6.Cu")
		(net "M_C_CPU1_SB_RSP<1>")
	)
	(gr_poly
		(pts
			(xy 94.437708 -248.601738) (xy 94.437708 -248.557542) (xy 94.082108 -248.557542) (xy 94.082108 -248.601738)
			(xy 94.129098 -248.754138) (xy 94.390718 -248.754138)
		)
		(stroke
			(width 0)
			(type solid)
		)
		(fill yes)
		(layer "In6.Cu")
		(net "M_A_CPU1_SB_RSP<0>")
	)
	(gr_poly
		(pts
			(xy 94.437708 -244.127274) (xy 94.390718 -243.974874) (xy 94.129098 -243.974874) (xy 94.082108 -244.127274)
			(xy 94.082108 -244.17147) (xy 94.437708 -244.17147)
		)
		(stroke
			(width 0)
			(type solid)
		)
		(fill yes)
		(layer "In6.Cu")
		(net "M_C_CPU1_SB_DQ<2>")
	)
	(gr_poly
		(pts
			(xy 94.437708 -239.24387) (xy 94.390718 -239.09147) (xy 94.129098 -239.09147) (xy 94.082108 -239.24387)
			(xy 94.082108 -239.288066) (xy 94.437708 -239.288066)
		)
		(stroke
			(width 0)
			(type solid)
		)
		(fill yes)
		(layer "In6.Cu")
		(net "M_C_CPU1_SB_DQ<10>")
	)
	(gr_poly
		(pts
			(xy 94.437708 -238.83493) (xy 94.437708 -238.790734) (xy 94.082108 -238.790734) (xy 94.082108 -238.83493)
			(xy 94.129098 -238.98733) (xy 94.390718 -238.98733)
		)
		(stroke
			(width 0)
			(type solid)
		)
		(fill yes)
		(layer "In6.Cu")
		(net "M_C_CPU1_SB_DQ<9>")
	)
	(gr_poly
		(pts
			(xy 94.437708 -234.360466) (xy 94.390718 -234.208066) (xy 94.129098 -234.208066) (xy 94.082108 -234.360466)
			(xy 94.082108 -234.404916) (xy 94.437708 -234.404916)
		)
		(stroke
			(width 0)
			(type solid)
		)
		(fill yes)
		(layer "In6.Cu")
		(net "M_D_CPU1_SB_DQ<18>")
	)
	(gr_poly
		(pts
			(xy 94.437708 -233.952034) (xy 94.437708 -233.907584) (xy 94.082108 -233.907584) (xy 94.082108 -233.952034)
			(xy 94.129098 -234.104434) (xy 94.390718 -234.104434)
		)
		(stroke
			(width 0)
			(type solid)
		)
		(fill yes)
		(layer "In6.Cu")
		(net "M_D_CPU1_SB_DQ<17>")
	)
	(gr_poly
		(pts
			(xy 94.437708 -229.477062) (xy 94.390718 -229.324662) (xy 94.129098 -229.324662) (xy 94.082108 -229.477062)
			(xy 94.082108 -229.521512) (xy 94.437708 -229.521512)
		)
		(stroke
			(width 0)
			(type solid)
		)
		(fill yes)
		(layer "In6.Cu")
		(net "M_C_CPU1_SB_DQ<24>")
	)
	(gr_poly
		(pts
			(xy 94.437708 -229.06863) (xy 94.437708 -229.02418) (xy 94.082108 -229.02418) (xy 94.082108 -229.06863)
			(xy 94.129098 -229.22103) (xy 94.390718 -229.22103)
		)
		(stroke
			(width 0)
			(type solid)
		)
		(fill yes)
		(layer "In6.Cu")
		(net "M_C_CPU1_SB_DQ<25>")
	)
	(gr_poly
		(pts
			(xy 94.440248 -247.382538) (xy 94.393258 -247.230138) (xy 94.131638 -247.230138) (xy 94.084648 -247.382538)
			(xy 94.084648 -247.426734) (xy 94.440248 -247.426734)
		)
		(stroke
			(width 0)
			(type solid)
		)
		(fill yes)
		(layer "In6.Cu")
		(net "M_A_CPU1_SB_RSP<1>")
	)
	(gr_poly
		(pts
			(xy 94.440248 -245.346474) (xy 94.440248 -245.302278) (xy 94.084648 -245.302278) (xy 94.084648 -245.346474)
			(xy 94.131638 -245.498874) (xy 94.393258 -245.498874)
		)
		(stroke
			(width 0)
			(type solid)
		)
		(fill yes)
		(layer "In6.Cu")
		(net "M_D_CPU1_SB_CS_N<0>")
	)
	(gr_poly
		(pts
			(xy 94.440248 -240.46307) (xy 94.440248 -240.418874) (xy 94.084648 -240.418874) (xy 94.084648 -240.46307)
			(xy 94.131638 -240.61547) (xy 94.393258 -240.61547)
		)
		(stroke
			(width 0)
			(type solid)
		)
		(fill yes)
		(layer "In6.Cu")
		(net "M_C_CPU1_SB_DQ<5>")
	)
	(gr_poly
		(pts
			(xy 94.440248 -235.579666) (xy 94.440248 -235.53547) (xy 94.084648 -235.53547) (xy 94.084648 -235.579666)
			(xy 94.131638 -235.732066) (xy 94.393258 -235.732066)
		)
		(stroke
			(width 0)
			(type solid)
		)
		(fill yes)
		(layer "In6.Cu")
		(net "M_C_CPU1_SB_DQ<13>")
	)
	(gr_poly
		(pts
			(xy 94.440248 -230.696262) (xy 94.440248 -230.652066) (xy 94.084648 -230.652066) (xy 94.084648 -230.696262)
			(xy 94.131638 -230.848662) (xy 94.393258 -230.848662)
		)
		(stroke
			(width 0)
			(type solid)
		)
		(fill yes)
		(layer "In6.Cu")
		(net "M_D_CPU1_SB_DQ<21>")
	)
	(gr_poly
		(pts
			(xy 94.440248 -227.440998) (xy 94.440248 -227.396548) (xy 94.084648 -227.396548) (xy 94.084648 -227.440998)
			(xy 94.131638 -227.593398) (xy 94.393258 -227.593398)
		)
		(stroke
			(width 0)
			(type solid)
		)
		(fill yes)
		(layer "In6.Cu")
		(net "M_C_CPU1_SB_DQS_DN<8>")
	)
	(gr_poly
		(pts
			(xy 94.440248 -226.22129) (xy 94.393258 -226.06889) (xy 94.131638 -226.06889) (xy 94.084648 -226.22129)
			(xy 94.084648 -226.26574) (xy 94.440248 -226.26574)
		)
		(stroke
			(width 0)
			(type solid)
		)
		(fill yes)
		(layer "In6.Cu")
		(net "M_C_CPU1_SB_DQ<30>")
	)
	(gr_poly
		(pts
			(xy 94.440248 -225.813366) (xy 94.440248 -225.768916) (xy 94.084648 -225.768916) (xy 94.084648 -225.813366)
			(xy 94.131638 -225.965766) (xy 94.393258 -225.965766)
		)
		(stroke
			(width 0)
			(type solid)
		)
		(fill yes)
		(layer "In6.Cu")
		(net "M_C_CPU1_SB_DQ<31>")
	)
	(gr_poly
		(pts
			(xy 94.538292 -263.482074) (xy 94.538292 -263.437624) (xy 94.182692 -263.437624) (xy 94.182692 -263.482074)
			(xy 94.229682 -263.634474) (xy 94.491302 -263.634474)
		)
		(stroke
			(width 0)
			(type solid)
		)
		(fill yes)
		(layer "In6.Cu")
		(net "M_C_CPU1_SA_DQ<29>")
	)
	(gr_poly
		(pts
			(xy 94.541594 -260.635242) (xy 94.494604 -260.482842) (xy 94.232984 -260.482842) (xy 94.185994 -260.635242)
			(xy 94.185994 -260.679438) (xy 94.541594 -260.679438)
		)
		(stroke
			(width 0)
			(type solid)
		)
		(fill yes)
		(layer "In6.Cu")
		(net "M_C_CPU1_SA_DQS_DP<9>")
	)
	(gr_poly
		(pts
			(xy 94.541848 -271.620742) (xy 94.541848 -271.576546) (xy 94.186248 -271.576546) (xy 94.186248 -271.620742)
			(xy 94.233238 -271.773142) (xy 94.494858 -271.773142)
		)
		(stroke
			(width 0)
			(type solid)
		)
		(fill yes)
		(layer "In6.Cu")
		(net "M_C_CPU1_SA_DQ<9>")
	)
	(gr_poly
		(pts
			(xy 94.541848 -256.971038) (xy 94.541848 -256.926588) (xy 94.186248 -256.926588) (xy 94.186248 -256.971038)
			(xy 94.233238 -257.123438) (xy 94.494858 -257.123438)
		)
		(stroke
			(width 0)
			(type solid)
		)
		(fill yes)
		(layer "In6.Cu")
		(net "M_D_CPU1_SA_RSP<0>")
	)
	(gr_poly
		(pts
			(xy 94.541848 -255.751838) (xy 94.494858 -255.599438) (xy 94.233238 -255.599438) (xy 94.186248 -255.751838)
			(xy 94.186248 -255.796288) (xy 94.541848 -255.796288)
		)
		(stroke
			(width 0)
			(type solid)
		)
		(fill yes)
		(layer "In6.Cu")
		(net "M_D_CPU1_SB_RSP<1>")
	)
	(gr_poly
		(pts
			(xy 94.54769 -273.657314) (xy 94.5007 -273.504914) (xy 94.23908 -273.504914) (xy 94.19209 -273.657314)
			(xy 94.19209 -273.701764) (xy 94.54769 -273.701764)
		)
		(stroke
			(width 0)
			(type solid)
		)
		(fill yes)
		(layer "In6.Cu")
		(net "M_D_CPU1_SA_DQ<6>")
	)
	(gr_poly
		(pts
			(xy 94.54769 -273.248882) (xy 94.54769 -273.204432) (xy 94.19209 -273.204432) (xy 94.19209 -273.248882)
			(xy 94.23908 -273.401282) (xy 94.5007 -273.401282)
		)
		(stroke
			(width 0)
			(type solid)
		)
		(fill yes)
		(layer "In6.Cu")
		(net "M_D_CPU1_SA_DQ<5>")
	)
	(gr_poly
		(pts
			(xy 94.54769 -268.77391) (xy 94.5007 -268.62151) (xy 94.23908 -268.62151) (xy 94.19209 -268.77391)
			(xy 94.19209 -268.81836) (xy 94.54769 -268.81836)
		)
		(stroke
			(width 0)
			(type solid)
		)
		(fill yes)
		(layer "In6.Cu")
		(net "M_C_CPU1_SA_DQ<14>")
	)
	(gr_poly
		(pts
			(xy 94.54769 -268.365478) (xy 94.54769 -268.321028) (xy 94.19209 -268.321028) (xy 94.19209 -268.365478)
			(xy 94.23908 -268.517878) (xy 94.5007 -268.517878)
		)
		(stroke
			(width 0)
			(type solid)
		)
		(fill yes)
		(layer "In6.Cu")
		(net "M_C_CPU1_SA_DQ<13>")
	)
	(gr_poly
		(pts
			(xy 94.54769 -263.891014) (xy 94.5007 -263.738614) (xy 94.23908 -263.738614) (xy 94.19209 -263.891014)
			(xy 94.19209 -263.93521) (xy 94.54769 -263.93521)
		)
		(stroke
			(width 0)
			(type solid)
		)
		(fill yes)
		(layer "In6.Cu")
		(net "M_C_CPU1_SA_DQ<30>")
	)
	(gr_poly
		(pts
			(xy 94.54769 -259.00761) (xy 94.5007 -258.85521) (xy 94.23908 -258.85521) (xy 94.19209 -259.00761)
			(xy 94.19209 -259.051806) (xy 94.54769 -259.051806)
		)
		(stroke
			(width 0)
			(type solid)
		)
		(fill yes)
		(layer "In6.Cu")
		(net "M_C_CPU1_SA_CB<4>")
	)
	(gr_poly
		(pts
			(xy 94.54769 -258.59867) (xy 94.54769 -258.554474) (xy 94.19209 -258.554474) (xy 94.19209 -258.59867)
			(xy 94.23908 -258.75107) (xy 94.5007 -258.75107)
		)
		(stroke
			(width 0)
			(type solid)
		)
		(fill yes)
		(layer "In6.Cu")
		(net "M_C_CPU1_SA_CB<7>")
	)
	(gr_poly
		(pts
			(xy 94.55023 -274.876514) (xy 94.55023 -274.832318) (xy 94.19463 -274.832318) (xy 94.19463 -274.876514)
			(xy 94.24162 -275.028914) (xy 94.50324 -275.028914)
		)
		(stroke
			(width 0)
			(type solid)
		)
		(fill yes)
		(layer "In6.Cu")
		(net "M_D_CPU1_SA_DQS_DN<5>")
	)
	(gr_poly
		(pts
			(xy 94.55023 -272.029174) (xy 94.50324 -271.876774) (xy 94.24162 -271.876774) (xy 94.19463 -272.029174)
			(xy 94.19463 -272.073624) (xy 94.55023 -272.073624)
		)
		(stroke
			(width 0)
			(type solid)
		)
		(fill yes)
		(layer "In6.Cu")
		(net "M_C_CPU1_SA_DQ<10>")
	)
	(gr_poly
		(pts
			(xy 94.55023 -269.993618) (xy 94.55023 -269.949168) (xy 94.19463 -269.949168) (xy 94.19463 -269.993618)
			(xy 94.24162 -270.146018) (xy 94.50324 -270.146018)
		)
		(stroke
			(width 0)
			(type solid)
		)
		(fill yes)
		(layer "In6.Cu")
		(net "M_C_CPU1_SA_DQS_DN<6>")
	)
	(gr_poly
		(pts
			(xy 94.55023 -267.14577) (xy 94.50324 -266.99337) (xy 94.24162 -266.99337) (xy 94.19463 -267.14577)
			(xy 94.19463 -267.19022) (xy 94.55023 -267.19022)
		)
		(stroke
			(width 0)
			(type solid)
		)
		(fill yes)
		(layer "In6.Cu")
		(net "M_C_CPU1_SA_DQ<26>")
	)
	(gr_poly
		(pts
			(xy 94.55023 -266.737846) (xy 94.55023 -266.69365) (xy 94.19463 -266.69365) (xy 94.19463 -266.737846)
			(xy 94.24162 -266.890246) (xy 94.50324 -266.890246)
		)
		(stroke
			(width 0)
			(type solid)
		)
		(fill yes)
		(layer "In6.Cu")
		(net "M_C_CPU1_SA_DQ<25>")
	)
	(gr_poly
		(pts
			(xy 94.55023 -265.110214) (xy 94.55023 -265.065764) (xy 94.19463 -265.065764) (xy 94.19463 -265.110214)
			(xy 94.24162 -265.262614) (xy 94.50324 -265.262614)
		)
		(stroke
			(width 0)
			(type solid)
		)
		(fill yes)
		(layer "In6.Cu")
		(net "M_C_CPU1_SA_DQS_DN<8>")
	)
	(gr_poly
		(pts
			(xy 94.55023 -262.262874) (xy 94.50324 -262.110474) (xy 94.24162 -262.110474) (xy 94.19463 -262.262874)
			(xy 94.19463 -262.30707) (xy 94.55023 -262.30707)
		)
		(stroke
			(width 0)
			(type solid)
		)
		(fill yes)
		(layer "In6.Cu")
		(net "M_C_CPU1_SA_CB<0>")
	)
	(gr_poly
		(pts
			(xy 94.55023 -261.854442) (xy 94.55023 -261.810246) (xy 94.19463 -261.810246) (xy 94.19463 -261.854442)
			(xy 94.24162 -262.006842) (xy 94.50324 -262.006842)
		)
		(stroke
			(width 0)
			(type solid)
		)
		(fill yes)
		(layer "In6.Cu")
		(net "M_C_CPU1_SA_CB<3>")
	)
	(gr_poly
		(pts
			(xy 94.55023 -255.343406) (xy 94.55023 -255.29921) (xy 94.19463 -255.29921) (xy 94.19463 -255.343406)
			(xy 94.24162 -255.495806) (xy 94.50324 -255.495806)
		)
		(stroke
			(width 0)
			(type solid)
		)
		(fill yes)
		(layer "In6.Cu")
		(net "M_C_CPU1_SA_RSP<0>")
	)
	(gr_poly
		(pts
			(xy 94.621096 -254.184404) (xy 94.512638 -254.067564) (xy 94.474284 -254.045466) (xy 94.296484 -254.353314)
			(xy 94.334838 -254.375412) (xy 94.490286 -254.410972)
		)
		(stroke
			(width 0)
			(type solid)
		)
		(fill yes)
		(layer "In6.Cu")
		(net "M_C_CPU1_SA_RSP<1>")
	)
	(gr_poly
		(pts
			(xy 94.752922 -246.820182) (xy 94.791276 -246.798084) (xy 94.613476 -246.490236) (xy 94.575122 -246.512334)
			(xy 94.466664 -246.629174) (xy 94.597474 -246.855742)
		)
		(stroke
			(width 0)
			(type solid)
		)
		(fill yes)
		(layer "In6.Cu")
		(net "M_D_CPU1_SB_CS_N<2>")
	)
	(gr_poly
		(pts
			(xy 94.868238 -246.209566) (xy 94.976696 -246.092726) (xy 94.845886 -245.866158) (xy 94.690438 -245.901718)
			(xy 94.652084 -245.923816) (xy 94.829884 -246.231664)
		)
		(stroke
			(width 0)
			(type solid)
		)
		(fill yes)
		(layer "In6.Cu")
		(net "M_D_CPU1_SB_CS_N<3>")
	)
	(gr_poly
		(pts
			(xy 94.89313 -247.787922) (xy 94.89313 -247.743726) (xy 94.53753 -247.743726) (xy 94.53753 -247.787922)
			(xy 94.58452 -247.940322) (xy 94.84614 -247.940322)
		)
		(stroke
			(width 0)
			(type solid)
		)
		(fill yes)
		(layer "In6.Cu")
		(net "M_A_CPU1_SA_RSP<1>")
	)
	(gr_poly
		(pts
			(xy 94.89313 -244.940582) (xy 94.84614 -244.788182) (xy 94.58452 -244.788182) (xy 94.53753 -244.940582)
			(xy 94.53753 -244.985032) (xy 94.89313 -244.985032)
		)
		(stroke
			(width 0)
			(type solid)
		)
		(fill yes)
		(layer "In6.Cu")
		(net "M_D_CPU1_SB_CS_N<1>")
	)
	(gr_poly
		(pts
			(xy 94.89313 -240.057178) (xy 94.84614 -239.904778) (xy 94.58452 -239.904778) (xy 94.53753 -240.057178)
			(xy 94.53753 -240.101628) (xy 94.89313 -240.101628)
		)
		(stroke
			(width 0)
			(type solid)
		)
		(fill yes)
		(layer "In6.Cu")
		(net "M_C_CPU1_SB_DQ<7>")
	)
	(gr_poly
		(pts
			(xy 94.89313 -235.174282) (xy 94.84614 -235.021882) (xy 94.58452 -235.021882) (xy 94.53753 -235.174282)
			(xy 94.53753 -235.218478) (xy 94.89313 -235.218478)
		)
		(stroke
			(width 0)
			(type solid)
		)
		(fill yes)
		(layer "In6.Cu")
		(net "M_C_CPU1_SB_DQ<15>")
	)
	(gr_poly
		(pts
			(xy 94.89313 -230.290878) (xy 94.84614 -230.138478) (xy 94.58452 -230.138478) (xy 94.53753 -230.290878)
			(xy 94.53753 -230.335074) (xy 94.89313 -230.335074)
		)
		(stroke
			(width 0)
			(type solid)
		)
		(fill yes)
		(layer "In6.Cu")
		(net "M_D_CPU1_SB_DQ<23>")
	)
	(gr_poly
		(pts
			(xy 94.89313 -225.407474) (xy 94.84614 -225.255074) (xy 94.58452 -225.255074) (xy 94.53753 -225.407474)
			(xy 94.53753 -225.45167) (xy 94.89313 -225.45167)
		)
		(stroke
			(width 0)
			(type solid)
		)
		(fill yes)
		(layer "In6.Cu")
		(net "M_C_CPU1_SB_DQ<29>")
	)
	(gr_poly
		(pts
			(xy 94.89567 -241.685318) (xy 94.84868 -241.532918) (xy 94.58706 -241.532918) (xy 94.54007 -241.685318)
			(xy 94.54007 -241.729768) (xy 94.89567 -241.729768)
		)
		(stroke
			(width 0)
			(type solid)
		)
		(fill yes)
		(layer "In6.Cu")
		(net "M_C_CPU1_SB_DQS_DP<5>")
	)
	(gr_poly
		(pts
			(xy 94.901512 -248.196354) (xy 94.854522 -248.043954) (xy 94.592902 -248.043954) (xy 94.545912 -248.196354)
			(xy 94.545912 -248.240804) (xy 94.901512 -248.240804)
		)
		(stroke
			(width 0)
			(type solid)
		)
		(fill yes)
		(layer "In6.Cu")
		(net "M_A_CPU1_SA_RSP<0>")
	)
	(gr_poly
		(pts
			(xy 94.901512 -244.53215) (xy 94.901512 -244.487954) (xy 94.545912 -244.487954) (xy 94.545912 -244.53215)
			(xy 94.592902 -244.68455) (xy 94.854522 -244.68455)
		)
		(stroke
			(width 0)
			(type solid)
		)
		(fill yes)
		(layer "In6.Cu")
		(net "M_C_CPU1_SB_DQ<0>")
	)
	(gr_poly
		(pts
			(xy 94.901512 -234.76585) (xy 94.901512 -234.7214) (xy 94.545912 -234.7214) (xy 94.545912 -234.76585)
			(xy 94.592902 -234.91825) (xy 94.854522 -234.91825)
		)
		(stroke
			(width 0)
			(type solid)
		)
		(fill yes)
		(layer "In6.Cu")
		(net "M_D_CPU1_SB_DQ<16>")
	)
	(gr_poly
		(pts
			(xy 94.901512 -229.882446) (xy 94.901512 -229.837996) (xy 94.545912 -229.837996) (xy 94.545912 -229.882446)
			(xy 94.592902 -230.034846) (xy 94.854522 -230.034846)
		)
		(stroke
			(width 0)
			(type solid)
		)
		(fill yes)
		(layer "In6.Cu")
		(net "M_C_CPU1_SB_DQ<26>")
	)
	(gr_poly
		(pts
			(xy 95.002858 -253.309882) (xy 94.955868 -253.157482) (xy 94.694248 -253.157482) (xy 94.647258 -253.309882)
			(xy 94.647258 -253.354332) (xy 95.002858 -253.354332)
		)
		(stroke
			(width 0)
			(type solid)
		)
		(fill yes)
		(layer "In6.Cu")
		(net "M_C_CPU1_SB_RSP<1>")
	)
	(gr_poly
		(pts
			(xy 95.003112 -272.435066) (xy 95.003112 -272.39087) (xy 94.647512 -272.39087) (xy 94.647512 -272.435066)
			(xy 94.694502 -272.587466) (xy 94.956122 -272.587466)
		)
		(stroke
			(width 0)
			(type solid)
		)
		(fill yes)
		(layer "In6.Cu")
		(net "M_C_CPU1_SA_DQ<8>")
	)
	(gr_poly
		(pts
			(xy 95.003112 -267.551662) (xy 95.003112 -267.507466) (xy 94.647512 -267.507466) (xy 94.647512 -267.551662)
			(xy 94.694502 -267.704062) (xy 94.956122 -267.704062)
		)
		(stroke
			(width 0)
			(type solid)
		)
		(fill yes)
		(layer "In6.Cu")
		(net "M_C_CPU1_SA_DQ<24>")
	)
	(gr_poly
		(pts
			(xy 95.003112 -262.668258) (xy 95.003112 -262.624062) (xy 94.647512 -262.624062) (xy 94.647512 -262.668258)
			(xy 94.694502 -262.820658) (xy 94.956122 -262.820658)
		)
		(stroke
			(width 0)
			(type solid)
		)
		(fill yes)
		(layer "In6.Cu")
		(net "M_C_CPU1_SA_CB<2>")
	)
	(gr_poly
		(pts
			(xy 95.005652 -256.565654) (xy 94.958662 -256.413254) (xy 94.697042 -256.413254) (xy 94.650052 -256.565654)
			(xy 94.650052 -256.610104) (xy 95.005652 -256.610104)
		)
		(stroke
			(width 0)
			(type solid)
		)
		(fill yes)
		(layer "In6.Cu")
		(net "M_D_CPU1_SB_RSP<0>")
	)
	(gr_poly
		(pts
			(xy 95.011494 -272.843498) (xy 94.964504 -272.691098) (xy 94.702884 -272.691098) (xy 94.655894 -272.843498)
			(xy 94.655894 -272.887948) (xy 95.011494 -272.887948)
		)
		(stroke
			(width 0)
			(type solid)
		)
		(fill yes)
		(layer "In6.Cu")
		(net "M_D_CPU1_SA_DQ<7>")
	)
	(gr_poly
		(pts
			(xy 95.011494 -267.960094) (xy 94.964504 -267.807694) (xy 94.702884 -267.807694) (xy 94.655894 -267.960094)
			(xy 94.655894 -268.004544) (xy 95.011494 -268.004544)
		)
		(stroke
			(width 0)
			(type solid)
		)
		(fill yes)
		(layer "In6.Cu")
		(net "M_C_CPU1_SA_DQ<15>")
	)
	(gr_poly
		(pts
			(xy 95.011494 -258.193286) (xy 94.964504 -258.040886) (xy 94.702884 -258.040886) (xy 94.655894 -258.193286)
			(xy 94.655894 -258.237736) (xy 95.011494 -258.237736)
		)
		(stroke
			(width 0)
			(type solid)
		)
		(fill yes)
		(layer "In6.Cu")
		(net "M_C_CPU1_SA_CB<5>")
	)
	(gr_poly
		(pts
			(xy 95.011748 -277.317962) (xy 95.011748 -277.273766) (xy 94.656148 -277.273766) (xy 94.656148 -277.317962)
			(xy 94.703138 -277.470362) (xy 94.964758 -277.470362)
		)
		(stroke
			(width 0)
			(type solid)
		)
		(fill yes)
		(layer "In6.Cu")
		(net "M_D_CPU1_SA_DQ<0>")
	)
	(gr_poly
		(pts
			(xy 95.01505 -263.077198) (xy 94.96806 -262.924798) (xy 94.70644 -262.924798) (xy 94.65945 -263.077198)
			(xy 94.65945 -263.121394) (xy 95.01505 -263.121394)
		)
		(stroke
			(width 0)
			(type solid)
		)
		(fill yes)
		(layer "In6.Cu")
		(net "M_C_CPU1_SA_DQ<31>")
	)
	(gr_poly
		(pts
			(xy 95.019876 -261.040626) (xy 95.019876 -260.99643) (xy 94.664276 -260.99643) (xy 94.664276 -261.040626)
			(xy 94.711266 -261.193026) (xy 94.972886 -261.193026)
		)
		(stroke
			(width 0)
			(type solid)
		)
		(fill yes)
		(layer "In6.Cu")
		(net "M_C_CPU1_SA_DQS_DN<9>")
	)
	(gr_poly
		(pts
			(xy 95.332804 -259.258562) (xy 95.371158 -259.236464) (xy 95.193358 -258.928616) (xy 95.155004 -258.950714)
			(xy 95.046546 -259.067554) (xy 95.177356 -259.294122)
		)
		(stroke
			(width 0)
			(type solid)
		)
		(fill yes)
		(layer "In6.Cu")
		(net "M_C_CPU1_SA_CB<7>")
	)
	(gr_poly
		(pts
			(xy 95.337122 -225.860356) (xy 95.44558 -225.743516) (xy 95.31477 -225.516948) (xy 95.159322 -225.552508)
			(xy 95.120968 -225.574606) (xy 95.298768 -225.882454)
		)
		(stroke
			(width 0)
			(type solid)
		)
		(fill yes)
		(layer "In6.Cu")
		(net "M_C_CPU1_SB_DQ<29>")
	)
	(gr_poly
		(pts
			(xy 95.377508 -248.602246) (xy 95.377508 -248.557796) (xy 95.021908 -248.557796) (xy 95.021908 -248.602246)
			(xy 95.068898 -248.754646) (xy 95.330518 -248.754646)
		)
		(stroke
			(width 0)
			(type solid)
		)
		(fill yes)
		(layer "In6.Cu")
		(net "M_A_CPU1_SB_RSP<0>")
	)
	(gr_poly
		(pts
			(xy 95.380048 -247.382538) (xy 95.333058 -247.230138) (xy 95.071438 -247.230138) (xy 95.024448 -247.382538)
			(xy 95.024448 -247.426734) (xy 95.380048 -247.426734)
		)
		(stroke
			(width 0)
			(type solid)
		)
		(fill yes)
		(layer "In6.Cu")
		(net "M_A_CPU1_SB_RSP<1>")
	)
	(gr_poly
		(pts
			(xy 95.380048 -246.974106) (xy 95.380048 -246.92991) (xy 95.024448 -246.92991) (xy 95.024448 -246.974106)
			(xy 95.071438 -247.126506) (xy 95.333058 -247.126506)
		)
		(stroke
			(width 0)
			(type solid)
		)
		(fill yes)
		(layer "In6.Cu")
		(net "M_D_CPU1_SB_CS_N<2>")
	)
	(gr_poly
		(pts
			(xy 95.380048 -240.46307) (xy 95.380048 -240.418874) (xy 95.024448 -240.418874) (xy 95.024448 -240.46307)
			(xy 95.071438 -240.61547) (xy 95.333058 -240.61547)
		)
		(stroke
			(width 0)
			(type solid)
		)
		(fill yes)
		(layer "In6.Cu")
		(net "M_C_CPU1_SB_DQ<5>")
	)
	(gr_poly
		(pts
			(xy 95.448628 -258.648962) (xy 95.557086 -258.532122) (xy 95.426276 -258.305554) (xy 95.270828 -258.341114)
			(xy 95.232474 -258.363212) (xy 95.410274 -258.67106)
		)
		(stroke
			(width 0)
			(type solid)
		)
		(fill yes)
		(layer "In6.Cu")
		(net "M_C_CPU1_SA_CB<5>")
	)
	(gr_poly
		(pts
			(xy 95.473012 -273.657314) (xy 95.426022 -273.504914) (xy 95.164402 -273.504914) (xy 95.117412 -273.657314)
			(xy 95.117412 -273.70151) (xy 95.473012 -273.70151)
		)
		(stroke
			(width 0)
			(type solid)
		)
		(fill yes)
		(layer "In6.Cu")
		(net "M_D_CPU1_SA_DQ<6>")
	)
	(gr_poly
		(pts
			(xy 95.473012 -268.77391) (xy 95.426022 -268.62151) (xy 95.164402 -268.62151) (xy 95.117412 -268.77391)
			(xy 95.117412 -268.818106) (xy 95.473012 -268.818106)
		)
		(stroke
			(width 0)
			(type solid)
		)
		(fill yes)
		(layer "In6.Cu")
		(net "M_C_CPU1_SA_DQ<14>")
	)
	(gr_poly
		(pts
			(xy 95.481648 -254.124206) (xy 95.434658 -253.971806) (xy 95.173038 -253.971806) (xy 95.126048 -254.124206)
			(xy 95.126048 -254.168402) (xy 95.481648 -254.168402)
		)
		(stroke
			(width 0)
			(type solid)
		)
		(fill yes)
		(layer "In6.Cu")
		(net "M_C_CPU1_SB_RSP<0>")
	)
	(gr_poly
		(pts
			(xy 95.48749 -273.248882) (xy 95.48749 -273.204686) (xy 95.13189 -273.204686) (xy 95.13189 -273.248882)
			(xy 95.17888 -273.401282) (xy 95.4405 -273.401282)
		)
		(stroke
			(width 0)
			(type solid)
		)
		(fill yes)
		(layer "In6.Cu")
		(net "M_D_CPU1_SA_DQ<5>")
	)
	(gr_poly
		(pts
			(xy 95.48749 -268.365478) (xy 95.48749 -268.321282) (xy 95.13189 -268.321282) (xy 95.13189 -268.365478)
			(xy 95.17888 -268.517878) (xy 95.4405 -268.517878)
		)
		(stroke
			(width 0)
			(type solid)
		)
		(fill yes)
		(layer "In6.Cu")
		(net "M_C_CPU1_SA_DQ<13>")
	)
	(gr_poly
		(pts
			(xy 95.489776 -253.715774) (xy 95.489776 -253.671324) (xy 95.134176 -253.671324) (xy 95.134176 -253.715774)
			(xy 95.181166 -253.868174) (xy 95.442786 -253.868174)
		)
		(stroke
			(width 0)
			(type solid)
		)
		(fill yes)
		(layer "In6.Cu")
		(net "M_C_CPU1_SA_RSP<1>")
	)
	(gr_poly
		(pts
			(xy 95.49003 -274.876514) (xy 95.49003 -274.832318) (xy 95.13443 -274.832318) (xy 95.13443 -274.876514)
			(xy 95.18142 -275.028914) (xy 95.44304 -275.028914)
		)
		(stroke
			(width 0)
			(type solid)
		)
		(fill yes)
		(layer "In6.Cu")
		(net "M_D_CPU1_SA_DQS_DN<5>")
	)
	(gr_poly
		(pts
			(xy 95.49003 -262.262874) (xy 95.44304 -262.110474) (xy 95.18142 -262.110474) (xy 95.13443 -262.262874)
			(xy 95.13443 -262.30707) (xy 95.49003 -262.30707)
		)
		(stroke
			(width 0)
			(type solid)
		)
		(fill yes)
		(layer "In6.Cu")
		(net "M_C_CPU1_SA_CB<0>")
	)
	(gr_poly
		(pts
			(xy 95.49003 -261.854442) (xy 95.49003 -261.810246) (xy 95.13443 -261.810246) (xy 95.13443 -261.854442)
			(xy 95.18142 -262.006842) (xy 95.44304 -262.006842)
		)
		(stroke
			(width 0)
			(type solid)
		)
		(fill yes)
		(layer "In6.Cu")
		(net "M_C_CPU1_SA_CB<3>")
	)
	(gr_poly
		(pts
			(xy 95.49003 -256.971038) (xy 95.49003 -256.926842) (xy 95.13443 -256.926842) (xy 95.13443 -256.971038)
			(xy 95.18142 -257.123438) (xy 95.44304 -257.123438)
		)
		(stroke
			(width 0)
			(type solid)
		)
		(fill yes)
		(layer "In6.Cu")
		(net "M_D_CPU1_SA_RSP<0>")
	)
	(gr_poly
		(pts
			(xy 95.49003 -255.751838) (xy 95.44304 -255.599438) (xy 95.18142 -255.599438) (xy 95.13443 -255.751838)
			(xy 95.13443 -255.796034) (xy 95.49003 -255.796034)
		)
		(stroke
			(width 0)
			(type solid)
		)
		(fill yes)
		(layer "In6.Cu")
		(net "M_D_CPU1_SB_RSP<1>")
	)
	(gr_poly
		(pts
			(xy 95.731076 -245.930928) (xy 95.692722 -245.90883) (xy 95.537274 -245.87327) (xy 95.406464 -246.099838)
			(xy 95.514922 -246.216678) (xy 95.553276 -246.238776)
		)
		(stroke
			(width 0)
			(type solid)
		)
		(fill yes)
		(layer "In6.Cu")
		(net "M_D_CPU1_SB_CS_N<3>")
	)
	(gr_poly
		(pts
			(xy 95.83293 -241.685318) (xy 95.78594 -241.532918) (xy 95.52432 -241.532918) (xy 95.47733 -241.685318)
			(xy 95.47733 -241.729514) (xy 95.83293 -241.729514)
		)
		(stroke
			(width 0)
			(type solid)
		)
		(fill yes)
		(layer "In6.Cu")
		(net "M_C_CPU1_SB_DQS_DP<5>")
	)
	(gr_poly
		(pts
			(xy 95.83293 -240.057178) (xy 95.78594 -239.904778) (xy 95.52432 -239.904778) (xy 95.47733 -240.057178)
			(xy 95.47733 -240.101628) (xy 95.83293 -240.101628)
		)
		(stroke
			(width 0)
			(type solid)
		)
		(fill yes)
		(layer "In6.Cu")
		(net "M_C_CPU1_SB_DQ<7>")
	)
	(gr_poly
		(pts
			(xy 95.83547 -248.196354) (xy 95.78848 -248.043954) (xy 95.52686 -248.043954) (xy 95.47987 -248.196354)
			(xy 95.47987 -248.24055) (xy 95.83547 -248.24055)
		)
		(stroke
			(width 0)
			(type solid)
		)
		(fill yes)
		(layer "In6.Cu")
		(net "M_A_CPU1_SA_RSP<0>")
	)
	(gr_poly
		(pts
			(xy 95.83547 -247.787922) (xy 95.83547 -247.743726) (xy 95.47987 -247.743726) (xy 95.47987 -247.787922)
			(xy 95.52686 -247.940322) (xy 95.78848 -247.940322)
		)
		(stroke
			(width 0)
			(type solid)
		)
		(fill yes)
		(layer "In6.Cu")
		(net "M_A_CPU1_SA_RSP<1>")
	)
	(gr_poly
		(pts
			(xy 95.915226 -246.638826) (xy 95.806768 -246.521986) (xy 95.768414 -246.499888) (xy 95.590614 -246.807736)
			(xy 95.628968 -246.829834) (xy 95.784416 -246.865394)
		)
		(stroke
			(width 0)
			(type solid)
		)
		(fill yes)
		(layer "In6.Cu")
		(net "M_D_CPU1_SB_CS_N<2>")
	)
	(gr_poly
		(pts
			(xy 95.942912 -262.668258) (xy 95.942912 -262.624062) (xy 95.587312 -262.624062) (xy 95.587312 -262.668258)
			(xy 95.634302 -262.820658) (xy 95.895922 -262.820658)
		)
		(stroke
			(width 0)
			(type solid)
		)
		(fill yes)
		(layer "In6.Cu")
		(net "M_C_CPU1_SA_CB<2>")
	)
	(gr_poly
		(pts
			(xy 95.942912 -256.565654) (xy 95.895922 -256.413254) (xy 95.634302 -256.413254) (xy 95.587312 -256.565654)
			(xy 95.587312 -256.60985) (xy 95.942912 -256.60985)
		)
		(stroke
			(width 0)
			(type solid)
		)
		(fill yes)
		(layer "In6.Cu")
		(net "M_D_CPU1_SB_RSP<0>")
	)
	(gr_poly
		(pts
			(xy 95.942912 -253.309882) (xy 95.895922 -253.157482) (xy 95.634302 -253.157482) (xy 95.587312 -253.309882)
			(xy 95.587312 -253.354332) (xy 95.942912 -253.354332)
		)
		(stroke
			(width 0)
			(type solid)
		)
		(fill yes)
		(layer "In6.Cu")
		(net "M_C_CPU1_SB_RSP<1>")
	)
	(gr_poly
		(pts
			(xy 96.30537 -247.382538) (xy 96.25838 -247.230138) (xy 95.99676 -247.230138) (xy 95.94977 -247.382538)
			(xy 95.94977 -247.426988) (xy 96.30537 -247.426988)
		)
		(stroke
			(width 0)
			(type solid)
		)
		(fill yes)
		(layer "In6.Cu")
		(net "M_A_CPU1_SB_RSP<1>")
	)
	(gr_poly
		(pts
			(xy 96.311466 -248.601738) (xy 96.311466 -248.557542) (xy 95.955866 -248.557542) (xy 95.955866 -248.601738)
			(xy 96.002856 -248.754138) (xy 96.264476 -248.754138)
		)
		(stroke
			(width 0)
			(type solid)
		)
		(fill yes)
		(layer "In6.Cu")
		(net "M_A_CPU1_SB_RSP<0>")
	)
	(gr_poly
		(pts
			(xy 96.77527 -248.196354) (xy 96.72828 -248.043954) (xy 96.46666 -248.043954) (xy 96.41967 -248.196354)
			(xy 96.41967 -248.240804) (xy 96.77527 -248.240804)
		)
		(stroke
			(width 0)
			(type solid)
		)
		(fill yes)
		(layer "In6.Cu")
		(net "M_A_CPU1_SA_RSP<0>")
	)
	(gr_poly
		(pts
			(xy 96.787208 -247.787922) (xy 96.787208 -247.743472) (xy 96.431608 -247.743472) (xy 96.431608 -247.787922)
			(xy 96.478598 -247.940322) (xy 96.740218 -247.940322)
		)
		(stroke
			(width 0)
			(type solid)
		)
		(fill yes)
		(layer "In6.Cu")
		(net "M_A_CPU1_SA_RSP<1>")
	)
	(gr_poly
		(pts
			(xy 97.257108 -247.382538) (xy 97.210118 -247.230138) (xy 96.948498 -247.230138) (xy 96.901508 -247.382538)
			(xy 96.901508 -247.426734) (xy 97.257108 -247.426734)
		)
		(stroke
			(width 0)
			(type solid)
		)
		(fill yes)
		(layer "In6.Cu")
		(net "M_A_CPU1_SB_RSP<1>")
	)
	(gr_poly
		(pts
			(xy 97.259648 -248.602246) (xy 97.259648 -248.557796) (xy 96.904048 -248.557796) (xy 96.904048 -248.602246)
			(xy 96.951038 -248.754646) (xy 97.212658 -248.754646)
		)
		(stroke
			(width 0)
			(type solid)
		)
		(fill yes)
		(layer "In6.Cu")
		(net "M_A_CPU1_SB_RSP<0>")
	)
	(gr_poly
		(pts
			(xy 97.71507 -248.196354) (xy 97.66808 -248.043954) (xy 97.40646 -248.043954) (xy 97.35947 -248.196354)
			(xy 97.35947 -248.24055) (xy 97.71507 -248.24055)
		)
		(stroke
			(width 0)
			(type solid)
		)
		(fill yes)
		(layer "In6.Cu")
		(net "M_A_CPU1_SA_RSP<0>")
	)
	(gr_poly
		(pts
			(xy 97.71507 -247.787922) (xy 97.71507 -247.743726) (xy 97.35947 -247.743726) (xy 97.35947 -247.787922)
			(xy 97.40646 -247.940322) (xy 97.66808 -247.940322)
		)
		(stroke
			(width 0)
			(type solid)
		)
		(fill yes)
		(layer "In6.Cu")
		(net "M_A_CPU1_SA_RSP<1>")
	)
	(gr_poly
		(pts
			(xy 98.18497 -247.382538) (xy 98.13798 -247.230138) (xy 97.87636 -247.230138) (xy 97.82937 -247.382538)
			(xy 97.82937 -247.426988) (xy 98.18497 -247.426988)
		)
		(stroke
			(width 0)
			(type solid)
		)
		(fill yes)
		(layer "In6.Cu")
		(net "M_A_CPU1_SB_RSP<1>")
	)
	(gr_poly
		(pts
			(xy 98.191066 -248.601738) (xy 98.191066 -248.557542) (xy 97.835466 -248.557542) (xy 97.835466 -248.601738)
			(xy 97.882456 -248.754138) (xy 98.144076 -248.754138)
		)
		(stroke
			(width 0)
			(type solid)
		)
		(fill yes)
		(layer "In6.Cu")
		(net "M_A_CPU1_SB_RSP<0>")
	)
	(gr_poly
		(pts
			(xy 98.65487 -248.196354) (xy 98.60788 -248.043954) (xy 98.34626 -248.043954) (xy 98.29927 -248.196354)
			(xy 98.29927 -248.240804) (xy 98.65487 -248.240804)
		)
		(stroke
			(width 0)
			(type solid)
		)
		(fill yes)
		(layer "In6.Cu")
		(net "M_A_CPU1_SA_RSP<0>")
	)
	(gr_poly
		(pts
			(xy 98.666808 -247.787922) (xy 98.666808 -247.743472) (xy 98.311208 -247.743472) (xy 98.311208 -247.787922)
			(xy 98.358198 -247.940322) (xy 98.619818 -247.940322)
		)
		(stroke
			(width 0)
			(type solid)
		)
		(fill yes)
		(layer "In6.Cu")
		(net "M_A_CPU1_SA_RSP<1>")
	)
	(gr_poly
		(pts
			(xy 99.136708 -247.382538) (xy 99.089718 -247.230138) (xy 98.828098 -247.230138) (xy 98.781108 -247.382538)
			(xy 98.781108 -247.426734) (xy 99.136708 -247.426734)
		)
		(stroke
			(width 0)
			(type solid)
		)
		(fill yes)
		(layer "In6.Cu")
		(net "M_A_CPU1_SB_RSP<1>")
	)
	(gr_poly
		(pts
			(xy 99.139248 -248.602246) (xy 99.139248 -248.557796) (xy 98.783648 -248.557796) (xy 98.783648 -248.602246)
			(xy 98.830638 -248.754646) (xy 99.092258 -248.754646)
		)
		(stroke
			(width 0)
			(type solid)
		)
		(fill yes)
		(layer "In6.Cu")
		(net "M_A_CPU1_SB_RSP<0>")
	)
	(gr_poly
		(pts
			(xy 99.59213 -248.196354) (xy 99.54514 -248.043954) (xy 99.28352 -248.043954) (xy 99.23653 -248.196354)
			(xy 99.23653 -248.24055) (xy 99.59213 -248.24055)
		)
		(stroke
			(width 0)
			(type solid)
		)
		(fill yes)
		(layer "In6.Cu")
		(net "M_A_CPU1_SA_RSP<0>")
	)
	(gr_poly
		(pts
			(xy 99.59213 -247.787922) (xy 99.59213 -247.743726) (xy 99.23653 -247.743726) (xy 99.23653 -247.787922)
			(xy 99.28352 -247.940322) (xy 99.54514 -247.940322)
		)
		(stroke
			(width 0)
			(type solid)
		)
		(fill yes)
		(layer "In6.Cu")
		(net "M_A_CPU1_SA_RSP<1>")
	)
	(gr_poly
		(pts
			(xy 99.965764 -246.735092) (xy 99.92741 -246.712994) (xy 99.771962 -246.677434) (xy 99.641152 -246.904002)
			(xy 99.74961 -247.020842) (xy 99.787964 -247.04294)
		)
		(stroke
			(width 0)
			(type solid)
		)
		(fill yes)
		(layer "In6.Cu")
		(net "M_A_CPU1_SB_RSP<1>")
	)
	(gr_poly
		(pts
			(xy 100.079048 -248.602246) (xy 100.079048 -248.557796) (xy 99.723448 -248.557796) (xy 99.723448 -248.602246)
			(xy 99.770438 -248.754646) (xy 100.032058 -248.754646)
		)
		(stroke
			(width 0)
			(type solid)
		)
		(fill yes)
		(layer "In6.Cu")
		(net "M_A_CPU1_SB_RSP<0>")
	)
	(gr_poly
		(pts
			(xy 100.149914 -247.44299) (xy 100.041456 -247.32615) (xy 100.003102 -247.304052) (xy 99.825302 -247.6119)
			(xy 99.863656 -247.633998) (xy 100.019104 -247.669558)
		)
		(stroke
			(width 0)
			(type solid)
		)
		(fill yes)
		(layer "In6.Cu")
		(net "M_A_CPU1_SA_RSP<1>")
	)
	(gr_poly
		(pts
			(xy 100.53447 -246.568722) (xy 100.48748 -246.416322) (xy 100.22586 -246.416322) (xy 100.17887 -246.568722)
			(xy 100.17887 -246.612918) (xy 100.53447 -246.612918)
		)
		(stroke
			(width 0)
			(type solid)
		)
		(fill yes)
		(layer "In6.Cu")
		(net "M_A_CPU1_SB_RSP<1>")
	)
	(gr_poly
		(pts
			(xy 101.010466 -246.974106) (xy 101.010466 -246.929656) (xy 100.654866 -246.929656) (xy 100.654866 -246.974106)
			(xy 100.701856 -247.126506) (xy 100.963476 -247.126506)
		)
		(stroke
			(width 0)
			(type solid)
		)
		(fill yes)
		(layer "In6.Cu")
		(net "M_A_CPU1_SA_RSP<1>")
	)
	(gr_poly
		(pts
			(xy 101.47427 -246.568722) (xy 101.42728 -246.416322) (xy 101.16566 -246.416322) (xy 101.11867 -246.568722)
			(xy 101.11867 -246.613172) (xy 101.47427 -246.613172)
		)
		(stroke
			(width 0)
			(type solid)
		)
		(fill yes)
		(layer "In6.Cu")
		(net "M_A_CPU1_SB_RSP<1>")
	)
	(gr_poly
		(pts
			(xy 101.921056 -247.030494) (xy 102.029514 -246.913654) (xy 101.898704 -246.687086) (xy 101.743256 -246.722646)
			(xy 101.704902 -246.744744) (xy 101.882702 -247.052592)
		)
		(stroke
			(width 0)
			(type solid)
		)
		(fill yes)
		(layer "In6.Cu")
		(net "M_A_CPU1_SB_RSP<1>")
	)
	(gr_poly
		(pts
			(xy 124.96927 -249.416062) (xy 124.96927 -249.371612) (xy 124.61367 -249.371612) (xy 124.61367 -249.416062)
			(xy 124.66066 -249.568462) (xy 124.92228 -249.568462)
		)
		(stroke
			(width 0)
			(type solid)
		)
		(fill yes)
		(layer "In6.Cu")
		(net "M_E_CPU1_SA_RSP<0>")
	)
	(gr_poly
		(pts
			(xy 125.453648 -248.602246) (xy 125.453648 -248.557796) (xy 125.098048 -248.557796) (xy 125.098048 -248.602246)
			(xy 125.145038 -248.754646) (xy 125.406658 -248.754646)
		)
		(stroke
			(width 0)
			(type solid)
		)
		(fill yes)
		(layer "In6.Cu")
		(net "M_E_CPU1_SA_RSP<1>")
	)
	(gr_poly
		(pts
			(xy 125.90907 -249.415554) (xy 125.90907 -249.371358) (xy 125.55347 -249.371358) (xy 125.55347 -249.415554)
			(xy 125.60046 -249.567954) (xy 125.86208 -249.567954)
		)
		(stroke
			(width 0)
			(type solid)
		)
		(fill yes)
		(layer "In6.Cu")
		(net "M_E_CPU1_SA_RSP<0>")
	)
	(gr_poly
		(pts
			(xy 126.385066 -248.601738) (xy 126.385066 -248.557542) (xy 126.029466 -248.557542) (xy 126.029466 -248.601738)
			(xy 126.076456 -248.754138) (xy 126.338076 -248.754138)
		)
		(stroke
			(width 0)
			(type solid)
		)
		(fill yes)
		(layer "In6.Cu")
		(net "M_E_CPU1_SA_RSP<1>")
	)
	(gr_poly
		(pts
			(xy 126.393448 -249.01017) (xy 126.346458 -248.85777) (xy 126.084838 -248.85777) (xy 126.037848 -249.01017)
			(xy 126.037848 -249.05462) (xy 126.393448 -249.05462)
		)
		(stroke
			(width 0)
			(type solid)
		)
		(fill yes)
		(layer "In6.Cu")
		(net "M_E_CPU1_SB_RSP<0>")
	)
	(gr_poly
		(pts
			(xy 126.84633 -249.416062) (xy 126.84633 -249.371612) (xy 126.49073 -249.371612) (xy 126.49073 -249.416062)
			(xy 126.53772 -249.568462) (xy 126.79934 -249.568462)
		)
		(stroke
			(width 0)
			(type solid)
		)
		(fill yes)
		(layer "In6.Cu")
		(net "M_E_CPU1_SA_RSP<0>")
	)
	(gr_poly
		(pts
			(xy 126.84887 -248.196354) (xy 126.80188 -248.043954) (xy 126.54026 -248.043954) (xy 126.49327 -248.196354)
			(xy 126.49327 -248.240804) (xy 126.84887 -248.240804)
		)
		(stroke
			(width 0)
			(type solid)
		)
		(fill yes)
		(layer "In6.Cu")
		(net "M_E_CPU1_SB_RSP<1>")
	)
	(gr_poly
		(pts
			(xy 127.333248 -249.01017) (xy 127.286258 -248.85777) (xy 127.024638 -248.85777) (xy 126.977648 -249.01017)
			(xy 126.977648 -249.05462) (xy 127.333248 -249.05462)
		)
		(stroke
			(width 0)
			(type solid)
		)
		(fill yes)
		(layer "In6.Cu")
		(net "M_E_CPU1_SB_RSP<0>")
	)
	(gr_poly
		(pts
			(xy 127.333248 -248.602246) (xy 127.333248 -248.557796) (xy 126.977648 -248.557796) (xy 126.977648 -248.602246)
			(xy 127.024638 -248.754646) (xy 127.286258 -248.754646)
		)
		(stroke
			(width 0)
			(type solid)
		)
		(fill yes)
		(layer "In6.Cu")
		(net "M_E_CPU1_SA_RSP<1>")
	)
	(gr_poly
		(pts
			(xy 127.78613 -249.416062) (xy 127.78613 -249.371612) (xy 127.43053 -249.371612) (xy 127.43053 -249.416062)
			(xy 127.47752 -249.568462) (xy 127.73914 -249.568462)
		)
		(stroke
			(width 0)
			(type solid)
		)
		(fill yes)
		(layer "In6.Cu")
		(net "M_E_CPU1_SA_RSP<0>")
	)
	(gr_poly
		(pts
			(xy 127.78613 -248.196354) (xy 127.73914 -248.043954) (xy 127.47752 -248.043954) (xy 127.43053 -248.196354)
			(xy 127.43053 -248.24055) (xy 127.78613 -248.24055)
		)
		(stroke
			(width 0)
			(type solid)
		)
		(fill yes)
		(layer "In6.Cu")
		(net "M_E_CPU1_SB_RSP<1>")
	)
	(gr_poly
		(pts
			(xy 127.78867 -244.53215) (xy 127.78867 -244.487954) (xy 127.43307 -244.487954) (xy 127.43307 -244.53215)
			(xy 127.48006 -244.68455) (xy 127.74168 -244.68455)
		)
		(stroke
			(width 0)
			(type solid)
		)
		(fill yes)
		(layer "In6.Cu")
		(net "M_H_CPU1_SB_CS_N<2>")
	)
	(gr_poly
		(pts
			(xy 128.273048 -249.01017) (xy 128.226058 -248.85777) (xy 127.964438 -248.85777) (xy 127.917448 -249.01017)
			(xy 127.917448 -249.05462) (xy 128.273048 -249.05462)
		)
		(stroke
			(width 0)
			(type solid)
		)
		(fill yes)
		(layer "In6.Cu")
		(net "M_E_CPU1_SB_RSP<0>")
	)
	(gr_poly
		(pts
			(xy 128.273048 -248.602246) (xy 128.273048 -248.557796) (xy 127.917448 -248.557796) (xy 127.917448 -248.602246)
			(xy 127.964438 -248.754646) (xy 128.226058 -248.754646)
		)
		(stroke
			(width 0)
			(type solid)
		)
		(fill yes)
		(layer "In6.Cu")
		(net "M_E_CPU1_SA_RSP<1>")
	)
	(gr_poly
		(pts
			(xy 128.273048 -243.718842) (xy 128.273048 -243.674392) (xy 127.917448 -243.674392) (xy 127.917448 -243.718842)
			(xy 127.964438 -243.871242) (xy 128.226058 -243.871242)
		)
		(stroke
			(width 0)
			(type solid)
		)
		(fill yes)
		(layer "In6.Cu")
		(net "M_H_CPU1_SB_CS_N<0>")
	)
	(gr_poly
		(pts
			(xy 128.273048 -242.090702) (xy 128.273048 -242.046506) (xy 127.917448 -242.046506) (xy 127.917448 -242.090702)
			(xy 127.964438 -242.243102) (xy 128.226058 -242.243102)
		)
		(stroke
			(width 0)
			(type solid)
		)
		(fill yes)
		(layer "In6.Cu")
		(net "M_G_CPU1_SB_DQ<0>")
	)
	(gr_poly
		(pts
			(xy 128.273048 -232.732326) (xy 128.226058 -232.579926) (xy 127.964438 -232.579926) (xy 127.917448 -232.732326)
			(xy 127.917448 -232.776776) (xy 128.273048 -232.776776)
		)
		(stroke
			(width 0)
			(type solid)
		)
		(fill yes)
		(layer "In6.Cu")
		(net "M_G_CPU1_SB_DQ<13>")
	)
	(gr_poly
		(pts
			(xy 128.37033 -265.109706) (xy 128.37033 -265.06551) (xy 128.01473 -265.06551) (xy 128.01473 -265.109706)
			(xy 128.06172 -265.262106) (xy 128.32334 -265.262106)
		)
		(stroke
			(width 0)
			(type solid)
		)
		(fill yes)
		(layer "In6.Cu")
		(net "M_G_CPU1_SA_CB<0>")
	)
	(gr_poly
		(pts
			(xy 128.38303 -274.876514) (xy 128.38303 -274.832318) (xy 128.02743 -274.832318) (xy 128.02743 -274.876514)
			(xy 128.07442 -275.028914) (xy 128.33604 -275.028914)
		)
		(stroke
			(width 0)
			(type solid)
		)
		(fill yes)
		(layer "In6.Cu")
		(net "M_G_CPU1_SA_DQ<8>")
	)
	(gr_poly
		(pts
			(xy 128.38303 -269.993618) (xy 128.38303 -269.949168) (xy 128.02743 -269.949168) (xy 128.02743 -269.993618)
			(xy 128.07442 -270.146018) (xy 128.33604 -270.146018)
		)
		(stroke
			(width 0)
			(type solid)
		)
		(fill yes)
		(layer "In6.Cu")
		(net "M_G_CPU1_SA_DQ<24>")
	)
	(gr_poly
		(pts
			(xy 128.72593 -249.416062) (xy 128.72593 -249.371612) (xy 128.37033 -249.371612) (xy 128.37033 -249.416062)
			(xy 128.41732 -249.568462) (xy 128.67894 -249.568462)
		)
		(stroke
			(width 0)
			(type solid)
		)
		(fill yes)
		(layer "In6.Cu")
		(net "M_E_CPU1_SA_RSP<0>")
	)
	(gr_poly
		(pts
			(xy 128.72593 -248.196354) (xy 128.67894 -248.043954) (xy 128.41732 -248.043954) (xy 128.37033 -248.196354)
			(xy 128.37033 -248.24055) (xy 128.72593 -248.24055)
		)
		(stroke
			(width 0)
			(type solid)
		)
		(fill yes)
		(layer "In6.Cu")
		(net "M_E_CPU1_SB_RSP<1>")
	)
	(gr_poly
		(pts
			(xy 128.72593 -244.532658) (xy 128.72593 -244.488208) (xy 128.37033 -244.488208) (xy 128.37033 -244.532658)
			(xy 128.41732 -244.685058) (xy 128.67894 -244.685058)
		)
		(stroke
			(width 0)
			(type solid)
		)
		(fill yes)
		(layer "In6.Cu")
		(net "M_H_CPU1_SB_CS_N<2>")
	)
	(gr_poly
		(pts
			(xy 128.72593 -243.31295) (xy 128.67894 -243.16055) (xy 128.41732 -243.16055) (xy 128.37033 -243.31295)
			(xy 128.37033 -243.3574) (xy 128.72593 -243.3574)
		)
		(stroke
			(width 0)
			(type solid)
		)
		(fill yes)
		(layer "In6.Cu")
		(net "M_H_CPU1_SB_CS_N<1>")
	)
	(gr_poly
		(pts
			(xy 128.72593 -233.546142) (xy 128.67894 -233.393742) (xy 128.41732 -233.393742) (xy 128.37033 -233.546142)
			(xy 128.37033 -233.590592) (xy 128.72593 -233.590592)
		)
		(stroke
			(width 0)
			(type solid)
		)
		(fill yes)
		(layer "In6.Cu")
		(net "M_G_CPU1_SB_DQ<12>")
	)
	(gr_poly
		(pts
			(xy 128.72593 -233.138218) (xy 128.72593 -233.093768) (xy 128.37033 -233.093768) (xy 128.37033 -233.138218)
			(xy 128.41732 -233.290618) (xy 128.67894 -233.290618)
		)
		(stroke
			(width 0)
			(type solid)
		)
		(fill yes)
		(layer "In6.Cu")
		(net "M_G_CPU1_SB_DQ<15>")
	)
	(gr_poly
		(pts
			(xy 128.72847 -241.685318) (xy 128.68148 -241.532918) (xy 128.41986 -241.532918) (xy 128.37287 -241.685318)
			(xy 128.37287 -241.729514) (xy 128.72847 -241.729514)
		)
		(stroke
			(width 0)
			(type solid)
		)
		(fill yes)
		(layer "In6.Cu")
		(net "M_G_CPU1_SB_DQ<2>")
	)
	(gr_poly
		(pts
			(xy 128.72847 -241.276886) (xy 128.72847 -241.23269) (xy 128.37287 -241.23269) (xy 128.37287 -241.276886)
			(xy 128.41986 -241.429286) (xy 128.68148 -241.429286)
		)
		(stroke
			(width 0)
			(type solid)
		)
		(fill yes)
		(layer "In6.Cu")
		(net "M_G_CPU1_SB_DQ<1>")
	)
	(gr_poly
		(pts
			(xy 128.734058 -270.577818) (xy 128.695704 -270.55572) (xy 128.540256 -270.52016) (xy 128.409446 -270.746728)
			(xy 128.517904 -270.863568) (xy 128.556258 -270.885666)
		)
		(stroke
			(width 0)
			(type solid)
		)
		(fill yes)
		(layer "In6.Cu")
		(net "M_G_CPU1_SA_DQ<15>")
	)
	(gr_poly
		(pts
			(xy 128.739392 -260.80212) (xy 128.701038 -260.780022) (xy 128.54559 -260.744462) (xy 128.41478 -260.97103)
			(xy 128.523238 -261.08787) (xy 128.561592 -261.109968)
		)
		(stroke
			(width 0)
			(type solid)
		)
		(fill yes)
		(layer "In6.Cu")
		(net "M_G_CPU1_SA_CB<7>")
	)
	(gr_poly
		(pts
			(xy 128.835912 -274.47113) (xy 128.788922 -274.31873) (xy 128.527302 -274.31873) (xy 128.480312 -274.47113)
			(xy 128.480312 -274.515326) (xy 128.835912 -274.515326)
		)
		(stroke
			(width 0)
			(type solid)
		)
		(fill yes)
		(layer "In6.Cu")
		(net "M_G_CPU1_SA_DQ<10>")
	)
	(gr_poly
		(pts
			(xy 128.84785 -264.29589) (xy 128.84785 -264.25144) (xy 128.49225 -264.25144) (xy 128.49225 -264.29589)
			(xy 128.53924 -264.44829) (xy 128.80086 -264.44829)
		)
		(stroke
			(width 0)
			(type solid)
		)
		(fill yes)
		(layer "In6.Cu")
		(net "M_G_CPU1_SA_CB<1>")
	)
	(gr_poly
		(pts
			(xy 128.850644 -269.178278) (xy 128.850644 -269.134082) (xy 128.495044 -269.134082) (xy 128.495044 -269.178278)
			(xy 128.542034 -269.330678) (xy 128.803654 -269.330678)
		)
		(stroke
			(width 0)
			(type solid)
		)
		(fill yes)
		(layer "In6.Cu")
		(net "M_G_CPU1_SA_DQ<25>")
	)
	(gr_poly
		(pts
			(xy 128.918208 -271.285716) (xy 128.80975 -271.168876) (xy 128.771396 -271.146778) (xy 128.593596 -271.454626)
			(xy 128.63195 -271.476724) (xy 128.787398 -271.512284)
		)
		(stroke
			(width 0)
			(type solid)
		)
		(fill yes)
		(layer "In6.Cu")
		(net "M_G_CPU1_SA_DQ<13>")
	)
	(gr_poly
		(pts
			(xy 129.093976 -227.211636) (xy 129.055622 -227.189538) (xy 128.900174 -227.153978) (xy 128.769364 -227.380546)
			(xy 128.877822 -227.497386) (xy 128.916176 -227.519484)
		)
		(stroke
			(width 0)
			(type solid)
		)
		(fill yes)
		(layer "In6.Cu")
		(net "M_H_CPU1_SB_DQ<23>")
	)
	(gr_poly
		(pts
			(xy 129.20091 -237.616238) (xy 129.15392 -237.463838) (xy 128.8923 -237.463838) (xy 128.84531 -237.616238)
			(xy 128.84531 -237.660434) (xy 129.20091 -237.660434)
		)
		(stroke
			(width 0)
			(type solid)
		)
		(fill yes)
		(layer "In6.Cu")
		(net "M_G_CPU1_SB_DQ<7>")
	)
	(gr_poly
		(pts
			(xy 129.204466 -242.090702) (xy 129.204466 -242.046252) (xy 128.848866 -242.046252) (xy 128.848866 -242.090702)
			(xy 128.895856 -242.243102) (xy 129.157476 -242.243102)
		)
		(stroke
			(width 0)
			(type solid)
		)
		(fill yes)
		(layer "In6.Cu")
		(net "M_G_CPU1_SB_DQ<0>")
	)
	(gr_poly
		(pts
			(xy 129.204466 -240.871502) (xy 129.157476 -240.719102) (xy 128.895856 -240.719102) (xy 128.848866 -240.871502)
			(xy 128.848866 -240.915952) (xy 129.204466 -240.915952)
		)
		(stroke
			(width 0)
			(type solid)
		)
		(fill yes)
		(layer "In6.Cu")
		(net "M_G_CPU1_SB_DQ<3>")
	)
	(gr_poly
		(pts
			(xy 129.204466 -237.207298) (xy 129.204466 -237.163102) (xy 128.848866 -237.163102) (xy 128.848866 -237.207298)
			(xy 128.895856 -237.359698) (xy 129.157476 -237.359698)
		)
		(stroke
			(width 0)
			(type solid)
		)
		(fill yes)
		(layer "In6.Cu")
		(net "M_G_CPU1_SB_DQ<8>")
	)
	(gr_poly
		(pts
			(xy 129.204466 -232.323894) (xy 129.204466 -232.279698) (xy 128.848866 -232.279698) (xy 128.848866 -232.323894)
			(xy 128.895856 -232.476294) (xy 129.157476 -232.476294)
		)
		(stroke
			(width 0)
			(type solid)
		)
		(fill yes)
		(layer "In6.Cu")
		(net "M_H_CPU1_SB_DQ<16>")
	)
	(gr_poly
		(pts
			(xy 129.210308 -249.010678) (xy 129.163318 -248.858278) (xy 128.901698 -248.858278) (xy 128.854708 -249.010678)
			(xy 128.854708 -249.054874) (xy 129.210308 -249.054874)
		)
		(stroke
			(width 0)
			(type solid)
		)
		(fill yes)
		(layer "In6.Cu")
		(net "M_E_CPU1_SB_RSP<0>")
	)
	(gr_poly
		(pts
			(xy 129.210308 -248.601738) (xy 129.210308 -248.557542) (xy 128.854708 -248.557542) (xy 128.854708 -248.601738)
			(xy 128.901698 -248.754138) (xy 129.163318 -248.754138)
		)
		(stroke
			(width 0)
			(type solid)
		)
		(fill yes)
		(layer "In6.Cu")
		(net "M_E_CPU1_SA_RSP<1>")
	)
	(gr_poly
		(pts
			(xy 129.210308 -243.718334) (xy 129.210308 -243.674138) (xy 128.854708 -243.674138) (xy 128.854708 -243.718334)
			(xy 128.901698 -243.870734) (xy 129.163318 -243.870734)
		)
		(stroke
			(width 0)
			(type solid)
		)
		(fill yes)
		(layer "In6.Cu")
		(net "M_H_CPU1_SB_CS_N<0>")
	)
	(gr_poly
		(pts
			(xy 129.212848 -240.46307) (xy 129.212848 -240.418874) (xy 128.857248 -240.418874) (xy 128.857248 -240.46307)
			(xy 128.904238 -240.61547) (xy 129.165858 -240.61547)
		)
		(stroke
			(width 0)
			(type solid)
		)
		(fill yes)
		(layer "In6.Cu")
		(net "M_G_CPU1_SB_DQS_DP<0>")
	)
	(gr_poly
		(pts
			(xy 129.212848 -232.732326) (xy 129.165858 -232.579926) (xy 128.904238 -232.579926) (xy 128.857248 -232.732326)
			(xy 128.857248 -232.776776) (xy 129.212848 -232.776776)
		)
		(stroke
			(width 0)
			(type solid)
		)
		(fill yes)
		(layer "In6.Cu")
		(net "M_G_CPU1_SB_DQ<13>")
	)
	(gr_poly
		(pts
			(xy 129.212848 -230.696262) (xy 129.212848 -230.652066) (xy 128.857248 -230.652066) (xy 128.857248 -230.696262)
			(xy 128.904238 -230.848662) (xy 129.165858 -230.848662)
		)
		(stroke
			(width 0)
			(type solid)
		)
		(fill yes)
		(layer "In6.Cu")
		(net "M_H_CPU1_SB_DQS_DP<2>")
	)
	(gr_poly
		(pts
			(xy 129.279904 -227.915978) (xy 129.171446 -227.799138) (xy 129.133092 -227.77704) (xy 128.955292 -228.084888)
			(xy 128.993646 -228.106986) (xy 129.149094 -228.142546)
		)
		(stroke
			(width 0)
			(type solid)
		)
		(fill yes)
		(layer "In6.Cu")
		(net "M_H_CPU1_SB_DQ<21>")
	)
	(gr_poly
		(pts
			(xy 129.31013 -265.109706) (xy 129.31013 -265.06551) (xy 128.95453 -265.06551) (xy 128.95453 -265.109706)
			(xy 129.00152 -265.262106) (xy 129.26314 -265.262106)
		)
		(stroke
			(width 0)
			(type solid)
		)
		(fill yes)
		(layer "In6.Cu")
		(net "M_G_CPU1_SA_CB<0>")
	)
	(gr_poly
		(pts
			(xy 129.310892 -265.518646) (xy 129.263902 -265.366246) (xy 129.002282 -265.366246) (xy 128.955292 -265.518646)
			(xy 128.955292 -265.563096) (xy 129.310892 -265.563096)
		)
		(stroke
			(width 0)
			(type solid)
		)
		(fill yes)
		(layer "In6.Cu")
		(net "M_G_CPU1_SA_DQ<31>")
	)
	(gr_poly
		(pts
			(xy 129.314448 -275.284946) (xy 129.267458 -275.132546) (xy 129.005838 -275.132546) (xy 128.958848 -275.284946)
			(xy 128.958848 -275.329396) (xy 129.314448 -275.329396)
		)
		(stroke
			(width 0)
			(type solid)
		)
		(fill yes)
		(layer "In6.Cu")
		(net "M_H_CPU1_SA_DQ<7>")
	)
	(gr_poly
		(pts
			(xy 129.32283 -274.876514) (xy 129.32283 -274.832318) (xy 128.96723 -274.832318) (xy 128.96723 -274.876514)
			(xy 129.01422 -275.028914) (xy 129.27584 -275.028914)
		)
		(stroke
			(width 0)
			(type solid)
		)
		(fill yes)
		(layer "In6.Cu")
		(net "M_G_CPU1_SA_DQ<8>")
	)
	(gr_poly
		(pts
			(xy 129.32283 -270.401542) (xy 129.27584 -270.249142) (xy 129.01422 -270.249142) (xy 128.96723 -270.401542)
			(xy 128.96723 -270.445992) (xy 129.32283 -270.445992)
		)
		(stroke
			(width 0)
			(type solid)
		)
		(fill yes)
		(layer "In6.Cu")
		(net "M_G_CPU1_SA_DQ<15>")
	)
	(gr_poly
		(pts
			(xy 129.32283 -269.993618) (xy 129.32283 -269.949168) (xy 128.96723 -269.949168) (xy 128.96723 -269.993618)
			(xy 129.01422 -270.146018) (xy 129.27584 -270.146018)
		)
		(stroke
			(width 0)
			(type solid)
		)
		(fill yes)
		(layer "In6.Cu")
		(net "M_G_CPU1_SA_DQ<24>")
	)
	(gr_poly
		(pts
			(xy 129.32283 -268.365478) (xy 129.32283 -268.321282) (xy 128.96723 -268.321282) (xy 128.96723 -268.365478)
			(xy 129.01422 -268.517878) (xy 129.27584 -268.517878)
		)
		(stroke
			(width 0)
			(type solid)
		)
		(fill yes)
		(layer "In6.Cu")
		(net "M_G_CPU1_SA_DQS_DP<3>")
	)
	(gr_poly
		(pts
			(xy 129.32283 -260.634734) (xy 129.27584 -260.482334) (xy 129.01422 -260.482334) (xy 128.96723 -260.634734)
			(xy 128.96723 -260.679184) (xy 129.32283 -260.679184)
		)
		(stroke
			(width 0)
			(type solid)
		)
		(fill yes)
		(layer "In6.Cu")
		(net "M_G_CPU1_SA_CB<7>")
	)
	(gr_poly
		(pts
			(xy 129.56921 -228.016308) (xy 129.530856 -227.99421) (xy 129.375408 -227.95865) (xy 129.244598 -228.185218)
			(xy 129.353056 -228.302058) (xy 129.39141 -228.324156)
		)
		(stroke
			(width 0)
			(type solid)
		)
		(fill yes)
		(layer "In6.Cu")
		(net "M_H_CPU1_SB_DQ<22>")
	)
	(gr_poly
		(pts
			(xy 129.66573 -240.057178) (xy 129.61874 -239.904778) (xy 129.35712 -239.904778) (xy 129.31013 -240.057178)
			(xy 129.31013 -240.101628) (xy 129.66573 -240.101628)
		)
		(stroke
			(width 0)
			(type solid)
		)
		(fill yes)
		(layer "In6.Cu")
		(net "M_G_CPU1_SB_DQS_DN<0>")
	)
	(gr_poly
		(pts
			(xy 129.66573 -233.138218) (xy 129.66573 -233.093768) (xy 129.31013 -233.093768) (xy 129.31013 -233.138218)
			(xy 129.35712 -233.290618) (xy 129.61874 -233.290618)
		)
		(stroke
			(width 0)
			(type solid)
		)
		(fill yes)
		(layer "In6.Cu")
		(net "M_G_CPU1_SB_DQ<15>")
	)
	(gr_poly
		(pts
			(xy 129.66573 -230.290878) (xy 129.61874 -230.138478) (xy 129.35712 -230.138478) (xy 129.31013 -230.290878)
			(xy 129.31013 -230.335074) (xy 129.66573 -230.335074)
		)
		(stroke
			(width 0)
			(type solid)
		)
		(fill yes)
		(layer "In6.Cu")
		(net "M_H_CPU1_SB_DQS_DN<2>")
	)
	(gr_poly
		(pts
			(xy 129.66573 -227.035106) (xy 129.61874 -226.882706) (xy 129.35712 -226.882706) (xy 129.31013 -227.035106)
			(xy 129.31013 -227.079556) (xy 129.66573 -227.079556)
		)
		(stroke
			(width 0)
			(type solid)
		)
		(fill yes)
		(layer "In6.Cu")
		(net "M_H_CPU1_SB_DQ<23>")
	)
	(gr_poly
		(pts
			(xy 129.66827 -241.685318) (xy 129.62128 -241.532918) (xy 129.35966 -241.532918) (xy 129.31267 -241.685318)
			(xy 129.31267 -241.729768) (xy 129.66827 -241.729768)
		)
		(stroke
			(width 0)
			(type solid)
		)
		(fill yes)
		(layer "In6.Cu")
		(net "M_G_CPU1_SB_DQ<2>")
	)
	(gr_poly
		(pts
			(xy 129.66827 -241.276886) (xy 129.66827 -241.232436) (xy 129.31267 -241.232436) (xy 129.31267 -241.276886)
			(xy 129.35966 -241.429286) (xy 129.62128 -241.429286)
		)
		(stroke
			(width 0)
			(type solid)
		)
		(fill yes)
		(layer "In6.Cu")
		(net "M_G_CPU1_SB_DQ<1>")
	)
	(gr_poly
		(pts
			(xy 129.66827 -236.801914) (xy 129.62128 -236.649514) (xy 129.35966 -236.649514) (xy 129.31267 -236.801914)
			(xy 129.31267 -236.846364) (xy 129.66827 -236.846364)
		)
		(stroke
			(width 0)
			(type solid)
		)
		(fill yes)
		(layer "In6.Cu")
		(net "M_G_CPU1_SB_DQ<10>")
	)
	(gr_poly
		(pts
			(xy 129.66827 -236.393482) (xy 129.66827 -236.349286) (xy 129.31267 -236.349286) (xy 129.31267 -236.393482)
			(xy 129.35966 -236.545882) (xy 129.62128 -236.545882)
		)
		(stroke
			(width 0)
			(type solid)
		)
		(fill yes)
		(layer "In6.Cu")
		(net "M_G_CPU1_SB_DQ<11>")
	)
	(gr_poly
		(pts
			(xy 129.66827 -231.919018) (xy 129.62128 -231.766618) (xy 129.35966 -231.766618) (xy 129.31267 -231.919018)
			(xy 129.31267 -231.963214) (xy 129.66827 -231.963214)
		)
		(stroke
			(width 0)
			(type solid)
		)
		(fill yes)
		(layer "In6.Cu")
		(net "M_H_CPU1_SB_DQ<18>")
	)
	(gr_poly
		(pts
			(xy 129.66827 -231.510078) (xy 129.66827 -231.465882) (xy 129.31267 -231.465882) (xy 129.31267 -231.510078)
			(xy 129.35966 -231.662478) (xy 129.62128 -231.662478)
		)
		(stroke
			(width 0)
			(type solid)
		)
		(fill yes)
		(layer "In6.Cu")
		(net "M_H_CPU1_SB_DQ<17>")
	)
	(gr_poly
		(pts
			(xy 129.674112 -249.415554) (xy 129.674112 -249.371358) (xy 129.318512 -249.371358) (xy 129.318512 -249.415554)
			(xy 129.365502 -249.567954) (xy 129.627122 -249.567954)
		)
		(stroke
			(width 0)
			(type solid)
		)
		(fill yes)
		(layer "In6.Cu")
		(net "M_E_CPU1_SA_RSP<0>")
	)
	(gr_poly
		(pts
			(xy 129.674112 -248.196354) (xy 129.627122 -248.043954) (xy 129.365502 -248.043954) (xy 129.318512 -248.196354)
			(xy 129.318512 -248.240804) (xy 129.674112 -248.240804)
		)
		(stroke
			(width 0)
			(type solid)
		)
		(fill yes)
		(layer "In6.Cu")
		(net "M_E_CPU1_SB_RSP<1>")
	)
	(gr_poly
		(pts
			(xy 129.674112 -244.53215) (xy 129.674112 -244.487954) (xy 129.318512 -244.487954) (xy 129.318512 -244.53215)
			(xy 129.365502 -244.68455) (xy 129.627122 -244.68455)
		)
		(stroke
			(width 0)
			(type solid)
		)
		(fill yes)
		(layer "In6.Cu")
		(net "M_H_CPU1_SB_CS_N<2>")
	)
	(gr_poly
		(pts
			(xy 129.674112 -243.313458) (xy 129.627122 -243.161058) (xy 129.365502 -243.161058) (xy 129.318512 -243.313458)
			(xy 129.318512 -243.357654) (xy 129.674112 -243.357654)
		)
		(stroke
			(width 0)
			(type solid)
		)
		(fill yes)
		(layer "In6.Cu")
		(net "M_H_CPU1_SB_CS_N<1>")
	)
	(gr_poly
		(pts
			(xy 129.674112 -234.76585) (xy 129.674112 -234.7214) (xy 129.318512 -234.7214) (xy 129.318512 -234.76585)
			(xy 129.365502 -234.91825) (xy 129.627122 -234.91825)
		)
		(stroke
			(width 0)
			(type solid)
		)
		(fill yes)
		(layer "In6.Cu")
		(net "M_G_CPU1_SB_DQS_DP<1>")
	)
	(gr_poly
		(pts
			(xy 129.674112 -233.54665) (xy 129.627122 -233.39425) (xy 129.365502 -233.39425) (xy 129.318512 -233.54665)
			(xy 129.318512 -233.590846) (xy 129.674112 -233.590846)
		)
		(stroke
			(width 0)
			(type solid)
		)
		(fill yes)
		(layer "In6.Cu")
		(net "M_G_CPU1_SB_DQ<12>")
	)
	(gr_poly
		(pts
			(xy 129.677668 -238.021114) (xy 129.677668 -237.976664) (xy 129.322068 -237.976664) (xy 129.322068 -238.021114)
			(xy 129.369058 -238.173514) (xy 129.630678 -238.173514)
		)
		(stroke
			(width 0)
			(type solid)
		)
		(fill yes)
		(layer "In6.Cu")
		(net "M_G_CPU1_SB_DQ<5>")
	)
	(gr_poly
		(pts
			(xy 129.67843 -238.430054) (xy 129.63144 -238.277654) (xy 129.36982 -238.277654) (xy 129.32283 -238.430054)
			(xy 129.32283 -238.47425) (xy 129.67843 -238.47425)
		)
		(stroke
			(width 0)
			(type solid)
		)
		(fill yes)
		(layer "In6.Cu")
		(net "M_G_CPU1_SB_DQ<6>")
	)
	(gr_poly
		(pts
			(xy 129.749042 -228.73081) (xy 129.640584 -228.61397) (xy 129.60223 -228.591872) (xy 129.42443 -228.89972)
			(xy 129.462784 -228.921818) (xy 129.618232 -228.957378)
		)
		(stroke
			(width 0)
			(type solid)
		)
		(fill yes)
		(layer "In6.Cu")
		(net "M_H_CPU1_SB_DQ<20>")
	)
	(gr_poly
		(pts
			(xy 129.775712 -274.47113) (xy 129.728722 -274.31873) (xy 129.467102 -274.31873) (xy 129.420112 -274.47113)
			(xy 129.420112 -274.515326) (xy 129.775712 -274.515326)
		)
		(stroke
			(width 0)
			(type solid)
		)
		(fill yes)
		(layer "In6.Cu")
		(net "M_G_CPU1_SA_DQ<10>")
	)
	(gr_poly
		(pts
			(xy 129.775712 -272.843498) (xy 129.728722 -272.691098) (xy 129.467102 -272.691098) (xy 129.420112 -272.843498)
			(xy 129.420112 -272.887694) (xy 129.775712 -272.887694)
		)
		(stroke
			(width 0)
			(type solid)
		)
		(fill yes)
		(layer "In6.Cu")
		(net "M_G_CPU1_SA_DQS_DN<1>")
	)
	(gr_poly
		(pts
			(xy 129.775712 -270.807434) (xy 129.775712 -270.762984) (xy 129.420112 -270.762984) (xy 129.420112 -270.807434)
			(xy 129.467102 -270.959834) (xy 129.728722 -270.959834)
		)
		(stroke
			(width 0)
			(type solid)
		)
		(fill yes)
		(layer "In6.Cu")
		(net "M_G_CPU1_SA_DQ<13>")
	)
	(gr_poly
		(pts
			(xy 129.775712 -269.587726) (xy 129.728722 -269.435326) (xy 129.467102 -269.435326) (xy 129.420112 -269.587726)
			(xy 129.420112 -269.631922) (xy 129.775712 -269.631922)
		)
		(stroke
			(width 0)
			(type solid)
		)
		(fill yes)
		(layer "In6.Cu")
		(net "M_G_CPU1_SA_DQ<26>")
	)
	(gr_poly
		(pts
			(xy 129.775712 -267.960094) (xy 129.728722 -267.807694) (xy 129.467102 -267.807694) (xy 129.420112 -267.960094)
			(xy 129.420112 -268.00429) (xy 129.775712 -268.00429)
		)
		(stroke
			(width 0)
			(type solid)
		)
		(fill yes)
		(layer "In6.Cu")
		(net "M_G_CPU1_SA_DQS_DN<3>")
	)
	(gr_poly
		(pts
			(xy 129.775712 -261.449058) (xy 129.728722 -261.296658) (xy 129.467102 -261.296658) (xy 129.420112 -261.449058)
			(xy 129.420112 -261.493254) (xy 129.775712 -261.493254)
		)
		(stroke
			(width 0)
			(type solid)
		)
		(fill yes)
		(layer "In6.Cu")
		(net "M_G_CPU1_SA_CB<6>")
	)
	(gr_poly
		(pts
			(xy 129.775712 -261.040626) (xy 129.775712 -260.99643) (xy 129.420112 -260.99643) (xy 129.420112 -261.040626)
			(xy 129.467102 -261.193026) (xy 129.728722 -261.193026)
		)
		(stroke
			(width 0)
			(type solid)
		)
		(fill yes)
		(layer "In6.Cu")
		(net "M_G_CPU1_SA_CB<5>")
	)
	(gr_poly
		(pts
			(xy 129.778252 -277.726394) (xy 129.731262 -277.573994) (xy 129.469642 -277.573994) (xy 129.422652 -277.726394)
			(xy 129.422652 -277.770844) (xy 129.778252 -277.770844)
		)
		(stroke
			(width 0)
			(type solid)
		)
		(fill yes)
		(layer "In6.Cu")
		(net "M_H_CPU1_SA_DQS_DN<0>")
	)
	(gr_poly
		(pts
			(xy 129.778252 -276.09927) (xy 129.731262 -275.94687) (xy 129.469642 -275.94687) (xy 129.422652 -276.09927)
			(xy 129.422652 -276.143466) (xy 129.778252 -276.143466)
		)
		(stroke
			(width 0)
			(type solid)
		)
		(fill yes)
		(layer "In6.Cu")
		(net "M_H_CPU1_SA_DQ<6>")
	)
	(gr_poly
		(pts
			(xy 129.778252 -275.690584) (xy 129.778252 -275.646134) (xy 129.422652 -275.646134) (xy 129.422652 -275.690584)
			(xy 129.469642 -275.842984) (xy 129.731262 -275.842984)
		)
		(stroke
			(width 0)
			(type solid)
		)
		(fill yes)
		(layer "In6.Cu")
		(net "M_H_CPU1_SA_DQ<5>")
	)
	(gr_poly
		(pts
			(xy 129.778252 -265.923522) (xy 129.778252 -265.879326) (xy 129.422652 -265.879326) (xy 129.422652 -265.923522)
			(xy 129.469642 -266.075922) (xy 129.731262 -266.075922)
		)
		(stroke
			(width 0)
			(type solid)
		)
		(fill yes)
		(layer "In6.Cu")
		(net "M_G_CPU1_SA_DQ<29>")
	)
	(gr_poly
		(pts
			(xy 129.784094 -263.07669) (xy 129.737104 -262.92429) (xy 129.475484 -262.92429) (xy 129.428494 -263.07669)
			(xy 129.428494 -263.12114) (xy 129.784094 -263.12114)
		)
		(stroke
			(width 0)
			(type solid)
		)
		(fill yes)
		(layer "In6.Cu")
		(net "M_G_CPU1_SA_DQS_DN<4>")
	)
	(gr_poly
		(pts
			(xy 129.78765 -274.062698) (xy 129.78765 -274.018248) (xy 129.43205 -274.018248) (xy 129.43205 -274.062698)
			(xy 129.47904 -274.215098) (xy 129.74066 -274.215098)
		)
		(stroke
			(width 0)
			(type solid)
		)
		(fill yes)
		(layer "In6.Cu")
		(net "M_G_CPU1_SA_DQ<9>")
	)
	(gr_poly
		(pts
			(xy 129.78765 -271.215866) (xy 129.74066 -271.063466) (xy 129.47904 -271.063466) (xy 129.43205 -271.215866)
			(xy 129.43205 -271.260062) (xy 129.78765 -271.260062)
		)
		(stroke
			(width 0)
			(type solid)
		)
		(fill yes)
		(layer "In6.Cu")
		(net "M_G_CPU1_SA_DQ<14>")
	)
	(gr_poly
		(pts
			(xy 129.78765 -269.179294) (xy 129.78765 -269.134844) (xy 129.43205 -269.134844) (xy 129.43205 -269.179294)
			(xy 129.47904 -269.331694) (xy 129.74066 -269.331694)
		)
		(stroke
			(width 0)
			(type solid)
		)
		(fill yes)
		(layer "In6.Cu")
		(net "M_G_CPU1_SA_DQ<25>")
	)
	(gr_poly
		(pts
			(xy 129.78765 -266.332462) (xy 129.74066 -266.180062) (xy 129.47904 -266.180062) (xy 129.43205 -266.332462)
			(xy 129.43205 -266.376658) (xy 129.78765 -266.376658)
		)
		(stroke
			(width 0)
			(type solid)
		)
		(fill yes)
		(layer "In6.Cu")
		(net "M_G_CPU1_SA_DQ<30>")
	)
	(gr_poly
		(pts
			(xy 129.78765 -264.29589) (xy 129.78765 -264.25144) (xy 129.43205 -264.25144) (xy 129.43205 -264.29589)
			(xy 129.47904 -264.44829) (xy 129.74066 -264.44829)
		)
		(stroke
			(width 0)
			(type solid)
		)
		(fill yes)
		(layer "In6.Cu")
		(net "M_G_CPU1_SA_CB<1>")
	)
	(gr_poly
		(pts
			(xy 129.788412 -264.70483) (xy 129.741422 -264.55243) (xy 129.479802 -264.55243) (xy 129.432812 -264.70483)
			(xy 129.432812 -264.749026) (xy 129.788412 -264.749026)
		)
		(stroke
			(width 0)
			(type solid)
		)
		(fill yes)
		(layer "In6.Cu")
		(net "M_G_CPU1_SA_CB<2>")
	)
	(gr_poly
		(pts
			(xy 130.032252 -228.843332) (xy 129.993898 -228.821234) (xy 129.83845 -228.785674) (xy 129.70764 -229.012242)
			(xy 129.816098 -229.129082) (xy 129.854452 -229.15118)
		)
		(stroke
			(width 0)
			(type solid)
		)
		(fill yes)
		(layer "In6.Cu")
		(net "M_H_CPU1_SB_DQS_DP<7>")
	)
	(gr_poly
		(pts
			(xy 130.134614 -235.579158) (xy 130.134614 -235.534708) (xy 129.779014 -235.534708) (xy 129.779014 -235.579158)
			(xy 129.826004 -235.731558) (xy 130.087624 -235.731558)
		)
		(stroke
			(width 0)
			(type solid)
		)
		(fill yes)
		(layer "In6.Cu")
		(net "M_G_CPU1_SB_DQS_DN<6>")
	)
	(gr_poly
		(pts
			(xy 130.139948 -238.83493) (xy 130.139948 -238.790734) (xy 129.784348 -238.790734) (xy 129.784348 -238.83493)
			(xy 129.831338 -238.98733) (xy 130.092958 -238.98733)
		)
		(stroke
			(width 0)
			(type solid)
		)
		(fill yes)
		(layer "In6.Cu")
		(net "M_G_CPU1_SB_DQ<4>")
	)
	(gr_poly
		(pts
			(xy 130.139948 -233.951526) (xy 130.139948 -233.90733) (xy 129.784348 -233.90733) (xy 129.784348 -233.951526)
			(xy 129.831338 -234.103926) (xy 130.092958 -234.103926)
		)
		(stroke
			(width 0)
			(type solid)
		)
		(fill yes)
		(layer "In6.Cu")
		(net "M_G_CPU1_SB_DQ<14>")
	)
	(gr_poly
		(pts
			(xy 130.14071 -237.616238) (xy 130.09372 -237.463838) (xy 129.8321 -237.463838) (xy 129.78511 -237.616238)
			(xy 129.78511 -237.660434) (xy 130.14071 -237.660434)
		)
		(stroke
			(width 0)
			(type solid)
		)
		(fill yes)
		(layer "In6.Cu")
		(net "M_G_CPU1_SB_DQ<7>")
	)
	(gr_poly
		(pts
			(xy 130.144012 -239.24387) (xy 130.097022 -239.09147) (xy 129.835402 -239.09147) (xy 129.788412 -239.24387)
			(xy 129.788412 -239.28832) (xy 130.144012 -239.28832)
		)
		(stroke
			(width 0)
			(type solid)
		)
		(fill yes)
		(layer "In6.Cu")
		(net "M_G_CPU1_SB_DQS_DP<5>")
	)
	(gr_poly
		(pts
			(xy 130.150108 -249.01017) (xy 130.103118 -248.85777) (xy 129.841498 -248.85777) (xy 129.794508 -249.01017)
			(xy 129.794508 -249.05462) (xy 130.150108 -249.05462)
		)
		(stroke
			(width 0)
			(type solid)
		)
		(fill yes)
		(layer "In6.Cu")
		(net "M_E_CPU1_SB_RSP<0>")
	)
	(gr_poly
		(pts
			(xy 130.150108 -248.602246) (xy 130.150108 -248.557796) (xy 129.794508 -248.557796) (xy 129.794508 -248.602246)
			(xy 129.841498 -248.754646) (xy 130.103118 -248.754646)
		)
		(stroke
			(width 0)
			(type solid)
		)
		(fill yes)
		(layer "In6.Cu")
		(net "M_E_CPU1_SA_RSP<1>")
	)
	(gr_poly
		(pts
			(xy 130.150108 -244.126766) (xy 130.103118 -243.974366) (xy 129.841498 -243.974366) (xy 129.794508 -244.126766)
			(xy 129.794508 -244.171216) (xy 130.150108 -244.171216)
		)
		(stroke
			(width 0)
			(type solid)
		)
		(fill yes)
		(layer "In6.Cu")
		(net "M_H_CPU1_SB_CS_N<3>")
	)
	(gr_poly
		(pts
			(xy 130.150108 -243.718842) (xy 130.150108 -243.674392) (xy 129.794508 -243.674392) (xy 129.794508 -243.718842)
			(xy 129.841498 -243.871242) (xy 130.103118 -243.871242)
		)
		(stroke
			(width 0)
			(type solid)
		)
		(fill yes)
		(layer "In6.Cu")
		(net "M_H_CPU1_SB_CS_N<0>")
	)
	(gr_poly
		(pts
			(xy 130.150108 -234.360466) (xy 130.103118 -234.208066) (xy 129.841498 -234.208066) (xy 129.794508 -234.360466)
			(xy 129.794508 -234.404662) (xy 130.150108 -234.404662)
		)
		(stroke
			(width 0)
			(type solid)
		)
		(fill yes)
		(layer "In6.Cu")
		(net "M_G_CPU1_SB_DQS_DN<1>")
	)
	(gr_poly
		(pts
			(xy 130.152648 -242.090702) (xy 130.152648 -242.046506) (xy 129.797048 -242.046506) (xy 129.797048 -242.090702)
			(xy 129.844038 -242.243102) (xy 130.105658 -242.243102)
		)
		(stroke
			(width 0)
			(type solid)
		)
		(fill yes)
		(layer "In6.Cu")
		(net "M_G_CPU1_SB_DQ<0>")
	)
	(gr_poly
		(pts
			(xy 130.152648 -240.871502) (xy 130.105658 -240.719102) (xy 129.844038 -240.719102) (xy 129.797048 -240.871502)
			(xy 129.797048 -240.915698) (xy 130.152648 -240.915698)
		)
		(stroke
			(width 0)
			(type solid)
		)
		(fill yes)
		(layer "In6.Cu")
		(net "M_G_CPU1_SB_DQ<3>")
	)
	(gr_poly
		(pts
			(xy 130.152648 -240.46307) (xy 130.152648 -240.418874) (xy 129.797048 -240.418874) (xy 129.797048 -240.46307)
			(xy 129.844038 -240.61547) (xy 130.105658 -240.61547)
		)
		(stroke
			(width 0)
			(type solid)
		)
		(fill yes)
		(layer "In6.Cu")
		(net "M_G_CPU1_SB_DQS_DP<0>")
	)
	(gr_poly
		(pts
			(xy 130.152648 -237.207806) (xy 130.152648 -237.163356) (xy 129.797048 -237.163356) (xy 129.797048 -237.207806)
			(xy 129.844038 -237.360206) (xy 130.105658 -237.360206)
		)
		(stroke
			(width 0)
			(type solid)
		)
		(fill yes)
		(layer "In6.Cu")
		(net "M_G_CPU1_SB_DQ<8>")
	)
	(gr_poly
		(pts
			(xy 130.152648 -235.988098) (xy 130.105658 -235.835698) (xy 129.844038 -235.835698) (xy 129.797048 -235.988098)
			(xy 129.797048 -236.032294) (xy 130.152648 -236.032294)
		)
		(stroke
			(width 0)
			(type solid)
		)
		(fill yes)
		(layer "In6.Cu")
		(net "M_G_CPU1_SB_DQ<9>")
	)
	(gr_poly
		(pts
			(xy 130.152648 -232.732326) (xy 130.105658 -232.579926) (xy 129.844038 -232.579926) (xy 129.797048 -232.732326)
			(xy 129.797048 -232.776776) (xy 130.152648 -232.776776)
		)
		(stroke
			(width 0)
			(type solid)
		)
		(fill yes)
		(layer "In6.Cu")
		(net "M_G_CPU1_SB_DQ<13>")
	)
	(gr_poly
		(pts
			(xy 130.152648 -232.324402) (xy 130.152648 -232.279952) (xy 129.797048 -232.279952) (xy 129.797048 -232.324402)
			(xy 129.844038 -232.476802) (xy 130.105658 -232.476802)
		)
		(stroke
			(width 0)
			(type solid)
		)
		(fill yes)
		(layer "In6.Cu")
		(net "M_H_CPU1_SB_DQ<16>")
	)
	(gr_poly
		(pts
			(xy 130.152648 -231.104694) (xy 130.105658 -230.952294) (xy 129.844038 -230.952294) (xy 129.797048 -231.104694)
			(xy 129.797048 -231.14889) (xy 130.152648 -231.14889)
		)
		(stroke
			(width 0)
			(type solid)
		)
		(fill yes)
		(layer "In6.Cu")
		(net "M_H_CPU1_SB_DQ<19>")
	)
	(gr_poly
		(pts
			(xy 130.152648 -230.696262) (xy 130.152648 -230.652066) (xy 129.797048 -230.652066) (xy 129.797048 -230.696262)
			(xy 129.844038 -230.848662) (xy 130.105658 -230.848662)
		)
		(stroke
			(width 0)
			(type solid)
		)
		(fill yes)
		(layer "In6.Cu")
		(net "M_H_CPU1_SB_DQS_DP<2>")
	)
	(gr_poly
		(pts
			(xy 130.152648 -227.848922) (xy 130.105658 -227.696522) (xy 129.844038 -227.696522) (xy 129.797048 -227.848922)
			(xy 129.797048 -227.893372) (xy 130.152648 -227.893372)
		)
		(stroke
			(width 0)
			(type solid)
		)
		(fill yes)
		(layer "In6.Cu")
		(net "M_H_CPU1_SB_DQ<22>")
	)
	(gr_poly
		(pts
			(xy 130.152648 -227.440998) (xy 130.152648 -227.396548) (xy 129.797048 -227.396548) (xy 129.797048 -227.440998)
			(xy 129.844038 -227.593398) (xy 130.105658 -227.593398)
		)
		(stroke
			(width 0)
			(type solid)
		)
		(fill yes)
		(layer "In6.Cu")
		(net "M_H_CPU1_SB_DQ<21>")
	)
	(gr_poly
		(pts
			(xy 130.225292 -229.534466) (xy 130.116834 -229.417626) (xy 130.07848 -229.395528) (xy 129.90068 -229.703376)
			(xy 129.939034 -229.725474) (xy 130.094482 -229.761034)
		)
		(stroke
			(width 0)
			(type solid)
		)
		(fill yes)
		(layer "In6.Cu")
		(net "M_H_CPU1_SB_DQS_DN<7>")
	)
	(gr_poly
		(pts
			(xy 130.24993 -265.109706) (xy 130.24993 -265.06551) (xy 129.89433 -265.06551) (xy 129.89433 -265.109706)
			(xy 129.94132 -265.262106) (xy 130.20294 -265.262106)
		)
		(stroke
			(width 0)
			(type solid)
		)
		(fill yes)
		(layer "In6.Cu")
		(net "M_G_CPU1_SA_CB<0>")
	)
	(gr_poly
		(pts
			(xy 130.250692 -273.657314) (xy 130.203702 -273.504914) (xy 129.942082 -273.504914) (xy 129.895092 -273.657314)
			(xy 129.895092 -273.701764) (xy 130.250692 -273.701764)
		)
		(stroke
			(width 0)
			(type solid)
		)
		(fill yes)
		(layer "In6.Cu")
		(net "M_G_CPU1_SA_DQ<11>")
	)
	(gr_poly
		(pts
			(xy 130.250692 -271.62125) (xy 130.250692 -271.5768) (xy 129.895092 -271.5768) (xy 129.895092 -271.62125)
			(xy 129.942082 -271.77365) (xy 130.203702 -271.77365)
		)
		(stroke
			(width 0)
			(type solid)
		)
		(fill yes)
		(layer "In6.Cu")
		(net "M_G_CPU1_SA_DQ<12>")
	)
	(gr_poly
		(pts
			(xy 130.250692 -266.737846) (xy 130.250692 -266.693396) (xy 129.895092 -266.693396) (xy 129.895092 -266.737846)
			(xy 129.942082 -266.890246) (xy 130.203702 -266.890246)
		)
		(stroke
			(width 0)
			(type solid)
		)
		(fill yes)
		(layer "In6.Cu")
		(net "M_G_CPU1_SA_DQ<28>")
	)
	(gr_poly
		(pts
			(xy 130.250692 -265.518646) (xy 130.203702 -265.366246) (xy 129.942082 -265.366246) (xy 129.895092 -265.518646)
			(xy 129.895092 -265.563096) (xy 130.250692 -265.563096)
		)
		(stroke
			(width 0)
			(type solid)
		)
		(fill yes)
		(layer "In6.Cu")
		(net "M_G_CPU1_SA_DQ<31>")
	)
	(gr_poly
		(pts
			(xy 130.250692 -263.891014) (xy 130.203702 -263.738614) (xy 129.942082 -263.738614) (xy 129.895092 -263.891014)
			(xy 129.895092 -263.93521) (xy 130.250692 -263.93521)
		)
		(stroke
			(width 0)
			(type solid)
		)
		(fill yes)
		(layer "In6.Cu")
		(net "M_G_CPU1_SA_CB<3>")
	)
	(gr_poly
		(pts
			(xy 130.253994 -272.03019) (xy 130.207004 -271.87779) (xy 129.945384 -271.87779) (xy 129.898394 -272.03019)
			(xy 129.898394 -272.07464) (xy 130.253994 -272.07464)
		)
		(stroke
			(width 0)
			(type solid)
		)
		(fill yes)
		(layer "In6.Cu")
		(net "M_G_CPU1_SA_DQS_DP<6>")
	)
	(gr_poly
		(pts
			(xy 130.255518 -267.146786) (xy 130.208528 -266.994386) (xy 129.946908 -266.994386) (xy 129.899918 -267.146786)
			(xy 129.899918 -267.190982) (xy 130.255518 -267.190982)
		)
		(stroke
			(width 0)
			(type solid)
		)
		(fill yes)
		(layer "In6.Cu")
		(net "M_G_CPU1_SA_DQS_DP<8>")
	)
	(gr_poly
		(pts
			(xy 130.26009 -263.482582) (xy 130.26009 -263.438132) (xy 129.90449 -263.438132) (xy 129.90449 -263.482582)
			(xy 129.95148 -263.634982) (xy 130.2131 -263.634982)
		)
		(stroke
			(width 0)
			(type solid)
		)
		(fill yes)
		(layer "In6.Cu")
		(net "M_G_CPU1_SA_DQS_DP<4>")
	)
	(gr_poly
		(pts
			(xy 130.26263 -276.5044) (xy 130.26263 -276.460204) (xy 129.90703 -276.460204) (xy 129.90703 -276.5044)
			(xy 129.95402 -276.6568) (xy 130.21564 -276.6568)
		)
		(stroke
			(width 0)
			(type solid)
		)
		(fill yes)
		(layer "In6.Cu")
		(net "M_H_CPU1_SA_DQ<4>")
	)
	(gr_poly
		(pts
			(xy 130.26263 -275.284946) (xy 130.21564 -275.132546) (xy 129.95402 -275.132546) (xy 129.90703 -275.284946)
			(xy 129.90703 -275.329142) (xy 130.26263 -275.329142)
		)
		(stroke
			(width 0)
			(type solid)
		)
		(fill yes)
		(layer "In6.Cu")
		(net "M_H_CPU1_SA_DQ<7>")
	)
	(gr_poly
		(pts
			(xy 130.26263 -274.876514) (xy 130.26263 -274.832318) (xy 129.90703 -274.832318) (xy 129.90703 -274.876514)
			(xy 129.95402 -275.028914) (xy 130.21564 -275.028914)
		)
		(stroke
			(width 0)
			(type solid)
		)
		(fill yes)
		(layer "In6.Cu")
		(net "M_G_CPU1_SA_DQ<8>")
	)
	(gr_poly
		(pts
			(xy 130.26263 -273.248882) (xy 130.26263 -273.204686) (xy 129.90703 -273.204686) (xy 129.90703 -273.248882)
			(xy 129.95402 -273.401282) (xy 130.21564 -273.401282)
		)
		(stroke
			(width 0)
			(type solid)
		)
		(fill yes)
		(layer "In6.Cu")
		(net "M_G_CPU1_SA_DQS_DP<1>")
	)
	(gr_poly
		(pts
			(xy 130.26263 -270.401542) (xy 130.21564 -270.249142) (xy 129.95402 -270.249142) (xy 129.90703 -270.401542)
			(xy 129.90703 -270.445992) (xy 130.26263 -270.445992)
		)
		(stroke
			(width 0)
			(type solid)
		)
		(fill yes)
		(layer "In6.Cu")
		(net "M_G_CPU1_SA_DQ<15>")
	)
	(gr_poly
		(pts
			(xy 130.26263 -269.993618) (xy 130.26263 -269.949168) (xy 129.90703 -269.949168) (xy 129.90703 -269.993618)
			(xy 129.95402 -270.146018) (xy 130.21564 -270.146018)
		)
		(stroke
			(width 0)
			(type solid)
		)
		(fill yes)
		(layer "In6.Cu")
		(net "M_G_CPU1_SA_DQ<24>")
	)
	(gr_poly
		(pts
			(xy 130.26263 -268.77391) (xy 130.21564 -268.62151) (xy 129.95402 -268.62151) (xy 129.90703 -268.77391)
			(xy 129.90703 -268.818106) (xy 130.26263 -268.818106)
		)
		(stroke
			(width 0)
			(type solid)
		)
		(fill yes)
		(layer "In6.Cu")
		(net "M_G_CPU1_SA_DQ<27>")
	)
	(gr_poly
		(pts
			(xy 130.26263 -268.365478) (xy 130.26263 -268.321282) (xy 129.90703 -268.321282) (xy 129.90703 -268.365478)
			(xy 129.95402 -268.517878) (xy 130.21564 -268.517878)
		)
		(stroke
			(width 0)
			(type solid)
		)
		(fill yes)
		(layer "In6.Cu")
		(net "M_G_CPU1_SA_DQS_DP<3>")
	)
	(gr_poly
		(pts
			(xy 130.26263 -262.262874) (xy 130.21564 -262.110474) (xy 129.95402 -262.110474) (xy 129.90703 -262.262874)
			(xy 129.90703 -262.30707) (xy 130.26263 -262.30707)
		)
		(stroke
			(width 0)
			(type solid)
		)
		(fill yes)
		(layer "In6.Cu")
		(net "M_G_CPU1_SA_DQS_DP<9>")
	)
	(gr_poly
		(pts
			(xy 130.26263 -261.854442) (xy 130.26263 -261.810246) (xy 129.90703 -261.810246) (xy 129.90703 -261.854442)
			(xy 129.95402 -262.006842) (xy 130.21564 -262.006842)
		)
		(stroke
			(width 0)
			(type solid)
		)
		(fill yes)
		(layer "In6.Cu")
		(net "M_G_CPU1_SA_CB<4>")
	)
	(gr_poly
		(pts
			(xy 130.26263 -260.634734) (xy 130.21564 -260.482334) (xy 129.95402 -260.482334) (xy 129.90703 -260.634734)
			(xy 129.90703 -260.679184) (xy 130.26263 -260.679184)
		)
		(stroke
			(width 0)
			(type solid)
		)
		(fill yes)
		(layer "In6.Cu")
		(net "M_G_CPU1_SA_CB<7>")
	)
	(gr_poly
		(pts
			(xy 130.503676 -229.653084) (xy 130.465322 -229.630986) (xy 130.309874 -229.595426) (xy 130.179064 -229.821994)
			(xy 130.287522 -229.938834) (xy 130.325876 -229.960932)
		)
		(stroke
			(width 0)
			(type solid)
		)
		(fill yes)
		(layer "In6.Cu")
		(net "M_H_CPU1_SB_DQS_DN<2>")
	)
	(gr_poly
		(pts
			(xy 130.60553 -249.416062) (xy 130.60553 -249.371612) (xy 130.24993 -249.371612) (xy 130.24993 -249.416062)
			(xy 130.29692 -249.568462) (xy 130.55854 -249.568462)
		)
		(stroke
			(width 0)
			(type solid)
		)
		(fill yes)
		(layer "In6.Cu")
		(net "M_E_CPU1_SA_RSP<0>")
	)
	(gr_poly
		(pts
			(xy 130.60553 -244.532658) (xy 130.60553 -244.488208) (xy 130.24993 -244.488208) (xy 130.24993 -244.532658)
			(xy 130.29692 -244.685058) (xy 130.55854 -244.685058)
		)
		(stroke
			(width 0)
			(type solid)
		)
		(fill yes)
		(layer "In6.Cu")
		(net "M_H_CPU1_SB_CS_N<2>")
	)
	(gr_poly
		(pts
			(xy 130.60553 -243.31295) (xy 130.55854 -243.16055) (xy 130.29692 -243.16055) (xy 130.24993 -243.31295)
			(xy 130.24993 -243.3574) (xy 130.60553 -243.3574)
		)
		(stroke
			(width 0)
			(type solid)
		)
		(fill yes)
		(layer "In6.Cu")
		(net "M_H_CPU1_SB_CS_N<1>")
	)
	(gr_poly
		(pts
			(xy 130.60553 -241.685318) (xy 130.55854 -241.532918) (xy 130.29692 -241.532918) (xy 130.24993 -241.685318)
			(xy 130.24993 -241.729514) (xy 130.60553 -241.729514)
		)
		(stroke
			(width 0)
			(type solid)
		)
		(fill yes)
		(layer "In6.Cu")
		(net "M_G_CPU1_SB_DQ<2>")
	)
	(gr_poly
		(pts
			(xy 130.60553 -241.276886) (xy 130.60553 -241.23269) (xy 130.24993 -241.23269) (xy 130.24993 -241.276886)
			(xy 130.29692 -241.429286) (xy 130.55854 -241.429286)
		)
		(stroke
			(width 0)
			(type solid)
		)
		(fill yes)
		(layer "In6.Cu")
		(net "M_G_CPU1_SB_DQ<1>")
	)
	(gr_poly
		(pts
			(xy 130.60553 -240.057178) (xy 130.55854 -239.904778) (xy 130.29692 -239.904778) (xy 130.24993 -240.057178)
			(xy 130.24993 -240.101628) (xy 130.60553 -240.101628)
		)
		(stroke
			(width 0)
			(type solid)
		)
		(fill yes)
		(layer "In6.Cu")
		(net "M_G_CPU1_SB_DQS_DN<0>")
	)
	(gr_poly
		(pts
			(xy 130.60553 -239.649254) (xy 130.60553 -239.604804) (xy 130.24993 -239.604804) (xy 130.24993 -239.649254)
			(xy 130.29692 -239.801654) (xy 130.55854 -239.801654)
		)
		(stroke
			(width 0)
			(type solid)
		)
		(fill yes)
		(layer "In6.Cu")
		(net "M_G_CPU1_SB_DQS_DN<5>")
	)
	(gr_poly
		(pts
			(xy 130.60553 -236.801914) (xy 130.55854 -236.649514) (xy 130.29692 -236.649514) (xy 130.24993 -236.801914)
			(xy 130.24993 -236.84611) (xy 130.60553 -236.84611)
		)
		(stroke
			(width 0)
			(type solid)
		)
		(fill yes)
		(layer "In6.Cu")
		(net "M_G_CPU1_SB_DQ<10>")
	)
	(gr_poly
		(pts
			(xy 130.60553 -236.39399) (xy 130.60553 -236.34954) (xy 130.24993 -236.34954) (xy 130.24993 -236.39399)
			(xy 130.29692 -236.54639) (xy 130.55854 -236.54639)
		)
		(stroke
			(width 0)
			(type solid)
		)
		(fill yes)
		(layer "In6.Cu")
		(net "M_G_CPU1_SB_DQ<11>")
	)
	(gr_poly
		(pts
			(xy 130.60553 -234.76585) (xy 130.60553 -234.721654) (xy 130.24993 -234.721654) (xy 130.24993 -234.76585)
			(xy 130.29692 -234.91825) (xy 130.55854 -234.91825)
		)
		(stroke
			(width 0)
			(type solid)
		)
		(fill yes)
		(layer "In6.Cu")
		(net "M_G_CPU1_SB_DQS_DP<1>")
	)
	(gr_poly
		(pts
			(xy 130.60553 -233.546142) (xy 130.55854 -233.393742) (xy 130.29692 -233.393742) (xy 130.24993 -233.546142)
			(xy 130.24993 -233.590592) (xy 130.60553 -233.590592)
		)
		(stroke
			(width 0)
			(type solid)
		)
		(fill yes)
		(layer "In6.Cu")
		(net "M_G_CPU1_SB_DQ<12>")
	)
	(gr_poly
		(pts
			(xy 130.60553 -233.138218) (xy 130.60553 -233.093768) (xy 130.24993 -233.093768) (xy 130.24993 -233.138218)
			(xy 130.29692 -233.290618) (xy 130.55854 -233.290618)
		)
		(stroke
			(width 0)
			(type solid)
		)
		(fill yes)
		(layer "In6.Cu")
		(net "M_G_CPU1_SB_DQ<15>")
	)
	(gr_poly
		(pts
			(xy 130.60553 -231.91851) (xy 130.55854 -231.76611) (xy 130.29692 -231.76611) (xy 130.24993 -231.91851)
			(xy 130.24993 -231.96296) (xy 130.60553 -231.96296)
		)
		(stroke
			(width 0)
			(type solid)
		)
		(fill yes)
		(layer "In6.Cu")
		(net "M_H_CPU1_SB_DQ<18>")
	)
	(gr_poly
		(pts
			(xy 130.60553 -231.510586) (xy 130.60553 -231.466136) (xy 130.24993 -231.466136) (xy 130.24993 -231.510586)
			(xy 130.29692 -231.662986) (xy 130.55854 -231.662986)
		)
		(stroke
			(width 0)
			(type solid)
		)
		(fill yes)
		(layer "In6.Cu")
		(net "M_H_CPU1_SB_DQ<17>")
	)
	(gr_poly
		(pts
			(xy 130.60553 -228.663246) (xy 130.55854 -228.510846) (xy 130.29692 -228.510846) (xy 130.24993 -228.663246)
			(xy 130.24993 -228.707442) (xy 130.60553 -228.707442)
		)
		(stroke
			(width 0)
			(type solid)
		)
		(fill yes)
		(layer "In6.Cu")
		(net "M_H_CPU1_SB_DQS_DP<7>")
	)
	(gr_poly
		(pts
			(xy 130.60553 -228.254814) (xy 130.60553 -228.210618) (xy 130.24993 -228.210618) (xy 130.24993 -228.254814)
			(xy 130.29692 -228.407214) (xy 130.55854 -228.407214)
		)
		(stroke
			(width 0)
			(type solid)
		)
		(fill yes)
		(layer "In6.Cu")
		(net "M_H_CPU1_SB_DQ<20>")
	)
	(gr_poly
		(pts
			(xy 130.60807 -248.196354) (xy 130.56108 -248.043954) (xy 130.29946 -248.043954) (xy 130.25247 -248.196354)
			(xy 130.25247 -248.24055) (xy 130.60807 -248.24055)
		)
		(stroke
			(width 0)
			(type solid)
		)
		(fill yes)
		(layer "In6.Cu")
		(net "M_E_CPU1_SB_RSP<1>")
	)
	(gr_poly
		(pts
			(xy 130.60807 -227.035106) (xy 130.56108 -226.882706) (xy 130.29946 -226.882706) (xy 130.25247 -227.035106)
			(xy 130.25247 -227.079556) (xy 130.60807 -227.079556)
		)
		(stroke
			(width 0)
			(type solid)
		)
		(fill yes)
		(layer "In6.Cu")
		(net "M_H_CPU1_SB_DQ<23>")
	)
	(gr_poly
		(pts
			(xy 130.617468 -238.021114) (xy 130.617468 -237.976664) (xy 130.261868 -237.976664) (xy 130.261868 -238.021114)
			(xy 130.308858 -238.173514) (xy 130.570478 -238.173514)
		)
		(stroke
			(width 0)
			(type solid)
		)
		(fill yes)
		(layer "In6.Cu")
		(net "M_G_CPU1_SB_DQ<5>")
	)
	(gr_poly
		(pts
			(xy 130.617468 -235.174282) (xy 130.570478 -235.021882) (xy 130.308858 -235.021882) (xy 130.261868 -235.174282)
			(xy 130.261868 -235.218732) (xy 130.617468 -235.218732)
		)
		(stroke
			(width 0)
			(type solid)
		)
		(fill yes)
		(layer "In6.Cu")
		(net "M_G_CPU1_SB_DQS_DP<6>")
	)
	(gr_poly
		(pts
			(xy 130.61823 -238.430054) (xy 130.57124 -238.277654) (xy 130.30962 -238.277654) (xy 130.26263 -238.430054)
			(xy 130.26263 -238.47425) (xy 130.61823 -238.47425)
		)
		(stroke
			(width 0)
			(type solid)
		)
		(fill yes)
		(layer "In6.Cu")
		(net "M_G_CPU1_SB_DQ<6>")
	)
	(gr_poly
		(pts
			(xy 130.687826 -230.360982) (xy 130.579368 -230.244142) (xy 130.541014 -230.222044) (xy 130.363214 -230.529892)
			(xy 130.401568 -230.55199) (xy 130.557016 -230.58755)
		)
		(stroke
			(width 0)
			(type solid)
		)
		(fill yes)
		(layer "In6.Cu")
		(net "M_H_CPU1_SB_DQS_DP<2>")
	)
	(gr_poly
		(pts
			(xy 130.715512 -276.098762) (xy 130.668522 -275.946362) (xy 130.406902 -275.946362) (xy 130.359912 -276.098762)
			(xy 130.359912 -276.143212) (xy 130.715512 -276.143212)
		)
		(stroke
			(width 0)
			(type solid)
		)
		(fill yes)
		(layer "In6.Cu")
		(net "M_H_CPU1_SA_DQ<6>")
	)
	(gr_poly
		(pts
			(xy 130.715512 -275.690584) (xy 130.715512 -275.646388) (xy 130.359912 -275.646388) (xy 130.359912 -275.690584)
			(xy 130.406902 -275.842984) (xy 130.668522 -275.842984)
		)
		(stroke
			(width 0)
			(type solid)
		)
		(fill yes)
		(layer "In6.Cu")
		(net "M_H_CPU1_SA_DQ<5>")
	)
	(gr_poly
		(pts
			(xy 130.715512 -274.47113) (xy 130.668522 -274.31873) (xy 130.406902 -274.31873) (xy 130.359912 -274.47113)
			(xy 130.359912 -274.515326) (xy 130.715512 -274.515326)
		)
		(stroke
			(width 0)
			(type solid)
		)
		(fill yes)
		(layer "In6.Cu")
		(net "M_G_CPU1_SA_DQ<10>")
	)
	(gr_poly
		(pts
			(xy 130.715512 -272.843498) (xy 130.668522 -272.691098) (xy 130.406902 -272.691098) (xy 130.359912 -272.843498)
			(xy 130.359912 -272.887694) (xy 130.715512 -272.887694)
		)
		(stroke
			(width 0)
			(type solid)
		)
		(fill yes)
		(layer "In6.Cu")
		(net "M_G_CPU1_SA_DQS_DN<1>")
	)
	(gr_poly
		(pts
			(xy 130.715512 -272.435066) (xy 130.715512 -272.39087) (xy 130.359912 -272.39087) (xy 130.359912 -272.435066)
			(xy 130.406902 -272.587466) (xy 130.668522 -272.587466)
		)
		(stroke
			(width 0)
			(type solid)
		)
		(fill yes)
		(layer "In6.Cu")
		(net "M_G_CPU1_SA_DQS_DN<6>")
	)
	(gr_poly
		(pts
			(xy 130.715512 -270.807434) (xy 130.715512 -270.762984) (xy 130.359912 -270.762984) (xy 130.359912 -270.807434)
			(xy 130.406902 -270.959834) (xy 130.668522 -270.959834)
		)
		(stroke
			(width 0)
			(type solid)
		)
		(fill yes)
		(layer "In6.Cu")
		(net "M_G_CPU1_SA_DQ<13>")
	)
	(gr_poly
		(pts
			(xy 130.715512 -269.587726) (xy 130.668522 -269.435326) (xy 130.406902 -269.435326) (xy 130.359912 -269.587726)
			(xy 130.359912 -269.631922) (xy 130.715512 -269.631922)
		)
		(stroke
			(width 0)
			(type solid)
		)
		(fill yes)
		(layer "In6.Cu")
		(net "M_G_CPU1_SA_DQ<26>")
	)
	(gr_poly
		(pts
			(xy 130.715512 -267.960094) (xy 130.668522 -267.807694) (xy 130.406902 -267.807694) (xy 130.359912 -267.960094)
			(xy 130.359912 -268.00429) (xy 130.715512 -268.00429)
		)
		(stroke
			(width 0)
			(type solid)
		)
		(fill yes)
		(layer "In6.Cu")
		(net "M_G_CPU1_SA_DQS_DN<3>")
	)
	(gr_poly
		(pts
			(xy 130.715512 -267.551662) (xy 130.715512 -267.507466) (xy 130.359912 -267.507466) (xy 130.359912 -267.551662)
			(xy 130.406902 -267.704062) (xy 130.668522 -267.704062)
		)
		(stroke
			(width 0)
			(type solid)
		)
		(fill yes)
		(layer "In6.Cu")
		(net "M_G_CPU1_SA_DQS_DN<8>")
	)
	(gr_poly
		(pts
			(xy 130.715512 -263.07669) (xy 130.668522 -262.92429) (xy 130.406902 -262.92429) (xy 130.359912 -263.07669)
			(xy 130.359912 -263.120886) (xy 130.715512 -263.120886)
		)
		(stroke
			(width 0)
			(type solid)
		)
		(fill yes)
		(layer "In6.Cu")
		(net "M_G_CPU1_SA_DQS_DN<4>")
	)
	(gr_poly
		(pts
			(xy 130.715512 -262.668258) (xy 130.715512 -262.624062) (xy 130.359912 -262.624062) (xy 130.359912 -262.668258)
			(xy 130.406902 -262.820658) (xy 130.668522 -262.820658)
		)
		(stroke
			(width 0)
			(type solid)
		)
		(fill yes)
		(layer "In6.Cu")
		(net "M_G_CPU1_SA_DQS_DN<9>")
	)
	(gr_poly
		(pts
			(xy 130.715512 -261.449058) (xy 130.668522 -261.296658) (xy 130.406902 -261.296658) (xy 130.359912 -261.449058)
			(xy 130.359912 -261.493254) (xy 130.715512 -261.493254)
		)
		(stroke
			(width 0)
			(type solid)
		)
		(fill yes)
		(layer "In6.Cu")
		(net "M_G_CPU1_SA_CB<6>")
	)
	(gr_poly
		(pts
			(xy 130.715512 -261.040626) (xy 130.715512 -260.99643) (xy 130.359912 -260.99643) (xy 130.359912 -261.040626)
			(xy 130.406902 -261.193026) (xy 130.668522 -261.193026)
		)
		(stroke
			(width 0)
			(type solid)
		)
		(fill yes)
		(layer "In6.Cu")
		(net "M_G_CPU1_SA_CB<5>")
	)
	(gr_poly
		(pts
			(xy 130.724402 -277.318216) (xy 130.724402 -277.27402) (xy 130.368802 -277.27402) (xy 130.368802 -277.318216)
			(xy 130.415792 -277.470616) (xy 130.677412 -277.470616)
		)
		(stroke
			(width 0)
			(type solid)
		)
		(fill yes)
		(layer "In6.Cu")
		(net "M_H_CPU1_SA_DQS_DN<5>")
	)
	(gr_poly
		(pts
			(xy 130.72745 -274.062698) (xy 130.72745 -274.018248) (xy 130.37185 -274.018248) (xy 130.37185 -274.062698)
			(xy 130.41884 -274.215098) (xy 130.68046 -274.215098)
		)
		(stroke
			(width 0)
			(type solid)
		)
		(fill yes)
		(layer "In6.Cu")
		(net "M_G_CPU1_SA_DQ<9>")
	)
	(gr_poly
		(pts
			(xy 130.72745 -271.215866) (xy 130.68046 -271.063466) (xy 130.41884 -271.063466) (xy 130.37185 -271.215866)
			(xy 130.37185 -271.260062) (xy 130.72745 -271.260062)
		)
		(stroke
			(width 0)
			(type solid)
		)
		(fill yes)
		(layer "In6.Cu")
		(net "M_G_CPU1_SA_DQ<14>")
	)
	(gr_poly
		(pts
			(xy 130.72745 -269.179294) (xy 130.72745 -269.134844) (xy 130.37185 -269.134844) (xy 130.37185 -269.179294)
			(xy 130.41884 -269.331694) (xy 130.68046 -269.331694)
		)
		(stroke
			(width 0)
			(type solid)
		)
		(fill yes)
		(layer "In6.Cu")
		(net "M_G_CPU1_SA_DQ<25>")
	)
	(gr_poly
		(pts
			(xy 130.72745 -266.332462) (xy 130.68046 -266.180062) (xy 130.41884 -266.180062) (xy 130.37185 -266.332462)
			(xy 130.37185 -266.376658) (xy 130.72745 -266.376658)
		)
		(stroke
			(width 0)
			(type solid)
		)
		(fill yes)
		(layer "In6.Cu")
		(net "M_G_CPU1_SA_DQ<30>")
	)
	(gr_poly
		(pts
			(xy 130.72745 -265.923522) (xy 130.72745 -265.879326) (xy 130.37185 -265.879326) (xy 130.37185 -265.923522)
			(xy 130.41884 -266.075922) (xy 130.68046 -266.075922)
		)
		(stroke
			(width 0)
			(type solid)
		)
		(fill yes)
		(layer "In6.Cu")
		(net "M_G_CPU1_SA_DQ<29>")
	)
	(gr_poly
		(pts
			(xy 130.72745 -264.29589) (xy 130.72745 -264.25144) (xy 130.37185 -264.25144) (xy 130.37185 -264.29589)
			(xy 130.41884 -264.44829) (xy 130.68046 -264.44829)
		)
		(stroke
			(width 0)
			(type solid)
		)
		(fill yes)
		(layer "In6.Cu")
		(net "M_G_CPU1_SA_CB<1>")
	)
	(gr_poly
		(pts
			(xy 130.728212 -264.70483) (xy 130.681222 -264.55243) (xy 130.419602 -264.55243) (xy 130.372612 -264.70483)
			(xy 130.372612 -264.749026) (xy 130.728212 -264.749026)
		)
		(stroke
			(width 0)
			(type solid)
		)
		(fill yes)
		(layer "In6.Cu")
		(net "M_G_CPU1_SA_CB<2>")
	)
	(gr_poly
		(pts
			(xy 130.73253 -277.726394) (xy 130.68554 -277.573994) (xy 130.42392 -277.573994) (xy 130.37693 -277.726394)
			(xy 130.37693 -277.770844) (xy 130.73253 -277.770844)
		)
		(stroke
			(width 0)
			(type solid)
		)
		(fill yes)
		(layer "In6.Cu")
		(net "M_H_CPU1_SA_DQS_DN<0>")
	)
	(gr_poly
		(pts
			(xy 130.979164 -230.457248) (xy 130.94081 -230.43515) (xy 130.785362 -230.39959) (xy 130.654552 -230.626158)
			(xy 130.76301 -230.742998) (xy 130.801364 -230.765096)
		)
		(stroke
			(width 0)
			(type solid)
		)
		(fill yes)
		(layer "In6.Cu")
		(net "M_H_CPU1_SB_DQ<19>")
	)
	(gr_poly
		(pts
			(xy 131.079748 -238.83493) (xy 131.079748 -238.790734) (xy 130.724148 -238.790734) (xy 130.724148 -238.83493)
			(xy 130.771138 -238.98733) (xy 131.032758 -238.98733)
		)
		(stroke
			(width 0)
			(type solid)
		)
		(fill yes)
		(layer "In6.Cu")
		(net "M_G_CPU1_SB_DQ<4>")
	)
	(gr_poly
		(pts
			(xy 131.079748 -233.951526) (xy 131.079748 -233.90733) (xy 130.724148 -233.90733) (xy 130.724148 -233.951526)
			(xy 130.771138 -234.103926) (xy 131.032758 -234.103926)
		)
		(stroke
			(width 0)
			(type solid)
		)
		(fill yes)
		(layer "In6.Cu")
		(net "M_G_CPU1_SB_DQ<14>")
	)
	(gr_poly
		(pts
			(xy 131.08051 -237.616238) (xy 131.03352 -237.463838) (xy 130.7719 -237.463838) (xy 130.72491 -237.616238)
			(xy 130.72491 -237.660434) (xy 131.08051 -237.660434)
		)
		(stroke
			(width 0)
			(type solid)
		)
		(fill yes)
		(layer "In6.Cu")
		(net "M_G_CPU1_SB_DQ<7>")
	)
	(gr_poly
		(pts
			(xy 131.08051 -235.579666) (xy 131.08051 -235.535216) (xy 130.72491 -235.535216) (xy 130.72491 -235.579666)
			(xy 130.7719 -235.732066) (xy 131.03352 -235.732066)
		)
		(stroke
			(width 0)
			(type solid)
		)
		(fill yes)
		(layer "In6.Cu")
		(net "M_G_CPU1_SB_DQS_DN<6>")
	)
	(gr_poly
		(pts
			(xy 131.084066 -248.601738) (xy 131.084066 -248.557542) (xy 130.728466 -248.557542) (xy 130.728466 -248.601738)
			(xy 130.775456 -248.754138) (xy 131.037076 -248.754138)
		)
		(stroke
			(width 0)
			(type solid)
		)
		(fill yes)
		(layer "In6.Cu")
		(net "M_E_CPU1_SA_RSP<1>")
	)
	(gr_poly
		(pts
			(xy 131.084066 -227.44049) (xy 131.084066 -227.396294) (xy 130.728466 -227.396294) (xy 130.728466 -227.44049)
			(xy 130.775456 -227.59289) (xy 131.037076 -227.59289)
		)
		(stroke
			(width 0)
			(type solid)
		)
		(fill yes)
		(layer "In6.Cu")
		(net "M_H_CPU1_SB_DQ<21>")
	)
	(gr_poly
		(pts
			(xy 131.092448 -249.01017) (xy 131.045458 -248.85777) (xy 130.783838 -248.85777) (xy 130.736848 -249.01017)
			(xy 130.736848 -249.05462) (xy 131.092448 -249.05462)
		)
		(stroke
			(width 0)
			(type solid)
		)
		(fill yes)
		(layer "In6.Cu")
		(net "M_E_CPU1_SB_RSP<0>")
	)
	(gr_poly
		(pts
			(xy 131.092448 -244.126766) (xy 131.045458 -243.974366) (xy 130.783838 -243.974366) (xy 130.736848 -244.126766)
			(xy 130.736848 -244.171216) (xy 131.092448 -244.171216)
		)
		(stroke
			(width 0)
			(type solid)
		)
		(fill yes)
		(layer "In6.Cu")
		(net "M_H_CPU1_SB_CS_N<3>")
	)
	(gr_poly
		(pts
			(xy 131.092448 -243.718842) (xy 131.092448 -243.674392) (xy 130.736848 -243.674392) (xy 130.736848 -243.718842)
			(xy 130.783838 -243.871242) (xy 131.045458 -243.871242)
		)
		(stroke
			(width 0)
			(type solid)
		)
		(fill yes)
		(layer "In6.Cu")
		(net "M_H_CPU1_SB_CS_N<0>")
	)
	(gr_poly
		(pts
			(xy 131.092448 -242.090702) (xy 131.092448 -242.046506) (xy 130.736848 -242.046506) (xy 130.736848 -242.090702)
			(xy 130.783838 -242.243102) (xy 131.045458 -242.243102)
		)
		(stroke
			(width 0)
			(type solid)
		)
		(fill yes)
		(layer "In6.Cu")
		(net "M_G_CPU1_SB_DQ<0>")
	)
	(gr_poly
		(pts
			(xy 131.092448 -240.871502) (xy 131.045458 -240.719102) (xy 130.783838 -240.719102) (xy 130.736848 -240.871502)
			(xy 130.736848 -240.915698) (xy 131.092448 -240.915698)
		)
		(stroke
			(width 0)
			(type solid)
		)
		(fill yes)
		(layer "In6.Cu")
		(net "M_G_CPU1_SB_DQ<3>")
	)
	(gr_poly
		(pts
			(xy 131.092448 -240.46307) (xy 131.092448 -240.418874) (xy 130.736848 -240.418874) (xy 130.736848 -240.46307)
			(xy 130.783838 -240.61547) (xy 131.045458 -240.61547)
		)
		(stroke
			(width 0)
			(type solid)
		)
		(fill yes)
		(layer "In6.Cu")
		(net "M_G_CPU1_SB_DQS_DP<0>")
	)
	(gr_poly
		(pts
			(xy 131.092448 -239.243362) (xy 131.045458 -239.090962) (xy 130.783838 -239.090962) (xy 130.736848 -239.243362)
			(xy 130.736848 -239.287812) (xy 131.092448 -239.287812)
		)
		(stroke
			(width 0)
			(type solid)
		)
		(fill yes)
		(layer "In6.Cu")
		(net "M_G_CPU1_SB_DQS_DP<5>")
	)
	(gr_poly
		(pts
			(xy 131.092448 -237.207806) (xy 131.092448 -237.163356) (xy 130.736848 -237.163356) (xy 130.736848 -237.207806)
			(xy 130.783838 -237.360206) (xy 131.045458 -237.360206)
		)
		(stroke
			(width 0)
			(type solid)
		)
		(fill yes)
		(layer "In6.Cu")
		(net "M_G_CPU1_SB_DQ<8>")
	)
	(gr_poly
		(pts
			(xy 131.092448 -235.988098) (xy 131.045458 -235.835698) (xy 130.783838 -235.835698) (xy 130.736848 -235.988098)
			(xy 130.736848 -236.032294) (xy 131.092448 -236.032294)
		)
		(stroke
			(width 0)
			(type solid)
		)
		(fill yes)
		(layer "In6.Cu")
		(net "M_G_CPU1_SB_DQ<9>")
	)
	(gr_poly
		(pts
			(xy 131.092448 -234.360466) (xy 131.045458 -234.208066) (xy 130.783838 -234.208066) (xy 130.736848 -234.360466)
			(xy 130.736848 -234.404662) (xy 131.092448 -234.404662)
		)
		(stroke
			(width 0)
			(type solid)
		)
		(fill yes)
		(layer "In6.Cu")
		(net "M_G_CPU1_SB_DQS_DN<1>")
	)
	(gr_poly
		(pts
			(xy 131.092448 -232.732326) (xy 131.045458 -232.579926) (xy 130.783838 -232.579926) (xy 130.736848 -232.732326)
			(xy 130.736848 -232.776776) (xy 131.092448 -232.776776)
		)
		(stroke
			(width 0)
			(type solid)
		)
		(fill yes)
		(layer "In6.Cu")
		(net "M_G_CPU1_SB_DQ<13>")
	)
	(gr_poly
		(pts
			(xy 131.092448 -232.324402) (xy 131.092448 -232.279952) (xy 130.736848 -232.279952) (xy 130.736848 -232.324402)
			(xy 130.783838 -232.476802) (xy 131.045458 -232.476802)
		)
		(stroke
			(width 0)
			(type solid)
		)
		(fill yes)
		(layer "In6.Cu")
		(net "M_H_CPU1_SB_DQ<16>")
	)
	(gr_poly
		(pts
			(xy 131.092448 -229.477062) (xy 131.045458 -229.324662) (xy 130.783838 -229.324662) (xy 130.736848 -229.477062)
			(xy 130.736848 -229.521258) (xy 131.092448 -229.521258)
		)
		(stroke
			(width 0)
			(type solid)
		)
		(fill yes)
		(layer "In6.Cu")
		(net "M_H_CPU1_SB_DQS_DN<2>")
	)
	(gr_poly
		(pts
			(xy 131.092448 -229.06863) (xy 131.092448 -229.024434) (xy 130.736848 -229.024434) (xy 130.736848 -229.06863)
			(xy 130.783838 -229.22103) (xy 131.045458 -229.22103)
		)
		(stroke
			(width 0)
			(type solid)
		)
		(fill yes)
		(layer "In6.Cu")
		(net "M_H_CPU1_SB_DQS_DN<7>")
	)
	(gr_poly
		(pts
			(xy 131.092448 -227.848922) (xy 131.045458 -227.696522) (xy 130.783838 -227.696522) (xy 130.736848 -227.848922)
			(xy 130.736848 -227.893372) (xy 131.092448 -227.893372)
		)
		(stroke
			(width 0)
			(type solid)
		)
		(fill yes)
		(layer "In6.Cu")
		(net "M_H_CPU1_SB_DQ<22>")
	)
	(gr_poly
		(pts
			(xy 131.15798 -231.17429) (xy 131.049522 -231.05745) (xy 131.011168 -231.035352) (xy 130.833368 -231.3432)
			(xy 130.871722 -231.365298) (xy 131.02717 -231.400858)
		)
		(stroke
			(width 0)
			(type solid)
		)
		(fill yes)
		(layer "In6.Cu")
		(net "M_H_CPU1_SB_DQ<17>")
	)
	(gr_poly
		(pts
			(xy 131.187952 -278.132286) (xy 131.187952 -278.08809) (xy 130.832352 -278.08809) (xy 130.832352 -278.132286)
			(xy 130.879342 -278.284686) (xy 131.140962 -278.284686)
		)
		(stroke
			(width 0)
			(type solid)
		)
		(fill yes)
		(layer "In6.Cu")
		(net "M_H_CPU1_SA_DQS_DP<0>")
	)
	(gr_poly
		(pts
			(xy 131.18973 -265.109706) (xy 131.18973 -265.06551) (xy 130.83413 -265.06551) (xy 130.83413 -265.109706)
			(xy 130.88112 -265.262106) (xy 131.14274 -265.262106)
		)
		(stroke
			(width 0)
			(type solid)
		)
		(fill yes)
		(layer "In6.Cu")
		(net "M_G_CPU1_SA_CB<0>")
	)
	(gr_poly
		(pts
			(xy 131.190492 -271.62125) (xy 131.190492 -271.5768) (xy 130.834892 -271.5768) (xy 130.834892 -271.62125)
			(xy 130.881882 -271.77365) (xy 131.143502 -271.77365)
		)
		(stroke
			(width 0)
			(type solid)
		)
		(fill yes)
		(layer "In6.Cu")
		(net "M_G_CPU1_SA_DQ<12>")
	)
	(gr_poly
		(pts
			(xy 131.190492 -266.737846) (xy 131.190492 -266.693396) (xy 130.834892 -266.693396) (xy 130.834892 -266.737846)
			(xy 130.881882 -266.890246) (xy 131.143502 -266.890246)
		)
		(stroke
			(width 0)
			(type solid)
		)
		(fill yes)
		(layer "In6.Cu")
		(net "M_G_CPU1_SA_DQ<28>")
	)
	(gr_poly
		(pts
			(xy 131.190492 -265.518646) (xy 131.143502 -265.366246) (xy 130.881882 -265.366246) (xy 130.834892 -265.518646)
			(xy 130.834892 -265.563096) (xy 131.190492 -265.563096)
		)
		(stroke
			(width 0)
			(type solid)
		)
		(fill yes)
		(layer "In6.Cu")
		(net "M_G_CPU1_SA_DQ<31>")
	)
	(gr_poly
		(pts
			(xy 131.190492 -263.891014) (xy 131.143502 -263.738614) (xy 130.881882 -263.738614) (xy 130.834892 -263.891014)
			(xy 130.834892 -263.93521) (xy 131.190492 -263.93521)
		)
		(stroke
			(width 0)
			(type solid)
		)
		(fill yes)
		(layer "In6.Cu")
		(net "M_G_CPU1_SA_CB<3>")
	)
	(gr_poly
		(pts
			(xy 131.194048 -276.913086) (xy 131.147058 -276.760686) (xy 130.885438 -276.760686) (xy 130.838448 -276.913086)
			(xy 130.838448 -276.957282) (xy 131.194048 -276.957282)
		)
		(stroke
			(width 0)
			(type solid)
		)
		(fill yes)
		(layer "In6.Cu")
		(net "M_H_CPU1_SA_DQS_DP<5>")
	)
	(gr_poly
		(pts
			(xy 131.19989 -278.540718) (xy 131.1529 -278.388318) (xy 130.89128 -278.388318) (xy 130.84429 -278.540718)
			(xy 130.84429 -278.584914) (xy 131.19989 -278.584914)
		)
		(stroke
			(width 0)
			(type solid)
		)
		(fill yes)
		(layer "In6.Cu")
		(net "M_H_CPU1_SA_DQ<1>")
	)
	(gr_poly
		(pts
			(xy 131.20243 -276.5044) (xy 131.20243 -276.460204) (xy 130.84683 -276.460204) (xy 130.84683 -276.5044)
			(xy 130.89382 -276.6568) (xy 131.15544 -276.6568)
		)
		(stroke
			(width 0)
			(type solid)
		)
		(fill yes)
		(layer "In6.Cu")
		(net "M_H_CPU1_SA_DQ<4>")
	)
	(gr_poly
		(pts
			(xy 131.20243 -275.284946) (xy 131.15544 -275.132546) (xy 130.89382 -275.132546) (xy 130.84683 -275.284946)
			(xy 130.84683 -275.329142) (xy 131.20243 -275.329142)
		)
		(stroke
			(width 0)
			(type solid)
		)
		(fill yes)
		(layer "In6.Cu")
		(net "M_H_CPU1_SA_DQ<7>")
	)
	(gr_poly
		(pts
			(xy 131.20243 -274.876514) (xy 131.20243 -274.832318) (xy 130.84683 -274.832318) (xy 130.84683 -274.876514)
			(xy 130.89382 -275.028914) (xy 131.15544 -275.028914)
		)
		(stroke
			(width 0)
			(type solid)
		)
		(fill yes)
		(layer "In6.Cu")
		(net "M_G_CPU1_SA_DQ<8>")
	)
	(gr_poly
		(pts
			(xy 131.20243 -273.657314) (xy 131.15544 -273.504914) (xy 130.89382 -273.504914) (xy 130.84683 -273.657314)
			(xy 130.84683 -273.70151) (xy 131.20243 -273.70151)
		)
		(stroke
			(width 0)
			(type solid)
		)
		(fill yes)
		(layer "In6.Cu")
		(net "M_G_CPU1_SA_DQ<11>")
	)
	(gr_poly
		(pts
			(xy 131.20243 -273.248882) (xy 131.20243 -273.204686) (xy 130.84683 -273.204686) (xy 130.84683 -273.248882)
			(xy 130.89382 -273.401282) (xy 131.15544 -273.401282)
		)
		(stroke
			(width 0)
			(type solid)
		)
		(fill yes)
		(layer "In6.Cu")
		(net "M_G_CPU1_SA_DQS_DP<1>")
	)
	(gr_poly
		(pts
			(xy 131.20243 -272.029174) (xy 131.15544 -271.876774) (xy 130.89382 -271.876774) (xy 130.84683 -272.029174)
			(xy 130.84683 -272.073624) (xy 131.20243 -272.073624)
		)
		(stroke
			(width 0)
			(type solid)
		)
		(fill yes)
		(layer "In6.Cu")
		(net "M_G_CPU1_SA_DQS_DP<6>")
	)
	(gr_poly
		(pts
			(xy 131.20243 -270.401542) (xy 131.15544 -270.249142) (xy 130.89382 -270.249142) (xy 130.84683 -270.401542)
			(xy 130.84683 -270.445992) (xy 131.20243 -270.445992)
		)
		(stroke
			(width 0)
			(type solid)
		)
		(fill yes)
		(layer "In6.Cu")
		(net "M_G_CPU1_SA_DQ<15>")
	)
	(gr_poly
		(pts
			(xy 131.20243 -269.993618) (xy 131.20243 -269.949168) (xy 130.84683 -269.949168) (xy 130.84683 -269.993618)
			(xy 130.89382 -270.146018) (xy 131.15544 -270.146018)
		)
		(stroke
			(width 0)
			(type solid)
		)
		(fill yes)
		(layer "In6.Cu")
		(net "M_G_CPU1_SA_DQ<24>")
	)
	(gr_poly
		(pts
			(xy 131.20243 -268.77391) (xy 131.15544 -268.62151) (xy 130.89382 -268.62151) (xy 130.84683 -268.77391)
			(xy 130.84683 -268.818106) (xy 131.20243 -268.818106)
		)
		(stroke
			(width 0)
			(type solid)
		)
		(fill yes)
		(layer "In6.Cu")
		(net "M_G_CPU1_SA_DQ<27>")
	)
	(gr_poly
		(pts
			(xy 131.20243 -268.365478) (xy 131.20243 -268.321282) (xy 130.84683 -268.321282) (xy 130.84683 -268.365478)
			(xy 130.89382 -268.517878) (xy 131.15544 -268.517878)
		)
		(stroke
			(width 0)
			(type solid)
		)
		(fill yes)
		(layer "In6.Cu")
		(net "M_G_CPU1_SA_DQS_DP<3>")
	)
	(gr_poly
		(pts
			(xy 131.20243 -267.146278) (xy 131.15544 -266.993878) (xy 130.89382 -266.993878) (xy 130.84683 -267.146278)
			(xy 130.84683 -267.190474) (xy 131.20243 -267.190474)
		)
		(stroke
			(width 0)
			(type solid)
		)
		(fill yes)
		(layer "In6.Cu")
		(net "M_G_CPU1_SA_DQS_DP<8>")
	)
	(gr_poly
		(pts
			(xy 131.20243 -263.482582) (xy 131.20243 -263.438132) (xy 130.84683 -263.438132) (xy 130.84683 -263.482582)
			(xy 130.89382 -263.634982) (xy 131.15544 -263.634982)
		)
		(stroke
			(width 0)
			(type solid)
		)
		(fill yes)
		(layer "In6.Cu")
		(net "M_G_CPU1_SA_DQS_DP<4>")
	)
	(gr_poly
		(pts
			(xy 131.20243 -262.262874) (xy 131.15544 -262.110474) (xy 130.89382 -262.110474) (xy 130.84683 -262.262874)
			(xy 130.84683 -262.30707) (xy 131.20243 -262.30707)
		)
		(stroke
			(width 0)
			(type solid)
		)
		(fill yes)
		(layer "In6.Cu")
		(net "M_G_CPU1_SA_DQS_DP<9>")
	)
	(gr_poly
		(pts
			(xy 131.20243 -261.854442) (xy 131.20243 -261.810246) (xy 130.84683 -261.810246) (xy 130.84683 -261.854442)
			(xy 130.89382 -262.006842) (xy 131.15544 -262.006842)
		)
		(stroke
			(width 0)
			(type solid)
		)
		(fill yes)
		(layer "In6.Cu")
		(net "M_G_CPU1_SA_CB<4>")
	)
	(gr_poly
		(pts
			(xy 131.20243 -260.634734) (xy 131.15544 -260.482334) (xy 130.89382 -260.482334) (xy 130.84683 -260.634734)
			(xy 130.84683 -260.679184) (xy 131.20243 -260.679184)
		)
		(stroke
			(width 0)
			(type solid)
		)
		(fill yes)
		(layer "In6.Cu")
		(net "M_G_CPU1_SA_CB<7>")
	)
	(gr_poly
		(pts
			(xy 131.44881 -231.271826) (xy 131.410456 -231.249728) (xy 131.255008 -231.214168) (xy 131.124198 -231.440736)
			(xy 131.232656 -231.557576) (xy 131.27101 -231.579674)
		)
		(stroke
			(width 0)
			(type solid)
		)
		(fill yes)
		(layer "In6.Cu")
		(net "M_H_CPU1_SB_DQ<18>")
	)
	(gr_poly
		(pts
			(xy 131.54533 -243.31295) (xy 131.49834 -243.16055) (xy 131.23672 -243.16055) (xy 131.18973 -243.31295)
			(xy 131.18973 -243.3574) (xy 131.54533 -243.3574)
		)
		(stroke
			(width 0)
			(type solid)
		)
		(fill yes)
		(layer "In6.Cu")
		(net "M_H_CPU1_SB_CS_N<1>")
	)
	(gr_poly
		(pts
			(xy 131.54533 -241.685318) (xy 131.49834 -241.532918) (xy 131.23672 -241.532918) (xy 131.18973 -241.685318)
			(xy 131.18973 -241.729514) (xy 131.54533 -241.729514)
		)
		(stroke
			(width 0)
			(type solid)
		)
		(fill yes)
		(layer "In6.Cu")
		(net "M_G_CPU1_SB_DQ<2>")
	)
	(gr_poly
		(pts
			(xy 131.54533 -241.276886) (xy 131.54533 -241.23269) (xy 131.18973 -241.23269) (xy 131.18973 -241.276886)
			(xy 131.23672 -241.429286) (xy 131.49834 -241.429286)
		)
		(stroke
			(width 0)
			(type solid)
		)
		(fill yes)
		(layer "In6.Cu")
		(net "M_G_CPU1_SB_DQ<1>")
	)
	(gr_poly
		(pts
			(xy 131.54533 -236.801914) (xy 131.49834 -236.649514) (xy 131.23672 -236.649514) (xy 131.18973 -236.801914)
			(xy 131.18973 -236.84611) (xy 131.54533 -236.84611)
		)
		(stroke
			(width 0)
			(type solid)
		)
		(fill yes)
		(layer "In6.Cu")
		(net "M_G_CPU1_SB_DQ<10>")
	)
	(gr_poly
		(pts
			(xy 131.54533 -236.39399) (xy 131.54533 -236.34954) (xy 131.18973 -236.34954) (xy 131.18973 -236.39399)
			(xy 131.23672 -236.54639) (xy 131.49834 -236.54639)
		)
		(stroke
			(width 0)
			(type solid)
		)
		(fill yes)
		(layer "In6.Cu")
		(net "M_G_CPU1_SB_DQ<11>")
	)
	(gr_poly
		(pts
			(xy 131.54533 -233.546142) (xy 131.49834 -233.393742) (xy 131.23672 -233.393742) (xy 131.18973 -233.546142)
			(xy 131.18973 -233.590592) (xy 131.54533 -233.590592)
		)
		(stroke
			(width 0)
			(type solid)
		)
		(fill yes)
		(layer "In6.Cu")
		(net "M_G_CPU1_SB_DQ<12>")
	)
	(gr_poly
		(pts
			(xy 131.54533 -233.138218) (xy 131.54533 -233.093768) (xy 131.18973 -233.093768) (xy 131.18973 -233.138218)
			(xy 131.23672 -233.290618) (xy 131.49834 -233.290618)
		)
		(stroke
			(width 0)
			(type solid)
		)
		(fill yes)
		(layer "In6.Cu")
		(net "M_G_CPU1_SB_DQ<15>")
	)
	(gr_poly
		(pts
			(xy 131.54533 -228.663246) (xy 131.49834 -228.510846) (xy 131.23672 -228.510846) (xy 131.18973 -228.663246)
			(xy 131.18973 -228.707442) (xy 131.54533 -228.707442)
		)
		(stroke
			(width 0)
			(type solid)
		)
		(fill yes)
		(layer "In6.Cu")
		(net "M_H_CPU1_SB_DQS_DP<7>")
	)
	(gr_poly
		(pts
			(xy 131.54533 -228.254814) (xy 131.54533 -228.210618) (xy 131.18973 -228.210618) (xy 131.18973 -228.254814)
			(xy 131.23672 -228.407214) (xy 131.49834 -228.407214)
		)
		(stroke
			(width 0)
			(type solid)
		)
		(fill yes)
		(layer "In6.Cu")
		(net "M_H_CPU1_SB_DQ<20>")
	)
	(gr_poly
		(pts
			(xy 131.54787 -249.416062) (xy 131.54787 -249.371612) (xy 131.19227 -249.371612) (xy 131.19227 -249.416062)
			(xy 131.23926 -249.568462) (xy 131.50088 -249.568462)
		)
		(stroke
			(width 0)
			(type solid)
		)
		(fill yes)
		(layer "In6.Cu")
		(net "M_E_CPU1_SA_RSP<0>")
	)
	(gr_poly
		(pts
			(xy 131.54787 -248.196354) (xy 131.50088 -248.043954) (xy 131.23926 -248.043954) (xy 131.19227 -248.196354)
			(xy 131.19227 -248.240804) (xy 131.54787 -248.240804)
		)
		(stroke
			(width 0)
			(type solid)
		)
		(fill yes)
		(layer "In6.Cu")
		(net "M_E_CPU1_SB_RSP<1>")
	)
	(gr_poly
		(pts
			(xy 131.54787 -244.532658) (xy 131.54787 -244.488208) (xy 131.19227 -244.488208) (xy 131.19227 -244.532658)
			(xy 131.23926 -244.685058) (xy 131.50088 -244.685058)
		)
		(stroke
			(width 0)
			(type solid)
		)
		(fill yes)
		(layer "In6.Cu")
		(net "M_H_CPU1_SB_CS_N<2>")
	)
	(gr_poly
		(pts
			(xy 131.54787 -240.057178) (xy 131.50088 -239.904778) (xy 131.23926 -239.904778) (xy 131.19227 -240.057178)
			(xy 131.19227 -240.101628) (xy 131.54787 -240.101628)
		)
		(stroke
			(width 0)
			(type solid)
		)
		(fill yes)
		(layer "In6.Cu")
		(net "M_G_CPU1_SB_DQS_DN<0>")
	)
	(gr_poly
		(pts
			(xy 131.54787 -239.649254) (xy 131.54787 -239.604804) (xy 131.19227 -239.604804) (xy 131.19227 -239.649254)
			(xy 131.23926 -239.801654) (xy 131.50088 -239.801654)
		)
		(stroke
			(width 0)
			(type solid)
		)
		(fill yes)
		(layer "In6.Cu")
		(net "M_G_CPU1_SB_DQS_DN<5>")
	)
	(gr_poly
		(pts
			(xy 131.54787 -234.76585) (xy 131.54787 -234.721654) (xy 131.19227 -234.721654) (xy 131.19227 -234.76585)
			(xy 131.23926 -234.91825) (xy 131.50088 -234.91825)
		)
		(stroke
			(width 0)
			(type solid)
		)
		(fill yes)
		(layer "In6.Cu")
		(net "M_G_CPU1_SB_DQS_DP<1>")
	)
	(gr_poly
		(pts
			(xy 131.54787 -230.290878) (xy 131.50088 -230.138478) (xy 131.23926 -230.138478) (xy 131.19227 -230.290878)
			(xy 131.19227 -230.335074) (xy 131.54787 -230.335074)
		)
		(stroke
			(width 0)
			(type solid)
		)
		(fill yes)
		(layer "In6.Cu")
		(net "M_H_CPU1_SB_DQ<19>")
	)
	(gr_poly
		(pts
			(xy 131.54787 -229.882446) (xy 131.54787 -229.83825) (xy 131.19227 -229.83825) (xy 131.19227 -229.882446)
			(xy 131.23926 -230.034846) (xy 131.50088 -230.034846)
		)
		(stroke
			(width 0)
			(type solid)
		)
		(fill yes)
		(layer "In6.Cu")
		(net "M_H_CPU1_SB_DQS_DP<2>")
	)
	(gr_poly
		(pts
			(xy 131.54787 -227.035614) (xy 131.50088 -226.883214) (xy 131.23926 -226.883214) (xy 131.19227 -227.035614)
			(xy 131.19227 -227.07981) (xy 131.54787 -227.07981)
		)
		(stroke
			(width 0)
			(type solid)
		)
		(fill yes)
		(layer "In6.Cu")
		(net "M_H_CPU1_SB_DQ<23>")
	)
	(gr_poly
		(pts
			(xy 131.557268 -238.021114) (xy 131.557268 -237.976664) (xy 131.201668 -237.976664) (xy 131.201668 -238.021114)
			(xy 131.248658 -238.173514) (xy 131.510278 -238.173514)
		)
		(stroke
			(width 0)
			(type solid)
		)
		(fill yes)
		(layer "In6.Cu")
		(net "M_G_CPU1_SB_DQ<5>")
	)
	(gr_poly
		(pts
			(xy 131.557268 -235.174282) (xy 131.510278 -235.021882) (xy 131.248658 -235.021882) (xy 131.201668 -235.174282)
			(xy 131.201668 -235.218732) (xy 131.557268 -235.218732)
		)
		(stroke
			(width 0)
			(type solid)
		)
		(fill yes)
		(layer "In6.Cu")
		(net "M_G_CPU1_SB_DQS_DP<6>")
	)
	(gr_poly
		(pts
			(xy 131.55803 -238.430054) (xy 131.51104 -238.277654) (xy 131.24942 -238.277654) (xy 131.20243 -238.430054)
			(xy 131.20243 -238.47425) (xy 131.55803 -238.47425)
		)
		(stroke
			(width 0)
			(type solid)
		)
		(fill yes)
		(layer "In6.Cu")
		(net "M_G_CPU1_SB_DQ<6>")
	)
	(gr_poly
		(pts
			(xy 131.627626 -231.988868) (xy 131.519168 -231.872028) (xy 131.480814 -231.84993) (xy 131.303014 -232.157778)
			(xy 131.341368 -232.179876) (xy 131.496816 -232.215436)
		)
		(stroke
			(width 0)
			(type solid)
		)
		(fill yes)
		(layer "In6.Cu")
		(net "M_H_CPU1_SB_DQ<16>")
	)
	(gr_poly
		(pts
			(xy 131.655312 -276.098762) (xy 131.608322 -275.946362) (xy 131.346702 -275.946362) (xy 131.299712 -276.098762)
			(xy 131.299712 -276.143212) (xy 131.655312 -276.143212)
		)
		(stroke
			(width 0)
			(type solid)
		)
		(fill yes)
		(layer "In6.Cu")
		(net "M_H_CPU1_SA_DQ<6>")
	)
	(gr_poly
		(pts
			(xy 131.655312 -275.690584) (xy 131.655312 -275.646388) (xy 131.299712 -275.646388) (xy 131.299712 -275.690584)
			(xy 131.346702 -275.842984) (xy 131.608322 -275.842984)
		)
		(stroke
			(width 0)
			(type solid)
		)
		(fill yes)
		(layer "In6.Cu")
		(net "M_H_CPU1_SA_DQ<5>")
	)
	(gr_poly
		(pts
			(xy 131.655312 -274.47113) (xy 131.608322 -274.31873) (xy 131.346702 -274.31873) (xy 131.299712 -274.47113)
			(xy 131.299712 -274.515326) (xy 131.655312 -274.515326)
		)
		(stroke
			(width 0)
			(type solid)
		)
		(fill yes)
		(layer "In6.Cu")
		(net "M_G_CPU1_SA_DQ<10>")
	)
	(gr_poly
		(pts
			(xy 131.655312 -274.062698) (xy 131.655312 -274.018502) (xy 131.299712 -274.018502) (xy 131.299712 -274.062698)
			(xy 131.346702 -274.215098) (xy 131.608322 -274.215098)
		)
		(stroke
			(width 0)
			(type solid)
		)
		(fill yes)
		(layer "In6.Cu")
		(net "M_G_CPU1_SA_DQ<9>")
	)
	(gr_poly
		(pts
			(xy 131.655312 -270.807434) (xy 131.655312 -270.762984) (xy 131.299712 -270.762984) (xy 131.299712 -270.807434)
			(xy 131.346702 -270.959834) (xy 131.608322 -270.959834)
		)
		(stroke
			(width 0)
			(type solid)
		)
		(fill yes)
		(layer "In6.Cu")
		(net "M_G_CPU1_SA_DQ<13>")
	)
	(gr_poly
		(pts
			(xy 131.655312 -269.587726) (xy 131.608322 -269.435326) (xy 131.346702 -269.435326) (xy 131.299712 -269.587726)
			(xy 131.299712 -269.631922) (xy 131.655312 -269.631922)
		)
		(stroke
			(width 0)
			(type solid)
		)
		(fill yes)
		(layer "In6.Cu")
		(net "M_G_CPU1_SA_DQ<26>")
	)
	(gr_poly
		(pts
			(xy 131.655312 -261.449058) (xy 131.608322 -261.296658) (xy 131.346702 -261.296658) (xy 131.299712 -261.449058)
			(xy 131.299712 -261.493254) (xy 131.655312 -261.493254)
		)
		(stroke
			(width 0)
			(type solid)
		)
		(fill yes)
		(layer "In6.Cu")
		(net "M_G_CPU1_SA_CB<6>")
	)
	(gr_poly
		(pts
			(xy 131.655312 -261.040626) (xy 131.655312 -260.99643) (xy 131.299712 -260.99643) (xy 131.299712 -261.040626)
			(xy 131.346702 -261.193026) (xy 131.608322 -261.193026)
		)
		(stroke
			(width 0)
			(type solid)
		)
		(fill yes)
		(layer "In6.Cu")
		(net "M_G_CPU1_SA_CB<5>")
	)
	(gr_poly
		(pts
			(xy 131.657852 -278.946102) (xy 131.657852 -278.901906) (xy 131.302252 -278.901906) (xy 131.302252 -278.946102)
			(xy 131.349242 -279.098502) (xy 131.610862 -279.098502)
		)
		(stroke
			(width 0)
			(type solid)
		)
		(fill yes)
		(layer "In6.Cu")
		(net "M_H_CPU1_SA_DQ<3>")
	)
	(gr_poly
		(pts
			(xy 131.657852 -277.726902) (xy 131.610862 -277.574502) (xy 131.349242 -277.574502) (xy 131.302252 -277.726902)
			(xy 131.302252 -277.771098) (xy 131.657852 -277.771098)
		)
		(stroke
			(width 0)
			(type solid)
		)
		(fill yes)
		(layer "In6.Cu")
		(net "M_H_CPU1_SA_DQS_DN<0>")
	)
	(gr_poly
		(pts
			(xy 131.657852 -277.317962) (xy 131.657852 -277.273766) (xy 131.302252 -277.273766) (xy 131.302252 -277.317962)
			(xy 131.349242 -277.470362) (xy 131.610862 -277.470362)
		)
		(stroke
			(width 0)
			(type solid)
		)
		(fill yes)
		(layer "In6.Cu")
		(net "M_H_CPU1_SA_DQS_DN<5>")
	)
	(gr_poly
		(pts
			(xy 131.657852 -272.843498) (xy 131.610862 -272.691098) (xy 131.349242 -272.691098) (xy 131.302252 -272.843498)
			(xy 131.302252 -272.887694) (xy 131.657852 -272.887694)
		)
		(stroke
			(width 0)
			(type solid)
		)
		(fill yes)
		(layer "In6.Cu")
		(net "M_G_CPU1_SA_DQS_DN<1>")
	)
	(gr_poly
		(pts
			(xy 131.657852 -272.435066) (xy 131.657852 -272.39087) (xy 131.302252 -272.39087) (xy 131.302252 -272.435066)
			(xy 131.349242 -272.587466) (xy 131.610862 -272.587466)
		)
		(stroke
			(width 0)
			(type solid)
		)
		(fill yes)
		(layer "In6.Cu")
		(net "M_G_CPU1_SA_DQS_DN<6>")
	)
	(gr_poly
		(pts
			(xy 131.657852 -267.960094) (xy 131.610862 -267.807694) (xy 131.349242 -267.807694) (xy 131.302252 -267.960094)
			(xy 131.302252 -268.00429) (xy 131.657852 -268.00429)
		)
		(stroke
			(width 0)
			(type solid)
		)
		(fill yes)
		(layer "In6.Cu")
		(net "M_G_CPU1_SA_DQS_DN<3>")
	)
	(gr_poly
		(pts
			(xy 131.657852 -267.551662) (xy 131.657852 -267.507466) (xy 131.302252 -267.507466) (xy 131.302252 -267.551662)
			(xy 131.349242 -267.704062) (xy 131.610862 -267.704062)
		)
		(stroke
			(width 0)
			(type solid)
		)
		(fill yes)
		(layer "In6.Cu")
		(net "M_G_CPU1_SA_DQS_DN<8>")
	)
	(gr_poly
		(pts
			(xy 131.657852 -263.07669) (xy 131.610862 -262.92429) (xy 131.349242 -262.92429) (xy 131.302252 -263.07669)
			(xy 131.302252 -263.120886) (xy 131.657852 -263.120886)
		)
		(stroke
			(width 0)
			(type solid)
		)
		(fill yes)
		(layer "In6.Cu")
		(net "M_G_CPU1_SA_DQS_DN<4>")
	)
	(gr_poly
		(pts
			(xy 131.657852 -262.668258) (xy 131.657852 -262.624062) (xy 131.302252 -262.624062) (xy 131.302252 -262.668258)
			(xy 131.349242 -262.820658) (xy 131.610862 -262.820658)
		)
		(stroke
			(width 0)
			(type solid)
		)
		(fill yes)
		(layer "In6.Cu")
		(net "M_G_CPU1_SA_DQS_DN<9>")
	)
	(gr_poly
		(pts
			(xy 131.66725 -271.215866) (xy 131.62026 -271.063466) (xy 131.35864 -271.063466) (xy 131.31165 -271.215866)
			(xy 131.31165 -271.260062) (xy 131.66725 -271.260062)
		)
		(stroke
			(width 0)
			(type solid)
		)
		(fill yes)
		(layer "In6.Cu")
		(net "M_G_CPU1_SA_DQ<14>")
	)
	(gr_poly
		(pts
			(xy 131.66725 -269.179294) (xy 131.66725 -269.134844) (xy 131.31165 -269.134844) (xy 131.31165 -269.179294)
			(xy 131.35864 -269.331694) (xy 131.62026 -269.331694)
		)
		(stroke
			(width 0)
			(type solid)
		)
		(fill yes)
		(layer "In6.Cu")
		(net "M_G_CPU1_SA_DQ<25>")
	)
	(gr_poly
		(pts
			(xy 131.66725 -266.332462) (xy 131.62026 -266.180062) (xy 131.35864 -266.180062) (xy 131.31165 -266.332462)
			(xy 131.31165 -266.376658) (xy 131.66725 -266.376658)
		)
		(stroke
			(width 0)
			(type solid)
		)
		(fill yes)
		(layer "In6.Cu")
		(net "M_G_CPU1_SA_DQ<30>")
	)
	(gr_poly
		(pts
			(xy 131.66725 -265.923522) (xy 131.66725 -265.879326) (xy 131.31165 -265.879326) (xy 131.31165 -265.923522)
			(xy 131.35864 -266.075922) (xy 131.62026 -266.075922)
		)
		(stroke
			(width 0)
			(type solid)
		)
		(fill yes)
		(layer "In6.Cu")
		(net "M_G_CPU1_SA_DQ<29>")
	)
	(gr_poly
		(pts
			(xy 131.66725 -264.29589) (xy 131.66725 -264.25144) (xy 131.31165 -264.25144) (xy 131.31165 -264.29589)
			(xy 131.35864 -264.44829) (xy 131.62026 -264.44829)
		)
		(stroke
			(width 0)
			(type solid)
		)
		(fill yes)
		(layer "In6.Cu")
		(net "M_G_CPU1_SA_CB<1>")
	)
	(gr_poly
		(pts
			(xy 131.668012 -264.70483) (xy 131.621022 -264.55243) (xy 131.359402 -264.55243) (xy 131.312412 -264.70483)
			(xy 131.312412 -264.749026) (xy 131.668012 -264.749026)
		)
		(stroke
			(width 0)
			(type solid)
		)
		(fill yes)
		(layer "In6.Cu")
		(net "M_G_CPU1_SA_CB<2>")
	)
	(gr_poly
		(pts
			(xy 132.01777 -240.46307) (xy 132.01777 -240.41862) (xy 131.66217 -240.41862) (xy 131.66217 -240.46307)
			(xy 131.70916 -240.61547) (xy 131.97078 -240.61547)
		)
		(stroke
			(width 0)
			(type solid)
		)
		(fill yes)
		(layer "In6.Cu")
		(net "M_G_CPU1_SB_DQS_DP<0>")
	)
	(gr_poly
		(pts
			(xy 132.01777 -230.696262) (xy 132.01777 -230.651812) (xy 131.66217 -230.651812) (xy 131.66217 -230.696262)
			(xy 131.70916 -230.848662) (xy 131.97078 -230.848662)
		)
		(stroke
			(width 0)
			(type solid)
		)
		(fill yes)
		(layer "In6.Cu")
		(net "M_H_CPU1_SB_DQ<17>")
	)
	(gr_poly
		(pts
			(xy 132.019548 -238.83493) (xy 132.019548 -238.790734) (xy 131.663948 -238.790734) (xy 131.663948 -238.83493)
			(xy 131.710938 -238.98733) (xy 131.972558 -238.98733)
		)
		(stroke
			(width 0)
			(type solid)
		)
		(fill yes)
		(layer "In6.Cu")
		(net "M_G_CPU1_SB_DQ<4>")
	)
	(gr_poly
		(pts
			(xy 132.019548 -233.951526) (xy 132.019548 -233.90733) (xy 131.663948 -233.90733) (xy 131.663948 -233.951526)
			(xy 131.710938 -234.103926) (xy 131.972558 -234.103926)
		)
		(stroke
			(width 0)
			(type solid)
		)
		(fill yes)
		(layer "In6.Cu")
		(net "M_G_CPU1_SB_DQ<14>")
	)
	(gr_poly
		(pts
			(xy 132.02031 -237.616238) (xy 131.97332 -237.463838) (xy 131.7117 -237.463838) (xy 131.66471 -237.616238)
			(xy 131.66471 -237.660434) (xy 132.02031 -237.660434)
		)
		(stroke
			(width 0)
			(type solid)
		)
		(fill yes)
		(layer "In6.Cu")
		(net "M_G_CPU1_SB_DQ<7>")
	)
	(gr_poly
		(pts
			(xy 132.02031 -235.579666) (xy 132.02031 -235.535216) (xy 131.66471 -235.535216) (xy 131.66471 -235.579666)
			(xy 131.7117 -235.732066) (xy 131.97332 -235.732066)
		)
		(stroke
			(width 0)
			(type solid)
		)
		(fill yes)
		(layer "In6.Cu")
		(net "M_G_CPU1_SB_DQS_DN<6>")
	)
	(gr_poly
		(pts
			(xy 132.023866 -249.010678) (xy 131.976876 -248.858278) (xy 131.715256 -248.858278) (xy 131.668266 -249.010678)
			(xy 131.668266 -249.054874) (xy 132.023866 -249.054874)
		)
		(stroke
			(width 0)
			(type solid)
		)
		(fill yes)
		(layer "In6.Cu")
		(net "M_E_CPU1_SB_RSP<0>")
	)
	(gr_poly
		(pts
			(xy 132.023866 -244.127274) (xy 131.976876 -243.974874) (xy 131.715256 -243.974874) (xy 131.668266 -244.127274)
			(xy 131.668266 -244.17147) (xy 132.023866 -244.17147)
		)
		(stroke
			(width 0)
			(type solid)
		)
		(fill yes)
		(layer "In6.Cu")
		(net "M_H_CPU1_SB_CS_N<3>")
	)
	(gr_poly
		(pts
			(xy 132.023866 -239.24387) (xy 131.976876 -239.09147) (xy 131.715256 -239.09147) (xy 131.668266 -239.24387)
			(xy 131.668266 -239.288066) (xy 132.023866 -239.288066)
		)
		(stroke
			(width 0)
			(type solid)
		)
		(fill yes)
		(layer "In6.Cu")
		(net "M_G_CPU1_SB_DQS_DP<5>")
	)
	(gr_poly
		(pts
			(xy 132.023866 -234.360466) (xy 131.976876 -234.208066) (xy 131.715256 -234.208066) (xy 131.668266 -234.360466)
			(xy 131.668266 -234.404916) (xy 132.023866 -234.404916)
		)
		(stroke
			(width 0)
			(type solid)
		)
		(fill yes)
		(layer "In6.Cu")
		(net "M_G_CPU1_SB_DQS_DN<1>")
	)
	(gr_poly
		(pts
			(xy 132.023866 -229.477062) (xy 131.976876 -229.324662) (xy 131.715256 -229.324662) (xy 131.668266 -229.477062)
			(xy 131.668266 -229.521512) (xy 132.023866 -229.521512)
		)
		(stroke
			(width 0)
			(type solid)
		)
		(fill yes)
		(layer "In6.Cu")
		(net "M_H_CPU1_SB_DQS_DN<2>")
	)
	(gr_poly
		(pts
			(xy 132.029708 -240.871502) (xy 131.982718 -240.719102) (xy 131.721098 -240.719102) (xy 131.674108 -240.871502)
			(xy 131.674108 -240.915952) (xy 132.029708 -240.915952)
		)
		(stroke
			(width 0)
			(type solid)
		)
		(fill yes)
		(layer "In6.Cu")
		(net "M_G_CPU1_SB_DQ<3>")
	)
	(gr_poly
		(pts
			(xy 132.029708 -235.988098) (xy 131.982718 -235.835698) (xy 131.721098 -235.835698) (xy 131.674108 -235.988098)
			(xy 131.674108 -236.032548) (xy 132.029708 -236.032548)
		)
		(stroke
			(width 0)
			(type solid)
		)
		(fill yes)
		(layer "In6.Cu")
		(net "M_G_CPU1_SB_DQ<9>")
	)
	(gr_poly
		(pts
			(xy 132.029708 -231.104694) (xy 131.982718 -230.952294) (xy 131.721098 -230.952294) (xy 131.674108 -231.104694)
			(xy 131.674108 -231.149144) (xy 132.029708 -231.149144)
		)
		(stroke
			(width 0)
			(type solid)
		)
		(fill yes)
		(layer "In6.Cu")
		(net "M_H_CPU1_SB_DQ<18>")
	)
	(gr_poly
		(pts
			(xy 132.032248 -248.602246) (xy 132.032248 -248.557796) (xy 131.676648 -248.557796) (xy 131.676648 -248.602246)
			(xy 131.723638 -248.754646) (xy 131.985258 -248.754646)
		)
		(stroke
			(width 0)
			(type solid)
		)
		(fill yes)
		(layer "In6.Cu")
		(net "M_E_CPU1_SA_RSP<1>")
	)
	(gr_poly
		(pts
			(xy 132.032248 -243.718842) (xy 132.032248 -243.674392) (xy 131.676648 -243.674392) (xy 131.676648 -243.718842)
			(xy 131.723638 -243.871242) (xy 131.985258 -243.871242)
		)
		(stroke
			(width 0)
			(type solid)
		)
		(fill yes)
		(layer "In6.Cu")
		(net "M_H_CPU1_SB_CS_N<0>")
	)
	(gr_poly
		(pts
			(xy 132.032248 -242.090702) (xy 132.032248 -242.046506) (xy 131.676648 -242.046506) (xy 131.676648 -242.090702)
			(xy 131.723638 -242.243102) (xy 131.985258 -242.243102)
		)
		(stroke
			(width 0)
			(type solid)
		)
		(fill yes)
		(layer "In6.Cu")
		(net "M_G_CPU1_SB_DQ<0>")
	)
	(gr_poly
		(pts
			(xy 132.032248 -237.207806) (xy 132.032248 -237.163356) (xy 131.676648 -237.163356) (xy 131.676648 -237.207806)
			(xy 131.723638 -237.360206) (xy 131.985258 -237.360206)
		)
		(stroke
			(width 0)
			(type solid)
		)
		(fill yes)
		(layer "In6.Cu")
		(net "M_G_CPU1_SB_DQ<8>")
	)
	(gr_poly
		(pts
			(xy 132.032248 -232.732326) (xy 131.985258 -232.579926) (xy 131.723638 -232.579926) (xy 131.676648 -232.732326)
			(xy 131.676648 -232.776776) (xy 132.032248 -232.776776)
		)
		(stroke
			(width 0)
			(type solid)
		)
		(fill yes)
		(layer "In6.Cu")
		(net "M_G_CPU1_SB_DQ<13>")
	)
	(gr_poly
		(pts
			(xy 132.032248 -229.06863) (xy 132.032248 -229.024434) (xy 131.676648 -229.024434) (xy 131.676648 -229.06863)
			(xy 131.723638 -229.22103) (xy 131.985258 -229.22103)
		)
		(stroke
			(width 0)
			(type solid)
		)
		(fill yes)
		(layer "In6.Cu")
		(net "M_H_CPU1_SB_DQS_DN<7>")
	)
	(gr_poly
		(pts
			(xy 132.032248 -227.848922) (xy 131.985258 -227.696522) (xy 131.723638 -227.696522) (xy 131.676648 -227.848922)
			(xy 131.676648 -227.893372) (xy 132.032248 -227.893372)
		)
		(stroke
			(width 0)
			(type solid)
		)
		(fill yes)
		(layer "In6.Cu")
		(net "M_H_CPU1_SB_DQ<22>")
	)
	(gr_poly
		(pts
			(xy 132.032248 -227.440998) (xy 132.032248 -227.396548) (xy 131.676648 -227.396548) (xy 131.676648 -227.440998)
			(xy 131.723638 -227.593398) (xy 131.985258 -227.593398)
		)
		(stroke
			(width 0)
			(type solid)
		)
		(fill yes)
		(layer "In6.Cu")
		(net "M_H_CPU1_SB_DQ<21>")
	)
	(gr_poly
		(pts
			(xy 132.127752 -279.759664) (xy 132.127752 -279.715468) (xy 131.772152 -279.715468) (xy 131.772152 -279.759664)
			(xy 131.819142 -279.912064) (xy 132.080762 -279.912064)
		)
		(stroke
			(width 0)
			(type solid)
		)
		(fill yes)
		(layer "In6.Cu")
		(net "M_H_CPU1_SA_DQ<0>")
	)
	(gr_poly
		(pts
			(xy 132.127752 -272.029682) (xy 132.080762 -271.877282) (xy 131.819142 -271.877282) (xy 131.772152 -272.029682)
			(xy 131.772152 -272.073878) (xy 132.127752 -272.073878)
		)
		(stroke
			(width 0)
			(type solid)
		)
		(fill yes)
		(layer "In6.Cu")
		(net "M_G_CPU1_SA_DQS_DP<6>")
	)
	(gr_poly
		(pts
			(xy 132.127752 -267.146278) (xy 132.080762 -266.993878) (xy 131.819142 -266.993878) (xy 131.772152 -267.146278)
			(xy 131.772152 -267.190728) (xy 132.127752 -267.190728)
		)
		(stroke
			(width 0)
			(type solid)
		)
		(fill yes)
		(layer "In6.Cu")
		(net "M_G_CPU1_SA_DQS_DP<8>")
	)
	(gr_poly
		(pts
			(xy 132.127752 -262.262874) (xy 132.080762 -262.110474) (xy 131.819142 -262.110474) (xy 131.772152 -262.262874)
			(xy 131.772152 -262.307324) (xy 132.127752 -262.307324)
		)
		(stroke
			(width 0)
			(type solid)
		)
		(fill yes)
		(layer "In6.Cu")
		(net "M_G_CPU1_SA_DQS_DP<9>")
	)
	(gr_poly
		(pts
			(xy 132.12953 -265.109706) (xy 132.12953 -265.06551) (xy 131.77393 -265.06551) (xy 131.77393 -265.109706)
			(xy 131.82092 -265.262106) (xy 132.08254 -265.262106)
		)
		(stroke
			(width 0)
			(type solid)
		)
		(fill yes)
		(layer "In6.Cu")
		(net "M_G_CPU1_SA_CB<0>")
	)
	(gr_poly
		(pts
			(xy 132.130292 -271.62125) (xy 132.130292 -271.5768) (xy 131.774692 -271.5768) (xy 131.774692 -271.62125)
			(xy 131.821682 -271.77365) (xy 132.083302 -271.77365)
		)
		(stroke
			(width 0)
			(type solid)
		)
		(fill yes)
		(layer "In6.Cu")
		(net "M_G_CPU1_SA_DQ<12>")
	)
	(gr_poly
		(pts
			(xy 132.130292 -266.737846) (xy 132.130292 -266.693396) (xy 131.774692 -266.693396) (xy 131.774692 -266.737846)
			(xy 131.821682 -266.890246) (xy 132.083302 -266.890246)
		)
		(stroke
			(width 0)
			(type solid)
		)
		(fill yes)
		(layer "In6.Cu")
		(net "M_G_CPU1_SA_DQ<28>")
	)
	(gr_poly
		(pts
			(xy 132.130292 -265.518646) (xy 132.083302 -265.366246) (xy 131.821682 -265.366246) (xy 131.774692 -265.518646)
			(xy 131.774692 -265.563096) (xy 132.130292 -265.563096)
		)
		(stroke
			(width 0)
			(type solid)
		)
		(fill yes)
		(layer "In6.Cu")
		(net "M_G_CPU1_SA_DQ<31>")
	)
	(gr_poly
		(pts
			(xy 132.130292 -263.891014) (xy 132.083302 -263.738614) (xy 131.821682 -263.738614) (xy 131.774692 -263.891014)
			(xy 131.774692 -263.93521) (xy 132.130292 -263.93521)
		)
		(stroke
			(width 0)
			(type solid)
		)
		(fill yes)
		(layer "In6.Cu")
		(net "M_G_CPU1_SA_CB<3>")
	)
	(gr_poly
		(pts
			(xy 132.133848 -278.540718) (xy 132.086858 -278.388318) (xy 131.825238 -278.388318) (xy 131.778248 -278.540718)
			(xy 131.778248 -278.585168) (xy 132.133848 -278.585168)
		)
		(stroke
			(width 0)
			(type solid)
		)
		(fill yes)
		(layer "In6.Cu")
		(net "M_H_CPU1_SA_DQ<1>")
	)
	(gr_poly
		(pts
			(xy 132.133848 -273.248882) (xy 132.133848 -273.204432) (xy 131.778248 -273.204432) (xy 131.778248 -273.248882)
			(xy 131.825238 -273.401282) (xy 132.086858 -273.401282)
		)
		(stroke
			(width 0)
			(type solid)
		)
		(fill yes)
		(layer "In6.Cu")
		(net "M_G_CPU1_SA_DQS_DP<1>")
	)
	(gr_poly
		(pts
			(xy 132.133848 -268.365478) (xy 132.133848 -268.321028) (xy 131.778248 -268.321028) (xy 131.778248 -268.365478)
			(xy 131.825238 -268.517878) (xy 132.086858 -268.517878)
		)
		(stroke
			(width 0)
			(type solid)
		)
		(fill yes)
		(layer "In6.Cu")
		(net "M_G_CPU1_SA_DQS_DP<3>")
	)
	(gr_poly
		(pts
			(xy 132.133848 -263.482074) (xy 132.133848 -263.437878) (xy 131.778248 -263.437878) (xy 131.778248 -263.482074)
			(xy 131.825238 -263.634474) (xy 132.086858 -263.634474)
		)
		(stroke
			(width 0)
			(type solid)
		)
		(fill yes)
		(layer "In6.Cu")
		(net "M_G_CPU1_SA_DQS_DP<4>")
	)
	(gr_poly
		(pts
			(xy 132.13969 -276.913086) (xy 132.0927 -276.760686) (xy 131.83108 -276.760686) (xy 131.78409 -276.913086)
			(xy 131.78409 -276.957282) (xy 132.13969 -276.957282)
		)
		(stroke
			(width 0)
			(type solid)
		)
		(fill yes)
		(layer "In6.Cu")
		(net "M_H_CPU1_SA_DQS_DP<5>")
	)
	(gr_poly
		(pts
			(xy 132.13969 -276.504146) (xy 132.13969 -276.45995) (xy 131.78409 -276.45995) (xy 131.78409 -276.504146)
			(xy 131.83108 -276.656546) (xy 132.0927 -276.656546)
		)
		(stroke
			(width 0)
			(type solid)
		)
		(fill yes)
		(layer "In6.Cu")
		(net "M_H_CPU1_SA_DQ<4>")
	)
	(gr_poly
		(pts
			(xy 132.13969 -261.854442) (xy 132.13969 -261.809992) (xy 131.78409 -261.809992) (xy 131.78409 -261.854442)
			(xy 131.83108 -262.006842) (xy 132.0927 -262.006842)
		)
		(stroke
			(width 0)
			(type solid)
		)
		(fill yes)
		(layer "In6.Cu")
		(net "M_G_CPU1_SA_CB<4>")
	)
	(gr_poly
		(pts
			(xy 132.14223 -278.132286) (xy 132.14223 -278.08809) (xy 131.78663 -278.08809) (xy 131.78663 -278.132286)
			(xy 131.83362 -278.284686) (xy 132.09524 -278.284686)
		)
		(stroke
			(width 0)
			(type solid)
		)
		(fill yes)
		(layer "In6.Cu")
		(net "M_H_CPU1_SA_DQS_DP<0>")
	)
	(gr_poly
		(pts
			(xy 132.14223 -275.284946) (xy 132.09524 -275.132546) (xy 131.83362 -275.132546) (xy 131.78663 -275.284946)
			(xy 131.78663 -275.329142) (xy 132.14223 -275.329142)
		)
		(stroke
			(width 0)
			(type solid)
		)
		(fill yes)
		(layer "In6.Cu")
		(net "M_H_CPU1_SA_DQ<7>")
	)
	(gr_poly
		(pts
			(xy 132.14223 -274.876514) (xy 132.14223 -274.832318) (xy 131.78663 -274.832318) (xy 131.78663 -274.876514)
			(xy 131.83362 -275.028914) (xy 132.09524 -275.028914)
		)
		(stroke
			(width 0)
			(type solid)
		)
		(fill yes)
		(layer "In6.Cu")
		(net "M_G_CPU1_SA_DQ<8>")
	)
	(gr_poly
		(pts
			(xy 132.14223 -273.657314) (xy 132.09524 -273.504914) (xy 131.83362 -273.504914) (xy 131.78663 -273.657314)
			(xy 131.78663 -273.70151) (xy 132.14223 -273.70151)
		)
		(stroke
			(width 0)
			(type solid)
		)
		(fill yes)
		(layer "In6.Cu")
		(net "M_G_CPU1_SA_DQ<11>")
	)
	(gr_poly
		(pts
			(xy 132.14223 -270.401542) (xy 132.09524 -270.249142) (xy 131.83362 -270.249142) (xy 131.78663 -270.401542)
			(xy 131.78663 -270.445992) (xy 132.14223 -270.445992)
		)
		(stroke
			(width 0)
			(type solid)
		)
		(fill yes)
		(layer "In6.Cu")
		(net "M_G_CPU1_SA_DQ<15>")
	)
	(gr_poly
		(pts
			(xy 132.14223 -269.993618) (xy 132.14223 -269.949168) (xy 131.78663 -269.949168) (xy 131.78663 -269.993618)
			(xy 131.83362 -270.146018) (xy 132.09524 -270.146018)
		)
		(stroke
			(width 0)
			(type solid)
		)
		(fill yes)
		(layer "In6.Cu")
		(net "M_G_CPU1_SA_DQ<24>")
	)
	(gr_poly
		(pts
			(xy 132.14223 -268.77391) (xy 132.09524 -268.62151) (xy 131.83362 -268.62151) (xy 131.78663 -268.77391)
			(xy 131.78663 -268.818106) (xy 132.14223 -268.818106)
		)
		(stroke
			(width 0)
			(type solid)
		)
		(fill yes)
		(layer "In6.Cu")
		(net "M_G_CPU1_SA_DQ<27>")
	)
	(gr_poly
		(pts
			(xy 132.14223 -260.634734) (xy 132.09524 -260.482334) (xy 131.83362 -260.482334) (xy 131.78663 -260.634734)
			(xy 131.78663 -260.679184) (xy 132.14223 -260.679184)
		)
		(stroke
			(width 0)
			(type solid)
		)
		(fill yes)
		(layer "In6.Cu")
		(net "M_G_CPU1_SA_CB<7>")
	)
	(gr_poly
		(pts
			(xy 132.48513 -241.685318) (xy 132.43814 -241.532918) (xy 132.17652 -241.532918) (xy 132.12953 -241.685318)
			(xy 132.12953 -241.729514) (xy 132.48513 -241.729514)
		)
		(stroke
			(width 0)
			(type solid)
		)
		(fill yes)
		(layer "In6.Cu")
		(net "M_G_CPU1_SB_DQ<2>")
	)
	(gr_poly
		(pts
			(xy 132.48513 -236.801914) (xy 132.43814 -236.649514) (xy 132.17652 -236.649514) (xy 132.12953 -236.801914)
			(xy 132.12953 -236.84611) (xy 132.48513 -236.84611)
		)
		(stroke
			(width 0)
			(type solid)
		)
		(fill yes)
		(layer "In6.Cu")
		(net "M_G_CPU1_SB_DQ<10>")
	)
	(gr_poly
		(pts
			(xy 132.48513 -227.035106) (xy 132.43814 -226.882706) (xy 132.17652 -226.882706) (xy 132.12953 -227.035106)
			(xy 132.12953 -227.079556) (xy 132.48513 -227.079556)
		)
		(stroke
			(width 0)
			(type solid)
		)
		(fill yes)
		(layer "In6.Cu")
		(net "M_H_CPU1_SB_DQ<23>")
	)
	(gr_poly
		(pts
			(xy 132.48767 -248.196354) (xy 132.44068 -248.043954) (xy 132.17906 -248.043954) (xy 132.13207 -248.196354)
			(xy 132.13207 -248.24055) (xy 132.48767 -248.24055)
		)
		(stroke
			(width 0)
			(type solid)
		)
		(fill yes)
		(layer "In6.Cu")
		(net "M_E_CPU1_SB_RSP<1>")
	)
	(gr_poly
		(pts
			(xy 132.48767 -244.53215) (xy 132.48767 -244.487954) (xy 132.13207 -244.487954) (xy 132.13207 -244.53215)
			(xy 132.17906 -244.68455) (xy 132.44068 -244.68455)
		)
		(stroke
			(width 0)
			(type solid)
		)
		(fill yes)
		(layer "In6.Cu")
		(net "M_H_CPU1_SB_CS_N<2>")
	)
	(gr_poly
		(pts
			(xy 132.48767 -243.31295) (xy 132.44068 -243.16055) (xy 132.17906 -243.16055) (xy 132.13207 -243.31295)
			(xy 132.13207 -243.3574) (xy 132.48767 -243.3574)
		)
		(stroke
			(width 0)
			(type solid)
		)
		(fill yes)
		(layer "In6.Cu")
		(net "M_H_CPU1_SB_CS_N<1>")
	)
	(gr_poly
		(pts
			(xy 132.48767 -239.648746) (xy 132.48767 -239.60455) (xy 132.13207 -239.60455) (xy 132.13207 -239.648746)
			(xy 132.17906 -239.801146) (xy 132.44068 -239.801146)
		)
		(stroke
			(width 0)
			(type solid)
		)
		(fill yes)
		(layer "In6.Cu")
		(net "M_G_CPU1_SB_DQS_DN<5>")
	)
	(gr_poly
		(pts
			(xy 132.48767 -234.76585) (xy 132.48767 -234.7214) (xy 132.13207 -234.7214) (xy 132.13207 -234.76585)
			(xy 132.17906 -234.91825) (xy 132.44068 -234.91825)
		)
		(stroke
			(width 0)
			(type solid)
		)
		(fill yes)
		(layer "In6.Cu")
		(net "M_G_CPU1_SB_DQS_DP<1>")
	)
	(gr_poly
		(pts
			(xy 132.48767 -233.546142) (xy 132.44068 -233.393742) (xy 132.17906 -233.393742) (xy 132.13207 -233.546142)
			(xy 132.13207 -233.590592) (xy 132.48767 -233.590592)
		)
		(stroke
			(width 0)
			(type solid)
		)
		(fill yes)
		(layer "In6.Cu")
		(net "M_G_CPU1_SB_DQ<12>")
	)
	(gr_poly
		(pts
			(xy 132.48767 -233.138218) (xy 132.48767 -233.093768) (xy 132.13207 -233.093768) (xy 132.13207 -233.138218)
			(xy 132.17906 -233.290618) (xy 132.44068 -233.290618)
		)
		(stroke
			(width 0)
			(type solid)
		)
		(fill yes)
		(layer "In6.Cu")
		(net "M_G_CPU1_SB_DQ<15>")
	)
	(gr_poly
		(pts
			(xy 132.48767 -229.882446) (xy 132.48767 -229.837996) (xy 132.13207 -229.837996) (xy 132.13207 -229.882446)
			(xy 132.17906 -230.034846) (xy 132.44068 -230.034846)
		)
		(stroke
			(width 0)
			(type solid)
		)
		(fill yes)
		(layer "In6.Cu")
		(net "M_H_CPU1_SB_DQS_DP<2>")
	)
	(gr_poly
		(pts
			(xy 132.48767 -228.663246) (xy 132.44068 -228.510846) (xy 132.17906 -228.510846) (xy 132.13207 -228.663246)
			(xy 132.13207 -228.707442) (xy 132.48767 -228.707442)
		)
		(stroke
			(width 0)
			(type solid)
		)
		(fill yes)
		(layer "In6.Cu")
		(net "M_H_CPU1_SB_DQS_DP<7>")
	)
	(gr_poly
		(pts
			(xy 132.48767 -228.254814) (xy 132.48767 -228.210618) (xy 132.13207 -228.210618) (xy 132.13207 -228.254814)
			(xy 132.17906 -228.407214) (xy 132.44068 -228.407214)
		)
		(stroke
			(width 0)
			(type solid)
		)
		(fill yes)
		(layer "In6.Cu")
		(net "M_H_CPU1_SB_DQ<20>")
	)
	(gr_poly
		(pts
			(xy 132.493512 -241.276886) (xy 132.493512 -241.232436) (xy 132.137912 -241.232436) (xy 132.137912 -241.276886)
			(xy 132.184902 -241.429286) (xy 132.446522 -241.429286)
		)
		(stroke
			(width 0)
			(type solid)
		)
		(fill yes)
		(layer "In6.Cu")
		(net "M_G_CPU1_SB_DQ<1>")
	)
	(gr_poly
		(pts
			(xy 132.493512 -236.393482) (xy 132.493512 -236.349286) (xy 132.137912 -236.349286) (xy 132.137912 -236.393482)
			(xy 132.184902 -236.545882) (xy 132.446522 -236.545882)
		)
		(stroke
			(width 0)
			(type solid)
		)
		(fill yes)
		(layer "In6.Cu")
		(net "M_G_CPU1_SB_DQ<11>")
	)
	(gr_poly
		(pts
			(xy 132.493512 -231.510078) (xy 132.493512 -231.465882) (xy 132.137912 -231.465882) (xy 132.137912 -231.510078)
			(xy 132.184902 -231.662478) (xy 132.446522 -231.662478)
		)
		(stroke
			(width 0)
			(type solid)
		)
		(fill yes)
		(layer "In6.Cu")
		(net "M_H_CPU1_SB_DQ<16>")
	)
	(gr_poly
		(pts
			(xy 132.493766 -249.415554) (xy 132.493766 -249.371358) (xy 132.138166 -249.371358) (xy 132.138166 -249.415554)
			(xy 132.185156 -249.567954) (xy 132.446776 -249.567954)
		)
		(stroke
			(width 0)
			(type solid)
		)
		(fill yes)
		(layer "In6.Cu")
		(net "M_E_CPU1_SA_RSP<0>")
	)
	(gr_poly
		(pts
			(xy 132.497068 -238.021114) (xy 132.497068 -237.976664) (xy 132.141468 -237.976664) (xy 132.141468 -238.021114)
			(xy 132.188458 -238.173514) (xy 132.450078 -238.173514)
		)
		(stroke
			(width 0)
			(type solid)
		)
		(fill yes)
		(layer "In6.Cu")
		(net "M_G_CPU1_SB_DQ<5>")
	)
	(gr_poly
		(pts
			(xy 132.497068 -235.174282) (xy 132.450078 -235.021882) (xy 132.188458 -235.021882) (xy 132.141468 -235.174282)
			(xy 132.141468 -235.218732) (xy 132.497068 -235.218732)
		)
		(stroke
			(width 0)
			(type solid)
		)
		(fill yes)
		(layer "In6.Cu")
		(net "M_G_CPU1_SB_DQS_DP<6>")
	)
	(gr_poly
		(pts
			(xy 132.49783 -238.430054) (xy 132.45084 -238.277654) (xy 132.18922 -238.277654) (xy 132.14223 -238.430054)
			(xy 132.14223 -238.47425) (xy 132.49783 -238.47425)
		)
		(stroke
			(width 0)
			(type solid)
		)
		(fill yes)
		(layer "In6.Cu")
		(net "M_G_CPU1_SB_DQ<6>")
	)
	(gr_poly
		(pts
			(xy 132.499608 -240.057686) (xy 132.452618 -239.905286) (xy 132.190998 -239.905286) (xy 132.144008 -240.057686)
			(xy 132.144008 -240.101882) (xy 132.499608 -240.101882)
		)
		(stroke
			(width 0)
			(type solid)
		)
		(fill yes)
		(layer "In6.Cu")
		(net "M_G_CPU1_SB_DQS_DN<0>")
	)
	(gr_poly
		(pts
			(xy 132.499608 -230.290878) (xy 132.452618 -230.138478) (xy 132.190998 -230.138478) (xy 132.144008 -230.290878)
			(xy 132.144008 -230.335328) (xy 132.499608 -230.335328)
		)
		(stroke
			(width 0)
			(type solid)
		)
		(fill yes)
		(layer "In6.Cu")
		(net "M_H_CPU1_SB_DQ<19>")
	)
	(gr_poly
		(pts
			(xy 132.595112 -277.726394) (xy 132.548122 -277.573994) (xy 132.286502 -277.573994) (xy 132.239512 -277.726394)
			(xy 132.239512 -277.770844) (xy 132.595112 -277.770844)
		)
		(stroke
			(width 0)
			(type solid)
		)
		(fill yes)
		(layer "In6.Cu")
		(net "M_H_CPU1_SA_DQS_DN<0>")
	)
	(gr_poly
		(pts
			(xy 132.595112 -275.690584) (xy 132.595112 -275.646388) (xy 132.239512 -275.646388) (xy 132.239512 -275.690584)
			(xy 132.286502 -275.842984) (xy 132.548122 -275.842984)
		)
		(stroke
			(width 0)
			(type solid)
		)
		(fill yes)
		(layer "In6.Cu")
		(net "M_H_CPU1_SA_DQ<5>")
	)
	(gr_poly
		(pts
			(xy 132.595112 -270.807434) (xy 132.595112 -270.762984) (xy 132.239512 -270.762984) (xy 132.239512 -270.807434)
			(xy 132.286502 -270.959834) (xy 132.548122 -270.959834)
		)
		(stroke
			(width 0)
			(type solid)
		)
		(fill yes)
		(layer "In6.Cu")
		(net "M_G_CPU1_SA_DQ<13>")
	)
	(gr_poly
		(pts
			(xy 132.595112 -261.040626) (xy 132.595112 -260.99643) (xy 132.239512 -260.99643) (xy 132.239512 -261.040626)
			(xy 132.286502 -261.193026) (xy 132.548122 -261.193026)
		)
		(stroke
			(width 0)
			(type solid)
		)
		(fill yes)
		(layer "In6.Cu")
		(net "M_G_CPU1_SA_CB<5>")
	)
	(gr_poly
		(pts
			(xy 132.597652 -274.47113) (xy 132.550662 -274.31873) (xy 132.289042 -274.31873) (xy 132.242052 -274.47113)
			(xy 132.242052 -274.515326) (xy 132.597652 -274.515326)
		)
		(stroke
			(width 0)
			(type solid)
		)
		(fill yes)
		(layer "In6.Cu")
		(net "M_G_CPU1_SA_DQ<10>")
	)
	(gr_poly
		(pts
			(xy 132.597652 -274.062698) (xy 132.597652 -274.018502) (xy 132.242052 -274.018502) (xy 132.242052 -274.062698)
			(xy 132.289042 -274.215098) (xy 132.550662 -274.215098)
		)
		(stroke
			(width 0)
			(type solid)
		)
		(fill yes)
		(layer "In6.Cu")
		(net "M_G_CPU1_SA_DQ<9>")
	)
	(gr_poly
		(pts
			(xy 132.597652 -272.843498) (xy 132.550662 -272.691098) (xy 132.289042 -272.691098) (xy 132.242052 -272.843498)
			(xy 132.242052 -272.887948) (xy 132.597652 -272.887948)
		)
		(stroke
			(width 0)
			(type solid)
		)
		(fill yes)
		(layer "In6.Cu")
		(net "M_G_CPU1_SA_DQS_DN<1>")
	)
	(gr_poly
		(pts
			(xy 132.597652 -269.587726) (xy 132.550662 -269.435326) (xy 132.289042 -269.435326) (xy 132.242052 -269.587726)
			(xy 132.242052 -269.631922) (xy 132.597652 -269.631922)
		)
		(stroke
			(width 0)
			(type solid)
		)
		(fill yes)
		(layer "In6.Cu")
		(net "M_G_CPU1_SA_DQ<26>")
	)
	(gr_poly
		(pts
			(xy 132.597652 -267.960094) (xy 132.550662 -267.807694) (xy 132.289042 -267.807694) (xy 132.242052 -267.960094)
			(xy 132.242052 -268.004544) (xy 132.597652 -268.004544)
		)
		(stroke
			(width 0)
			(type solid)
		)
		(fill yes)
		(layer "In6.Cu")
		(net "M_G_CPU1_SA_DQS_DN<3>")
	)
	(gr_poly
		(pts
			(xy 132.597652 -263.07669) (xy 132.550662 -262.92429) (xy 132.289042 -262.92429) (xy 132.242052 -263.07669)
			(xy 132.242052 -263.12114) (xy 132.597652 -263.12114)
		)
		(stroke
			(width 0)
			(type solid)
		)
		(fill yes)
		(layer "In6.Cu")
		(net "M_G_CPU1_SA_DQS_DN<4>")
	)
	(gr_poly
		(pts
			(xy 132.603494 -277.317962) (xy 132.603494 -277.273766) (xy 132.247894 -277.273766) (xy 132.247894 -277.317962)
			(xy 132.294884 -277.470362) (xy 132.556504 -277.470362)
		)
		(stroke
			(width 0)
			(type solid)
		)
		(fill yes)
		(layer "In6.Cu")
		(net "M_H_CPU1_SA_DQS_DN<5>")
	)
	(gr_poly
		(pts
			(xy 132.603494 -276.09927) (xy 132.556504 -275.94687) (xy 132.294884 -275.94687) (xy 132.247894 -276.09927)
			(xy 132.247894 -276.143466) (xy 132.603494 -276.143466)
		)
		(stroke
			(width 0)
			(type solid)
		)
		(fill yes)
		(layer "In6.Cu")
		(net "M_H_CPU1_SA_DQ<6>")
	)
	(gr_poly
		(pts
			(xy 132.603494 -261.449058) (xy 132.556504 -261.296658) (xy 132.294884 -261.296658) (xy 132.247894 -261.449058)
			(xy 132.247894 -261.493508) (xy 132.603494 -261.493508)
		)
		(stroke
			(width 0)
			(type solid)
		)
		(fill yes)
		(layer "In6.Cu")
		(net "M_G_CPU1_SA_CB<6>")
	)
	(gr_poly
		(pts
			(xy 132.603748 -278.945848) (xy 132.603748 -278.901652) (xy 132.248148 -278.901652) (xy 132.248148 -278.945848)
			(xy 132.295138 -279.098248) (xy 132.556758 -279.098248)
		)
		(stroke
			(width 0)
			(type solid)
		)
		(fill yes)
		(layer "In6.Cu")
		(net "M_H_CPU1_SA_DQ<3>")
	)
	(gr_poly
		(pts
			(xy 132.60705 -271.215866) (xy 132.56006 -271.063466) (xy 132.29844 -271.063466) (xy 132.25145 -271.215866)
			(xy 132.25145 -271.260062) (xy 132.60705 -271.260062)
		)
		(stroke
			(width 0)
			(type solid)
		)
		(fill yes)
		(layer "In6.Cu")
		(net "M_G_CPU1_SA_DQ<14>")
	)
	(gr_poly
		(pts
			(xy 132.60705 -269.179294) (xy 132.60705 -269.134844) (xy 132.25145 -269.134844) (xy 132.25145 -269.179294)
			(xy 132.29844 -269.331694) (xy 132.56006 -269.331694)
		)
		(stroke
			(width 0)
			(type solid)
		)
		(fill yes)
		(layer "In6.Cu")
		(net "M_G_CPU1_SA_DQ<25>")
	)
	(gr_poly
		(pts
			(xy 132.60705 -266.332462) (xy 132.56006 -266.180062) (xy 132.29844 -266.180062) (xy 132.25145 -266.332462)
			(xy 132.25145 -266.376658) (xy 132.60705 -266.376658)
		)
		(stroke
			(width 0)
			(type solid)
		)
		(fill yes)
		(layer "In6.Cu")
		(net "M_G_CPU1_SA_DQ<30>")
	)
	(gr_poly
		(pts
			(xy 132.60705 -265.923522) (xy 132.60705 -265.879326) (xy 132.25145 -265.879326) (xy 132.25145 -265.923522)
			(xy 132.29844 -266.075922) (xy 132.56006 -266.075922)
		)
		(stroke
			(width 0)
			(type solid)
		)
		(fill yes)
		(layer "In6.Cu")
		(net "M_G_CPU1_SA_DQ<29>")
	)
	(gr_poly
		(pts
			(xy 132.60705 -264.29589) (xy 132.60705 -264.25144) (xy 132.25145 -264.25144) (xy 132.25145 -264.29589)
			(xy 132.29844 -264.44829) (xy 132.56006 -264.44829)
		)
		(stroke
			(width 0)
			(type solid)
		)
		(fill yes)
		(layer "In6.Cu")
		(net "M_G_CPU1_SA_CB<1>")
	)
	(gr_poly
		(pts
			(xy 132.607812 -264.70483) (xy 132.560822 -264.55243) (xy 132.299202 -264.55243) (xy 132.252212 -264.70483)
			(xy 132.252212 -264.749026) (xy 132.607812 -264.749026)
		)
		(stroke
			(width 0)
			(type solid)
		)
		(fill yes)
		(layer "In6.Cu")
		(net "M_G_CPU1_SA_CB<2>")
	)
	(gr_poly
		(pts
			(xy 132.60959 -272.435066) (xy 132.60959 -272.390616) (xy 132.25399 -272.390616) (xy 132.25399 -272.435066)
			(xy 132.30098 -272.587466) (xy 132.5626 -272.587466)
		)
		(stroke
			(width 0)
			(type solid)
		)
		(fill yes)
		(layer "In6.Cu")
		(net "M_G_CPU1_SA_DQS_DN<6>")
	)
	(gr_poly
		(pts
			(xy 132.60959 -267.551662) (xy 132.60959 -267.507212) (xy 132.25399 -267.507212) (xy 132.25399 -267.551662)
			(xy 132.30098 -267.704062) (xy 132.5626 -267.704062)
		)
		(stroke
			(width 0)
			(type solid)
		)
		(fill yes)
		(layer "In6.Cu")
		(net "M_G_CPU1_SA_DQS_DN<8>")
	)
	(gr_poly
		(pts
			(xy 132.60959 -262.668258) (xy 132.60959 -262.623808) (xy 132.25399 -262.623808) (xy 132.25399 -262.668258)
			(xy 132.30098 -262.820658) (xy 132.5626 -262.820658)
		)
		(stroke
			(width 0)
			(type solid)
		)
		(fill yes)
		(layer "In6.Cu")
		(net "M_G_CPU1_SA_DQS_DN<9>")
	)
	(gr_poly
		(pts
			(xy 132.61213 -279.354534) (xy 132.56514 -279.202134) (xy 132.30352 -279.202134) (xy 132.25653 -279.354534)
			(xy 132.25653 -279.39873) (xy 132.61213 -279.39873)
		)
		(stroke
			(width 0)
			(type solid)
		)
		(fill yes)
		(layer "In6.Cu")
		(net "M_H_CPU1_SA_DQ<2>")
	)
	(gr_poly
		(pts
			(xy 132.95757 -232.732834) (xy 132.91058 -232.580434) (xy 132.64896 -232.580434) (xy 132.60197 -232.732834)
			(xy 132.60197 -232.77703) (xy 132.95757 -232.77703)
		)
		(stroke
			(width 0)
			(type solid)
		)
		(fill yes)
		(layer "In6.Cu")
		(net "M_G_CPU1_SB_DQ<13>")
	)
	(gr_poly
		(pts
			(xy 132.959348 -238.83493) (xy 132.959348 -238.790734) (xy 132.603748 -238.790734) (xy 132.603748 -238.83493)
			(xy 132.650738 -238.98733) (xy 132.912358 -238.98733)
		)
		(stroke
			(width 0)
			(type solid)
		)
		(fill yes)
		(layer "In6.Cu")
		(net "M_G_CPU1_SB_DQ<4>")
	)
	(gr_poly
		(pts
			(xy 132.96011 -237.616238) (xy 132.91312 -237.463838) (xy 132.6515 -237.463838) (xy 132.60451 -237.616238)
			(xy 132.60451 -237.660434) (xy 132.96011 -237.660434)
		)
		(stroke
			(width 0)
			(type solid)
		)
		(fill yes)
		(layer "In6.Cu")
		(net "M_G_CPU1_SB_DQ<7>")
	)
	(gr_poly
		(pts
			(xy 132.963666 -249.010678) (xy 132.916676 -248.858278) (xy 132.655056 -248.858278) (xy 132.608066 -249.010678)
			(xy 132.608066 -249.054874) (xy 132.963666 -249.054874)
		)
		(stroke
			(width 0)
			(type solid)
		)
		(fill yes)
		(layer "In6.Cu")
		(net "M_E_CPU1_SB_RSP<0>")
	)
	(gr_poly
		(pts
			(xy 132.963666 -248.601738) (xy 132.963666 -248.557542) (xy 132.608066 -248.557542) (xy 132.608066 -248.601738)
			(xy 132.655056 -248.754138) (xy 132.916676 -248.754138)
		)
		(stroke
			(width 0)
			(type solid)
		)
		(fill yes)
		(layer "In6.Cu")
		(net "M_E_CPU1_SA_RSP<1>")
	)
	(gr_poly
		(pts
			(xy 132.963666 -243.718334) (xy 132.963666 -243.674138) (xy 132.608066 -243.674138) (xy 132.608066 -243.718334)
			(xy 132.655056 -243.870734) (xy 132.916676 -243.870734)
		)
		(stroke
			(width 0)
			(type solid)
		)
		(fill yes)
		(layer "In6.Cu")
		(net "M_H_CPU1_SB_CS_N<0>")
	)
	(gr_poly
		(pts
			(xy 132.963666 -233.952034) (xy 132.963666 -233.907584) (xy 132.608066 -233.907584) (xy 132.608066 -233.952034)
			(xy 132.655056 -234.104434) (xy 132.916676 -234.104434)
		)
		(stroke
			(width 0)
			(type solid)
		)
		(fill yes)
		(layer "In6.Cu")
		(net "M_G_CPU1_SB_DQ<14>")
	)
	(gr_poly
		(pts
			(xy 132.963666 -229.06863) (xy 132.963666 -229.02418) (xy 132.608066 -229.02418) (xy 132.608066 -229.06863)
			(xy 132.655056 -229.22103) (xy 132.916676 -229.22103)
		)
		(stroke
			(width 0)
			(type solid)
		)
		(fill yes)
		(layer "In6.Cu")
		(net "M_H_CPU1_SB_DQS_DN<7>")
	)
	(gr_poly
		(pts
			(xy 132.963666 -227.84943) (xy 132.916676 -227.69703) (xy 132.655056 -227.69703) (xy 132.608066 -227.84943)
			(xy 132.608066 -227.893626) (xy 132.963666 -227.893626)
		)
		(stroke
			(width 0)
			(type solid)
		)
		(fill yes)
		(layer "In6.Cu")
		(net "M_H_CPU1_SB_DQ<22>")
	)
	(gr_poly
		(pts
			(xy 132.969508 -240.871502) (xy 132.922518 -240.719102) (xy 132.660898 -240.719102) (xy 132.613908 -240.871502)
			(xy 132.613908 -240.915698) (xy 132.969508 -240.915698)
		)
		(stroke
			(width 0)
			(type solid)
		)
		(fill yes)
		(layer "In6.Cu")
		(net "M_G_CPU1_SB_DQ<3>")
	)
	(gr_poly
		(pts
			(xy 132.969508 -240.46307) (xy 132.969508 -240.418874) (xy 132.613908 -240.418874) (xy 132.613908 -240.46307)
			(xy 132.660898 -240.61547) (xy 132.922518 -240.61547)
		)
		(stroke
			(width 0)
			(type solid)
		)
		(fill yes)
		(layer "In6.Cu")
		(net "M_G_CPU1_SB_DQS_DP<0>")
	)
	(gr_poly
		(pts
			(xy 132.969508 -237.207298) (xy 132.969508 -237.163102) (xy 132.613908 -237.163102) (xy 132.613908 -237.207298)
			(xy 132.660898 -237.359698) (xy 132.922518 -237.359698)
		)
		(stroke
			(width 0)
			(type solid)
		)
		(fill yes)
		(layer "In6.Cu")
		(net "M_G_CPU1_SB_DQ<8>")
	)
	(gr_poly
		(pts
			(xy 132.969508 -235.988098) (xy 132.922518 -235.835698) (xy 132.660898 -235.835698) (xy 132.613908 -235.988098)
			(xy 132.613908 -236.032294) (xy 132.969508 -236.032294)
		)
		(stroke
			(width 0)
			(type solid)
		)
		(fill yes)
		(layer "In6.Cu")
		(net "M_G_CPU1_SB_DQ<9>")
	)
	(gr_poly
		(pts
			(xy 132.969508 -235.579666) (xy 132.969508 -235.53547) (xy 132.613908 -235.53547) (xy 132.613908 -235.579666)
			(xy 132.660898 -235.732066) (xy 132.922518 -235.732066)
		)
		(stroke
			(width 0)
			(type solid)
		)
		(fill yes)
		(layer "In6.Cu")
		(net "M_G_CPU1_SB_DQS_DN<6>")
	)
	(gr_poly
		(pts
			(xy 132.969508 -231.104694) (xy 132.922518 -230.952294) (xy 132.660898 -230.952294) (xy 132.613908 -231.104694)
			(xy 132.613908 -231.14889) (xy 132.969508 -231.14889)
		)
		(stroke
			(width 0)
			(type solid)
		)
		(fill yes)
		(layer "In6.Cu")
		(net "M_H_CPU1_SB_DQ<18>")
	)
	(gr_poly
		(pts
			(xy 132.969508 -230.696262) (xy 132.969508 -230.652066) (xy 132.613908 -230.652066) (xy 132.613908 -230.696262)
			(xy 132.660898 -230.848662) (xy 132.922518 -230.848662)
		)
		(stroke
			(width 0)
			(type solid)
		)
		(fill yes)
		(layer "In6.Cu")
		(net "M_H_CPU1_SB_DQ<17>")
	)
	(gr_poly
		(pts
			(xy 132.972048 -244.126766) (xy 132.925058 -243.974366) (xy 132.663438 -243.974366) (xy 132.616448 -244.126766)
			(xy 132.616448 -244.171216) (xy 132.972048 -244.171216)
		)
		(stroke
			(width 0)
			(type solid)
		)
		(fill yes)
		(layer "In6.Cu")
		(net "M_H_CPU1_SB_CS_N<3>")
	)
	(gr_poly
		(pts
			(xy 132.972048 -242.090702) (xy 132.972048 -242.046506) (xy 132.616448 -242.046506) (xy 132.616448 -242.090702)
			(xy 132.663438 -242.243102) (xy 132.925058 -242.243102)
		)
		(stroke
			(width 0)
			(type solid)
		)
		(fill yes)
		(layer "In6.Cu")
		(net "M_G_CPU1_SB_DQ<0>")
	)
	(gr_poly
		(pts
			(xy 132.972048 -239.243362) (xy 132.925058 -239.090962) (xy 132.663438 -239.090962) (xy 132.616448 -239.243362)
			(xy 132.616448 -239.287812) (xy 132.972048 -239.287812)
		)
		(stroke
			(width 0)
			(type solid)
		)
		(fill yes)
		(layer "In6.Cu")
		(net "M_G_CPU1_SB_DQS_DP<5>")
	)
	(gr_poly
		(pts
			(xy 132.972048 -234.360466) (xy 132.925058 -234.208066) (xy 132.663438 -234.208066) (xy 132.616448 -234.360466)
			(xy 132.616448 -234.404662) (xy 132.972048 -234.404662)
		)
		(stroke
			(width 0)
			(type solid)
		)
		(fill yes)
		(layer "In6.Cu")
		(net "M_G_CPU1_SB_DQS_DN<1>")
	)
	(gr_poly
		(pts
			(xy 132.972048 -229.477062) (xy 132.925058 -229.324662) (xy 132.663438 -229.324662) (xy 132.616448 -229.477062)
			(xy 132.616448 -229.521258) (xy 132.972048 -229.521258)
		)
		(stroke
			(width 0)
			(type solid)
		)
		(fill yes)
		(layer "In6.Cu")
		(net "M_H_CPU1_SB_DQS_DN<2>")
	)
	(gr_poly
		(pts
			(xy 132.972048 -227.440998) (xy 132.972048 -227.396548) (xy 132.616448 -227.396548) (xy 132.616448 -227.440998)
			(xy 132.663438 -227.593398) (xy 132.925058 -227.593398)
		)
		(stroke
			(width 0)
			(type solid)
		)
		(fill yes)
		(layer "In6.Cu")
		(net "M_H_CPU1_SB_DQ<21>")
	)
	(gr_poly
		(pts
			(xy 133.067552 -279.759918) (xy 133.067552 -279.715722) (xy 132.711952 -279.715722) (xy 132.711952 -279.759918)
			(xy 132.758942 -279.912318) (xy 133.020562 -279.912318)
		)
		(stroke
			(width 0)
			(type solid)
		)
		(fill yes)
		(layer "In6.Cu")
		(net "M_H_CPU1_SA_DQ<0>")
	)
	(gr_poly
		(pts
			(xy 133.067552 -274.876514) (xy 133.067552 -274.832064) (xy 132.711952 -274.832064) (xy 132.711952 -274.876514)
			(xy 132.758942 -275.028914) (xy 133.020562 -275.028914)
		)
		(stroke
			(width 0)
			(type solid)
		)
		(fill yes)
		(layer "In6.Cu")
		(net "M_G_CPU1_SA_DQ<8>")
	)
	(gr_poly
		(pts
			(xy 133.067552 -269.99311) (xy 133.067552 -269.948914) (xy 132.711952 -269.948914) (xy 132.711952 -269.99311)
			(xy 132.758942 -270.14551) (xy 133.020562 -270.14551)
		)
		(stroke
			(width 0)
			(type solid)
		)
		(fill yes)
		(layer "In6.Cu")
		(net "M_G_CPU1_SA_DQ<24>")
	)
	(gr_poly
		(pts
			(xy 133.06933 -265.109706) (xy 133.06933 -265.06551) (xy 132.71373 -265.06551) (xy 132.71373 -265.109706)
			(xy 132.76072 -265.262106) (xy 133.02234 -265.262106)
		)
		(stroke
			(width 0)
			(type solid)
		)
		(fill yes)
		(layer "In6.Cu")
		(net "M_G_CPU1_SA_CB<0>")
	)
	(gr_poly
		(pts
			(xy 133.070092 -271.62125) (xy 133.070092 -271.5768) (xy 132.714492 -271.5768) (xy 132.714492 -271.62125)
			(xy 132.761482 -271.77365) (xy 133.023102 -271.77365)
		)
		(stroke
			(width 0)
			(type solid)
		)
		(fill yes)
		(layer "In6.Cu")
		(net "M_G_CPU1_SA_DQ<12>")
	)
	(gr_poly
		(pts
			(xy 133.070092 -266.737846) (xy 133.070092 -266.693396) (xy 132.714492 -266.693396) (xy 132.714492 -266.737846)
			(xy 132.761482 -266.890246) (xy 133.023102 -266.890246)
		)
		(stroke
			(width 0)
			(type solid)
		)
		(fill yes)
		(layer "In6.Cu")
		(net "M_G_CPU1_SA_DQ<28>")
	)
	(gr_poly
		(pts
			(xy 133.070092 -265.518646) (xy 133.023102 -265.366246) (xy 132.761482 -265.366246) (xy 132.714492 -265.518646)
			(xy 132.714492 -265.563096) (xy 133.070092 -265.563096)
		)
		(stroke
			(width 0)
			(type solid)
		)
		(fill yes)
		(layer "In6.Cu")
		(net "M_G_CPU1_SA_DQ<31>")
	)
	(gr_poly
		(pts
			(xy 133.070092 -263.891014) (xy 133.023102 -263.738614) (xy 132.761482 -263.738614) (xy 132.714492 -263.891014)
			(xy 132.714492 -263.93521) (xy 133.070092 -263.93521)
		)
		(stroke
			(width 0)
			(type solid)
		)
		(fill yes)
		(layer "In6.Cu")
		(net "M_G_CPU1_SA_CB<3>")
	)
	(gr_poly
		(pts
			(xy 133.073648 -278.540718) (xy 133.026658 -278.388318) (xy 132.765038 -278.388318) (xy 132.718048 -278.540718)
			(xy 132.718048 -278.585168) (xy 133.073648 -278.585168)
		)
		(stroke
			(width 0)
			(type solid)
		)
		(fill yes)
		(layer "In6.Cu")
		(net "M_H_CPU1_SA_DQ<1>")
	)
	(gr_poly
		(pts
			(xy 133.073648 -273.657314) (xy 133.026658 -273.504914) (xy 132.765038 -273.504914) (xy 132.718048 -273.657314)
			(xy 132.718048 -273.701764) (xy 133.073648 -273.701764)
		)
		(stroke
			(width 0)
			(type solid)
		)
		(fill yes)
		(layer "In6.Cu")
		(net "M_G_CPU1_SA_DQ<11>")
	)
	(gr_poly
		(pts
			(xy 133.073648 -268.77391) (xy 133.026658 -268.62151) (xy 132.765038 -268.62151) (xy 132.718048 -268.77391)
			(xy 132.718048 -268.81836) (xy 133.073648 -268.81836)
		)
		(stroke
			(width 0)
			(type solid)
		)
		(fill yes)
		(layer "In6.Cu")
		(net "M_G_CPU1_SA_DQ<27>")
	)
	(gr_poly
		(pts
			(xy 133.07949 -276.912578) (xy 133.0325 -276.760178) (xy 132.77088 -276.760178) (xy 132.72389 -276.912578)
			(xy 132.72389 -276.957028) (xy 133.07949 -276.957028)
		)
		(stroke
			(width 0)
			(type solid)
		)
		(fill yes)
		(layer "In6.Cu")
		(net "M_H_CPU1_SA_DQS_DP<5>")
	)
	(gr_poly
		(pts
			(xy 133.07949 -276.5044) (xy 133.07949 -276.460204) (xy 132.72389 -276.460204) (xy 132.72389 -276.5044)
			(xy 132.77088 -276.6568) (xy 133.0325 -276.6568)
		)
		(stroke
			(width 0)
			(type solid)
		)
		(fill yes)
		(layer "In6.Cu")
		(net "M_H_CPU1_SA_DQ<4>")
	)
	(gr_poly
		(pts
			(xy 133.07949 -275.284946) (xy 133.0325 -275.132546) (xy 132.77088 -275.132546) (xy 132.72389 -275.284946)
			(xy 132.72389 -275.329396) (xy 133.07949 -275.329396)
		)
		(stroke
			(width 0)
			(type solid)
		)
		(fill yes)
		(layer "In6.Cu")
		(net "M_H_CPU1_SA_DQ<7>")
	)
	(gr_poly
		(pts
			(xy 133.07949 -272.029174) (xy 133.0325 -271.876774) (xy 132.77088 -271.876774) (xy 132.72389 -272.029174)
			(xy 132.72389 -272.073624) (xy 133.07949 -272.073624)
		)
		(stroke
			(width 0)
			(type solid)
		)
		(fill yes)
		(layer "In6.Cu")
		(net "M_G_CPU1_SA_DQS_DP<6>")
	)
	(gr_poly
		(pts
			(xy 133.07949 -270.40205) (xy 133.0325 -270.24965) (xy 132.77088 -270.24965) (xy 132.72389 -270.40205)
			(xy 132.72389 -270.446246) (xy 133.07949 -270.446246)
		)
		(stroke
			(width 0)
			(type solid)
		)
		(fill yes)
		(layer "In6.Cu")
		(net "M_G_CPU1_SA_DQ<15>")
	)
	(gr_poly
		(pts
			(xy 133.07949 -267.146278) (xy 133.0325 -266.993878) (xy 132.77088 -266.993878) (xy 132.72389 -267.146278)
			(xy 132.72389 -267.190474) (xy 133.07949 -267.190474)
		)
		(stroke
			(width 0)
			(type solid)
		)
		(fill yes)
		(layer "In6.Cu")
		(net "M_G_CPU1_SA_DQS_DP<8>")
	)
	(gr_poly
		(pts
			(xy 133.07949 -262.262874) (xy 133.0325 -262.110474) (xy 132.77088 -262.110474) (xy 132.72389 -262.262874)
			(xy 132.72389 -262.30707) (xy 133.07949 -262.30707)
		)
		(stroke
			(width 0)
			(type solid)
		)
		(fill yes)
		(layer "In6.Cu")
		(net "M_G_CPU1_SA_DQS_DP<9>")
	)
	(gr_poly
		(pts
			(xy 133.07949 -261.854442) (xy 133.07949 -261.810246) (xy 132.72389 -261.810246) (xy 132.72389 -261.854442)
			(xy 132.77088 -262.006842) (xy 133.0325 -262.006842)
		)
		(stroke
			(width 0)
			(type solid)
		)
		(fill yes)
		(layer "In6.Cu")
		(net "M_G_CPU1_SA_CB<4>")
	)
	(gr_poly
		(pts
			(xy 133.07949 -260.635242) (xy 133.0325 -260.482842) (xy 132.77088 -260.482842) (xy 132.72389 -260.635242)
			(xy 132.72389 -260.679438) (xy 133.07949 -260.679438)
		)
		(stroke
			(width 0)
			(type solid)
		)
		(fill yes)
		(layer "In6.Cu")
		(net "M_G_CPU1_SA_CB<7>")
	)
	(gr_poly
		(pts
			(xy 133.08203 -278.132286) (xy 133.08203 -278.08809) (xy 132.72643 -278.08809) (xy 132.72643 -278.132286)
			(xy 132.77342 -278.284686) (xy 133.03504 -278.284686)
		)
		(stroke
			(width 0)
			(type solid)
		)
		(fill yes)
		(layer "In6.Cu")
		(net "M_H_CPU1_SA_DQS_DP<0>")
	)
	(gr_poly
		(pts
			(xy 133.08203 -273.248882) (xy 133.08203 -273.204686) (xy 132.72643 -273.204686) (xy 132.72643 -273.248882)
			(xy 132.77342 -273.401282) (xy 133.03504 -273.401282)
		)
		(stroke
			(width 0)
			(type solid)
		)
		(fill yes)
		(layer "In6.Cu")
		(net "M_G_CPU1_SA_DQS_DP<1>")
	)
	(gr_poly
		(pts
			(xy 133.08203 -268.365478) (xy 133.08203 -268.321282) (xy 132.72643 -268.321282) (xy 132.72643 -268.365478)
			(xy 132.77342 -268.517878) (xy 133.03504 -268.517878)
		)
		(stroke
			(width 0)
			(type solid)
		)
		(fill yes)
		(layer "In6.Cu")
		(net "M_G_CPU1_SA_DQS_DP<3>")
	)
	(gr_poly
		(pts
			(xy 133.08203 -263.482582) (xy 133.08203 -263.438132) (xy 132.72643 -263.438132) (xy 132.72643 -263.482582)
			(xy 132.77342 -263.634982) (xy 133.03504 -263.634982)
		)
		(stroke
			(width 0)
			(type solid)
		)
		(fill yes)
		(layer "In6.Cu")
		(net "M_G_CPU1_SA_DQS_DP<4>")
	)
	(gr_poly
		(pts
			(xy 133.42747 -244.532658) (xy 133.42747 -244.488208) (xy 133.07187 -244.488208) (xy 133.07187 -244.532658)
			(xy 133.11886 -244.685058) (xy 133.38048 -244.685058)
		)
		(stroke
			(width 0)
			(type solid)
		)
		(fill yes)
		(layer "In6.Cu")
		(net "M_H_CPU1_SB_CS_N<2>")
	)
	(gr_poly
		(pts
			(xy 133.42747 -241.685318) (xy 133.38048 -241.532918) (xy 133.11886 -241.532918) (xy 133.07187 -241.685318)
			(xy 133.07187 -241.729514) (xy 133.42747 -241.729514)
		)
		(stroke
			(width 0)
			(type solid)
		)
		(fill yes)
		(layer "In6.Cu")
		(net "M_G_CPU1_SB_DQ<2>")
	)
	(gr_poly
		(pts
			(xy 133.42747 -241.276886) (xy 133.42747 -241.23269) (xy 133.07187 -241.23269) (xy 133.07187 -241.276886)
			(xy 133.11886 -241.429286) (xy 133.38048 -241.429286)
		)
		(stroke
			(width 0)
			(type solid)
		)
		(fill yes)
		(layer "In6.Cu")
		(net "M_G_CPU1_SB_DQ<1>")
	)
	(gr_poly
		(pts
			(xy 133.42747 -240.057178) (xy 133.38048 -239.904778) (xy 133.11886 -239.904778) (xy 133.07187 -240.057178)
			(xy 133.07187 -240.101628) (xy 133.42747 -240.101628)
		)
		(stroke
			(width 0)
			(type solid)
		)
		(fill yes)
		(layer "In6.Cu")
		(net "M_G_CPU1_SB_DQS_DN<0>")
	)
	(gr_poly
		(pts
			(xy 133.42747 -239.649254) (xy 133.42747 -239.604804) (xy 133.07187 -239.604804) (xy 133.07187 -239.649254)
			(xy 133.11886 -239.801654) (xy 133.38048 -239.801654)
		)
		(stroke
			(width 0)
			(type solid)
		)
		(fill yes)
		(layer "In6.Cu")
		(net "M_G_CPU1_SB_DQS_DN<5>")
	)
	(gr_poly
		(pts
			(xy 133.42747 -236.39399) (xy 133.42747 -236.34954) (xy 133.07187 -236.34954) (xy 133.07187 -236.39399)
			(xy 133.11886 -236.54639) (xy 133.38048 -236.54639)
		)
		(stroke
			(width 0)
			(type solid)
		)
		(fill yes)
		(layer "In6.Cu")
		(net "M_G_CPU1_SB_DQ<11>")
	)
	(gr_poly
		(pts
			(xy 133.42747 -235.174282) (xy 133.38048 -235.021882) (xy 133.11886 -235.021882) (xy 133.07187 -235.174282)
			(xy 133.07187 -235.218478) (xy 133.42747 -235.218478)
		)
		(stroke
			(width 0)
			(type solid)
		)
		(fill yes)
		(layer "In6.Cu")
		(net "M_G_CPU1_SB_DQS_DP<6>")
	)
	(gr_poly
		(pts
			(xy 133.42747 -234.76585) (xy 133.42747 -234.721654) (xy 133.07187 -234.721654) (xy 133.07187 -234.76585)
			(xy 133.11886 -234.91825) (xy 133.38048 -234.91825)
		)
		(stroke
			(width 0)
			(type solid)
		)
		(fill yes)
		(layer "In6.Cu")
		(net "M_G_CPU1_SB_DQS_DP<1>")
	)
	(gr_poly
		(pts
			(xy 133.42747 -231.510586) (xy 133.42747 -231.466136) (xy 133.07187 -231.466136) (xy 133.07187 -231.510586)
			(xy 133.11886 -231.662986) (xy 133.38048 -231.662986)
		)
		(stroke
			(width 0)
			(type solid)
		)
		(fill yes)
		(layer "In6.Cu")
		(net "M_H_CPU1_SB_DQ<16>")
	)
	(gr_poly
		(pts
			(xy 133.42747 -230.290878) (xy 133.38048 -230.138478) (xy 133.11886 -230.138478) (xy 133.07187 -230.290878)
			(xy 133.07187 -230.335074) (xy 133.42747 -230.335074)
		)
		(stroke
			(width 0)
			(type solid)
		)
		(fill yes)
		(layer "In6.Cu")
		(net "M_H_CPU1_SB_DQ<19>")
	)
	(gr_poly
		(pts
			(xy 133.42747 -229.882446) (xy 133.42747 -229.83825) (xy 133.07187 -229.83825) (xy 133.07187 -229.882446)
			(xy 133.11886 -230.034846) (xy 133.38048 -230.034846)
		)
		(stroke
			(width 0)
			(type solid)
		)
		(fill yes)
		(layer "In6.Cu")
		(net "M_H_CPU1_SB_DQS_DP<2>")
	)
	(gr_poly
		(pts
			(xy 133.42747 -227.035106) (xy 133.38048 -226.882706) (xy 133.11886 -226.882706) (xy 133.07187 -227.035106)
			(xy 133.07187 -227.079556) (xy 133.42747 -227.079556)
		)
		(stroke
			(width 0)
			(type solid)
		)
		(fill yes)
		(layer "In6.Cu")
		(net "M_H_CPU1_SB_DQ<23>")
	)
	(gr_poly
		(pts
			(xy 133.433566 -249.415554) (xy 133.433566 -249.371358) (xy 133.077966 -249.371358) (xy 133.077966 -249.415554)
			(xy 133.124956 -249.567954) (xy 133.386576 -249.567954)
		)
		(stroke
			(width 0)
			(type solid)
		)
		(fill yes)
		(layer "In6.Cu")
		(net "M_E_CPU1_SA_RSP<0>")
	)
	(gr_poly
		(pts
			(xy 133.433566 -248.196354) (xy 133.386576 -248.043954) (xy 133.124956 -248.043954) (xy 133.077966 -248.196354)
			(xy 133.077966 -248.240804) (xy 133.433566 -248.240804)
		)
		(stroke
			(width 0)
			(type solid)
		)
		(fill yes)
		(layer "In6.Cu")
		(net "M_E_CPU1_SB_RSP<1>")
	)
	(gr_poly
		(pts
			(xy 133.433566 -243.313458) (xy 133.386576 -243.161058) (xy 133.124956 -243.161058) (xy 133.077966 -243.313458)
			(xy 133.077966 -243.357654) (xy 133.433566 -243.357654)
		)
		(stroke
			(width 0)
			(type solid)
		)
		(fill yes)
		(layer "In6.Cu")
		(net "M_H_CPU1_SB_CS_N<1>")
	)
	(gr_poly
		(pts
			(xy 133.433566 -233.54665) (xy 133.386576 -233.39425) (xy 133.124956 -233.39425) (xy 133.077966 -233.54665)
			(xy 133.077966 -233.590846) (xy 133.433566 -233.590846)
		)
		(stroke
			(width 0)
			(type solid)
		)
		(fill yes)
		(layer "In6.Cu")
		(net "M_G_CPU1_SB_DQ<12>")
	)
	(gr_poly
		(pts
			(xy 133.433566 -228.663246) (xy 133.386576 -228.510846) (xy 133.124956 -228.510846) (xy 133.077966 -228.663246)
			(xy 133.077966 -228.707696) (xy 133.433566 -228.707696)
		)
		(stroke
			(width 0)
			(type solid)
		)
		(fill yes)
		(layer "In6.Cu")
		(net "M_H_CPU1_SB_DQS_DP<7>")
	)
	(gr_poly
		(pts
			(xy 133.433566 -228.254814) (xy 133.433566 -228.210364) (xy 133.077966 -228.210364) (xy 133.077966 -228.254814)
			(xy 133.124956 -228.407214) (xy 133.386576 -228.407214)
		)
		(stroke
			(width 0)
			(type solid)
		)
		(fill yes)
		(layer "In6.Cu")
		(net "M_H_CPU1_SB_DQ<20>")
	)
	(gr_poly
		(pts
			(xy 133.436868 -238.021114) (xy 133.436868 -237.976664) (xy 133.081268 -237.976664) (xy 133.081268 -238.021114)
			(xy 133.128258 -238.173514) (xy 133.389878 -238.173514)
		)
		(stroke
			(width 0)
			(type solid)
		)
		(fill yes)
		(layer "In6.Cu")
		(net "M_G_CPU1_SB_DQ<5>")
	)
	(gr_poly
		(pts
			(xy 133.43763 -238.430054) (xy 133.39064 -238.277654) (xy 133.12902 -238.277654) (xy 133.08203 -238.430054)
			(xy 133.08203 -238.47425) (xy 133.43763 -238.47425)
		)
		(stroke
			(width 0)
			(type solid)
		)
		(fill yes)
		(layer "In6.Cu")
		(net "M_G_CPU1_SB_DQ<6>")
	)
	(gr_poly
		(pts
			(xy 133.439408 -236.801914) (xy 133.392418 -236.649514) (xy 133.130798 -236.649514) (xy 133.083808 -236.801914)
			(xy 133.083808 -236.84611) (xy 133.439408 -236.84611)
		)
		(stroke
			(width 0)
			(type solid)
		)
		(fill yes)
		(layer "In6.Cu")
		(net "M_G_CPU1_SB_DQ<10>")
	)
	(gr_poly
		(pts
			(xy 133.441948 -233.138218) (xy 133.441948 -233.093768) (xy 133.086348 -233.093768) (xy 133.086348 -233.138218)
			(xy 133.133338 -233.290618) (xy 133.394958 -233.290618)
		)
		(stroke
			(width 0)
			(type solid)
		)
		(fill yes)
		(layer "In6.Cu")
		(net "M_G_CPU1_SB_DQ<15>")
	)
	(gr_poly
		(pts
			(xy 133.534912 -277.726394) (xy 133.487922 -277.573994) (xy 133.226302 -277.573994) (xy 133.179312 -277.726394)
			(xy 133.179312 -277.770844) (xy 133.534912 -277.770844)
		)
		(stroke
			(width 0)
			(type solid)
		)
		(fill yes)
		(layer "In6.Cu")
		(net "M_H_CPU1_SA_DQS_DN<0>")
	)
	(gr_poly
		(pts
			(xy 133.534912 -277.318216) (xy 133.534912 -277.27402) (xy 133.179312 -277.27402) (xy 133.179312 -277.318216)
			(xy 133.226302 -277.470616) (xy 133.487922 -277.470616)
		)
		(stroke
			(width 0)
			(type solid)
		)
		(fill yes)
		(layer "In6.Cu")
		(net "M_H_CPU1_SA_DQS_DN<5>")
	)
	(gr_poly
		(pts
			(xy 133.534912 -276.098762) (xy 133.487922 -275.946362) (xy 133.226302 -275.946362) (xy 133.179312 -276.098762)
			(xy 133.179312 -276.143212) (xy 133.534912 -276.143212)
		)
		(stroke
			(width 0)
			(type solid)
		)
		(fill yes)
		(layer "In6.Cu")
		(net "M_H_CPU1_SA_DQ<6>")
	)
	(gr_poly
		(pts
			(xy 133.534912 -272.843498) (xy 133.487922 -272.691098) (xy 133.226302 -272.691098) (xy 133.179312 -272.843498)
			(xy 133.179312 -272.887694) (xy 133.534912 -272.887694)
		)
		(stroke
			(width 0)
			(type solid)
		)
		(fill yes)
		(layer "In6.Cu")
		(net "M_G_CPU1_SA_DQS_DN<1>")
	)
	(gr_poly
		(pts
			(xy 133.534912 -272.435066) (xy 133.534912 -272.39087) (xy 133.179312 -272.39087) (xy 133.179312 -272.435066)
			(xy 133.226302 -272.587466) (xy 133.487922 -272.587466)
		)
		(stroke
			(width 0)
			(type solid)
		)
		(fill yes)
		(layer "In6.Cu")
		(net "M_G_CPU1_SA_DQS_DN<6>")
	)
	(gr_poly
		(pts
			(xy 133.534912 -267.960094) (xy 133.487922 -267.807694) (xy 133.226302 -267.807694) (xy 133.179312 -267.960094)
			(xy 133.179312 -268.00429) (xy 133.534912 -268.00429)
		)
		(stroke
			(width 0)
			(type solid)
		)
		(fill yes)
		(layer "In6.Cu")
		(net "M_G_CPU1_SA_DQS_DN<3>")
	)
	(gr_poly
		(pts
			(xy 133.534912 -267.551662) (xy 133.534912 -267.507466) (xy 133.179312 -267.507466) (xy 133.179312 -267.551662)
			(xy 133.226302 -267.704062) (xy 133.487922 -267.704062)
		)
		(stroke
			(width 0)
			(type solid)
		)
		(fill yes)
		(layer "In6.Cu")
		(net "M_G_CPU1_SA_DQS_DN<8>")
	)
	(gr_poly
		(pts
			(xy 133.534912 -263.07669) (xy 133.487922 -262.92429) (xy 133.226302 -262.92429) (xy 133.179312 -263.07669)
			(xy 133.179312 -263.120886) (xy 133.534912 -263.120886)
		)
		(stroke
			(width 0)
			(type solid)
		)
		(fill yes)
		(layer "In6.Cu")
		(net "M_G_CPU1_SA_DQS_DN<4>")
	)
	(gr_poly
		(pts
			(xy 133.534912 -262.668258) (xy 133.534912 -262.624062) (xy 133.179312 -262.624062) (xy 133.179312 -262.668258)
			(xy 133.226302 -262.820658) (xy 133.487922 -262.820658)
		)
		(stroke
			(width 0)
			(type solid)
		)
		(fill yes)
		(layer "In6.Cu")
		(net "M_G_CPU1_SA_DQS_DN<9>")
	)
	(gr_poly
		(pts
			(xy 133.534912 -261.449058) (xy 133.487922 -261.296658) (xy 133.226302 -261.296658) (xy 133.179312 -261.449058)
			(xy 133.179312 -261.493254) (xy 133.534912 -261.493254)
		)
		(stroke
			(width 0)
			(type solid)
		)
		(fill yes)
		(layer "In6.Cu")
		(net "M_G_CPU1_SA_CB<6>")
	)
	(gr_poly
		(pts
			(xy 133.537452 -279.354788) (xy 133.490462 -279.202388) (xy 133.228842 -279.202388) (xy 133.181852 -279.354788)
			(xy 133.181852 -279.398984) (xy 133.537452 -279.398984)
		)
		(stroke
			(width 0)
			(type solid)
		)
		(fill yes)
		(layer "In6.Cu")
		(net "M_H_CPU1_SA_DQ<2>")
	)
	(gr_poly
		(pts
			(xy 133.537452 -278.945848) (xy 133.537452 -278.901652) (xy 133.181852 -278.901652) (xy 133.181852 -278.945848)
			(xy 133.228842 -279.098248) (xy 133.490462 -279.098248)
		)
		(stroke
			(width 0)
			(type solid)
		)
		(fill yes)
		(layer "In6.Cu")
		(net "M_H_CPU1_SA_DQ<3>")
	)
	(gr_poly
		(pts
			(xy 133.537452 -274.062698) (xy 133.537452 -274.018248) (xy 133.181852 -274.018248) (xy 133.181852 -274.062698)
			(xy 133.228842 -274.215098) (xy 133.490462 -274.215098)
		)
		(stroke
			(width 0)
			(type solid)
		)
		(fill yes)
		(layer "In6.Cu")
		(net "M_G_CPU1_SA_DQ<9>")
	)
	(gr_poly
		(pts
			(xy 133.537452 -269.179294) (xy 133.537452 -269.134844) (xy 133.181852 -269.134844) (xy 133.181852 -269.179294)
			(xy 133.228842 -269.331694) (xy 133.490462 -269.331694)
		)
		(stroke
			(width 0)
			(type solid)
		)
		(fill yes)
		(layer "In6.Cu")
		(net "M_G_CPU1_SA_DQ<25>")
	)
	(gr_poly
		(pts
			(xy 133.543294 -275.690584) (xy 133.543294 -275.646134) (xy 133.187694 -275.646134) (xy 133.187694 -275.690584)
			(xy 133.234684 -275.842984) (xy 133.496304 -275.842984)
		)
		(stroke
			(width 0)
			(type solid)
		)
		(fill yes)
		(layer "In6.Cu")
		(net "M_H_CPU1_SA_DQ<5>")
	)
	(gr_poly
		(pts
			(xy 133.543294 -270.806926) (xy 133.543294 -270.76273) (xy 133.187694 -270.76273) (xy 133.187694 -270.806926)
			(xy 133.234684 -270.959326) (xy 133.496304 -270.959326)
		)
		(stroke
			(width 0)
			(type solid)
		)
		(fill yes)
		(layer "In6.Cu")
		(net "M_G_CPU1_SA_DQ<13>")
	)
	(gr_poly
		(pts
			(xy 133.543294 -261.040626) (xy 133.543294 -260.996176) (xy 133.187694 -260.996176) (xy 133.187694 -261.040626)
			(xy 133.234684 -261.193026) (xy 133.496304 -261.193026)
		)
		(stroke
			(width 0)
			(type solid)
		)
		(fill yes)
		(layer "In6.Cu")
		(net "M_G_CPU1_SA_CB<5>")
	)
	(gr_poly
		(pts
			(xy 133.54685 -271.215866) (xy 133.49986 -271.063466) (xy 133.23824 -271.063466) (xy 133.19125 -271.215866)
			(xy 133.19125 -271.260062) (xy 133.54685 -271.260062)
		)
		(stroke
			(width 0)
			(type solid)
		)
		(fill yes)
		(layer "In6.Cu")
		(net "M_G_CPU1_SA_DQ<14>")
	)
	(gr_poly
		(pts
			(xy 133.54685 -266.332462) (xy 133.49986 -266.180062) (xy 133.23824 -266.180062) (xy 133.19125 -266.332462)
			(xy 133.19125 -266.376658) (xy 133.54685 -266.376658)
		)
		(stroke
			(width 0)
			(type solid)
		)
		(fill yes)
		(layer "In6.Cu")
		(net "M_G_CPU1_SA_DQ<30>")
	)
	(gr_poly
		(pts
			(xy 133.54685 -265.923522) (xy 133.54685 -265.879326) (xy 133.19125 -265.879326) (xy 133.19125 -265.923522)
			(xy 133.23824 -266.075922) (xy 133.49986 -266.075922)
		)
		(stroke
			(width 0)
			(type solid)
		)
		(fill yes)
		(layer "In6.Cu")
		(net "M_G_CPU1_SA_DQ<29>")
	)
	(gr_poly
		(pts
			(xy 133.54685 -264.29589) (xy 133.54685 -264.25144) (xy 133.19125 -264.25144) (xy 133.19125 -264.29589)
			(xy 133.23824 -264.44829) (xy 133.49986 -264.44829)
		)
		(stroke
			(width 0)
			(type solid)
		)
		(fill yes)
		(layer "In6.Cu")
		(net "M_G_CPU1_SA_CB<1>")
	)
	(gr_poly
		(pts
			(xy 133.547612 -264.70483) (xy 133.500622 -264.55243) (xy 133.239002 -264.55243) (xy 133.192012 -264.70483)
			(xy 133.192012 -264.749026) (xy 133.547612 -264.749026)
		)
		(stroke
			(width 0)
			(type solid)
		)
		(fill yes)
		(layer "In6.Cu")
		(net "M_G_CPU1_SA_CB<2>")
	)
	(gr_poly
		(pts
			(xy 133.54939 -274.47113) (xy 133.5024 -274.31873) (xy 133.24078 -274.31873) (xy 133.19379 -274.47113)
			(xy 133.19379 -274.51558) (xy 133.54939 -274.51558)
		)
		(stroke
			(width 0)
			(type solid)
		)
		(fill yes)
		(layer "In6.Cu")
		(net "M_G_CPU1_SA_DQ<10>")
	)
	(gr_poly
		(pts
			(xy 133.54939 -269.587726) (xy 133.5024 -269.435326) (xy 133.24078 -269.435326) (xy 133.19379 -269.587726)
			(xy 133.19379 -269.632176) (xy 133.54939 -269.632176)
		)
		(stroke
			(width 0)
			(type solid)
		)
		(fill yes)
		(layer "In6.Cu")
		(net "M_G_CPU1_SA_DQ<26>")
	)
	(gr_poly
		(pts
			(xy 133.89737 -237.207806) (xy 133.89737 -237.163356) (xy 133.54177 -237.163356) (xy 133.54177 -237.207806)
			(xy 133.58876 -237.360206) (xy 133.85038 -237.360206)
		)
		(stroke
			(width 0)
			(type solid)
		)
		(fill yes)
		(layer "In6.Cu")
		(net "M_G_CPU1_SB_DQ<8>")
	)
	(gr_poly
		(pts
			(xy 133.89737 -232.732326) (xy 133.85038 -232.579926) (xy 133.58876 -232.579926) (xy 133.54177 -232.732326)
			(xy 133.54177 -232.776776) (xy 133.89737 -232.776776)
		)
		(stroke
			(width 0)
			(type solid)
		)
		(fill yes)
		(layer "In6.Cu")
		(net "M_G_CPU1_SB_DQ<13>")
	)
	(gr_poly
		(pts
			(xy 133.900164 -238.83493) (xy 133.900164 -238.790734) (xy 133.544564 -238.790734) (xy 133.544564 -238.83493)
			(xy 133.591554 -238.98733) (xy 133.853174 -238.98733)
		)
		(stroke
			(width 0)
			(type solid)
		)
		(fill yes)
		(layer "In6.Cu")
		(net "M_G_CPU1_SB_DQ<4>")
	)
	(gr_poly
		(pts
			(xy 133.90118 -237.61573) (xy 133.85419 -237.46333) (xy 133.59257 -237.46333) (xy 133.54558 -237.61573)
			(xy 133.54558 -237.66018) (xy 133.90118 -237.66018)
		)
		(stroke
			(width 0)
			(type solid)
		)
		(fill yes)
		(layer "In6.Cu")
		(net "M_G_CPU1_SB_DQ<7>")
	)
	(gr_poly
		(pts
			(xy 133.903466 -249.010678) (xy 133.856476 -248.858278) (xy 133.594856 -248.858278) (xy 133.547866 -249.010678)
			(xy 133.547866 -249.054874) (xy 133.903466 -249.054874)
		)
		(stroke
			(width 0)
			(type solid)
		)
		(fill yes)
		(layer "In6.Cu")
		(net "M_E_CPU1_SB_RSP<0>")
	)
	(gr_poly
		(pts
			(xy 133.903466 -248.601738) (xy 133.903466 -248.557542) (xy 133.547866 -248.557542) (xy 133.547866 -248.601738)
			(xy 133.594856 -248.754138) (xy 133.856476 -248.754138)
		)
		(stroke
			(width 0)
			(type solid)
		)
		(fill yes)
		(layer "In6.Cu")
		(net "M_E_CPU1_SA_RSP<1>")
	)
	(gr_poly
		(pts
			(xy 133.903466 -244.127274) (xy 133.856476 -243.974874) (xy 133.594856 -243.974874) (xy 133.547866 -244.127274)
			(xy 133.547866 -244.17147) (xy 133.903466 -244.17147)
		)
		(stroke
			(width 0)
			(type solid)
		)
		(fill yes)
		(layer "In6.Cu")
		(net "M_H_CPU1_SB_CS_N<3>")
	)
	(gr_poly
		(pts
			(xy 133.903466 -243.718334) (xy 133.903466 -243.674138) (xy 133.547866 -243.674138) (xy 133.547866 -243.718334)
			(xy 133.594856 -243.870734) (xy 133.856476 -243.870734)
		)
		(stroke
			(width 0)
			(type solid)
		)
		(fill yes)
		(layer "In6.Cu")
		(net "M_H_CPU1_SB_CS_N<0>")
	)
	(gr_poly
		(pts
			(xy 133.903466 -242.090702) (xy 133.903466 -242.046252) (xy 133.547866 -242.046252) (xy 133.547866 -242.090702)
			(xy 133.594856 -242.243102) (xy 133.856476 -242.243102)
		)
		(stroke
			(width 0)
			(type solid)
		)
		(fill yes)
		(layer "In6.Cu")
		(net "M_G_CPU1_SB_DQ<0>")
	)
	(gr_poly
		(pts
			(xy 133.903466 -240.871502) (xy 133.856476 -240.719102) (xy 133.594856 -240.719102) (xy 133.547866 -240.871502)
			(xy 133.547866 -240.915952) (xy 133.903466 -240.915952)
		)
		(stroke
			(width 0)
			(type solid)
		)
		(fill yes)
		(layer "In6.Cu")
		(net "M_G_CPU1_SB_DQ<3>")
	)
	(gr_poly
		(pts
			(xy 133.903466 -240.46307) (xy 133.903466 -240.41862) (xy 133.547866 -240.41862) (xy 133.547866 -240.46307)
			(xy 133.594856 -240.61547) (xy 133.856476 -240.61547)
		)
		(stroke
			(width 0)
			(type solid)
		)
		(fill yes)
		(layer "In6.Cu")
		(net "M_G_CPU1_SB_DQS_DP<0>")
	)
	(gr_poly
		(pts
			(xy 133.903466 -239.24387) (xy 133.856476 -239.09147) (xy 133.594856 -239.09147) (xy 133.547866 -239.24387)
			(xy 133.547866 -239.288066) (xy 133.903466 -239.288066)
		)
		(stroke
			(width 0)
			(type solid)
		)
		(fill yes)
		(layer "In6.Cu")
		(net "M_G_CPU1_SB_DQS_DP<5>")
	)
	(gr_poly
		(pts
			(xy 133.903466 -235.988098) (xy 133.856476 -235.835698) (xy 133.594856 -235.835698) (xy 133.547866 -235.988098)
			(xy 133.547866 -236.032548) (xy 133.903466 -236.032548)
		)
		(stroke
			(width 0)
			(type solid)
		)
		(fill yes)
		(layer "In6.Cu")
		(net "M_G_CPU1_SB_DQ<9>")
	)
	(gr_poly
		(pts
			(xy 133.903466 -235.579666) (xy 133.903466 -235.535216) (xy 133.547866 -235.535216) (xy 133.547866 -235.579666)
			(xy 133.594856 -235.732066) (xy 133.856476 -235.732066)
		)
		(stroke
			(width 0)
			(type solid)
		)
		(fill yes)
		(layer "In6.Cu")
		(net "M_G_CPU1_SB_DQS_DN<6>")
	)
	(gr_poly
		(pts
			(xy 133.903466 -234.360466) (xy 133.856476 -234.208066) (xy 133.594856 -234.208066) (xy 133.547866 -234.360466)
			(xy 133.547866 -234.404916) (xy 133.903466 -234.404916)
		)
		(stroke
			(width 0)
			(type solid)
		)
		(fill yes)
		(layer "In6.Cu")
		(net "M_G_CPU1_SB_DQS_DN<1>")
	)
	(gr_poly
		(pts
			(xy 133.903466 -233.952034) (xy 133.903466 -233.907584) (xy 133.547866 -233.907584) (xy 133.547866 -233.952034)
			(xy 133.594856 -234.104434) (xy 133.856476 -234.104434)
		)
		(stroke
			(width 0)
			(type solid)
		)
		(fill yes)
		(layer "In6.Cu")
		(net "M_G_CPU1_SB_DQ<14>")
	)
	(gr_poly
		(pts
			(xy 133.903466 -231.104694) (xy 133.856476 -230.952294) (xy 133.594856 -230.952294) (xy 133.547866 -231.104694)
			(xy 133.547866 -231.149144) (xy 133.903466 -231.149144)
		)
		(stroke
			(width 0)
			(type solid)
		)
		(fill yes)
		(layer "In6.Cu")
		(net "M_H_CPU1_SB_DQ<18>")
	)
	(gr_poly
		(pts
			(xy 133.903466 -230.696262) (xy 133.903466 -230.651812) (xy 133.547866 -230.651812) (xy 133.547866 -230.696262)
			(xy 133.594856 -230.848662) (xy 133.856476 -230.848662)
		)
		(stroke
			(width 0)
			(type solid)
		)
		(fill yes)
		(layer "In6.Cu")
		(net "M_H_CPU1_SB_DQ<17>")
	)
	(gr_poly
		(pts
			(xy 133.903466 -229.477062) (xy 133.856476 -229.324662) (xy 133.594856 -229.324662) (xy 133.547866 -229.477062)
			(xy 133.547866 -229.521512) (xy 133.903466 -229.521512)
		)
		(stroke
			(width 0)
			(type solid)
		)
		(fill yes)
		(layer "In6.Cu")
		(net "M_H_CPU1_SB_DQS_DN<2>")
	)
	(gr_poly
		(pts
			(xy 133.903466 -229.06863) (xy 133.903466 -229.02418) (xy 133.547866 -229.02418) (xy 133.547866 -229.06863)
			(xy 133.594856 -229.22103) (xy 133.856476 -229.22103)
		)
		(stroke
			(width 0)
			(type solid)
		)
		(fill yes)
		(layer "In6.Cu")
		(net "M_H_CPU1_SB_DQS_DN<7>")
	)
	(gr_poly
		(pts
			(xy 133.903466 -227.84943) (xy 133.856476 -227.69703) (xy 133.594856 -227.69703) (xy 133.547866 -227.84943)
			(xy 133.547866 -227.893626) (xy 133.903466 -227.893626)
		)
		(stroke
			(width 0)
			(type solid)
		)
		(fill yes)
		(layer "In6.Cu")
		(net "M_H_CPU1_SB_DQ<22>")
	)
	(gr_poly
		(pts
			(xy 133.903466 -227.44049) (xy 133.903466 -227.396294) (xy 133.547866 -227.396294) (xy 133.547866 -227.44049)
			(xy 133.594856 -227.59289) (xy 133.856476 -227.59289)
		)
		(stroke
			(width 0)
			(type solid)
		)
		(fill yes)
		(layer "In6.Cu")
		(net "M_H_CPU1_SB_DQ<21>")
	)
	(gr_poly
		(pts
			(xy 134.00913 -265.109706) (xy 134.00913 -265.06551) (xy 133.65353 -265.06551) (xy 133.65353 -265.109706)
			(xy 133.70052 -265.262106) (xy 133.96214 -265.262106)
		)
		(stroke
			(width 0)
			(type solid)
		)
		(fill yes)
		(layer "In6.Cu")
		(net "M_G_CPU1_SA_CB<0>")
	)
	(gr_poly
		(pts
			(xy 134.009892 -271.62125) (xy 134.009892 -271.5768) (xy 133.654292 -271.5768) (xy 133.654292 -271.62125)
			(xy 133.701282 -271.77365) (xy 133.962902 -271.77365)
		)
		(stroke
			(width 0)
			(type solid)
		)
		(fill yes)
		(layer "In6.Cu")
		(net "M_G_CPU1_SA_DQ<12>")
	)
	(gr_poly
		(pts
			(xy 134.009892 -266.737846) (xy 134.009892 -266.693396) (xy 133.654292 -266.693396) (xy 133.654292 -266.737846)
			(xy 133.701282 -266.890246) (xy 133.962902 -266.890246)
		)
		(stroke
			(width 0)
			(type solid)
		)
		(fill yes)
		(layer "In6.Cu")
		(net "M_G_CPU1_SA_DQ<28>")
	)
	(gr_poly
		(pts
			(xy 134.009892 -265.518646) (xy 133.962902 -265.366246) (xy 133.701282 -265.366246) (xy 133.654292 -265.518646)
			(xy 133.654292 -265.563096) (xy 134.009892 -265.563096)
		)
		(stroke
			(width 0)
			(type solid)
		)
		(fill yes)
		(layer "In6.Cu")
		(net "M_G_CPU1_SA_DQ<31>")
	)
	(gr_poly
		(pts
			(xy 134.01929 -278.540718) (xy 133.9723 -278.388318) (xy 133.71068 -278.388318) (xy 133.66369 -278.540718)
			(xy 133.66369 -278.585168) (xy 134.01929 -278.585168)
		)
		(stroke
			(width 0)
			(type solid)
		)
		(fill yes)
		(layer "In6.Cu")
		(net "M_H_CPU1_SA_DQ<1>")
	)
	(gr_poly
		(pts
			(xy 134.01929 -278.132032) (xy 134.01929 -278.087836) (xy 133.66369 -278.087836) (xy 133.66369 -278.132032)
			(xy 133.71068 -278.284432) (xy 133.9723 -278.284432)
		)
		(stroke
			(width 0)
			(type solid)
		)
		(fill yes)
		(layer "In6.Cu")
		(net "M_H_CPU1_SA_DQS_DP<0>")
	)
	(gr_poly
		(pts
			(xy 134.01929 -275.284946) (xy 133.9723 -275.132546) (xy 133.71068 -275.132546) (xy 133.66369 -275.284946)
			(xy 133.66369 -275.329142) (xy 134.01929 -275.329142)
		)
		(stroke
			(width 0)
			(type solid)
		)
		(fill yes)
		(layer "In6.Cu")
		(net "M_H_CPU1_SA_DQ<7>")
	)
	(gr_poly
		(pts
			(xy 134.01929 -274.876514) (xy 134.01929 -274.832318) (xy 133.66369 -274.832318) (xy 133.66369 -274.876514)
			(xy 133.71068 -275.028914) (xy 133.9723 -275.028914)
		)
		(stroke
			(width 0)
			(type solid)
		)
		(fill yes)
		(layer "In6.Cu")
		(net "M_G_CPU1_SA_DQ<8>")
	)
	(gr_poly
		(pts
			(xy 134.01929 -270.401542) (xy 133.9723 -270.249142) (xy 133.71068 -270.249142) (xy 133.66369 -270.401542)
			(xy 133.66369 -270.445992) (xy 134.01929 -270.445992)
		)
		(stroke
			(width 0)
			(type solid)
		)
		(fill yes)
		(layer "In6.Cu")
		(net "M_G_CPU1_SA_DQ<15>")
	)
	(gr_poly
		(pts
			(xy 134.01929 -269.993618) (xy 134.01929 -269.949168) (xy 133.66369 -269.949168) (xy 133.66369 -269.993618)
			(xy 133.71068 -270.146018) (xy 133.9723 -270.146018)
		)
		(stroke
			(width 0)
			(type solid)
		)
		(fill yes)
		(layer "In6.Cu")
		(net "M_G_CPU1_SA_DQ<24>")
	)
	(gr_poly
		(pts
			(xy 134.01929 -260.634734) (xy 133.9723 -260.482334) (xy 133.71068 -260.482334) (xy 133.66369 -260.634734)
			(xy 133.66369 -260.679184) (xy 134.01929 -260.679184)
		)
		(stroke
			(width 0)
			(type solid)
		)
		(fill yes)
		(layer "In6.Cu")
		(net "M_G_CPU1_SA_CB<7>")
	)
	(gr_poly
		(pts
			(xy 134.02183 -279.759918) (xy 134.02183 -279.715722) (xy 133.66623 -279.715722) (xy 133.66623 -279.759918)
			(xy 133.71322 -279.912318) (xy 133.97484 -279.912318)
		)
		(stroke
			(width 0)
			(type solid)
		)
		(fill yes)
		(layer "In6.Cu")
		(net "M_H_CPU1_SA_DQ<0>")
	)
	(gr_poly
		(pts
			(xy 134.02183 -276.912578) (xy 133.97484 -276.760178) (xy 133.71322 -276.760178) (xy 133.66623 -276.912578)
			(xy 133.66623 -276.957028) (xy 134.02183 -276.957028)
		)
		(stroke
			(width 0)
			(type solid)
		)
		(fill yes)
		(layer "In6.Cu")
		(net "M_H_CPU1_SA_DQS_DP<5>")
	)
	(gr_poly
		(pts
			(xy 134.02183 -276.5044) (xy 134.02183 -276.460204) (xy 133.66623 -276.460204) (xy 133.66623 -276.5044)
			(xy 133.71322 -276.6568) (xy 133.97484 -276.6568)
		)
		(stroke
			(width 0)
			(type solid)
		)
		(fill yes)
		(layer "In6.Cu")
		(net "M_H_CPU1_SA_DQ<4>")
	)
	(gr_poly
		(pts
			(xy 134.02183 -273.657314) (xy 133.97484 -273.504914) (xy 133.71322 -273.504914) (xy 133.66623 -273.657314)
			(xy 133.66623 -273.70151) (xy 134.02183 -273.70151)
		)
		(stroke
			(width 0)
			(type solid)
		)
		(fill yes)
		(layer "In6.Cu")
		(net "M_G_CPU1_SA_DQ<11>")
	)
	(gr_poly
		(pts
			(xy 134.02183 -273.248882) (xy 134.02183 -273.204686) (xy 133.66623 -273.204686) (xy 133.66623 -273.248882)
			(xy 133.71322 -273.401282) (xy 133.97484 -273.401282)
		)
		(stroke
			(width 0)
			(type solid)
		)
		(fill yes)
		(layer "In6.Cu")
		(net "M_G_CPU1_SA_DQS_DP<1>")
	)
	(gr_poly
		(pts
			(xy 134.02183 -272.029174) (xy 133.97484 -271.876774) (xy 133.71322 -271.876774) (xy 133.66623 -272.029174)
			(xy 133.66623 -272.073624) (xy 134.02183 -272.073624)
		)
		(stroke
			(width 0)
			(type solid)
		)
		(fill yes)
		(layer "In6.Cu")
		(net "M_G_CPU1_SA_DQS_DP<6>")
	)
	(gr_poly
		(pts
			(xy 134.02183 -268.77391) (xy 133.97484 -268.62151) (xy 133.71322 -268.62151) (xy 133.66623 -268.77391)
			(xy 133.66623 -268.818106) (xy 134.02183 -268.818106)
		)
		(stroke
			(width 0)
			(type solid)
		)
		(fill yes)
		(layer "In6.Cu")
		(net "M_G_CPU1_SA_DQ<27>")
	)
	(gr_poly
		(pts
			(xy 134.02183 -268.365478) (xy 134.02183 -268.321282) (xy 133.66623 -268.321282) (xy 133.66623 -268.365478)
			(xy 133.71322 -268.517878) (xy 133.97484 -268.517878)
		)
		(stroke
			(width 0)
			(type solid)
		)
		(fill yes)
		(layer "In6.Cu")
		(net "M_G_CPU1_SA_DQS_DP<3>")
	)
	(gr_poly
		(pts
			(xy 134.02183 -267.146278) (xy 133.97484 -266.993878) (xy 133.71322 -266.993878) (xy 133.66623 -267.146278)
			(xy 133.66623 -267.190474) (xy 134.02183 -267.190474)
		)
		(stroke
			(width 0)
			(type solid)
		)
		(fill yes)
		(layer "In6.Cu")
		(net "M_G_CPU1_SA_DQS_DP<8>")
	)
	(gr_poly
		(pts
			(xy 134.02183 -263.890506) (xy 133.97484 -263.738106) (xy 133.71322 -263.738106) (xy 133.66623 -263.890506)
			(xy 133.66623 -263.934956) (xy 134.02183 -263.934956)
		)
		(stroke
			(width 0)
			(type solid)
		)
		(fill yes)
		(layer "In6.Cu")
		(net "M_G_CPU1_SA_CB<3>")
	)
	(gr_poly
		(pts
			(xy 134.02183 -263.482582) (xy 134.02183 -263.438132) (xy 133.66623 -263.438132) (xy 133.66623 -263.482582)
			(xy 133.71322 -263.634982) (xy 133.97484 -263.634982)
		)
		(stroke
			(width 0)
			(type solid)
		)
		(fill yes)
		(layer "In6.Cu")
		(net "M_G_CPU1_SA_DQS_DP<4>")
	)
	(gr_poly
		(pts
			(xy 134.02183 -262.262874) (xy 133.97484 -262.110474) (xy 133.71322 -262.110474) (xy 133.66623 -262.262874)
			(xy 133.66623 -262.30707) (xy 134.02183 -262.30707)
		)
		(stroke
			(width 0)
			(type solid)
		)
		(fill yes)
		(layer "In6.Cu")
		(net "M_G_CPU1_SA_DQS_DP<9>")
	)
	(gr_poly
		(pts
			(xy 134.02183 -261.854442) (xy 134.02183 -261.810246) (xy 133.66623 -261.810246) (xy 133.66623 -261.854442)
			(xy 133.71322 -262.006842) (xy 133.97484 -262.006842)
		)
		(stroke
			(width 0)
			(type solid)
		)
		(fill yes)
		(layer "In6.Cu")
		(net "M_G_CPU1_SA_CB<4>")
	)
	(gr_poly
		(pts
			(xy 134.36727 -244.53215) (xy 134.36727 -244.487954) (xy 134.01167 -244.487954) (xy 134.01167 -244.53215)
			(xy 134.05866 -244.68455) (xy 134.32028 -244.68455)
		)
		(stroke
			(width 0)
			(type solid)
		)
		(fill yes)
		(layer "In6.Cu")
		(net "M_H_CPU1_SB_CS_N<2>")
	)
	(gr_poly
		(pts
			(xy 134.36727 -243.313458) (xy 134.32028 -243.161058) (xy 134.05866 -243.161058) (xy 134.01167 -243.313458)
			(xy 134.01167 -243.357654) (xy 134.36727 -243.357654)
		)
		(stroke
			(width 0)
			(type solid)
		)
		(fill yes)
		(layer "In6.Cu")
		(net "M_H_CPU1_SB_CS_N<1>")
	)
	(gr_poly
		(pts
			(xy 134.36727 -241.685318) (xy 134.32028 -241.532918) (xy 134.05866 -241.532918) (xy 134.01167 -241.685318)
			(xy 134.01167 -241.729768) (xy 134.36727 -241.729768)
		)
		(stroke
			(width 0)
			(type solid)
		)
		(fill yes)
		(layer "In6.Cu")
		(net "M_G_CPU1_SB_DQ<2>")
	)
	(gr_poly
		(pts
			(xy 134.36727 -241.276886) (xy 134.36727 -241.232436) (xy 134.01167 -241.232436) (xy 134.01167 -241.276886)
			(xy 134.05866 -241.429286) (xy 134.32028 -241.429286)
		)
		(stroke
			(width 0)
			(type solid)
		)
		(fill yes)
		(layer "In6.Cu")
		(net "M_G_CPU1_SB_DQ<1>")
	)
	(gr_poly
		(pts
			(xy 134.36727 -240.057686) (xy 134.32028 -239.905286) (xy 134.05866 -239.905286) (xy 134.01167 -240.057686)
			(xy 134.01167 -240.101882) (xy 134.36727 -240.101882)
		)
		(stroke
			(width 0)
			(type solid)
		)
		(fill yes)
		(layer "In6.Cu")
		(net "M_G_CPU1_SB_DQS_DN<0>")
	)
	(gr_poly
		(pts
			(xy 134.36727 -239.648746) (xy 134.36727 -239.60455) (xy 134.01167 -239.60455) (xy 134.01167 -239.648746)
			(xy 134.05866 -239.801146) (xy 134.32028 -239.801146)
		)
		(stroke
			(width 0)
			(type solid)
		)
		(fill yes)
		(layer "In6.Cu")
		(net "M_G_CPU1_SB_DQS_DN<5>")
	)
	(gr_poly
		(pts
			(xy 134.36727 -228.663246) (xy 134.32028 -228.510846) (xy 134.05866 -228.510846) (xy 134.01167 -228.663246)
			(xy 134.01167 -228.707696) (xy 134.36727 -228.707696)
		)
		(stroke
			(width 0)
			(type solid)
		)
		(fill yes)
		(layer "In6.Cu")
		(net "M_H_CPU1_SB_DQS_DP<7>")
	)
	(gr_poly
		(pts
			(xy 134.36727 -228.254814) (xy 134.36727 -228.210364) (xy 134.01167 -228.210364) (xy 134.01167 -228.254814)
			(xy 134.05866 -228.407214) (xy 134.32028 -228.407214)
		)
		(stroke
			(width 0)
			(type solid)
		)
		(fill yes)
		(layer "In6.Cu")
		(net "M_H_CPU1_SB_DQ<20>")
	)
	(gr_poly
		(pts
			(xy 134.36727 -227.035614) (xy 134.32028 -226.883214) (xy 134.05866 -226.883214) (xy 134.01167 -227.035614)
			(xy 134.01167 -227.07981) (xy 134.36727 -227.07981)
		)
		(stroke
			(width 0)
			(type solid)
		)
		(fill yes)
		(layer "In6.Cu")
		(net "M_H_CPU1_SB_DQ<23>")
	)
	(gr_poly
		(pts
			(xy 134.373112 -238.430054) (xy 134.326122 -238.277654) (xy 134.064502 -238.277654) (xy 134.017512 -238.430054)
			(xy 134.017512 -238.47425) (xy 134.373112 -238.47425)
		)
		(stroke
			(width 0)
			(type solid)
		)
		(fill yes)
		(layer "In6.Cu")
		(net "M_G_CPU1_SB_DQ<6>")
	)
	(gr_poly
		(pts
			(xy 134.373112 -238.021114) (xy 134.373112 -237.976664) (xy 134.017512 -237.976664) (xy 134.017512 -238.021114)
			(xy 134.064502 -238.173514) (xy 134.326122 -238.173514)
		)
		(stroke
			(width 0)
			(type solid)
		)
		(fill yes)
		(layer "In6.Cu")
		(net "M_G_CPU1_SB_DQ<5>")
	)
	(gr_poly
		(pts
			(xy 134.373366 -249.415554) (xy 134.373366 -249.371358) (xy 134.017766 -249.371358) (xy 134.017766 -249.415554)
			(xy 134.064756 -249.567954) (xy 134.326376 -249.567954)
		)
		(stroke
			(width 0)
			(type solid)
		)
		(fill yes)
		(layer "In6.Cu")
		(net "M_E_CPU1_SA_RSP<0>")
	)
	(gr_poly
		(pts
			(xy 134.373366 -248.196354) (xy 134.326376 -248.043954) (xy 134.064756 -248.043954) (xy 134.017766 -248.196354)
			(xy 134.017766 -248.240804) (xy 134.373366 -248.240804)
		)
		(stroke
			(width 0)
			(type solid)
		)
		(fill yes)
		(layer "In6.Cu")
		(net "M_E_CPU1_SB_RSP<1>")
	)
	(gr_poly
		(pts
			(xy 134.373366 -236.801914) (xy 134.326376 -236.649514) (xy 134.064756 -236.649514) (xy 134.017766 -236.801914)
			(xy 134.017766 -236.846364) (xy 134.373366 -236.846364)
		)
		(stroke
			(width 0)
			(type solid)
		)
		(fill yes)
		(layer "In6.Cu")
		(net "M_G_CPU1_SB_DQ<10>")
	)
	(gr_poly
		(pts
			(xy 134.373366 -236.393482) (xy 134.373366 -236.349286) (xy 134.017766 -236.349286) (xy 134.017766 -236.393482)
			(xy 134.064756 -236.545882) (xy 134.326376 -236.545882)
		)
		(stroke
			(width 0)
			(type solid)
		)
		(fill yes)
		(layer "In6.Cu")
		(net "M_G_CPU1_SB_DQ<11>")
	)
	(gr_poly
		(pts
			(xy 134.373366 -235.174282) (xy 134.326376 -235.021882) (xy 134.064756 -235.021882) (xy 134.017766 -235.174282)
			(xy 134.017766 -235.218732) (xy 134.373366 -235.218732)
		)
		(stroke
			(width 0)
			(type solid)
		)
		(fill yes)
		(layer "In6.Cu")
		(net "M_G_CPU1_SB_DQS_DP<6>")
	)
	(gr_poly
		(pts
			(xy 134.373366 -234.76585) (xy 134.373366 -234.7214) (xy 134.017766 -234.7214) (xy 134.017766 -234.76585)
			(xy 134.064756 -234.91825) (xy 134.326376 -234.91825)
		)
		(stroke
			(width 0)
			(type solid)
		)
		(fill yes)
		(layer "In6.Cu")
		(net "M_G_CPU1_SB_DQS_DP<1>")
	)
	(gr_poly
		(pts
			(xy 134.373366 -233.54665) (xy 134.326376 -233.39425) (xy 134.064756 -233.39425) (xy 134.017766 -233.54665)
			(xy 134.017766 -233.590846) (xy 134.373366 -233.590846)
		)
		(stroke
			(width 0)
			(type solid)
		)
		(fill yes)
		(layer "In6.Cu")
		(net "M_G_CPU1_SB_DQ<12>")
	)
	(gr_poly
		(pts
			(xy 134.373366 -233.13771) (xy 134.373366 -233.093514) (xy 134.017766 -233.093514) (xy 134.017766 -233.13771)
			(xy 134.064756 -233.29011) (xy 134.326376 -233.29011)
		)
		(stroke
			(width 0)
			(type solid)
		)
		(fill yes)
		(layer "In6.Cu")
		(net "M_G_CPU1_SB_DQ<15>")
	)
	(gr_poly
		(pts
			(xy 134.373366 -231.510078) (xy 134.373366 -231.465882) (xy 134.017766 -231.465882) (xy 134.017766 -231.510078)
			(xy 134.064756 -231.662478) (xy 134.326376 -231.662478)
		)
		(stroke
			(width 0)
			(type solid)
		)
		(fill yes)
		(layer "In6.Cu")
		(net "M_H_CPU1_SB_DQ<16>")
	)
	(gr_poly
		(pts
			(xy 134.373366 -230.290878) (xy 134.326376 -230.138478) (xy 134.064756 -230.138478) (xy 134.017766 -230.290878)
			(xy 134.017766 -230.335328) (xy 134.373366 -230.335328)
		)
		(stroke
			(width 0)
			(type solid)
		)
		(fill yes)
		(layer "In6.Cu")
		(net "M_H_CPU1_SB_DQ<19>")
	)
	(gr_poly
		(pts
			(xy 134.373366 -229.882446) (xy 134.373366 -229.837996) (xy 134.017766 -229.837996) (xy 134.017766 -229.882446)
			(xy 134.064756 -230.034846) (xy 134.326376 -230.034846)
		)
		(stroke
			(width 0)
			(type solid)
		)
		(fill yes)
		(layer "In6.Cu")
		(net "M_H_CPU1_SB_DQS_DP<2>")
	)
	(gr_poly
		(pts
			(xy 134.474712 -279.354534) (xy 134.427722 -279.202134) (xy 134.166102 -279.202134) (xy 134.119112 -279.354534)
			(xy 134.119112 -279.39873) (xy 134.474712 -279.39873)
		)
		(stroke
			(width 0)
			(type solid)
		)
		(fill yes)
		(layer "In6.Cu")
		(net "M_H_CPU1_SA_DQ<2>")
	)
	(gr_poly
		(pts
			(xy 134.474712 -277.318216) (xy 134.474712 -277.27402) (xy 134.119112 -277.27402) (xy 134.119112 -277.318216)
			(xy 134.166102 -277.470616) (xy 134.427722 -277.470616)
		)
		(stroke
			(width 0)
			(type solid)
		)
		(fill yes)
		(layer "In6.Cu")
		(net "M_H_CPU1_SA_DQS_DN<5>")
	)
	(gr_poly
		(pts
			(xy 134.474712 -276.098762) (xy 134.427722 -275.946362) (xy 134.166102 -275.946362) (xy 134.119112 -276.098762)
			(xy 134.119112 -276.143212) (xy 134.474712 -276.143212)
		)
		(stroke
			(width 0)
			(type solid)
		)
		(fill yes)
		(layer "In6.Cu")
		(net "M_H_CPU1_SA_DQ<6>")
	)
	(gr_poly
		(pts
			(xy 134.474712 -275.690584) (xy 134.474712 -275.646388) (xy 134.119112 -275.646388) (xy 134.119112 -275.690584)
			(xy 134.166102 -275.842984) (xy 134.427722 -275.842984)
		)
		(stroke
			(width 0)
			(type solid)
		)
		(fill yes)
		(layer "In6.Cu")
		(net "M_H_CPU1_SA_DQ<5>")
	)
	(gr_poly
		(pts
			(xy 134.474712 -274.47113) (xy 134.427722 -274.31873) (xy 134.166102 -274.31873) (xy 134.119112 -274.47113)
			(xy 134.119112 -274.515326) (xy 134.474712 -274.515326)
		)
		(stroke
			(width 0)
			(type solid)
		)
		(fill yes)
		(layer "In6.Cu")
		(net "M_G_CPU1_SA_DQ<10>")
	)
	(gr_poly
		(pts
			(xy 134.474712 -274.062698) (xy 134.474712 -274.018502) (xy 134.119112 -274.018502) (xy 134.119112 -274.062698)
			(xy 134.166102 -274.215098) (xy 134.427722 -274.215098)
		)
		(stroke
			(width 0)
			(type solid)
		)
		(fill yes)
		(layer "In6.Cu")
		(net "M_G_CPU1_SA_DQ<9>")
	)
	(gr_poly
		(pts
			(xy 134.474712 -272.843498) (xy 134.427722 -272.691098) (xy 134.166102 -272.691098) (xy 134.119112 -272.843498)
			(xy 134.119112 -272.887694) (xy 134.474712 -272.887694)
		)
		(stroke
			(width 0)
			(type solid)
		)
		(fill yes)
		(layer "In6.Cu")
		(net "M_G_CPU1_SA_DQS_DN<1>")
	)
	(gr_poly
		(pts
			(xy 134.474712 -272.435066) (xy 134.474712 -272.39087) (xy 134.119112 -272.39087) (xy 134.119112 -272.435066)
			(xy 134.166102 -272.587466) (xy 134.427722 -272.587466)
		)
		(stroke
			(width 0)
			(type solid)
		)
		(fill yes)
		(layer "In6.Cu")
		(net "M_G_CPU1_SA_DQS_DN<6>")
	)
	(gr_poly
		(pts
			(xy 134.474712 -270.807434) (xy 134.474712 -270.762984) (xy 134.119112 -270.762984) (xy 134.119112 -270.807434)
			(xy 134.166102 -270.959834) (xy 134.427722 -270.959834)
		)
		(stroke
			(width 0)
			(type solid)
		)
		(fill yes)
		(layer "In6.Cu")
		(net "M_G_CPU1_SA_DQ<13>")
	)
	(gr_poly
		(pts
			(xy 134.474712 -269.587726) (xy 134.427722 -269.435326) (xy 134.166102 -269.435326) (xy 134.119112 -269.587726)
			(xy 134.119112 -269.631922) (xy 134.474712 -269.631922)
		)
		(stroke
			(width 0)
			(type solid)
		)
		(fill yes)
		(layer "In6.Cu")
		(net "M_G_CPU1_SA_DQ<26>")
	)
	(gr_poly
		(pts
			(xy 134.474712 -269.179294) (xy 134.474712 -269.135098) (xy 134.119112 -269.135098) (xy 134.119112 -269.179294)
			(xy 134.166102 -269.331694) (xy 134.427722 -269.331694)
		)
		(stroke
			(width 0)
			(type solid)
		)
		(fill yes)
		(layer "In6.Cu")
		(net "M_G_CPU1_SA_DQ<25>")
	)
	(gr_poly
		(pts
			(xy 134.474712 -267.960094) (xy 134.427722 -267.807694) (xy 134.166102 -267.807694) (xy 134.119112 -267.960094)
			(xy 134.119112 -268.00429) (xy 134.474712 -268.00429)
		)
		(stroke
			(width 0)
			(type solid)
		)
		(fill yes)
		(layer "In6.Cu")
		(net "M_G_CPU1_SA_DQS_DN<3>")
	)
	(gr_poly
		(pts
			(xy 134.474712 -267.551662) (xy 134.474712 -267.507466) (xy 134.119112 -267.507466) (xy 134.119112 -267.551662)
			(xy 134.166102 -267.704062) (xy 134.427722 -267.704062)
		)
		(stroke
			(width 0)
			(type solid)
		)
		(fill yes)
		(layer "In6.Cu")
		(net "M_G_CPU1_SA_DQS_DN<8>")
	)
	(gr_poly
		(pts
			(xy 134.474712 -264.296398) (xy 134.474712 -264.251948) (xy 134.119112 -264.251948) (xy 134.119112 -264.296398)
			(xy 134.166102 -264.448798) (xy 134.427722 -264.448798)
		)
		(stroke
			(width 0)
			(type solid)
		)
		(fill yes)
		(layer "In6.Cu")
		(net "M_G_CPU1_SA_CB<1>")
	)
	(gr_poly
		(pts
			(xy 134.474712 -263.07669) (xy 134.427722 -262.92429) (xy 134.166102 -262.92429) (xy 134.119112 -263.07669)
			(xy 134.119112 -263.120886) (xy 134.474712 -263.120886)
		)
		(stroke
			(width 0)
			(type solid)
		)
		(fill yes)
		(layer "In6.Cu")
		(net "M_G_CPU1_SA_DQS_DN<4>")
	)
	(gr_poly
		(pts
			(xy 134.474712 -262.668258) (xy 134.474712 -262.624062) (xy 134.119112 -262.624062) (xy 134.119112 -262.668258)
			(xy 134.166102 -262.820658) (xy 134.427722 -262.820658)
		)
		(stroke
			(width 0)
			(type solid)
		)
		(fill yes)
		(layer "In6.Cu")
		(net "M_G_CPU1_SA_DQS_DN<9>")
	)
	(gr_poly
		(pts
			(xy 134.474712 -261.449058) (xy 134.427722 -261.296658) (xy 134.166102 -261.296658) (xy 134.119112 -261.449058)
			(xy 134.119112 -261.493254) (xy 134.474712 -261.493254)
		)
		(stroke
			(width 0)
			(type solid)
		)
		(fill yes)
		(layer "In6.Cu")
		(net "M_G_CPU1_SA_CB<6>")
	)
	(gr_poly
		(pts
			(xy 134.474712 -261.040626) (xy 134.474712 -260.99643) (xy 134.119112 -260.99643) (xy 134.119112 -261.040626)
			(xy 134.166102 -261.193026) (xy 134.427722 -261.193026)
		)
		(stroke
			(width 0)
			(type solid)
		)
		(fill yes)
		(layer "In6.Cu")
		(net "M_G_CPU1_SA_CB<5>")
	)
	(gr_poly
		(pts
			(xy 134.483094 -278.945848) (xy 134.483094 -278.901652) (xy 134.127494 -278.901652) (xy 134.127494 -278.945848)
			(xy 134.174484 -279.098248) (xy 134.436104 -279.098248)
		)
		(stroke
			(width 0)
			(type solid)
		)
		(fill yes)
		(layer "In6.Cu")
		(net "M_H_CPU1_SA_DQ<3>")
	)
	(gr_poly
		(pts
			(xy 134.483094 -277.726902) (xy 134.436104 -277.574502) (xy 134.174484 -277.574502) (xy 134.127494 -277.726902)
			(xy 134.127494 -277.771098) (xy 134.483094 -277.771098)
		)
		(stroke
			(width 0)
			(type solid)
		)
		(fill yes)
		(layer "In6.Cu")
		(net "M_H_CPU1_SA_DQS_DN<0>")
	)
	(gr_poly
		(pts
			(xy 134.48665 -271.215866) (xy 134.43966 -271.063466) (xy 134.17804 -271.063466) (xy 134.13105 -271.215866)
			(xy 134.13105 -271.260062) (xy 134.48665 -271.260062)
		)
		(stroke
			(width 0)
			(type solid)
		)
		(fill yes)
		(layer "In6.Cu")
		(net "M_G_CPU1_SA_DQ<14>")
	)
	(gr_poly
		(pts
			(xy 134.48665 -266.332462) (xy 134.43966 -266.180062) (xy 134.17804 -266.180062) (xy 134.13105 -266.332462)
			(xy 134.13105 -266.376658) (xy 134.48665 -266.376658)
		)
		(stroke
			(width 0)
			(type solid)
		)
		(fill yes)
		(layer "In6.Cu")
		(net "M_G_CPU1_SA_DQ<30>")
	)
	(gr_poly
		(pts
			(xy 134.48665 -265.923522) (xy 134.48665 -265.879326) (xy 134.13105 -265.879326) (xy 134.13105 -265.923522)
			(xy 134.17804 -266.075922) (xy 134.43966 -266.075922)
		)
		(stroke
			(width 0)
			(type solid)
		)
		(fill yes)
		(layer "In6.Cu")
		(net "M_G_CPU1_SA_DQ<29>")
	)
	(gr_poly
		(pts
			(xy 134.487412 -264.70483) (xy 134.440422 -264.55243) (xy 134.178802 -264.55243) (xy 134.131812 -264.70483)
			(xy 134.131812 -264.749026) (xy 134.487412 -264.749026)
		)
		(stroke
			(width 0)
			(type solid)
		)
		(fill yes)
		(layer "In6.Cu")
		(net "M_G_CPU1_SA_CB<2>")
	)
	(gr_poly
		(pts
			(xy 134.808722 -256.01041) (xy 134.847076 -255.988312) (xy 134.669276 -255.680464) (xy 134.630922 -255.702562)
			(xy 134.522464 -255.819402) (xy 134.653274 -256.04597)
		)
		(stroke
			(width 0)
			(type solid)
		)
		(fill yes)
		(layer "In6.Cu")
		(net "M_H_CPU1_SB_RSP<0>")
	)
	(gr_poly
		(pts
			(xy 134.843266 -249.010678) (xy 134.796276 -248.858278) (xy 134.534656 -248.858278) (xy 134.487666 -249.010678)
			(xy 134.487666 -249.054874) (xy 134.843266 -249.054874)
		)
		(stroke
			(width 0)
			(type solid)
		)
		(fill yes)
		(layer "In6.Cu")
		(net "M_E_CPU1_SB_RSP<0>")
	)
	(gr_poly
		(pts
			(xy 134.843266 -248.601738) (xy 134.843266 -248.557542) (xy 134.487666 -248.557542) (xy 134.487666 -248.601738)
			(xy 134.534656 -248.754138) (xy 134.796276 -248.754138)
		)
		(stroke
			(width 0)
			(type solid)
		)
		(fill yes)
		(layer "In6.Cu")
		(net "M_E_CPU1_SA_RSP<1>")
	)
	(gr_poly
		(pts
			(xy 134.843266 -238.83493) (xy 134.843266 -238.790734) (xy 134.487666 -238.790734) (xy 134.487666 -238.83493)
			(xy 134.534656 -238.98733) (xy 134.796276 -238.98733)
		)
		(stroke
			(width 0)
			(type solid)
		)
		(fill yes)
		(layer "In6.Cu")
		(net "M_G_CPU1_SB_DQ<4>")
	)
	(gr_poly
		(pts
			(xy 134.843266 -237.61573) (xy 134.796276 -237.46333) (xy 134.534656 -237.46333) (xy 134.487666 -237.61573)
			(xy 134.487666 -237.66018) (xy 134.843266 -237.66018)
		)
		(stroke
			(width 0)
			(type solid)
		)
		(fill yes)
		(layer "In6.Cu")
		(net "M_G_CPU1_SB_DQ<7>")
	)
	(gr_poly
		(pts
			(xy 134.843266 -237.207298) (xy 134.843266 -237.163102) (xy 134.487666 -237.163102) (xy 134.487666 -237.207298)
			(xy 134.534656 -237.359698) (xy 134.796276 -237.359698)
		)
		(stroke
			(width 0)
			(type solid)
		)
		(fill yes)
		(layer "In6.Cu")
		(net "M_G_CPU1_SB_DQ<8>")
	)
	(gr_poly
		(pts
			(xy 134.843266 -235.988098) (xy 134.796276 -235.835698) (xy 134.534656 -235.835698) (xy 134.487666 -235.988098)
			(xy 134.487666 -236.032548) (xy 134.843266 -236.032548)
		)
		(stroke
			(width 0)
			(type solid)
		)
		(fill yes)
		(layer "In6.Cu")
		(net "M_G_CPU1_SB_DQ<9>")
	)
	(gr_poly
		(pts
			(xy 134.843266 -235.579666) (xy 134.843266 -235.535216) (xy 134.487666 -235.535216) (xy 134.487666 -235.579666)
			(xy 134.534656 -235.732066) (xy 134.796276 -235.732066)
		)
		(stroke
			(width 0)
			(type solid)
		)
		(fill yes)
		(layer "In6.Cu")
		(net "M_G_CPU1_SB_DQS_DN<6>")
	)
	(gr_poly
		(pts
			(xy 134.843266 -234.360466) (xy 134.796276 -234.208066) (xy 134.534656 -234.208066) (xy 134.487666 -234.360466)
			(xy 134.487666 -234.404916) (xy 134.843266 -234.404916)
		)
		(stroke
			(width 0)
			(type solid)
		)
		(fill yes)
		(layer "In6.Cu")
		(net "M_G_CPU1_SB_DQS_DN<1>")
	)
	(gr_poly
		(pts
			(xy 134.843266 -233.952034) (xy 134.843266 -233.907584) (xy 134.487666 -233.907584) (xy 134.487666 -233.952034)
			(xy 134.534656 -234.104434) (xy 134.796276 -234.104434)
		)
		(stroke
			(width 0)
			(type solid)
		)
		(fill yes)
		(layer "In6.Cu")
		(net "M_G_CPU1_SB_DQ<14>")
	)
	(gr_poly
		(pts
			(xy 134.843266 -232.732834) (xy 134.796276 -232.580434) (xy 134.534656 -232.580434) (xy 134.487666 -232.732834)
			(xy 134.487666 -232.77703) (xy 134.843266 -232.77703)
		)
		(stroke
			(width 0)
			(type solid)
		)
		(fill yes)
		(layer "In6.Cu")
		(net "M_G_CPU1_SB_DQ<13>")
	)
	(gr_poly
		(pts
			(xy 134.843266 -231.104694) (xy 134.796276 -230.952294) (xy 134.534656 -230.952294) (xy 134.487666 -231.104694)
			(xy 134.487666 -231.149144) (xy 134.843266 -231.149144)
		)
		(stroke
			(width 0)
			(type solid)
		)
		(fill yes)
		(layer "In6.Cu")
		(net "M_H_CPU1_SB_DQ<18>")
	)
	(gr_poly
		(pts
			(xy 134.843266 -230.696262) (xy 134.843266 -230.651812) (xy 134.487666 -230.651812) (xy 134.487666 -230.696262)
			(xy 134.534656 -230.848662) (xy 134.796276 -230.848662)
		)
		(stroke
			(width 0)
			(type solid)
		)
		(fill yes)
		(layer "In6.Cu")
		(net "M_H_CPU1_SB_DQ<17>")
	)
	(gr_poly
		(pts
			(xy 134.843266 -229.477062) (xy 134.796276 -229.324662) (xy 134.534656 -229.324662) (xy 134.487666 -229.477062)
			(xy 134.487666 -229.521512) (xy 134.843266 -229.521512)
		)
		(stroke
			(width 0)
			(type solid)
		)
		(fill yes)
		(layer "In6.Cu")
		(net "M_H_CPU1_SB_DQS_DN<2>")
	)
	(gr_poly
		(pts
			(xy 134.851648 -244.126766) (xy 134.804658 -243.974366) (xy 134.543038 -243.974366) (xy 134.496048 -244.126766)
			(xy 134.496048 -244.171216) (xy 134.851648 -244.171216)
		)
		(stroke
			(width 0)
			(type solid)
		)
		(fill yes)
		(layer "In6.Cu")
		(net "M_H_CPU1_SB_CS_N<3>")
	)
	(gr_poly
		(pts
			(xy 134.851648 -243.718842) (xy 134.851648 -243.674392) (xy 134.496048 -243.674392) (xy 134.496048 -243.718842)
			(xy 134.543038 -243.871242) (xy 134.804658 -243.871242)
		)
		(stroke
			(width 0)
			(type solid)
		)
		(fill yes)
		(layer "In6.Cu")
		(net "M_H_CPU1_SB_CS_N<0>")
	)
	(gr_poly
		(pts
			(xy 134.851648 -242.090702) (xy 134.851648 -242.046506) (xy 134.496048 -242.046506) (xy 134.496048 -242.090702)
			(xy 134.543038 -242.243102) (xy 134.804658 -242.243102)
		)
		(stroke
			(width 0)
			(type solid)
		)
		(fill yes)
		(layer "In6.Cu")
		(net "M_G_CPU1_SB_DQ<0>")
	)
	(gr_poly
		(pts
			(xy 134.851648 -240.871502) (xy 134.804658 -240.719102) (xy 134.543038 -240.719102) (xy 134.496048 -240.871502)
			(xy 134.496048 -240.915698) (xy 134.851648 -240.915698)
		)
		(stroke
			(width 0)
			(type solid)
		)
		(fill yes)
		(layer "In6.Cu")
		(net "M_G_CPU1_SB_DQ<3>")
	)
	(gr_poly
		(pts
			(xy 134.851648 -240.46307) (xy 134.851648 -240.418874) (xy 134.496048 -240.418874) (xy 134.496048 -240.46307)
			(xy 134.543038 -240.61547) (xy 134.804658 -240.61547)
		)
		(stroke
			(width 0)
			(type solid)
		)
		(fill yes)
		(layer "In6.Cu")
		(net "M_G_CPU1_SB_DQS_DP<0>")
	)
	(gr_poly
		(pts
			(xy 134.851648 -239.243362) (xy 134.804658 -239.090962) (xy 134.543038 -239.090962) (xy 134.496048 -239.243362)
			(xy 134.496048 -239.287812) (xy 134.851648 -239.287812)
		)
		(stroke
			(width 0)
			(type solid)
		)
		(fill yes)
		(layer "In6.Cu")
		(net "M_G_CPU1_SB_DQS_DP<5>")
	)
	(gr_poly
		(pts
			(xy 134.851648 -229.06863) (xy 134.851648 -229.024434) (xy 134.496048 -229.024434) (xy 134.496048 -229.06863)
			(xy 134.543038 -229.22103) (xy 134.804658 -229.22103)
		)
		(stroke
			(width 0)
			(type solid)
		)
		(fill yes)
		(layer "In6.Cu")
		(net "M_H_CPU1_SB_DQS_DN<7>")
	)
	(gr_poly
		(pts
			(xy 134.851648 -227.848922) (xy 134.804658 -227.696522) (xy 134.543038 -227.696522) (xy 134.496048 -227.848922)
			(xy 134.496048 -227.893372) (xy 134.851648 -227.893372)
		)
		(stroke
			(width 0)
			(type solid)
		)
		(fill yes)
		(layer "In6.Cu")
		(net "M_H_CPU1_SB_DQ<22>")
	)
	(gr_poly
		(pts
			(xy 134.851648 -227.440998) (xy 134.851648 -227.396548) (xy 134.496048 -227.396548) (xy 134.496048 -227.440998)
			(xy 134.543038 -227.593398) (xy 134.804658 -227.593398)
		)
		(stroke
			(width 0)
			(type solid)
		)
		(fill yes)
		(layer "In6.Cu")
		(net "M_H_CPU1_SB_DQ<21>")
	)
	(gr_poly
		(pts
			(xy 134.918704 -255.39065) (xy 135.027162 -255.27381) (xy 134.896352 -255.047242) (xy 134.740904 -255.082802)
			(xy 134.70255 -255.1049) (xy 134.88035 -255.412748)
		)
		(stroke
			(width 0)
			(type solid)
		)
		(fill yes)
		(layer "In6.Cu")
		(net "M_H_CPU1_SA_RSP<0>")
	)
	(gr_poly
		(pts
			(xy 134.949692 -271.62125) (xy 134.949692 -271.5768) (xy 134.594092 -271.5768) (xy 134.594092 -271.62125)
			(xy 134.641082 -271.77365) (xy 134.902702 -271.77365)
		)
		(stroke
			(width 0)
			(type solid)
		)
		(fill yes)
		(layer "In6.Cu")
		(net "M_G_CPU1_SA_DQ<12>")
	)
	(gr_poly
		(pts
			(xy 134.949692 -266.737846) (xy 134.949692 -266.693396) (xy 134.594092 -266.693396) (xy 134.594092 -266.737846)
			(xy 134.641082 -266.890246) (xy 134.902702 -266.890246)
		)
		(stroke
			(width 0)
			(type solid)
		)
		(fill yes)
		(layer "In6.Cu")
		(net "M_G_CPU1_SA_DQ<28>")
	)
	(gr_poly
		(pts
			(xy 134.949692 -265.518646) (xy 134.902702 -265.366246) (xy 134.641082 -265.366246) (xy 134.594092 -265.518646)
			(xy 134.594092 -265.563096) (xy 134.949692 -265.563096)
		)
		(stroke
			(width 0)
			(type solid)
		)
		(fill yes)
		(layer "In6.Cu")
		(net "M_G_CPU1_SA_DQ<31>")
	)
	(gr_poly
		(pts
			(xy 134.952994 -279.759664) (xy 134.952994 -279.715468) (xy 134.597394 -279.715468) (xy 134.597394 -279.759664)
			(xy 134.644384 -279.912064) (xy 134.906004 -279.912064)
		)
		(stroke
			(width 0)
			(type solid)
		)
		(fill yes)
		(layer "In6.Cu")
		(net "M_H_CPU1_SA_DQ<0>")
	)
	(gr_poly
		(pts
			(xy 134.952994 -278.540718) (xy 134.906004 -278.388318) (xy 134.644384 -278.388318) (xy 134.597394 -278.540718)
			(xy 134.597394 -278.585168) (xy 134.952994 -278.585168)
		)
		(stroke
			(width 0)
			(type solid)
		)
		(fill yes)
		(layer "In6.Cu")
		(net "M_H_CPU1_SA_DQ<1>")
	)
	(gr_poly
		(pts
			(xy 134.952994 -278.132032) (xy 134.952994 -278.087836) (xy 134.597394 -278.087836) (xy 134.597394 -278.132032)
			(xy 134.644384 -278.284432) (xy 134.906004 -278.284432)
		)
		(stroke
			(width 0)
			(type solid)
		)
		(fill yes)
		(layer "In6.Cu")
		(net "M_H_CPU1_SA_DQS_DP<0>")
	)
	(gr_poly
		(pts
			(xy 134.95655 -275.284946) (xy 134.90956 -275.132546) (xy 134.64794 -275.132546) (xy 134.60095 -275.284946)
			(xy 134.60095 -275.329396) (xy 134.95655 -275.329396)
		)
		(stroke
			(width 0)
			(type solid)
		)
		(fill yes)
		(layer "In6.Cu")
		(net "M_H_CPU1_SA_DQ<7>")
	)
	(gr_poly
		(pts
			(xy 134.95909 -263.891014) (xy 134.9121 -263.738614) (xy 134.65048 -263.738614) (xy 134.60349 -263.891014)
			(xy 134.60349 -263.93521) (xy 134.95909 -263.93521)
		)
		(stroke
			(width 0)
			(type solid)
		)
		(fill yes)
		(layer "In6.Cu")
		(net "M_G_CPU1_SA_CB<3>")
	)
	(gr_poly
		(pts
			(xy 134.95909 -263.482074) (xy 134.95909 -263.437878) (xy 134.60349 -263.437878) (xy 134.60349 -263.482074)
			(xy 134.65048 -263.634474) (xy 134.9121 -263.634474)
		)
		(stroke
			(width 0)
			(type solid)
		)
		(fill yes)
		(layer "In6.Cu")
		(net "M_G_CPU1_SA_DQS_DP<4>")
	)
	(gr_poly
		(pts
			(xy 134.95909 -262.262874) (xy 134.9121 -262.110474) (xy 134.65048 -262.110474) (xy 134.60349 -262.262874)
			(xy 134.60349 -262.307324) (xy 134.95909 -262.307324)
		)
		(stroke
			(width 0)
			(type solid)
		)
		(fill yes)
		(layer "In6.Cu")
		(net "M_G_CPU1_SA_DQS_DP<9>")
	)
	(gr_poly
		(pts
			(xy 134.95909 -261.854442) (xy 134.95909 -261.809992) (xy 134.60349 -261.809992) (xy 134.60349 -261.854442)
			(xy 134.65048 -262.006842) (xy 134.9121 -262.006842)
		)
		(stroke
			(width 0)
			(type solid)
		)
		(fill yes)
		(layer "In6.Cu")
		(net "M_G_CPU1_SA_CB<4>")
	)
	(gr_poly
		(pts
			(xy 134.95909 -260.635242) (xy 134.9121 -260.482842) (xy 134.65048 -260.482842) (xy 134.60349 -260.635242)
			(xy 134.60349 -260.679438) (xy 134.95909 -260.679438)
		)
		(stroke
			(width 0)
			(type solid)
		)
		(fill yes)
		(layer "In6.Cu")
		(net "M_G_CPU1_SA_CB<7>")
	)
	(gr_poly
		(pts
			(xy 134.96163 -276.912578) (xy 134.91464 -276.760178) (xy 134.65302 -276.760178) (xy 134.60603 -276.912578)
			(xy 134.60603 -276.957028) (xy 134.96163 -276.957028)
		)
		(stroke
			(width 0)
			(type solid)
		)
		(fill yes)
		(layer "In6.Cu")
		(net "M_H_CPU1_SA_DQS_DP<5>")
	)
	(gr_poly
		(pts
			(xy 134.96163 -276.5044) (xy 134.96163 -276.460204) (xy 134.60603 -276.460204) (xy 134.60603 -276.5044)
			(xy 134.65302 -276.6568) (xy 134.91464 -276.6568)
		)
		(stroke
			(width 0)
			(type solid)
		)
		(fill yes)
		(layer "In6.Cu")
		(net "M_H_CPU1_SA_DQ<4>")
	)
	(gr_poly
		(pts
			(xy 134.96163 -273.657314) (xy 134.91464 -273.504914) (xy 134.65302 -273.504914) (xy 134.60603 -273.657314)
			(xy 134.60603 -273.70151) (xy 134.96163 -273.70151)
		)
		(stroke
			(width 0)
			(type solid)
		)
		(fill yes)
		(layer "In6.Cu")
		(net "M_G_CPU1_SA_DQ<11>")
	)
	(gr_poly
		(pts
			(xy 134.96163 -273.248882) (xy 134.96163 -273.204686) (xy 134.60603 -273.204686) (xy 134.60603 -273.248882)
			(xy 134.65302 -273.401282) (xy 134.91464 -273.401282)
		)
		(stroke
			(width 0)
			(type solid)
		)
		(fill yes)
		(layer "In6.Cu")
		(net "M_G_CPU1_SA_DQS_DP<1>")
	)
	(gr_poly
		(pts
			(xy 134.96163 -272.029174) (xy 134.91464 -271.876774) (xy 134.65302 -271.876774) (xy 134.60603 -272.029174)
			(xy 134.60603 -272.073624) (xy 134.96163 -272.073624)
		)
		(stroke
			(width 0)
			(type solid)
		)
		(fill yes)
		(layer "In6.Cu")
		(net "M_G_CPU1_SA_DQS_DP<6>")
	)
	(gr_poly
		(pts
			(xy 134.96163 -270.401542) (xy 134.91464 -270.249142) (xy 134.65302 -270.249142) (xy 134.60603 -270.401542)
			(xy 134.60603 -270.445992) (xy 134.96163 -270.445992)
		)
		(stroke
			(width 0)
			(type solid)
		)
		(fill yes)
		(layer "In6.Cu")
		(net "M_G_CPU1_SA_DQ<15>")
	)
	(gr_poly
		(pts
			(xy 134.96163 -269.993618) (xy 134.96163 -269.949168) (xy 134.60603 -269.949168) (xy 134.60603 -269.993618)
			(xy 134.65302 -270.146018) (xy 134.91464 -270.146018)
		)
		(stroke
			(width 0)
			(type solid)
		)
		(fill yes)
		(layer "In6.Cu")
		(net "M_G_CPU1_SA_DQ<24>")
	)
	(gr_poly
		(pts
			(xy 134.96163 -268.77391) (xy 134.91464 -268.62151) (xy 134.65302 -268.62151) (xy 134.60603 -268.77391)
			(xy 134.60603 -268.818106) (xy 134.96163 -268.818106)
		)
		(stroke
			(width 0)
			(type solid)
		)
		(fill yes)
		(layer "In6.Cu")
		(net "M_G_CPU1_SA_DQ<27>")
	)
	(gr_poly
		(pts
			(xy 134.96163 -268.365478) (xy 134.96163 -268.321282) (xy 134.60603 -268.321282) (xy 134.60603 -268.365478)
			(xy 134.65302 -268.517878) (xy 134.91464 -268.517878)
		)
		(stroke
			(width 0)
			(type solid)
		)
		(fill yes)
		(layer "In6.Cu")
		(net "M_G_CPU1_SA_DQS_DP<3>")
	)
	(gr_poly
		(pts
			(xy 134.96163 -267.14577) (xy 134.91464 -266.99337) (xy 134.65302 -266.99337) (xy 134.60603 -267.14577)
			(xy 134.60603 -267.19022) (xy 134.96163 -267.19022)
		)
		(stroke
			(width 0)
			(type solid)
		)
		(fill yes)
		(layer "In6.Cu")
		(net "M_G_CPU1_SA_DQS_DP<8>")
	)
	(gr_poly
		(pts
			(xy 134.96163 -265.110214) (xy 134.96163 -265.065764) (xy 134.60603 -265.065764) (xy 134.60603 -265.110214)
			(xy 134.65302 -265.262614) (xy 134.91464 -265.262614)
		)
		(stroke
			(width 0)
			(type solid)
		)
		(fill yes)
		(layer "In6.Cu")
		(net "M_G_CPU1_SA_CB<0>")
	)
	(gr_poly
		(pts
			(xy 134.962646 -274.876514) (xy 134.962646 -274.832318) (xy 134.607046 -274.832318) (xy 134.607046 -274.876514)
			(xy 134.654036 -275.028914) (xy 134.915656 -275.028914)
		)
		(stroke
			(width 0)
			(type solid)
		)
		(fill yes)
		(layer "In6.Cu")
		(net "M_G_CPU1_SA_DQ<8>")
	)
	(gr_poly
		(pts
			(xy 135.280654 -255.200404) (xy 135.319008 -255.178306) (xy 135.141208 -254.870458) (xy 135.102854 -254.892556)
			(xy 134.994396 -255.009396) (xy 135.125206 -255.235964)
		)
		(stroke
			(width 0)
			(type solid)
		)
		(fill yes)
		(layer "In6.Cu")
		(net "M_H_CPU1_SB_RSP<1>")
	)
	(gr_poly
		(pts
			(xy 135.30707 -244.532658) (xy 135.30707 -244.488208) (xy 134.95147 -244.488208) (xy 134.95147 -244.532658)
			(xy 134.99846 -244.685058) (xy 135.26008 -244.685058)
		)
		(stroke
			(width 0)
			(type solid)
		)
		(fill yes)
		(layer "In6.Cu")
		(net "M_H_CPU1_SB_CS_N<2>")
	)
	(gr_poly
		(pts
			(xy 135.30707 -243.31295) (xy 135.26008 -243.16055) (xy 134.99846 -243.16055) (xy 134.95147 -243.31295)
			(xy 134.95147 -243.3574) (xy 135.30707 -243.3574)
		)
		(stroke
			(width 0)
			(type solid)
		)
		(fill yes)
		(layer "In6.Cu")
		(net "M_H_CPU1_SB_CS_N<1>")
	)
	(gr_poly
		(pts
			(xy 135.30707 -241.685318) (xy 135.26008 -241.532918) (xy 134.99846 -241.532918) (xy 134.95147 -241.685318)
			(xy 134.95147 -241.729514) (xy 135.30707 -241.729514)
		)
		(stroke
			(width 0)
			(type solid)
		)
		(fill yes)
		(layer "In6.Cu")
		(net "M_G_CPU1_SB_DQ<2>")
	)
	(gr_poly
		(pts
			(xy 135.30707 -241.276886) (xy 135.30707 -241.23269) (xy 134.95147 -241.23269) (xy 134.95147 -241.276886)
			(xy 134.99846 -241.429286) (xy 135.26008 -241.429286)
		)
		(stroke
			(width 0)
			(type solid)
		)
		(fill yes)
		(layer "In6.Cu")
		(net "M_G_CPU1_SB_DQ<1>")
	)
	(gr_poly
		(pts
			(xy 135.30707 -239.649254) (xy 135.30707 -239.604804) (xy 134.95147 -239.604804) (xy 134.95147 -239.649254)
			(xy 134.99846 -239.801654) (xy 135.26008 -239.801654)
		)
		(stroke
			(width 0)
			(type solid)
		)
		(fill yes)
		(layer "In6.Cu")
		(net "M_G_CPU1_SB_DQS_DN<5>")
	)
	(gr_poly
		(pts
			(xy 135.30707 -236.801914) (xy 135.26008 -236.649514) (xy 134.99846 -236.649514) (xy 134.95147 -236.801914)
			(xy 134.95147 -236.846364) (xy 135.30707 -236.846364)
		)
		(stroke
			(width 0)
			(type solid)
		)
		(fill yes)
		(layer "In6.Cu")
		(net "M_G_CPU1_SB_DQ<10>")
	)
	(gr_poly
		(pts
			(xy 135.30707 -236.393482) (xy 135.30707 -236.349286) (xy 134.95147 -236.349286) (xy 134.95147 -236.393482)
			(xy 134.99846 -236.545882) (xy 135.26008 -236.545882)
		)
		(stroke
			(width 0)
			(type solid)
		)
		(fill yes)
		(layer "In6.Cu")
		(net "M_G_CPU1_SB_DQ<11>")
	)
	(gr_poly
		(pts
			(xy 135.30707 -228.663246) (xy 135.26008 -228.510846) (xy 134.99846 -228.510846) (xy 134.95147 -228.663246)
			(xy 134.95147 -228.707442) (xy 135.30707 -228.707442)
		)
		(stroke
			(width 0)
			(type solid)
		)
		(fill yes)
		(layer "In6.Cu")
		(net "M_H_CPU1_SB_DQS_DP<7>")
	)
	(gr_poly
		(pts
			(xy 135.30707 -228.254814) (xy 135.30707 -228.210618) (xy 134.95147 -228.210618) (xy 134.95147 -228.254814)
			(xy 134.99846 -228.407214) (xy 135.26008 -228.407214)
		)
		(stroke
			(width 0)
			(type solid)
		)
		(fill yes)
		(layer "In6.Cu")
		(net "M_H_CPU1_SB_DQ<20>")
	)
	(gr_poly
		(pts
			(xy 135.30707 -227.035106) (xy 135.26008 -226.882706) (xy 134.99846 -226.882706) (xy 134.95147 -227.035106)
			(xy 134.95147 -227.079556) (xy 135.30707 -227.079556)
		)
		(stroke
			(width 0)
			(type solid)
		)
		(fill yes)
		(layer "In6.Cu")
		(net "M_H_CPU1_SB_DQ<23>")
	)
	(gr_poly
		(pts
			(xy 135.313166 -248.196354) (xy 135.266176 -248.043954) (xy 135.004556 -248.043954) (xy 134.957566 -248.196354)
			(xy 134.957566 -248.240804) (xy 135.313166 -248.240804)
		)
		(stroke
			(width 0)
			(type solid)
		)
		(fill yes)
		(layer "In6.Cu")
		(net "M_E_CPU1_SB_RSP<1>")
	)
	(gr_poly
		(pts
			(xy 135.313166 -240.057686) (xy 135.266176 -239.905286) (xy 135.004556 -239.905286) (xy 134.957566 -240.057686)
			(xy 134.957566 -240.102136) (xy 135.313166 -240.102136)
		)
		(stroke
			(width 0)
			(type solid)
		)
		(fill yes)
		(layer "In6.Cu")
		(net "M_G_CPU1_SB_DQS_DN<0>")
	)
	(gr_poly
		(pts
			(xy 135.313166 -238.430054) (xy 135.266176 -238.277654) (xy 135.004556 -238.277654) (xy 134.957566 -238.430054)
			(xy 134.957566 -238.47425) (xy 135.313166 -238.47425)
		)
		(stroke
			(width 0)
			(type solid)
		)
		(fill yes)
		(layer "In6.Cu")
		(net "M_G_CPU1_SB_DQ<6>")
	)
	(gr_poly
		(pts
			(xy 135.313166 -238.021114) (xy 135.313166 -237.976918) (xy 134.957566 -237.976918) (xy 134.957566 -238.021114)
			(xy 135.004556 -238.173514) (xy 135.266176 -238.173514)
		)
		(stroke
			(width 0)
			(type solid)
		)
		(fill yes)
		(layer "In6.Cu")
		(net "M_G_CPU1_SB_DQ<5>")
	)
	(gr_poly
		(pts
			(xy 135.313166 -235.174282) (xy 135.266176 -235.021882) (xy 135.004556 -235.021882) (xy 134.957566 -235.174282)
			(xy 134.957566 -235.218732) (xy 135.313166 -235.218732)
		)
		(stroke
			(width 0)
			(type solid)
		)
		(fill yes)
		(layer "In6.Cu")
		(net "M_G_CPU1_SB_DQS_DP<6>")
	)
	(gr_poly
		(pts
			(xy 135.313166 -234.76585) (xy 135.313166 -234.7214) (xy 134.957566 -234.7214) (xy 134.957566 -234.76585)
			(xy 135.004556 -234.91825) (xy 135.266176 -234.91825)
		)
		(stroke
			(width 0)
			(type solid)
		)
		(fill yes)
		(layer "In6.Cu")
		(net "M_G_CPU1_SB_DQS_DP<1>")
	)
	(gr_poly
		(pts
			(xy 135.313166 -233.54665) (xy 135.266176 -233.39425) (xy 135.004556 -233.39425) (xy 134.957566 -233.54665)
			(xy 134.957566 -233.590846) (xy 135.313166 -233.590846)
		)
		(stroke
			(width 0)
			(type solid)
		)
		(fill yes)
		(layer "In6.Cu")
		(net "M_G_CPU1_SB_DQ<12>")
	)
	(gr_poly
		(pts
			(xy 135.313166 -233.13771) (xy 135.313166 -233.093514) (xy 134.957566 -233.093514) (xy 134.957566 -233.13771)
			(xy 135.004556 -233.29011) (xy 135.266176 -233.29011)
		)
		(stroke
			(width 0)
			(type solid)
		)
		(fill yes)
		(layer "In6.Cu")
		(net "M_G_CPU1_SB_DQ<15>")
	)
	(gr_poly
		(pts
			(xy 135.313166 -231.510078) (xy 135.313166 -231.465882) (xy 134.957566 -231.465882) (xy 134.957566 -231.510078)
			(xy 135.004556 -231.662478) (xy 135.266176 -231.662478)
		)
		(stroke
			(width 0)
			(type solid)
		)
		(fill yes)
		(layer "In6.Cu")
		(net "M_H_CPU1_SB_DQ<16>")
	)
	(gr_poly
		(pts
			(xy 135.313166 -230.290878) (xy 135.266176 -230.138478) (xy 135.004556 -230.138478) (xy 134.957566 -230.290878)
			(xy 134.957566 -230.335328) (xy 135.313166 -230.335328)
		)
		(stroke
			(width 0)
			(type solid)
		)
		(fill yes)
		(layer "In6.Cu")
		(net "M_H_CPU1_SB_DQ<19>")
	)
	(gr_poly
		(pts
			(xy 135.313166 -229.882446) (xy 135.313166 -229.837996) (xy 134.957566 -229.837996) (xy 134.957566 -229.882446)
			(xy 135.004556 -230.034846) (xy 135.266176 -230.034846)
		)
		(stroke
			(width 0)
			(type solid)
		)
		(fill yes)
		(layer "In6.Cu")
		(net "M_H_CPU1_SB_DQS_DP<2>")
	)
	(gr_poly
		(pts
			(xy 135.414512 -277.318216) (xy 135.414512 -277.27402) (xy 135.058912 -277.27402) (xy 135.058912 -277.318216)
			(xy 135.105902 -277.470616) (xy 135.367522 -277.470616)
		)
		(stroke
			(width 0)
			(type solid)
		)
		(fill yes)
		(layer "In6.Cu")
		(net "M_H_CPU1_SA_DQS_DN<5>")
	)
	(gr_poly
		(pts
			(xy 135.414512 -276.098762) (xy 135.367522 -275.946362) (xy 135.105902 -275.946362) (xy 135.058912 -276.098762)
			(xy 135.058912 -276.143212) (xy 135.414512 -276.143212)
		)
		(stroke
			(width 0)
			(type solid)
		)
		(fill yes)
		(layer "In6.Cu")
		(net "M_H_CPU1_SA_DQ<6>")
	)
	(gr_poly
		(pts
			(xy 135.414512 -275.690584) (xy 135.414512 -275.646388) (xy 135.058912 -275.646388) (xy 135.058912 -275.690584)
			(xy 135.105902 -275.842984) (xy 135.367522 -275.842984)
		)
		(stroke
			(width 0)
			(type solid)
		)
		(fill yes)
		(layer "In6.Cu")
		(net "M_H_CPU1_SA_DQ<5>")
	)
	(gr_poly
		(pts
			(xy 135.414512 -274.47113) (xy 135.367522 -274.31873) (xy 135.105902 -274.31873) (xy 135.058912 -274.47113)
			(xy 135.058912 -274.515326) (xy 135.414512 -274.515326)
		)
		(stroke
			(width 0)
			(type solid)
		)
		(fill yes)
		(layer "In6.Cu")
		(net "M_G_CPU1_SA_DQ<10>")
	)
	(gr_poly
		(pts
			(xy 135.414512 -274.062698) (xy 135.414512 -274.018502) (xy 135.058912 -274.018502) (xy 135.058912 -274.062698)
			(xy 135.105902 -274.215098) (xy 135.367522 -274.215098)
		)
		(stroke
			(width 0)
			(type solid)
		)
		(fill yes)
		(layer "In6.Cu")
		(net "M_G_CPU1_SA_DQ<9>")
	)
	(gr_poly
		(pts
			(xy 135.414512 -272.843498) (xy 135.367522 -272.691098) (xy 135.105902 -272.691098) (xy 135.058912 -272.843498)
			(xy 135.058912 -272.887694) (xy 135.414512 -272.887694)
		)
		(stroke
			(width 0)
			(type solid)
		)
		(fill yes)
		(layer "In6.Cu")
		(net "M_G_CPU1_SA_DQS_DN<1>")
	)
	(gr_poly
		(pts
			(xy 135.414512 -272.435066) (xy 135.414512 -272.39087) (xy 135.058912 -272.39087) (xy 135.058912 -272.435066)
			(xy 135.105902 -272.587466) (xy 135.367522 -272.587466)
		)
		(stroke
			(width 0)
			(type solid)
		)
		(fill yes)
		(layer "In6.Cu")
		(net "M_G_CPU1_SA_DQS_DN<6>")
	)
	(gr_poly
		(pts
			(xy 135.414512 -270.807434) (xy 135.414512 -270.762984) (xy 135.058912 -270.762984) (xy 135.058912 -270.807434)
			(xy 135.105902 -270.959834) (xy 135.367522 -270.959834)
		)
		(stroke
			(width 0)
			(type solid)
		)
		(fill yes)
		(layer "In6.Cu")
		(net "M_G_CPU1_SA_DQ<13>")
	)
	(gr_poly
		(pts
			(xy 135.414512 -269.587726) (xy 135.367522 -269.435326) (xy 135.105902 -269.435326) (xy 135.058912 -269.587726)
			(xy 135.058912 -269.631922) (xy 135.414512 -269.631922)
		)
		(stroke
			(width 0)
			(type solid)
		)
		(fill yes)
		(layer "In6.Cu")
		(net "M_G_CPU1_SA_DQ<26>")
	)
	(gr_poly
		(pts
			(xy 135.414512 -269.179294) (xy 135.414512 -269.135098) (xy 135.058912 -269.135098) (xy 135.058912 -269.179294)
			(xy 135.105902 -269.331694) (xy 135.367522 -269.331694)
		)
		(stroke
			(width 0)
			(type solid)
		)
		(fill yes)
		(layer "In6.Cu")
		(net "M_G_CPU1_SA_DQ<25>")
	)
	(gr_poly
		(pts
			(xy 135.414512 -267.960094) (xy 135.367522 -267.807694) (xy 135.105902 -267.807694) (xy 135.058912 -267.960094)
			(xy 135.058912 -268.00429) (xy 135.414512 -268.00429)
		)
		(stroke
			(width 0)
			(type solid)
		)
		(fill yes)
		(layer "In6.Cu")
		(net "M_G_CPU1_SA_DQS_DN<3>")
	)
	(gr_poly
		(pts
			(xy 135.414512 -267.551662) (xy 135.414512 -267.507466) (xy 135.058912 -267.507466) (xy 135.058912 -267.551662)
			(xy 135.105902 -267.704062) (xy 135.367522 -267.704062)
		)
		(stroke
			(width 0)
			(type solid)
		)
		(fill yes)
		(layer "In6.Cu")
		(net "M_G_CPU1_SA_DQS_DN<8>")
	)
	(gr_poly
		(pts
			(xy 135.414512 -266.331954) (xy 135.367522 -266.179554) (xy 135.105902 -266.179554) (xy 135.058912 -266.331954)
			(xy 135.058912 -266.376404) (xy 135.414512 -266.376404)
		)
		(stroke
			(width 0)
			(type solid)
		)
		(fill yes)
		(layer "In6.Cu")
		(net "M_G_CPU1_SA_DQ<30>")
	)
	(gr_poly
		(pts
			(xy 135.414512 -265.92403) (xy 135.414512 -265.879834) (xy 135.058912 -265.879834) (xy 135.058912 -265.92403)
			(xy 135.105902 -266.07643) (xy 135.367522 -266.07643)
		)
		(stroke
			(width 0)
			(type solid)
		)
		(fill yes)
		(layer "In6.Cu")
		(net "M_G_CPU1_SA_DQ<29>")
	)
	(gr_poly
		(pts
			(xy 135.414512 -264.704322) (xy 135.367522 -264.551922) (xy 135.105902 -264.551922) (xy 135.058912 -264.704322)
			(xy 135.058912 -264.748772) (xy 135.414512 -264.748772)
		)
		(stroke
			(width 0)
			(type solid)
		)
		(fill yes)
		(layer "In6.Cu")
		(net "M_G_CPU1_SA_CB<2>")
	)
	(gr_poly
		(pts
			(xy 135.416798 -277.726902) (xy 135.369808 -277.574502) (xy 135.108188 -277.574502) (xy 135.061198 -277.726902)
			(xy 135.061198 -277.771098) (xy 135.416798 -277.771098)
		)
		(stroke
			(width 0)
			(type solid)
		)
		(fill yes)
		(layer "In6.Cu")
		(net "M_H_CPU1_SA_DQS_DN<0>")
	)
	(gr_poly
		(pts
			(xy 135.422894 -278.945848) (xy 135.422894 -278.901652) (xy 135.067294 -278.901652) (xy 135.067294 -278.945848)
			(xy 135.114284 -279.098248) (xy 135.375904 -279.098248)
		)
		(stroke
			(width 0)
			(type solid)
		)
		(fill yes)
		(layer "In6.Cu")
		(net "M_H_CPU1_SA_DQ<3>")
	)
	(gr_poly
		(pts
			(xy 135.422894 -264.29589) (xy 135.422894 -264.251694) (xy 135.067294 -264.251694) (xy 135.067294 -264.29589)
			(xy 135.114284 -264.44829) (xy 135.375904 -264.44829)
		)
		(stroke
			(width 0)
			(type solid)
		)
		(fill yes)
		(layer "In6.Cu")
		(net "M_G_CPU1_SA_CB<1>")
	)
	(gr_poly
		(pts
			(xy 135.422894 -263.07669) (xy 135.375904 -262.92429) (xy 135.114284 -262.92429) (xy 135.067294 -263.07669)
			(xy 135.067294 -263.12114) (xy 135.422894 -263.12114)
		)
		(stroke
			(width 0)
			(type solid)
		)
		(fill yes)
		(layer "In6.Cu")
		(net "M_G_CPU1_SA_DQS_DN<4>")
	)
	(gr_poly
		(pts
			(xy 135.422894 -262.668258) (xy 135.422894 -262.623808) (xy 135.067294 -262.623808) (xy 135.067294 -262.668258)
			(xy 135.114284 -262.820658) (xy 135.375904 -262.820658)
		)
		(stroke
			(width 0)
			(type solid)
		)
		(fill yes)
		(layer "In6.Cu")
		(net "M_G_CPU1_SA_DQS_DN<9>")
	)
	(gr_poly
		(pts
			(xy 135.422894 -261.449058) (xy 135.375904 -261.296658) (xy 135.114284 -261.296658) (xy 135.067294 -261.449058)
			(xy 135.067294 -261.493508) (xy 135.422894 -261.493508)
		)
		(stroke
			(width 0)
			(type solid)
		)
		(fill yes)
		(layer "In6.Cu")
		(net "M_G_CPU1_SA_CB<6>")
	)
	(gr_poly
		(pts
			(xy 135.422894 -261.040626) (xy 135.422894 -260.996176) (xy 135.067294 -260.996176) (xy 135.067294 -261.040626)
			(xy 135.114284 -261.193026) (xy 135.375904 -261.193026)
		)
		(stroke
			(width 0)
			(type solid)
		)
		(fill yes)
		(layer "In6.Cu")
		(net "M_G_CPU1_SA_CB<5>")
	)
	(gr_poly
		(pts
			(xy 135.422894 -256.157222) (xy 135.422894 -256.112772) (xy 135.067294 -256.112772) (xy 135.067294 -256.157222)
			(xy 135.114284 -256.309622) (xy 135.375904 -256.309622)
		)
		(stroke
			(width 0)
			(type solid)
		)
		(fill yes)
		(layer "In6.Cu")
		(net "M_H_CPU1_SB_RSP<0>")
	)
	(gr_poly
		(pts
			(xy 135.42518 -271.215866) (xy 135.37819 -271.063466) (xy 135.11657 -271.063466) (xy 135.06958 -271.215866)
			(xy 135.06958 -271.260316) (xy 135.42518 -271.260316)
		)
		(stroke
			(width 0)
			(type solid)
		)
		(fill yes)
		(layer "In6.Cu")
		(net "M_G_CPU1_SA_DQ<14>")
	)
	(gr_poly
		(pts
			(xy 135.431276 -279.354534) (xy 135.384286 -279.202134) (xy 135.122666 -279.202134) (xy 135.075676 -279.354534)
			(xy 135.075676 -279.39873) (xy 135.431276 -279.39873)
		)
		(stroke
			(width 0)
			(type solid)
		)
		(fill yes)
		(layer "In6.Cu")
		(net "M_H_CPU1_SA_DQ<2>")
	)
	(gr_poly
		(pts
			(xy 135.783066 -244.127274) (xy 135.736076 -243.974874) (xy 135.474456 -243.974874) (xy 135.427466 -244.127274)
			(xy 135.427466 -244.17147) (xy 135.783066 -244.17147)
		)
		(stroke
			(width 0)
			(type solid)
		)
		(fill yes)
		(layer "In6.Cu")
		(net "M_H_CPU1_SB_CS_N<3>")
	)
	(gr_poly
		(pts
			(xy 135.783066 -243.718334) (xy 135.783066 -243.674138) (xy 135.427466 -243.674138) (xy 135.427466 -243.718334)
			(xy 135.474456 -243.870734) (xy 135.736076 -243.870734)
		)
		(stroke
			(width 0)
			(type solid)
		)
		(fill yes)
		(layer "In6.Cu")
		(net "M_H_CPU1_SB_CS_N<0>")
	)
	(gr_poly
		(pts
			(xy 135.783066 -242.090702) (xy 135.783066 -242.046252) (xy 135.427466 -242.046252) (xy 135.427466 -242.090702)
			(xy 135.474456 -242.243102) (xy 135.736076 -242.243102)
		)
		(stroke
			(width 0)
			(type solid)
		)
		(fill yes)
		(layer "In6.Cu")
		(net "M_G_CPU1_SB_DQ<0>")
	)
	(gr_poly
		(pts
			(xy 135.783066 -240.871502) (xy 135.736076 -240.719102) (xy 135.474456 -240.719102) (xy 135.427466 -240.871502)
			(xy 135.427466 -240.915952) (xy 135.783066 -240.915952)
		)
		(stroke
			(width 0)
			(type solid)
		)
		(fill yes)
		(layer "In6.Cu")
		(net "M_G_CPU1_SB_DQ<3>")
	)
	(gr_poly
		(pts
			(xy 135.783066 -240.46307) (xy 135.783066 -240.41862) (xy 135.427466 -240.41862) (xy 135.427466 -240.46307)
			(xy 135.474456 -240.61547) (xy 135.736076 -240.61547)
		)
		(stroke
			(width 0)
			(type solid)
		)
		(fill yes)
		(layer "In6.Cu")
		(net "M_G_CPU1_SB_DQS_DP<0>")
	)
	(gr_poly
		(pts
			(xy 135.783066 -239.24387) (xy 135.736076 -239.09147) (xy 135.474456 -239.09147) (xy 135.427466 -239.24387)
			(xy 135.427466 -239.288066) (xy 135.783066 -239.288066)
		)
		(stroke
			(width 0)
			(type solid)
		)
		(fill yes)
		(layer "In6.Cu")
		(net "M_G_CPU1_SB_DQS_DP<5>")
	)
	(gr_poly
		(pts
			(xy 135.783066 -238.83493) (xy 135.783066 -238.790734) (xy 135.427466 -238.790734) (xy 135.427466 -238.83493)
			(xy 135.474456 -238.98733) (xy 135.736076 -238.98733)
		)
		(stroke
			(width 0)
			(type solid)
		)
		(fill yes)
		(layer "In6.Cu")
		(net "M_G_CPU1_SB_DQ<4>")
	)
	(gr_poly
		(pts
			(xy 135.783066 -237.61573) (xy 135.736076 -237.46333) (xy 135.474456 -237.46333) (xy 135.427466 -237.61573)
			(xy 135.427466 -237.66018) (xy 135.783066 -237.66018)
		)
		(stroke
			(width 0)
			(type solid)
		)
		(fill yes)
		(layer "In6.Cu")
		(net "M_G_CPU1_SB_DQ<7>")
	)
	(gr_poly
		(pts
			(xy 135.783066 -235.579666) (xy 135.783066 -235.535216) (xy 135.427466 -235.535216) (xy 135.427466 -235.579666)
			(xy 135.474456 -235.732066) (xy 135.736076 -235.732066)
		)
		(stroke
			(width 0)
			(type solid)
		)
		(fill yes)
		(layer "In6.Cu")
		(net "M_G_CPU1_SB_DQS_DN<6>")
	)
	(gr_poly
		(pts
			(xy 135.783066 -234.360466) (xy 135.736076 -234.208066) (xy 135.474456 -234.208066) (xy 135.427466 -234.360466)
			(xy 135.427466 -234.404916) (xy 135.783066 -234.404916)
		)
		(stroke
			(width 0)
			(type solid)
		)
		(fill yes)
		(layer "In6.Cu")
		(net "M_G_CPU1_SB_DQS_DN<1>")
	)
	(gr_poly
		(pts
			(xy 135.783066 -233.952034) (xy 135.783066 -233.907584) (xy 135.427466 -233.907584) (xy 135.427466 -233.952034)
			(xy 135.474456 -234.104434) (xy 135.736076 -234.104434)
		)
		(stroke
			(width 0)
			(type solid)
		)
		(fill yes)
		(layer "In6.Cu")
		(net "M_G_CPU1_SB_DQ<14>")
	)
	(gr_poly
		(pts
			(xy 135.783066 -232.732834) (xy 135.736076 -232.580434) (xy 135.474456 -232.580434) (xy 135.427466 -232.732834)
			(xy 135.427466 -232.77703) (xy 135.783066 -232.77703)
		)
		(stroke
			(width 0)
			(type solid)
		)
		(fill yes)
		(layer "In6.Cu")
		(net "M_G_CPU1_SB_DQ<13>")
	)
	(gr_poly
		(pts
			(xy 135.783066 -231.104694) (xy 135.736076 -230.952294) (xy 135.474456 -230.952294) (xy 135.427466 -231.104694)
			(xy 135.427466 -231.149144) (xy 135.783066 -231.149144)
		)
		(stroke
			(width 0)
			(type solid)
		)
		(fill yes)
		(layer "In6.Cu")
		(net "M_H_CPU1_SB_DQ<18>")
	)
	(gr_poly
		(pts
			(xy 135.783066 -230.696262) (xy 135.783066 -230.651812) (xy 135.427466 -230.651812) (xy 135.427466 -230.696262)
			(xy 135.474456 -230.848662) (xy 135.736076 -230.848662)
		)
		(stroke
			(width 0)
			(type solid)
		)
		(fill yes)
		(layer "In6.Cu")
		(net "M_H_CPU1_SB_DQ<17>")
	)
	(gr_poly
		(pts
			(xy 135.783066 -229.477062) (xy 135.736076 -229.324662) (xy 135.474456 -229.324662) (xy 135.427466 -229.477062)
			(xy 135.427466 -229.521512) (xy 135.783066 -229.521512)
		)
		(stroke
			(width 0)
			(type solid)
		)
		(fill yes)
		(layer "In6.Cu")
		(net "M_H_CPU1_SB_DQS_DN<2>")
	)
	(gr_poly
		(pts
			(xy 135.783066 -229.06863) (xy 135.783066 -229.02418) (xy 135.427466 -229.02418) (xy 135.427466 -229.06863)
			(xy 135.474456 -229.22103) (xy 135.736076 -229.22103)
		)
		(stroke
			(width 0)
			(type solid)
		)
		(fill yes)
		(layer "In6.Cu")
		(net "M_H_CPU1_SB_DQS_DN<7>")
	)
	(gr_poly
		(pts
			(xy 135.783066 -227.84943) (xy 135.736076 -227.69703) (xy 135.474456 -227.69703) (xy 135.427466 -227.84943)
			(xy 135.427466 -227.893626) (xy 135.783066 -227.893626)
		)
		(stroke
			(width 0)
			(type solid)
		)
		(fill yes)
		(layer "In6.Cu")
		(net "M_H_CPU1_SB_DQ<22>")
	)
	(gr_poly
		(pts
			(xy 135.783066 -227.44049) (xy 135.783066 -227.396294) (xy 135.427466 -227.396294) (xy 135.427466 -227.44049)
			(xy 135.474456 -227.59289) (xy 135.736076 -227.59289)
		)
		(stroke
			(width 0)
			(type solid)
		)
		(fill yes)
		(layer "In6.Cu")
		(net "M_H_CPU1_SB_DQ<21>")
	)
	(gr_poly
		(pts
			(xy 135.791448 -237.207806) (xy 135.791448 -237.163356) (xy 135.435848 -237.163356) (xy 135.435848 -237.207806)
			(xy 135.482838 -237.360206) (xy 135.744458 -237.360206)
		)
		(stroke
			(width 0)
			(type solid)
		)
		(fill yes)
		(layer "In6.Cu")
		(net "M_G_CPU1_SB_DQ<8>")
	)
	(gr_poly
		(pts
			(xy 135.791448 -235.988098) (xy 135.744458 -235.835698) (xy 135.482838 -235.835698) (xy 135.435848 -235.988098)
			(xy 135.435848 -236.032294) (xy 135.791448 -236.032294)
		)
		(stroke
			(width 0)
			(type solid)
		)
		(fill yes)
		(layer "In6.Cu")
		(net "M_G_CPU1_SB_DQ<9>")
	)
	(gr_poly
		(pts
			(xy 135.886698 -279.759918) (xy 135.886698 -279.715722) (xy 135.531098 -279.715722) (xy 135.531098 -279.759918)
			(xy 135.578088 -279.912318) (xy 135.839708 -279.912318)
		)
		(stroke
			(width 0)
			(type solid)
		)
		(fill yes)
		(layer "In6.Cu")
		(net "M_H_CPU1_SA_DQ<0>")
	)
	(gr_poly
		(pts
			(xy 135.89254 -262.262874) (xy 135.84555 -262.110474) (xy 135.58393 -262.110474) (xy 135.53694 -262.262874)
			(xy 135.53694 -262.30707) (xy 135.89254 -262.30707)
		)
		(stroke
			(width 0)
			(type solid)
		)
		(fill yes)
		(layer "In6.Cu")
		(net "M_G_CPU1_SA_DQS_DP<9>")
	)
	(gr_poly
		(pts
			(xy 135.892794 -278.540718) (xy 135.845804 -278.388318) (xy 135.584184 -278.388318) (xy 135.537194 -278.540718)
			(xy 135.537194 -278.585168) (xy 135.892794 -278.585168)
		)
		(stroke
			(width 0)
			(type solid)
		)
		(fill yes)
		(layer "In6.Cu")
		(net "M_H_CPU1_SA_DQ<1>")
	)
	(gr_poly
		(pts
			(xy 135.892794 -263.891014) (xy 135.845804 -263.738614) (xy 135.584184 -263.738614) (xy 135.537194 -263.891014)
			(xy 135.537194 -263.93521) (xy 135.892794 -263.93521)
		)
		(stroke
			(width 0)
			(type solid)
		)
		(fill yes)
		(layer "In6.Cu")
		(net "M_G_CPU1_SA_CB<3>")
	)
	(gr_poly
		(pts
			(xy 135.892794 -263.481566) (xy 135.892794 -263.437116) (xy 135.537194 -263.437116) (xy 135.537194 -263.481566)
			(xy 135.584184 -263.633966) (xy 135.845804 -263.633966)
		)
		(stroke
			(width 0)
			(type solid)
		)
		(fill yes)
		(layer "In6.Cu")
		(net "M_G_CPU1_SA_DQS_DP<4>")
	)
	(gr_poly
		(pts
			(xy 135.892794 -261.854442) (xy 135.892794 -261.809992) (xy 135.537194 -261.809992) (xy 135.537194 -261.854442)
			(xy 135.584184 -262.006842) (xy 135.845804 -262.006842)
		)
		(stroke
			(width 0)
			(type solid)
		)
		(fill yes)
		(layer "In6.Cu")
		(net "M_G_CPU1_SA_CB<4>")
	)
	(gr_poly
		(pts
			(xy 135.892794 -260.635242) (xy 135.845804 -260.482842) (xy 135.584184 -260.482842) (xy 135.537194 -260.635242)
			(xy 135.537194 -260.679438) (xy 135.892794 -260.679438)
		)
		(stroke
			(width 0)
			(type solid)
		)
		(fill yes)
		(layer "In6.Cu")
		(net "M_G_CPU1_SA_CB<7>")
	)
	(gr_poly
		(pts
			(xy 135.892794 -255.751838) (xy 135.845804 -255.599438) (xy 135.584184 -255.599438) (xy 135.537194 -255.751838)
			(xy 135.537194 -255.796288) (xy 135.892794 -255.796288)
		)
		(stroke
			(width 0)
			(type solid)
		)
		(fill yes)
		(layer "In6.Cu")
		(net "M_H_CPU1_SA_RSP<0>")
	)
	(gr_poly
		(pts
			(xy 135.892794 -255.343406) (xy 135.892794 -255.298956) (xy 135.537194 -255.298956) (xy 135.537194 -255.343406)
			(xy 135.584184 -255.495806) (xy 135.845804 -255.495806)
		)
		(stroke
			(width 0)
			(type solid)
		)
		(fill yes)
		(layer "In6.Cu")
		(net "M_H_CPU1_SB_RSP<1>")
	)
	(gr_poly
		(pts
			(xy 135.893048 -271.620742) (xy 135.893048 -271.576546) (xy 135.537448 -271.576546) (xy 135.537448 -271.620742)
			(xy 135.584438 -271.773142) (xy 135.846058 -271.773142)
		)
		(stroke
			(width 0)
			(type solid)
		)
		(fill yes)
		(layer "In6.Cu")
		(net "M_G_CPU1_SA_DQ<12>")
	)
	(gr_poly
		(pts
			(xy 135.89889 -276.504146) (xy 135.89889 -276.45995) (xy 135.54329 -276.45995) (xy 135.54329 -276.504146)
			(xy 135.59028 -276.656546) (xy 135.8519 -276.656546)
		)
		(stroke
			(width 0)
			(type solid)
		)
		(fill yes)
		(layer "In6.Cu")
		(net "M_H_CPU1_SA_DQ<4>")
	)
	(gr_poly
		(pts
			(xy 135.89889 -273.657314) (xy 135.8519 -273.504914) (xy 135.59028 -273.504914) (xy 135.54329 -273.657314)
			(xy 135.54329 -273.701764) (xy 135.89889 -273.701764)
		)
		(stroke
			(width 0)
			(type solid)
		)
		(fill yes)
		(layer "In6.Cu")
		(net "M_G_CPU1_SA_DQ<11>")
	)
	(gr_poly
		(pts
			(xy 135.89889 -273.248882) (xy 135.89889 -273.204432) (xy 135.54329 -273.204432) (xy 135.54329 -273.248882)
			(xy 135.59028 -273.401282) (xy 135.8519 -273.401282)
		)
		(stroke
			(width 0)
			(type solid)
		)
		(fill yes)
		(layer "In6.Cu")
		(net "M_G_CPU1_SA_DQS_DP<1>")
	)
	(gr_poly
		(pts
			(xy 135.89889 -268.77391) (xy 135.8519 -268.62151) (xy 135.59028 -268.62151) (xy 135.54329 -268.77391)
			(xy 135.54329 -268.81836) (xy 135.89889 -268.81836)
		)
		(stroke
			(width 0)
			(type solid)
		)
		(fill yes)
		(layer "In6.Cu")
		(net "M_G_CPU1_SA_DQ<27>")
	)
	(gr_poly
		(pts
			(xy 135.89889 -268.365478) (xy 135.89889 -268.321028) (xy 135.54329 -268.321028) (xy 135.54329 -268.365478)
			(xy 135.59028 -268.517878) (xy 135.8519 -268.517878)
		)
		(stroke
			(width 0)
			(type solid)
		)
		(fill yes)
		(layer "In6.Cu")
		(net "M_G_CPU1_SA_DQS_DP<3>")
	)
	(gr_poly
		(pts
			(xy 135.89889 -267.146278) (xy 135.8519 -266.993878) (xy 135.59028 -266.993878) (xy 135.54329 -267.146278)
			(xy 135.54329 -267.190474) (xy 135.89889 -267.190474)
		)
		(stroke
			(width 0)
			(type solid)
		)
		(fill yes)
		(layer "In6.Cu")
		(net "M_G_CPU1_SA_DQS_DP<8>")
	)
	(gr_poly
		(pts
			(xy 135.89889 -266.737846) (xy 135.89889 -266.693396) (xy 135.54329 -266.693396) (xy 135.54329 -266.737846)
			(xy 135.59028 -266.890246) (xy 135.8519 -266.890246)
		)
		(stroke
			(width 0)
			(type solid)
		)
		(fill yes)
		(layer "In6.Cu")
		(net "M_G_CPU1_SA_DQ<28>")
	)
	(gr_poly
		(pts
			(xy 135.901176 -278.132286) (xy 135.901176 -278.08809) (xy 135.545576 -278.08809) (xy 135.545576 -278.132286)
			(xy 135.592566 -278.284686) (xy 135.854186 -278.284686)
		)
		(stroke
			(width 0)
			(type solid)
		)
		(fill yes)
		(layer "In6.Cu")
		(net "M_H_CPU1_SA_DQS_DP<0>")
	)
	(gr_poly
		(pts
			(xy 135.901176 -276.912578) (xy 135.854186 -276.760178) (xy 135.592566 -276.760178) (xy 135.545576 -276.912578)
			(xy 135.545576 -276.957028) (xy 135.901176 -276.957028)
		)
		(stroke
			(width 0)
			(type solid)
		)
		(fill yes)
		(layer "In6.Cu")
		(net "M_H_CPU1_SA_DQS_DP<5>")
	)
	(gr_poly
		(pts
			(xy 135.90143 -275.284946) (xy 135.85444 -275.132546) (xy 135.59282 -275.132546) (xy 135.54583 -275.284946)
			(xy 135.54583 -275.329396) (xy 135.90143 -275.329396)
		)
		(stroke
			(width 0)
			(type solid)
		)
		(fill yes)
		(layer "In6.Cu")
		(net "M_H_CPU1_SA_DQ<7>")
	)
	(gr_poly
		(pts
			(xy 135.90143 -274.876768) (xy 135.90143 -274.832572) (xy 135.54583 -274.832572) (xy 135.54583 -274.876768)
			(xy 135.59282 -275.029168) (xy 135.85444 -275.029168)
		)
		(stroke
			(width 0)
			(type solid)
		)
		(fill yes)
		(layer "In6.Cu")
		(net "M_G_CPU1_SA_DQ<8>")
	)
	(gr_poly
		(pts
			(xy 135.90143 -272.029174) (xy 135.85444 -271.876774) (xy 135.59282 -271.876774) (xy 135.54583 -272.029174)
			(xy 135.54583 -272.073624) (xy 135.90143 -272.073624)
		)
		(stroke
			(width 0)
			(type solid)
		)
		(fill yes)
		(layer "In6.Cu")
		(net "M_G_CPU1_SA_DQS_DP<6>")
	)
	(gr_poly
		(pts
			(xy 135.90143 -270.401542) (xy 135.85444 -270.249142) (xy 135.59282 -270.249142) (xy 135.54583 -270.401542)
			(xy 135.54583 -270.445992) (xy 135.90143 -270.445992)
		)
		(stroke
			(width 0)
			(type solid)
		)
		(fill yes)
		(layer "In6.Cu")
		(net "M_G_CPU1_SA_DQ<15>")
	)
	(gr_poly
		(pts
			(xy 135.90143 -269.993618) (xy 135.90143 -269.949168) (xy 135.54583 -269.949168) (xy 135.54583 -269.993618)
			(xy 135.59282 -270.146018) (xy 135.85444 -270.146018)
		)
		(stroke
			(width 0)
			(type solid)
		)
		(fill yes)
		(layer "In6.Cu")
		(net "M_G_CPU1_SA_DQ<24>")
	)
	(gr_poly
		(pts
			(xy 135.90143 -265.518138) (xy 135.85444 -265.365738) (xy 135.59282 -265.365738) (xy 135.54583 -265.518138)
			(xy 135.54583 -265.562588) (xy 135.90143 -265.562588)
		)
		(stroke
			(width 0)
			(type solid)
		)
		(fill yes)
		(layer "In6.Cu")
		(net "M_G_CPU1_SA_DQ<31>")
	)
	(gr_poly
		(pts
			(xy 135.90143 -265.110214) (xy 135.90143 -265.065764) (xy 135.54583 -265.065764) (xy 135.54583 -265.110214)
			(xy 135.59282 -265.262614) (xy 135.85444 -265.262614)
		)
		(stroke
			(width 0)
			(type solid)
		)
		(fill yes)
		(layer "In6.Cu")
		(net "M_G_CPU1_SA_CB<0>")
	)
	(gr_poly
		(pts
			(xy 136.24433 -236.801914) (xy 136.19734 -236.649514) (xy 135.93572 -236.649514) (xy 135.88873 -236.801914)
			(xy 135.88873 -236.84611) (xy 136.24433 -236.84611)
		)
		(stroke
			(width 0)
			(type solid)
		)
		(fill yes)
		(layer "In6.Cu")
		(net "M_G_CPU1_SB_DQ<10>")
	)
	(gr_poly
		(pts
			(xy 136.24433 -236.39399) (xy 136.24433 -236.34954) (xy 135.88873 -236.34954) (xy 135.88873 -236.39399)
			(xy 135.93572 -236.54639) (xy 136.19734 -236.54639)
		)
		(stroke
			(width 0)
			(type solid)
		)
		(fill yes)
		(layer "In6.Cu")
		(net "M_G_CPU1_SB_DQ<11>")
	)
	(gr_poly
		(pts
			(xy 136.24687 -244.53215) (xy 136.24687 -244.487954) (xy 135.89127 -244.487954) (xy 135.89127 -244.53215)
			(xy 135.93826 -244.68455) (xy 136.19988 -244.68455)
		)
		(stroke
			(width 0)
			(type solid)
		)
		(fill yes)
		(layer "In6.Cu")
		(net "M_H_CPU1_SB_CS_N<2>")
	)
	(gr_poly
		(pts
			(xy 136.24687 -235.174282) (xy 136.19988 -235.021882) (xy 135.93826 -235.021882) (xy 135.89127 -235.174282)
			(xy 135.89127 -235.218732) (xy 136.24687 -235.218732)
		)
		(stroke
			(width 0)
			(type solid)
		)
		(fill yes)
		(layer "In6.Cu")
		(net "M_G_CPU1_SB_DQS_DP<6>")
	)
	(gr_poly
		(pts
			(xy 136.24687 -234.76585) (xy 136.24687 -234.7214) (xy 135.89127 -234.7214) (xy 135.89127 -234.76585)
			(xy 135.93826 -234.91825) (xy 136.19988 -234.91825)
		)
		(stroke
			(width 0)
			(type solid)
		)
		(fill yes)
		(layer "In6.Cu")
		(net "M_G_CPU1_SB_DQS_DP<1>")
	)
	(gr_poly
		(pts
			(xy 136.249664 -240.057686) (xy 136.202674 -239.905286) (xy 135.941054 -239.905286) (xy 135.894064 -240.057686)
			(xy 135.894064 -240.101882) (xy 136.249664 -240.101882)
		)
		(stroke
			(width 0)
			(type solid)
		)
		(fill yes)
		(layer "In6.Cu")
		(net "M_G_CPU1_SB_DQS_DN<0>")
	)
	(gr_poly
		(pts
			(xy 136.252712 -228.663246) (xy 136.205722 -228.510846) (xy 135.944102 -228.510846) (xy 135.897112 -228.663246)
			(xy 135.897112 -228.707442) (xy 136.252712 -228.707442)
		)
		(stroke
			(width 0)
			(type solid)
		)
		(fill yes)
		(layer "In6.Cu")
		(net "M_H_CPU1_SB_DQS_DP<7>")
	)
	(gr_poly
		(pts
			(xy 136.252966 -243.313458) (xy 136.205976 -243.161058) (xy 135.944356 -243.161058) (xy 135.897366 -243.313458)
			(xy 135.897366 -243.357654) (xy 136.252966 -243.357654)
		)
		(stroke
			(width 0)
			(type solid)
		)
		(fill yes)
		(layer "In6.Cu")
		(net "M_H_CPU1_SB_CS_N<1>")
	)
	(gr_poly
		(pts
			(xy 136.252966 -241.685318) (xy 136.205976 -241.532918) (xy 135.944356 -241.532918) (xy 135.897366 -241.685318)
			(xy 135.897366 -241.729768) (xy 136.252966 -241.729768)
		)
		(stroke
			(width 0)
			(type solid)
		)
		(fill yes)
		(layer "In6.Cu")
		(net "M_G_CPU1_SB_DQ<2>")
	)
	(gr_poly
		(pts
			(xy 136.252966 -241.276886) (xy 136.252966 -241.232436) (xy 135.897366 -241.232436) (xy 135.897366 -241.276886)
			(xy 135.944356 -241.429286) (xy 136.205976 -241.429286)
		)
		(stroke
			(width 0)
			(type solid)
		)
		(fill yes)
		(layer "In6.Cu")
		(net "M_G_CPU1_SB_DQ<1>")
	)
	(gr_poly
		(pts
			(xy 136.252966 -239.648746) (xy 136.252966 -239.604296) (xy 135.897366 -239.604296) (xy 135.897366 -239.648746)
			(xy 135.944356 -239.801146) (xy 136.205976 -239.801146)
		)
		(stroke
			(width 0)
			(type solid)
		)
		(fill yes)
		(layer "In6.Cu")
		(net "M_G_CPU1_SB_DQS_DN<5>")
	)
	(gr_poly
		(pts
			(xy 136.252966 -238.430054) (xy 136.205976 -238.277654) (xy 135.944356 -238.277654) (xy 135.897366 -238.430054)
			(xy 135.897366 -238.47425) (xy 136.252966 -238.47425)
		)
		(stroke
			(width 0)
			(type solid)
		)
		(fill yes)
		(layer "In6.Cu")
		(net "M_G_CPU1_SB_DQ<6>")
	)
	(gr_poly
		(pts
			(xy 136.252966 -238.021114) (xy 136.252966 -237.976918) (xy 135.897366 -237.976918) (xy 135.897366 -238.021114)
			(xy 135.944356 -238.173514) (xy 136.205976 -238.173514)
		)
		(stroke
			(width 0)
			(type solid)
		)
		(fill yes)
		(layer "In6.Cu")
		(net "M_G_CPU1_SB_DQ<5>")
	)
	(gr_poly
		(pts
			(xy 136.252966 -233.54665) (xy 136.205976 -233.39425) (xy 135.944356 -233.39425) (xy 135.897366 -233.54665)
			(xy 135.897366 -233.590846) (xy 136.252966 -233.590846)
		)
		(stroke
			(width 0)
			(type solid)
		)
		(fill yes)
		(layer "In6.Cu")
		(net "M_G_CPU1_SB_DQ<12>")
	)
	(gr_poly
		(pts
			(xy 136.252966 -233.13771) (xy 136.252966 -233.093514) (xy 135.897366 -233.093514) (xy 135.897366 -233.13771)
			(xy 135.944356 -233.29011) (xy 136.205976 -233.29011)
		)
		(stroke
			(width 0)
			(type solid)
		)
		(fill yes)
		(layer "In6.Cu")
		(net "M_G_CPU1_SB_DQ<15>")
	)
	(gr_poly
		(pts
			(xy 136.252966 -231.510078) (xy 136.252966 -231.465882) (xy 135.897366 -231.465882) (xy 135.897366 -231.510078)
			(xy 135.944356 -231.662478) (xy 136.205976 -231.662478)
		)
		(stroke
			(width 0)
			(type solid)
		)
		(fill yes)
		(layer "In6.Cu")
		(net "M_H_CPU1_SB_DQ<16>")
	)
	(gr_poly
		(pts
			(xy 136.252966 -230.290878) (xy 136.205976 -230.138478) (xy 135.944356 -230.138478) (xy 135.897366 -230.290878)
			(xy 135.897366 -230.335328) (xy 136.252966 -230.335328)
		)
		(stroke
			(width 0)
			(type solid)
		)
		(fill yes)
		(layer "In6.Cu")
		(net "M_H_CPU1_SB_DQ<19>")
	)
	(gr_poly
		(pts
			(xy 136.252966 -229.882446) (xy 136.252966 -229.837996) (xy 135.897366 -229.837996) (xy 135.897366 -229.882446)
			(xy 135.944356 -230.034846) (xy 136.205976 -230.034846)
		)
		(stroke
			(width 0)
			(type solid)
		)
		(fill yes)
		(layer "In6.Cu")
		(net "M_H_CPU1_SB_DQS_DP<2>")
	)
	(gr_poly
		(pts
			(xy 136.252966 -228.254814) (xy 136.252966 -228.210364) (xy 135.897366 -228.210364) (xy 135.897366 -228.254814)
			(xy 135.944356 -228.407214) (xy 136.205976 -228.407214)
		)
		(stroke
			(width 0)
			(type solid)
		)
		(fill yes)
		(layer "In6.Cu")
		(net "M_H_CPU1_SB_DQ<20>")
	)
	(gr_poly
		(pts
			(xy 136.252966 -227.035614) (xy 136.205976 -226.883214) (xy 135.944356 -226.883214) (xy 135.897366 -227.035614)
			(xy 135.897366 -227.07981) (xy 136.252966 -227.07981)
		)
		(stroke
			(width 0)
			(type solid)
		)
		(fill yes)
		(layer "In6.Cu")
		(net "M_H_CPU1_SB_DQ<23>")
	)
	(gr_poly
		(pts
			(xy 136.354312 -275.690584) (xy 136.354312 -275.646388) (xy 135.998712 -275.646388) (xy 135.998712 -275.690584)
			(xy 136.045702 -275.842984) (xy 136.307322 -275.842984)
		)
		(stroke
			(width 0)
			(type solid)
		)
		(fill yes)
		(layer "In6.Cu")
		(net "M_H_CPU1_SA_DQ<5>")
	)
	(gr_poly
		(pts
			(xy 136.354312 -274.47113) (xy 136.307322 -274.31873) (xy 136.045702 -274.31873) (xy 135.998712 -274.47113)
			(xy 135.998712 -274.515326) (xy 136.354312 -274.515326)
		)
		(stroke
			(width 0)
			(type solid)
		)
		(fill yes)
		(layer "In6.Cu")
		(net "M_G_CPU1_SA_DQ<10>")
	)
	(gr_poly
		(pts
			(xy 136.354312 -272.435066) (xy 136.354312 -272.39087) (xy 135.998712 -272.39087) (xy 135.998712 -272.435066)
			(xy 136.045702 -272.587466) (xy 136.307322 -272.587466)
		)
		(stroke
			(width 0)
			(type solid)
		)
		(fill yes)
		(layer "In6.Cu")
		(net "M_G_CPU1_SA_DQS_DN<6>")
	)
	(gr_poly
		(pts
			(xy 136.354312 -271.215358) (xy 136.307322 -271.062958) (xy 136.045702 -271.062958) (xy 135.998712 -271.215358)
			(xy 135.998712 -271.259808) (xy 136.354312 -271.259808)
		)
		(stroke
			(width 0)
			(type solid)
		)
		(fill yes)
		(layer "In6.Cu")
		(net "M_G_CPU1_SA_DQ<14>")
	)
	(gr_poly
		(pts
			(xy 136.354312 -270.807434) (xy 136.354312 -270.762984) (xy 135.998712 -270.762984) (xy 135.998712 -270.807434)
			(xy 136.045702 -270.959834) (xy 136.307322 -270.959834)
		)
		(stroke
			(width 0)
			(type solid)
		)
		(fill yes)
		(layer "In6.Cu")
		(net "M_G_CPU1_SA_DQ<13>")
	)
	(gr_poly
		(pts
			(xy 136.354312 -269.587726) (xy 136.307322 -269.435326) (xy 136.045702 -269.435326) (xy 135.998712 -269.587726)
			(xy 135.998712 -269.631922) (xy 136.354312 -269.631922)
		)
		(stroke
			(width 0)
			(type solid)
		)
		(fill yes)
		(layer "In6.Cu")
		(net "M_G_CPU1_SA_DQ<26>")
	)
	(gr_poly
		(pts
			(xy 136.354312 -265.92403) (xy 136.354312 -265.879834) (xy 135.998712 -265.879834) (xy 135.998712 -265.92403)
			(xy 136.045702 -266.07643) (xy 136.307322 -266.07643)
		)
		(stroke
			(width 0)
			(type solid)
		)
		(fill yes)
		(layer "In6.Cu")
		(net "M_G_CPU1_SA_DQ<29>")
	)
	(gr_poly
		(pts
			(xy 136.354312 -264.704322) (xy 136.307322 -264.551922) (xy 136.045702 -264.551922) (xy 135.998712 -264.704322)
			(xy 135.998712 -264.748772) (xy 136.354312 -264.748772)
		)
		(stroke
			(width 0)
			(type solid)
		)
		(fill yes)
		(layer "In6.Cu")
		(net "M_G_CPU1_SA_CB<2>")
	)
	(gr_poly
		(pts
			(xy 136.356598 -277.726394) (xy 136.309608 -277.573994) (xy 136.047988 -277.573994) (xy 136.000998 -277.726394)
			(xy 136.000998 -277.770844) (xy 136.356598 -277.770844)
		)
		(stroke
			(width 0)
			(type solid)
		)
		(fill yes)
		(layer "In6.Cu")
		(net "M_H_CPU1_SA_DQS_DN<0>")
	)
	(gr_poly
		(pts
			(xy 136.356598 -277.318216) (xy 136.356598 -277.27402) (xy 136.000998 -277.27402) (xy 136.000998 -277.318216)
			(xy 136.047988 -277.470616) (xy 136.309608 -277.470616)
		)
		(stroke
			(width 0)
			(type solid)
		)
		(fill yes)
		(layer "In6.Cu")
		(net "M_H_CPU1_SA_DQS_DN<5>")
	)
	(gr_poly
		(pts
			(xy 136.362694 -279.354788) (xy 136.315704 -279.202388) (xy 136.054084 -279.202388) (xy 136.007094 -279.354788)
			(xy 136.007094 -279.398984) (xy 136.362694 -279.398984)
		)
		(stroke
			(width 0)
			(type solid)
		)
		(fill yes)
		(layer "In6.Cu")
		(net "M_H_CPU1_SA_DQ<2>")
	)
	(gr_poly
		(pts
			(xy 136.362694 -278.945848) (xy 136.362694 -278.901652) (xy 136.007094 -278.901652) (xy 136.007094 -278.945848)
			(xy 136.054084 -279.098248) (xy 136.315704 -279.098248)
		)
		(stroke
			(width 0)
			(type solid)
		)
		(fill yes)
		(layer "In6.Cu")
		(net "M_H_CPU1_SA_DQ<3>")
	)
	(gr_poly
		(pts
			(xy 136.362694 -276.09927) (xy 136.315704 -275.94687) (xy 136.054084 -275.94687) (xy 136.007094 -276.09927)
			(xy 136.007094 -276.143466) (xy 136.362694 -276.143466)
		)
		(stroke
			(width 0)
			(type solid)
		)
		(fill yes)
		(layer "In6.Cu")
		(net "M_H_CPU1_SA_DQ<6>")
	)
	(gr_poly
		(pts
			(xy 136.362694 -274.062698) (xy 136.362694 -274.018248) (xy 136.007094 -274.018248) (xy 136.007094 -274.062698)
			(xy 136.054084 -274.215098) (xy 136.315704 -274.215098)
		)
		(stroke
			(width 0)
			(type solid)
		)
		(fill yes)
		(layer "In6.Cu")
		(net "M_G_CPU1_SA_DQ<9>")
	)
	(gr_poly
		(pts
			(xy 136.362694 -272.843498) (xy 136.315704 -272.691098) (xy 136.054084 -272.691098) (xy 136.007094 -272.843498)
			(xy 136.007094 -272.887948) (xy 136.362694 -272.887948)
		)
		(stroke
			(width 0)
			(type solid)
		)
		(fill yes)
		(layer "In6.Cu")
		(net "M_G_CPU1_SA_DQS_DN<1>")
	)
	(gr_poly
		(pts
			(xy 136.362694 -269.179294) (xy 136.362694 -269.134844) (xy 136.007094 -269.134844) (xy 136.007094 -269.179294)
			(xy 136.054084 -269.331694) (xy 136.315704 -269.331694)
		)
		(stroke
			(width 0)
			(type solid)
		)
		(fill yes)
		(layer "In6.Cu")
		(net "M_G_CPU1_SA_DQ<25>")
	)
	(gr_poly
		(pts
			(xy 136.362694 -267.960094) (xy 136.315704 -267.807694) (xy 136.054084 -267.807694) (xy 136.007094 -267.960094)
			(xy 136.007094 -268.004544) (xy 136.362694 -268.004544)
		)
		(stroke
			(width 0)
			(type solid)
		)
		(fill yes)
		(layer "In6.Cu")
		(net "M_G_CPU1_SA_DQS_DN<3>")
	)
	(gr_poly
		(pts
			(xy 136.362694 -267.551662) (xy 136.362694 -267.507212) (xy 136.007094 -267.507212) (xy 136.007094 -267.551662)
			(xy 136.054084 -267.704062) (xy 136.315704 -267.704062)
		)
		(stroke
			(width 0)
			(type solid)
		)
		(fill yes)
		(layer "In6.Cu")
		(net "M_G_CPU1_SA_DQS_DN<8>")
	)
	(gr_poly
		(pts
			(xy 136.362694 -266.332462) (xy 136.315704 -266.180062) (xy 136.054084 -266.180062) (xy 136.007094 -266.332462)
			(xy 136.007094 -266.376658) (xy 136.362694 -266.376658)
		)
		(stroke
			(width 0)
			(type solid)
		)
		(fill yes)
		(layer "In6.Cu")
		(net "M_G_CPU1_SA_DQ<30>")
	)
	(gr_poly
		(pts
			(xy 136.362694 -264.29589) (xy 136.362694 -264.251694) (xy 136.007094 -264.251694) (xy 136.007094 -264.29589)
			(xy 136.054084 -264.44829) (xy 136.315704 -264.44829)
		)
		(stroke
			(width 0)
			(type solid)
		)
		(fill yes)
		(layer "In6.Cu")
		(net "M_G_CPU1_SA_CB<1>")
	)
	(gr_poly
		(pts
			(xy 136.362694 -263.07669) (xy 136.315704 -262.92429) (xy 136.054084 -262.92429) (xy 136.007094 -263.07669)
			(xy 136.007094 -263.12114) (xy 136.362694 -263.12114)
		)
		(stroke
			(width 0)
			(type solid)
		)
		(fill yes)
		(layer "In6.Cu")
		(net "M_G_CPU1_SA_DQS_DN<4>")
	)
	(gr_poly
		(pts
			(xy 136.362694 -262.668258) (xy 136.362694 -262.623808) (xy 136.007094 -262.623808) (xy 136.007094 -262.668258)
			(xy 136.054084 -262.820658) (xy 136.315704 -262.820658)
		)
		(stroke
			(width 0)
			(type solid)
		)
		(fill yes)
		(layer "In6.Cu")
		(net "M_G_CPU1_SA_DQS_DN<9>")
	)
	(gr_poly
		(pts
			(xy 136.362694 -261.449058) (xy 136.315704 -261.296658) (xy 136.054084 -261.296658) (xy 136.007094 -261.449058)
			(xy 136.007094 -261.493508) (xy 136.362694 -261.493508)
		)
		(stroke
			(width 0)
			(type solid)
		)
		(fill yes)
		(layer "In6.Cu")
		(net "M_G_CPU1_SA_CB<6>")
	)
	(gr_poly
		(pts
			(xy 136.362694 -261.040626) (xy 136.362694 -260.996176) (xy 136.007094 -260.996176) (xy 136.007094 -261.040626)
			(xy 136.054084 -261.193026) (xy 136.315704 -261.193026)
		)
		(stroke
			(width 0)
			(type solid)
		)
		(fill yes)
		(layer "In6.Cu")
		(net "M_G_CPU1_SA_CB<5>")
	)
	(gr_poly
		(pts
			(xy 136.362694 -256.157222) (xy 136.362694 -256.112772) (xy 136.007094 -256.112772) (xy 136.007094 -256.157222)
			(xy 136.054084 -256.309622) (xy 136.315704 -256.309622)
		)
		(stroke
			(width 0)
			(type solid)
		)
		(fill yes)
		(layer "In6.Cu")
		(net "M_H_CPU1_SB_RSP<0>")
	)
	(gr_poly
		(pts
			(xy 136.362694 -254.938022) (xy 136.315704 -254.785622) (xy 136.054084 -254.785622) (xy 136.007094 -254.938022)
			(xy 136.007094 -254.982218) (xy 136.362694 -254.982218)
		)
		(stroke
			(width 0)
			(type solid)
		)
		(fill yes)
		(layer "In6.Cu")
		(net "M_H_CPU1_SA_RSP<1>")
	)
	(gr_poly
		(pts
			(xy 136.616948 -232.087674) (xy 136.578594 -232.065576) (xy 136.423146 -232.030016) (xy 136.292336 -232.256584)
			(xy 136.400794 -232.373424) (xy 136.439148 -232.395522)
		)
		(stroke
			(width 0)
			(type solid)
		)
		(fill yes)
		(layer "In6.Cu")
		(net "M_G_CPU1_SB_DQ<13>")
	)
	(gr_poly
		(pts
			(xy 136.690354 -280.430986) (xy 136.728708 -280.408888) (xy 136.550908 -280.10104) (xy 136.512554 -280.123138)
			(xy 136.404096 -280.239978) (xy 136.534906 -280.466546)
		)
		(stroke
			(width 0)
			(type solid)
		)
		(fill yes)
		(layer "In6.Cu")
		(net "M_H_CPU1_SA_DQ<0>")
	)
	(gr_poly
		(pts
			(xy 136.722866 -243.718334) (xy 136.722866 -243.674138) (xy 136.367266 -243.674138) (xy 136.367266 -243.718334)
			(xy 136.414256 -243.870734) (xy 136.675876 -243.870734)
		)
		(stroke
			(width 0)
			(type solid)
		)
		(fill yes)
		(layer "In6.Cu")
		(net "M_H_CPU1_SB_CS_N<0>")
	)
	(gr_poly
		(pts
			(xy 136.722866 -242.090702) (xy 136.722866 -242.046252) (xy 136.367266 -242.046252) (xy 136.367266 -242.090702)
			(xy 136.414256 -242.243102) (xy 136.675876 -242.243102)
		)
		(stroke
			(width 0)
			(type solid)
		)
		(fill yes)
		(layer "In6.Cu")
		(net "M_G_CPU1_SB_DQ<0>")
	)
	(gr_poly
		(pts
			(xy 136.722866 -240.871502) (xy 136.675876 -240.719102) (xy 136.414256 -240.719102) (xy 136.367266 -240.871502)
			(xy 136.367266 -240.915952) (xy 136.722866 -240.915952)
		)
		(stroke
			(width 0)
			(type solid)
		)
		(fill yes)
		(layer "In6.Cu")
		(net "M_G_CPU1_SB_DQ<3>")
	)
	(gr_poly
		(pts
			(xy 136.722866 -238.83493) (xy 136.722866 -238.790734) (xy 136.367266 -238.790734) (xy 136.367266 -238.83493)
			(xy 136.414256 -238.98733) (xy 136.675876 -238.98733)
		)
		(stroke
			(width 0)
			(type solid)
		)
		(fill yes)
		(layer "In6.Cu")
		(net "M_G_CPU1_SB_DQ<4>")
	)
	(gr_poly
		(pts
			(xy 136.722866 -237.61573) (xy 136.675876 -237.46333) (xy 136.414256 -237.46333) (xy 136.367266 -237.61573)
			(xy 136.367266 -237.66018) (xy 136.722866 -237.66018)
		)
		(stroke
			(width 0)
			(type solid)
		)
		(fill yes)
		(layer "In6.Cu")
		(net "M_G_CPU1_SB_DQ<7>")
	)
	(gr_poly
		(pts
			(xy 136.722866 -233.952034) (xy 136.722866 -233.907584) (xy 136.367266 -233.907584) (xy 136.367266 -233.952034)
			(xy 136.414256 -234.104434) (xy 136.675876 -234.104434)
		)
		(stroke
			(width 0)
			(type solid)
		)
		(fill yes)
		(layer "In6.Cu")
		(net "M_G_CPU1_SB_DQ<14>")
	)
	(gr_poly
		(pts
			(xy 136.722866 -231.104694) (xy 136.675876 -230.952294) (xy 136.414256 -230.952294) (xy 136.367266 -231.104694)
			(xy 136.367266 -231.149144) (xy 136.722866 -231.149144)
		)
		(stroke
			(width 0)
			(type solid)
		)
		(fill yes)
		(layer "In6.Cu")
		(net "M_H_CPU1_SB_DQ<18>")
	)
	(gr_poly
		(pts
			(xy 136.722866 -230.696262) (xy 136.722866 -230.651812) (xy 136.367266 -230.651812) (xy 136.367266 -230.696262)
			(xy 136.414256 -230.848662) (xy 136.675876 -230.848662)
		)
		(stroke
			(width 0)
			(type solid)
		)
		(fill yes)
		(layer "In6.Cu")
		(net "M_H_CPU1_SB_DQ<17>")
	)
	(gr_poly
		(pts
			(xy 136.722866 -229.477062) (xy 136.675876 -229.324662) (xy 136.414256 -229.324662) (xy 136.367266 -229.477062)
			(xy 136.367266 -229.521512) (xy 136.722866 -229.521512)
		)
		(stroke
			(width 0)
			(type solid)
		)
		(fill yes)
		(layer "In6.Cu")
		(net "M_H_CPU1_SB_DQS_DN<2>")
	)
	(gr_poly
		(pts
			(xy 136.722866 -229.06863) (xy 136.722866 -229.02418) (xy 136.367266 -229.02418) (xy 136.367266 -229.06863)
			(xy 136.414256 -229.22103) (xy 136.675876 -229.22103)
		)
		(stroke
			(width 0)
			(type solid)
		)
		(fill yes)
		(layer "In6.Cu")
		(net "M_H_CPU1_SB_DQS_DN<7>")
	)
	(gr_poly
		(pts
			(xy 136.722866 -227.84943) (xy 136.675876 -227.69703) (xy 136.414256 -227.69703) (xy 136.367266 -227.84943)
			(xy 136.367266 -227.893626) (xy 136.722866 -227.893626)
		)
		(stroke
			(width 0)
			(type solid)
		)
		(fill yes)
		(layer "In6.Cu")
		(net "M_H_CPU1_SB_DQ<22>")
	)
	(gr_poly
		(pts
			(xy 136.722866 -227.44049) (xy 136.722866 -227.396294) (xy 136.367266 -227.396294) (xy 136.367266 -227.44049)
			(xy 136.414256 -227.59289) (xy 136.675876 -227.59289)
		)
		(stroke
			(width 0)
			(type solid)
		)
		(fill yes)
		(layer "In6.Cu")
		(net "M_H_CPU1_SB_DQ<21>")
	)
	(gr_poly
		(pts
			(xy 136.725406 -216.454736) (xy 136.678416 -216.302336) (xy 136.416796 -216.302336) (xy 136.369806 -216.454736)
			(xy 136.369806 -216.498932) (xy 136.725406 -216.498932)
		)
		(stroke
			(width 0)
			(type solid)
		)
		(fill yes)
		(layer "In6.Cu")
		(net "M_G_CPU1_SB_DQ<29>")
	)
	(gr_poly
		(pts
			(xy 136.731248 -240.46307) (xy 136.731248 -240.418874) (xy 136.375648 -240.418874) (xy 136.375648 -240.46307)
			(xy 136.422638 -240.61547) (xy 136.684258 -240.61547)
		)
		(stroke
			(width 0)
			(type solid)
		)
		(fill yes)
		(layer "In6.Cu")
		(net "M_G_CPU1_SB_DQS_DP<0>")
	)
	(gr_poly
		(pts
			(xy 136.731248 -239.243362) (xy 136.684258 -239.090962) (xy 136.422638 -239.090962) (xy 136.375648 -239.243362)
			(xy 136.375648 -239.287812) (xy 136.731248 -239.287812)
		)
		(stroke
			(width 0)
			(type solid)
		)
		(fill yes)
		(layer "In6.Cu")
		(net "M_G_CPU1_SB_DQS_DP<5>")
	)
	(gr_poly
		(pts
			(xy 136.731248 -237.207806) (xy 136.731248 -237.163356) (xy 136.375648 -237.163356) (xy 136.375648 -237.207806)
			(xy 136.422638 -237.360206) (xy 136.684258 -237.360206)
		)
		(stroke
			(width 0)
			(type solid)
		)
		(fill yes)
		(layer "In6.Cu")
		(net "M_G_CPU1_SB_DQ<8>")
	)
	(gr_poly
		(pts
			(xy 136.731248 -235.988098) (xy 136.684258 -235.835698) (xy 136.422638 -235.835698) (xy 136.375648 -235.988098)
			(xy 136.375648 -236.032294) (xy 136.731248 -236.032294)
		)
		(stroke
			(width 0)
			(type solid)
		)
		(fill yes)
		(layer "In6.Cu")
		(net "M_G_CPU1_SB_DQ<9>")
	)
	(gr_poly
		(pts
			(xy 136.731248 -235.579666) (xy 136.731248 -235.53547) (xy 136.375648 -235.53547) (xy 136.375648 -235.579666)
			(xy 136.422638 -235.732066) (xy 136.684258 -235.732066)
		)
		(stroke
			(width 0)
			(type solid)
		)
		(fill yes)
		(layer "In6.Cu")
		(net "M_G_CPU1_SB_DQS_DN<6>")
	)
	(gr_poly
		(pts
			(xy 136.731248 -234.360466) (xy 136.684258 -234.208066) (xy 136.422638 -234.208066) (xy 136.375648 -234.360466)
			(xy 136.375648 -234.404662) (xy 136.731248 -234.404662)
		)
		(stroke
			(width 0)
			(type solid)
		)
		(fill yes)
		(layer "In6.Cu")
		(net "M_G_CPU1_SB_DQS_DN<1>")
	)
	(gr_poly
		(pts
			(xy 136.797796 -232.800144) (xy 136.689338 -232.683304) (xy 136.650984 -232.661206) (xy 136.473184 -232.969054)
			(xy 136.511538 -232.991152) (xy 136.666986 -233.026712)
		)
		(stroke
			(width 0)
			(type solid)
		)
		(fill yes)
		(layer "In6.Cu")
		(net "M_G_CPU1_SB_DQ<15>")
	)
	(gr_poly
		(pts
			(xy 136.799066 -279.809194) (xy 136.907524 -279.692354) (xy 136.776714 -279.465786) (xy 136.621266 -279.501346)
			(xy 136.582912 -279.523444) (xy 136.760712 -279.831292)
		)
		(stroke
			(width 0)
			(type solid)
		)
		(fill yes)
		(layer "In6.Cu")
		(net "M_H_CPU1_SA_DQ<2>")
	)
	(gr_poly
		(pts
			(xy 136.826498 -268.77391) (xy 136.779508 -268.62151) (xy 136.517888 -268.62151) (xy 136.470898 -268.77391)
			(xy 136.470898 -268.81836) (xy 136.826498 -268.81836)
		)
		(stroke
			(width 0)
			(type solid)
		)
		(fill yes)
		(layer "In6.Cu")
		(net "M_G_CPU1_SA_DQ<27>")
	)
	(gr_poly
		(pts
			(xy 136.826498 -268.365478) (xy 136.826498 -268.321028) (xy 136.470898 -268.321028) (xy 136.470898 -268.365478)
			(xy 136.517888 -268.517878) (xy 136.779508 -268.517878)
		)
		(stroke
			(width 0)
			(type solid)
		)
		(fill yes)
		(layer "In6.Cu")
		(net "M_G_CPU1_SA_DQS_DP<3>")
	)
	(gr_poly
		(pts
			(xy 136.826498 -267.146278) (xy 136.779508 -266.993878) (xy 136.517888 -266.993878) (xy 136.470898 -267.146278)
			(xy 136.470898 -267.190474) (xy 136.826498 -267.190474)
		)
		(stroke
			(width 0)
			(type solid)
		)
		(fill yes)
		(layer "In6.Cu")
		(net "M_G_CPU1_SA_DQS_DP<8>")
	)
	(gr_poly
		(pts
			(xy 136.826498 -266.737846) (xy 136.826498 -266.693396) (xy 136.470898 -266.693396) (xy 136.470898 -266.737846)
			(xy 136.517888 -266.890246) (xy 136.779508 -266.890246)
		)
		(stroke
			(width 0)
			(type solid)
		)
		(fill yes)
		(layer "In6.Cu")
		(net "M_G_CPU1_SA_DQ<28>")
	)
	(gr_poly
		(pts
			(xy 136.827514 -255.343406) (xy 136.827514 -255.298956) (xy 136.471914 -255.298956) (xy 136.471914 -255.343406)
			(xy 136.518904 -255.495806) (xy 136.780524 -255.495806)
		)
		(stroke
			(width 0)
			(type solid)
		)
		(fill yes)
		(layer "In6.Cu")
		(net "M_H_CPU1_SB_RSP<1>")
	)
	(gr_poly
		(pts
			(xy 136.83234 -262.262874) (xy 136.78535 -262.110474) (xy 136.52373 -262.110474) (xy 136.47674 -262.262874)
			(xy 136.47674 -262.30707) (xy 136.83234 -262.30707)
		)
		(stroke
			(width 0)
			(type solid)
		)
		(fill yes)
		(layer "In6.Cu")
		(net "M_G_CPU1_SA_DQS_DP<9>")
	)
	(gr_poly
		(pts
			(xy 136.832594 -278.540718) (xy 136.785604 -278.388318) (xy 136.523984 -278.388318) (xy 136.476994 -278.540718)
			(xy 136.476994 -278.585168) (xy 136.832594 -278.585168)
		)
		(stroke
			(width 0)
			(type solid)
		)
		(fill yes)
		(layer "In6.Cu")
		(net "M_H_CPU1_SA_DQ<1>")
	)
	(gr_poly
		(pts
			(xy 136.832594 -278.132032) (xy 136.832594 -278.087836) (xy 136.476994 -278.087836) (xy 136.476994 -278.132032)
			(xy 136.523984 -278.284432) (xy 136.785604 -278.284432)
		)
		(stroke
			(width 0)
			(type solid)
		)
		(fill yes)
		(layer "In6.Cu")
		(net "M_H_CPU1_SA_DQS_DP<0>")
	)
	(gr_poly
		(pts
			(xy 136.832594 -276.913086) (xy 136.785604 -276.760686) (xy 136.523984 -276.760686) (xy 136.476994 -276.913086)
			(xy 136.476994 -276.957282) (xy 136.832594 -276.957282)
		)
		(stroke
			(width 0)
			(type solid)
		)
		(fill yes)
		(layer "In6.Cu")
		(net "M_H_CPU1_SA_DQS_DP<5>")
	)
	(gr_poly
		(pts
			(xy 136.832594 -276.504146) (xy 136.832594 -276.45995) (xy 136.476994 -276.45995) (xy 136.476994 -276.504146)
			(xy 136.523984 -276.656546) (xy 136.785604 -276.656546)
		)
		(stroke
			(width 0)
			(type solid)
		)
		(fill yes)
		(layer "In6.Cu")
		(net "M_H_CPU1_SA_DQ<4>")
	)
	(gr_poly
		(pts
			(xy 136.832594 -273.657314) (xy 136.785604 -273.504914) (xy 136.523984 -273.504914) (xy 136.476994 -273.657314)
			(xy 136.476994 -273.701764) (xy 136.832594 -273.701764)
		)
		(stroke
			(width 0)
			(type solid)
		)
		(fill yes)
		(layer "In6.Cu")
		(net "M_G_CPU1_SA_DQ<11>")
	)
	(gr_poly
		(pts
			(xy 136.832594 -273.248882) (xy 136.832594 -273.204432) (xy 136.476994 -273.204432) (xy 136.476994 -273.248882)
			(xy 136.523984 -273.401282) (xy 136.785604 -273.401282)
		)
		(stroke
			(width 0)
			(type solid)
		)
		(fill yes)
		(layer "In6.Cu")
		(net "M_G_CPU1_SA_DQS_DP<1>")
	)
	(gr_poly
		(pts
			(xy 136.832594 -263.891014) (xy 136.785604 -263.738614) (xy 136.523984 -263.738614) (xy 136.476994 -263.891014)
			(xy 136.476994 -263.93521) (xy 136.832594 -263.93521)
		)
		(stroke
			(width 0)
			(type solid)
		)
		(fill yes)
		(layer "In6.Cu")
		(net "M_G_CPU1_SA_CB<3>")
	)
	(gr_poly
		(pts
			(xy 136.832594 -263.482074) (xy 136.832594 -263.437878) (xy 136.476994 -263.437878) (xy 136.476994 -263.482074)
			(xy 136.523984 -263.634474) (xy 136.785604 -263.634474)
		)
		(stroke
			(width 0)
			(type solid)
		)
		(fill yes)
		(layer "In6.Cu")
		(net "M_G_CPU1_SA_DQS_DP<4>")
	)
	(gr_poly
		(pts
			(xy 136.832594 -261.854442) (xy 136.832594 -261.809992) (xy 136.476994 -261.809992) (xy 136.476994 -261.854442)
			(xy 136.523984 -262.006842) (xy 136.785604 -262.006842)
		)
		(stroke
			(width 0)
			(type solid)
		)
		(fill yes)
		(layer "In6.Cu")
		(net "M_G_CPU1_SA_CB<4>")
	)
	(gr_poly
		(pts
			(xy 136.832594 -260.635242) (xy 136.785604 -260.482842) (xy 136.523984 -260.482842) (xy 136.476994 -260.635242)
			(xy 136.476994 -260.679438) (xy 136.832594 -260.679438)
		)
		(stroke
			(width 0)
			(type solid)
		)
		(fill yes)
		(layer "In6.Cu")
		(net "M_G_CPU1_SA_CB<7>")
	)
	(gr_poly
		(pts
			(xy 136.84123 -275.284946) (xy 136.79424 -275.132546) (xy 136.53262 -275.132546) (xy 136.48563 -275.284946)
			(xy 136.48563 -275.329396) (xy 136.84123 -275.329396)
		)
		(stroke
			(width 0)
			(type solid)
		)
		(fill yes)
		(layer "In6.Cu")
		(net "M_H_CPU1_SA_DQ<7>")
	)
	(gr_poly
		(pts
			(xy 136.84123 -274.876768) (xy 136.84123 -274.832572) (xy 136.48563 -274.832572) (xy 136.48563 -274.876768)
			(xy 136.53262 -275.029168) (xy 136.79424 -275.029168)
		)
		(stroke
			(width 0)
			(type solid)
		)
		(fill yes)
		(layer "In6.Cu")
		(net "M_G_CPU1_SA_DQ<8>")
	)
	(gr_poly
		(pts
			(xy 136.84123 -272.029174) (xy 136.79424 -271.876774) (xy 136.53262 -271.876774) (xy 136.48563 -272.029174)
			(xy 136.48563 -272.073624) (xy 136.84123 -272.073624)
		)
		(stroke
			(width 0)
			(type solid)
		)
		(fill yes)
		(layer "In6.Cu")
		(net "M_G_CPU1_SA_DQS_DP<6>")
	)
	(gr_poly
		(pts
			(xy 136.84123 -271.62125) (xy 136.84123 -271.5768) (xy 136.48563 -271.5768) (xy 136.48563 -271.62125)
			(xy 136.53262 -271.77365) (xy 136.79424 -271.77365)
		)
		(stroke
			(width 0)
			(type solid)
		)
		(fill yes)
		(layer "In6.Cu")
		(net "M_G_CPU1_SA_DQ<12>")
	)
	(gr_poly
		(pts
			(xy 136.84123 -270.401542) (xy 136.79424 -270.249142) (xy 136.53262 -270.249142) (xy 136.48563 -270.401542)
			(xy 136.48563 -270.445992) (xy 136.84123 -270.445992)
		)
		(stroke
			(width 0)
			(type solid)
		)
		(fill yes)
		(layer "In6.Cu")
		(net "M_G_CPU1_SA_DQ<15>")
	)
	(gr_poly
		(pts
			(xy 136.84123 -269.993618) (xy 136.84123 -269.949168) (xy 136.48563 -269.949168) (xy 136.48563 -269.993618)
			(xy 136.53262 -270.146018) (xy 136.79424 -270.146018)
		)
		(stroke
			(width 0)
			(type solid)
		)
		(fill yes)
		(layer "In6.Cu")
		(net "M_G_CPU1_SA_DQ<24>")
	)
	(gr_poly
		(pts
			(xy 136.84123 -265.518138) (xy 136.79424 -265.365738) (xy 136.53262 -265.365738) (xy 136.48563 -265.518138)
			(xy 136.48563 -265.562588) (xy 136.84123 -265.562588)
		)
		(stroke
			(width 0)
			(type solid)
		)
		(fill yes)
		(layer "In6.Cu")
		(net "M_G_CPU1_SA_DQ<31>")
	)
	(gr_poly
		(pts
			(xy 136.84123 -265.110214) (xy 136.84123 -265.065764) (xy 136.48563 -265.065764) (xy 136.48563 -265.110214)
			(xy 136.53262 -265.262614) (xy 136.79424 -265.262614)
		)
		(stroke
			(width 0)
			(type solid)
		)
		(fill yes)
		(layer "In6.Cu")
		(net "M_G_CPU1_SA_CB<0>")
	)
	(gr_poly
		(pts
			(xy 136.842754 -255.75133) (xy 136.795764 -255.59893) (xy 136.534144 -255.59893) (xy 136.487154 -255.75133)
			(xy 136.487154 -255.79578) (xy 136.842754 -255.79578)
		)
		(stroke
			(width 0)
			(type solid)
		)
		(fill yes)
		(layer "In6.Cu")
		(net "M_H_CPU1_SA_RSP<0>")
	)
	(gr_poly
		(pts
			(xy 137.086848 -232.90149) (xy 137.048494 -232.879392) (xy 136.893046 -232.843832) (xy 136.762236 -233.0704)
			(xy 136.870694 -233.18724) (xy 136.909048 -233.209338)
		)
		(stroke
			(width 0)
			(type solid)
		)
		(fill yes)
		(layer "In6.Cu")
		(net "M_G_CPU1_SB_DQ<12>")
	)
	(gr_poly
		(pts
			(xy 137.158222 -281.240992) (xy 137.196576 -281.218894) (xy 137.018776 -280.911046) (xy 136.980422 -280.933144)
			(xy 136.871964 -281.049984) (xy 137.002774 -281.276552)
		)
		(stroke
			(width 0)
			(type solid)
		)
		(fill yes)
		(layer "In6.Cu")
		(net "M_H_CPU1_SA_DQ<0>")
	)
	(gr_poly
		(pts
			(xy 137.158222 -279.613106) (xy 137.196576 -279.591008) (xy 137.018776 -279.28316) (xy 136.980422 -279.305258)
			(xy 136.871964 -279.422098) (xy 137.002774 -279.648666)
		)
		(stroke
			(width 0)
			(type solid)
		)
		(fill yes)
		(layer "In6.Cu")
		(net "M_H_CPU1_SA_DQ<3>")
	)
	(gr_poly
		(pts
			(xy 137.18413 -240.057178) (xy 137.13714 -239.904778) (xy 136.87552 -239.904778) (xy 136.82853 -240.057178)
			(xy 136.82853 -240.101628) (xy 137.18413 -240.101628)
		)
		(stroke
			(width 0)
			(type solid)
		)
		(fill yes)
		(layer "In6.Cu")
		(net "M_G_CPU1_SB_DQS_DN<0>")
	)
	(gr_poly
		(pts
			(xy 137.18413 -239.649254) (xy 137.18413 -239.604804) (xy 136.82853 -239.604804) (xy 136.82853 -239.649254)
			(xy 136.87552 -239.801654) (xy 137.13714 -239.801654)
		)
		(stroke
			(width 0)
			(type solid)
		)
		(fill yes)
		(layer "In6.Cu")
		(net "M_G_CPU1_SB_DQS_DN<5>")
	)
	(gr_poly
		(pts
			(xy 137.18413 -236.801914) (xy 137.13714 -236.649514) (xy 136.87552 -236.649514) (xy 136.82853 -236.801914)
			(xy 136.82853 -236.84611) (xy 137.18413 -236.84611)
		)
		(stroke
			(width 0)
			(type solid)
		)
		(fill yes)
		(layer "In6.Cu")
		(net "M_G_CPU1_SB_DQ<10>")
	)
	(gr_poly
		(pts
			(xy 137.18413 -236.39399) (xy 137.18413 -236.34954) (xy 136.82853 -236.34954) (xy 136.82853 -236.39399)
			(xy 136.87552 -236.54639) (xy 137.13714 -236.54639)
		)
		(stroke
			(width 0)
			(type solid)
		)
		(fill yes)
		(layer "In6.Cu")
		(net "M_G_CPU1_SB_DQ<11>")
	)
	(gr_poly
		(pts
			(xy 137.18413 -235.174282) (xy 137.13714 -235.021882) (xy 136.87552 -235.021882) (xy 136.82853 -235.174282)
			(xy 136.82853 -235.218478) (xy 137.18413 -235.218478)
		)
		(stroke
			(width 0)
			(type solid)
		)
		(fill yes)
		(layer "In6.Cu")
		(net "M_G_CPU1_SB_DQS_DP<6>")
	)
	(gr_poly
		(pts
			(xy 137.18413 -234.76585) (xy 137.18413 -234.721654) (xy 136.82853 -234.721654) (xy 136.82853 -234.76585)
			(xy 136.87552 -234.91825) (xy 137.13714 -234.91825)
		)
		(stroke
			(width 0)
			(type solid)
		)
		(fill yes)
		(layer "In6.Cu")
		(net "M_G_CPU1_SB_DQS_DP<1>")
	)
	(gr_poly
		(pts
			(xy 137.192766 -241.685318) (xy 137.145776 -241.532918) (xy 136.884156 -241.532918) (xy 136.837166 -241.685318)
			(xy 136.837166 -241.729768) (xy 137.192766 -241.729768)
		)
		(stroke
			(width 0)
			(type solid)
		)
		(fill yes)
		(layer "In6.Cu")
		(net "M_G_CPU1_SB_DQ<2>")
	)
	(gr_poly
		(pts
			(xy 137.192766 -241.276886) (xy 137.192766 -241.232436) (xy 136.837166 -241.232436) (xy 136.837166 -241.276886)
			(xy 136.884156 -241.429286) (xy 137.145776 -241.429286)
		)
		(stroke
			(width 0)
			(type solid)
		)
		(fill yes)
		(layer "In6.Cu")
		(net "M_G_CPU1_SB_DQ<1>")
	)
	(gr_poly
		(pts
			(xy 137.192766 -238.430054) (xy 137.145776 -238.277654) (xy 136.884156 -238.277654) (xy 136.837166 -238.430054)
			(xy 136.837166 -238.47425) (xy 137.192766 -238.47425)
		)
		(stroke
			(width 0)
			(type solid)
		)
		(fill yes)
		(layer "In6.Cu")
		(net "M_G_CPU1_SB_DQ<6>")
	)
	(gr_poly
		(pts
			(xy 137.192766 -238.021114) (xy 137.192766 -237.976918) (xy 136.837166 -237.976918) (xy 136.837166 -238.021114)
			(xy 136.884156 -238.173514) (xy 137.145776 -238.173514)
		)
		(stroke
			(width 0)
			(type solid)
		)
		(fill yes)
		(layer "In6.Cu")
		(net "M_G_CPU1_SB_DQ<5>")
	)
	(gr_poly
		(pts
			(xy 137.192766 -231.919018) (xy 137.145776 -231.766618) (xy 136.884156 -231.766618) (xy 136.837166 -231.919018)
			(xy 136.837166 -231.963214) (xy 137.192766 -231.963214)
		)
		(stroke
			(width 0)
			(type solid)
		)
		(fill yes)
		(layer "In6.Cu")
		(net "M_G_CPU1_SB_DQ<13>")
	)
	(gr_poly
		(pts
			(xy 137.192766 -231.510078) (xy 137.192766 -231.465882) (xy 136.837166 -231.465882) (xy 136.837166 -231.510078)
			(xy 136.884156 -231.662478) (xy 137.145776 -231.662478)
		)
		(stroke
			(width 0)
			(type solid)
		)
		(fill yes)
		(layer "In6.Cu")
		(net "M_H_CPU1_SB_DQ<16>")
	)
	(gr_poly
		(pts
			(xy 137.192766 -230.290878) (xy 137.145776 -230.138478) (xy 136.884156 -230.138478) (xy 136.837166 -230.290878)
			(xy 136.837166 -230.335328) (xy 137.192766 -230.335328)
		)
		(stroke
			(width 0)
			(type solid)
		)
		(fill yes)
		(layer "In6.Cu")
		(net "M_H_CPU1_SB_DQ<19>")
	)
	(gr_poly
		(pts
			(xy 137.192766 -229.882446) (xy 137.192766 -229.837996) (xy 136.837166 -229.837996) (xy 136.837166 -229.882446)
			(xy 136.884156 -230.034846) (xy 137.145776 -230.034846)
		)
		(stroke
			(width 0)
			(type solid)
		)
		(fill yes)
		(layer "In6.Cu")
		(net "M_H_CPU1_SB_DQS_DP<2>")
	)
	(gr_poly
		(pts
			(xy 137.192766 -228.663754) (xy 137.145776 -228.511354) (xy 136.884156 -228.511354) (xy 136.837166 -228.663754)
			(xy 136.837166 -228.70795) (xy 137.192766 -228.70795)
		)
		(stroke
			(width 0)
			(type solid)
		)
		(fill yes)
		(layer "In6.Cu")
		(net "M_H_CPU1_SB_DQS_DP<7>")
	)
	(gr_poly
		(pts
			(xy 137.192766 -228.254814) (xy 137.192766 -228.210364) (xy 136.837166 -228.210364) (xy 136.837166 -228.254814)
			(xy 136.884156 -228.407214) (xy 137.145776 -228.407214)
		)
		(stroke
			(width 0)
			(type solid)
		)
		(fill yes)
		(layer "In6.Cu")
		(net "M_H_CPU1_SB_DQ<20>")
	)
	(gr_poly
		(pts
			(xy 137.265664 -233.618024) (xy 137.157206 -233.501184) (xy 137.118852 -233.479086) (xy 136.941052 -233.786934)
			(xy 136.979406 -233.809032) (xy 137.134854 -233.844592)
		)
		(stroke
			(width 0)
			(type solid)
		)
		(fill yes)
		(layer "In6.Cu")
		(net "M_G_CPU1_SB_DQ<14>")
	)
	(gr_poly
		(pts
			(xy 137.266934 -280.6192) (xy 137.375392 -280.50236) (xy 137.244582 -280.275792) (xy 137.089134 -280.311352)
			(xy 137.05078 -280.33345) (xy 137.22858 -280.641298)
		)
		(stroke
			(width 0)
			(type solid)
		)
		(fill yes)
		(layer "In6.Cu")
		(net "M_H_CPU1_SA_DQ<2>")
	)
	(gr_poly
		(pts
			(xy 137.268966 -278.995378) (xy 137.377424 -278.878538) (xy 137.246614 -278.65197) (xy 137.091166 -278.68753)
			(xy 137.052812 -278.709628) (xy 137.230612 -279.017476)
		)
		(stroke
			(width 0)
			(type solid)
		)
		(fill yes)
		(layer "In6.Cu")
		(net "M_H_CPU1_SA_DQ<1>")
	)
	(gr_poly
		(pts
			(xy 137.294112 -275.690584) (xy 137.294112 -275.646388) (xy 136.938512 -275.646388) (xy 136.938512 -275.690584)
			(xy 136.985502 -275.842984) (xy 137.247122 -275.842984)
		)
		(stroke
			(width 0)
			(type solid)
		)
		(fill yes)
		(layer "In6.Cu")
		(net "M_H_CPU1_SA_DQ<5>")
	)
	(gr_poly
		(pts
			(xy 137.294112 -274.47113) (xy 137.247122 -274.31873) (xy 136.985502 -274.31873) (xy 136.938512 -274.47113)
			(xy 136.938512 -274.515326) (xy 137.294112 -274.515326)
		)
		(stroke
			(width 0)
			(type solid)
		)
		(fill yes)
		(layer "In6.Cu")
		(net "M_G_CPU1_SA_DQ<10>")
	)
	(gr_poly
		(pts
			(xy 137.294112 -272.435066) (xy 137.294112 -272.39087) (xy 136.938512 -272.39087) (xy 136.938512 -272.435066)
			(xy 136.985502 -272.587466) (xy 137.247122 -272.587466)
		)
		(stroke
			(width 0)
			(type solid)
		)
		(fill yes)
		(layer "In6.Cu")
		(net "M_G_CPU1_SA_DQS_DN<6>")
	)
	(gr_poly
		(pts
			(xy 137.294112 -271.215358) (xy 137.247122 -271.062958) (xy 136.985502 -271.062958) (xy 136.938512 -271.215358)
			(xy 136.938512 -271.259808) (xy 137.294112 -271.259808)
		)
		(stroke
			(width 0)
			(type solid)
		)
		(fill yes)
		(layer "In6.Cu")
		(net "M_G_CPU1_SA_DQ<14>")
	)
	(gr_poly
		(pts
			(xy 137.294112 -270.807434) (xy 137.294112 -270.762984) (xy 136.938512 -270.762984) (xy 136.938512 -270.807434)
			(xy 136.985502 -270.959834) (xy 137.247122 -270.959834)
		)
		(stroke
			(width 0)
			(type solid)
		)
		(fill yes)
		(layer "In6.Cu")
		(net "M_G_CPU1_SA_DQ<13>")
	)
	(gr_poly
		(pts
			(xy 137.294112 -269.587726) (xy 137.247122 -269.435326) (xy 136.985502 -269.435326) (xy 136.938512 -269.587726)
			(xy 136.938512 -269.631922) (xy 137.294112 -269.631922)
		)
		(stroke
			(width 0)
			(type solid)
		)
		(fill yes)
		(layer "In6.Cu")
		(net "M_G_CPU1_SA_DQ<26>")
	)
	(gr_poly
		(pts
			(xy 137.294112 -265.92403) (xy 137.294112 -265.879834) (xy 136.938512 -265.879834) (xy 136.938512 -265.92403)
			(xy 136.985502 -266.07643) (xy 137.247122 -266.07643)
		)
		(stroke
			(width 0)
			(type solid)
		)
		(fill yes)
		(layer "In6.Cu")
		(net "M_G_CPU1_SA_DQ<29>")
	)
	(gr_poly
		(pts
			(xy 137.294112 -264.704322) (xy 137.247122 -264.551922) (xy 136.985502 -264.551922) (xy 136.938512 -264.704322)
			(xy 136.938512 -264.748772) (xy 137.294112 -264.748772)
		)
		(stroke
			(width 0)
			(type solid)
		)
		(fill yes)
		(layer "In6.Cu")
		(net "M_G_CPU1_SA_CB<2>")
	)
	(gr_poly
		(pts
			(xy 137.294112 -256.157222) (xy 137.294112 -256.113026) (xy 136.938512 -256.113026) (xy 136.938512 -256.157222)
			(xy 136.985502 -256.309622) (xy 137.247122 -256.309622)
		)
		(stroke
			(width 0)
			(type solid)
		)
		(fill yes)
		(layer "In6.Cu")
		(net "M_H_CPU1_SB_RSP<0>")
	)
	(gr_poly
		(pts
			(xy 137.294112 -254.937514) (xy 137.247122 -254.785114) (xy 136.985502 -254.785114) (xy 136.938512 -254.937514)
			(xy 136.938512 -254.981964) (xy 137.294112 -254.981964)
		)
		(stroke
			(width 0)
			(type solid)
		)
		(fill yes)
		(layer "In6.Cu")
		(net "M_H_CPU1_SA_RSP<1>")
	)
	(gr_poly
		(pts
			(xy 137.30224 -269.179294) (xy 137.30224 -269.134844) (xy 136.94664 -269.134844) (xy 136.94664 -269.179294)
			(xy 136.99363 -269.331694) (xy 137.25525 -269.331694)
		)
		(stroke
			(width 0)
			(type solid)
		)
		(fill yes)
		(layer "In6.Cu")
		(net "M_G_CPU1_SA_DQ<25>")
	)
	(gr_poly
		(pts
			(xy 137.302494 -277.726902) (xy 137.255504 -277.574502) (xy 136.993884 -277.574502) (xy 136.946894 -277.726902)
			(xy 136.946894 -277.771098) (xy 137.302494 -277.771098)
		)
		(stroke
			(width 0)
			(type solid)
		)
		(fill yes)
		(layer "In6.Cu")
		(net "M_H_CPU1_SA_DQS_DN<0>")
	)
	(gr_poly
		(pts
			(xy 137.302494 -277.317962) (xy 137.302494 -277.273766) (xy 136.946894 -277.273766) (xy 136.946894 -277.317962)
			(xy 136.993884 -277.470362) (xy 137.255504 -277.470362)
		)
		(stroke
			(width 0)
			(type solid)
		)
		(fill yes)
		(layer "In6.Cu")
		(net "M_H_CPU1_SA_DQS_DN<5>")
	)
	(gr_poly
		(pts
			(xy 137.302494 -276.09927) (xy 137.255504 -275.94687) (xy 136.993884 -275.94687) (xy 136.946894 -276.09927)
			(xy 136.946894 -276.143466) (xy 137.302494 -276.143466)
		)
		(stroke
			(width 0)
			(type solid)
		)
		(fill yes)
		(layer "In6.Cu")
		(net "M_H_CPU1_SA_DQ<6>")
	)
	(gr_poly
		(pts
			(xy 137.302494 -274.062698) (xy 137.302494 -274.018248) (xy 136.946894 -274.018248) (xy 136.946894 -274.062698)
			(xy 136.993884 -274.215098) (xy 137.255504 -274.215098)
		)
		(stroke
			(width 0)
			(type solid)
		)
		(fill yes)
		(layer "In6.Cu")
		(net "M_G_CPU1_SA_DQ<9>")
	)
	(gr_poly
		(pts
			(xy 137.302494 -272.843498) (xy 137.255504 -272.691098) (xy 136.993884 -272.691098) (xy 136.946894 -272.843498)
			(xy 136.946894 -272.887948) (xy 137.302494 -272.887948)
		)
		(stroke
			(width 0)
			(type solid)
		)
		(fill yes)
		(layer "In6.Cu")
		(net "M_G_CPU1_SA_DQS_DN<1>")
	)
	(gr_poly
		(pts
			(xy 137.302494 -264.29589) (xy 137.302494 -264.251694) (xy 136.946894 -264.251694) (xy 136.946894 -264.29589)
			(xy 136.993884 -264.44829) (xy 137.255504 -264.44829)
		)
		(stroke
			(width 0)
			(type solid)
		)
		(fill yes)
		(layer "In6.Cu")
		(net "M_G_CPU1_SA_CB<1>")
	)
	(gr_poly
		(pts
			(xy 137.302494 -263.07669) (xy 137.255504 -262.92429) (xy 136.993884 -262.92429) (xy 136.946894 -263.07669)
			(xy 136.946894 -263.12114) (xy 137.302494 -263.12114)
		)
		(stroke
			(width 0)
			(type solid)
		)
		(fill yes)
		(layer "In6.Cu")
		(net "M_G_CPU1_SA_DQS_DN<4>")
	)
	(gr_poly
		(pts
			(xy 137.302494 -262.668258) (xy 137.302494 -262.623808) (xy 136.946894 -262.623808) (xy 136.946894 -262.668258)
			(xy 136.993884 -262.820658) (xy 137.255504 -262.820658)
		)
		(stroke
			(width 0)
			(type solid)
		)
		(fill yes)
		(layer "In6.Cu")
		(net "M_G_CPU1_SA_DQS_DN<9>")
	)
	(gr_poly
		(pts
			(xy 137.302494 -261.449058) (xy 137.255504 -261.296658) (xy 136.993884 -261.296658) (xy 136.946894 -261.449058)
			(xy 136.946894 -261.493508) (xy 137.302494 -261.493508)
		)
		(stroke
			(width 0)
			(type solid)
		)
		(fill yes)
		(layer "In6.Cu")
		(net "M_G_CPU1_SA_CB<6>")
	)
	(gr_poly
		(pts
			(xy 137.302494 -261.040626) (xy 137.302494 -260.996176) (xy 136.946894 -260.996176) (xy 136.946894 -261.040626)
			(xy 136.993884 -261.193026) (xy 137.255504 -261.193026)
		)
		(stroke
			(width 0)
			(type solid)
		)
		(fill yes)
		(layer "In6.Cu")
		(net "M_G_CPU1_SA_CB<5>")
	)
	(gr_poly
		(pts
			(xy 137.308336 -266.332462) (xy 137.261346 -266.180062) (xy 136.999726 -266.180062) (xy 136.952736 -266.332462)
			(xy 136.952736 -266.376658) (xy 137.308336 -266.376658)
		)
		(stroke
			(width 0)
			(type solid)
		)
		(fill yes)
		(layer "In6.Cu")
		(net "M_G_CPU1_SA_DQ<30>")
	)
	(gr_poly
		(pts
			(xy 137.310876 -267.960094) (xy 137.263886 -267.807694) (xy 137.002266 -267.807694) (xy 136.955276 -267.960094)
			(xy 136.955276 -268.00429) (xy 137.310876 -268.00429)
		)
		(stroke
			(width 0)
			(type solid)
		)
		(fill yes)
		(layer "In6.Cu")
		(net "M_G_CPU1_SA_DQS_DN<3>")
	)
	(gr_poly
		(pts
			(xy 137.310876 -267.551662) (xy 137.310876 -267.507466) (xy 136.955276 -267.507466) (xy 136.955276 -267.551662)
			(xy 137.002266 -267.704062) (xy 137.263886 -267.704062)
		)
		(stroke
			(width 0)
			(type solid)
		)
		(fill yes)
		(layer "In6.Cu")
		(net "M_G_CPU1_SA_DQS_DN<8>")
	)
	(gr_poly
		(pts
			(xy 137.55878 -233.711496) (xy 137.520426 -233.689398) (xy 137.364978 -233.653838) (xy 137.234168 -233.880406)
			(xy 137.342626 -233.997246) (xy 137.38098 -234.019344)
		)
		(stroke
			(width 0)
			(type solid)
		)
		(fill yes)
		(layer "In6.Cu")
		(net "M_G_CPU1_SB_DQS_DN<1>")
	)
	(gr_poly
		(pts
			(xy 137.628122 -278.79929) (xy 137.666476 -278.777192) (xy 137.488676 -278.469344) (xy 137.450322 -278.491442)
			(xy 137.341864 -278.608282) (xy 137.472674 -278.83485)
		)
		(stroke
			(width 0)
			(type solid)
		)
		(fill yes)
		(layer "In6.Cu")
		(net "M_H_CPU1_SA_DQS_DP<0>")
	)
	(gr_poly
		(pts
			(xy 137.630154 -280.430986) (xy 137.668508 -280.408888) (xy 137.490708 -280.10104) (xy 137.452354 -280.123138)
			(xy 137.343896 -280.239978) (xy 137.474706 -280.466546)
		)
		(stroke
			(width 0)
			(type solid)
		)
		(fill yes)
		(layer "In6.Cu")
		(net "M_H_CPU1_SA_DQ<3>")
	)
	(gr_poly
		(pts
			(xy 137.662666 -242.090702) (xy 137.662666 -242.046252) (xy 137.307066 -242.046252) (xy 137.307066 -242.090702)
			(xy 137.354056 -242.243102) (xy 137.615676 -242.243102)
		)
		(stroke
			(width 0)
			(type solid)
		)
		(fill yes)
		(layer "In6.Cu")
		(net "M_G_CPU1_SB_DQ<0>")
	)
	(gr_poly
		(pts
			(xy 137.662666 -240.871502) (xy 137.615676 -240.719102) (xy 137.354056 -240.719102) (xy 137.307066 -240.871502)
			(xy 137.307066 -240.915952) (xy 137.662666 -240.915952)
		)
		(stroke
			(width 0)
			(type solid)
		)
		(fill yes)
		(layer "In6.Cu")
		(net "M_G_CPU1_SB_DQ<3>")
	)
	(gr_poly
		(pts
			(xy 137.662666 -238.83493) (xy 137.662666 -238.790734) (xy 137.307066 -238.790734) (xy 137.307066 -238.83493)
			(xy 137.354056 -238.98733) (xy 137.615676 -238.98733)
		)
		(stroke
			(width 0)
			(type solid)
		)
		(fill yes)
		(layer "In6.Cu")
		(net "M_G_CPU1_SB_DQ<4>")
	)
	(gr_poly
		(pts
			(xy 137.662666 -237.61573) (xy 137.615676 -237.46333) (xy 137.354056 -237.46333) (xy 137.307066 -237.61573)
			(xy 137.307066 -237.66018) (xy 137.662666 -237.66018)
		)
		(stroke
			(width 0)
			(type solid)
		)
		(fill yes)
		(layer "In6.Cu")
		(net "M_G_CPU1_SB_DQ<7>")
	)
	(gr_poly
		(pts
			(xy 137.662666 -232.732834) (xy 137.615676 -232.580434) (xy 137.354056 -232.580434) (xy 137.307066 -232.732834)
			(xy 137.307066 -232.77703) (xy 137.662666 -232.77703)
		)
		(stroke
			(width 0)
			(type solid)
		)
		(fill yes)
		(layer "In6.Cu")
		(net "M_G_CPU1_SB_DQ<12>")
	)
	(gr_poly
		(pts
			(xy 137.662666 -232.323894) (xy 137.662666 -232.279698) (xy 137.307066 -232.279698) (xy 137.307066 -232.323894)
			(xy 137.354056 -232.476294) (xy 137.615676 -232.476294)
		)
		(stroke
			(width 0)
			(type solid)
		)
		(fill yes)
		(layer "In6.Cu")
		(net "M_G_CPU1_SB_DQ<15>")
	)
	(gr_poly
		(pts
			(xy 137.662666 -231.104694) (xy 137.615676 -230.952294) (xy 137.354056 -230.952294) (xy 137.307066 -231.104694)
			(xy 137.307066 -231.149144) (xy 137.662666 -231.149144)
		)
		(stroke
			(width 0)
			(type solid)
		)
		(fill yes)
		(layer "In6.Cu")
		(net "M_H_CPU1_SB_DQ<18>")
	)
	(gr_poly
		(pts
			(xy 137.662666 -230.696262) (xy 137.662666 -230.651812) (xy 137.307066 -230.651812) (xy 137.307066 -230.696262)
			(xy 137.354056 -230.848662) (xy 137.615676 -230.848662)
		)
		(stroke
			(width 0)
			(type solid)
		)
		(fill yes)
		(layer "In6.Cu")
		(net "M_H_CPU1_SB_DQ<17>")
	)
	(gr_poly
		(pts
			(xy 137.671048 -240.46307) (xy 137.671048 -240.418874) (xy 137.315448 -240.418874) (xy 137.315448 -240.46307)
			(xy 137.362438 -240.61547) (xy 137.624058 -240.61547)
		)
		(stroke
			(width 0)
			(type solid)
		)
		(fill yes)
		(layer "In6.Cu")
		(net "M_G_CPU1_SB_DQS_DP<0>")
	)
	(gr_poly
		(pts
			(xy 137.671048 -239.243362) (xy 137.624058 -239.090962) (xy 137.362438 -239.090962) (xy 137.315448 -239.243362)
			(xy 137.315448 -239.287812) (xy 137.671048 -239.287812)
		)
		(stroke
			(width 0)
			(type solid)
		)
		(fill yes)
		(layer "In6.Cu")
		(net "M_G_CPU1_SB_DQS_DP<5>")
	)
	(gr_poly
		(pts
			(xy 137.671048 -237.207806) (xy 137.671048 -237.163356) (xy 137.315448 -237.163356) (xy 137.315448 -237.207806)
			(xy 137.362438 -237.360206) (xy 137.624058 -237.360206)
		)
		(stroke
			(width 0)
			(type solid)
		)
		(fill yes)
		(layer "In6.Cu")
		(net "M_G_CPU1_SB_DQ<8>")
	)
	(gr_poly
		(pts
			(xy 137.671048 -235.988098) (xy 137.624058 -235.835698) (xy 137.362438 -235.835698) (xy 137.315448 -235.988098)
			(xy 137.315448 -236.032294) (xy 137.671048 -236.032294)
		)
		(stroke
			(width 0)
			(type solid)
		)
		(fill yes)
		(layer "In6.Cu")
		(net "M_G_CPU1_SB_DQ<9>")
	)
	(gr_poly
		(pts
			(xy 137.671048 -235.579666) (xy 137.671048 -235.53547) (xy 137.315448 -235.53547) (xy 137.315448 -235.579666)
			(xy 137.362438 -235.732066) (xy 137.624058 -235.732066)
		)
		(stroke
			(width 0)
			(type solid)
		)
		(fill yes)
		(layer "In6.Cu")
		(net "M_G_CPU1_SB_DQS_DN<6>")
	)
	(gr_poly
		(pts
			(xy 137.736834 -278.177498) (xy 137.845292 -278.060658) (xy 137.714482 -277.83409) (xy 137.559034 -277.86965)
			(xy 137.52068 -277.891748) (xy 137.69848 -278.199596)
		)
		(stroke
			(width 0)
			(type solid)
		)
		(fill yes)
		(layer "In6.Cu")
		(net "M_H_CPU1_SA_DQS_DN<0>")
	)
	(gr_poly
		(pts
			(xy 137.738866 -279.809194) (xy 137.847324 -279.692354) (xy 137.716514 -279.465786) (xy 137.561066 -279.501346)
			(xy 137.522712 -279.523444) (xy 137.700512 -279.831292)
		)
		(stroke
			(width 0)
			(type solid)
		)
		(fill yes)
		(layer "In6.Cu")
		(net "M_H_CPU1_SA_DQ<1>")
	)
	(gr_poly
		(pts
			(xy 137.741914 -234.420918) (xy 137.633456 -234.304078) (xy 137.595102 -234.28198) (xy 137.417302 -234.589828)
			(xy 137.455656 -234.611926) (xy 137.611104 -234.647486)
		)
		(stroke
			(width 0)
			(type solid)
		)
		(fill yes)
		(layer "In6.Cu")
		(net "M_G_CPU1_SB_DQS_DP<1>")
	)
	(gr_poly
		(pts
			(xy 137.763758 -268.365478) (xy 137.763758 -268.321282) (xy 137.408158 -268.321282) (xy 137.408158 -268.365478)
			(xy 137.455148 -268.517878) (xy 137.716768 -268.517878)
		)
		(stroke
			(width 0)
			(type solid)
		)
		(fill yes)
		(layer "In6.Cu")
		(net "M_G_CPU1_SA_DQS_DP<3>")
	)
	(gr_poly
		(pts
			(xy 137.763758 -267.14577) (xy 137.716768 -266.99337) (xy 137.455148 -266.99337) (xy 137.408158 -267.14577)
			(xy 137.408158 -267.19022) (xy 137.763758 -267.19022)
		)
		(stroke
			(width 0)
			(type solid)
		)
		(fill yes)
		(layer "In6.Cu")
		(net "M_G_CPU1_SA_DQS_DP<8>")
	)
	(gr_poly
		(pts
			(xy 137.766044 -266.737846) (xy 137.766044 -266.693396) (xy 137.410444 -266.693396) (xy 137.410444 -266.737846)
			(xy 137.457434 -266.890246) (xy 137.719054 -266.890246)
		)
		(stroke
			(width 0)
			(type solid)
		)
		(fill yes)
		(layer "In6.Cu")
		(net "M_G_CPU1_SA_DQ<28>")
	)
	(gr_poly
		(pts
			(xy 137.766298 -273.248882) (xy 137.766298 -273.204432) (xy 137.410698 -273.204432) (xy 137.410698 -273.248882)
			(xy 137.457688 -273.401282) (xy 137.719308 -273.401282)
		)
		(stroke
			(width 0)
			(type solid)
		)
		(fill yes)
		(layer "In6.Cu")
		(net "M_G_CPU1_SA_DQS_DP<1>")
	)
	(gr_poly
		(pts
			(xy 137.772394 -281.38755) (xy 137.772394 -281.343354) (xy 137.416794 -281.343354) (xy 137.416794 -281.38755)
			(xy 137.463784 -281.53995) (xy 137.725404 -281.53995)
		)
		(stroke
			(width 0)
			(type solid)
		)
		(fill yes)
		(layer "In6.Cu")
		(net "M_H_CPU1_SA_DQ<0>")
	)
	(gr_poly
		(pts
			(xy 137.772394 -276.913086) (xy 137.725404 -276.760686) (xy 137.463784 -276.760686) (xy 137.416794 -276.913086)
			(xy 137.416794 -276.957282) (xy 137.772394 -276.957282)
		)
		(stroke
			(width 0)
			(type solid)
		)
		(fill yes)
		(layer "In6.Cu")
		(net "M_H_CPU1_SA_DQS_DP<5>")
	)
	(gr_poly
		(pts
			(xy 137.772394 -276.504146) (xy 137.772394 -276.45995) (xy 137.416794 -276.45995) (xy 137.416794 -276.504146)
			(xy 137.463784 -276.656546) (xy 137.725404 -276.656546)
		)
		(stroke
			(width 0)
			(type solid)
		)
		(fill yes)
		(layer "In6.Cu")
		(net "M_H_CPU1_SA_DQ<4>")
	)
	(gr_poly
		(pts
			(xy 137.772394 -273.657314) (xy 137.725404 -273.504914) (xy 137.463784 -273.504914) (xy 137.416794 -273.657314)
			(xy 137.416794 -273.701764) (xy 137.772394 -273.701764)
		)
		(stroke
			(width 0)
			(type solid)
		)
		(fill yes)
		(layer "In6.Cu")
		(net "M_G_CPU1_SA_DQ<11>")
	)
	(gr_poly
		(pts
			(xy 137.772394 -263.482074) (xy 137.772394 -263.437878) (xy 137.416794 -263.437878) (xy 137.416794 -263.482074)
			(xy 137.463784 -263.634474) (xy 137.725404 -263.634474)
		)
		(stroke
			(width 0)
			(type solid)
		)
		(fill yes)
		(layer "In6.Cu")
		(net "M_G_CPU1_SA_DQS_DP<4>")
	)
	(gr_poly
		(pts
			(xy 137.772394 -262.262874) (xy 137.725404 -262.110474) (xy 137.463784 -262.110474) (xy 137.416794 -262.262874)
			(xy 137.416794 -262.307324) (xy 137.772394 -262.307324)
		)
		(stroke
			(width 0)
			(type solid)
		)
		(fill yes)
		(layer "In6.Cu")
		(net "M_G_CPU1_SA_DQS_DP<9>")
	)
	(gr_poly
		(pts
			(xy 137.772394 -261.854442) (xy 137.772394 -261.809992) (xy 137.416794 -261.809992) (xy 137.416794 -261.854442)
			(xy 137.463784 -262.006842) (xy 137.725404 -262.006842)
		)
		(stroke
			(width 0)
			(type solid)
		)
		(fill yes)
		(layer "In6.Cu")
		(net "M_G_CPU1_SA_CB<4>")
	)
	(gr_poly
		(pts
			(xy 137.772394 -260.635242) (xy 137.725404 -260.482842) (xy 137.463784 -260.482842) (xy 137.416794 -260.635242)
			(xy 137.416794 -260.679438) (xy 137.772394 -260.679438)
		)
		(stroke
			(width 0)
			(type solid)
		)
		(fill yes)
		(layer "In6.Cu")
		(net "M_G_CPU1_SA_CB<7>")
	)
	(gr_poly
		(pts
			(xy 137.777982 -268.77391) (xy 137.730992 -268.62151) (xy 137.469372 -268.62151) (xy 137.422382 -268.77391)
			(xy 137.422382 -268.81836) (xy 137.777982 -268.81836)
		)
		(stroke
			(width 0)
			(type solid)
		)
		(fill yes)
		(layer "In6.Cu")
		(net "M_G_CPU1_SA_DQ<27>")
	)
	(gr_poly
		(pts
			(xy 137.77849 -263.890506) (xy 137.7315 -263.738106) (xy 137.46988 -263.738106) (xy 137.42289 -263.890506)
			(xy 137.42289 -263.934956) (xy 137.77849 -263.934956)
		)
		(stroke
			(width 0)
			(type solid)
		)
		(fill yes)
		(layer "In6.Cu")
		(net "M_G_CPU1_SA_CB<3>")
	)
	(gr_poly
		(pts
			(xy 137.78103 -275.284946) (xy 137.73404 -275.132546) (xy 137.47242 -275.132546) (xy 137.42543 -275.284946)
			(xy 137.42543 -275.329396) (xy 137.78103 -275.329396)
		)
		(stroke
			(width 0)
			(type solid)
		)
		(fill yes)
		(layer "In6.Cu")
		(net "M_H_CPU1_SA_DQ<7>")
	)
	(gr_poly
		(pts
			(xy 137.78103 -274.876768) (xy 137.78103 -274.832572) (xy 137.42543 -274.832572) (xy 137.42543 -274.876768)
			(xy 137.47242 -275.029168) (xy 137.73404 -275.029168)
		)
		(stroke
			(width 0)
			(type solid)
		)
		(fill yes)
		(layer "In6.Cu")
		(net "M_G_CPU1_SA_DQ<8>")
	)
	(gr_poly
		(pts
			(xy 137.78103 -272.029174) (xy 137.73404 -271.876774) (xy 137.47242 -271.876774) (xy 137.42543 -272.029174)
			(xy 137.42543 -272.073624) (xy 137.78103 -272.073624)
		)
		(stroke
			(width 0)
			(type solid)
		)
		(fill yes)
		(layer "In6.Cu")
		(net "M_G_CPU1_SA_DQS_DP<6>")
	)
	(gr_poly
		(pts
			(xy 137.78103 -271.62125) (xy 137.78103 -271.5768) (xy 137.42543 -271.5768) (xy 137.42543 -271.62125)
			(xy 137.47242 -271.77365) (xy 137.73404 -271.77365)
		)
		(stroke
			(width 0)
			(type solid)
		)
		(fill yes)
		(layer "In6.Cu")
		(net "M_G_CPU1_SA_DQ<12>")
	)
	(gr_poly
		(pts
			(xy 137.78103 -270.401542) (xy 137.73404 -270.249142) (xy 137.47242 -270.249142) (xy 137.42543 -270.401542)
			(xy 137.42543 -270.445992) (xy 137.78103 -270.445992)
		)
		(stroke
			(width 0)
			(type solid)
		)
		(fill yes)
		(layer "In6.Cu")
		(net "M_G_CPU1_SA_DQ<15>")
	)
	(gr_poly
		(pts
			(xy 137.78103 -269.993618) (xy 137.78103 -269.949168) (xy 137.42543 -269.949168) (xy 137.42543 -269.993618)
			(xy 137.47242 -270.146018) (xy 137.73404 -270.146018)
		)
		(stroke
			(width 0)
			(type solid)
		)
		(fill yes)
		(layer "In6.Cu")
		(net "M_G_CPU1_SA_DQ<24>")
	)
	(gr_poly
		(pts
			(xy 137.78103 -265.518138) (xy 137.73404 -265.365738) (xy 137.47242 -265.365738) (xy 137.42543 -265.518138)
			(xy 137.42543 -265.562588) (xy 137.78103 -265.562588)
		)
		(stroke
			(width 0)
			(type solid)
		)
		(fill yes)
		(layer "In6.Cu")
		(net "M_G_CPU1_SA_DQ<31>")
	)
	(gr_poly
		(pts
			(xy 137.78103 -265.110214) (xy 137.78103 -265.065764) (xy 137.42543 -265.065764) (xy 137.42543 -265.110214)
			(xy 137.47242 -265.262614) (xy 137.73404 -265.262614)
		)
		(stroke
			(width 0)
			(type solid)
		)
		(fill yes)
		(layer "In6.Cu")
		(net "M_G_CPU1_SA_CB<0>")
	)
	(gr_poly
		(pts
			(xy 137.78103 -255.75133) (xy 137.73404 -255.59893) (xy 137.47242 -255.59893) (xy 137.42543 -255.75133)
			(xy 137.42543 -255.79578) (xy 137.78103 -255.79578)
		)
		(stroke
			(width 0)
			(type solid)
		)
		(fill yes)
		(layer "In6.Cu")
		(net "M_H_CPU1_SA_RSP<0>")
	)
	(gr_poly
		(pts
			(xy 137.78103 -255.343406) (xy 137.78103 -255.298956) (xy 137.42543 -255.298956) (xy 137.42543 -255.343406)
			(xy 137.47242 -255.495806) (xy 137.73404 -255.495806)
		)
		(stroke
			(width 0)
			(type solid)
		)
		(fill yes)
		(layer "In6.Cu")
		(net "M_H_CPU1_SB_RSP<1>")
	)
	(gr_poly
		(pts
			(xy 138.022076 -234.536488) (xy 137.983722 -234.51439) (xy 137.828274 -234.47883) (xy 137.697464 -234.705398)
			(xy 137.805922 -234.822238) (xy 137.844276 -234.844336)
		)
		(stroke
			(width 0)
			(type solid)
		)
		(fill yes)
		(layer "In6.Cu")
		(net "M_G_CPU1_SB_DQS_DP<6>")
	)
	(gr_poly
		(pts
			(xy 138.098022 -279.613106) (xy 138.136376 -279.591008) (xy 137.958576 -279.28316) (xy 137.920222 -279.305258)
			(xy 137.811764 -279.422098) (xy 137.942574 -279.648666)
		)
		(stroke
			(width 0)
			(type solid)
		)
		(fill yes)
		(layer "In6.Cu")
		(net "M_H_CPU1_SA_DQS_DP<0>")
	)
	(gr_poly
		(pts
			(xy 138.100054 -277.989284) (xy 138.138408 -277.967186) (xy 137.960608 -277.659338) (xy 137.922254 -277.681436)
			(xy 137.813796 -277.798276) (xy 137.944606 -278.024844)
		)
		(stroke
			(width 0)
			(type solid)
		)
		(fill yes)
		(layer "In6.Cu")
		(net "M_H_CPU1_SA_DQS_DN<5>")
	)
	(gr_poly
		(pts
			(xy 138.12393 -240.057178) (xy 138.07694 -239.904778) (xy 137.81532 -239.904778) (xy 137.76833 -240.057178)
			(xy 137.76833 -240.101628) (xy 138.12393 -240.101628)
		)
		(stroke
			(width 0)
			(type solid)
		)
		(fill yes)
		(layer "In6.Cu")
		(net "M_G_CPU1_SB_DQS_DN<0>")
	)
	(gr_poly
		(pts
			(xy 138.12393 -239.649254) (xy 138.12393 -239.604804) (xy 137.76833 -239.604804) (xy 137.76833 -239.649254)
			(xy 137.81532 -239.801654) (xy 138.07694 -239.801654)
		)
		(stroke
			(width 0)
			(type solid)
		)
		(fill yes)
		(layer "In6.Cu")
		(net "M_G_CPU1_SB_DQS_DN<5>")
	)
	(gr_poly
		(pts
			(xy 138.12393 -236.801914) (xy 138.07694 -236.649514) (xy 137.81532 -236.649514) (xy 137.76833 -236.801914)
			(xy 137.76833 -236.84611) (xy 138.12393 -236.84611)
		)
		(stroke
			(width 0)
			(type solid)
		)
		(fill yes)
		(layer "In6.Cu")
		(net "M_G_CPU1_SB_DQ<10>")
	)
	(gr_poly
		(pts
			(xy 138.12393 -236.39399) (xy 138.12393 -236.34954) (xy 137.76833 -236.34954) (xy 137.76833 -236.39399)
			(xy 137.81532 -236.54639) (xy 138.07694 -236.54639)
		)
		(stroke
			(width 0)
			(type solid)
		)
		(fill yes)
		(layer "In6.Cu")
		(net "M_G_CPU1_SB_DQ<11>")
	)
	(gr_poly
		(pts
			(xy 138.124184 -217.268298) (xy 138.077194 -217.115898) (xy 137.815574 -217.115898) (xy 137.768584 -217.268298)
			(xy 137.768584 -217.312748) (xy 138.124184 -217.312748)
		)
		(stroke
			(width 0)
			(type solid)
		)
		(fill yes)
		(layer "In6.Cu")
		(net "M_G_CPU1_SB_DQS_DP<8>")
	)
	(gr_poly
		(pts
			(xy 138.132566 -241.685318) (xy 138.085576 -241.532918) (xy 137.823956 -241.532918) (xy 137.776966 -241.685318)
			(xy 137.776966 -241.729768) (xy 138.132566 -241.729768)
		)
		(stroke
			(width 0)
			(type solid)
		)
		(fill yes)
		(layer "In6.Cu")
		(net "M_G_CPU1_SB_DQ<2>")
	)
	(gr_poly
		(pts
			(xy 138.132566 -241.276886) (xy 138.132566 -241.232436) (xy 137.776966 -241.232436) (xy 137.776966 -241.276886)
			(xy 137.823956 -241.429286) (xy 138.085576 -241.429286)
		)
		(stroke
			(width 0)
			(type solid)
		)
		(fill yes)
		(layer "In6.Cu")
		(net "M_G_CPU1_SB_DQ<1>")
	)
	(gr_poly
		(pts
			(xy 138.132566 -238.430054) (xy 138.085576 -238.277654) (xy 137.823956 -238.277654) (xy 137.776966 -238.430054)
			(xy 137.776966 -238.47425) (xy 138.132566 -238.47425)
		)
		(stroke
			(width 0)
			(type solid)
		)
		(fill yes)
		(layer "In6.Cu")
		(net "M_G_CPU1_SB_DQ<6>")
	)
	(gr_poly
		(pts
			(xy 138.132566 -238.021114) (xy 138.132566 -237.976918) (xy 137.776966 -237.976918) (xy 137.776966 -238.021114)
			(xy 137.823956 -238.173514) (xy 138.085576 -238.173514)
		)
		(stroke
			(width 0)
			(type solid)
		)
		(fill yes)
		(layer "In6.Cu")
		(net "M_G_CPU1_SB_DQ<5>")
	)
	(gr_poly
		(pts
			(xy 138.132566 -233.54665) (xy 138.085576 -233.39425) (xy 137.823956 -233.39425) (xy 137.776966 -233.54665)
			(xy 137.776966 -233.590846) (xy 138.132566 -233.590846)
		)
		(stroke
			(width 0)
			(type solid)
		)
		(fill yes)
		(layer "In6.Cu")
		(net "M_G_CPU1_SB_DQS_DN<1>")
	)
	(gr_poly
		(pts
			(xy 138.132566 -233.13771) (xy 138.132566 -233.093514) (xy 137.776966 -233.093514) (xy 137.776966 -233.13771)
			(xy 137.823956 -233.29011) (xy 138.085576 -233.29011)
		)
		(stroke
			(width 0)
			(type solid)
		)
		(fill yes)
		(layer "In6.Cu")
		(net "M_G_CPU1_SB_DQ<14>")
	)
	(gr_poly
		(pts
			(xy 138.132566 -231.919018) (xy 138.085576 -231.766618) (xy 137.823956 -231.766618) (xy 137.776966 -231.919018)
			(xy 137.776966 -231.963214) (xy 138.132566 -231.963214)
		)
		(stroke
			(width 0)
			(type solid)
		)
		(fill yes)
		(layer "In6.Cu")
		(net "M_G_CPU1_SB_DQ<13>")
	)
	(gr_poly
		(pts
			(xy 138.132566 -216.859866) (xy 138.132566 -216.815416) (xy 137.776966 -216.815416) (xy 137.776966 -216.859866)
			(xy 137.823956 -217.012266) (xy 138.085576 -217.012266)
		)
		(stroke
			(width 0)
			(type solid)
		)
		(fill yes)
		(layer "In6.Cu")
		(net "M_G_CPU1_SB_DQ<28>")
	)
	(gr_poly
		(pts
			(xy 138.132566 -215.638888) (xy 138.085576 -215.486488) (xy 137.823956 -215.486488) (xy 137.776966 -215.638888)
			(xy 137.776966 -215.683084) (xy 138.132566 -215.683084)
		)
		(stroke
			(width 0)
			(type solid)
		)
		(fill yes)
		(layer "In6.Cu")
		(net "M_G_CPU1_SB_DQ<31>")
	)
	(gr_poly
		(pts
			(xy 138.206226 -235.244386) (xy 138.097768 -235.127546) (xy 138.059414 -235.105448) (xy 137.881614 -235.413296)
			(xy 137.919968 -235.435394) (xy 138.075416 -235.470954)
		)
		(stroke
			(width 0)
			(type solid)
		)
		(fill yes)
		(layer "In6.Cu")
		(net "M_G_CPU1_SB_DQS_DN<6>")
	)
	(gr_poly
		(pts
			(xy 138.208766 -278.995378) (xy 138.317224 -278.878538) (xy 138.186414 -278.65197) (xy 138.030966 -278.68753)
			(xy 137.992612 -278.709628) (xy 138.170412 -279.017476)
		)
		(stroke
			(width 0)
			(type solid)
		)
		(fill yes)
		(layer "In6.Cu")
		(net "M_H_CPU1_SA_DQS_DN<0>")
	)
	(gr_poly
		(pts
			(xy 138.208766 -277.367492) (xy 138.317224 -277.250652) (xy 138.186414 -277.024084) (xy 138.030966 -277.059644)
			(xy 137.992612 -277.081742) (xy 138.170412 -277.38959)
		)
		(stroke
			(width 0)
			(type solid)
		)
		(fill yes)
		(layer "In6.Cu")
		(net "M_H_CPU1_SA_DQS_DP<5>")
	)
	(gr_poly
		(pts
			(xy 138.233912 -275.690584) (xy 138.233912 -275.646388) (xy 137.878312 -275.646388) (xy 137.878312 -275.690584)
			(xy 137.925302 -275.842984) (xy 138.186922 -275.842984)
		)
		(stroke
			(width 0)
			(type solid)
		)
		(fill yes)
		(layer "In6.Cu")
		(net "M_H_CPU1_SA_DQ<5>")
	)
	(gr_poly
		(pts
			(xy 138.233912 -272.435066) (xy 138.233912 -272.39087) (xy 137.878312 -272.39087) (xy 137.878312 -272.435066)
			(xy 137.925302 -272.587466) (xy 138.186922 -272.587466)
		)
		(stroke
			(width 0)
			(type solid)
		)
		(fill yes)
		(layer "In6.Cu")
		(net "M_G_CPU1_SA_DQS_DN<6>")
	)
	(gr_poly
		(pts
			(xy 138.233912 -271.215358) (xy 138.186922 -271.062958) (xy 137.925302 -271.062958) (xy 137.878312 -271.215358)
			(xy 137.878312 -271.259808) (xy 138.233912 -271.259808)
		)
		(stroke
			(width 0)
			(type solid)
		)
		(fill yes)
		(layer "In6.Cu")
		(net "M_G_CPU1_SA_DQ<14>")
	)
	(gr_poly
		(pts
			(xy 138.233912 -270.807434) (xy 138.233912 -270.762984) (xy 137.878312 -270.762984) (xy 137.878312 -270.807434)
			(xy 137.925302 -270.959834) (xy 138.186922 -270.959834)
		)
		(stroke
			(width 0)
			(type solid)
		)
		(fill yes)
		(layer "In6.Cu")
		(net "M_G_CPU1_SA_DQ<13>")
	)
	(gr_poly
		(pts
			(xy 138.233912 -269.587726) (xy 138.186922 -269.435326) (xy 137.925302 -269.435326) (xy 137.878312 -269.587726)
			(xy 137.878312 -269.631922) (xy 138.233912 -269.631922)
		)
		(stroke
			(width 0)
			(type solid)
		)
		(fill yes)
		(layer "In6.Cu")
		(net "M_G_CPU1_SA_DQ<26>")
	)
	(gr_poly
		(pts
			(xy 138.233912 -265.92403) (xy 138.233912 -265.879834) (xy 137.878312 -265.879834) (xy 137.878312 -265.92403)
			(xy 137.925302 -266.07643) (xy 138.186922 -266.07643)
		)
		(stroke
			(width 0)
			(type solid)
		)
		(fill yes)
		(layer "In6.Cu")
		(net "M_G_CPU1_SA_DQ<29>")
	)
	(gr_poly
		(pts
			(xy 138.233912 -264.704322) (xy 138.186922 -264.551922) (xy 137.925302 -264.551922) (xy 137.878312 -264.704322)
			(xy 137.878312 -264.748772) (xy 138.233912 -264.748772)
		)
		(stroke
			(width 0)
			(type solid)
		)
		(fill yes)
		(layer "In6.Cu")
		(net "M_G_CPU1_SA_CB<2>")
	)
	(gr_poly
		(pts
			(xy 138.233912 -264.296398) (xy 138.233912 -264.251948) (xy 137.878312 -264.251948) (xy 137.878312 -264.296398)
			(xy 137.925302 -264.448798) (xy 138.186922 -264.448798)
		)
		(stroke
			(width 0)
			(type solid)
		)
		(fill yes)
		(layer "In6.Cu")
		(net "M_G_CPU1_SA_CB<1>")
	)
	(gr_poly
		(pts
			(xy 138.233912 -254.937514) (xy 138.186922 -254.785114) (xy 137.925302 -254.785114) (xy 137.878312 -254.937514)
			(xy 137.878312 -254.981964) (xy 138.233912 -254.981964)
		)
		(stroke
			(width 0)
			(type solid)
		)
		(fill yes)
		(layer "In6.Cu")
		(net "M_H_CPU1_SA_RSP<1>")
	)
	(gr_poly
		(pts
			(xy 138.234166 -256.157222) (xy 138.234166 -256.113026) (xy 137.878566 -256.113026) (xy 137.878566 -256.157222)
			(xy 137.925556 -256.309622) (xy 138.187176 -256.309622)
		)
		(stroke
			(width 0)
			(type solid)
		)
		(fill yes)
		(layer "In6.Cu")
		(net "M_H_CPU1_SB_RSP<0>")
	)
	(gr_poly
		(pts
			(xy 138.23569 -269.179294) (xy 138.23569 -269.134844) (xy 137.88009 -269.134844) (xy 137.88009 -269.179294)
			(xy 137.92708 -269.331694) (xy 138.1887 -269.331694)
		)
		(stroke
			(width 0)
			(type solid)
		)
		(fill yes)
		(layer "In6.Cu")
		(net "M_G_CPU1_SA_DQ<25>")
	)
	(gr_poly
		(pts
			(xy 138.236452 -280.574242) (xy 138.236452 -280.529792) (xy 137.880852 -280.529792) (xy 137.880852 -280.574242)
			(xy 137.927842 -280.726642) (xy 138.189462 -280.726642)
		)
		(stroke
			(width 0)
			(type solid)
		)
		(fill yes)
		(layer "In6.Cu")
		(net "M_H_CPU1_SA_DQ<3>")
	)
	(gr_poly
		(pts
			(xy 138.242294 -276.09927) (xy 138.195304 -275.94687) (xy 137.933684 -275.94687) (xy 137.886694 -276.09927)
			(xy 137.886694 -276.143466) (xy 138.242294 -276.143466)
		)
		(stroke
			(width 0)
			(type solid)
		)
		(fill yes)
		(layer "In6.Cu")
		(net "M_H_CPU1_SA_DQ<6>")
	)
	(gr_poly
		(pts
			(xy 138.242294 -274.062698) (xy 138.242294 -274.018248) (xy 137.886694 -274.018248) (xy 137.886694 -274.062698)
			(xy 137.933684 -274.215098) (xy 138.195304 -274.215098)
		)
		(stroke
			(width 0)
			(type solid)
		)
		(fill yes)
		(layer "In6.Cu")
		(net "M_G_CPU1_SA_DQ<9>")
	)
	(gr_poly
		(pts
			(xy 138.242294 -261.449058) (xy 138.195304 -261.296658) (xy 137.933684 -261.296658) (xy 137.886694 -261.449058)
			(xy 137.886694 -261.493508) (xy 138.242294 -261.493508)
		)
		(stroke
			(width 0)
			(type solid)
		)
		(fill yes)
		(layer "In6.Cu")
		(net "M_G_CPU1_SA_CB<6>")
	)
	(gr_poly
		(pts
			(xy 138.242294 -261.040626) (xy 138.242294 -260.996176) (xy 137.886694 -260.996176) (xy 137.886694 -261.040626)
			(xy 137.933684 -261.193026) (xy 138.195304 -261.193026)
		)
		(stroke
			(width 0)
			(type solid)
		)
		(fill yes)
		(layer "In6.Cu")
		(net "M_G_CPU1_SA_CB<5>")
	)
	(gr_poly
		(pts
			(xy 138.247882 -272.843498) (xy 138.200892 -272.691098) (xy 137.939272 -272.691098) (xy 137.892282 -272.843498)
			(xy 137.892282 -272.887948) (xy 138.247882 -272.887948)
		)
		(stroke
			(width 0)
			(type solid)
		)
		(fill yes)
		(layer "In6.Cu")
		(net "M_G_CPU1_SA_DQS_DN<1>")
	)
	(gr_poly
		(pts
			(xy 138.247882 -266.332462) (xy 138.200892 -266.180062) (xy 137.939272 -266.180062) (xy 137.892282 -266.332462)
			(xy 137.892282 -266.376658) (xy 138.247882 -266.376658)
		)
		(stroke
			(width 0)
			(type solid)
		)
		(fill yes)
		(layer "In6.Cu")
		(net "M_G_CPU1_SA_DQ<30>")
	)
	(gr_poly
		(pts
			(xy 138.24839 -280.98242) (xy 138.2014 -280.83002) (xy 137.93978 -280.83002) (xy 137.89279 -280.98242)
			(xy 137.89279 -281.026616) (xy 138.24839 -281.026616)
		)
		(stroke
			(width 0)
			(type solid)
		)
		(fill yes)
		(layer "In6.Cu")
		(net "M_H_CPU1_SA_DQ<2>")
	)
	(gr_poly
		(pts
			(xy 138.24839 -263.07669) (xy 138.2014 -262.92429) (xy 137.93978 -262.92429) (xy 137.89279 -263.07669)
			(xy 137.89279 -263.120886) (xy 138.24839 -263.120886)
		)
		(stroke
			(width 0)
			(type solid)
		)
		(fill yes)
		(layer "In6.Cu")
		(net "M_G_CPU1_SA_DQS_DN<4>")
	)
	(gr_poly
		(pts
			(xy 138.24839 -262.668258) (xy 138.24839 -262.624062) (xy 137.89279 -262.624062) (xy 137.89279 -262.668258)
			(xy 137.93978 -262.820658) (xy 138.2014 -262.820658)
		)
		(stroke
			(width 0)
			(type solid)
		)
		(fill yes)
		(layer "In6.Cu")
		(net "M_G_CPU1_SA_DQS_DN<9>")
	)
	(gr_poly
		(pts
			(xy 138.250422 -267.960094) (xy 138.203432 -267.807694) (xy 137.941812 -267.807694) (xy 137.894822 -267.960094)
			(xy 137.894822 -268.00429) (xy 138.250422 -268.00429)
		)
		(stroke
			(width 0)
			(type solid)
		)
		(fill yes)
		(layer "In6.Cu")
		(net "M_G_CPU1_SA_DQS_DN<3>")
	)
	(gr_poly
		(pts
			(xy 138.250422 -267.551662) (xy 138.250422 -267.507466) (xy 137.894822 -267.507466) (xy 137.894822 -267.551662)
			(xy 137.941812 -267.704062) (xy 138.203432 -267.704062)
		)
		(stroke
			(width 0)
			(type solid)
		)
		(fill yes)
		(layer "In6.Cu")
		(net "M_G_CPU1_SA_DQS_DN<8>")
	)
	(gr_poly
		(pts
			(xy 138.497564 -235.340652) (xy 138.45921 -235.318554) (xy 138.303762 -235.282994) (xy 138.172952 -235.509562)
			(xy 138.28141 -235.626402) (xy 138.319764 -235.6485)
		)
		(stroke
			(width 0)
			(type solid)
		)
		(fill yes)
		(layer "In6.Cu")
		(net "M_G_CPU1_SB_DQ<9>")
	)
	(gr_poly
		(pts
			(xy 138.567922 -277.171404) (xy 138.606276 -277.149306) (xy 138.428476 -276.841458) (xy 138.390122 -276.863556)
			(xy 138.281664 -276.980396) (xy 138.412474 -277.206964)
		)
		(stroke
			(width 0)
			(type solid)
		)
		(fill yes)
		(layer "In6.Cu")
		(net "M_H_CPU1_SA_DQ<4>")
	)
	(gr_poly
		(pts
			(xy 138.569954 -278.803354) (xy 138.608308 -278.781256) (xy 138.430508 -278.473408) (xy 138.392154 -278.495506)
			(xy 138.283696 -278.612346) (xy 138.414506 -278.838914)
		)
		(stroke
			(width 0)
			(type solid)
		)
		(fill yes)
		(layer "In6.Cu")
		(net "M_H_CPU1_SA_DQS_DN<5>")
	)
	(gr_poly
		(pts
			(xy 138.602466 -242.090702) (xy 138.602466 -242.046252) (xy 138.246866 -242.046252) (xy 138.246866 -242.090702)
			(xy 138.293856 -242.243102) (xy 138.555476 -242.243102)
		)
		(stroke
			(width 0)
			(type solid)
		)
		(fill yes)
		(layer "In6.Cu")
		(net "M_G_CPU1_SB_DQ<0>")
	)
	(gr_poly
		(pts
			(xy 138.602466 -240.871502) (xy 138.555476 -240.719102) (xy 138.293856 -240.719102) (xy 138.246866 -240.871502)
			(xy 138.246866 -240.915952) (xy 138.602466 -240.915952)
		)
		(stroke
			(width 0)
			(type solid)
		)
		(fill yes)
		(layer "In6.Cu")
		(net "M_G_CPU1_SB_DQ<3>")
	)
	(gr_poly
		(pts
			(xy 138.602466 -238.83493) (xy 138.602466 -238.790734) (xy 138.246866 -238.790734) (xy 138.246866 -238.83493)
			(xy 138.293856 -238.98733) (xy 138.555476 -238.98733)
		)
		(stroke
			(width 0)
			(type solid)
		)
		(fill yes)
		(layer "In6.Cu")
		(net "M_G_CPU1_SB_DQ<4>")
	)
	(gr_poly
		(pts
			(xy 138.602466 -237.61573) (xy 138.555476 -237.46333) (xy 138.293856 -237.46333) (xy 138.246866 -237.61573)
			(xy 138.246866 -237.66018) (xy 138.602466 -237.66018)
		)
		(stroke
			(width 0)
			(type solid)
		)
		(fill yes)
		(layer "In6.Cu")
		(net "M_G_CPU1_SB_DQ<7>")
	)
	(gr_poly
		(pts
			(xy 138.602466 -233.952034) (xy 138.602466 -233.907584) (xy 138.246866 -233.907584) (xy 138.246866 -233.952034)
			(xy 138.293856 -234.104434) (xy 138.555476 -234.104434)
		)
		(stroke
			(width 0)
			(type solid)
		)
		(fill yes)
		(layer "In6.Cu")
		(net "M_G_CPU1_SB_DQS_DP<1>")
	)
	(gr_poly
		(pts
			(xy 138.602466 -232.732834) (xy 138.555476 -232.580434) (xy 138.293856 -232.580434) (xy 138.246866 -232.732834)
			(xy 138.246866 -232.77703) (xy 138.602466 -232.77703)
		)
		(stroke
			(width 0)
			(type solid)
		)
		(fill yes)
		(layer "In6.Cu")
		(net "M_G_CPU1_SB_DQ<12>")
	)
	(gr_poly
		(pts
			(xy 138.602466 -232.323894) (xy 138.602466 -232.279698) (xy 138.246866 -232.279698) (xy 138.246866 -232.323894)
			(xy 138.293856 -232.476294) (xy 138.555476 -232.476294)
		)
		(stroke
			(width 0)
			(type solid)
		)
		(fill yes)
		(layer "In6.Cu")
		(net "M_G_CPU1_SB_DQ<15>")
	)
	(gr_poly
		(pts
			(xy 138.602466 -220.929454) (xy 138.602466 -220.885258) (xy 138.246866 -220.885258) (xy 138.246866 -220.929454)
			(xy 138.293856 -221.081854) (xy 138.555476 -221.081854)
		)
		(stroke
			(width 0)
			(type solid)
		)
		(fill yes)
		(layer "In6.Cu")
		(net "M_G_CPU1_SB_DQ<24>")
	)
	(gr_poly
		(pts
			(xy 138.602466 -218.082622) (xy 138.555476 -217.930222) (xy 138.293856 -217.930222) (xy 138.246866 -218.082622)
			(xy 138.246866 -218.127072) (xy 138.602466 -218.127072)
		)
		(stroke
			(width 0)
			(type solid)
		)
		(fill yes)
		(layer "In6.Cu")
		(net "M_G_CPU1_SB_DQS_DN<3>")
	)
	(gr_poly
		(pts
			(xy 138.602466 -217.67419) (xy 138.602466 -217.62974) (xy 138.246866 -217.62974) (xy 138.246866 -217.67419)
			(xy 138.293856 -217.82659) (xy 138.555476 -217.82659)
		)
		(stroke
			(width 0)
			(type solid)
		)
		(fill yes)
		(layer "In6.Cu")
		(net "M_G_CPU1_SB_DQS_DN<8>")
	)
	(gr_poly
		(pts
			(xy 138.604752 -216.045542) (xy 138.604752 -216.001346) (xy 138.249152 -216.001346) (xy 138.249152 -216.045542)
			(xy 138.296142 -216.197942) (xy 138.557762 -216.197942)
		)
		(stroke
			(width 0)
			(type solid)
		)
		(fill yes)
		(layer "In6.Cu")
		(net "M_G_CPU1_SB_DQ<29>")
	)
	(gr_poly
		(pts
			(xy 138.610848 -240.46307) (xy 138.610848 -240.418874) (xy 138.255248 -240.418874) (xy 138.255248 -240.46307)
			(xy 138.302238 -240.61547) (xy 138.563858 -240.61547)
		)
		(stroke
			(width 0)
			(type solid)
		)
		(fill yes)
		(layer "In6.Cu")
		(net "M_G_CPU1_SB_DQS_DP<0>")
	)
	(gr_poly
		(pts
			(xy 138.610848 -239.243362) (xy 138.563858 -239.090962) (xy 138.302238 -239.090962) (xy 138.255248 -239.243362)
			(xy 138.255248 -239.287812) (xy 138.610848 -239.287812)
		)
		(stroke
			(width 0)
			(type solid)
		)
		(fill yes)
		(layer "In6.Cu")
		(net "M_G_CPU1_SB_DQS_DP<5>")
	)
	(gr_poly
		(pts
			(xy 138.610848 -237.207806) (xy 138.610848 -237.163356) (xy 138.255248 -237.163356) (xy 138.255248 -237.207806)
			(xy 138.302238 -237.360206) (xy 138.563858 -237.360206)
		)
		(stroke
			(width 0)
			(type solid)
		)
		(fill yes)
		(layer "In6.Cu")
		(net "M_G_CPU1_SB_DQ<8>")
	)
	(gr_poly
		(pts
			(xy 138.610848 -234.360466) (xy 138.563858 -234.208066) (xy 138.302238 -234.208066) (xy 138.255248 -234.360466)
			(xy 138.255248 -234.404662) (xy 138.610848 -234.404662)
		)
		(stroke
			(width 0)
			(type solid)
		)
		(fill yes)
		(layer "In6.Cu")
		(net "M_G_CPU1_SB_DQS_DP<6>")
	)
	(gr_poly
		(pts
			(xy 138.67638 -236.057694) (xy 138.567922 -235.940854) (xy 138.529568 -235.918756) (xy 138.351768 -236.226604)
			(xy 138.390122 -236.248702) (xy 138.54557 -236.284262)
		)
		(stroke
			(width 0)
			(type solid)
		)
		(fill yes)
		(layer "In6.Cu")
		(net "M_G_CPU1_SB_DQ<11>")
	)
	(gr_poly
		(pts
			(xy 138.676634 -278.177498) (xy 138.785092 -278.060658) (xy 138.654282 -277.83409) (xy 138.498834 -277.86965)
			(xy 138.46048 -277.891748) (xy 138.63828 -278.199596)
		)
		(stroke
			(width 0)
			(type solid)
		)
		(fill yes)
		(layer "In6.Cu")
		(net "M_H_CPU1_SA_DQS_DP<5>")
	)
	(gr_poly
		(pts
			(xy 138.678666 -276.553676) (xy 138.787124 -276.436836) (xy 138.656314 -276.210268) (xy 138.500866 -276.245828)
			(xy 138.462512 -276.267926) (xy 138.640312 -276.575774)
		)
		(stroke
			(width 0)
			(type solid)
		)
		(fill yes)
		(layer "In6.Cu")
		(net "M_H_CPU1_SA_DQ<6>")
	)
	(gr_poly
		(pts
			(xy 138.701526 -268.365478) (xy 138.701526 -268.321028) (xy 138.345926 -268.321028) (xy 138.345926 -268.365478)
			(xy 138.392916 -268.517878) (xy 138.654536 -268.517878)
		)
		(stroke
			(width 0)
			(type solid)
		)
		(fill yes)
		(layer "In6.Cu")
		(net "M_G_CPU1_SA_DQS_DP<3>")
	)
	(gr_poly
		(pts
			(xy 138.701526 -267.146278) (xy 138.654536 -266.993878) (xy 138.392916 -266.993878) (xy 138.345926 -267.146278)
			(xy 138.345926 -267.190474) (xy 138.701526 -267.190474)
		)
		(stroke
			(width 0)
			(type solid)
		)
		(fill yes)
		(layer "In6.Cu")
		(net "M_G_CPU1_SA_DQS_DP<8>")
	)
	(gr_poly
		(pts
			(xy 138.703812 -263.482582) (xy 138.703812 -263.438132) (xy 138.348212 -263.438132) (xy 138.348212 -263.482582)
			(xy 138.395202 -263.634982) (xy 138.656822 -263.634982)
		)
		(stroke
			(width 0)
			(type solid)
		)
		(fill yes)
		(layer "In6.Cu")
		(net "M_G_CPU1_SA_DQS_DP<4>")
	)
	(gr_poly
		(pts
			(xy 138.703812 -262.262874) (xy 138.656822 -262.110474) (xy 138.395202 -262.110474) (xy 138.348212 -262.262874)
			(xy 138.348212 -262.30707) (xy 138.703812 -262.30707)
		)
		(stroke
			(width 0)
			(type solid)
		)
		(fill yes)
		(layer "In6.Cu")
		(net "M_G_CPU1_SA_DQS_DP<9>")
	)
	(gr_poly
		(pts
			(xy 138.70559 -266.737846) (xy 138.70559 -266.693396) (xy 138.34999 -266.693396) (xy 138.34999 -266.737846)
			(xy 138.39698 -266.890246) (xy 138.6586 -266.890246)
		)
		(stroke
			(width 0)
			(type solid)
		)
		(fill yes)
		(layer "In6.Cu")
		(net "M_G_CPU1_SA_DQ<28>")
	)
	(gr_poly
		(pts
			(xy 138.706352 -281.388058) (xy 138.706352 -281.343608) (xy 138.350752 -281.343608) (xy 138.350752 -281.388058)
			(xy 138.397742 -281.540458) (xy 138.659362 -281.540458)
		)
		(stroke
			(width 0)
			(type solid)
		)
		(fill yes)
		(layer "In6.Cu")
		(net "M_H_CPU1_SA_DQ<0>")
	)
	(gr_poly
		(pts
			(xy 138.712194 -279.759664) (xy 138.712194 -279.715468) (xy 138.356594 -279.715468) (xy 138.356594 -279.759664)
			(xy 138.403584 -279.912064) (xy 138.665204 -279.912064)
		)
		(stroke
			(width 0)
			(type solid)
		)
		(fill yes)
		(layer "In6.Cu")
		(net "M_H_CPU1_SA_DQS_DP<0>")
	)
	(gr_poly
		(pts
			(xy 138.712194 -261.854442) (xy 138.712194 -261.809992) (xy 138.356594 -261.809992) (xy 138.356594 -261.854442)
			(xy 138.403584 -262.006842) (xy 138.665204 -262.006842)
		)
		(stroke
			(width 0)
			(type solid)
		)
		(fill yes)
		(layer "In6.Cu")
		(net "M_G_CPU1_SA_CB<4>")
	)
	(gr_poly
		(pts
			(xy 138.717528 -268.77391) (xy 138.670538 -268.62151) (xy 138.408918 -268.62151) (xy 138.361928 -268.77391)
			(xy 138.361928 -268.81836) (xy 138.717528 -268.81836)
		)
		(stroke
			(width 0)
			(type solid)
		)
		(fill yes)
		(layer "In6.Cu")
		(net "M_G_CPU1_SA_DQ<27>")
	)
	(gr_poly
		(pts
			(xy 138.718544 -280.16835) (xy 138.671554 -280.01595) (xy 138.409934 -280.01595) (xy 138.362944 -280.16835)
			(xy 138.362944 -280.212546) (xy 138.718544 -280.212546)
		)
		(stroke
			(width 0)
			(type solid)
		)
		(fill yes)
		(layer "In6.Cu")
		(net "M_H_CPU1_SA_DQ<1>")
	)
	(gr_poly
		(pts
			(xy 138.72083 -275.284946) (xy 138.67384 -275.132546) (xy 138.41222 -275.132546) (xy 138.36523 -275.284946)
			(xy 138.36523 -275.329396) (xy 138.72083 -275.329396)
		)
		(stroke
			(width 0)
			(type solid)
		)
		(fill yes)
		(layer "In6.Cu")
		(net "M_H_CPU1_SA_DQ<7>")
	)
	(gr_poly
		(pts
			(xy 138.72083 -271.62125) (xy 138.72083 -271.5768) (xy 138.36523 -271.5768) (xy 138.36523 -271.62125)
			(xy 138.41222 -271.77365) (xy 138.67384 -271.77365)
		)
		(stroke
			(width 0)
			(type solid)
		)
		(fill yes)
		(layer "In6.Cu")
		(net "M_G_CPU1_SA_DQ<12>")
	)
	(gr_poly
		(pts
			(xy 138.72083 -269.993618) (xy 138.72083 -269.949168) (xy 138.36523 -269.949168) (xy 138.36523 -269.993618)
			(xy 138.41222 -270.146018) (xy 138.67384 -270.146018)
		)
		(stroke
			(width 0)
			(type solid)
		)
		(fill yes)
		(layer "In6.Cu")
		(net "M_G_CPU1_SA_DQ<24>")
	)
	(gr_poly
		(pts
			(xy 138.72083 -265.518138) (xy 138.67384 -265.365738) (xy 138.41222 -265.365738) (xy 138.36523 -265.518138)
			(xy 138.36523 -265.562588) (xy 138.72083 -265.562588)
		)
		(stroke
			(width 0)
			(type solid)
		)
		(fill yes)
		(layer "In6.Cu")
		(net "M_G_CPU1_SA_DQ<31>")
	)
	(gr_poly
		(pts
			(xy 138.72083 -265.110214) (xy 138.72083 -265.065764) (xy 138.36523 -265.065764) (xy 138.36523 -265.110214)
			(xy 138.41222 -265.262614) (xy 138.67384 -265.262614)
		)
		(stroke
			(width 0)
			(type solid)
		)
		(fill yes)
		(layer "In6.Cu")
		(net "M_G_CPU1_SA_CB<0>")
	)
	(gr_poly
		(pts
			(xy 138.72083 -263.890506) (xy 138.67384 -263.738106) (xy 138.41222 -263.738106) (xy 138.36523 -263.890506)
			(xy 138.36523 -263.934956) (xy 138.72083 -263.934956)
		)
		(stroke
			(width 0)
			(type solid)
		)
		(fill yes)
		(layer "In6.Cu")
		(net "M_G_CPU1_SA_CB<3>")
	)
	(gr_poly
		(pts
			(xy 138.72083 -255.343406) (xy 138.72083 -255.298956) (xy 138.36523 -255.298956) (xy 138.36523 -255.343406)
			(xy 138.41222 -255.495806) (xy 138.67384 -255.495806)
		)
		(stroke
			(width 0)
			(type solid)
		)
		(fill yes)
		(layer "In6.Cu")
		(net "M_H_CPU1_SB_RSP<1>")
	)
	(gr_poly
		(pts
			(xy 138.785092 -260.706616) (xy 138.676634 -260.589776) (xy 138.63828 -260.567678) (xy 138.46048 -260.875526)
			(xy 138.498834 -260.897624) (xy 138.654282 -260.933184)
		)
		(stroke
			(width 0)
			(type solid)
		)
		(fill yes)
		(layer "In6.Cu")
		(net "M_G_CPU1_SA_CB<5>")
	)
	(gr_poly
		(pts
			(xy 138.96721 -236.15523) (xy 138.928856 -236.133132) (xy 138.773408 -236.097572) (xy 138.642598 -236.32414)
			(xy 138.751056 -236.44098) (xy 138.78941 -236.463078)
		)
		(stroke
			(width 0)
			(type solid)
		)
		(fill yes)
		(layer "In6.Cu")
		(net "M_G_CPU1_SB_DQ<10>")
	)
	(gr_poly
		(pts
			(xy 139.037822 -276.357588) (xy 139.076176 -276.33549) (xy 138.898376 -276.027642) (xy 138.860022 -276.04974)
			(xy 138.751564 -276.16658) (xy 138.882374 -276.393148)
		)
		(stroke
			(width 0)
			(type solid)
		)
		(fill yes)
		(layer "In6.Cu")
		(net "M_H_CPU1_SA_DQ<5>")
	)
	(gr_poly
		(pts
			(xy 139.06373 -240.057178) (xy 139.01674 -239.904778) (xy 138.75512 -239.904778) (xy 138.70813 -240.057178)
			(xy 138.70813 -240.101628) (xy 139.06373 -240.101628)
		)
		(stroke
			(width 0)
			(type solid)
		)
		(fill yes)
		(layer "In6.Cu")
		(net "M_G_CPU1_SB_DQS_DN<0>")
	)
	(gr_poly
		(pts
			(xy 139.06373 -239.649254) (xy 139.06373 -239.604804) (xy 138.70813 -239.604804) (xy 138.70813 -239.649254)
			(xy 138.75512 -239.801654) (xy 139.01674 -239.801654)
		)
		(stroke
			(width 0)
			(type solid)
		)
		(fill yes)
		(layer "In6.Cu")
		(net "M_G_CPU1_SB_DQS_DN<5>")
	)
	(gr_poly
		(pts
			(xy 139.06373 -235.174282) (xy 139.01674 -235.021882) (xy 138.75512 -235.021882) (xy 138.70813 -235.174282)
			(xy 138.70813 -235.218478) (xy 139.06373 -235.218478)
		)
		(stroke
			(width 0)
			(type solid)
		)
		(fill yes)
		(layer "In6.Cu")
		(net "M_G_CPU1_SB_DQ<9>")
	)
	(gr_poly
		(pts
			(xy 139.064238 -216.859866) (xy 139.064238 -216.81567) (xy 138.708638 -216.81567) (xy 138.708638 -216.859866)
			(xy 138.755628 -217.012266) (xy 139.017248 -217.012266)
		)
		(stroke
			(width 0)
			(type solid)
		)
		(fill yes)
		(layer "In6.Cu")
		(net "M_G_CPU1_SB_DQ<28>")
	)
	(gr_poly
		(pts
			(xy 139.066524 -215.64092) (xy 139.019534 -215.48852) (xy 138.757914 -215.48852) (xy 138.710924 -215.64092)
			(xy 138.710924 -215.68537) (xy 139.066524 -215.68537)
		)
		(stroke
			(width 0)
			(type solid)
		)
		(fill yes)
		(layer "In6.Cu")
		(net "M_G_CPU1_SB_DQ<31>")
	)
	(gr_poly
		(pts
			(xy 139.072366 -241.685318) (xy 139.025376 -241.532918) (xy 138.763756 -241.532918) (xy 138.716766 -241.685318)
			(xy 138.716766 -241.729768) (xy 139.072366 -241.729768)
		)
		(stroke
			(width 0)
			(type solid)
		)
		(fill yes)
		(layer "In6.Cu")
		(net "M_G_CPU1_SB_DQ<2>")
	)
	(gr_poly
		(pts
			(xy 139.072366 -238.430054) (xy 139.025376 -238.277654) (xy 138.763756 -238.277654) (xy 138.716766 -238.430054)
			(xy 138.716766 -238.47425) (xy 139.072366 -238.47425)
		)
		(stroke
			(width 0)
			(type solid)
		)
		(fill yes)
		(layer "In6.Cu")
		(net "M_G_CPU1_SB_DQ<6>")
	)
	(gr_poly
		(pts
			(xy 139.072366 -233.54665) (xy 139.025376 -233.39425) (xy 138.763756 -233.39425) (xy 138.716766 -233.54665)
			(xy 138.716766 -233.590846) (xy 139.072366 -233.590846)
		)
		(stroke
			(width 0)
			(type solid)
		)
		(fill yes)
		(layer "In6.Cu")
		(net "M_G_CPU1_SB_DQS_DN<1>")
	)
	(gr_poly
		(pts
			(xy 139.072366 -220.52407) (xy 139.025376 -220.37167) (xy 138.763756 -220.37167) (xy 138.716766 -220.52407)
			(xy 138.716766 -220.56852) (xy 139.072366 -220.56852)
		)
		(stroke
			(width 0)
			(type solid)
		)
		(fill yes)
		(layer "In6.Cu")
		(net "M_G_CPU1_SB_DQ<26>")
	)
	(gr_poly
		(pts
			(xy 139.078208 -260.800088) (xy 139.039854 -260.77799) (xy 138.884406 -260.74243) (xy 138.753596 -260.968998)
			(xy 138.862054 -261.085838) (xy 138.900408 -261.107936)
		)
		(stroke
			(width 0)
			(type solid)
		)
		(fill yes)
		(layer "In6.Cu")
		(net "M_G_CPU1_SA_CB<6>")
	)
	(gr_poly
		(pts
			(xy 139.080748 -218.488006) (xy 139.080748 -218.44381) (xy 138.725148 -218.44381) (xy 138.725148 -218.488006)
			(xy 138.772138 -218.640406) (xy 139.033758 -218.640406)
		)
		(stroke
			(width 0)
			(type solid)
		)
		(fill yes)
		(layer "In6.Cu")
		(net "M_G_CPU1_SB_DQS_DP<3>")
	)
	(gr_poly
		(pts
			(xy 139.080748 -217.268298) (xy 139.033758 -217.115898) (xy 138.772138 -217.115898) (xy 138.725148 -217.268298)
			(xy 138.725148 -217.312748) (xy 139.080748 -217.312748)
		)
		(stroke
			(width 0)
			(type solid)
		)
		(fill yes)
		(layer "In6.Cu")
		(net "M_G_CPU1_SB_DQS_DP<8>")
	)
	(gr_poly
		(pts
			(xy 139.146026 -236.872272) (xy 139.037568 -236.755432) (xy 138.999214 -236.733334) (xy 138.821414 -237.041182)
			(xy 138.859768 -237.06328) (xy 139.015216 -237.09884)
		)
		(stroke
			(width 0)
			(type solid)
		)
		(fill yes)
		(layer "In6.Cu")
		(net "M_G_CPU1_SB_DQ<8>")
	)
	(gr_poly
		(pts
			(xy 139.173712 -269.587726) (xy 139.126722 -269.435326) (xy 138.865102 -269.435326) (xy 138.818112 -269.587726)
			(xy 138.818112 -269.631922) (xy 139.173712 -269.631922)
		)
		(stroke
			(width 0)
			(type solid)
		)
		(fill yes)
		(layer "In6.Cu")
		(net "M_G_CPU1_SA_DQ<26>")
	)
	(gr_poly
		(pts
			(xy 139.173712 -265.92403) (xy 139.173712 -265.879834) (xy 138.818112 -265.879834) (xy 138.818112 -265.92403)
			(xy 138.865102 -266.07643) (xy 139.126722 -266.07643)
		)
		(stroke
			(width 0)
			(type solid)
		)
		(fill yes)
		(layer "In6.Cu")
		(net "M_G_CPU1_SA_DQ<29>")
	)
	(gr_poly
		(pts
			(xy 139.173712 -264.704322) (xy 139.126722 -264.551922) (xy 138.865102 -264.551922) (xy 138.818112 -264.704322)
			(xy 138.818112 -264.748772) (xy 139.173712 -264.748772)
		)
		(stroke
			(width 0)
			(type solid)
		)
		(fill yes)
		(layer "In6.Cu")
		(net "M_G_CPU1_SA_CB<2>")
	)
	(gr_poly
		(pts
			(xy 139.173712 -264.296398) (xy 139.173712 -264.251948) (xy 138.818112 -264.251948) (xy 138.818112 -264.296398)
			(xy 138.865102 -264.448798) (xy 139.126722 -264.448798)
		)
		(stroke
			(width 0)
			(type solid)
		)
		(fill yes)
		(layer "In6.Cu")
		(net "M_G_CPU1_SA_CB<1>")
	)
	(gr_poly
		(pts
			(xy 139.175236 -269.179294) (xy 139.175236 -269.134844) (xy 138.819636 -269.134844) (xy 138.819636 -269.179294)
			(xy 138.866626 -269.331694) (xy 139.128246 -269.331694)
		)
		(stroke
			(width 0)
			(type solid)
		)
		(fill yes)
		(layer "In6.Cu")
		(net "M_G_CPU1_SA_DQ<25>")
	)
	(gr_poly
		(pts
			(xy 139.187428 -267.551662) (xy 139.187428 -267.507212) (xy 138.831828 -267.507212) (xy 138.831828 -267.551662)
			(xy 138.878818 -267.704062) (xy 139.140438 -267.704062)
		)
		(stroke
			(width 0)
			(type solid)
		)
		(fill yes)
		(layer "In6.Cu")
		(net "M_G_CPU1_SA_DQS_DN<8>")
	)
	(gr_poly
		(pts
			(xy 139.187428 -266.332462) (xy 139.140438 -266.180062) (xy 138.878818 -266.180062) (xy 138.831828 -266.332462)
			(xy 138.831828 -266.376658) (xy 139.187428 -266.376658)
		)
		(stroke
			(width 0)
			(type solid)
		)
		(fill yes)
		(layer "In6.Cu")
		(net "M_G_CPU1_SA_DQ<30>")
	)
	(gr_poly
		(pts
			(xy 139.188444 -280.98242) (xy 139.141454 -280.83002) (xy 138.879834 -280.83002) (xy 138.832844 -280.98242)
			(xy 138.832844 -281.026616) (xy 139.188444 -281.026616)
		)
		(stroke
			(width 0)
			(type solid)
		)
		(fill yes)
		(layer "In6.Cu")
		(net "M_H_CPU1_SA_DQ<2>")
	)
	(gr_poly
		(pts
			(xy 139.189968 -267.960094) (xy 139.142978 -267.807694) (xy 138.881358 -267.807694) (xy 138.834368 -267.960094)
			(xy 138.834368 -268.004544) (xy 139.189968 -268.004544)
		)
		(stroke
			(width 0)
			(type solid)
		)
		(fill yes)
		(layer "In6.Cu")
		(net "M_G_CPU1_SA_DQS_DN<3>")
	)
	(gr_poly
		(pts
			(xy 139.19073 -263.07669) (xy 139.14374 -262.92429) (xy 138.88212 -262.92429) (xy 138.83513 -263.07669)
			(xy 138.83513 -263.120886) (xy 139.19073 -263.120886)
		)
		(stroke
			(width 0)
			(type solid)
		)
		(fill yes)
		(layer "In6.Cu")
		(net "M_G_CPU1_SA_DQS_DN<4>")
	)
	(gr_poly
		(pts
			(xy 139.19073 -262.668258) (xy 139.19073 -262.624062) (xy 138.83513 -262.624062) (xy 138.83513 -262.668258)
			(xy 138.88212 -262.820658) (xy 139.14374 -262.820658)
		)
		(stroke
			(width 0)
			(type solid)
		)
		(fill yes)
		(layer "In6.Cu")
		(net "M_G_CPU1_SA_DQS_DN<9>")
	)
	(gr_poly
		(pts
			(xy 139.257024 -261.516622) (xy 139.148566 -261.399782) (xy 139.110212 -261.377684) (xy 138.932412 -261.685532)
			(xy 138.970766 -261.70763) (xy 139.126214 -261.74319)
		)
		(stroke
			(width 0)
			(type solid)
		)
		(fill yes)
		(layer "In6.Cu")
		(net "M_G_CPU1_SA_CB<4>")
	)
	(gr_poly
		(pts
			(xy 139.53363 -218.082622) (xy 139.48664 -217.930222) (xy 139.22502 -217.930222) (xy 139.17803 -218.082622)
			(xy 139.17803 -218.126818) (xy 139.53363 -218.126818)
		)
		(stroke
			(width 0)
			(type solid)
		)
		(fill yes)
		(layer "In6.Cu")
		(net "M_G_CPU1_SB_DQS_DN<3>")
	)
	(gr_poly
		(pts
			(xy 139.53363 -217.67419) (xy 139.53363 -217.629994) (xy 139.17803 -217.629994) (xy 139.17803 -217.67419)
			(xy 139.22502 -217.82659) (xy 139.48664 -217.82659)
		)
		(stroke
			(width 0)
			(type solid)
		)
		(fill yes)
		(layer "In6.Cu")
		(net "M_G_CPU1_SB_DQS_DN<8>")
	)
	(gr_poly
		(pts
			(xy 139.539726 -261.628382) (xy 139.501372 -261.606284) (xy 139.345924 -261.570724) (xy 139.215114 -261.797292)
			(xy 139.323572 -261.914132) (xy 139.361926 -261.93623)
		)
		(stroke
			(width 0)
			(type solid)
		)
		(fill yes)
		(layer "In6.Cu")
		(net "M_G_CPU1_SA_DQS_DP<9>")
	)
	(gr_poly
		(pts
			(xy 139.542266 -220.929454) (xy 139.542266 -220.885258) (xy 139.186666 -220.885258) (xy 139.186666 -220.929454)
			(xy 139.233656 -221.081854) (xy 139.495276 -221.081854)
		)
		(stroke
			(width 0)
			(type solid)
		)
		(fill yes)
		(layer "In6.Cu")
		(net "M_G_CPU1_SB_DQ<24>")
	)
	(gr_poly
		(pts
			(xy 139.548108 -216.453974) (xy 139.501118 -216.301574) (xy 139.239498 -216.301574) (xy 139.192508 -216.453974)
			(xy 139.192508 -216.498424) (xy 139.548108 -216.498424)
		)
		(stroke
			(width 0)
			(type solid)
		)
		(fill yes)
		(layer "In6.Cu")
		(net "M_G_CPU1_SB_DQ<30>")
	)
	(gr_poly
		(pts
			(xy 139.645136 -268.365478) (xy 139.645136 -268.321028) (xy 139.289536 -268.321028) (xy 139.289536 -268.365478)
			(xy 139.336526 -268.517878) (xy 139.598146 -268.517878)
		)
		(stroke
			(width 0)
			(type solid)
		)
		(fill yes)
		(layer "In6.Cu")
		(net "M_G_CPU1_SA_DQS_DP<3>")
	)
	(gr_poly
		(pts
			(xy 139.645136 -266.737846) (xy 139.645136 -266.693396) (xy 139.289536 -266.693396) (xy 139.289536 -266.737846)
			(xy 139.336526 -266.890246) (xy 139.598146 -266.890246)
		)
		(stroke
			(width 0)
			(type solid)
		)
		(fill yes)
		(layer "In6.Cu")
		(net "M_G_CPU1_SA_DQ<28>")
	)
	(gr_poly
		(pts
			(xy 139.651994 -263.481566) (xy 139.651994 -263.43737) (xy 139.296394 -263.43737) (xy 139.296394 -263.481566)
			(xy 139.343384 -263.633966) (xy 139.605004 -263.633966)
		)
		(stroke
			(width 0)
			(type solid)
		)
		(fill yes)
		(layer "In6.Cu")
		(net "M_G_CPU1_SA_DQS_DP<4>")
	)
	(gr_poly
		(pts
			(xy 139.657074 -268.77391) (xy 139.610084 -268.62151) (xy 139.348464 -268.62151) (xy 139.301474 -268.77391)
			(xy 139.301474 -268.81836) (xy 139.657074 -268.81836)
		)
		(stroke
			(width 0)
			(type solid)
		)
		(fill yes)
		(layer "In6.Cu")
		(net "M_G_CPU1_SA_DQ<27>")
	)
	(gr_poly
		(pts
			(xy 139.657074 -267.146278) (xy 139.610084 -266.993878) (xy 139.348464 -266.993878) (xy 139.301474 -267.146278)
			(xy 139.301474 -267.190474) (xy 139.657074 -267.190474)
		)
		(stroke
			(width 0)
			(type solid)
		)
		(fill yes)
		(layer "In6.Cu")
		(net "M_G_CPU1_SA_DQS_DP<8>")
	)
	(gr_poly
		(pts
			(xy 139.66063 -265.518138) (xy 139.61364 -265.365738) (xy 139.35202 -265.365738) (xy 139.30503 -265.518138)
			(xy 139.30503 -265.562588) (xy 139.66063 -265.562588)
		)
		(stroke
			(width 0)
			(type solid)
		)
		(fill yes)
		(layer "In6.Cu")
		(net "M_G_CPU1_SA_DQ<31>")
	)
	(gr_poly
		(pts
			(xy 139.725908 -262.332978) (xy 139.61745 -262.216138) (xy 139.579096 -262.19404) (xy 139.401296 -262.501888)
			(xy 139.43965 -262.523986) (xy 139.595098 -262.559546)
		)
		(stroke
			(width 0)
			(type solid)
		)
		(fill yes)
		(layer "In6.Cu")
		(net "M_G_CPU1_SA_DQS_DN<9>")
	)
	(gr_poly
		(pts
			(xy 140.004038 -216.859866) (xy 140.004038 -216.81567) (xy 139.648438 -216.81567) (xy 139.648438 -216.859866)
			(xy 139.695428 -217.012266) (xy 139.957048 -217.012266)
		)
		(stroke
			(width 0)
			(type solid)
		)
		(fill yes)
		(layer "In6.Cu")
		(net "M_G_CPU1_SB_DQ<28>")
	)
	(gr_poly
		(pts
			(xy 140.012166 -220.52407) (xy 139.965176 -220.37167) (xy 139.703556 -220.37167) (xy 139.656566 -220.52407)
			(xy 139.656566 -220.56852) (xy 140.012166 -220.56852)
		)
		(stroke
			(width 0)
			(type solid)
		)
		(fill yes)
		(layer "In6.Cu")
		(net "M_G_CPU1_SB_DQ<26>")
	)
	(gr_poly
		(pts
			(xy 140.020548 -218.896438) (xy 139.973558 -218.744038) (xy 139.711938 -218.744038) (xy 139.664948 -218.896438)
			(xy 139.664948 -218.940634) (xy 140.020548 -218.940634)
		)
		(stroke
			(width 0)
			(type solid)
		)
		(fill yes)
		(layer "In6.Cu")
		(net "M_G_CPU1_SB_DQ<27>")
	)
	(gr_poly
		(pts
			(xy 140.020548 -218.488006) (xy 140.020548 -218.44381) (xy 139.664948 -218.44381) (xy 139.664948 -218.488006)
			(xy 139.711938 -218.640406) (xy 139.973558 -218.640406)
		)
		(stroke
			(width 0)
			(type solid)
		)
		(fill yes)
		(layer "In6.Cu")
		(net "M_G_CPU1_SB_DQS_DP<3>")
	)
	(gr_poly
		(pts
			(xy 140.020548 -217.268298) (xy 139.973558 -217.115898) (xy 139.711938 -217.115898) (xy 139.664948 -217.268298)
			(xy 139.664948 -217.312748) (xy 140.020548 -217.312748)
		)
		(stroke
			(width 0)
			(type solid)
		)
		(fill yes)
		(layer "In6.Cu")
		(net "M_G_CPU1_SB_DQS_DP<8>")
	)
	(gr_poly
		(pts
			(xy 140.126974 -266.332462) (xy 140.079984 -266.180062) (xy 139.818364 -266.180062) (xy 139.771374 -266.332462)
			(xy 139.771374 -266.376658) (xy 140.126974 -266.376658)
		)
		(stroke
			(width 0)
			(type solid)
		)
		(fill yes)
		(layer "In6.Cu")
		(net "M_G_CPU1_SA_DQ<30>")
	)
	(gr_poly
		(pts
			(xy 140.47343 -219.301822) (xy 140.47343 -219.257626) (xy 140.11783 -219.257626) (xy 140.11783 -219.301822)
			(xy 140.16482 -219.454222) (xy 140.42644 -219.454222)
		)
		(stroke
			(width 0)
			(type solid)
		)
		(fill yes)
		(layer "In6.Cu")
		(net "M_G_CPU1_SB_DQ<25>")
	)
	(gr_poly
		(pts
			(xy 140.47343 -218.082622) (xy 140.42644 -217.930222) (xy 140.16482 -217.930222) (xy 140.11783 -218.082622)
			(xy 140.11783 -218.126818) (xy 140.47343 -218.126818)
		)
		(stroke
			(width 0)
			(type solid)
		)
		(fill yes)
		(layer "In6.Cu")
		(net "M_G_CPU1_SB_DQS_DN<3>")
	)
	(gr_poly
		(pts
			(xy 140.47343 -217.67419) (xy 140.47343 -217.629994) (xy 140.11783 -217.629994) (xy 140.11783 -217.67419)
			(xy 140.16482 -217.82659) (xy 140.42644 -217.82659)
		)
		(stroke
			(width 0)
			(type solid)
		)
		(fill yes)
		(layer "In6.Cu")
		(net "M_G_CPU1_SB_DQS_DN<8>")
	)
	(gr_poly
		(pts
			(xy 140.541248 -221.051374) (xy 140.56106 -220.893132) (xy 140.553186 -220.849444) (xy 140.203174 -220.91142)
			(xy 140.210794 -220.954854) (xy 140.283438 -221.09684)
		)
		(stroke
			(width 0)
			(type solid)
		)
		(fill yes)
		(layer "In6.Cu")
		(net "M_G_CPU1_SB_DQ<24>")
	)
	(gr_poly
		(pts
			(xy 140.960348 -218.896438) (xy 140.913358 -218.744038) (xy 140.651738 -218.744038) (xy 140.604748 -218.896438)
			(xy 140.604748 -218.940634) (xy 140.960348 -218.940634)
		)
		(stroke
			(width 0)
			(type solid)
		)
		(fill yes)
		(layer "In6.Cu")
		(net "M_G_CPU1_SB_DQ<27>")
	)
	(gr_poly
		(pts
			(xy 140.960348 -218.488006) (xy 140.960348 -218.44381) (xy 140.604748 -218.44381) (xy 140.604748 -218.488006)
			(xy 140.651738 -218.640406) (xy 140.913358 -218.640406)
		)
		(stroke
			(width 0)
			(type solid)
		)
		(fill yes)
		(layer "In6.Cu")
		(net "M_G_CPU1_SB_DQS_DP<3>")
	)
	(gr_poly
		(pts
			(xy 141.41323 -219.301822) (xy 141.41323 -219.257626) (xy 141.05763 -219.257626) (xy 141.05763 -219.301822)
			(xy 141.10462 -219.454222) (xy 141.36624 -219.454222)
		)
		(stroke
			(width 0)
			(type solid)
		)
		(fill yes)
		(layer "In6.Cu")
		(net "M_G_CPU1_SB_DQ<25>")
	)
	(gr_poly
		(pts
			(xy 332.409292 -234.78998) (xy 332.416912 -234.746546) (xy 332.0669 -234.68457) (xy 332.059026 -234.728258)
			(xy 332.078838 -234.8865) (xy 332.336648 -234.931966)
		)
		(stroke
			(width 0)
			(type solid)
		)
		(fill yes)
		(layer "In6.Cu")
		(net "M_C_CPU0_SB_DQ<13>")
	)
	(gr_poly
		(pts
			(xy 332.495398 -244.940582) (xy 332.448408 -244.788182) (xy 332.186788 -244.788182) (xy 332.139798 -244.940582)
			(xy 332.139798 -244.985032) (xy 332.495398 -244.985032)
		)
		(stroke
			(width 0)
			(type solid)
		)
		(fill yes)
		(layer "In6.Cu")
		(net "M_D_CPU0_SB_CS_N<1>")
	)
	(gr_poly
		(pts
			(xy 332.50378 -244.53215) (xy 332.50378 -244.487954) (xy 332.14818 -244.487954) (xy 332.14818 -244.53215)
			(xy 332.19517 -244.68455) (xy 332.45679 -244.68455)
		)
		(stroke
			(width 0)
			(type solid)
		)
		(fill yes)
		(layer "In6.Cu")
		(net "M_C_CPU0_SB_DQ<0>")
	)
	(gr_poly
		(pts
			(xy 332.504034 -246.16029) (xy 332.504034 -246.11584) (xy 332.148434 -246.11584) (xy 332.148434 -246.16029)
			(xy 332.195424 -246.31269) (xy 332.457044 -246.31269)
		)
		(stroke
			(width 0)
			(type solid)
		)
		(fill yes)
		(layer "In6.Cu")
		(net "M_D_CPU0_SB_CS_N<2>")
	)
	(gr_poly
		(pts
			(xy 332.504034 -231.510078) (xy 332.504034 -231.465882) (xy 332.148434 -231.465882) (xy 332.148434 -231.510078)
			(xy 332.195424 -231.662478) (xy 332.457044 -231.662478)
		)
		(stroke
			(width 0)
			(type solid)
		)
		(fill yes)
		(layer "In6.Cu")
		(net "M_D_CPU0_SB_DQS_DP<2>")
	)
	(gr_poly
		(pts
			(xy 332.51013 -236.802422) (xy 332.46314 -236.650022) (xy 332.20152 -236.650022) (xy 332.15453 -236.802422)
			(xy 332.15453 -236.846618) (xy 332.51013 -236.846618)
		)
		(stroke
			(width 0)
			(type solid)
		)
		(fill yes)
		(layer "In6.Cu")
		(net "M_C_CPU0_SB_DQS_DN<1>")
	)
	(gr_poly
		(pts
			(xy 332.512416 -243.31295) (xy 332.465426 -243.16055) (xy 332.203806 -243.16055) (xy 332.156816 -243.31295)
			(xy 332.156816 -243.3574) (xy 332.512416 -243.3574)
		)
		(stroke
			(width 0)
			(type solid)
		)
		(fill yes)
		(layer "In6.Cu")
		(net "M_C_CPU0_SB_DQ<3>")
	)
	(gr_poly
		(pts
			(xy 332.512416 -242.905026) (xy 332.512416 -242.860576) (xy 332.156816 -242.860576) (xy 332.156816 -242.905026)
			(xy 332.203806 -243.057426) (xy 332.465426 -243.057426)
		)
		(stroke
			(width 0)
			(type solid)
		)
		(fill yes)
		(layer "In6.Cu")
		(net "M_C_CPU0_SB_DQS_DP<0>")
	)
	(gr_poly
		(pts
			(xy 332.613762 -261.449058) (xy 332.566772 -261.296658) (xy 332.305152 -261.296658) (xy 332.258162 -261.449058)
			(xy 332.258162 -261.493508) (xy 332.613762 -261.493508)
		)
		(stroke
			(width 0)
			(type solid)
		)
		(fill yes)
		(layer "In6.Cu")
		(net "M_C_CPU0_SA_CB<1>")
	)
	(gr_poly
		(pts
			(xy 332.613762 -261.040626) (xy 332.613762 -260.996176) (xy 332.258162 -260.996176) (xy 332.258162 -261.040626)
			(xy 332.305152 -261.193026) (xy 332.566772 -261.193026)
		)
		(stroke
			(width 0)
			(type solid)
		)
		(fill yes)
		(layer "In6.Cu")
		(net "M_C_CPU0_SA_DQS_DN<9>")
	)
	(gr_poly
		(pts
			(xy 332.613762 -259.821426) (xy 332.566772 -259.669026) (xy 332.305152 -259.669026) (xy 332.258162 -259.821426)
			(xy 332.258162 -259.865622) (xy 332.613762 -259.865622)
		)
		(stroke
			(width 0)
			(type solid)
		)
		(fill yes)
		(layer "In6.Cu")
		(net "M_C_CPU0_SA_DQS_DN<4>")
	)
	(gr_poly
		(pts
			(xy 332.613762 -256.565654) (xy 332.566772 -256.413254) (xy 332.305152 -256.413254) (xy 332.258162 -256.565654)
			(xy 332.258162 -256.610104) (xy 332.613762 -256.610104)
		)
		(stroke
			(width 0)
			(type solid)
		)
		(fill yes)
		(layer "In6.Cu")
		(net "M_D_CPU0_SB_RSP<0>")
	)
	(gr_poly
		(pts
			(xy 332.613762 -256.157222) (xy 332.613762 -256.112772) (xy 332.258162 -256.112772) (xy 332.258162 -256.157222)
			(xy 332.305152 -256.309622) (xy 332.566772 -256.309622)
		)
		(stroke
			(width 0)
			(type solid)
		)
		(fill yes)
		(layer "In6.Cu")
		(net "M_D_CPU0_SA_RSP<1>")
	)
	(gr_poly
		(pts
			(xy 332.830424 -232.993184) (xy 332.868778 -232.971086) (xy 332.690978 -232.663238) (xy 332.652624 -232.685336)
			(xy 332.544166 -232.802176) (xy 332.674976 -233.028744)
		)
		(stroke
			(width 0)
			(type solid)
		)
		(fill yes)
		(layer "In6.Cu")
		(net "M_D_CPU0_SB_DQ<17>")
	)
	(gr_poly
		(pts
			(xy 332.830424 -223.226376) (xy 332.868778 -223.204278) (xy 332.690978 -222.89643) (xy 332.652624 -222.918528)
			(xy 332.544166 -223.035368) (xy 332.674976 -223.261936)
		)
		(stroke
			(width 0)
			(type solid)
		)
		(fill yes)
		(layer "In6.Cu")
		(net "M_C_CPU0_SB_DQ<31>")
	)
	(gr_poly
		(pts
			(xy 332.830678 -239.504728) (xy 332.869032 -239.48263) (xy 332.691232 -239.174782) (xy 332.652878 -239.19688)
			(xy 332.54442 -239.31372) (xy 332.67523 -239.540288)
		)
		(stroke
			(width 0)
			(type solid)
		)
		(fill yes)
		(layer "In6.Cu")
		(net "M_C_CPU0_SB_DQ<8>")
	)
	(gr_poly
		(pts
			(xy 332.940406 -238.88446) (xy 333.048864 -238.76762) (xy 332.918054 -238.541052) (xy 332.762606 -238.576612)
			(xy 332.724252 -238.59871) (xy 332.902052 -238.906558)
		)
		(stroke
			(width 0)
			(type solid)
		)
		(fill yes)
		(layer "In6.Cu")
		(net "M_C_CPU0_SB_DQ<10>")
	)
	(gr_poly
		(pts
			(xy 332.963012 -225.812858) (xy 332.963012 -225.768408) (xy 332.607412 -225.768408) (xy 332.607412 -225.812858)
			(xy 332.654402 -225.965258) (xy 332.916022 -225.965258)
		)
		(stroke
			(width 0)
			(type solid)
		)
		(fill yes)
		(layer "In6.Cu")
		(net "M_C_CPU0_SB_DQS_DP<3>")
	)
	(gr_poly
		(pts
			(xy 332.965298 -243.718842) (xy 332.965298 -243.674392) (xy 332.609698 -243.674392) (xy 332.609698 -243.718842)
			(xy 332.656688 -243.871242) (xy 332.918308 -243.871242)
		)
		(stroke
			(width 0)
			(type solid)
		)
		(fill yes)
		(layer "In6.Cu")
		(net "M_C_CPU0_SB_DQ<1>")
	)
	(gr_poly
		(pts
			(xy 332.965298 -242.499134) (xy 332.918308 -242.346734) (xy 332.656688 -242.346734) (xy 332.609698 -242.499134)
			(xy 332.609698 -242.54333) (xy 332.965298 -242.54333)
		)
		(stroke
			(width 0)
			(type solid)
		)
		(fill yes)
		(layer "In6.Cu")
		(net "M_C_CPU0_SB_DQS_DN<0>")
	)
	(gr_poly
		(pts
			(xy 332.965298 -237.207806) (xy 332.965298 -237.163356) (xy 332.609698 -237.163356) (xy 332.609698 -237.207806)
			(xy 332.656688 -237.360206) (xy 332.918308 -237.360206)
		)
		(stroke
			(width 0)
			(type solid)
		)
		(fill yes)
		(layer "In6.Cu")
		(net "M_C_CPU0_SB_DQS_DP<1>")
	)
	(gr_poly
		(pts
			(xy 332.965552 -237.61573) (xy 332.918562 -237.46333) (xy 332.656942 -237.46333) (xy 332.609952 -237.61573)
			(xy 332.609952 -237.66018) (xy 332.965552 -237.66018)
		)
		(stroke
			(width 0)
			(type solid)
		)
		(fill yes)
		(layer "In6.Cu")
		(net "M_C_CPU0_SB_DQ<11>")
	)
	(gr_poly
		(pts
			(xy 332.96606 -229.477062) (xy 332.91907 -229.324662) (xy 332.65745 -229.324662) (xy 332.61046 -229.477062)
			(xy 332.61046 -229.521512) (xy 332.96606 -229.521512)
		)
		(stroke
			(width 0)
			(type solid)
		)
		(fill yes)
		(layer "In6.Cu")
		(net "M_D_CPU0_SB_DQ<22>")
	)
	(gr_poly
		(pts
			(xy 332.966314 -240.46307) (xy 332.966314 -240.418874) (xy 332.610714 -240.418874) (xy 332.610714 -240.46307)
			(xy 332.657704 -240.61547) (xy 332.919324 -240.61547)
		)
		(stroke
			(width 0)
			(type solid)
		)
		(fill yes)
		(layer "In6.Cu")
		(net "M_C_CPU0_SB_DQ<5>")
	)
	(gr_poly
		(pts
			(xy 332.967838 -230.69677) (xy 332.967838 -230.65232) (xy 332.612238 -230.65232) (xy 332.612238 -230.69677)
			(xy 332.659228 -230.84917) (xy 332.920848 -230.84917)
		)
		(stroke
			(width 0)
			(type solid)
		)
		(fill yes)
		(layer "In6.Cu")
		(net "M_D_CPU0_SB_DQS_DN<7>")
	)
	(gr_poly
		(pts
			(xy 332.968092 -233.952542) (xy 332.968092 -233.908092) (xy 332.612492 -233.908092) (xy 332.612492 -233.952542)
			(xy 332.659482 -234.104942) (xy 332.921102 -234.104942)
		)
		(stroke
			(width 0)
			(type solid)
		)
		(fill yes)
		(layer "In6.Cu")
		(net "M_D_CPU0_SB_DQ<16>")
	)
	(gr_poly
		(pts
			(xy 332.97368 -244.127274) (xy 332.92669 -243.974874) (xy 332.66507 -243.974874) (xy 332.61808 -244.127274)
			(xy 332.61808 -244.17147) (xy 332.97368 -244.17147)
		)
		(stroke
			(width 0)
			(type solid)
		)
		(fill yes)
		(layer "In6.Cu")
		(net "M_C_CPU0_SB_DQ<2>")
	)
	(gr_poly
		(pts
			(xy 332.973934 -247.382538) (xy 332.926944 -247.230138) (xy 332.665324 -247.230138) (xy 332.618334 -247.382538)
			(xy 332.618334 -247.426988) (xy 332.973934 -247.426988)
		)
		(stroke
			(width 0)
			(type solid)
		)
		(fill yes)
		(layer "In6.Cu")
		(net "M_A_CPU0_SB_RSP<1>")
	)
	(gr_poly
		(pts
			(xy 332.973934 -245.754906) (xy 332.926944 -245.602506) (xy 332.665324 -245.602506) (xy 332.618334 -245.754906)
			(xy 332.618334 -245.799356) (xy 332.973934 -245.799356)
		)
		(stroke
			(width 0)
			(type solid)
		)
		(fill yes)
		(layer "In6.Cu")
		(net "M_D_CPU0_SB_CS_N<3>")
	)
	(gr_poly
		(pts
			(xy 332.973934 -235.988098) (xy 332.926944 -235.835698) (xy 332.665324 -235.835698) (xy 332.618334 -235.988098)
			(xy 332.618334 -236.032548) (xy 332.973934 -236.032548)
		)
		(stroke
			(width 0)
			(type solid)
		)
		(fill yes)
		(layer "In6.Cu")
		(net "M_C_CPU0_SB_DQS_DP<6>")
	)
	(gr_poly
		(pts
			(xy 332.973934 -231.104694) (xy 332.926944 -230.952294) (xy 332.665324 -230.952294) (xy 332.618334 -231.104694)
			(xy 332.618334 -231.149144) (xy 332.973934 -231.149144)
		)
		(stroke
			(width 0)
			(type solid)
		)
		(fill yes)
		(layer "In6.Cu")
		(net "M_D_CPU0_SB_DQS_DN<2>")
	)
	(gr_poly
		(pts
			(xy 332.973934 -229.06863) (xy 332.973934 -229.024434) (xy 332.618334 -229.024434) (xy 332.618334 -229.06863)
			(xy 332.665324 -229.22103) (xy 332.926944 -229.22103)
		)
		(stroke
			(width 0)
			(type solid)
		)
		(fill yes)
		(layer "In6.Cu")
		(net "M_D_CPU0_SB_DQ<21>")
	)
	(gr_poly
		(pts
			(xy 332.977236 -234.360466) (xy 332.930246 -234.208066) (xy 332.668626 -234.208066) (xy 332.621636 -234.360466)
			(xy 332.621636 -234.404916) (xy 332.977236 -234.404916)
		)
		(stroke
			(width 0)
			(type solid)
		)
		(fill yes)
		(layer "In6.Cu")
		(net "M_C_CPU0_SB_DQ<15>")
	)
	(gr_poly
		(pts
			(xy 332.977744 -264.873486) (xy 332.93939 -264.851388) (xy 332.783942 -264.815828) (xy 332.653132 -265.042396)
			(xy 332.76159 -265.159236) (xy 332.799944 -265.181334)
		)
		(stroke
			(width 0)
			(type solid)
		)
		(fill yes)
		(layer "In6.Cu")
		(net "M_C_CPU0_SA_DQS_DP<8>")
	)
	(gr_poly
		(pts
			(xy 332.979776 -235.580174) (xy 332.979776 -235.535724) (xy 332.624176 -235.535724) (xy 332.624176 -235.580174)
			(xy 332.671166 -235.732574) (xy 332.932786 -235.732574)
		)
		(stroke
			(width 0)
			(type solid)
		)
		(fill yes)
		(layer "In6.Cu")
		(net "M_C_CPU0_SB_DQ<12>")
	)
	(gr_poly
		(pts
			(xy 332.979776 -227.44049) (xy 332.979776 -227.396294) (xy 332.624176 -227.396294) (xy 332.624176 -227.44049)
			(xy 332.671166 -227.59289) (xy 332.932786 -227.59289)
		)
		(stroke
			(width 0)
			(type solid)
		)
		(fill yes)
		(layer "In6.Cu")
		(net "M_C_CPU0_SB_DQ<26>")
	)
	(gr_poly
		(pts
			(xy 332.98003 -224.185226) (xy 332.98003 -224.140776) (xy 332.62443 -224.140776) (xy 332.62443 -224.185226)
			(xy 332.67142 -224.337626) (xy 332.93304 -224.337626)
		)
		(stroke
			(width 0)
			(type solid)
		)
		(fill yes)
		(layer "In6.Cu")
		(net "M_C_CPU0_SB_DQ<28>")
	)
	(gr_poly
		(pts
			(xy 332.982316 -245.346474) (xy 332.982316 -245.302278) (xy 332.626716 -245.302278) (xy 332.626716 -245.346474)
			(xy 332.673706 -245.498874) (xy 332.935326 -245.498874)
		)
		(stroke
			(width 0)
			(type solid)
		)
		(fill yes)
		(layer "In6.Cu")
		(net "M_D_CPU0_SB_CS_N<0>")
	)
	(gr_poly
		(pts
			(xy 333.083662 -263.891014) (xy 333.036672 -263.738614) (xy 332.775052 -263.738614) (xy 332.728062 -263.891014)
			(xy 332.728062 -263.93521) (xy 333.083662 -263.93521)
		)
		(stroke
			(width 0)
			(type solid)
		)
		(fill yes)
		(layer "In6.Cu")
		(net "M_C_CPU0_SA_DQ<30>")
	)
	(gr_poly
		(pts
			(xy 333.083662 -263.482074) (xy 333.083662 -263.437878) (xy 332.728062 -263.437878) (xy 332.728062 -263.482074)
			(xy 332.775052 -263.634474) (xy 333.036672 -263.634474)
		)
		(stroke
			(width 0)
			(type solid)
		)
		(fill yes)
		(layer "In6.Cu")
		(net "M_C_CPU0_SA_DQ<29>")
	)
	(gr_poly
		(pts
			(xy 333.083662 -262.262874) (xy 333.036672 -262.110474) (xy 332.775052 -262.110474) (xy 332.728062 -262.262874)
			(xy 332.728062 -262.307324) (xy 333.083662 -262.307324)
		)
		(stroke
			(width 0)
			(type solid)
		)
		(fill yes)
		(layer "In6.Cu")
		(net "M_C_CPU0_SA_CB<0>")
	)
	(gr_poly
		(pts
			(xy 333.083662 -261.854442) (xy 333.083662 -261.809992) (xy 332.728062 -261.809992) (xy 332.728062 -261.854442)
			(xy 332.775052 -262.006842) (xy 333.036672 -262.006842)
		)
		(stroke
			(width 0)
			(type solid)
		)
		(fill yes)
		(layer "In6.Cu")
		(net "M_C_CPU0_SA_CB<3>")
	)
	(gr_poly
		(pts
			(xy 333.083662 -260.635242) (xy 333.036672 -260.482842) (xy 332.775052 -260.482842) (xy 332.728062 -260.635242)
			(xy 332.728062 -260.679438) (xy 333.083662 -260.679438)
		)
		(stroke
			(width 0)
			(type solid)
		)
		(fill yes)
		(layer "In6.Cu")
		(net "M_C_CPU0_SA_DQS_DP<9>")
	)
	(gr_poly
		(pts
			(xy 333.083662 -260.226302) (xy 333.083662 -260.182106) (xy 332.728062 -260.182106) (xy 332.728062 -260.226302)
			(xy 332.775052 -260.378702) (xy 333.036672 -260.378702)
		)
		(stroke
			(width 0)
			(type solid)
		)
		(fill yes)
		(layer "In6.Cu")
		(net "M_C_CPU0_SA_DQS_DP<4>")
	)
	(gr_poly
		(pts
			(xy 333.083662 -259.00761) (xy 333.036672 -258.85521) (xy 332.775052 -258.85521) (xy 332.728062 -259.00761)
			(xy 332.728062 -259.051806) (xy 333.083662 -259.051806)
		)
		(stroke
			(width 0)
			(type solid)
		)
		(fill yes)
		(layer "In6.Cu")
		(net "M_C_CPU0_SA_CB<4>")
	)
	(gr_poly
		(pts
			(xy 333.083662 -258.59867) (xy 333.083662 -258.554474) (xy 332.728062 -258.554474) (xy 332.728062 -258.59867)
			(xy 332.775052 -258.75107) (xy 333.036672 -258.75107)
		)
		(stroke
			(width 0)
			(type solid)
		)
		(fill yes)
		(layer "In6.Cu")
		(net "M_C_CPU0_SA_CB<7>")
	)
	(gr_poly
		(pts
			(xy 333.083662 -256.971038) (xy 333.083662 -256.926588) (xy 332.728062 -256.926588) (xy 332.728062 -256.971038)
			(xy 332.775052 -257.123438) (xy 333.036672 -257.123438)
		)
		(stroke
			(width 0)
			(type solid)
		)
		(fill yes)
		(layer "In6.Cu")
		(net "M_D_CPU0_SA_RSP<0>")
	)
	(gr_poly
		(pts
			(xy 333.083662 -255.751838) (xy 333.036672 -255.599438) (xy 332.775052 -255.599438) (xy 332.728062 -255.751838)
			(xy 332.728062 -255.796288) (xy 333.083662 -255.796288)
		)
		(stroke
			(width 0)
			(type solid)
		)
		(fill yes)
		(layer "In6.Cu")
		(net "M_D_CPU0_SB_RSP<1>")
	)
	(gr_poly
		(pts
			(xy 333.15656 -267.217652) (xy 333.048102 -267.100812) (xy 333.009748 -267.078714) (xy 332.831948 -267.386562)
			(xy 332.870302 -267.40866) (xy 333.02575 -267.44422)
		)
		(stroke
			(width 0)
			(type solid)
		)
		(fill yes)
		(layer "In6.Cu")
		(net "M_C_CPU0_SA_DQ<25>")
	)
	(gr_poly
		(pts
			(xy 333.300578 -232.179876) (xy 333.338932 -232.157778) (xy 333.161132 -231.84993) (xy 333.122778 -231.872028)
			(xy 333.01432 -231.988868) (xy 333.14513 -232.215436)
		)
		(stroke
			(width 0)
			(type solid)
		)
		(fill yes)
		(layer "In6.Cu")
		(net "M_D_CPU0_SB_DQS_DP<2>")
	)
	(gr_poly
		(pts
			(xy 333.408274 -231.555544) (xy 333.516732 -231.438704) (xy 333.385922 -231.212136) (xy 333.230474 -231.247696)
			(xy 333.19212 -231.269794) (xy 333.36992 -231.577642)
		)
		(stroke
			(width 0)
			(type solid)
		)
		(fill yes)
		(layer "In6.Cu")
		(net "M_D_CPU0_SB_DQS_DN<2>")
	)
	(gr_poly
		(pts
			(xy 333.414878 -238.077756) (xy 333.523336 -237.960916) (xy 333.392526 -237.734348) (xy 333.237078 -237.769908)
			(xy 333.198724 -237.792006) (xy 333.376524 -238.099854)
		)
		(stroke
			(width 0)
			(type solid)
		)
		(fill yes)
		(layer "In6.Cu")
		(net "M_C_CPU0_SB_DQ<11>")
	)
	(gr_poly
		(pts
			(xy 333.42961 -241.685318) (xy 333.38262 -241.532918) (xy 333.121 -241.532918) (xy 333.07401 -241.685318)
			(xy 333.07401 -241.729514) (xy 333.42961 -241.729514)
		)
		(stroke
			(width 0)
			(type solid)
		)
		(fill yes)
		(layer "In6.Cu")
		(net "M_C_CPU0_SB_DQS_DP<5>")
	)
	(gr_poly
		(pts
			(xy 333.435198 -244.940582) (xy 333.388208 -244.788182) (xy 333.126588 -244.788182) (xy 333.079598 -244.940582)
			(xy 333.079598 -244.985032) (xy 333.435198 -244.985032)
		)
		(stroke
			(width 0)
			(type solid)
		)
		(fill yes)
		(layer "In6.Cu")
		(net "M_D_CPU0_SB_CS_N<1>")
	)
	(gr_poly
		(pts
			(xy 333.435198 -241.276886) (xy 333.435198 -241.23269) (xy 333.079598 -241.23269) (xy 333.079598 -241.276886)
			(xy 333.126588 -241.429286) (xy 333.388208 -241.429286)
		)
		(stroke
			(width 0)
			(type solid)
		)
		(fill yes)
		(layer "In6.Cu")
		(net "M_C_CPU0_SB_DQ<4>")
	)
	(gr_poly
		(pts
			(xy 333.435198 -239.649254) (xy 333.435198 -239.604804) (xy 333.079598 -239.604804) (xy 333.079598 -239.649254)
			(xy 333.126588 -239.801654) (xy 333.388208 -239.801654)
		)
		(stroke
			(width 0)
			(type solid)
		)
		(fill yes)
		(layer "In6.Cu")
		(net "M_C_CPU0_SB_DQ<8>")
	)
	(gr_poly
		(pts
			(xy 333.435452 -236.39399) (xy 333.435452 -236.34954) (xy 333.079852 -236.34954) (xy 333.079852 -236.39399)
			(xy 333.126842 -236.54639) (xy 333.388462 -236.54639)
		)
		(stroke
			(width 0)
			(type solid)
		)
		(fill yes)
		(layer "In6.Cu")
		(net "M_C_CPU0_SB_DQS_DN<6>")
	)
	(gr_poly
		(pts
			(xy 333.437992 -235.174282) (xy 333.391002 -235.021882) (xy 333.129382 -235.021882) (xy 333.082392 -235.174282)
			(xy 333.082392 -235.218732) (xy 333.437992 -235.218732)
		)
		(stroke
			(width 0)
			(type solid)
		)
		(fill yes)
		(layer "In6.Cu")
		(net "M_C_CPU0_SB_DQ<14>")
	)
	(gr_poly
		(pts
			(xy 333.437992 -234.766358) (xy 333.437992 -234.721908) (xy 333.082392 -234.721908) (xy 333.082392 -234.766358)
			(xy 333.129382 -234.918758) (xy 333.391002 -234.918758)
		)
		(stroke
			(width 0)
			(type solid)
		)
		(fill yes)
		(layer "In6.Cu")
		(net "M_C_CPU0_SB_DQ<13>")
	)
	(gr_poly
		(pts
			(xy 333.44358 -244.53215) (xy 333.44358 -244.487954) (xy 333.08798 -244.487954) (xy 333.08798 -244.53215)
			(xy 333.13497 -244.68455) (xy 333.39659 -244.68455)
		)
		(stroke
			(width 0)
			(type solid)
		)
		(fill yes)
		(layer "In6.Cu")
		(net "M_C_CPU0_SB_DQ<0>")
	)
	(gr_poly
		(pts
			(xy 333.443834 -247.787922) (xy 333.443834 -247.743472) (xy 333.088234 -247.743472) (xy 333.088234 -247.787922)
			(xy 333.135224 -247.940322) (xy 333.396844 -247.940322)
		)
		(stroke
			(width 0)
			(type solid)
		)
		(fill yes)
		(layer "In6.Cu")
		(net "M_A_CPU0_SA_RSP<1>")
	)
	(gr_poly
		(pts
			(xy 333.443834 -246.16029) (xy 333.443834 -246.11584) (xy 333.088234 -246.11584) (xy 333.088234 -246.16029)
			(xy 333.135224 -246.31269) (xy 333.396844 -246.31269)
		)
		(stroke
			(width 0)
			(type solid)
		)
		(fill yes)
		(layer "In6.Cu")
		(net "M_D_CPU0_SB_CS_N<2>")
	)
	(gr_poly
		(pts
			(xy 333.443834 -230.291386) (xy 333.396844 -230.138986) (xy 333.135224 -230.138986) (xy 333.088234 -230.291386)
			(xy 333.088234 -230.335582) (xy 333.443834 -230.335582)
		)
		(stroke
			(width 0)
			(type solid)
		)
		(fill yes)
		(layer "In6.Cu")
		(net "M_D_CPU0_SB_DQS_DP<7>")
	)
	(gr_poly
		(pts
			(xy 333.443834 -229.882446) (xy 333.443834 -229.83825) (xy 333.088234 -229.83825) (xy 333.088234 -229.882446)
			(xy 333.135224 -230.034846) (xy 333.396844 -230.034846)
		)
		(stroke
			(width 0)
			(type solid)
		)
		(fill yes)
		(layer "In6.Cu")
		(net "M_D_CPU0_SB_DQ<20>")
	)
	(gr_poly
		(pts
			(xy 333.443834 -228.663754) (xy 333.396844 -228.511354) (xy 333.135224 -228.511354) (xy 333.088234 -228.663754)
			(xy 333.088234 -228.70795) (xy 333.443834 -228.70795)
		)
		(stroke
			(width 0)
			(type solid)
		)
		(fill yes)
		(layer "In6.Cu")
		(net "M_D_CPU0_SB_DQ<23>")
	)
	(gr_poly
		(pts
			(xy 333.448406 -240.057178) (xy 333.401416 -239.904778) (xy 333.139796 -239.904778) (xy 333.092806 -240.057178)
			(xy 333.092806 -240.101628) (xy 333.448406 -240.101628)
		)
		(stroke
			(width 0)
			(type solid)
		)
		(fill yes)
		(layer "In6.Cu")
		(net "M_C_CPU0_SB_DQ<7>")
	)
	(gr_poly
		(pts
			(xy 333.449168 -233.54665) (xy 333.402178 -233.39425) (xy 333.140558 -233.39425) (xy 333.093568 -233.54665)
			(xy 333.093568 -233.5911) (xy 333.449168 -233.5911)
		)
		(stroke
			(width 0)
			(type solid)
		)
		(fill yes)
		(layer "In6.Cu")
		(net "M_D_CPU0_SB_DQ<18>")
	)
	(gr_poly
		(pts
			(xy 333.449676 -267.311124) (xy 333.411322 -267.289026) (xy 333.255874 -267.253466) (xy 333.125064 -267.480034)
			(xy 333.233522 -267.596874) (xy 333.271876 -267.618972)
		)
		(stroke
			(width 0)
			(type solid)
		)
		(fill yes)
		(layer "In6.Cu")
		(net "M_C_CPU0_SA_DQ<26>")
	)
	(gr_poly
		(pts
			(xy 333.449676 -233.138218) (xy 333.449676 -233.093768) (xy 333.094076 -233.093768) (xy 333.094076 -233.138218)
			(xy 333.141066 -233.290618) (xy 333.402686 -233.290618)
		)
		(stroke
			(width 0)
			(type solid)
		)
		(fill yes)
		(layer "In6.Cu")
		(net "M_D_CPU0_SB_DQ<17>")
	)
	(gr_poly
		(pts
			(xy 333.449676 -227.035106) (xy 333.402686 -226.882706) (xy 333.141066 -226.882706) (xy 333.094076 -227.035106)
			(xy 333.094076 -227.079556) (xy 333.449676 -227.079556)
		)
		(stroke
			(width 0)
			(type solid)
		)
		(fill yes)
		(layer "In6.Cu")
		(net "M_C_CPU0_SB_DQ<24>")
	)
	(gr_poly
		(pts
			(xy 333.449676 -226.627182) (xy 333.449676 -226.582732) (xy 333.094076 -226.582732) (xy 333.094076 -226.627182)
			(xy 333.141066 -226.779582) (xy 333.402686 -226.779582)
		)
		(stroke
			(width 0)
			(type solid)
		)
		(fill yes)
		(layer "In6.Cu")
		(net "M_C_CPU0_SB_DQ<25>")
	)
	(gr_poly
		(pts
			(xy 333.452216 -243.31295) (xy 333.405226 -243.16055) (xy 333.143606 -243.16055) (xy 333.096616 -243.31295)
			(xy 333.096616 -243.3574) (xy 333.452216 -243.3574)
		)
		(stroke
			(width 0)
			(type solid)
		)
		(fill yes)
		(layer "In6.Cu")
		(net "M_C_CPU0_SB_DQ<3>")
	)
	(gr_poly
		(pts
			(xy 333.452216 -242.905026) (xy 333.452216 -242.860576) (xy 333.096616 -242.860576) (xy 333.096616 -242.905026)
			(xy 333.143606 -243.057426) (xy 333.405226 -243.057426)
		)
		(stroke
			(width 0)
			(type solid)
		)
		(fill yes)
		(layer "In6.Cu")
		(net "M_C_CPU0_SB_DQS_DP<0>")
	)
	(gr_poly
		(pts
			(xy 333.452216 -236.801914) (xy 333.405226 -236.649514) (xy 333.143606 -236.649514) (xy 333.096616 -236.801914)
			(xy 333.096616 -236.846364) (xy 333.452216 -236.846364)
		)
		(stroke
			(width 0)
			(type solid)
		)
		(fill yes)
		(layer "In6.Cu")
		(net "M_C_CPU0_SB_DQS_DN<1>")
	)
	(gr_poly
		(pts
			(xy 333.452216 -225.407474) (xy 333.405226 -225.255074) (xy 333.143606 -225.255074) (xy 333.096616 -225.407474)
			(xy 333.096616 -225.45167) (xy 333.452216 -225.45167)
		)
		(stroke
			(width 0)
			(type solid)
		)
		(fill yes)
		(layer "In6.Cu")
		(net "M_C_CPU0_SB_DQS_DN<3>")
	)
	(gr_poly
		(pts
			(xy 333.452216 -224.999042) (xy 333.452216 -224.954846) (xy 333.096616 -224.954846) (xy 333.096616 -224.999042)
			(xy 333.143606 -225.151442) (xy 333.405226 -225.151442)
		)
		(stroke
			(width 0)
			(type solid)
		)
		(fill yes)
		(layer "In6.Cu")
		(net "M_C_CPU0_SB_DQS_DN<8>")
	)
	(gr_poly
		(pts
			(xy 333.452216 -223.779842) (xy 333.405226 -223.627442) (xy 333.143606 -223.627442) (xy 333.096616 -223.779842)
			(xy 333.096616 -223.824038) (xy 333.452216 -223.824038)
		)
		(stroke
			(width 0)
			(type solid)
		)
		(fill yes)
		(layer "In6.Cu")
		(net "M_C_CPU0_SB_DQ<30>")
	)
	(gr_poly
		(pts
			(xy 333.452216 -223.37141) (xy 333.452216 -223.327214) (xy 333.096616 -223.327214) (xy 333.096616 -223.37141)
			(xy 333.143606 -223.52381) (xy 333.405226 -223.52381)
		)
		(stroke
			(width 0)
			(type solid)
		)
		(fill yes)
		(layer "In6.Cu")
		(net "M_C_CPU0_SB_DQ<31>")
	)
	(gr_poly
		(pts
			(xy 333.54772 -272.843498) (xy 333.50073 -272.691098) (xy 333.23911 -272.691098) (xy 333.19212 -272.843498)
			(xy 333.19212 -272.887948) (xy 333.54772 -272.887948)
		)
		(stroke
			(width 0)
			(type solid)
		)
		(fill yes)
		(layer "In6.Cu")
		(net "M_C_CPU0_SA_DQ<11>")
	)
	(gr_poly
		(pts
			(xy 333.553562 -264.70483) (xy 333.506572 -264.55243) (xy 333.244952 -264.55243) (xy 333.197962 -264.70483)
			(xy 333.197962 -264.749026) (xy 333.553562 -264.749026)
		)
		(stroke
			(width 0)
			(type solid)
		)
		(fill yes)
		(layer "In6.Cu")
		(net "M_C_CPU0_SA_DQS_DP<8>")
	)
	(gr_poly
		(pts
			(xy 333.553562 -264.29589) (xy 333.553562 -264.251694) (xy 333.197962 -264.251694) (xy 333.197962 -264.29589)
			(xy 333.244952 -264.44829) (xy 333.506572 -264.44829)
		)
		(stroke
			(width 0)
			(type solid)
		)
		(fill yes)
		(layer "In6.Cu")
		(net "M_C_CPU0_SA_DQ<28>")
	)
	(gr_poly
		(pts
			(xy 333.553562 -263.07669) (xy 333.506572 -262.92429) (xy 333.244952 -262.92429) (xy 333.197962 -263.07669)
			(xy 333.197962 -263.12114) (xy 333.553562 -263.12114)
		)
		(stroke
			(width 0)
			(type solid)
		)
		(fill yes)
		(layer "In6.Cu")
		(net "M_C_CPU0_SA_DQ<31>")
	)
	(gr_poly
		(pts
			(xy 333.553562 -262.668258) (xy 333.553562 -262.623808) (xy 333.197962 -262.623808) (xy 333.197962 -262.668258)
			(xy 333.244952 -262.820658) (xy 333.506572 -262.820658)
		)
		(stroke
			(width 0)
			(type solid)
		)
		(fill yes)
		(layer "In6.Cu")
		(net "M_C_CPU0_SA_CB<2>")
	)
	(gr_poly
		(pts
			(xy 333.553562 -261.449058) (xy 333.506572 -261.296658) (xy 333.244952 -261.296658) (xy 333.197962 -261.449058)
			(xy 333.197962 -261.493508) (xy 333.553562 -261.493508)
		)
		(stroke
			(width 0)
			(type solid)
		)
		(fill yes)
		(layer "In6.Cu")
		(net "M_C_CPU0_SA_CB<1>")
	)
	(gr_poly
		(pts
			(xy 333.553562 -261.040626) (xy 333.553562 -260.996176) (xy 333.197962 -260.996176) (xy 333.197962 -261.040626)
			(xy 333.244952 -261.193026) (xy 333.506572 -261.193026)
		)
		(stroke
			(width 0)
			(type solid)
		)
		(fill yes)
		(layer "In6.Cu")
		(net "M_C_CPU0_SA_DQS_DN<9>")
	)
	(gr_poly
		(pts
			(xy 333.553562 -259.821426) (xy 333.506572 -259.669026) (xy 333.244952 -259.669026) (xy 333.197962 -259.821426)
			(xy 333.197962 -259.865622) (xy 333.553562 -259.865622)
		)
		(stroke
			(width 0)
			(type solid)
		)
		(fill yes)
		(layer "In6.Cu")
		(net "M_C_CPU0_SA_DQS_DN<4>")
	)
	(gr_poly
		(pts
			(xy 333.553562 -259.412486) (xy 333.553562 -259.36829) (xy 333.197962 -259.36829) (xy 333.197962 -259.412486)
			(xy 333.244952 -259.564886) (xy 333.506572 -259.564886)
		)
		(stroke
			(width 0)
			(type solid)
		)
		(fill yes)
		(layer "In6.Cu")
		(net "M_C_CPU0_SA_CB<6>")
	)
	(gr_poly
		(pts
			(xy 333.553562 -258.193286) (xy 333.506572 -258.040886) (xy 333.244952 -258.040886) (xy 333.197962 -258.193286)
			(xy 333.197962 -258.237736) (xy 333.553562 -258.237736)
		)
		(stroke
			(width 0)
			(type solid)
		)
		(fill yes)
		(layer "In6.Cu")
		(net "M_C_CPU0_SA_CB<5>")
	)
	(gr_poly
		(pts
			(xy 333.553562 -256.565654) (xy 333.506572 -256.413254) (xy 333.244952 -256.413254) (xy 333.197962 -256.565654)
			(xy 333.197962 -256.610104) (xy 333.553562 -256.610104)
		)
		(stroke
			(width 0)
			(type solid)
		)
		(fill yes)
		(layer "In6.Cu")
		(net "M_D_CPU0_SB_RSP<0>")
	)
	(gr_poly
		(pts
			(xy 333.553562 -256.157222) (xy 333.553562 -256.112772) (xy 333.197962 -256.112772) (xy 333.197962 -256.157222)
			(xy 333.244952 -256.309622) (xy 333.506572 -256.309622)
		)
		(stroke
			(width 0)
			(type solid)
		)
		(fill yes)
		(layer "In6.Cu")
		(net "M_D_CPU0_SA_RSP<1>")
	)
	(gr_poly
		(pts
			(xy 333.628492 -271.283176) (xy 333.520034 -271.166336) (xy 333.48168 -271.144238) (xy 333.30388 -271.452086)
			(xy 333.342234 -271.474184) (xy 333.497682 -271.509744)
		)
		(stroke
			(width 0)
			(type solid)
		)
		(fill yes)
		(layer "In6.Cu")
		(net "M_C_CPU0_SA_DQS_DN<6>")
	)
	(gr_poly
		(pts
			(xy 333.628492 -268.027658) (xy 333.520034 -267.910818) (xy 333.48168 -267.88872) (xy 333.30388 -268.196568)
			(xy 333.342234 -268.218666) (xy 333.497682 -268.254226)
		)
		(stroke
			(width 0)
			(type solid)
		)
		(fill yes)
		(layer "In6.Cu")
		(net "M_C_CPU0_SA_DQ<24>")
	)
	(gr_poly
		(pts
			(xy 333.762096 -237.862364) (xy 333.80045 -237.840266) (xy 333.62265 -237.532418) (xy 333.584296 -237.554516)
			(xy 333.475838 -237.671356) (xy 333.606648 -237.897924)
		)
		(stroke
			(width 0)
			(type solid)
		)
		(fill yes)
		(layer "In6.Cu")
		(net "M_C_CPU0_SB_DQS_DP<1>")
	)
	(gr_poly
		(pts
			(xy 333.769462 -231.36352) (xy 333.807816 -231.341422) (xy 333.630016 -231.033574) (xy 333.591662 -231.055672)
			(xy 333.483204 -231.172512) (xy 333.614014 -231.39908)
		)
		(stroke
			(width 0)
			(type solid)
		)
		(fill yes)
		(layer "In6.Cu")
		(net "M_D_CPU0_SB_DQS_DN<7>")
	)
	(gr_poly
		(pts
			(xy 333.880206 -230.745792) (xy 333.988664 -230.628952) (xy 333.857854 -230.402384) (xy 333.702406 -230.437944)
			(xy 333.664052 -230.460042) (xy 333.841852 -230.76789)
		)
		(stroke
			(width 0)
			(type solid)
		)
		(fill yes)
		(layer "In6.Cu")
		(net "M_D_CPU0_SB_DQS_DP<7>")
	)
	(gr_poly
		(pts
			(xy 333.887318 -237.26902) (xy 333.995776 -237.15218) (xy 333.864966 -236.925612) (xy 333.709518 -236.961172)
			(xy 333.671164 -236.98327) (xy 333.848964 -237.291118)
		)
		(stroke
			(width 0)
			(type solid)
		)
		(fill yes)
		(layer "In6.Cu")
		(net "M_C_CPU0_SB_DQS_DN<1>")
	)
	(gr_poly
		(pts
			(xy 333.905098 -243.718842) (xy 333.905098 -243.674392) (xy 333.549498 -243.674392) (xy 333.549498 -243.718842)
			(xy 333.596488 -243.871242) (xy 333.858108 -243.871242)
		)
		(stroke
			(width 0)
			(type solid)
		)
		(fill yes)
		(layer "In6.Cu")
		(net "M_C_CPU0_SB_DQ<1>")
	)
	(gr_poly
		(pts
			(xy 333.905352 -238.835438) (xy 333.905352 -238.790988) (xy 333.549752 -238.790988) (xy 333.549752 -238.835438)
			(xy 333.596742 -238.987838) (xy 333.858362 -238.987838)
		)
		(stroke
			(width 0)
			(type solid)
		)
		(fill yes)
		(layer "In6.Cu")
		(net "M_C_CPU0_SB_DQ<9>")
	)
	(gr_poly
		(pts
			(xy 333.906368 -240.46307) (xy 333.906368 -240.418874) (xy 333.550768 -240.418874) (xy 333.550768 -240.46307)
			(xy 333.597758 -240.61547) (xy 333.859378 -240.61547)
		)
		(stroke
			(width 0)
			(type solid)
		)
		(fill yes)
		(layer "In6.Cu")
		(net "M_C_CPU0_SB_DQ<5>")
	)
	(gr_poly
		(pts
			(xy 333.907638 -242.499134) (xy 333.860648 -242.346734) (xy 333.599028 -242.346734) (xy 333.552038 -242.499134)
			(xy 333.552038 -242.54333) (xy 333.907638 -242.54333)
		)
		(stroke
			(width 0)
			(type solid)
		)
		(fill yes)
		(layer "In6.Cu")
		(net "M_C_CPU0_SB_DQS_DN<0>")
	)
	(gr_poly
		(pts
			(xy 333.907638 -232.324402) (xy 333.907638 -232.279952) (xy 333.552038 -232.279952) (xy 333.552038 -232.324402)
			(xy 333.599028 -232.476802) (xy 333.860648 -232.476802)
		)
		(stroke
			(width 0)
			(type solid)
		)
		(fill yes)
		(layer "In6.Cu")
		(net "M_D_CPU0_SB_DQS_DP<2>")
	)
	(gr_poly
		(pts
			(xy 333.907638 -227.440998) (xy 333.907638 -227.396548) (xy 333.552038 -227.396548) (xy 333.552038 -227.440998)
			(xy 333.599028 -227.593398) (xy 333.860648 -227.593398)
		)
		(stroke
			(width 0)
			(type solid)
		)
		(fill yes)
		(layer "In6.Cu")
		(net "M_C_CPU0_SB_DQ<26>")
	)
	(gr_poly
		(pts
			(xy 333.907638 -226.22129) (xy 333.860648 -226.06889) (xy 333.599028 -226.06889) (xy 333.552038 -226.22129)
			(xy 333.552038 -226.26574) (xy 333.907638 -226.26574)
		)
		(stroke
			(width 0)
			(type solid)
		)
		(fill yes)
		(layer "In6.Cu")
		(net "M_C_CPU0_SB_DQ<27>")
	)
	(gr_poly
		(pts
			(xy 333.907638 -225.813366) (xy 333.907638 -225.768916) (xy 333.552038 -225.768916) (xy 333.552038 -225.813366)
			(xy 333.599028 -225.965766) (xy 333.860648 -225.965766)
		)
		(stroke
			(width 0)
			(type solid)
		)
		(fill yes)
		(layer "In6.Cu")
		(net "M_C_CPU0_SB_DQS_DP<3>")
	)
	(gr_poly
		(pts
			(xy 333.907638 -224.593658) (xy 333.860648 -224.441258) (xy 333.599028 -224.441258) (xy 333.552038 -224.593658)
			(xy 333.552038 -224.637854) (xy 333.907638 -224.637854)
		)
		(stroke
			(width 0)
			(type solid)
		)
		(fill yes)
		(layer "In6.Cu")
		(net "M_C_CPU0_SB_DQS_DP<8>")
	)
	(gr_poly
		(pts
			(xy 333.907638 -224.185226) (xy 333.907638 -224.14103) (xy 333.552038 -224.14103) (xy 333.552038 -224.185226)
			(xy 333.599028 -224.337626) (xy 333.860648 -224.337626)
		)
		(stroke
			(width 0)
			(type solid)
		)
		(fill yes)
		(layer "In6.Cu")
		(net "M_C_CPU0_SB_DQ<28>")
	)
	(gr_poly
		(pts
			(xy 333.907638 -222.965518) (xy 333.860648 -222.813118) (xy 333.599028 -222.813118) (xy 333.552038 -222.965518)
			(xy 333.552038 -223.009968) (xy 333.907638 -223.009968)
		)
		(stroke
			(width 0)
			(type solid)
		)
		(fill yes)
		(layer "In6.Cu")
		(net "M_C_CPU0_SB_DQ<29>")
	)
	(gr_poly
		(pts
			(xy 333.9084 -233.952034) (xy 333.9084 -233.907838) (xy 333.5528 -233.907838) (xy 333.5528 -233.952034)
			(xy 333.59979 -234.104434) (xy 333.86141 -234.104434)
		)
		(stroke
			(width 0)
			(type solid)
		)
		(fill yes)
		(layer "In6.Cu")
		(net "M_D_CPU0_SB_DQ<16>")
	)
	(gr_poly
		(pts
			(xy 333.912972 -274.647152) (xy 333.874618 -274.625054) (xy 333.71917 -274.589494) (xy 333.58836 -274.816062)
			(xy 333.696818 -274.932902) (xy 333.735172 -274.955)
		)
		(stroke
			(width 0)
			(type solid)
		)
		(fill yes)
		(layer "In6.Cu")
		(net "M_D_CPU0_SA_DQ<7>")
	)
	(gr_poly
		(pts
			(xy 333.91348 -244.127274) (xy 333.86649 -243.974874) (xy 333.60487 -243.974874) (xy 333.55788 -244.127274)
			(xy 333.55788 -244.17147) (xy 333.91348 -244.17147)
		)
		(stroke
			(width 0)
			(type solid)
		)
		(fill yes)
		(layer "In6.Cu")
		(net "M_C_CPU0_SB_DQ<2>")
	)
	(gr_poly
		(pts
			(xy 333.913734 -247.382538) (xy 333.866744 -247.230138) (xy 333.605124 -247.230138) (xy 333.558134 -247.382538)
			(xy 333.558134 -247.426988) (xy 333.913734 -247.426988)
		)
		(stroke
			(width 0)
			(type solid)
		)
		(fill yes)
		(layer "In6.Cu")
		(net "M_A_CPU0_SB_RSP<1>")
	)
	(gr_poly
		(pts
			(xy 333.913734 -245.754906) (xy 333.866744 -245.602506) (xy 333.605124 -245.602506) (xy 333.558134 -245.754906)
			(xy 333.558134 -245.799356) (xy 333.913734 -245.799356)
		)
		(stroke
			(width 0)
			(type solid)
		)
		(fill yes)
		(layer "In6.Cu")
		(net "M_D_CPU0_SB_CS_N<3>")
	)
	(gr_poly
		(pts
			(xy 333.913734 -229.47757) (xy 333.866744 -229.32517) (xy 333.605124 -229.32517) (xy 333.558134 -229.47757)
			(xy 333.558134 -229.521766) (xy 333.913734 -229.521766)
		)
		(stroke
			(width 0)
			(type solid)
		)
		(fill yes)
		(layer "In6.Cu")
		(net "M_D_CPU0_SB_DQ<22>")
	)
	(gr_poly
		(pts
			(xy 333.913734 -229.06863) (xy 333.913734 -229.024434) (xy 333.558134 -229.024434) (xy 333.558134 -229.06863)
			(xy 333.605124 -229.22103) (xy 333.866744 -229.22103)
		)
		(stroke
			(width 0)
			(type solid)
		)
		(fill yes)
		(layer "In6.Cu")
		(net "M_D_CPU0_SB_DQ<21>")
	)
	(gr_poly
		(pts
			(xy 333.913988 -235.579666) (xy 333.913988 -235.53547) (xy 333.558388 -235.53547) (xy 333.558388 -235.579666)
			(xy 333.605378 -235.732066) (xy 333.866998 -235.732066)
		)
		(stroke
			(width 0)
			(type solid)
		)
		(fill yes)
		(layer "In6.Cu")
		(net "M_C_CPU0_SB_DQ<12>")
	)
	(gr_poly
		(pts
			(xy 333.917544 -279.523444) (xy 333.87919 -279.501346) (xy 333.723742 -279.465786) (xy 333.592932 -279.692354)
			(xy 333.70139 -279.809194) (xy 333.739744 -279.831292)
		)
		(stroke
			(width 0)
			(type solid)
		)
		(fill yes)
		(layer "In6.Cu")
		(net "M_D_CPU0_SA_DQ<3>")
	)
	(gr_poly
		(pts
			(xy 333.917544 -268.129004) (xy 333.87919 -268.106906) (xy 333.723742 -268.071346) (xy 333.592932 -268.297914)
			(xy 333.70139 -268.414754) (xy 333.739744 -268.436852)
		)
		(stroke
			(width 0)
			(type solid)
		)
		(fill yes)
		(layer "In6.Cu")
		(net "M_C_CPU0_SA_DQ<15>")
	)
	(gr_poly
		(pts
			(xy 333.91856 -271.382744) (xy 333.880206 -271.360646) (xy 333.724758 -271.325086) (xy 333.593948 -271.551654)
			(xy 333.702406 -271.668494) (xy 333.74076 -271.690592)
		)
		(stroke
			(width 0)
			(type solid)
		)
		(fill yes)
		(layer "In6.Cu")
		(net "M_C_CPU0_SA_DQS_DN<1>")
	)
	(gr_poly
		(pts
			(xy 333.919068 -234.360466) (xy 333.872078 -234.208066) (xy 333.610458 -234.208066) (xy 333.563468 -234.360466)
			(xy 333.563468 -234.404916) (xy 333.919068 -234.404916)
		)
		(stroke
			(width 0)
			(type solid)
		)
		(fill yes)
		(layer "In6.Cu")
		(net "M_C_CPU0_SB_DQ<15>")
	)
	(gr_poly
		(pts
			(xy 333.919576 -232.732326) (xy 333.872586 -232.579926) (xy 333.610966 -232.579926) (xy 333.563976 -232.732326)
			(xy 333.563976 -232.776776) (xy 333.919576 -232.776776)
		)
		(stroke
			(width 0)
			(type solid)
		)
		(fill yes)
		(layer "In6.Cu")
		(net "M_D_CPU0_SB_DQ<19>")
	)
	(gr_poly
		(pts
			(xy 333.921608 -242.090702) (xy 333.921608 -242.046506) (xy 333.566008 -242.046506) (xy 333.566008 -242.090702)
			(xy 333.612998 -242.243102) (xy 333.874618 -242.243102)
		)
		(stroke
			(width 0)
			(type solid)
		)
		(fill yes)
		(layer "In6.Cu")
		(net "M_C_CPU0_SB_DQS_DN<5>")
	)
	(gr_poly
		(pts
			(xy 333.922116 -249.01017) (xy 333.875126 -248.85777) (xy 333.613506 -248.85777) (xy 333.566516 -249.01017)
			(xy 333.566516 -249.05462) (xy 333.922116 -249.05462)
		)
		(stroke
			(width 0)
			(type solid)
		)
		(fill yes)
		(layer "In6.Cu")
		(net "M_A_CPU0_SA_RSP<0>")
	)
	(gr_poly
		(pts
			(xy 333.922116 -245.346474) (xy 333.922116 -245.302278) (xy 333.566516 -245.302278) (xy 333.566516 -245.346474)
			(xy 333.613506 -245.498874) (xy 333.875126 -245.498874)
		)
		(stroke
			(width 0)
			(type solid)
		)
		(fill yes)
		(layer "In6.Cu")
		(net "M_D_CPU0_SB_CS_N<0>")
	)
	(gr_poly
		(pts
			(xy 333.922116 -240.871502) (xy 333.875126 -240.719102) (xy 333.613506 -240.719102) (xy 333.566516 -240.871502)
			(xy 333.566516 -240.915698) (xy 333.922116 -240.915698)
		)
		(stroke
			(width 0)
			(type solid)
		)
		(fill yes)
		(layer "In6.Cu")
		(net "M_C_CPU0_SB_DQ<6>")
	)
	(gr_poly
		(pts
			(xy 333.922116 -239.243362) (xy 333.875126 -239.090962) (xy 333.613506 -239.090962) (xy 333.566516 -239.243362)
			(xy 333.566516 -239.287812) (xy 333.922116 -239.287812)
		)
		(stroke
			(width 0)
			(type solid)
		)
		(fill yes)
		(layer "In6.Cu")
		(net "M_C_CPU0_SB_DQ<10>")
	)
	(gr_poly
		(pts
			(xy 333.92237 -235.988098) (xy 333.87538 -235.835698) (xy 333.61376 -235.835698) (xy 333.56677 -235.988098)
			(xy 333.56677 -236.032548) (xy 333.92237 -236.032548)
		)
		(stroke
			(width 0)
			(type solid)
		)
		(fill yes)
		(layer "In6.Cu")
		(net "M_C_CPU0_SB_DQS_DP<6>")
	)
	(gr_poly
		(pts
			(xy 334.023462 -267.146278) (xy 333.976472 -266.993878) (xy 333.714852 -266.993878) (xy 333.667862 -267.146278)
			(xy 333.667862 -267.190474) (xy 334.023462 -267.190474)
		)
		(stroke
			(width 0)
			(type solid)
		)
		(fill yes)
		(layer "In6.Cu")
		(net "M_C_CPU0_SA_DQ<26>")
	)
	(gr_poly
		(pts
			(xy 334.023462 -266.737846) (xy 334.023462 -266.693396) (xy 333.667862 -266.693396) (xy 333.667862 -266.737846)
			(xy 333.714852 -266.890246) (xy 333.976472 -266.890246)
		)
		(stroke
			(width 0)
			(type solid)
		)
		(fill yes)
		(layer "In6.Cu")
		(net "M_C_CPU0_SA_DQ<25>")
	)
	(gr_poly
		(pts
			(xy 334.023462 -265.518646) (xy 333.976472 -265.366246) (xy 333.714852 -265.366246) (xy 333.667862 -265.518646)
			(xy 333.667862 -265.562842) (xy 334.023462 -265.562842)
		)
		(stroke
			(width 0)
			(type solid)
		)
		(fill yes)
		(layer "In6.Cu")
		(net "M_C_CPU0_SA_DQS_DN<3>")
	)
	(gr_poly
		(pts
			(xy 334.023462 -265.109706) (xy 334.023462 -265.06551) (xy 333.667862 -265.06551) (xy 333.667862 -265.109706)
			(xy 333.714852 -265.262106) (xy 333.976472 -265.262106)
		)
		(stroke
			(width 0)
			(type solid)
		)
		(fill yes)
		(layer "In6.Cu")
		(net "M_C_CPU0_SA_DQS_DN<8>")
	)
	(gr_poly
		(pts
			(xy 334.023462 -263.891014) (xy 333.976472 -263.738614) (xy 333.714852 -263.738614) (xy 333.667862 -263.891014)
			(xy 333.667862 -263.93521) (xy 334.023462 -263.93521)
		)
		(stroke
			(width 0)
			(type solid)
		)
		(fill yes)
		(layer "In6.Cu")
		(net "M_C_CPU0_SA_DQ<30>")
	)
	(gr_poly
		(pts
			(xy 334.023462 -263.482074) (xy 334.023462 -263.437878) (xy 333.667862 -263.437878) (xy 333.667862 -263.482074)
			(xy 333.714852 -263.634474) (xy 333.976472 -263.634474)
		)
		(stroke
			(width 0)
			(type solid)
		)
		(fill yes)
		(layer "In6.Cu")
		(net "M_C_CPU0_SA_DQ<29>")
	)
	(gr_poly
		(pts
			(xy 334.023462 -262.262874) (xy 333.976472 -262.110474) (xy 333.714852 -262.110474) (xy 333.667862 -262.262874)
			(xy 333.667862 -262.307324) (xy 334.023462 -262.307324)
		)
		(stroke
			(width 0)
			(type solid)
		)
		(fill yes)
		(layer "In6.Cu")
		(net "M_C_CPU0_SA_CB<0>")
	)
	(gr_poly
		(pts
			(xy 334.023462 -261.854442) (xy 334.023462 -261.809992) (xy 333.667862 -261.809992) (xy 333.667862 -261.854442)
			(xy 333.714852 -262.006842) (xy 333.976472 -262.006842)
		)
		(stroke
			(width 0)
			(type solid)
		)
		(fill yes)
		(layer "In6.Cu")
		(net "M_C_CPU0_SA_CB<3>")
	)
	(gr_poly
		(pts
			(xy 334.023462 -260.635242) (xy 333.976472 -260.482842) (xy 333.714852 -260.482842) (xy 333.667862 -260.635242)
			(xy 333.667862 -260.679438) (xy 334.023462 -260.679438)
		)
		(stroke
			(width 0)
			(type solid)
		)
		(fill yes)
		(layer "In6.Cu")
		(net "M_C_CPU0_SA_DQS_DP<9>")
	)
	(gr_poly
		(pts
			(xy 334.023462 -260.226302) (xy 334.023462 -260.182106) (xy 333.667862 -260.182106) (xy 333.667862 -260.226302)
			(xy 333.714852 -260.378702) (xy 333.976472 -260.378702)
		)
		(stroke
			(width 0)
			(type solid)
		)
		(fill yes)
		(layer "In6.Cu")
		(net "M_C_CPU0_SA_DQS_DP<4>")
	)
	(gr_poly
		(pts
			(xy 334.023462 -259.00761) (xy 333.976472 -258.85521) (xy 333.714852 -258.85521) (xy 333.667862 -259.00761)
			(xy 333.667862 -259.051806) (xy 334.023462 -259.051806)
		)
		(stroke
			(width 0)
			(type solid)
		)
		(fill yes)
		(layer "In6.Cu")
		(net "M_C_CPU0_SA_CB<4>")
	)
	(gr_poly
		(pts
			(xy 334.023462 -258.59867) (xy 334.023462 -258.554474) (xy 333.667862 -258.554474) (xy 333.667862 -258.59867)
			(xy 333.714852 -258.75107) (xy 333.976472 -258.75107)
		)
		(stroke
			(width 0)
			(type solid)
		)
		(fill yes)
		(layer "In6.Cu")
		(net "M_C_CPU0_SA_CB<7>")
	)
	(gr_poly
		(pts
			(xy 334.023462 -256.971038) (xy 334.023462 -256.926588) (xy 333.667862 -256.926588) (xy 333.667862 -256.971038)
			(xy 333.714852 -257.123438) (xy 333.976472 -257.123438)
		)
		(stroke
			(width 0)
			(type solid)
		)
		(fill yes)
		(layer "In6.Cu")
		(net "M_D_CPU0_SA_RSP<0>")
	)
	(gr_poly
		(pts
			(xy 334.023462 -255.751838) (xy 333.976472 -255.599438) (xy 333.714852 -255.599438) (xy 333.667862 -255.751838)
			(xy 333.667862 -255.796288) (xy 334.023462 -255.796288)
		)
		(stroke
			(width 0)
			(type solid)
		)
		(fill yes)
		(layer "In6.Cu")
		(net "M_D_CPU0_SB_RSP<1>")
	)
	(gr_poly
		(pts
			(xy 334.023462 -255.343406) (xy 334.023462 -255.298956) (xy 333.667862 -255.298956) (xy 333.667862 -255.343406)
			(xy 333.714852 -255.495806) (xy 333.976472 -255.495806)
		)
		(stroke
			(width 0)
			(type solid)
		)
		(fill yes)
		(layer "In6.Cu")
		(net "M_C_CPU0_SA_RSP<0>")
	)
	(gr_poly
		(pts
			(xy 334.031844 -276.5044) (xy 334.031844 -276.460204) (xy 333.676244 -276.460204) (xy 333.676244 -276.5044)
			(xy 333.723234 -276.6568) (xy 333.984854 -276.6568)
		)
		(stroke
			(width 0)
			(type solid)
		)
		(fill yes)
		(layer "In6.Cu")
		(net "M_D_CPU0_SA_DQ<4>")
	)
	(gr_poly
		(pts
			(xy 334.032098 -273.657314) (xy 333.985108 -273.504914) (xy 333.723488 -273.504914) (xy 333.676498 -273.657314)
			(xy 333.676498 -273.70151) (xy 334.032098 -273.70151)
		)
		(stroke
			(width 0)
			(type solid)
		)
		(fill yes)
		(layer "In6.Cu")
		(net "M_C_CPU0_SA_DQ<10>")
	)
	(gr_poly
		(pts
			(xy 334.032098 -273.248882) (xy 334.032098 -273.204686) (xy 333.676498 -273.204686) (xy 333.676498 -273.248882)
			(xy 333.723488 -273.401282) (xy 333.985108 -273.401282)
		)
		(stroke
			(width 0)
			(type solid)
		)
		(fill yes)
		(layer "In6.Cu")
		(net "M_C_CPU0_SA_DQ<9>")
	)
	(gr_poly
		(pts
			(xy 334.096106 -275.356574) (xy 333.987648 -275.239734) (xy 333.949294 -275.217636) (xy 333.771494 -275.525484)
			(xy 333.809848 -275.547582) (xy 333.965296 -275.583142)
		)
		(stroke
			(width 0)
			(type solid)
		)
		(fill yes)
		(layer "In6.Cu")
		(net "M_D_CPU0_SA_DQ<5>")
	)
	(gr_poly
		(pts
			(xy 334.09636 -280.239978) (xy 333.987902 -280.123138) (xy 333.949548 -280.10104) (xy 333.771748 -280.408888)
			(xy 333.810102 -280.430986) (xy 333.96555 -280.466546)
		)
		(stroke
			(width 0)
			(type solid)
		)
		(fill yes)
		(layer "In6.Cu")
		(net "M_D_CPU0_SA_DQ<1>")
	)
	(gr_poly
		(pts
			(xy 334.098392 -268.841474) (xy 333.989934 -268.724634) (xy 333.95158 -268.702536) (xy 333.77378 -269.010384)
			(xy 333.812134 -269.032482) (xy 333.967582 -269.068042)
		)
		(stroke
			(width 0)
			(type solid)
		)
		(fill yes)
		(layer "In6.Cu")
		(net "M_C_CPU0_SA_DQ<13>")
	)
	(gr_poly
		(pts
			(xy 334.102964 -272.089626) (xy 333.994506 -271.972786) (xy 333.956152 -271.950688) (xy 333.778352 -272.258536)
			(xy 333.816706 -272.280634) (xy 333.972154 -272.316194)
		)
		(stroke
			(width 0)
			(type solid)
		)
		(fill yes)
		(layer "In6.Cu")
		(net "M_C_CPU0_SA_DQS_DP<1>")
	)
	(gr_poly
		(pts
			(xy 334.239362 -237.06074) (xy 334.277716 -237.038642) (xy 334.099916 -236.730794) (xy 334.061562 -236.752892)
			(xy 333.953104 -236.869732) (xy 334.083914 -237.0963)
		)
		(stroke
			(width 0)
			(type solid)
		)
		(fill yes)
		(layer "In6.Cu")
		(net "M_C_CPU0_SB_DQS_DN<6>")
	)
	(gr_poly
		(pts
			(xy 334.240378 -230.551736) (xy 334.278732 -230.529638) (xy 334.100932 -230.22179) (xy 334.062578 -230.243888)
			(xy 333.95412 -230.360728) (xy 334.08493 -230.587296)
		)
		(stroke
			(width 0)
			(type solid)
		)
		(fill yes)
		(layer "In6.Cu")
		(net "M_D_CPU0_SB_DQ<20>")
	)
	(gr_poly
		(pts
			(xy 334.350106 -236.443012) (xy 334.458564 -236.326172) (xy 334.327754 -236.099604) (xy 334.172306 -236.135164)
			(xy 334.133952 -236.157262) (xy 334.311752 -236.46511)
		)
		(stroke
			(width 0)
			(type solid)
		)
		(fill yes)
		(layer "In6.Cu")
		(net "M_C_CPU0_SB_DQS_DP<6>")
	)
	(gr_poly
		(pts
			(xy 334.350106 -229.931722) (xy 334.458564 -229.814882) (xy 334.327754 -229.588314) (xy 334.172306 -229.623874)
			(xy 334.133952 -229.645972) (xy 334.311752 -229.95382)
		)
		(stroke
			(width 0)
			(type solid)
		)
		(fill yes)
		(layer "In6.Cu")
		(net "M_D_CPU0_SB_DQ<22>")
	)
	(gr_poly
		(pts
			(xy 334.374998 -249.416062) (xy 334.374998 -249.371612) (xy 334.019398 -249.371612) (xy 334.019398 -249.416062)
			(xy 334.066388 -249.568462) (xy 334.328008 -249.568462)
		)
		(stroke
			(width 0)
			(type solid)
		)
		(fill yes)
		(layer "In6.Cu")
		(net "M_A_CPU0_SB_RSP<0>")
	)
	(gr_poly
		(pts
			(xy 334.374998 -244.940582) (xy 334.328008 -244.788182) (xy 334.066388 -244.788182) (xy 334.019398 -244.940582)
			(xy 334.019398 -244.985032) (xy 334.374998 -244.985032)
		)
		(stroke
			(width 0)
			(type solid)
		)
		(fill yes)
		(layer "In6.Cu")
		(net "M_D_CPU0_SB_CS_N<1>")
	)
	(gr_poly
		(pts
			(xy 334.374998 -241.685318) (xy 334.328008 -241.532918) (xy 334.066388 -241.532918) (xy 334.019398 -241.685318)
			(xy 334.019398 -241.729514) (xy 334.374998 -241.729514)
		)
		(stroke
			(width 0)
			(type solid)
		)
		(fill yes)
		(layer "In6.Cu")
		(net "M_C_CPU0_SB_DQS_DP<5>")
	)
	(gr_poly
		(pts
			(xy 334.374998 -239.649254) (xy 334.374998 -239.604804) (xy 334.019398 -239.604804) (xy 334.019398 -239.649254)
			(xy 334.066388 -239.801654) (xy 334.328008 -239.801654)
		)
		(stroke
			(width 0)
			(type solid)
		)
		(fill yes)
		(layer "In6.Cu")
		(net "M_C_CPU0_SB_DQ<8>")
	)
	(gr_poly
		(pts
			(xy 334.377538 -241.276886) (xy 334.377538 -241.23269) (xy 334.021938 -241.23269) (xy 334.021938 -241.276886)
			(xy 334.068928 -241.429286) (xy 334.330548 -241.429286)
		)
		(stroke
			(width 0)
			(type solid)
		)
		(fill yes)
		(layer "In6.Cu")
		(net "M_C_CPU0_SB_DQ<4>")
	)
	(gr_poly
		(pts
			(xy 334.377538 -233.138218) (xy 334.377538 -233.094022) (xy 334.021938 -233.094022) (xy 334.021938 -233.138218)
			(xy 334.068928 -233.290618) (xy 334.330548 -233.290618)
		)
		(stroke
			(width 0)
			(type solid)
		)
		(fill yes)
		(layer "In6.Cu")
		(net "M_D_CPU0_SB_DQ<17>")
	)
	(gr_poly
		(pts
			(xy 334.377538 -227.035614) (xy 334.330548 -226.883214) (xy 334.068928 -226.883214) (xy 334.021938 -227.035614)
			(xy 334.021938 -227.07981) (xy 334.377538 -227.07981)
		)
		(stroke
			(width 0)
			(type solid)
		)
		(fill yes)
		(layer "In6.Cu")
		(net "M_C_CPU0_SB_DQ<24>")
	)
	(gr_poly
		(pts
			(xy 334.377538 -226.626674) (xy 334.377538 -226.582478) (xy 334.021938 -226.582478) (xy 334.021938 -226.626674)
			(xy 334.068928 -226.779074) (xy 334.330548 -226.779074)
		)
		(stroke
			(width 0)
			(type solid)
		)
		(fill yes)
		(layer "In6.Cu")
		(net "M_C_CPU0_SB_DQ<25>")
	)
	(gr_poly
		(pts
			(xy 334.3783 -234.76585) (xy 334.3783 -234.721654) (xy 334.0227 -234.721654) (xy 334.0227 -234.76585)
			(xy 334.06969 -234.91825) (xy 334.33131 -234.91825)
		)
		(stroke
			(width 0)
			(type solid)
		)
		(fill yes)
		(layer "In6.Cu")
		(net "M_C_CPU0_SB_DQ<13>")
	)
	(gr_poly
		(pts
			(xy 334.38338 -244.53215) (xy 334.38338 -244.487954) (xy 334.02778 -244.487954) (xy 334.02778 -244.53215)
			(xy 334.07477 -244.68455) (xy 334.33639 -244.68455)
		)
		(stroke
			(width 0)
			(type solid)
		)
		(fill yes)
		(layer "In6.Cu")
		(net "M_C_CPU0_SB_DQ<0>")
	)
	(gr_poly
		(pts
			(xy 334.383634 -247.787922) (xy 334.383634 -247.743472) (xy 334.028034 -247.743472) (xy 334.028034 -247.787922)
			(xy 334.075024 -247.940322) (xy 334.336644 -247.940322)
		)
		(stroke
			(width 0)
			(type solid)
		)
		(fill yes)
		(layer "In6.Cu")
		(net "M_A_CPU0_SA_RSP<1>")
	)
	(gr_poly
		(pts
			(xy 334.383634 -246.16029) (xy 334.383634 -246.11584) (xy 334.028034 -246.11584) (xy 334.028034 -246.16029)
			(xy 334.075024 -246.31269) (xy 334.336644 -246.31269)
		)
		(stroke
			(width 0)
			(type solid)
		)
		(fill yes)
		(layer "In6.Cu")
		(net "M_D_CPU0_SB_CS_N<2>")
	)
	(gr_poly
		(pts
			(xy 334.383634 -242.904518) (xy 334.383634 -242.860322) (xy 334.028034 -242.860322) (xy 334.028034 -242.904518)
			(xy 334.075024 -243.056918) (xy 334.336644 -243.056918)
		)
		(stroke
			(width 0)
			(type solid)
		)
		(fill yes)
		(layer "In6.Cu")
		(net "M_C_CPU0_SB_DQS_DP<0>")
	)
	(gr_poly
		(pts
			(xy 334.383634 -238.021114) (xy 334.383634 -237.976918) (xy 334.028034 -237.976918) (xy 334.028034 -238.021114)
			(xy 334.075024 -238.173514) (xy 334.336644 -238.173514)
		)
		(stroke
			(width 0)
			(type solid)
		)
		(fill yes)
		(layer "In6.Cu")
		(net "M_C_CPU0_SB_DQS_DP<1>")
	)
	(gr_poly
		(pts
			(xy 334.383634 -231.919018) (xy 334.336644 -231.766618) (xy 334.075024 -231.766618) (xy 334.028034 -231.919018)
			(xy 334.028034 -231.963214) (xy 334.383634 -231.963214)
		)
		(stroke
			(width 0)
			(type solid)
		)
		(fill yes)
		(layer "In6.Cu")
		(net "M_D_CPU0_SB_DQS_DN<2>")
	)
	(gr_poly
		(pts
			(xy 334.383634 -231.510078) (xy 334.383634 -231.465882) (xy 334.028034 -231.465882) (xy 334.028034 -231.510078)
			(xy 334.075024 -231.662478) (xy 334.336644 -231.662478)
		)
		(stroke
			(width 0)
			(type solid)
		)
		(fill yes)
		(layer "In6.Cu")
		(net "M_D_CPU0_SB_DQS_DN<7>")
	)
	(gr_poly
		(pts
			(xy 334.383634 -228.663754) (xy 334.336644 -228.511354) (xy 334.075024 -228.511354) (xy 334.028034 -228.663754)
			(xy 334.028034 -228.70795) (xy 334.383634 -228.70795)
		)
		(stroke
			(width 0)
			(type solid)
		)
		(fill yes)
		(layer "In6.Cu")
		(net "M_D_CPU0_SB_DQ<23>")
	)
	(gr_poly
		(pts
			(xy 334.383634 -225.407474) (xy 334.336644 -225.255074) (xy 334.075024 -225.255074) (xy 334.028034 -225.407474)
			(xy 334.028034 -225.451924) (xy 334.383634 -225.451924)
		)
		(stroke
			(width 0)
			(type solid)
		)
		(fill yes)
		(layer "In6.Cu")
		(net "M_C_CPU0_SB_DQS_DN<3>")
	)
	(gr_poly
		(pts
			(xy 334.383634 -224.999042) (xy 334.383634 -224.954592) (xy 334.028034 -224.954592) (xy 334.028034 -224.999042)
			(xy 334.075024 -225.151442) (xy 334.336644 -225.151442)
		)
		(stroke
			(width 0)
			(type solid)
		)
		(fill yes)
		(layer "In6.Cu")
		(net "M_C_CPU0_SB_DQS_DN<8>")
	)
	(gr_poly
		(pts
			(xy 334.383634 -223.779842) (xy 334.336644 -223.627442) (xy 334.075024 -223.627442) (xy 334.028034 -223.779842)
			(xy 334.028034 -223.824292) (xy 334.383634 -223.824292)
		)
		(stroke
			(width 0)
			(type solid)
		)
		(fill yes)
		(layer "In6.Cu")
		(net "M_C_CPU0_SB_DQ<30>")
	)
	(gr_poly
		(pts
			(xy 334.383634 -223.37141) (xy 334.383634 -223.32696) (xy 334.028034 -223.32696) (xy 334.028034 -223.37141)
			(xy 334.075024 -223.52381) (xy 334.336644 -223.52381)
		)
		(stroke
			(width 0)
			(type solid)
		)
		(fill yes)
		(layer "In6.Cu")
		(net "M_C_CPU0_SB_DQ<31>")
	)
	(gr_poly
		(pts
			(xy 334.387444 -278.709628) (xy 334.34909 -278.68753) (xy 334.193642 -278.65197) (xy 334.062832 -278.878538)
			(xy 334.17129 -278.995378) (xy 334.209644 -279.017476)
		)
		(stroke
			(width 0)
			(type solid)
		)
		(fill yes)
		(layer "In6.Cu")
		(net "M_D_CPU0_SA_DQ<3>")
	)
	(gr_poly
		(pts
			(xy 334.387444 -268.94282) (xy 334.34909 -268.920722) (xy 334.193642 -268.885162) (xy 334.062832 -269.11173)
			(xy 334.17129 -269.22857) (xy 334.209644 -269.250668)
		)
		(stroke
			(width 0)
			(type solid)
		)
		(fill yes)
		(layer "In6.Cu")
		(net "M_C_CPU0_SA_DQ<14>")
	)
	(gr_poly
		(pts
			(xy 334.38846 -272.19656) (xy 334.350106 -272.174462) (xy 334.194658 -272.138902) (xy 334.063848 -272.36547)
			(xy 334.172306 -272.48231) (xy 334.21066 -272.504408)
		)
		(stroke
			(width 0)
			(type solid)
		)
		(fill yes)
		(layer "In6.Cu")
		(net "M_C_CPU0_SA_DQ<11>")
	)
	(gr_poly
		(pts
			(xy 334.388968 -235.174282) (xy 334.341978 -235.021882) (xy 334.080358 -235.021882) (xy 334.033368 -235.174282)
			(xy 334.033368 -235.218732) (xy 334.388968 -235.218732)
		)
		(stroke
			(width 0)
			(type solid)
		)
		(fill yes)
		(layer "In6.Cu")
		(net "M_C_CPU0_SB_DQ<14>")
	)
	(gr_poly
		(pts
			(xy 334.389222 -275.450046) (xy 334.350868 -275.427948) (xy 334.19542 -275.392388) (xy 334.06461 -275.618956)
			(xy 334.173068 -275.735796) (xy 334.211422 -275.757894)
		)
		(stroke
			(width 0)
			(type solid)
		)
		(fill yes)
		(layer "In6.Cu")
		(net "M_D_CPU0_SA_DQ<6>")
	)
	(gr_poly
		(pts
			(xy 334.389476 -280.33345) (xy 334.351122 -280.311352) (xy 334.195674 -280.275792) (xy 334.064864 -280.50236)
			(xy 334.173322 -280.6192) (xy 334.211676 -280.641298)
		)
		(stroke
			(width 0)
			(type solid)
		)
		(fill yes)
		(layer "In6.Cu")
		(net "M_D_CPU0_SA_DQ<2>")
	)
	(gr_poly
		(pts
			(xy 334.389476 -233.54665) (xy 334.342486 -233.39425) (xy 334.080866 -233.39425) (xy 334.033876 -233.54665)
			(xy 334.033876 -233.590846) (xy 334.389476 -233.590846)
		)
		(stroke
			(width 0)
			(type solid)
		)
		(fill yes)
		(layer "In6.Cu")
		(net "M_D_CPU0_SB_DQ<18>")
	)
	(gr_poly
		(pts
			(xy 334.391 -240.057178) (xy 334.34401 -239.904778) (xy 334.08239 -239.904778) (xy 334.0354 -240.057178)
			(xy 334.0354 -240.101628) (xy 334.391 -240.101628)
		)
		(stroke
			(width 0)
			(type solid)
		)
		(fill yes)
		(layer "In6.Cu")
		(net "M_C_CPU0_SB_DQ<7>")
	)
	(gr_poly
		(pts
			(xy 334.392016 -243.31295) (xy 334.345026 -243.16055) (xy 334.083406 -243.16055) (xy 334.036416 -243.31295)
			(xy 334.036416 -243.3574) (xy 334.392016 -243.3574)
		)
		(stroke
			(width 0)
			(type solid)
		)
		(fill yes)
		(layer "In6.Cu")
		(net "M_C_CPU0_SB_DQ<3>")
	)
	(gr_poly
		(pts
			(xy 334.39227 -238.429546) (xy 334.34528 -238.277146) (xy 334.08366 -238.277146) (xy 334.03667 -238.429546)
			(xy 334.03667 -238.473996) (xy 334.39227 -238.473996)
		)
		(stroke
			(width 0)
			(type solid)
		)
		(fill yes)
		(layer "In6.Cu")
		(net "M_C_CPU0_SB_DQ<11>")
	)
	(gr_poly
		(pts
			(xy 334.484726 -277.726902) (xy 334.437736 -277.574502) (xy 334.176116 -277.574502) (xy 334.129126 -277.726902)
			(xy 334.129126 -277.771098) (xy 334.484726 -277.771098)
		)
		(stroke
			(width 0)
			(type solid)
		)
		(fill yes)
		(layer "In6.Cu")
		(net "M_D_CPU0_SA_DQS_DN<0>")
	)
	(gr_poly
		(pts
			(xy 334.484726 -277.31847) (xy 334.484726 -277.274274) (xy 334.129126 -277.274274) (xy 334.129126 -277.31847)
			(xy 334.176116 -277.47087) (xy 334.437736 -277.47087)
		)
		(stroke
			(width 0)
			(type solid)
		)
		(fill yes)
		(layer "In6.Cu")
		(net "M_D_CPU0_SA_DQS_DN<5>")
	)
	(gr_poly
		(pts
			(xy 334.48498 -274.062698) (xy 334.48498 -274.018502) (xy 334.12938 -274.018502) (xy 334.12938 -274.062698)
			(xy 334.17637 -274.215098) (xy 334.43799 -274.215098)
		)
		(stroke
			(width 0)
			(type solid)
		)
		(fill yes)
		(layer "In6.Cu")
		(net "M_C_CPU0_SA_DQ<8>")
	)
	(gr_poly
		(pts
			(xy 334.48752 -271.215358) (xy 334.44053 -271.062958) (xy 334.17891 -271.062958) (xy 334.13192 -271.215358)
			(xy 334.13192 -271.259808) (xy 334.48752 -271.259808)
		)
		(stroke
			(width 0)
			(type solid)
		)
		(fill yes)
		(layer "In6.Cu")
		(net "M_C_CPU0_SA_DQS_DN<1>")
	)
	(gr_poly
		(pts
			(xy 334.493362 -270.806926) (xy 334.493362 -270.76273) (xy 334.137762 -270.76273) (xy 334.137762 -270.806926)
			(xy 334.184752 -270.959326) (xy 334.446372 -270.959326)
		)
		(stroke
			(width 0)
			(type solid)
		)
		(fill yes)
		(layer "In6.Cu")
		(net "M_C_CPU0_SA_DQS_DN<6>")
	)
	(gr_poly
		(pts
			(xy 334.493362 -267.960094) (xy 334.446372 -267.807694) (xy 334.184752 -267.807694) (xy 334.137762 -267.960094)
			(xy 334.137762 -268.004544) (xy 334.493362 -268.004544)
		)
		(stroke
			(width 0)
			(type solid)
		)
		(fill yes)
		(layer "In6.Cu")
		(net "M_C_CPU0_SA_DQ<15>")
	)
	(gr_poly
		(pts
			(xy 334.493362 -267.551662) (xy 334.493362 -267.507212) (xy 334.137762 -267.507212) (xy 334.137762 -267.551662)
			(xy 334.184752 -267.704062) (xy 334.446372 -267.704062)
		)
		(stroke
			(width 0)
			(type solid)
		)
		(fill yes)
		(layer "In6.Cu")
		(net "M_C_CPU0_SA_DQ<24>")
	)
	(gr_poly
		(pts
			(xy 334.493362 -266.332462) (xy 334.446372 -266.180062) (xy 334.184752 -266.180062) (xy 334.137762 -266.332462)
			(xy 334.137762 -266.376658) (xy 334.493362 -266.376658)
		)
		(stroke
			(width 0)
			(type solid)
		)
		(fill yes)
		(layer "In6.Cu")
		(net "M_C_CPU0_SA_DQ<27>")
	)
	(gr_poly
		(pts
			(xy 334.493362 -265.92403) (xy 334.493362 -265.87958) (xy 334.137762 -265.87958) (xy 334.137762 -265.92403)
			(xy 334.184752 -266.07643) (xy 334.446372 -266.07643)
		)
		(stroke
			(width 0)
			(type solid)
		)
		(fill yes)
		(layer "In6.Cu")
		(net "M_C_CPU0_SA_DQS_DP<3>")
	)
	(gr_poly
		(pts
			(xy 334.493362 -264.70483) (xy 334.446372 -264.55243) (xy 334.184752 -264.55243) (xy 334.137762 -264.70483)
			(xy 334.137762 -264.749026) (xy 334.493362 -264.749026)
		)
		(stroke
			(width 0)
			(type solid)
		)
		(fill yes)
		(layer "In6.Cu")
		(net "M_C_CPU0_SA_DQS_DP<8>")
	)
	(gr_poly
		(pts
			(xy 334.493362 -264.29589) (xy 334.493362 -264.251694) (xy 334.137762 -264.251694) (xy 334.137762 -264.29589)
			(xy 334.184752 -264.44829) (xy 334.446372 -264.44829)
		)
		(stroke
			(width 0)
			(type solid)
		)
		(fill yes)
		(layer "In6.Cu")
		(net "M_C_CPU0_SA_DQ<28>")
	)
	(gr_poly
		(pts
			(xy 334.493362 -263.07669) (xy 334.446372 -262.92429) (xy 334.184752 -262.92429) (xy 334.137762 -263.07669)
			(xy 334.137762 -263.12114) (xy 334.493362 -263.12114)
		)
		(stroke
			(width 0)
			(type solid)
		)
		(fill yes)
		(layer "In6.Cu")
		(net "M_C_CPU0_SA_DQ<31>")
	)
	(gr_poly
		(pts
			(xy 334.493362 -262.668258) (xy 334.493362 -262.623808) (xy 334.137762 -262.623808) (xy 334.137762 -262.668258)
			(xy 334.184752 -262.820658) (xy 334.446372 -262.820658)
		)
		(stroke
			(width 0)
			(type solid)
		)
		(fill yes)
		(layer "In6.Cu")
		(net "M_C_CPU0_SA_CB<2>")
	)
	(gr_poly
		(pts
			(xy 334.493362 -261.449058) (xy 334.446372 -261.296658) (xy 334.184752 -261.296658) (xy 334.137762 -261.449058)
			(xy 334.137762 -261.493508) (xy 334.493362 -261.493508)
		)
		(stroke
			(width 0)
			(type solid)
		)
		(fill yes)
		(layer "In6.Cu")
		(net "M_C_CPU0_SA_CB<1>")
	)
	(gr_poly
		(pts
			(xy 334.493362 -261.040626) (xy 334.493362 -260.996176) (xy 334.137762 -260.996176) (xy 334.137762 -261.040626)
			(xy 334.184752 -261.193026) (xy 334.446372 -261.193026)
		)
		(stroke
			(width 0)
			(type solid)
		)
		(fill yes)
		(layer "In6.Cu")
		(net "M_C_CPU0_SA_DQS_DN<9>")
	)
	(gr_poly
		(pts
			(xy 334.493362 -259.821426) (xy 334.446372 -259.669026) (xy 334.184752 -259.669026) (xy 334.137762 -259.821426)
			(xy 334.137762 -259.865622) (xy 334.493362 -259.865622)
		)
		(stroke
			(width 0)
			(type solid)
		)
		(fill yes)
		(layer "In6.Cu")
		(net "M_C_CPU0_SA_DQS_DN<4>")
	)
	(gr_poly
		(pts
			(xy 334.493362 -259.412486) (xy 334.493362 -259.36829) (xy 334.137762 -259.36829) (xy 334.137762 -259.412486)
			(xy 334.184752 -259.564886) (xy 334.446372 -259.564886)
		)
		(stroke
			(width 0)
			(type solid)
		)
		(fill yes)
		(layer "In6.Cu")
		(net "M_C_CPU0_SA_CB<6>")
	)
	(gr_poly
		(pts
			(xy 334.493362 -258.193286) (xy 334.446372 -258.040886) (xy 334.184752 -258.040886) (xy 334.137762 -258.193286)
			(xy 334.137762 -258.237736) (xy 334.493362 -258.237736)
		)
		(stroke
			(width 0)
			(type solid)
		)
		(fill yes)
		(layer "In6.Cu")
		(net "M_C_CPU0_SA_CB<5>")
	)
	(gr_poly
		(pts
			(xy 334.493362 -256.565654) (xy 334.446372 -256.413254) (xy 334.184752 -256.413254) (xy 334.137762 -256.565654)
			(xy 334.137762 -256.610104) (xy 334.493362 -256.610104)
		)
		(stroke
			(width 0)
			(type solid)
		)
		(fill yes)
		(layer "In6.Cu")
		(net "M_D_CPU0_SB_RSP<0>")
	)
	(gr_poly
		(pts
			(xy 334.493362 -256.157222) (xy 334.493362 -256.112772) (xy 334.137762 -256.112772) (xy 334.137762 -256.157222)
			(xy 334.184752 -256.309622) (xy 334.446372 -256.309622)
		)
		(stroke
			(width 0)
			(type solid)
		)
		(fill yes)
		(layer "In6.Cu")
		(net "M_D_CPU0_SA_RSP<1>")
	)
	(gr_poly
		(pts
			(xy 334.493362 -254.938022) (xy 334.446372 -254.785622) (xy 334.184752 -254.785622) (xy 334.137762 -254.938022)
			(xy 334.137762 -254.982218) (xy 334.493362 -254.982218)
		)
		(stroke
			(width 0)
			(type solid)
		)
		(fill yes)
		(layer "In6.Cu")
		(net "M_C_CPU0_SB_RSP<0>")
	)
	(gr_poly
		(pts
			(xy 334.493362 -254.529082) (xy 334.493362 -254.484886) (xy 334.137762 -254.484886) (xy 334.137762 -254.529082)
			(xy 334.184752 -254.681482) (xy 334.446372 -254.681482)
		)
		(stroke
			(width 0)
			(type solid)
		)
		(fill yes)
		(layer "In6.Cu")
		(net "M_C_CPU0_SA_RSP<1>")
	)
	(gr_poly
		(pts
			(xy 334.501744 -274.47113) (xy 334.454754 -274.31873) (xy 334.193134 -274.31873) (xy 334.146144 -274.47113)
			(xy 334.146144 -274.515326) (xy 334.501744 -274.515326)
		)
		(stroke
			(width 0)
			(type solid)
		)
		(fill yes)
		(layer "In6.Cu")
		(net "M_D_CPU0_SA_DQ<7>")
	)
	(gr_poly
		(pts
			(xy 334.56626 -269.659354) (xy 334.457802 -269.542514) (xy 334.419448 -269.520416) (xy 334.241648 -269.828264)
			(xy 334.280002 -269.850362) (xy 334.43545 -269.885922)
		)
		(stroke
			(width 0)
			(type solid)
		)
		(fill yes)
		(layer "In6.Cu")
		(net "M_C_CPU0_SA_DQ<12>")
	)
	(gr_poly
		(pts
			(xy 334.567022 -276.16912) (xy 334.458564 -276.05228) (xy 334.42021 -276.030182) (xy 334.24241 -276.33803)
			(xy 334.280764 -276.360128) (xy 334.436212 -276.395688)
		)
		(stroke
			(width 0)
			(type solid)
		)
		(fill yes)
		(layer "In6.Cu")
		(net "M_D_CPU0_SA_DQ<4>")
	)
	(gr_poly
		(pts
			(xy 334.568292 -281.049984) (xy 334.459834 -280.933144) (xy 334.42148 -280.911046) (xy 334.24368 -281.218894)
			(xy 334.282034 -281.240992) (xy 334.437482 -281.276552)
		)
		(stroke
			(width 0)
			(type solid)
		)
		(fill yes)
		(layer "In6.Cu")
		(net "M_D_CPU0_SA_DQ<0>")
	)
	(gr_poly
		(pts
			(xy 334.568292 -279.422098) (xy 334.459834 -279.305258) (xy 334.42148 -279.28316) (xy 334.24368 -279.591008)
			(xy 334.282034 -279.613106) (xy 334.437482 -279.648666)
		)
		(stroke
			(width 0)
			(type solid)
		)
		(fill yes)
		(layer "In6.Cu")
		(net "M_D_CPU0_SA_DQ<1>")
	)
	(gr_poly
		(pts
			(xy 334.572864 -272.903696) (xy 334.464406 -272.786856) (xy 334.426052 -272.764758) (xy 334.248252 -273.072606)
			(xy 334.286606 -273.094704) (xy 334.442054 -273.130264)
		)
		(stroke
			(width 0)
			(type solid)
		)
		(fill yes)
		(layer "In6.Cu")
		(net "M_C_CPU0_SA_DQ<9>")
	)
	(gr_poly
		(pts
			(xy 334.709008 -229.735888) (xy 334.747362 -229.71379) (xy 334.569562 -229.405942) (xy 334.531208 -229.42804)
			(xy 334.42275 -229.54488) (xy 334.55356 -229.771448)
		)
		(stroke
			(width 0)
			(type solid)
		)
		(fill yes)
		(layer "In6.Cu")
		(net "M_D_CPU0_SB_DQ<21>")
	)
	(gr_poly
		(pts
			(xy 334.709262 -236.246924) (xy 334.747616 -236.224826) (xy 334.569816 -235.916978) (xy 334.531462 -235.939076)
			(xy 334.423004 -236.055916) (xy 334.553814 -236.282484)
		)
		(stroke
			(width 0)
			(type solid)
		)
		(fill yes)
		(layer "In6.Cu")
		(net "M_C_CPU0_SB_DQ<12>")
	)
	(gr_poly
		(pts
			(xy 334.710024 -228.10978) (xy 334.748378 -228.087682) (xy 334.570578 -227.779834) (xy 334.532224 -227.801932)
			(xy 334.423766 -227.918772) (xy 334.554576 -228.14534)
		)
		(stroke
			(width 0)
			(type solid)
		)
		(fill yes)
		(layer "In6.Cu")
		(net "M_C_CPU0_SB_DQ<26>")
	)
	(gr_poly
		(pts
			(xy 334.749648 -248.361454) (xy 334.711294 -248.339356) (xy 334.555846 -248.303796) (xy 334.425036 -248.530364)
			(xy 334.533494 -248.647204) (xy 334.571848 -248.669302)
		)
		(stroke
			(width 0)
			(type solid)
		)
		(fill yes)
		(layer "In6.Cu")
		(net "M_A_CPU0_SA_RSP<0>")
	)
	(gr_poly
		(pts
			(xy 334.819244 -235.627164) (xy 334.927702 -235.510324) (xy 334.796892 -235.283756) (xy 334.641444 -235.319316)
			(xy 334.60309 -235.341414) (xy 334.78089 -235.649262)
		)
		(stroke
			(width 0)
			(type solid)
		)
		(fill yes)
		(layer "In6.Cu")
		(net "M_C_CPU0_SB_DQ<14>")
	)
	(gr_poly
		(pts
			(xy 334.820006 -229.117906) (xy 334.928464 -229.001066) (xy 334.797654 -228.774498) (xy 334.642206 -228.810058)
			(xy 334.603852 -228.832156) (xy 334.781652 -229.140004)
		)
		(stroke
			(width 0)
			(type solid)
		)
		(fill yes)
		(layer "In6.Cu")
		(net "M_D_CPU0_SB_DQ<23>")
	)
	(gr_poly
		(pts
			(xy 334.824324 -227.497132) (xy 334.932782 -227.380292) (xy 334.801972 -227.153724) (xy 334.646524 -227.189284)
			(xy 334.60817 -227.211382) (xy 334.78597 -227.51923)
		)
		(stroke
			(width 0)
			(type solid)
		)
		(fill yes)
		(layer "In6.Cu")
		(net "M_C_CPU0_SB_DQ<24>")
	)
	(gr_poly
		(pts
			(xy 334.840834 -240.46307) (xy 334.840834 -240.418874) (xy 334.485234 -240.418874) (xy 334.485234 -240.46307)
			(xy 334.532224 -240.61547) (xy 334.793844 -240.61547)
		)
		(stroke
			(width 0)
			(type solid)
		)
		(fill yes)
		(layer "In6.Cu")
		(net "M_C_CPU0_SB_DQ<5>")
	)
	(gr_poly
		(pts
			(xy 334.844898 -243.718842) (xy 334.844898 -243.674392) (xy 334.489298 -243.674392) (xy 334.489298 -243.718842)
			(xy 334.536288 -243.871242) (xy 334.797908 -243.871242)
		)
		(stroke
			(width 0)
			(type solid)
		)
		(fill yes)
		(layer "In6.Cu")
		(net "M_C_CPU0_SB_DQ<1>")
	)
	(gr_poly
		(pts
			(xy 334.845152 -238.835438) (xy 334.845152 -238.790988) (xy 334.489552 -238.790988) (xy 334.489552 -238.835438)
			(xy 334.536542 -238.987838) (xy 334.798162 -238.987838)
		)
		(stroke
			(width 0)
			(type solid)
		)
		(fill yes)
		(layer "In6.Cu")
		(net "M_C_CPU0_SB_DQ<9>")
	)
	(gr_poly
		(pts
			(xy 334.847438 -242.499134) (xy 334.800448 -242.346734) (xy 334.538828 -242.346734) (xy 334.491838 -242.499134)
			(xy 334.491838 -242.543584) (xy 334.847438 -242.543584)
		)
		(stroke
			(width 0)
			(type solid)
		)
		(fill yes)
		(layer "In6.Cu")
		(net "M_C_CPU0_SB_DQS_DN<0>")
	)
	(gr_poly
		(pts
			(xy 334.847438 -242.090702) (xy 334.847438 -242.046252) (xy 334.491838 -242.046252) (xy 334.491838 -242.090702)
			(xy 334.538828 -242.243102) (xy 334.800448 -242.243102)
		)
		(stroke
			(width 0)
			(type solid)
		)
		(fill yes)
		(layer "In6.Cu")
		(net "M_C_CPU0_SB_DQS_DN<5>")
	)
	(gr_poly
		(pts
			(xy 334.847438 -237.207298) (xy 334.847438 -237.163102) (xy 334.491838 -237.163102) (xy 334.491838 -237.207298)
			(xy 334.538828 -237.359698) (xy 334.800448 -237.359698)
		)
		(stroke
			(width 0)
			(type solid)
		)
		(fill yes)
		(layer "In6.Cu")
		(net "M_C_CPU0_SB_DQS_DN<6>")
	)
	(gr_poly
		(pts
			(xy 334.847438 -233.952542) (xy 334.847438 -233.908092) (xy 334.491838 -233.908092) (xy 334.491838 -233.952542)
			(xy 334.538828 -234.104942) (xy 334.800448 -234.104942)
		)
		(stroke
			(width 0)
			(type solid)
		)
		(fill yes)
		(layer "In6.Cu")
		(net "M_D_CPU0_SB_DQ<16>")
	)
	(gr_poly
		(pts
			(xy 334.847438 -225.812858) (xy 334.847438 -225.768662) (xy 334.491838 -225.768662) (xy 334.491838 -225.812858)
			(xy 334.538828 -225.965258) (xy 334.800448 -225.965258)
		)
		(stroke
			(width 0)
			(type solid)
		)
		(fill yes)
		(layer "In6.Cu")
		(net "M_C_CPU0_SB_DQS_DP<3>")
	)
	(gr_poly
		(pts
			(xy 334.853026 -273.01952) (xy 334.814672 -272.997422) (xy 334.659224 -272.961862) (xy 334.528414 -273.18843)
			(xy 334.636872 -273.30527) (xy 334.675226 -273.327368)
		)
		(stroke
			(width 0)
			(type solid)
		)
		(fill yes)
		(layer "In6.Cu")
		(net "M_C_CPU0_SA_DQ<10>")
	)
	(gr_poly
		(pts
			(xy 334.85328 -244.127274) (xy 334.80629 -243.974874) (xy 334.54467 -243.974874) (xy 334.49768 -244.127274)
			(xy 334.49768 -244.17147) (xy 334.85328 -244.17147)
		)
		(stroke
			(width 0)
			(type solid)
		)
		(fill yes)
		(layer "In6.Cu")
		(net "M_C_CPU0_SB_DQ<2>")
	)
	(gr_poly
		(pts
			(xy 334.853534 -247.382538) (xy 334.806544 -247.230138) (xy 334.544924 -247.230138) (xy 334.497934 -247.382538)
			(xy 334.497934 -247.426988) (xy 334.853534 -247.426988)
		)
		(stroke
			(width 0)
			(type solid)
		)
		(fill yes)
		(layer "In6.Cu")
		(net "M_A_CPU0_SB_RSP<1>")
	)
	(gr_poly
		(pts
			(xy 334.853534 -245.754906) (xy 334.806544 -245.602506) (xy 334.544924 -245.602506) (xy 334.497934 -245.754906)
			(xy 334.497934 -245.799356) (xy 334.853534 -245.799356)
		)
		(stroke
			(width 0)
			(type solid)
		)
		(fill yes)
		(layer "In6.Cu")
		(net "M_D_CPU0_SB_CS_N<3>")
	)
	(gr_poly
		(pts
			(xy 334.853534 -240.871502) (xy 334.806544 -240.719102) (xy 334.544924 -240.719102) (xy 334.497934 -240.871502)
			(xy 334.497934 -240.915952) (xy 334.853534 -240.915952)
		)
		(stroke
			(width 0)
			(type solid)
		)
		(fill yes)
		(layer "In6.Cu")
		(net "M_C_CPU0_SB_DQ<6>")
	)
	(gr_poly
		(pts
			(xy 334.853534 -232.732834) (xy 334.806544 -232.580434) (xy 334.544924 -232.580434) (xy 334.497934 -232.732834)
			(xy 334.497934 -232.777284) (xy 334.853534 -232.777284)
		)
		(stroke
			(width 0)
			(type solid)
		)
		(fill yes)
		(layer "In6.Cu")
		(net "M_D_CPU0_SB_DQ<19>")
	)
	(gr_poly
		(pts
			(xy 334.853534 -232.323894) (xy 334.853534 -232.279698) (xy 334.497934 -232.279698) (xy 334.497934 -232.323894)
			(xy 334.544924 -232.476294) (xy 334.806544 -232.476294)
		)
		(stroke
			(width 0)
			(type solid)
		)
		(fill yes)
		(layer "In6.Cu")
		(net "M_D_CPU0_SB_DQS_DP<2>")
	)
	(gr_poly
		(pts
			(xy 334.853534 -231.105202) (xy 334.806544 -230.952802) (xy 334.544924 -230.952802) (xy 334.497934 -231.105202)
			(xy 334.497934 -231.149398) (xy 334.853534 -231.149398)
		)
		(stroke
			(width 0)
			(type solid)
		)
		(fill yes)
		(layer "In6.Cu")
		(net "M_D_CPU0_SB_DQS_DP<7>")
	)
	(gr_poly
		(pts
			(xy 334.853534 -224.593658) (xy 334.806544 -224.441258) (xy 334.544924 -224.441258) (xy 334.497934 -224.593658)
			(xy 334.497934 -224.638108) (xy 334.853534 -224.638108)
		)
		(stroke
			(width 0)
			(type solid)
		)
		(fill yes)
		(layer "In6.Cu")
		(net "M_C_CPU0_SB_DQS_DP<8>")
	)
	(gr_poly
		(pts
			(xy 334.853534 -224.185226) (xy 334.853534 -224.140776) (xy 334.497934 -224.140776) (xy 334.497934 -224.185226)
			(xy 334.544924 -224.337626) (xy 334.806544 -224.337626)
		)
		(stroke
			(width 0)
			(type solid)
		)
		(fill yes)
		(layer "In6.Cu")
		(net "M_C_CPU0_SB_DQ<28>")
	)
	(gr_poly
		(pts
			(xy 334.853534 -222.966026) (xy 334.806544 -222.813626) (xy 334.544924 -222.813626) (xy 334.497934 -222.966026)
			(xy 334.497934 -223.010222) (xy 334.853534 -223.010222)
		)
		(stroke
			(width 0)
			(type solid)
		)
		(fill yes)
		(layer "In6.Cu")
		(net "M_C_CPU0_SB_DQ<29>")
	)
	(gr_poly
		(pts
			(xy 334.857344 -279.523444) (xy 334.81899 -279.501346) (xy 334.663542 -279.465786) (xy 334.532732 -279.692354)
			(xy 334.64119 -279.809194) (xy 334.679544 -279.831292)
		)
		(stroke
			(width 0)
			(type solid)
		)
		(fill yes)
		(layer "In6.Cu")
		(net "M_D_CPU0_SA_DQ<2>")
	)
	(gr_poly
		(pts
			(xy 334.85836 -276.265386) (xy 334.820006 -276.243288) (xy 334.664558 -276.207728) (xy 334.533748 -276.434296)
			(xy 334.642206 -276.551136) (xy 334.68056 -276.573234)
		)
		(stroke
			(width 0)
			(type solid)
		)
		(fill yes)
		(layer "In6.Cu")
		(net "M_D_CPU0_SA_DQS_DP<5>")
	)
	(gr_poly
		(pts
			(xy 334.859376 -269.752826) (xy 334.821022 -269.730728) (xy 334.665574 -269.695168) (xy 334.534764 -269.921736)
			(xy 334.643222 -270.038576) (xy 334.681576 -270.060674)
		)
		(stroke
			(width 0)
			(type solid)
		)
		(fill yes)
		(layer "In6.Cu")
		(net "M_C_CPU0_SA_DQS_DP<6>")
	)
	(gr_poly
		(pts
			(xy 334.859376 -237.616238) (xy 334.812386 -237.463838) (xy 334.550766 -237.463838) (xy 334.503776 -237.616238)
			(xy 334.503776 -237.660434) (xy 334.859376 -237.660434)
		)
		(stroke
			(width 0)
			(type solid)
		)
		(fill yes)
		(layer "In6.Cu")
		(net "M_C_CPU0_SB_DQS_DN<1>")
	)
	(gr_poly
		(pts
			(xy 334.859376 -234.360466) (xy 334.812386 -234.208066) (xy 334.550766 -234.208066) (xy 334.503776 -234.360466)
			(xy 334.503776 -234.404662) (xy 334.859376 -234.404662)
		)
		(stroke
			(width 0)
			(type solid)
		)
		(fill yes)
		(layer "In6.Cu")
		(net "M_C_CPU0_SB_DQ<15>")
	)
	(gr_poly
		(pts
			(xy 334.859376 -226.221798) (xy 334.812386 -226.069398) (xy 334.550766 -226.069398) (xy 334.503776 -226.221798)
			(xy 334.503776 -226.265994) (xy 334.859376 -226.265994)
		)
		(stroke
			(width 0)
			(type solid)
		)
		(fill yes)
		(layer "In6.Cu")
		(net "M_C_CPU0_SB_DQ<27>")
	)
	(gr_poly
		(pts
			(xy 334.861916 -245.346474) (xy 334.861916 -245.302278) (xy 334.506316 -245.302278) (xy 334.506316 -245.346474)
			(xy 334.553306 -245.498874) (xy 334.814926 -245.498874)
		)
		(stroke
			(width 0)
			(type solid)
		)
		(fill yes)
		(layer "In6.Cu")
		(net "M_D_CPU0_SB_CS_N<0>")
	)
	(gr_poly
		(pts
			(xy 334.861916 -239.243362) (xy 334.814926 -239.090962) (xy 334.553306 -239.090962) (xy 334.506316 -239.243362)
			(xy 334.506316 -239.287812) (xy 334.861916 -239.287812)
		)
		(stroke
			(width 0)
			(type solid)
		)
		(fill yes)
		(layer "In6.Cu")
		(net "M_C_CPU0_SB_DQ<10>")
	)
	(gr_poly
		(pts
			(xy 334.861916 -230.69677) (xy 334.861916 -230.65232) (xy 334.506316 -230.65232) (xy 334.506316 -230.69677)
			(xy 334.553306 -230.84917) (xy 334.814926 -230.84917)
		)
		(stroke
			(width 0)
			(type solid)
		)
		(fill yes)
		(layer "In6.Cu")
		(net "M_D_CPU0_SB_DQ<20>")
	)
	(gr_poly
		(pts
			(xy 334.932782 -249.070876) (xy 334.824324 -248.954036) (xy 334.78597 -248.931938) (xy 334.60817 -249.239786)
			(xy 334.646524 -249.261884) (xy 334.801972 -249.297444)
		)
		(stroke
			(width 0)
			(type solid)
		)
		(fill yes)
		(layer "In6.Cu")
		(net "M_A_CPU0_SB_RSP<0>")
	)
	(gr_poly
		(pts
			(xy 334.954626 -274.876514) (xy 334.954626 -274.832318) (xy 334.599026 -274.832318) (xy 334.599026 -274.876514)
			(xy 334.646016 -275.028914) (xy 334.907636 -275.028914)
		)
		(stroke
			(width 0)
			(type solid)
		)
		(fill yes)
		(layer "In6.Cu")
		(net "M_D_CPU0_SA_DQ<5>")
	)
	(gr_poly
		(pts
			(xy 334.95488 -272.029174) (xy 334.90789 -271.876774) (xy 334.64627 -271.876774) (xy 334.59928 -272.029174)
			(xy 334.59928 -272.073624) (xy 334.95488 -272.073624)
		)
		(stroke
			(width 0)
			(type solid)
		)
		(fill yes)
		(layer "In6.Cu")
		(net "M_C_CPU0_SA_DQ<11>")
	)
	(gr_poly
		(pts
			(xy 334.963008 -275.284946) (xy 334.916018 -275.132546) (xy 334.654398 -275.132546) (xy 334.607408 -275.284946)
			(xy 334.607408 -275.329396) (xy 334.963008 -275.329396)
		)
		(stroke
			(width 0)
			(type solid)
		)
		(fill yes)
		(layer "In6.Cu")
		(net "M_D_CPU0_SA_DQ<6>")
	)
	(gr_poly
		(pts
			(xy 334.963262 -278.540718) (xy 334.916272 -278.388318) (xy 334.654652 -278.388318) (xy 334.607662 -278.540718)
			(xy 334.607662 -278.585168) (xy 334.963262 -278.585168)
		)
		(stroke
			(width 0)
			(type solid)
		)
		(fill yes)
		(layer "In6.Cu")
		(net "M_D_CPU0_SA_DQ<3>")
	)
	(gr_poly
		(pts
			(xy 334.963262 -268.77391) (xy 334.916272 -268.62151) (xy 334.654652 -268.62151) (xy 334.607662 -268.77391)
			(xy 334.607662 -268.81836) (xy 334.963262 -268.81836)
		)
		(stroke
			(width 0)
			(type solid)
		)
		(fill yes)
		(layer "In6.Cu")
		(net "M_C_CPU0_SA_DQ<14>")
	)
	(gr_poly
		(pts
			(xy 334.963262 -268.365478) (xy 334.963262 -268.321028) (xy 334.607662 -268.321028) (xy 334.607662 -268.365478)
			(xy 334.654652 -268.517878) (xy 334.916272 -268.517878)
		)
		(stroke
			(width 0)
			(type solid)
		)
		(fill yes)
		(layer "In6.Cu")
		(net "M_C_CPU0_SA_DQ<13>")
	)
	(gr_poly
		(pts
			(xy 334.963262 -267.146278) (xy 334.916272 -266.993878) (xy 334.654652 -266.993878) (xy 334.607662 -267.146278)
			(xy 334.607662 -267.190474) (xy 334.963262 -267.190474)
		)
		(stroke
			(width 0)
			(type solid)
		)
		(fill yes)
		(layer "In6.Cu")
		(net "M_C_CPU0_SA_DQ<26>")
	)
	(gr_poly
		(pts
			(xy 334.963262 -266.737846) (xy 334.963262 -266.693396) (xy 334.607662 -266.693396) (xy 334.607662 -266.737846)
			(xy 334.654652 -266.890246) (xy 334.916272 -266.890246)
		)
		(stroke
			(width 0)
			(type solid)
		)
		(fill yes)
		(layer "In6.Cu")
		(net "M_C_CPU0_SA_DQ<25>")
	)
	(gr_poly
		(pts
			(xy 334.963262 -265.518646) (xy 334.916272 -265.366246) (xy 334.654652 -265.366246) (xy 334.607662 -265.518646)
			(xy 334.607662 -265.562842) (xy 334.963262 -265.562842)
		)
		(stroke
			(width 0)
			(type solid)
		)
		(fill yes)
		(layer "In6.Cu")
		(net "M_C_CPU0_SA_DQS_DN<3>")
	)
	(gr_poly
		(pts
			(xy 334.963262 -265.109706) (xy 334.963262 -265.06551) (xy 334.607662 -265.06551) (xy 334.607662 -265.109706)
			(xy 334.654652 -265.262106) (xy 334.916272 -265.262106)
		)
		(stroke
			(width 0)
			(type solid)
		)
		(fill yes)
		(layer "In6.Cu")
		(net "M_C_CPU0_SA_DQS_DN<8>")
	)
	(gr_poly
		(pts
			(xy 334.963262 -263.891014) (xy 334.916272 -263.738614) (xy 334.654652 -263.738614) (xy 334.607662 -263.891014)
			(xy 334.607662 -263.93521) (xy 334.963262 -263.93521)
		)
		(stroke
			(width 0)
			(type solid)
		)
		(fill yes)
		(layer "In6.Cu")
		(net "M_C_CPU0_SA_DQ<30>")
	)
	(gr_poly
		(pts
			(xy 334.963262 -263.482074) (xy 334.963262 -263.437878) (xy 334.607662 -263.437878) (xy 334.607662 -263.482074)
			(xy 334.654652 -263.634474) (xy 334.916272 -263.634474)
		)
		(stroke
			(width 0)
			(type solid)
		)
		(fill yes)
		(layer "In6.Cu")
		(net "M_C_CPU0_SA_DQ<29>")
	)
	(gr_poly
		(pts
			(xy 334.963262 -262.262874) (xy 334.916272 -262.110474) (xy 334.654652 -262.110474) (xy 334.607662 -262.262874)
			(xy 334.607662 -262.307324) (xy 334.963262 -262.307324)
		)
		(stroke
			(width 0)
			(type solid)
		)
		(fill yes)
		(layer "In6.Cu")
		(net "M_C_CPU0_SA_CB<0>")
	)
	(gr_poly
		(pts
			(xy 334.963262 -261.854442) (xy 334.963262 -261.809992) (xy 334.607662 -261.809992) (xy 334.607662 -261.854442)
			(xy 334.654652 -262.006842) (xy 334.916272 -262.006842)
		)
		(stroke
			(width 0)
			(type solid)
		)
		(fill yes)
		(layer "In6.Cu")
		(net "M_C_CPU0_SA_CB<3>")
	)
	(gr_poly
		(pts
			(xy 334.963262 -260.635242) (xy 334.916272 -260.482842) (xy 334.654652 -260.482842) (xy 334.607662 -260.635242)
			(xy 334.607662 -260.679438) (xy 334.963262 -260.679438)
		)
		(stroke
			(width 0)
			(type solid)
		)
		(fill yes)
		(layer "In6.Cu")
		(net "M_C_CPU0_SA_DQS_DP<9>")
	)
	(gr_poly
		(pts
			(xy 334.963262 -260.226302) (xy 334.963262 -260.182106) (xy 334.607662 -260.182106) (xy 334.607662 -260.226302)
			(xy 334.654652 -260.378702) (xy 334.916272 -260.378702)
		)
		(stroke
			(width 0)
			(type solid)
		)
		(fill yes)
		(layer "In6.Cu")
		(net "M_C_CPU0_SA_DQS_DP<4>")
	)
	(gr_poly
		(pts
			(xy 334.963262 -259.00761) (xy 334.916272 -258.85521) (xy 334.654652 -258.85521) (xy 334.607662 -259.00761)
			(xy 334.607662 -259.051806) (xy 334.963262 -259.051806)
		)
		(stroke
			(width 0)
			(type solid)
		)
		(fill yes)
		(layer "In6.Cu")
		(net "M_C_CPU0_SA_CB<4>")
	)
	(gr_poly
		(pts
			(xy 334.963262 -258.59867) (xy 334.963262 -258.554474) (xy 334.607662 -258.554474) (xy 334.607662 -258.59867)
			(xy 334.654652 -258.75107) (xy 334.916272 -258.75107)
		)
		(stroke
			(width 0)
			(type solid)
		)
		(fill yes)
		(layer "In6.Cu")
		(net "M_C_CPU0_SA_CB<7>")
	)
	(gr_poly
		(pts
			(xy 334.963262 -256.971038) (xy 334.963262 -256.926588) (xy 334.607662 -256.926588) (xy 334.607662 -256.971038)
			(xy 334.654652 -257.123438) (xy 334.916272 -257.123438)
		)
		(stroke
			(width 0)
			(type solid)
		)
		(fill yes)
		(layer "In6.Cu")
		(net "M_D_CPU0_SA_RSP<0>")
	)
	(gr_poly
		(pts
			(xy 334.963262 -255.751838) (xy 334.916272 -255.599438) (xy 334.654652 -255.599438) (xy 334.607662 -255.751838)
			(xy 334.607662 -255.796288) (xy 334.963262 -255.796288)
		)
		(stroke
			(width 0)
			(type solid)
		)
		(fill yes)
		(layer "In6.Cu")
		(net "M_D_CPU0_SB_RSP<1>")
	)
	(gr_poly
		(pts
			(xy 334.963262 -255.343406) (xy 334.963262 -255.298956) (xy 334.607662 -255.298956) (xy 334.607662 -255.343406)
			(xy 334.654652 -255.495806) (xy 334.916272 -255.495806)
		)
		(stroke
			(width 0)
			(type solid)
		)
		(fill yes)
		(layer "In6.Cu")
		(net "M_C_CPU0_SA_RSP<0>")
	)
	(gr_poly
		(pts
			(xy 334.963262 -254.124206) (xy 334.916272 -253.971806) (xy 334.654652 -253.971806) (xy 334.607662 -254.124206)
			(xy 334.607662 -254.168402) (xy 334.963262 -254.168402)
		)
		(stroke
			(width 0)
			(type solid)
		)
		(fill yes)
		(layer "In6.Cu")
		(net "M_C_CPU0_SB_RSP<1>")
	)
	(gr_poly
		(pts
			(xy 334.971644 -278.132286) (xy 334.971644 -278.08809) (xy 334.616044 -278.08809) (xy 334.616044 -278.132286)
			(xy 334.663034 -278.284686) (xy 334.924654 -278.284686)
		)
		(stroke
			(width 0)
			(type solid)
		)
		(fill yes)
		(layer "In6.Cu")
		(net "M_D_CPU0_SA_DQS_DP<0>")
	)
	(gr_poly
		(pts
			(xy 334.971644 -271.620996) (xy 334.971644 -271.5768) (xy 334.616044 -271.5768) (xy 334.616044 -271.620996)
			(xy 334.663034 -271.773396) (xy 334.924654 -271.773396)
		)
		(stroke
			(width 0)
			(type solid)
		)
		(fill yes)
		(layer "In6.Cu")
		(net "M_C_CPU0_SA_DQS_DP<1>")
	)
	(gr_poly
		(pts
			(xy 335.03616 -280.239978) (xy 334.927702 -280.123138) (xy 334.889348 -280.10104) (xy 334.711548 -280.408888)
			(xy 334.749902 -280.430986) (xy 334.90535 -280.466546)
		)
		(stroke
			(width 0)
			(type solid)
		)
		(fill yes)
		(layer "In6.Cu")
		(net "M_D_CPU0_SA_DQ<0>")
	)
	(gr_poly
		(pts
			(xy 335.038192 -270.46936) (xy 334.929734 -270.35252) (xy 334.89138 -270.330422) (xy 334.71358 -270.63827)
			(xy 334.751934 -270.660368) (xy 334.907382 -270.695928)
		)
		(stroke
			(width 0)
			(type solid)
		)
		(fill yes)
		(layer "In6.Cu")
		(net "M_C_CPU0_SA_DQS_DN<6>")
	)
	(gr_poly
		(pts
			(xy 335.042764 -273.717766) (xy 334.934306 -273.600926) (xy 334.895952 -273.578828) (xy 334.718152 -273.886676)
			(xy 334.756506 -273.908774) (xy 334.911954 -273.944334)
		)
		(stroke
			(width 0)
			(type solid)
		)
		(fill yes)
		(layer "In6.Cu")
		(net "M_C_CPU0_SA_DQ<8>")
	)
	(gr_poly
		(pts
			(xy 335.172812 -235.422694) (xy 335.211166 -235.400596) (xy 335.033366 -235.092748) (xy 334.995012 -235.114846)
			(xy 334.886554 -235.231686) (xy 335.017364 -235.458254)
		)
		(stroke
			(width 0)
			(type solid)
		)
		(fill yes)
		(layer "In6.Cu")
		(net "M_C_CPU0_SB_DQ<13>")
	)
	(gr_poly
		(pts
			(xy 335.17459 -227.286566) (xy 335.212944 -227.264468) (xy 335.035144 -226.95662) (xy 334.99679 -226.978718)
			(xy 334.888332 -227.095558) (xy 335.019142 -227.322126)
		)
		(stroke
			(width 0)
			(type solid)
		)
		(fill yes)
		(layer "In6.Cu")
		(net "M_C_CPU0_SB_DQ<25>")
	)
	(gr_poly
		(pts
			(xy 335.180432 -228.924358) (xy 335.218786 -228.90226) (xy 335.040986 -228.594412) (xy 335.002632 -228.61651)
			(xy 334.894174 -228.73335) (xy 335.024984 -228.959918)
		)
		(stroke
			(width 0)
			(type solid)
		)
		(fill yes)
		(layer "In6.Cu")
		(net "M_C_CPU0_SB_DQ<26>")
	)
	(gr_poly
		(pts
			(xy 335.288636 -228.302058) (xy 335.397094 -228.185218) (xy 335.266284 -227.95865) (xy 335.110836 -227.99421)
			(xy 335.072482 -228.016308) (xy 335.250282 -228.324156)
		)
		(stroke
			(width 0)
			(type solid)
		)
		(fill yes)
		(layer "In6.Cu")
		(net "M_C_CPU0_SB_DQ<24>")
	)
	(gr_poly
		(pts
			(xy 335.294224 -234.822492) (xy 335.402682 -234.705652) (xy 335.271872 -234.479084) (xy 335.116424 -234.514644)
			(xy 335.07807 -234.536742) (xy 335.25587 -234.84459)
		)
		(stroke
			(width 0)
			(type solid)
		)
		(fill yes)
		(layer "In6.Cu")
		(net "M_C_CPU0_SB_DQ<15>")
	)
	(gr_poly
		(pts
			(xy 335.296002 -226.686364) (xy 335.40446 -226.569524) (xy 335.27365 -226.342956) (xy 335.118202 -226.378516)
			(xy 335.079848 -226.400614) (xy 335.257648 -226.708462)
		)
		(stroke
			(width 0)
			(type solid)
		)
		(fill yes)
		(layer "In6.Cu")
		(net "M_C_CPU0_SB_DQ<27>")
	)
	(gr_poly
		(pts
			(xy 335.313274 -230.290878) (xy 335.266284 -230.138478) (xy 335.004664 -230.138478) (xy 334.957674 -230.290878)
			(xy 334.957674 -230.335074) (xy 335.313274 -230.335074)
		)
		(stroke
			(width 0)
			(type solid)
		)
		(fill yes)
		(layer "In6.Cu")
		(net "M_D_CPU0_SB_DQ<22>")
	)
	(gr_poly
		(pts
			(xy 335.314798 -244.940582) (xy 335.267808 -244.788182) (xy 335.006188 -244.788182) (xy 334.959198 -244.940582)
			(xy 334.959198 -244.985032) (xy 335.314798 -244.985032)
		)
		(stroke
			(width 0)
			(type solid)
		)
		(fill yes)
		(layer "In6.Cu")
		(net "M_D_CPU0_SB_CS_N<1>")
	)
	(gr_poly
		(pts
			(xy 335.314798 -239.649254) (xy 335.314798 -239.604804) (xy 334.959198 -239.604804) (xy 334.959198 -239.649254)
			(xy 335.006188 -239.801654) (xy 335.267808 -239.801654)
		)
		(stroke
			(width 0)
			(type solid)
		)
		(fill yes)
		(layer "In6.Cu")
		(net "M_C_CPU0_SB_DQ<8>")
	)
	(gr_poly
		(pts
			(xy 335.31556 -233.138218) (xy 335.31556 -233.093768) (xy 334.95996 -233.093768) (xy 334.95996 -233.138218)
			(xy 335.00695 -233.290618) (xy 335.26857 -233.290618)
		)
		(stroke
			(width 0)
			(type solid)
		)
		(fill yes)
		(layer "In6.Cu")
		(net "M_D_CPU0_SB_DQ<17>")
	)
	(gr_poly
		(pts
			(xy 335.32318 -244.53215) (xy 335.32318 -244.487954) (xy 334.96758 -244.487954) (xy 334.96758 -244.53215)
			(xy 335.01457 -244.68455) (xy 335.27619 -244.68455)
		)
		(stroke
			(width 0)
			(type solid)
		)
		(fill yes)
		(layer "In6.Cu")
		(net "M_C_CPU0_SB_DQ<0>")
	)
	(gr_poly
		(pts
			(xy 335.323434 -248.196354) (xy 335.276444 -248.043954) (xy 335.014824 -248.043954) (xy 334.967834 -248.196354)
			(xy 334.967834 -248.240804) (xy 335.323434 -248.240804)
		)
		(stroke
			(width 0)
			(type solid)
		)
		(fill yes)
		(layer "In6.Cu")
		(net "M_A_CPU0_SA_RSP<0>")
	)
	(gr_poly
		(pts
			(xy 335.323434 -247.787922) (xy 335.323434 -247.743472) (xy 334.967834 -247.743472) (xy 334.967834 -247.787922)
			(xy 335.014824 -247.940322) (xy 335.276444 -247.940322)
		)
		(stroke
			(width 0)
			(type solid)
		)
		(fill yes)
		(layer "In6.Cu")
		(net "M_A_CPU0_SA_RSP<1>")
	)
	(gr_poly
		(pts
			(xy 335.323434 -246.16029) (xy 335.323434 -246.11584) (xy 334.967834 -246.11584) (xy 334.967834 -246.16029)
			(xy 335.014824 -246.31269) (xy 335.276444 -246.31269)
		)
		(stroke
			(width 0)
			(type solid)
		)
		(fill yes)
		(layer "In6.Cu")
		(net "M_D_CPU0_SB_CS_N<2>")
	)
	(gr_poly
		(pts
			(xy 335.323434 -241.276886) (xy 335.323434 -241.232436) (xy 334.967834 -241.232436) (xy 334.967834 -241.276886)
			(xy 335.014824 -241.429286) (xy 335.276444 -241.429286)
		)
		(stroke
			(width 0)
			(type solid)
		)
		(fill yes)
		(layer "In6.Cu")
		(net "M_C_CPU0_SB_DQ<4>")
	)
	(gr_poly
		(pts
			(xy 335.323434 -236.393482) (xy 335.323434 -236.349286) (xy 334.967834 -236.349286) (xy 334.967834 -236.393482)
			(xy 335.014824 -236.545882) (xy 335.276444 -236.545882)
		)
		(stroke
			(width 0)
			(type solid)
		)
		(fill yes)
		(layer "In6.Cu")
		(net "M_C_CPU0_SB_DQ<12>")
	)
	(gr_poly
		(pts
			(xy 335.323434 -231.919018) (xy 335.276444 -231.766618) (xy 335.014824 -231.766618) (xy 334.967834 -231.919018)
			(xy 334.967834 -231.963214) (xy 335.323434 -231.963214)
		)
		(stroke
			(width 0)
			(type solid)
		)
		(fill yes)
		(layer "In6.Cu")
		(net "M_D_CPU0_SB_DQS_DN<2>")
	)
	(gr_poly
		(pts
			(xy 335.323434 -231.510078) (xy 335.323434 -231.465882) (xy 334.967834 -231.465882) (xy 334.967834 -231.510078)
			(xy 335.014824 -231.662478) (xy 335.276444 -231.662478)
		)
		(stroke
			(width 0)
			(type solid)
		)
		(fill yes)
		(layer "In6.Cu")
		(net "M_D_CPU0_SB_DQS_DN<7>")
	)
	(gr_poly
		(pts
			(xy 335.323434 -224.999042) (xy 335.323434 -224.954592) (xy 334.967834 -224.954592) (xy 334.967834 -224.999042)
			(xy 335.014824 -225.151442) (xy 335.276444 -225.151442)
		)
		(stroke
			(width 0)
			(type solid)
		)
		(fill yes)
		(layer "In6.Cu")
		(net "M_C_CPU0_SB_DQS_DN<8>")
	)
	(gr_poly
		(pts
			(xy 335.323434 -223.779842) (xy 335.276444 -223.627442) (xy 335.014824 -223.627442) (xy 334.967834 -223.779842)
			(xy 334.967834 -223.824292) (xy 335.323434 -223.824292)
		)
		(stroke
			(width 0)
			(type solid)
		)
		(fill yes)
		(layer "In6.Cu")
		(net "M_C_CPU0_SB_DQ<30>")
	)
	(gr_poly
		(pts
			(xy 335.323434 -223.37141) (xy 335.323434 -223.32696) (xy 334.967834 -223.32696) (xy 334.967834 -223.37141)
			(xy 335.014824 -223.52381) (xy 335.276444 -223.52381)
		)
		(stroke
			(width 0)
			(type solid)
		)
		(fill yes)
		(layer "In6.Cu")
		(net "M_C_CPU0_SB_DQ<31>")
	)
	(gr_poly
		(pts
			(xy 335.327244 -273.826224) (xy 335.28889 -273.804126) (xy 335.133442 -273.768566) (xy 335.002632 -273.995134)
			(xy 335.11109 -274.111974) (xy 335.149444 -274.134072)
		)
		(stroke
			(width 0)
			(type solid)
		)
		(fill yes)
		(layer "In6.Cu")
		(net "M_D_CPU0_SA_DQ<7>")
	)
	(gr_poly
		(pts
			(xy 335.327244 -270.570706) (xy 335.28889 -270.548608) (xy 335.133442 -270.513048) (xy 335.002632 -270.739616)
			(xy 335.11109 -270.856456) (xy 335.149444 -270.878554)
		)
		(stroke
			(width 0)
			(type solid)
		)
		(fill yes)
		(layer "In6.Cu")
		(net "M_C_CPU0_SA_DQS_DN<1>")
	)
	(gr_poly
		(pts
			(xy 335.329276 -238.021622) (xy 335.329276 -237.977172) (xy 334.973676 -237.977172) (xy 334.973676 -238.021622)
			(xy 335.020666 -238.174022) (xy 335.282286 -238.174022)
		)
		(stroke
			(width 0)
			(type solid)
		)
		(fill yes)
		(layer "In6.Cu")
		(net "M_C_CPU0_SB_DQS_DP<1>")
	)
	(gr_poly
		(pts
			(xy 335.32953 -238.430054) (xy 335.28254 -238.277654) (xy 335.02092 -238.277654) (xy 334.97393 -238.430054)
			(xy 334.97393 -238.47425) (xy 335.32953 -238.47425)
		)
		(stroke
			(width 0)
			(type solid)
		)
		(fill yes)
		(layer "In6.Cu")
		(net "M_C_CPU0_SB_DQ<11>")
	)
	(gr_poly
		(pts
			(xy 335.331308 -233.54665) (xy 335.284318 -233.39425) (xy 335.022698 -233.39425) (xy 334.975708 -233.54665)
			(xy 334.975708 -233.5911) (xy 335.331308 -233.5911)
		)
		(stroke
			(width 0)
			(type solid)
		)
		(fill yes)
		(layer "In6.Cu")
		(net "M_D_CPU0_SB_DQ<18>")
	)
	(gr_poly
		(pts
			(xy 335.331816 -243.31295) (xy 335.284826 -243.16055) (xy 335.023206 -243.16055) (xy 334.976216 -243.31295)
			(xy 334.976216 -243.3574) (xy 335.331816 -243.3574)
		)
		(stroke
			(width 0)
			(type solid)
		)
		(fill yes)
		(layer "In6.Cu")
		(net "M_C_CPU0_SB_DQ<3>")
	)
	(gr_poly
		(pts
			(xy 335.331816 -242.905026) (xy 335.331816 -242.860576) (xy 334.976216 -242.860576) (xy 334.976216 -242.905026)
			(xy 335.023206 -243.057426) (xy 335.284826 -243.057426)
		)
		(stroke
			(width 0)
			(type solid)
		)
		(fill yes)
		(layer "In6.Cu")
		(net "M_C_CPU0_SB_DQS_DP<0>")
	)
	(gr_poly
		(pts
			(xy 335.331816 -241.685318) (xy 335.284826 -241.532918) (xy 335.023206 -241.532918) (xy 334.976216 -241.685318)
			(xy 334.976216 -241.729514) (xy 335.331816 -241.729514)
		)
		(stroke
			(width 0)
			(type solid)
		)
		(fill yes)
		(layer "In6.Cu")
		(net "M_C_CPU0_SB_DQS_DP<5>")
	)
	(gr_poly
		(pts
			(xy 335.331816 -236.801914) (xy 335.284826 -236.649514) (xy 335.023206 -236.649514) (xy 334.976216 -236.801914)
			(xy 334.976216 -236.846364) (xy 335.331816 -236.846364)
		)
		(stroke
			(width 0)
			(type solid)
		)
		(fill yes)
		(layer "In6.Cu")
		(net "M_C_CPU0_SB_DQS_DP<6>")
	)
	(gr_poly
		(pts
			(xy 335.331816 -225.407474) (xy 335.284826 -225.255074) (xy 335.023206 -225.255074) (xy 334.976216 -225.407474)
			(xy 334.976216 -225.45167) (xy 335.331816 -225.45167)
		)
		(stroke
			(width 0)
			(type solid)
		)
		(fill yes)
		(layer "In6.Cu")
		(net "M_C_CPU0_SB_DQS_DN<3>")
	)
	(gr_poly
		(pts
			(xy 335.333086 -240.057686) (xy 335.286096 -239.905286) (xy 335.024476 -239.905286) (xy 334.977486 -240.057686)
			(xy 334.977486 -240.101882) (xy 335.333086 -240.101882)
		)
		(stroke
			(width 0)
			(type solid)
		)
		(fill yes)
		(layer "In6.Cu")
		(net "M_C_CPU0_SB_DQ<7>")
	)
	(gr_poly
		(pts
			(xy 335.33334 -229.882954) (xy 335.33334 -229.838504) (xy 334.97774 -229.838504) (xy 334.97774 -229.882954)
			(xy 335.02473 -230.035354) (xy 335.28635 -230.035354)
		)
		(stroke
			(width 0)
			(type solid)
		)
		(fill yes)
		(layer "In6.Cu")
		(net "M_D_CPU0_SB_DQ<21>")
	)
	(gr_poly
		(pts
			(xy 335.424526 -277.726902) (xy 335.377536 -277.574502) (xy 335.115916 -277.574502) (xy 335.068926 -277.726902)
			(xy 335.068926 -277.771098) (xy 335.424526 -277.771098)
		)
		(stroke
			(width 0)
			(type solid)
		)
		(fill yes)
		(layer "In6.Cu")
		(net "M_D_CPU0_SA_DQS_DN<0>")
	)
	(gr_poly
		(pts
			(xy 335.424526 -276.098762) (xy 335.377536 -275.946362) (xy 335.115916 -275.946362) (xy 335.068926 -276.098762)
			(xy 335.068926 -276.143212) (xy 335.424526 -276.143212)
		)
		(stroke
			(width 0)
			(type solid)
		)
		(fill yes)
		(layer "In6.Cu")
		(net "M_D_CPU0_SA_DQS_DP<5>")
	)
	(gr_poly
		(pts
			(xy 335.432908 -275.690584) (xy 335.432908 -275.646134) (xy 335.077308 -275.646134) (xy 335.077308 -275.690584)
			(xy 335.124298 -275.842984) (xy 335.385918 -275.842984)
		)
		(stroke
			(width 0)
			(type solid)
		)
		(fill yes)
		(layer "In6.Cu")
		(net "M_D_CPU0_SA_DQ<4>")
	)
	(gr_poly
		(pts
			(xy 335.433162 -279.354788) (xy 335.386172 -279.202388) (xy 335.124552 -279.202388) (xy 335.077562 -279.354788)
			(xy 335.077562 -279.398984) (xy 335.433162 -279.398984)
		)
		(stroke
			(width 0)
			(type solid)
		)
		(fill yes)
		(layer "In6.Cu")
		(net "M_D_CPU0_SA_DQ<2>")
	)
	(gr_poly
		(pts
			(xy 335.433162 -278.945848) (xy 335.433162 -278.901652) (xy 335.077562 -278.901652) (xy 335.077562 -278.945848)
			(xy 335.124552 -279.098248) (xy 335.386172 -279.098248)
		)
		(stroke
			(width 0)
			(type solid)
		)
		(fill yes)
		(layer "In6.Cu")
		(net "M_D_CPU0_SA_DQ<1>")
	)
	(gr_poly
		(pts
			(xy 335.433162 -269.587726) (xy 335.386172 -269.435326) (xy 335.124552 -269.435326) (xy 335.077562 -269.587726)
			(xy 335.077562 -269.632176) (xy 335.433162 -269.632176)
		)
		(stroke
			(width 0)
			(type solid)
		)
		(fill yes)
		(layer "In6.Cu")
		(net "M_C_CPU0_SA_DQS_DP<6>")
	)
	(gr_poly
		(pts
			(xy 335.433162 -269.179294) (xy 335.433162 -269.134844) (xy 335.077562 -269.134844) (xy 335.077562 -269.179294)
			(xy 335.124552 -269.331694) (xy 335.386172 -269.331694)
		)
		(stroke
			(width 0)
			(type solid)
		)
		(fill yes)
		(layer "In6.Cu")
		(net "M_C_CPU0_SA_DQ<12>")
	)
	(gr_poly
		(pts
			(xy 335.433162 -267.960094) (xy 335.386172 -267.807694) (xy 335.124552 -267.807694) (xy 335.077562 -267.960094)
			(xy 335.077562 -268.004544) (xy 335.433162 -268.004544)
		)
		(stroke
			(width 0)
			(type solid)
		)
		(fill yes)
		(layer "In6.Cu")
		(net "M_C_CPU0_SA_DQ<15>")
	)
	(gr_poly
		(pts
			(xy 335.433162 -267.551662) (xy 335.433162 -267.507212) (xy 335.077562 -267.507212) (xy 335.077562 -267.551662)
			(xy 335.124552 -267.704062) (xy 335.386172 -267.704062)
		)
		(stroke
			(width 0)
			(type solid)
		)
		(fill yes)
		(layer "In6.Cu")
		(net "M_C_CPU0_SA_DQ<24>")
	)
	(gr_poly
		(pts
			(xy 335.433162 -266.332462) (xy 335.386172 -266.180062) (xy 335.124552 -266.180062) (xy 335.077562 -266.332462)
			(xy 335.077562 -266.376658) (xy 335.433162 -266.376658)
		)
		(stroke
			(width 0)
			(type solid)
		)
		(fill yes)
		(layer "In6.Cu")
		(net "M_C_CPU0_SA_DQ<27>")
	)
	(gr_poly
		(pts
			(xy 335.433162 -265.92403) (xy 335.433162 -265.87958) (xy 335.077562 -265.87958) (xy 335.077562 -265.92403)
			(xy 335.124552 -266.07643) (xy 335.386172 -266.07643)
		)
		(stroke
			(width 0)
			(type solid)
		)
		(fill yes)
		(layer "In6.Cu")
		(net "M_C_CPU0_SA_DQS_DP<3>")
	)
	(gr_poly
		(pts
			(xy 335.433162 -264.70483) (xy 335.386172 -264.55243) (xy 335.124552 -264.55243) (xy 335.077562 -264.70483)
			(xy 335.077562 -264.749026) (xy 335.433162 -264.749026)
		)
		(stroke
			(width 0)
			(type solid)
		)
		(fill yes)
		(layer "In6.Cu")
		(net "M_C_CPU0_SA_DQS_DP<8>")
	)
	(gr_poly
		(pts
			(xy 335.433162 -264.29589) (xy 335.433162 -264.251694) (xy 335.077562 -264.251694) (xy 335.077562 -264.29589)
			(xy 335.124552 -264.44829) (xy 335.386172 -264.44829)
		)
		(stroke
			(width 0)
			(type solid)
		)
		(fill yes)
		(layer "In6.Cu")
		(net "M_C_CPU0_SA_DQ<28>")
	)
	(gr_poly
		(pts
			(xy 335.433162 -263.07669) (xy 335.386172 -262.92429) (xy 335.124552 -262.92429) (xy 335.077562 -263.07669)
			(xy 335.077562 -263.12114) (xy 335.433162 -263.12114)
		)
		(stroke
			(width 0)
			(type solid)
		)
		(fill yes)
		(layer "In6.Cu")
		(net "M_C_CPU0_SA_DQ<31>")
	)
	(gr_poly
		(pts
			(xy 335.433162 -262.668258) (xy 335.433162 -262.623808) (xy 335.077562 -262.623808) (xy 335.077562 -262.668258)
			(xy 335.124552 -262.820658) (xy 335.386172 -262.820658)
		)
		(stroke
			(width 0)
			(type solid)
		)
		(fill yes)
		(layer "In6.Cu")
		(net "M_C_CPU0_SA_CB<2>")
	)
	(gr_poly
		(pts
			(xy 335.433162 -261.449058) (xy 335.386172 -261.296658) (xy 335.124552 -261.296658) (xy 335.077562 -261.449058)
			(xy 335.077562 -261.493508) (xy 335.433162 -261.493508)
		)
		(stroke
			(width 0)
			(type solid)
		)
		(fill yes)
		(layer "In6.Cu")
		(net "M_C_CPU0_SA_CB<1>")
	)
	(gr_poly
		(pts
			(xy 335.433162 -261.040626) (xy 335.433162 -260.996176) (xy 335.077562 -260.996176) (xy 335.077562 -261.040626)
			(xy 335.124552 -261.193026) (xy 335.386172 -261.193026)
		)
		(stroke
			(width 0)
			(type solid)
		)
		(fill yes)
		(layer "In6.Cu")
		(net "M_C_CPU0_SA_DQS_DN<9>")
	)
	(gr_poly
		(pts
			(xy 335.433162 -259.821426) (xy 335.386172 -259.669026) (xy 335.124552 -259.669026) (xy 335.077562 -259.821426)
			(xy 335.077562 -259.865622) (xy 335.433162 -259.865622)
		)
		(stroke
			(width 0)
			(type solid)
		)
		(fill yes)
		(layer "In6.Cu")
		(net "M_C_CPU0_SA_DQS_DN<4>")
	)
	(gr_poly
		(pts
			(xy 335.433162 -259.412486) (xy 335.433162 -259.36829) (xy 335.077562 -259.36829) (xy 335.077562 -259.412486)
			(xy 335.124552 -259.564886) (xy 335.386172 -259.564886)
		)
		(stroke
			(width 0)
			(type solid)
		)
		(fill yes)
		(layer "In6.Cu")
		(net "M_C_CPU0_SA_CB<6>")
	)
	(gr_poly
		(pts
			(xy 335.433162 -258.193286) (xy 335.386172 -258.040886) (xy 335.124552 -258.040886) (xy 335.077562 -258.193286)
			(xy 335.077562 -258.237736) (xy 335.433162 -258.237736)
		)
		(stroke
			(width 0)
			(type solid)
		)
		(fill yes)
		(layer "In6.Cu")
		(net "M_C_CPU0_SA_CB<5>")
	)
	(gr_poly
		(pts
			(xy 335.433162 -256.565654) (xy 335.386172 -256.413254) (xy 335.124552 -256.413254) (xy 335.077562 -256.565654)
			(xy 335.077562 -256.610104) (xy 335.433162 -256.610104)
		)
		(stroke
			(width 0)
			(type solid)
		)
		(fill yes)
		(layer "In6.Cu")
		(net "M_D_CPU0_SB_RSP<0>")
	)
	(gr_poly
		(pts
			(xy 335.433162 -256.157222) (xy 335.433162 -256.112772) (xy 335.077562 -256.112772) (xy 335.077562 -256.157222)
			(xy 335.124552 -256.309622) (xy 335.386172 -256.309622)
		)
		(stroke
			(width 0)
			(type solid)
		)
		(fill yes)
		(layer "In6.Cu")
		(net "M_D_CPU0_SA_RSP<1>")
	)
	(gr_poly
		(pts
			(xy 335.433162 -254.938022) (xy 335.386172 -254.785622) (xy 335.124552 -254.785622) (xy 335.077562 -254.938022)
			(xy 335.077562 -254.982218) (xy 335.433162 -254.982218)
		)
		(stroke
			(width 0)
			(type solid)
		)
		(fill yes)
		(layer "In6.Cu")
		(net "M_C_CPU0_SB_RSP<0>")
	)
	(gr_poly
		(pts
			(xy 335.433162 -254.529082) (xy 335.433162 -254.484886) (xy 335.077562 -254.484886) (xy 335.077562 -254.529082)
			(xy 335.124552 -254.681482) (xy 335.386172 -254.681482)
		)
		(stroke
			(width 0)
			(type solid)
		)
		(fill yes)
		(layer "In6.Cu")
		(net "M_C_CPU0_SA_RSP<1>")
	)
	(gr_poly
		(pts
			(xy 335.439258 -272.843498) (xy 335.392268 -272.691098) (xy 335.130648 -272.691098) (xy 335.083658 -272.843498)
			(xy 335.083658 -272.887948) (xy 335.439258 -272.887948)
		)
		(stroke
			(width 0)
			(type solid)
		)
		(fill yes)
		(layer "In6.Cu")
		(net "M_C_CPU0_SA_DQ<10>")
	)
	(gr_poly
		(pts
			(xy 335.439258 -272.435066) (xy 335.439258 -272.390616) (xy 335.083658 -272.390616) (xy 335.083658 -272.435066)
			(xy 335.130648 -272.587466) (xy 335.392268 -272.587466)
		)
		(stroke
			(width 0)
			(type solid)
		)
		(fill yes)
		(layer "In6.Cu")
		(net "M_C_CPU0_SA_DQ<9>")
	)
	(gr_poly
		(pts
			(xy 335.51241 -274.531582) (xy 335.403952 -274.414742) (xy 335.365598 -274.392644) (xy 335.187798 -274.700492)
			(xy 335.226152 -274.72259) (xy 335.3816 -274.75815)
		)
		(stroke
			(width 0)
			(type solid)
		)
		(fill yes)
		(layer "In6.Cu")
		(net "M_D_CPU0_SA_DQ<5>")
	)
	(gr_poly
		(pts
			(xy 335.51241 -271.27581) (xy 335.403952 -271.15897) (xy 335.365598 -271.136872) (xy 335.187798 -271.44472)
			(xy 335.226152 -271.466818) (xy 335.3816 -271.502378)
		)
		(stroke
			(width 0)
			(type solid)
		)
		(fill yes)
		(layer "In6.Cu")
		(net "M_C_CPU0_SA_DQS_DP<1>")
	)
	(gr_poly
		(pts
			(xy 335.642712 -226.469956) (xy 335.681066 -226.447858) (xy 335.503266 -226.14001) (xy 335.464912 -226.162108)
			(xy 335.356454 -226.278948) (xy 335.487264 -226.505516)
		)
		(stroke
			(width 0)
			(type solid)
		)
		(fill yes)
		(layer "In6.Cu")
		(net "M_C_CPU0_SB_DQS_DP<3>")
	)
	(gr_poly
		(pts
			(xy 335.6483 -228.106986) (xy 335.686654 -228.084888) (xy 335.508854 -227.77704) (xy 335.4705 -227.799138)
			(xy 335.362042 -227.915978) (xy 335.492852 -228.142546)
		)
		(stroke
			(width 0)
			(type solid)
		)
		(fill yes)
		(layer "In6.Cu")
		(net "M_C_CPU0_SB_DQ<25>")
	)
	(gr_poly
		(pts
			(xy 335.651094 -234.623102) (xy 335.689448 -234.601004) (xy 335.511648 -234.293156) (xy 335.473294 -234.315254)
			(xy 335.364836 -234.432094) (xy 335.495646 -234.658662)
		)
		(stroke
			(width 0)
			(type solid)
		)
		(fill yes)
		(layer "In6.Cu")
		(net "M_D_CPU0_SB_DQ<16>")
	)
	(gr_poly
		(pts
			(xy 335.757774 -233.9975) (xy 335.866232 -233.88066) (xy 335.735422 -233.654092) (xy 335.579974 -233.689652)
			(xy 335.54162 -233.71175) (xy 335.71942 -234.019598)
		)
		(stroke
			(width 0)
			(type solid)
		)
		(fill yes)
		(layer "In6.Cu")
		(net "M_D_CPU0_SB_DQ<18>")
	)
	(gr_poly
		(pts
			(xy 335.75879 -225.860356) (xy 335.867248 -225.743516) (xy 335.736438 -225.516948) (xy 335.58099 -225.552508)
			(xy 335.542636 -225.574606) (xy 335.720436 -225.882454)
		)
		(stroke
			(width 0)
			(type solid)
		)
		(fill yes)
		(layer "In6.Cu")
		(net "M_C_CPU0_SB_DQS_DN<3>")
	)
	(gr_poly
		(pts
			(xy 335.764124 -227.497386) (xy 335.872582 -227.380546) (xy 335.741772 -227.153978) (xy 335.586324 -227.189538)
			(xy 335.54797 -227.211636) (xy 335.72577 -227.519484)
		)
		(stroke
			(width 0)
			(type solid)
		)
		(fill yes)
		(layer "In6.Cu")
		(net "M_C_CPU0_SB_DQ<27>")
	)
	(gr_poly
		(pts
			(xy 335.787238 -243.718842) (xy 335.787238 -243.674392) (xy 335.431638 -243.674392) (xy 335.431638 -243.718842)
			(xy 335.478628 -243.871242) (xy 335.740248 -243.871242)
		)
		(stroke
			(width 0)
			(type solid)
		)
		(fill yes)
		(layer "In6.Cu")
		(net "M_C_CPU0_SB_DQ<1>")
	)
	(gr_poly
		(pts
			(xy 335.787238 -237.207806) (xy 335.787238 -237.163356) (xy 335.431638 -237.163356) (xy 335.431638 -237.207806)
			(xy 335.478628 -237.360206) (xy 335.740248 -237.360206)
		)
		(stroke
			(width 0)
			(type solid)
		)
		(fill yes)
		(layer "In6.Cu")
		(net "M_C_CPU0_SB_DQS_DN<6>")
	)
	(gr_poly
		(pts
			(xy 335.787238 -229.477062) (xy 335.740248 -229.324662) (xy 335.478628 -229.324662) (xy 335.431638 -229.477062)
			(xy 335.431638 -229.521258) (xy 335.787238 -229.521258)
		)
		(stroke
			(width 0)
			(type solid)
		)
		(fill yes)
		(layer "In6.Cu")
		(net "M_D_CPU0_SB_DQ<23>")
	)
	(gr_poly
		(pts
			(xy 335.787238 -229.06863) (xy 335.787238 -229.024434) (xy 335.431638 -229.024434) (xy 335.431638 -229.06863)
			(xy 335.478628 -229.22103) (xy 335.740248 -229.22103)
		)
		(stroke
			(width 0)
			(type solid)
		)
		(fill yes)
		(layer "In6.Cu")
		(net "M_C_CPU0_SB_DQ<26>")
	)
	(gr_poly
		(pts
			(xy 335.790794 -274.6502) (xy 335.75244 -274.628102) (xy 335.596992 -274.592542) (xy 335.466182 -274.81911)
			(xy 335.57464 -274.93595) (xy 335.612994 -274.958048)
		)
		(stroke
			(width 0)
			(type solid)
		)
		(fill yes)
		(layer "In6.Cu")
		(net "M_D_CPU0_SA_DQ<6>")
	)
	(gr_poly
		(pts
			(xy 335.793334 -248.601738) (xy 335.793334 -248.557542) (xy 335.437734 -248.557542) (xy 335.437734 -248.601738)
			(xy 335.484724 -248.754138) (xy 335.746344 -248.754138)
		)
		(stroke
			(width 0)
			(type solid)
		)
		(fill yes)
		(layer "In6.Cu")
		(net "M_A_CPU0_SB_RSP<0>")
	)
	(gr_poly
		(pts
			(xy 335.793334 -247.382538) (xy 335.746344 -247.230138) (xy 335.484724 -247.230138) (xy 335.437734 -247.382538)
			(xy 335.437734 -247.426988) (xy 335.793334 -247.426988)
		)
		(stroke
			(width 0)
			(type solid)
		)
		(fill yes)
		(layer "In6.Cu")
		(net "M_A_CPU0_SB_RSP<1>")
	)
	(gr_poly
		(pts
			(xy 335.793334 -245.754906) (xy 335.746344 -245.602506) (xy 335.484724 -245.602506) (xy 335.437734 -245.754906)
			(xy 335.437734 -245.799356) (xy 335.793334 -245.799356)
		)
		(stroke
			(width 0)
			(type solid)
		)
		(fill yes)
		(layer "In6.Cu")
		(net "M_D_CPU0_SB_CS_N<3>")
	)
	(gr_poly
		(pts
			(xy 335.793334 -242.499134) (xy 335.746344 -242.346734) (xy 335.484724 -242.346734) (xy 335.437734 -242.499134)
			(xy 335.437734 -242.54333) (xy 335.793334 -242.54333)
		)
		(stroke
			(width 0)
			(type solid)
		)
		(fill yes)
		(layer "In6.Cu")
		(net "M_C_CPU0_SB_DQS_DN<0>")
	)
	(gr_poly
		(pts
			(xy 335.793334 -242.090702) (xy 335.793334 -242.046506) (xy 335.437734 -242.046506) (xy 335.437734 -242.090702)
			(xy 335.484724 -242.243102) (xy 335.746344 -242.243102)
		)
		(stroke
			(width 0)
			(type solid)
		)
		(fill yes)
		(layer "In6.Cu")
		(net "M_C_CPU0_SB_DQS_DN<5>")
	)
	(gr_poly
		(pts
			(xy 335.793334 -240.871502) (xy 335.746344 -240.719102) (xy 335.484724 -240.719102) (xy 335.437734 -240.871502)
			(xy 335.437734 -240.915952) (xy 335.793334 -240.915952)
		)
		(stroke
			(width 0)
			(type solid)
		)
		(fill yes)
		(layer "In6.Cu")
		(net "M_C_CPU0_SB_DQ<6>")
	)
	(gr_poly
		(pts
			(xy 335.793334 -238.83493) (xy 335.793334 -238.790734) (xy 335.437734 -238.790734) (xy 335.437734 -238.83493)
			(xy 335.484724 -238.98733) (xy 335.746344 -238.98733)
		)
		(stroke
			(width 0)
			(type solid)
		)
		(fill yes)
		(layer "In6.Cu")
		(net "M_C_CPU0_SB_DQ<9>")
	)
	(gr_poly
		(pts
			(xy 335.793334 -235.579666) (xy 335.793334 -235.53547) (xy 335.437734 -235.53547) (xy 335.437734 -235.579666)
			(xy 335.484724 -235.732066) (xy 335.746344 -235.732066)
		)
		(stroke
			(width 0)
			(type solid)
		)
		(fill yes)
		(layer "In6.Cu")
		(net "M_C_CPU0_SB_DQ<13>")
	)
	(gr_poly
		(pts
			(xy 335.793334 -232.732834) (xy 335.746344 -232.580434) (xy 335.484724 -232.580434) (xy 335.437734 -232.732834)
			(xy 335.437734 -232.77703) (xy 335.793334 -232.77703)
		)
		(stroke
			(width 0)
			(type solid)
		)
		(fill yes)
		(layer "In6.Cu")
		(net "M_D_CPU0_SB_DQ<19>")
	)
	(gr_poly
		(pts
			(xy 335.793334 -232.323894) (xy 335.793334 -232.279698) (xy 335.437734 -232.279698) (xy 335.437734 -232.323894)
			(xy 335.484724 -232.476294) (xy 335.746344 -232.476294)
		)
		(stroke
			(width 0)
			(type solid)
		)
		(fill yes)
		(layer "In6.Cu")
		(net "M_D_CPU0_SB_DQS_DP<2>")
	)
	(gr_poly
		(pts
			(xy 335.793334 -230.696262) (xy 335.793334 -230.652066) (xy 335.437734 -230.652066) (xy 335.437734 -230.696262)
			(xy 335.484724 -230.848662) (xy 335.746344 -230.848662)
		)
		(stroke
			(width 0)
			(type solid)
		)
		(fill yes)
		(layer "In6.Cu")
		(net "M_D_CPU0_SB_DQ<20>")
	)
	(gr_poly
		(pts
			(xy 335.793334 -224.593658) (xy 335.746344 -224.441258) (xy 335.484724 -224.441258) (xy 335.437734 -224.593658)
			(xy 335.437734 -224.638108) (xy 335.793334 -224.638108)
		)
		(stroke
			(width 0)
			(type solid)
		)
		(fill yes)
		(layer "In6.Cu")
		(net "M_C_CPU0_SB_DQS_DP<8>")
	)
	(gr_poly
		(pts
			(xy 335.793334 -224.185226) (xy 335.793334 -224.140776) (xy 335.437734 -224.140776) (xy 335.437734 -224.185226)
			(xy 335.484724 -224.337626) (xy 335.746344 -224.337626)
		)
		(stroke
			(width 0)
			(type solid)
		)
		(fill yes)
		(layer "In6.Cu")
		(net "M_C_CPU0_SB_DQ<28>")
	)
	(gr_poly
		(pts
			(xy 335.797144 -271.384522) (xy 335.75879 -271.362424) (xy 335.603342 -271.326864) (xy 335.472532 -271.553432)
			(xy 335.58099 -271.670272) (xy 335.619344 -271.69237)
		)
		(stroke
			(width 0)
			(type solid)
		)
		(fill yes)
		(layer "In6.Cu")
		(net "M_C_CPU0_SA_DQ<11>")
	)
	(gr_poly
		(pts
			(xy 335.798414 -237.61573) (xy 335.751424 -237.46333) (xy 335.489804 -237.46333) (xy 335.442814 -237.61573)
			(xy 335.442814 -237.66018) (xy 335.798414 -237.66018)
		)
		(stroke
			(width 0)
			(type solid)
		)
		(fill yes)
		(layer "In6.Cu")
		(net "M_C_CPU0_SB_DQS_DN<1>")
	)
	(gr_poly
		(pts
			(xy 335.798668 -240.46307) (xy 335.798668 -240.418874) (xy 335.443068 -240.418874) (xy 335.443068 -240.46307)
			(xy 335.490058 -240.61547) (xy 335.751678 -240.61547)
		)
		(stroke
			(width 0)
			(type solid)
		)
		(fill yes)
		(layer "In6.Cu")
		(net "M_C_CPU0_SB_DQ<5>")
	)
	(gr_poly
		(pts
			(xy 335.799176 -244.126766) (xy 335.752186 -243.974366) (xy 335.490566 -243.974366) (xy 335.443576 -244.126766)
			(xy 335.443576 -244.171216) (xy 335.799176 -244.171216)
		)
		(stroke
			(width 0)
			(type solid)
		)
		(fill yes)
		(layer "In6.Cu")
		(net "M_C_CPU0_SB_DQ<2>")
	)
	(gr_poly
		(pts
			(xy 335.79943 -222.965518) (xy 335.75244 -222.813118) (xy 335.49082 -222.813118) (xy 335.44383 -222.965518)
			(xy 335.44383 -223.009968) (xy 335.79943 -223.009968)
		)
		(stroke
			(width 0)
			(type solid)
		)
		(fill yes)
		(layer "In6.Cu")
		(net "M_C_CPU0_SB_DQ<29>")
	)
	(gr_poly
		(pts
			(xy 335.801208 -235.988098) (xy 335.754218 -235.835698) (xy 335.492598 -235.835698) (xy 335.445608 -235.988098)
			(xy 335.445608 -236.032548) (xy 335.801208 -236.032548)
		)
		(stroke
			(width 0)
			(type solid)
		)
		(fill yes)
		(layer "In6.Cu")
		(net "M_C_CPU0_SB_DQ<14>")
	)
	(gr_poly
		(pts
			(xy 335.801208 -231.104694) (xy 335.754218 -230.952294) (xy 335.492598 -230.952294) (xy 335.445608 -231.104694)
			(xy 335.445608 -231.149144) (xy 335.801208 -231.149144)
		)
		(stroke
			(width 0)
			(type solid)
		)
		(fill yes)
		(layer "In6.Cu")
		(net "M_D_CPU0_SB_DQS_DP<7>")
	)
	(gr_poly
		(pts
			(xy 335.801716 -245.346474) (xy 335.801716 -245.302278) (xy 335.446116 -245.302278) (xy 335.446116 -245.346474)
			(xy 335.493106 -245.498874) (xy 335.754726 -245.498874)
		)
		(stroke
			(width 0)
			(type solid)
		)
		(fill yes)
		(layer "In6.Cu")
		(net "M_D_CPU0_SB_CS_N<0>")
	)
	(gr_poly
		(pts
			(xy 335.801716 -239.243362) (xy 335.754726 -239.090962) (xy 335.493106 -239.090962) (xy 335.446116 -239.243362)
			(xy 335.446116 -239.287812) (xy 335.801716 -239.287812)
		)
		(stroke
			(width 0)
			(type solid)
		)
		(fill yes)
		(layer "In6.Cu")
		(net "M_C_CPU0_SB_DQ<10>")
	)
	(gr_poly
		(pts
			(xy 335.903062 -279.759664) (xy 335.903062 -279.715468) (xy 335.547462 -279.715468) (xy 335.547462 -279.759664)
			(xy 335.594452 -279.912064) (xy 335.856072 -279.912064)
		)
		(stroke
			(width 0)
			(type solid)
		)
		(fill yes)
		(layer "In6.Cu")
		(net "M_D_CPU0_SA_DQ<0>")
	)
	(gr_poly
		(pts
			(xy 335.903062 -278.540718) (xy 335.856072 -278.388318) (xy 335.594452 -278.388318) (xy 335.547462 -278.540718)
			(xy 335.547462 -278.585168) (xy 335.903062 -278.585168)
		)
		(stroke
			(width 0)
			(type solid)
		)
		(fill yes)
		(layer "In6.Cu")
		(net "M_D_CPU0_SA_DQ<3>")
	)
	(gr_poly
		(pts
			(xy 335.903062 -273.657314) (xy 335.856072 -273.504914) (xy 335.594452 -273.504914) (xy 335.547462 -273.657314)
			(xy 335.547462 -273.701764) (xy 335.903062 -273.701764)
		)
		(stroke
			(width 0)
			(type solid)
		)
		(fill yes)
		(layer "In6.Cu")
		(net "M_D_CPU0_SA_DQ<7>")
	)
	(gr_poly
		(pts
			(xy 335.903062 -273.248882) (xy 335.903062 -273.204432) (xy 335.547462 -273.204432) (xy 335.547462 -273.248882)
			(xy 335.594452 -273.401282) (xy 335.856072 -273.401282)
		)
		(stroke
			(width 0)
			(type solid)
		)
		(fill yes)
		(layer "In6.Cu")
		(net "M_C_CPU0_SA_DQ<8>")
	)
	(gr_poly
		(pts
			(xy 335.903062 -270.40205) (xy 335.856072 -270.24965) (xy 335.594452 -270.24965) (xy 335.547462 -270.40205)
			(xy 335.547462 -270.446246) (xy 335.903062 -270.446246)
		)
		(stroke
			(width 0)
			(type solid)
		)
		(fill yes)
		(layer "In6.Cu")
		(net "M_C_CPU0_SA_DQS_DN<1>")
	)
	(gr_poly
		(pts
			(xy 335.903062 -269.99311) (xy 335.903062 -269.948914) (xy 335.547462 -269.948914) (xy 335.547462 -269.99311)
			(xy 335.594452 -270.14551) (xy 335.856072 -270.14551)
		)
		(stroke
			(width 0)
			(type solid)
		)
		(fill yes)
		(layer "In6.Cu")
		(net "M_C_CPU0_SA_DQS_DN<6>")
	)
	(gr_poly
		(pts
			(xy 335.903062 -268.77391) (xy 335.856072 -268.62151) (xy 335.594452 -268.62151) (xy 335.547462 -268.77391)
			(xy 335.547462 -268.81836) (xy 335.903062 -268.81836)
		)
		(stroke
			(width 0)
			(type solid)
		)
		(fill yes)
		(layer "In6.Cu")
		(net "M_C_CPU0_SA_DQ<14>")
	)
	(gr_poly
		(pts
			(xy 335.903062 -268.365478) (xy 335.903062 -268.321028) (xy 335.547462 -268.321028) (xy 335.547462 -268.365478)
			(xy 335.594452 -268.517878) (xy 335.856072 -268.517878)
		)
		(stroke
			(width 0)
			(type solid)
		)
		(fill yes)
		(layer "In6.Cu")
		(net "M_C_CPU0_SA_DQ<13>")
	)
	(gr_poly
		(pts
			(xy 335.903062 -267.146278) (xy 335.856072 -266.993878) (xy 335.594452 -266.993878) (xy 335.547462 -267.146278)
			(xy 335.547462 -267.190474) (xy 335.903062 -267.190474)
		)
		(stroke
			(width 0)
			(type solid)
		)
		(fill yes)
		(layer "In6.Cu")
		(net "M_C_CPU0_SA_DQ<26>")
	)
	(gr_poly
		(pts
			(xy 335.903062 -266.737846) (xy 335.903062 -266.693396) (xy 335.547462 -266.693396) (xy 335.547462 -266.737846)
			(xy 335.594452 -266.890246) (xy 335.856072 -266.890246)
		)
		(stroke
			(width 0)
			(type solid)
		)
		(fill yes)
		(layer "In6.Cu")
		(net "M_C_CPU0_SA_DQ<25>")
	)
	(gr_poly
		(pts
			(xy 335.903062 -265.518646) (xy 335.856072 -265.366246) (xy 335.594452 -265.366246) (xy 335.547462 -265.518646)
			(xy 335.547462 -265.562842) (xy 335.903062 -265.562842)
		)
		(stroke
			(width 0)
			(type solid)
		)
		(fill yes)
		(layer "In6.Cu")
		(net "M_C_CPU0_SA_DQS_DN<3>")
	)
	(gr_poly
		(pts
			(xy 335.903062 -265.109706) (xy 335.903062 -265.06551) (xy 335.547462 -265.06551) (xy 335.547462 -265.109706)
			(xy 335.594452 -265.262106) (xy 335.856072 -265.262106)
		)
		(stroke
			(width 0)
			(type solid)
		)
		(fill yes)
		(layer "In6.Cu")
		(net "M_C_CPU0_SA_DQS_DN<8>")
	)
	(gr_poly
		(pts
			(xy 335.903062 -263.891014) (xy 335.856072 -263.738614) (xy 335.594452 -263.738614) (xy 335.547462 -263.891014)
			(xy 335.547462 -263.93521) (xy 335.903062 -263.93521)
		)
		(stroke
			(width 0)
			(type solid)
		)
		(fill yes)
		(layer "In6.Cu")
		(net "M_C_CPU0_SA_DQ<30>")
	)
	(gr_poly
		(pts
			(xy 335.903062 -263.482074) (xy 335.903062 -263.437878) (xy 335.547462 -263.437878) (xy 335.547462 -263.482074)
			(xy 335.594452 -263.634474) (xy 335.856072 -263.634474)
		)
		(stroke
			(width 0)
			(type solid)
		)
		(fill yes)
		(layer "In6.Cu")
		(net "M_C_CPU0_SA_DQ<29>")
	)
	(gr_poly
		(pts
			(xy 335.903062 -262.262874) (xy 335.856072 -262.110474) (xy 335.594452 -262.110474) (xy 335.547462 -262.262874)
			(xy 335.547462 -262.307324) (xy 335.903062 -262.307324)
		)
		(stroke
			(width 0)
			(type solid)
		)
		(fill yes)
		(layer "In6.Cu")
		(net "M_C_CPU0_SA_CB<0>")
	)
	(gr_poly
		(pts
			(xy 335.903062 -261.854442) (xy 335.903062 -261.809992) (xy 335.547462 -261.809992) (xy 335.547462 -261.854442)
			(xy 335.594452 -262.006842) (xy 335.856072 -262.006842)
		)
		(stroke
			(width 0)
			(type solid)
		)
		(fill yes)
		(layer "In6.Cu")
		(net "M_C_CPU0_SA_CB<3>")
	)
	(gr_poly
		(pts
			(xy 335.903062 -260.635242) (xy 335.856072 -260.482842) (xy 335.594452 -260.482842) (xy 335.547462 -260.635242)
			(xy 335.547462 -260.679438) (xy 335.903062 -260.679438)
		)
		(stroke
			(width 0)
			(type solid)
		)
		(fill yes)
		(layer "In6.Cu")
		(net "M_C_CPU0_SA_DQS_DP<9>")
	)
	(gr_poly
		(pts
			(xy 335.903062 -260.226302) (xy 335.903062 -260.182106) (xy 335.547462 -260.182106) (xy 335.547462 -260.226302)
			(xy 335.594452 -260.378702) (xy 335.856072 -260.378702)
		)
		(stroke
			(width 0)
			(type solid)
		)
		(fill yes)
		(layer "In6.Cu")
		(net "M_C_CPU0_SA_DQS_DP<4>")
	)
	(gr_poly
		(pts
			(xy 335.903062 -259.00761) (xy 335.856072 -258.85521) (xy 335.594452 -258.85521) (xy 335.547462 -259.00761)
			(xy 335.547462 -259.051806) (xy 335.903062 -259.051806)
		)
		(stroke
			(width 0)
			(type solid)
		)
		(fill yes)
		(layer "In6.Cu")
		(net "M_C_CPU0_SA_CB<4>")
	)
	(gr_poly
		(pts
			(xy 335.903062 -258.59867) (xy 335.903062 -258.554474) (xy 335.547462 -258.554474) (xy 335.547462 -258.59867)
			(xy 335.594452 -258.75107) (xy 335.856072 -258.75107)
		)
		(stroke
			(width 0)
			(type solid)
		)
		(fill yes)
		(layer "In6.Cu")
		(net "M_C_CPU0_SA_CB<7>")
	)
	(gr_poly
		(pts
			(xy 335.903062 -256.971038) (xy 335.903062 -256.926588) (xy 335.547462 -256.926588) (xy 335.547462 -256.971038)
			(xy 335.594452 -257.123438) (xy 335.856072 -257.123438)
		)
		(stroke
			(width 0)
			(type solid)
		)
		(fill yes)
		(layer "In6.Cu")
		(net "M_D_CPU0_SA_RSP<0>")
	)
	(gr_poly
		(pts
			(xy 335.903062 -255.751838) (xy 335.856072 -255.599438) (xy 335.594452 -255.599438) (xy 335.547462 -255.751838)
			(xy 335.547462 -255.796288) (xy 335.903062 -255.796288)
		)
		(stroke
			(width 0)
			(type solid)
		)
		(fill yes)
		(layer "In6.Cu")
		(net "M_D_CPU0_SB_RSP<1>")
	)
	(gr_poly
		(pts
			(xy 335.903062 -255.343406) (xy 335.903062 -255.298956) (xy 335.547462 -255.298956) (xy 335.547462 -255.343406)
			(xy 335.594452 -255.495806) (xy 335.856072 -255.495806)
		)
		(stroke
			(width 0)
			(type solid)
		)
		(fill yes)
		(layer "In6.Cu")
		(net "M_C_CPU0_SA_RSP<0>")
	)
	(gr_poly
		(pts
			(xy 335.903062 -254.124206) (xy 335.856072 -253.971806) (xy 335.594452 -253.971806) (xy 335.547462 -254.124206)
			(xy 335.547462 -254.168402) (xy 335.903062 -254.168402)
		)
		(stroke
			(width 0)
			(type solid)
		)
		(fill yes)
		(layer "In6.Cu")
		(net "M_C_CPU0_SB_RSP<1>")
	)
	(gr_poly
		(pts
			(xy 335.911444 -278.132286) (xy 335.911444 -278.08809) (xy 335.555844 -278.08809) (xy 335.555844 -278.132286)
			(xy 335.602834 -278.284686) (xy 335.864454 -278.284686)
		)
		(stroke
			(width 0)
			(type solid)
		)
		(fill yes)
		(layer "In6.Cu")
		(net "M_D_CPU0_SA_DQS_DP<0>")
	)
	(gr_poly
		(pts
			(xy 335.911444 -276.5044) (xy 335.911444 -276.460204) (xy 335.555844 -276.460204) (xy 335.555844 -276.5044)
			(xy 335.602834 -276.6568) (xy 335.864454 -276.6568)
		)
		(stroke
			(width 0)
			(type solid)
		)
		(fill yes)
		(layer "In6.Cu")
		(net "M_D_CPU0_SA_DQS_DN<5>")
	)
	(gr_poly
		(pts
			(xy 335.97596 -272.101056) (xy 335.867502 -271.984216) (xy 335.829148 -271.962118) (xy 335.651348 -272.269966)
			(xy 335.689702 -272.292064) (xy 335.84515 -272.327624)
		)
		(stroke
			(width 0)
			(type solid)
		)
		(fill yes)
		(layer "In6.Cu")
		(net "M_C_CPU0_SA_DQ<9>")
	)
	(gr_poly
		(pts
			(xy 335.9785 -275.351748) (xy 335.870042 -275.234908) (xy 335.831688 -275.21281) (xy 335.653888 -275.520658)
			(xy 335.692242 -275.542756) (xy 335.84769 -275.578316)
		)
		(stroke
			(width 0)
			(type solid)
		)
		(fill yes)
		(layer "In6.Cu")
		(net "M_D_CPU0_SA_DQ<4>")
	)
	(gr_poly
		(pts
			(xy 336.11439 -227.28682) (xy 336.152744 -227.264722) (xy 335.974944 -226.956874) (xy 335.93659 -226.978972)
			(xy 335.828132 -227.095812) (xy 335.958942 -227.32238)
		)
		(stroke
			(width 0)
			(type solid)
		)
		(fill yes)
		(layer "In6.Cu")
		(net "M_C_CPU0_SB_DQS_DP<3>")
	)
	(gr_poly
		(pts
			(xy 336.119724 -233.807) (xy 336.158078 -233.784902) (xy 335.980278 -233.477054) (xy 335.941924 -233.499152)
			(xy 335.833466 -233.615992) (xy 335.964276 -233.84256)
		)
		(stroke
			(width 0)
			(type solid)
		)
		(fill yes)
		(layer "In6.Cu")
		(net "M_D_CPU0_SB_DQ<17>")
	)
	(gr_poly
		(pts
			(xy 336.120994 -225.67011) (xy 336.159348 -225.648012) (xy 335.981548 -225.340164) (xy 335.943194 -225.362262)
			(xy 335.834736 -225.479102) (xy 335.965546 -225.70567)
		)
		(stroke
			(width 0)
			(type solid)
		)
		(fill yes)
		(layer "In6.Cu")
		(net "M_C_CPU0_SB_DQS_DN<8>")
	)
	(gr_poly
		(pts
			(xy 336.229706 -233.18724) (xy 336.338164 -233.0704) (xy 336.207354 -232.843832) (xy 336.051906 -232.879392)
			(xy 336.013552 -232.90149) (xy 336.191352 -233.209338)
		)
		(stroke
			(width 0)
			(type solid)
		)
		(fill yes)
		(layer "In6.Cu")
		(net "M_D_CPU0_SB_DQ<19>")
	)
	(gr_poly
		(pts
			(xy 336.229706 -226.676204) (xy 336.338164 -226.559364) (xy 336.207354 -226.332796) (xy 336.051906 -226.368356)
			(xy 336.013552 -226.390454) (xy 336.191352 -226.698302)
		)
		(stroke
			(width 0)
			(type solid)
		)
		(fill yes)
		(layer "In6.Cu")
		(net "M_C_CPU0_SB_DQS_DN<3>")
	)
	(gr_poly
		(pts
			(xy 336.229706 -225.048318) (xy 336.338164 -224.931478) (xy 336.207354 -224.70491) (xy 336.051906 -224.74047)
			(xy 336.013552 -224.762568) (xy 336.191352 -225.070416)
		)
		(stroke
			(width 0)
			(type solid)
		)
		(fill yes)
		(layer "In6.Cu")
		(net "M_C_CPU0_SB_DQS_DP<8>")
	)
	(gr_poly
		(pts
			(xy 336.252566 -240.057178) (xy 336.205576 -239.904778) (xy 335.943956 -239.904778) (xy 335.896966 -240.057178)
			(xy 335.896966 -240.101628) (xy 336.252566 -240.101628)
		)
		(stroke
			(width 0)
			(type solid)
		)
		(fill yes)
		(layer "In6.Cu")
		(net "M_C_CPU0_SB_DQ<7>")
	)
	(gr_poly
		(pts
			(xy 336.253328 -234.76585) (xy 336.253328 -234.721654) (xy 335.897728 -234.721654) (xy 335.897728 -234.76585)
			(xy 335.944718 -234.91825) (xy 336.206338 -234.91825)
		)
		(stroke
			(width 0)
			(type solid)
		)
		(fill yes)
		(layer "In6.Cu")
		(net "M_D_CPU0_SB_DQ<16>")
	)
	(gr_poly
		(pts
			(xy 336.253328 -229.882446) (xy 336.253328 -229.83825) (xy 335.897728 -229.83825) (xy 335.897728 -229.882446)
			(xy 335.944718 -230.034846) (xy 336.206338 -230.034846)
		)
		(stroke
			(width 0)
			(type solid)
		)
		(fill yes)
		(layer "In6.Cu")
		(net "M_D_CPU0_SB_DQ<21>")
	)
	(gr_poly
		(pts
			(xy 336.254598 -244.940582) (xy 336.207608 -244.788182) (xy 335.945988 -244.788182) (xy 335.898998 -244.940582)
			(xy 335.898998 -244.985032) (xy 336.254598 -244.985032)
		)
		(stroke
			(width 0)
			(type solid)
		)
		(fill yes)
		(layer "In6.Cu")
		(net "M_D_CPU0_SB_CS_N<1>")
	)
	(gr_poly
		(pts
			(xy 336.254598 -244.532658) (xy 336.254598 -244.488208) (xy 335.898998 -244.488208) (xy 335.898998 -244.532658)
			(xy 335.945988 -244.685058) (xy 336.207608 -244.685058)
		)
		(stroke
			(width 0)
			(type solid)
		)
		(fill yes)
		(layer "In6.Cu")
		(net "M_C_CPU0_SB_DQ<0>")
	)
	(gr_poly
		(pts
			(xy 336.254598 -239.649254) (xy 336.254598 -239.604804) (xy 335.898998 -239.604804) (xy 335.898998 -239.649254)
			(xy 335.945988 -239.801654) (xy 336.207608 -239.801654)
		)
		(stroke
			(width 0)
			(type solid)
		)
		(fill yes)
		(layer "In6.Cu")
		(net "M_C_CPU0_SB_DQ<8>")
	)
	(gr_poly
		(pts
			(xy 336.254852 -241.685318) (xy 336.207862 -241.532918) (xy 335.946242 -241.532918) (xy 335.899252 -241.685318)
			(xy 335.899252 -241.729514) (xy 336.254852 -241.729514)
		)
		(stroke
			(width 0)
			(type solid)
		)
		(fill yes)
		(layer "In6.Cu")
		(net "M_C_CPU0_SB_DQS_DP<5>")
	)
	(gr_poly
		(pts
			(xy 336.254852 -223.37141) (xy 336.254852 -223.327214) (xy 335.899252 -223.327214) (xy 335.899252 -223.37141)
			(xy 335.946242 -223.52381) (xy 336.207862 -223.52381)
		)
		(stroke
			(width 0)
			(type solid)
		)
		(fill yes)
		(layer "In6.Cu")
		(net "M_C_CPU0_SB_DQ<31>")
	)
	(gr_poly
		(pts
			(xy 336.257138 -248.196354) (xy 336.210148 -248.043954) (xy 335.948528 -248.043954) (xy 335.901538 -248.196354)
			(xy 335.901538 -248.240804) (xy 336.257138 -248.240804)
		)
		(stroke
			(width 0)
			(type solid)
		)
		(fill yes)
		(layer "In6.Cu")
		(net "M_A_CPU0_SA_RSP<0>")
	)
	(gr_poly
		(pts
			(xy 336.257138 -247.787922) (xy 336.257138 -247.743472) (xy 335.901538 -247.743472) (xy 335.901538 -247.787922)
			(xy 335.948528 -247.940322) (xy 336.210148 -247.940322)
		)
		(stroke
			(width 0)
			(type solid)
		)
		(fill yes)
		(layer "In6.Cu")
		(net "M_A_CPU0_SA_RSP<1>")
	)
	(gr_poly
		(pts
			(xy 336.257138 -246.16029) (xy 336.257138 -246.11584) (xy 335.901538 -246.11584) (xy 335.901538 -246.16029)
			(xy 335.948528 -246.31269) (xy 336.210148 -246.31269)
		)
		(stroke
			(width 0)
			(type solid)
		)
		(fill yes)
		(layer "In6.Cu")
		(net "M_D_CPU0_SB_CS_N<2>")
	)
	(gr_poly
		(pts
			(xy 336.257138 -243.313458) (xy 336.210148 -243.161058) (xy 335.948528 -243.161058) (xy 335.901538 -243.313458)
			(xy 335.901538 -243.357654) (xy 336.257138 -243.357654)
		)
		(stroke
			(width 0)
			(type solid)
		)
		(fill yes)
		(layer "In6.Cu")
		(net "M_C_CPU0_SB_DQ<3>")
	)
	(gr_poly
		(pts
			(xy 336.257138 -242.904518) (xy 336.257138 -242.860322) (xy 335.901538 -242.860322) (xy 335.901538 -242.904518)
			(xy 335.948528 -243.056918) (xy 336.210148 -243.056918)
		)
		(stroke
			(width 0)
			(type solid)
		)
		(fill yes)
		(layer "In6.Cu")
		(net "M_C_CPU0_SB_DQS_DP<0>")
	)
	(gr_poly
		(pts
			(xy 336.257138 -241.276886) (xy 336.257138 -241.232436) (xy 335.901538 -241.232436) (xy 335.901538 -241.276886)
			(xy 335.948528 -241.429286) (xy 336.210148 -241.429286)
		)
		(stroke
			(width 0)
			(type solid)
		)
		(fill yes)
		(layer "In6.Cu")
		(net "M_C_CPU0_SB_DQ<4>")
	)
	(gr_poly
		(pts
			(xy 336.257138 -238.430054) (xy 336.210148 -238.277654) (xy 335.948528 -238.277654) (xy 335.901538 -238.430054)
			(xy 335.901538 -238.47425) (xy 336.257138 -238.47425)
		)
		(stroke
			(width 0)
			(type solid)
		)
		(fill yes)
		(layer "In6.Cu")
		(net "M_C_CPU0_SB_DQ<11>")
	)
	(gr_poly
		(pts
			(xy 336.257138 -238.021114) (xy 336.257138 -237.976918) (xy 335.901538 -237.976918) (xy 335.901538 -238.021114)
			(xy 335.948528 -238.173514) (xy 336.210148 -238.173514)
		)
		(stroke
			(width 0)
			(type solid)
		)
		(fill yes)
		(layer "In6.Cu")
		(net "M_C_CPU0_SB_DQS_DP<1>")
	)
	(gr_poly
		(pts
			(xy 336.257138 -235.174282) (xy 336.210148 -235.021882) (xy 335.948528 -235.021882) (xy 335.901538 -235.174282)
			(xy 335.901538 -235.218732) (xy 336.257138 -235.218732)
		)
		(stroke
			(width 0)
			(type solid)
		)
		(fill yes)
		(layer "In6.Cu")
		(net "M_C_CPU0_SB_DQ<15>")
	)
	(gr_poly
		(pts
			(xy 336.257138 -231.919018) (xy 336.210148 -231.766618) (xy 335.948528 -231.766618) (xy 335.901538 -231.919018)
			(xy 335.901538 -231.963214) (xy 336.257138 -231.963214)
		)
		(stroke
			(width 0)
			(type solid)
		)
		(fill yes)
		(layer "In6.Cu")
		(net "M_D_CPU0_SB_DQS_DN<2>")
	)
	(gr_poly
		(pts
			(xy 336.257138 -231.510078) (xy 336.257138 -231.465882) (xy 335.901538 -231.465882) (xy 335.901538 -231.510078)
			(xy 335.948528 -231.662478) (xy 336.210148 -231.662478)
		)
		(stroke
			(width 0)
			(type solid)
		)
		(fill yes)
		(layer "In6.Cu")
		(net "M_D_CPU0_SB_DQS_DN<7>")
	)
	(gr_poly
		(pts
			(xy 336.257138 -230.290878) (xy 336.210148 -230.138478) (xy 335.948528 -230.138478) (xy 335.901538 -230.290878)
			(xy 335.901538 -230.335328) (xy 336.257138 -230.335328)
		)
		(stroke
			(width 0)
			(type solid)
		)
		(fill yes)
		(layer "In6.Cu")
		(net "M_D_CPU0_SB_DQ<22>")
	)
	(gr_poly
		(pts
			(xy 336.257138 -228.663246) (xy 336.210148 -228.510846) (xy 335.948528 -228.510846) (xy 335.901538 -228.663246)
			(xy 335.901538 -228.707696) (xy 336.257138 -228.707696)
		)
		(stroke
			(width 0)
			(type solid)
		)
		(fill yes)
		(layer "In6.Cu")
		(net "M_C_CPU0_SB_DQ<24>")
	)
	(gr_poly
		(pts
			(xy 336.257138 -228.254814) (xy 336.257138 -228.210364) (xy 335.901538 -228.210364) (xy 335.901538 -228.254814)
			(xy 335.948528 -228.407214) (xy 336.210148 -228.407214)
		)
		(stroke
			(width 0)
			(type solid)
		)
		(fill yes)
		(layer "In6.Cu")
		(net "M_C_CPU0_SB_DQ<25>")
	)
	(gr_poly
		(pts
			(xy 336.257138 -223.779842) (xy 336.210148 -223.627442) (xy 335.948528 -223.627442) (xy 335.901538 -223.779842)
			(xy 335.901538 -223.824292) (xy 336.257138 -223.824292)
		)
		(stroke
			(width 0)
			(type solid)
		)
		(fill yes)
		(layer "In6.Cu")
		(net "M_C_CPU0_SB_DQ<30>")
	)
	(gr_poly
		(pts
			(xy 336.263234 -236.801914) (xy 336.216244 -236.649514) (xy 335.954624 -236.649514) (xy 335.907634 -236.801914)
			(xy 335.907634 -236.846364) (xy 336.263234 -236.846364)
		)
		(stroke
			(width 0)
			(type solid)
		)
		(fill yes)
		(layer "In6.Cu")
		(net "M_C_CPU0_SB_DQS_DP<6>")
	)
	(gr_poly
		(pts
			(xy 336.263234 -236.393482) (xy 336.263234 -236.349286) (xy 335.907634 -236.349286) (xy 335.907634 -236.393482)
			(xy 335.954624 -236.545882) (xy 336.216244 -236.545882)
		)
		(stroke
			(width 0)
			(type solid)
		)
		(fill yes)
		(layer "In6.Cu")
		(net "M_C_CPU0_SB_DQ<12>")
	)
	(gr_poly
		(pts
			(xy 336.26806 -272.19656) (xy 336.229706 -272.174462) (xy 336.074258 -272.138902) (xy 335.943448 -272.36547)
			(xy 336.051906 -272.48231) (xy 336.09026 -272.504408)
		)
		(stroke
			(width 0)
			(type solid)
		)
		(fill yes)
		(layer "In6.Cu")
		(net "M_C_CPU0_SA_DQ<10>")
	)
	(gr_poly
		(pts
			(xy 336.364326 -277.726902) (xy 336.317336 -277.574502) (xy 336.055716 -277.574502) (xy 336.008726 -277.726902)
			(xy 336.008726 -277.771098) (xy 336.364326 -277.771098)
		)
		(stroke
			(width 0)
			(type solid)
		)
		(fill yes)
		(layer "In6.Cu")
		(net "M_D_CPU0_SA_DQS_DN<0>")
	)
	(gr_poly
		(pts
			(xy 336.366866 -276.098762) (xy 336.319876 -275.946362) (xy 336.058256 -275.946362) (xy 336.011266 -276.098762)
			(xy 336.011266 -276.143212) (xy 336.366866 -276.143212)
		)
		(stroke
			(width 0)
			(type solid)
		)
		(fill yes)
		(layer "In6.Cu")
		(net "M_D_CPU0_SA_DQS_DP<5>")
	)
	(gr_poly
		(pts
			(xy 336.372962 -279.354788) (xy 336.325972 -279.202388) (xy 336.064352 -279.202388) (xy 336.017362 -279.354788)
			(xy 336.017362 -279.398984) (xy 336.372962 -279.398984)
		)
		(stroke
			(width 0)
			(type solid)
		)
		(fill yes)
		(layer "In6.Cu")
		(net "M_D_CPU0_SA_DQ<2>")
	)
	(gr_poly
		(pts
			(xy 336.372962 -278.945848) (xy 336.372962 -278.901652) (xy 336.017362 -278.901652) (xy 336.017362 -278.945848)
			(xy 336.064352 -279.098248) (xy 336.325972 -279.098248)
		)
		(stroke
			(width 0)
			(type solid)
		)
		(fill yes)
		(layer "In6.Cu")
		(net "M_D_CPU0_SA_DQ<1>")
	)
	(gr_poly
		(pts
			(xy 336.372962 -274.47113) (xy 336.325972 -274.31873) (xy 336.064352 -274.31873) (xy 336.017362 -274.47113)
			(xy 336.017362 -274.51558) (xy 336.372962 -274.51558)
		)
		(stroke
			(width 0)
			(type solid)
		)
		(fill yes)
		(layer "In6.Cu")
		(net "M_D_CPU0_SA_DQ<6>")
	)
	(gr_poly
		(pts
			(xy 336.372962 -274.062698) (xy 336.372962 -274.018248) (xy 336.017362 -274.018248) (xy 336.017362 -274.062698)
			(xy 336.064352 -274.215098) (xy 336.325972 -274.215098)
		)
		(stroke
			(width 0)
			(type solid)
		)
		(fill yes)
		(layer "In6.Cu")
		(net "M_D_CPU0_SA_DQ<5>")
	)
	(gr_poly
		(pts
			(xy 336.372962 -271.215866) (xy 336.325972 -271.063466) (xy 336.064352 -271.063466) (xy 336.017362 -271.215866)
			(xy 336.017362 -271.260062) (xy 336.372962 -271.260062)
		)
		(stroke
			(width 0)
			(type solid)
		)
		(fill yes)
		(layer "In6.Cu")
		(net "M_C_CPU0_SA_DQ<11>")
	)
	(gr_poly
		(pts
			(xy 336.372962 -270.806926) (xy 336.372962 -270.76273) (xy 336.017362 -270.76273) (xy 336.017362 -270.806926)
			(xy 336.064352 -270.959326) (xy 336.325972 -270.959326)
		)
		(stroke
			(width 0)
			(type solid)
		)
		(fill yes)
		(layer "In6.Cu")
		(net "M_C_CPU0_SA_DQS_DP<1>")
	)
	(gr_poly
		(pts
			(xy 336.372962 -269.587726) (xy 336.325972 -269.435326) (xy 336.064352 -269.435326) (xy 336.017362 -269.587726)
			(xy 336.017362 -269.632176) (xy 336.372962 -269.632176)
		)
		(stroke
			(width 0)
			(type solid)
		)
		(fill yes)
		(layer "In6.Cu")
		(net "M_C_CPU0_SA_DQS_DP<6>")
	)
	(gr_poly
		(pts
			(xy 336.372962 -269.179294) (xy 336.372962 -269.134844) (xy 336.017362 -269.134844) (xy 336.017362 -269.179294)
			(xy 336.064352 -269.331694) (xy 336.325972 -269.331694)
		)
		(stroke
			(width 0)
			(type solid)
		)
		(fill yes)
		(layer "In6.Cu")
		(net "M_C_CPU0_SA_DQ<12>")
	)
	(gr_poly
		(pts
			(xy 336.372962 -267.960094) (xy 336.325972 -267.807694) (xy 336.064352 -267.807694) (xy 336.017362 -267.960094)
			(xy 336.017362 -268.004544) (xy 336.372962 -268.004544)
		)
		(stroke
			(width 0)
			(type solid)
		)
		(fill yes)
		(layer "In6.Cu")
		(net "M_C_CPU0_SA_DQ<15>")
	)
	(gr_poly
		(pts
			(xy 336.372962 -267.551662) (xy 336.372962 -267.507212) (xy 336.017362 -267.507212) (xy 336.017362 -267.551662)
			(xy 336.064352 -267.704062) (xy 336.325972 -267.704062)
		)
		(stroke
			(width 0)
			(type solid)
		)
		(fill yes)
		(layer "In6.Cu")
		(net "M_C_CPU0_SA_DQ<24>")
	)
	(gr_poly
		(pts
			(xy 336.372962 -266.332462) (xy 336.325972 -266.180062) (xy 336.064352 -266.180062) (xy 336.017362 -266.332462)
			(xy 336.017362 -266.376658) (xy 336.372962 -266.376658)
		)
		(stroke
			(width 0)
			(type solid)
		)
		(fill yes)
		(layer "In6.Cu")
		(net "M_C_CPU0_SA_DQ<27>")
	)
	(gr_poly
		(pts
			(xy 336.372962 -265.92403) (xy 336.372962 -265.87958) (xy 336.017362 -265.87958) (xy 336.017362 -265.92403)
			(xy 336.064352 -266.07643) (xy 336.325972 -266.07643)
		)
		(stroke
			(width 0)
			(type solid)
		)
		(fill yes)
		(layer "In6.Cu")
		(net "M_C_CPU0_SA_DQS_DP<3>")
	)
	(gr_poly
		(pts
			(xy 336.372962 -264.70483) (xy 336.325972 -264.55243) (xy 336.064352 -264.55243) (xy 336.017362 -264.70483)
			(xy 336.017362 -264.749026) (xy 336.372962 -264.749026)
		)
		(stroke
			(width 0)
			(type solid)
		)
		(fill yes)
		(layer "In6.Cu")
		(net "M_C_CPU0_SA_DQS_DP<8>")
	)
	(gr_poly
		(pts
			(xy 336.372962 -264.29589) (xy 336.372962 -264.251694) (xy 336.017362 -264.251694) (xy 336.017362 -264.29589)
			(xy 336.064352 -264.44829) (xy 336.325972 -264.44829)
		)
		(stroke
			(width 0)
			(type solid)
		)
		(fill yes)
		(layer "In6.Cu")
		(net "M_C_CPU0_SA_DQ<28>")
	)
	(gr_poly
		(pts
			(xy 336.372962 -263.07669) (xy 336.325972 -262.92429) (xy 336.064352 -262.92429) (xy 336.017362 -263.07669)
			(xy 336.017362 -263.12114) (xy 336.372962 -263.12114)
		)
		(stroke
			(width 0)
			(type solid)
		)
		(fill yes)
		(layer "In6.Cu")
		(net "M_C_CPU0_SA_DQ<31>")
	)
	(gr_poly
		(pts
			(xy 336.372962 -262.668258) (xy 336.372962 -262.623808) (xy 336.017362 -262.623808) (xy 336.017362 -262.668258)
			(xy 336.064352 -262.820658) (xy 336.325972 -262.820658)
		)
		(stroke
			(width 0)
			(type solid)
		)
		(fill yes)
		(layer "In6.Cu")
		(net "M_C_CPU0_SA_CB<2>")
	)
	(gr_poly
		(pts
			(xy 336.372962 -261.449058) (xy 336.325972 -261.296658) (xy 336.064352 -261.296658) (xy 336.017362 -261.449058)
			(xy 336.017362 -261.493508) (xy 336.372962 -261.493508)
		)
		(stroke
			(width 0)
			(type solid)
		)
		(fill yes)
		(layer "In6.Cu")
		(net "M_C_CPU0_SA_CB<1>")
	)
	(gr_poly
		(pts
			(xy 336.372962 -261.040626) (xy 336.372962 -260.996176) (xy 336.017362 -260.996176) (xy 336.017362 -261.040626)
			(xy 336.064352 -261.193026) (xy 336.325972 -261.193026)
		)
		(stroke
			(width 0)
			(type solid)
		)
		(fill yes)
		(layer "In6.Cu")
		(net "M_C_CPU0_SA_DQS_DN<9>")
	)
	(gr_poly
		(pts
			(xy 336.372962 -259.821426) (xy 336.325972 -259.669026) (xy 336.064352 -259.669026) (xy 336.017362 -259.821426)
			(xy 336.017362 -259.865622) (xy 336.372962 -259.865622)
		)
		(stroke
			(width 0)
			(type solid)
		)
		(fill yes)
		(layer "In6.Cu")
		(net "M_C_CPU0_SA_DQS_DN<4>")
	)
	(gr_poly
		(pts
			(xy 336.372962 -259.412486) (xy 336.372962 -259.36829) (xy 336.017362 -259.36829) (xy 336.017362 -259.412486)
			(xy 336.064352 -259.564886) (xy 336.325972 -259.564886)
		)
		(stroke
			(width 0)
			(type solid)
		)
		(fill yes)
		(layer "In6.Cu")
		(net "M_C_CPU0_SA_CB<6>")
	)
	(gr_poly
		(pts
			(xy 336.372962 -258.193286) (xy 336.325972 -258.040886) (xy 336.064352 -258.040886) (xy 336.017362 -258.193286)
			(xy 336.017362 -258.237736) (xy 336.372962 -258.237736)
		)
		(stroke
			(width 0)
			(type solid)
		)
		(fill yes)
		(layer "In6.Cu")
		(net "M_C_CPU0_SA_CB<5>")
	)
	(gr_poly
		(pts
			(xy 336.372962 -256.565654) (xy 336.325972 -256.413254) (xy 336.064352 -256.413254) (xy 336.017362 -256.565654)
			(xy 336.017362 -256.610104) (xy 336.372962 -256.610104)
		)
		(stroke
			(width 0)
			(type solid)
		)
		(fill yes)
		(layer "In6.Cu")
		(net "M_D_CPU0_SB_RSP<0>")
	)
	(gr_poly
		(pts
			(xy 336.372962 -256.157222) (xy 336.372962 -256.112772) (xy 336.017362 -256.112772) (xy 336.017362 -256.157222)
			(xy 336.064352 -256.309622) (xy 336.325972 -256.309622)
		)
		(stroke
			(width 0)
			(type solid)
		)
		(fill yes)
		(layer "In6.Cu")
		(net "M_D_CPU0_SA_RSP<1>")
	)
	(gr_poly
		(pts
			(xy 336.372962 -254.938022) (xy 336.325972 -254.785622) (xy 336.064352 -254.785622) (xy 336.017362 -254.938022)
			(xy 336.017362 -254.982218) (xy 336.372962 -254.982218)
		)
		(stroke
			(width 0)
			(type solid)
		)
		(fill yes)
		(layer "In6.Cu")
		(net "M_C_CPU0_SB_RSP<0>")
	)
	(gr_poly
		(pts
			(xy 336.372962 -254.529082) (xy 336.372962 -254.484886) (xy 336.017362 -254.484886) (xy 336.017362 -254.529082)
			(xy 336.064352 -254.681482) (xy 336.325972 -254.681482)
		)
		(stroke
			(width 0)
			(type solid)
		)
		(fill yes)
		(layer "In6.Cu")
		(net "M_C_CPU0_SA_RSP<1>")
	)
	(gr_poly
		(pts
			(xy 336.454242 -272.900902) (xy 336.345784 -272.784062) (xy 336.30743 -272.761964) (xy 336.12963 -273.069812)
			(xy 336.167984 -273.09191) (xy 336.323432 -273.12747)
		)
		(stroke
			(width 0)
			(type solid)
		)
		(fill yes)
		(layer "In6.Cu")
		(net "M_C_CPU0_SA_DQ<8>")
	)
	(gr_poly
		(pts
			(xy 336.588862 -224.85223) (xy 336.627216 -224.830132) (xy 336.449416 -224.522284) (xy 336.411062 -224.544382)
			(xy 336.302604 -224.661222) (xy 336.433414 -224.88779)
		)
		(stroke
			(width 0)
			(type solid)
		)
		(fill yes)
		(layer "In6.Cu")
		(net "M_C_CPU0_SB_DQ<28>")
	)
	(gr_poly
		(pts
			(xy 336.589878 -226.482656) (xy 336.628232 -226.460558) (xy 336.450432 -226.15271) (xy 336.412078 -226.174808)
			(xy 336.30362 -226.291648) (xy 336.43443 -226.518216)
		)
		(stroke
			(width 0)
			(type solid)
		)
		(fill yes)
		(layer "In6.Cu")
		(net "M_C_CPU0_SB_DQS_DN<8>")
	)
	(gr_poly
		(pts
			(xy 336.697574 -225.858324) (xy 336.806032 -225.741484) (xy 336.675222 -225.514916) (xy 336.519774 -225.550476)
			(xy 336.48142 -225.572574) (xy 336.65922 -225.880422)
		)
		(stroke
			(width 0)
			(type solid)
		)
		(fill yes)
		(layer "In6.Cu")
		(net "M_C_CPU0_SB_DQS_DP<8>")
	)
	(gr_poly
		(pts
			(xy 336.73034 -243.718334) (xy 336.73034 -243.674138) (xy 336.37474 -243.674138) (xy 336.37474 -243.718334)
			(xy 336.42173 -243.870734) (xy 336.68335 -243.870734)
		)
		(stroke
			(width 0)
			(type solid)
		)
		(fill yes)
		(layer "In6.Cu")
		(net "M_C_CPU0_SB_DQ<1>")
	)
	(gr_poly
		(pts
			(xy 336.732626 -273.01952) (xy 336.694272 -272.997422) (xy 336.538824 -272.961862) (xy 336.408014 -273.18843)
			(xy 336.516472 -273.30527) (xy 336.554826 -273.327368)
		)
		(stroke
			(width 0)
			(type solid)
		)
		(fill yes)
		(layer "In6.Cu")
		(net "M_D_CPU0_SA_DQ<7>")
	)
	(gr_poly
		(pts
			(xy 336.732626 -242.499642) (xy 336.685636 -242.347242) (xy 336.424016 -242.347242) (xy 336.377026 -242.499642)
			(xy 336.377026 -242.543838) (xy 336.732626 -242.543838)
		)
		(stroke
			(width 0)
			(type solid)
		)
		(fill yes)
		(layer "In6.Cu")
		(net "M_C_CPU0_SB_DQS_DN<0>")
	)
	(gr_poly
		(pts
			(xy 336.733134 -237.207298) (xy 336.733134 -237.163102) (xy 336.377534 -237.163102) (xy 336.377534 -237.207298)
			(xy 336.424524 -237.359698) (xy 336.686144 -237.359698)
		)
		(stroke
			(width 0)
			(type solid)
		)
		(fill yes)
		(layer "In6.Cu")
		(net "M_C_CPU0_SB_DQS_DN<6>")
	)
	(gr_poly
		(pts
			(xy 336.733134 -235.988098) (xy 336.686144 -235.835698) (xy 336.424524 -235.835698) (xy 336.377534 -235.988098)
			(xy 336.377534 -236.032548) (xy 336.733134 -236.032548)
		)
		(stroke
			(width 0)
			(type solid)
		)
		(fill yes)
		(layer "In6.Cu")
		(net "M_C_CPU0_SB_DQ<14>")
	)
	(gr_poly
		(pts
			(xy 336.741516 -248.602246) (xy 336.741516 -248.557796) (xy 336.385916 -248.557796) (xy 336.385916 -248.602246)
			(xy 336.432906 -248.754646) (xy 336.694526 -248.754646)
		)
		(stroke
			(width 0)
			(type solid)
		)
		(fill yes)
		(layer "In6.Cu")
		(net "M_A_CPU0_SB_RSP<0>")
	)
	(gr_poly
		(pts
			(xy 336.741516 -247.382538) (xy 336.694526 -247.230138) (xy 336.432906 -247.230138) (xy 336.385916 -247.382538)
			(xy 336.385916 -247.426734) (xy 336.741516 -247.426734)
		)
		(stroke
			(width 0)
			(type solid)
		)
		(fill yes)
		(layer "In6.Cu")
		(net "M_A_CPU0_SB_RSP<1>")
	)
	(gr_poly
		(pts
			(xy 336.741516 -245.754906) (xy 336.694526 -245.602506) (xy 336.432906 -245.602506) (xy 336.385916 -245.754906)
			(xy 336.385916 -245.799102) (xy 336.741516 -245.799102)
		)
		(stroke
			(width 0)
			(type solid)
		)
		(fill yes)
		(layer "In6.Cu")
		(net "M_D_CPU0_SB_CS_N<3>")
	)
	(gr_poly
		(pts
			(xy 336.741516 -245.346474) (xy 336.741516 -245.302278) (xy 336.385916 -245.302278) (xy 336.385916 -245.346474)
			(xy 336.432906 -245.498874) (xy 336.694526 -245.498874)
		)
		(stroke
			(width 0)
			(type solid)
		)
		(fill yes)
		(layer "In6.Cu")
		(net "M_D_CPU0_SB_CS_N<0>")
	)
	(gr_poly
		(pts
			(xy 336.741516 -244.126766) (xy 336.694526 -243.974366) (xy 336.432906 -243.974366) (xy 336.385916 -244.126766)
			(xy 336.385916 -244.171216) (xy 336.741516 -244.171216)
		)
		(stroke
			(width 0)
			(type solid)
		)
		(fill yes)
		(layer "In6.Cu")
		(net "M_C_CPU0_SB_DQ<2>")
	)
	(gr_poly
		(pts
			(xy 336.741516 -242.090702) (xy 336.741516 -242.046506) (xy 336.385916 -242.046506) (xy 336.385916 -242.090702)
			(xy 336.432906 -242.243102) (xy 336.694526 -242.243102)
		)
		(stroke
			(width 0)
			(type solid)
		)
		(fill yes)
		(layer "In6.Cu")
		(net "M_C_CPU0_SB_DQS_DN<5>")
	)
	(gr_poly
		(pts
			(xy 336.741516 -240.871502) (xy 336.694526 -240.719102) (xy 336.432906 -240.719102) (xy 336.385916 -240.871502)
			(xy 336.385916 -240.915698) (xy 336.741516 -240.915698)
		)
		(stroke
			(width 0)
			(type solid)
		)
		(fill yes)
		(layer "In6.Cu")
		(net "M_C_CPU0_SB_DQ<6>")
	)
	(gr_poly
		(pts
			(xy 336.741516 -240.46307) (xy 336.741516 -240.418874) (xy 336.385916 -240.418874) (xy 336.385916 -240.46307)
			(xy 336.432906 -240.61547) (xy 336.694526 -240.61547)
		)
		(stroke
			(width 0)
			(type solid)
		)
		(fill yes)
		(layer "In6.Cu")
		(net "M_C_CPU0_SB_DQ<5>")
	)
	(gr_poly
		(pts
			(xy 336.741516 -239.243362) (xy 336.694526 -239.090962) (xy 336.432906 -239.090962) (xy 336.385916 -239.243362)
			(xy 336.385916 -239.287812) (xy 336.741516 -239.287812)
		)
		(stroke
			(width 0)
			(type solid)
		)
		(fill yes)
		(layer "In6.Cu")
		(net "M_C_CPU0_SB_DQ<10>")
	)
	(gr_poly
		(pts
			(xy 336.741516 -238.835438) (xy 336.741516 -238.790988) (xy 336.385916 -238.790988) (xy 336.385916 -238.835438)
			(xy 336.432906 -238.987838) (xy 336.694526 -238.987838)
		)
		(stroke
			(width 0)
			(type solid)
		)
		(fill yes)
		(layer "In6.Cu")
		(net "M_C_CPU0_SB_DQ<9>")
	)
	(gr_poly
		(pts
			(xy 336.741516 -237.61573) (xy 336.694526 -237.46333) (xy 336.432906 -237.46333) (xy 336.385916 -237.61573)
			(xy 336.385916 -237.659926) (xy 336.741516 -237.659926)
		)
		(stroke
			(width 0)
			(type solid)
		)
		(fill yes)
		(layer "In6.Cu")
		(net "M_C_CPU0_SB_DQS_DN<1>")
	)
	(gr_poly
		(pts
			(xy 336.741516 -235.579666) (xy 336.741516 -235.53547) (xy 336.385916 -235.53547) (xy 336.385916 -235.579666)
			(xy 336.432906 -235.732066) (xy 336.694526 -235.732066)
		)
		(stroke
			(width 0)
			(type solid)
		)
		(fill yes)
		(layer "In6.Cu")
		(net "M_C_CPU0_SB_DQ<13>")
	)
	(gr_poly
		(pts
			(xy 336.741516 -234.360466) (xy 336.694526 -234.208066) (xy 336.432906 -234.208066) (xy 336.385916 -234.360466)
			(xy 336.385916 -234.404662) (xy 336.741516 -234.404662)
		)
		(stroke
			(width 0)
			(type solid)
		)
		(fill yes)
		(layer "In6.Cu")
		(net "M_D_CPU0_SB_DQ<18>")
	)
	(gr_poly
		(pts
			(xy 336.741516 -233.952034) (xy 336.741516 -233.907838) (xy 336.385916 -233.907838) (xy 336.385916 -233.952034)
			(xy 336.432906 -234.104434) (xy 336.694526 -234.104434)
		)
		(stroke
			(width 0)
			(type solid)
		)
		(fill yes)
		(layer "In6.Cu")
		(net "M_D_CPU0_SB_DQ<17>")
	)
	(gr_poly
		(pts
			(xy 336.741516 -232.324402) (xy 336.741516 -232.279952) (xy 336.385916 -232.279952) (xy 336.385916 -232.324402)
			(xy 336.432906 -232.476802) (xy 336.694526 -232.476802)
		)
		(stroke
			(width 0)
			(type solid)
		)
		(fill yes)
		(layer "In6.Cu")
		(net "M_D_CPU0_SB_DQS_DP<2>")
	)
	(gr_poly
		(pts
			(xy 336.741516 -231.104694) (xy 336.694526 -230.952294) (xy 336.432906 -230.952294) (xy 336.385916 -231.104694)
			(xy 336.385916 -231.14889) (xy 336.741516 -231.14889)
		)
		(stroke
			(width 0)
			(type solid)
		)
		(fill yes)
		(layer "In6.Cu")
		(net "M_D_CPU0_SB_DQS_DP<7>")
	)
	(gr_poly
		(pts
			(xy 336.741516 -230.696262) (xy 336.741516 -230.652066) (xy 336.385916 -230.652066) (xy 336.385916 -230.696262)
			(xy 336.432906 -230.848662) (xy 336.694526 -230.848662)
		)
		(stroke
			(width 0)
			(type solid)
		)
		(fill yes)
		(layer "In6.Cu")
		(net "M_D_CPU0_SB_DQ<20>")
	)
	(gr_poly
		(pts
			(xy 336.741516 -229.477062) (xy 336.694526 -229.324662) (xy 336.432906 -229.324662) (xy 336.385916 -229.477062)
			(xy 336.385916 -229.521258) (xy 336.741516 -229.521258)
		)
		(stroke
			(width 0)
			(type solid)
		)
		(fill yes)
		(layer "In6.Cu")
		(net "M_D_CPU0_SB_DQ<23>")
	)
	(gr_poly
		(pts
			(xy 336.741516 -229.06863) (xy 336.741516 -229.024434) (xy 336.385916 -229.024434) (xy 336.385916 -229.06863)
			(xy 336.432906 -229.22103) (xy 336.694526 -229.22103)
		)
		(stroke
			(width 0)
			(type solid)
		)
		(fill yes)
		(layer "In6.Cu")
		(net "M_C_CPU0_SB_DQ<26>")
	)
	(gr_poly
		(pts
			(xy 336.741516 -227.848922) (xy 336.694526 -227.696522) (xy 336.432906 -227.696522) (xy 336.385916 -227.848922)
			(xy 336.385916 -227.893372) (xy 336.741516 -227.893372)
		)
		(stroke
			(width 0)
			(type solid)
		)
		(fill yes)
		(layer "In6.Cu")
		(net "M_C_CPU0_SB_DQ<27>")
	)
	(gr_poly
		(pts
			(xy 336.741516 -227.440998) (xy 336.741516 -227.396548) (xy 336.385916 -227.396548) (xy 336.385916 -227.440998)
			(xy 336.432906 -227.593398) (xy 336.694526 -227.593398)
		)
		(stroke
			(width 0)
			(type solid)
		)
		(fill yes)
		(layer "In6.Cu")
		(net "M_C_CPU0_SB_DQS_DP<3>")
	)
	(gr_poly
		(pts
			(xy 336.741516 -222.965518) (xy 336.694526 -222.813118) (xy 336.432906 -222.813118) (xy 336.385916 -222.965518)
			(xy 336.385916 -223.009968) (xy 336.741516 -223.009968)
		)
		(stroke
			(width 0)
			(type solid)
		)
		(fill yes)
		(layer "In6.Cu")
		(net "M_C_CPU0_SB_DQ<29>")
	)
	(gr_poly
		(pts
			(xy 336.83702 -272.029174) (xy 336.79003 -271.876774) (xy 336.52841 -271.876774) (xy 336.48142 -272.029174)
			(xy 336.48142 -272.073624) (xy 336.83702 -272.073624)
		)
		(stroke
			(width 0)
			(type solid)
		)
		(fill yes)
		(layer "In6.Cu")
		(net "M_C_CPU0_SA_DQ<10>")
	)
	(gr_poly
		(pts
			(xy 336.83956 -263.482074) (xy 336.83956 -263.437624) (xy 336.48396 -263.437624) (xy 336.48396 -263.482074)
			(xy 336.53095 -263.634474) (xy 336.79257 -263.634474)
		)
		(stroke
			(width 0)
			(type solid)
		)
		(fill yes)
		(layer "In6.Cu")
		(net "M_C_CPU0_SA_DQ<29>")
	)
	(gr_poly
		(pts
			(xy 336.842862 -279.759664) (xy 336.842862 -279.715468) (xy 336.487262 -279.715468) (xy 336.487262 -279.759664)
			(xy 336.534252 -279.912064) (xy 336.795872 -279.912064)
		)
		(stroke
			(width 0)
			(type solid)
		)
		(fill yes)
		(layer "In6.Cu")
		(net "M_D_CPU0_SA_DQ<0>")
	)
	(gr_poly
		(pts
			(xy 336.842862 -278.540718) (xy 336.795872 -278.388318) (xy 336.534252 -278.388318) (xy 336.487262 -278.540718)
			(xy 336.487262 -278.585168) (xy 336.842862 -278.585168)
		)
		(stroke
			(width 0)
			(type solid)
		)
		(fill yes)
		(layer "In6.Cu")
		(net "M_D_CPU0_SA_DQ<3>")
	)
	(gr_poly
		(pts
			(xy 336.842862 -276.504146) (xy 336.842862 -276.45995) (xy 336.487262 -276.45995) (xy 336.487262 -276.504146)
			(xy 336.534252 -276.656546) (xy 336.795872 -276.656546)
		)
		(stroke
			(width 0)
			(type solid)
		)
		(fill yes)
		(layer "In6.Cu")
		(net "M_D_CPU0_SA_DQS_DN<5>")
	)
	(gr_poly
		(pts
			(xy 336.842862 -274.876514) (xy 336.842862 -274.832064) (xy 336.487262 -274.832064) (xy 336.487262 -274.876514)
			(xy 336.534252 -275.028914) (xy 336.795872 -275.028914)
		)
		(stroke
			(width 0)
			(type solid)
		)
		(fill yes)
		(layer "In6.Cu")
		(net "M_D_CPU0_SA_DQ<4>")
	)
	(gr_poly
		(pts
			(xy 336.842862 -270.40205) (xy 336.795872 -270.24965) (xy 336.534252 -270.24965) (xy 336.487262 -270.40205)
			(xy 336.487262 -270.446246) (xy 336.842862 -270.446246)
		)
		(stroke
			(width 0)
			(type solid)
		)
		(fill yes)
		(layer "In6.Cu")
		(net "M_C_CPU0_SA_DQS_DN<1>")
	)
	(gr_poly
		(pts
			(xy 336.842862 -269.99311) (xy 336.842862 -269.948914) (xy 336.487262 -269.948914) (xy 336.487262 -269.99311)
			(xy 336.534252 -270.14551) (xy 336.795872 -270.14551)
		)
		(stroke
			(width 0)
			(type solid)
		)
		(fill yes)
		(layer "In6.Cu")
		(net "M_C_CPU0_SA_DQS_DN<6>")
	)
	(gr_poly
		(pts
			(xy 336.842862 -268.77391) (xy 336.795872 -268.62151) (xy 336.534252 -268.62151) (xy 336.487262 -268.77391)
			(xy 336.487262 -268.81836) (xy 336.842862 -268.81836)
		)
		(stroke
			(width 0)
			(type solid)
		)
		(fill yes)
		(layer "In6.Cu")
		(net "M_C_CPU0_SA_DQ<14>")
	)
	(gr_poly
		(pts
			(xy 336.842862 -268.365478) (xy 336.842862 -268.321028) (xy 336.487262 -268.321028) (xy 336.487262 -268.365478)
			(xy 336.534252 -268.517878) (xy 336.795872 -268.517878)
		)
		(stroke
			(width 0)
			(type solid)
		)
		(fill yes)
		(layer "In6.Cu")
		(net "M_C_CPU0_SA_DQ<13>")
	)
	(gr_poly
		(pts
			(xy 336.842862 -267.146278) (xy 336.795872 -266.993878) (xy 336.534252 -266.993878) (xy 336.487262 -267.146278)
			(xy 336.487262 -267.190474) (xy 336.842862 -267.190474)
		)
		(stroke
			(width 0)
			(type solid)
		)
		(fill yes)
		(layer "In6.Cu")
		(net "M_C_CPU0_SA_DQ<26>")
	)
	(gr_poly
		(pts
			(xy 336.842862 -266.737846) (xy 336.842862 -266.693396) (xy 336.487262 -266.693396) (xy 336.487262 -266.737846)
			(xy 336.534252 -266.890246) (xy 336.795872 -266.890246)
		)
		(stroke
			(width 0)
			(type solid)
		)
		(fill yes)
		(layer "In6.Cu")
		(net "M_C_CPU0_SA_DQ<25>")
	)
	(gr_poly
		(pts
			(xy 336.842862 -265.518646) (xy 336.795872 -265.366246) (xy 336.534252 -265.366246) (xy 336.487262 -265.518646)
			(xy 336.487262 -265.562842) (xy 336.842862 -265.562842)
		)
		(stroke
			(width 0)
			(type solid)
		)
		(fill yes)
		(layer "In6.Cu")
		(net "M_C_CPU0_SA_DQS_DN<3>")
	)
	(gr_poly
		(pts
			(xy 336.842862 -265.109706) (xy 336.842862 -265.06551) (xy 336.487262 -265.06551) (xy 336.487262 -265.109706)
			(xy 336.534252 -265.262106) (xy 336.795872 -265.262106)
		)
		(stroke
			(width 0)
			(type solid)
		)
		(fill yes)
		(layer "In6.Cu")
		(net "M_C_CPU0_SA_DQS_DN<8>")
	)
	(gr_poly
		(pts
			(xy 336.842862 -263.891014) (xy 336.795872 -263.738614) (xy 336.534252 -263.738614) (xy 336.487262 -263.891014)
			(xy 336.487262 -263.93521) (xy 336.842862 -263.93521)
		)
		(stroke
			(width 0)
			(type solid)
		)
		(fill yes)
		(layer "In6.Cu")
		(net "M_C_CPU0_SA_DQ<30>")
	)
	(gr_poly
		(pts
			(xy 336.842862 -259.00761) (xy 336.795872 -258.85521) (xy 336.534252 -258.85521) (xy 336.487262 -259.00761)
			(xy 336.487262 -259.051806) (xy 336.842862 -259.051806)
		)
		(stroke
			(width 0)
			(type solid)
		)
		(fill yes)
		(layer "In6.Cu")
		(net "M_C_CPU0_SA_CB<4>")
	)
	(gr_poly
		(pts
			(xy 336.842862 -258.59867) (xy 336.842862 -258.554474) (xy 336.487262 -258.554474) (xy 336.487262 -258.59867)
			(xy 336.534252 -258.75107) (xy 336.795872 -258.75107)
		)
		(stroke
			(width 0)
			(type solid)
		)
		(fill yes)
		(layer "In6.Cu")
		(net "M_C_CPU0_SA_CB<7>")
	)
	(gr_poly
		(pts
			(xy 336.842862 -256.971038) (xy 336.842862 -256.926588) (xy 336.487262 -256.926588) (xy 336.487262 -256.971038)
			(xy 336.534252 -257.123438) (xy 336.795872 -257.123438)
		)
		(stroke
			(width 0)
			(type solid)
		)
		(fill yes)
		(layer "In6.Cu")
		(net "M_D_CPU0_SA_RSP<0>")
	)
	(gr_poly
		(pts
			(xy 336.842862 -254.124206) (xy 336.795872 -253.971806) (xy 336.534252 -253.971806) (xy 336.487262 -254.124206)
			(xy 336.487262 -254.168402) (xy 336.842862 -254.168402)
		)
		(stroke
			(width 0)
			(type solid)
		)
		(fill yes)
		(layer "In6.Cu")
		(net "M_C_CPU0_SB_RSP<1>")
	)
	(gr_poly
		(pts
			(xy 336.848958 -271.62125) (xy 336.848958 -271.5768) (xy 336.493358 -271.5768) (xy 336.493358 -271.62125)
			(xy 336.540348 -271.77365) (xy 336.801968 -271.77365)
		)
		(stroke
			(width 0)
			(type solid)
		)
		(fill yes)
		(layer "In6.Cu")
		(net "M_C_CPU0_SA_DQ<9>")
	)
	(gr_poly
		(pts
			(xy 336.848958 -262.262874) (xy 336.801968 -262.110474) (xy 336.540348 -262.110474) (xy 336.493358 -262.262874)
			(xy 336.493358 -262.30707) (xy 336.848958 -262.30707)
		)
		(stroke
			(width 0)
			(type solid)
		)
		(fill yes)
		(layer "In6.Cu")
		(net "M_C_CPU0_SA_CB<0>")
	)
	(gr_poly
		(pts
			(xy 336.848958 -261.854442) (xy 336.848958 -261.810246) (xy 336.493358 -261.810246) (xy 336.493358 -261.854442)
			(xy 336.540348 -262.006842) (xy 336.801968 -262.006842)
		)
		(stroke
			(width 0)
			(type solid)
		)
		(fill yes)
		(layer "In6.Cu")
		(net "M_C_CPU0_SA_CB<3>")
	)
	(gr_poly
		(pts
			(xy 336.848958 -260.634734) (xy 336.801968 -260.482334) (xy 336.540348 -260.482334) (xy 336.493358 -260.634734)
			(xy 336.493358 -260.679184) (xy 336.848958 -260.679184)
		)
		(stroke
			(width 0)
			(type solid)
		)
		(fill yes)
		(layer "In6.Cu")
		(net "M_C_CPU0_SA_DQS_DP<9>")
	)
	(gr_poly
		(pts
			(xy 336.848958 -260.22681) (xy 336.848958 -260.18236) (xy 336.493358 -260.18236) (xy 336.493358 -260.22681)
			(xy 336.540348 -260.37921) (xy 336.801968 -260.37921)
		)
		(stroke
			(width 0)
			(type solid)
		)
		(fill yes)
		(layer "In6.Cu")
		(net "M_C_CPU0_SA_DQS_DP<4>")
	)
	(gr_poly
		(pts
			(xy 336.848958 -255.751838) (xy 336.801968 -255.599438) (xy 336.540348 -255.599438) (xy 336.493358 -255.751838)
			(xy 336.493358 -255.796034) (xy 336.848958 -255.796034)
		)
		(stroke
			(width 0)
			(type solid)
		)
		(fill yes)
		(layer "In6.Cu")
		(net "M_D_CPU0_SB_RSP<1>")
	)
	(gr_poly
		(pts
			(xy 336.848958 -255.343406) (xy 336.848958 -255.29921) (xy 336.493358 -255.29921) (xy 336.493358 -255.343406)
			(xy 336.540348 -255.495806) (xy 336.801968 -255.495806)
		)
		(stroke
			(width 0)
			(type solid)
		)
		(fill yes)
		(layer "In6.Cu")
		(net "M_C_CPU0_SA_RSP<0>")
	)
	(gr_poly
		(pts
			(xy 336.851244 -278.132286) (xy 336.851244 -278.08809) (xy 336.495644 -278.08809) (xy 336.495644 -278.132286)
			(xy 336.542634 -278.284686) (xy 336.804254 -278.284686)
		)
		(stroke
			(width 0)
			(type solid)
		)
		(fill yes)
		(layer "In6.Cu")
		(net "M_D_CPU0_SA_DQS_DP<0>")
	)
	(gr_poly
		(pts
			(xy 336.917792 -273.724878) (xy 336.809334 -273.608038) (xy 336.77098 -273.58594) (xy 336.59318 -273.893788)
			(xy 336.631534 -273.915886) (xy 336.786982 -273.951446)
		)
		(stroke
			(width 0)
			(type solid)
		)
		(fill yes)
		(layer "In6.Cu")
		(net "M_D_CPU0_SA_DQ<5>")
	)
	(gr_poly
		(pts
			(xy 337.051142 -224.025714) (xy 337.089496 -224.003616) (xy 336.911696 -223.695768) (xy 336.873342 -223.717866)
			(xy 336.764884 -223.834706) (xy 336.895694 -224.061274)
		)
		(stroke
			(width 0)
			(type solid)
		)
		(fill yes)
		(layer "In6.Cu")
		(net "M_C_CPU0_SB_DQ<31>")
	)
	(gr_poly
		(pts
			(xy 337.059524 -225.668078) (xy 337.097878 -225.64598) (xy 336.920078 -225.338132) (xy 336.881724 -225.36023)
			(xy 336.773266 -225.47707) (xy 336.904076 -225.703638)
		)
		(stroke
			(width 0)
			(type solid)
		)
		(fill yes)
		(layer "In6.Cu")
		(net "M_C_CPU0_SB_DQ<28>")
	)
	(gr_poly
		(pts
			(xy 337.169506 -225.048318) (xy 337.277964 -224.931478) (xy 337.147154 -224.70491) (xy 336.991706 -224.74047)
			(xy 336.953352 -224.762568) (xy 337.131152 -225.070416)
		)
		(stroke
			(width 0)
			(type solid)
		)
		(fill yes)
		(layer "In6.Cu")
		(net "M_C_CPU0_SB_DQ<30>")
	)
	(gr_poly
		(pts
			(xy 337.194398 -246.16029) (xy 337.194398 -246.116094) (xy 336.838798 -246.116094) (xy 336.838798 -246.16029)
			(xy 336.885788 -246.31269) (xy 337.147408 -246.31269)
		)
		(stroke
			(width 0)
			(type solid)
		)
		(fill yes)
		(layer "In6.Cu")
		(net "M_D_CPU0_SB_CS_N<2>")
	)
	(gr_poly
		(pts
			(xy 337.194398 -244.940582) (xy 337.147408 -244.788182) (xy 336.885788 -244.788182) (xy 336.838798 -244.940582)
			(xy 336.838798 -244.985032) (xy 337.194398 -244.985032)
		)
		(stroke
			(width 0)
			(type solid)
		)
		(fill yes)
		(layer "In6.Cu")
		(net "M_D_CPU0_SB_CS_N<1>")
	)
	(gr_poly
		(pts
			(xy 337.194398 -244.532658) (xy 337.194398 -244.488208) (xy 336.838798 -244.488208) (xy 336.838798 -244.532658)
			(xy 336.885788 -244.685058) (xy 337.147408 -244.685058)
		)
		(stroke
			(width 0)
			(type solid)
		)
		(fill yes)
		(layer "In6.Cu")
		(net "M_C_CPU0_SB_DQ<0>")
	)
	(gr_poly
		(pts
			(xy 337.194398 -242.905026) (xy 337.194398 -242.860576) (xy 336.838798 -242.860576) (xy 336.838798 -242.905026)
			(xy 336.885788 -243.057426) (xy 337.147408 -243.057426)
		)
		(stroke
			(width 0)
			(type solid)
		)
		(fill yes)
		(layer "In6.Cu")
		(net "M_C_CPU0_SB_DQS_DP<0>")
	)
	(gr_poly
		(pts
			(xy 337.194398 -241.685318) (xy 337.147408 -241.532918) (xy 336.885788 -241.532918) (xy 336.838798 -241.685318)
			(xy 336.838798 -241.729514) (xy 337.194398 -241.729514)
		)
		(stroke
			(width 0)
			(type solid)
		)
		(fill yes)
		(layer "In6.Cu")
		(net "M_C_CPU0_SB_DQS_DP<5>")
	)
	(gr_poly
		(pts
			(xy 337.194398 -241.276886) (xy 337.194398 -241.23269) (xy 336.838798 -241.23269) (xy 336.838798 -241.276886)
			(xy 336.885788 -241.429286) (xy 337.147408 -241.429286)
		)
		(stroke
			(width 0)
			(type solid)
		)
		(fill yes)
		(layer "In6.Cu")
		(net "M_C_CPU0_SB_DQ<4>")
	)
	(gr_poly
		(pts
			(xy 337.194398 -240.057178) (xy 337.147408 -239.904778) (xy 336.885788 -239.904778) (xy 336.838798 -240.057178)
			(xy 336.838798 -240.101628) (xy 337.194398 -240.101628)
		)
		(stroke
			(width 0)
			(type solid)
		)
		(fill yes)
		(layer "In6.Cu")
		(net "M_C_CPU0_SB_DQ<7>")
	)
	(gr_poly
		(pts
			(xy 337.194398 -239.649254) (xy 337.194398 -239.604804) (xy 336.838798 -239.604804) (xy 336.838798 -239.649254)
			(xy 336.885788 -239.801654) (xy 337.147408 -239.801654)
		)
		(stroke
			(width 0)
			(type solid)
		)
		(fill yes)
		(layer "In6.Cu")
		(net "M_C_CPU0_SB_DQ<8>")
	)
	(gr_poly
		(pts
			(xy 337.194398 -238.429546) (xy 337.147408 -238.277146) (xy 336.885788 -238.277146) (xy 336.838798 -238.429546)
			(xy 336.838798 -238.473996) (xy 337.194398 -238.473996)
		)
		(stroke
			(width 0)
			(type solid)
		)
		(fill yes)
		(layer "In6.Cu")
		(net "M_C_CPU0_SB_DQ<11>")
	)
	(gr_poly
		(pts
			(xy 337.194398 -238.021622) (xy 337.194398 -237.977172) (xy 336.838798 -237.977172) (xy 336.838798 -238.021622)
			(xy 336.885788 -238.174022) (xy 337.147408 -238.174022)
		)
		(stroke
			(width 0)
			(type solid)
		)
		(fill yes)
		(layer "In6.Cu")
		(net "M_C_CPU0_SB_DQS_DP<1>")
	)
	(gr_poly
		(pts
			(xy 337.194398 -235.174282) (xy 337.147408 -235.021882) (xy 336.885788 -235.021882) (xy 336.838798 -235.174282)
			(xy 336.838798 -235.218478) (xy 337.194398 -235.218478)
		)
		(stroke
			(width 0)
			(type solid)
		)
		(fill yes)
		(layer "In6.Cu")
		(net "M_C_CPU0_SB_DQ<15>")
	)
	(gr_poly
		(pts
			(xy 337.194398 -234.76585) (xy 337.194398 -234.721654) (xy 336.838798 -234.721654) (xy 336.838798 -234.76585)
			(xy 336.885788 -234.91825) (xy 337.147408 -234.91825)
		)
		(stroke
			(width 0)
			(type solid)
		)
		(fill yes)
		(layer "In6.Cu")
		(net "M_D_CPU0_SB_DQ<16>")
	)
	(gr_poly
		(pts
			(xy 337.194398 -233.546142) (xy 337.147408 -233.393742) (xy 336.885788 -233.393742) (xy 336.838798 -233.546142)
			(xy 336.838798 -233.590592) (xy 337.194398 -233.590592)
		)
		(stroke
			(width 0)
			(type solid)
		)
		(fill yes)
		(layer "In6.Cu")
		(net "M_D_CPU0_SB_DQ<19>")
	)
	(gr_poly
		(pts
			(xy 337.194398 -231.91851) (xy 337.147408 -231.76611) (xy 336.885788 -231.76611) (xy 336.838798 -231.91851)
			(xy 336.838798 -231.96296) (xy 337.194398 -231.96296)
		)
		(stroke
			(width 0)
			(type solid)
		)
		(fill yes)
		(layer "In6.Cu")
		(net "M_D_CPU0_SB_DQS_DN<2>")
	)
	(gr_poly
		(pts
			(xy 337.194398 -231.510586) (xy 337.194398 -231.466136) (xy 336.838798 -231.466136) (xy 336.838798 -231.510586)
			(xy 336.885788 -231.662986) (xy 337.147408 -231.662986)
		)
		(stroke
			(width 0)
			(type solid)
		)
		(fill yes)
		(layer "In6.Cu")
		(net "M_D_CPU0_SB_DQS_DN<7>")
	)
	(gr_poly
		(pts
			(xy 337.194398 -230.290878) (xy 337.147408 -230.138478) (xy 336.885788 -230.138478) (xy 336.838798 -230.290878)
			(xy 336.838798 -230.335074) (xy 337.194398 -230.335074)
		)
		(stroke
			(width 0)
			(type solid)
		)
		(fill yes)
		(layer "In6.Cu")
		(net "M_D_CPU0_SB_DQ<22>")
	)
	(gr_poly
		(pts
			(xy 337.194398 -229.882446) (xy 337.194398 -229.83825) (xy 336.838798 -229.83825) (xy 336.838798 -229.882446)
			(xy 336.885788 -230.034846) (xy 337.147408 -230.034846)
		)
		(stroke
			(width 0)
			(type solid)
		)
		(fill yes)
		(layer "In6.Cu")
		(net "M_D_CPU0_SB_DQ<21>")
	)
	(gr_poly
		(pts
			(xy 337.194398 -228.663246) (xy 337.147408 -228.510846) (xy 336.885788 -228.510846) (xy 336.838798 -228.663246)
			(xy 336.838798 -228.707442) (xy 337.194398 -228.707442)
		)
		(stroke
			(width 0)
			(type solid)
		)
		(fill yes)
		(layer "In6.Cu")
		(net "M_C_CPU0_SB_DQ<24>")
	)
	(gr_poly
		(pts
			(xy 337.194398 -228.254814) (xy 337.194398 -228.210618) (xy 336.838798 -228.210618) (xy 336.838798 -228.254814)
			(xy 336.885788 -228.407214) (xy 337.147408 -228.407214)
		)
		(stroke
			(width 0)
			(type solid)
		)
		(fill yes)
		(layer "In6.Cu")
		(net "M_C_CPU0_SB_DQ<25>")
	)
	(gr_poly
		(pts
			(xy 337.194398 -227.035106) (xy 337.147408 -226.882706) (xy 336.885788 -226.882706) (xy 336.838798 -227.035106)
			(xy 336.838798 -227.079556) (xy 337.194398 -227.079556)
		)
		(stroke
			(width 0)
			(type solid)
		)
		(fill yes)
		(layer "In6.Cu")
		(net "M_C_CPU0_SB_DQS_DN<3>")
	)
	(gr_poly
		(pts
			(xy 337.194398 -226.627182) (xy 337.194398 -226.582732) (xy 336.838798 -226.582732) (xy 336.838798 -226.627182)
			(xy 336.885788 -226.779582) (xy 337.147408 -226.779582)
		)
		(stroke
			(width 0)
			(type solid)
		)
		(fill yes)
		(layer "In6.Cu")
		(net "M_C_CPU0_SB_DQS_DN<8>")
	)
	(gr_poly
		(pts
			(xy 337.196938 -248.196354) (xy 337.149948 -248.043954) (xy 336.888328 -248.043954) (xy 336.841338 -248.196354)
			(xy 336.841338 -248.24055) (xy 337.196938 -248.24055)
		)
		(stroke
			(width 0)
			(type solid)
		)
		(fill yes)
		(layer "In6.Cu")
		(net "M_A_CPU0_SA_RSP<0>")
	)
	(gr_poly
		(pts
			(xy 337.196938 -247.787922) (xy 337.196938 -247.743726) (xy 336.841338 -247.743726) (xy 336.841338 -247.787922)
			(xy 336.888328 -247.940322) (xy 337.149948 -247.940322)
		)
		(stroke
			(width 0)
			(type solid)
		)
		(fill yes)
		(layer "In6.Cu")
		(net "M_A_CPU0_SA_RSP<1>")
	)
	(gr_poly
		(pts
			(xy 337.196938 -236.801914) (xy 337.149948 -236.649514) (xy 336.888328 -236.649514) (xy 336.841338 -236.801914)
			(xy 336.841338 -236.846364) (xy 337.196938 -236.846364)
		)
		(stroke
			(width 0)
			(type solid)
		)
		(fill yes)
		(layer "In6.Cu")
		(net "M_C_CPU0_SB_DQS_DP<6>")
	)
	(gr_poly
		(pts
			(xy 337.196938 -236.393482) (xy 337.196938 -236.349286) (xy 336.841338 -236.349286) (xy 336.841338 -236.393482)
			(xy 336.888328 -236.545882) (xy 337.149948 -236.545882)
		)
		(stroke
			(width 0)
			(type solid)
		)
		(fill yes)
		(layer "In6.Cu")
		(net "M_C_CPU0_SB_DQ<12>")
	)
	(gr_poly
		(pts
			(xy 337.200494 -277.092156) (xy 337.16214 -277.070058) (xy 337.006692 -277.034498) (xy 336.875882 -277.261066)
			(xy 336.98434 -277.377906) (xy 337.022694 -277.400004)
		)
		(stroke
			(width 0)
			(type solid)
		)
		(fill yes)
		(layer "In6.Cu")
		(net "M_D_CPU0_SA_DQS_DN<0>")
	)
	(gr_poly
		(pts
			(xy 337.206336 -243.313458) (xy 337.159346 -243.161058) (xy 336.897726 -243.161058) (xy 336.850736 -243.313458)
			(xy 336.850736 -243.357654) (xy 337.206336 -243.357654)
		)
		(stroke
			(width 0)
			(type solid)
		)
		(fill yes)
		(layer "In6.Cu")
		(net "M_C_CPU0_SB_DQ<3>")
	)
	(gr_poly
		(pts
			(xy 337.206844 -273.826224) (xy 337.16849 -273.804126) (xy 337.013042 -273.768566) (xy 336.882232 -273.995134)
			(xy 336.99069 -274.111974) (xy 337.029044 -274.134072)
		)
		(stroke
			(width 0)
			(type solid)
		)
		(fill yes)
		(layer "In6.Cu")
		(net "M_D_CPU0_SA_DQ<6>")
	)
	(gr_poly
		(pts
			(xy 337.208876 -275.450046) (xy 337.170522 -275.427948) (xy 337.015074 -275.392388) (xy 336.884264 -275.618956)
			(xy 336.992722 -275.735796) (xy 337.031076 -275.757894)
		)
		(stroke
			(width 0)
			(type solid)
		)
		(fill yes)
		(layer "In6.Cu")
		(net "M_D_CPU0_SA_DQS_DP<5>")
	)
	(gr_poly
		(pts
			(xy 337.30438 -271.215358) (xy 337.25739 -271.062958) (xy 336.99577 -271.062958) (xy 336.94878 -271.215358)
			(xy 336.94878 -271.259808) (xy 337.30438 -271.259808)
		)
		(stroke
			(width 0)
			(type solid)
		)
		(fill yes)
		(layer "In6.Cu")
		(net "M_C_CPU0_SA_DQ<11>")
	)
	(gr_poly
		(pts
			(xy 337.30438 -261.44855) (xy 337.25739 -261.29615) (xy 336.99577 -261.29615) (xy 336.94878 -261.44855)
			(xy 336.94878 -261.493) (xy 337.30438 -261.493)
		)
		(stroke
			(width 0)
			(type solid)
		)
		(fill yes)
		(layer "In6.Cu")
		(net "M_C_CPU0_SA_CB<1>")
	)
	(gr_poly
		(pts
			(xy 337.30438 -261.040626) (xy 337.30438 -260.99643) (xy 336.94878 -260.99643) (xy 336.94878 -261.040626)
			(xy 336.99577 -261.193026) (xy 337.25739 -261.193026)
		)
		(stroke
			(width 0)
			(type solid)
		)
		(fill yes)
		(layer "In6.Cu")
		(net "M_C_CPU0_SA_DQS_DN<9>")
	)
	(gr_poly
		(pts
			(xy 337.30438 -259.820918) (xy 337.25739 -259.668518) (xy 336.99577 -259.668518) (xy 336.94878 -259.820918)
			(xy 336.94878 -259.865368) (xy 337.30438 -259.865368)
		)
		(stroke
			(width 0)
			(type solid)
		)
		(fill yes)
		(layer "In6.Cu")
		(net "M_C_CPU0_SA_DQS_DN<4>")
	)
	(gr_poly
		(pts
			(xy 337.30438 -256.157222) (xy 337.30438 -256.113026) (xy 336.94878 -256.113026) (xy 336.94878 -256.157222)
			(xy 336.99577 -256.309622) (xy 337.25739 -256.309622)
		)
		(stroke
			(width 0)
			(type solid)
		)
		(fill yes)
		(layer "In6.Cu")
		(net "M_D_CPU0_SA_RSP<1>")
	)
	(gr_poly
		(pts
			(xy 337.30438 -254.937514) (xy 337.25739 -254.785114) (xy 336.99577 -254.785114) (xy 336.94878 -254.937514)
			(xy 336.94878 -254.981964) (xy 337.30438 -254.981964)
		)
		(stroke
			(width 0)
			(type solid)
		)
		(fill yes)
		(layer "In6.Cu")
		(net "M_C_CPU0_SB_RSP<0>")
	)
	(gr_poly
		(pts
			(xy 337.30692 -272.435066) (xy 337.30692 -272.390616) (xy 336.95132 -272.390616) (xy 336.95132 -272.435066)
			(xy 336.99831 -272.587466) (xy 337.25993 -272.587466)
		)
		(stroke
			(width 0)
			(type solid)
		)
		(fill yes)
		(layer "In6.Cu")
		(net "M_C_CPU0_SA_DQ<8>")
	)
	(gr_poly
		(pts
			(xy 337.312762 -279.354788) (xy 337.265772 -279.202388) (xy 337.004152 -279.202388) (xy 336.957162 -279.354788)
			(xy 336.957162 -279.398984) (xy 337.312762 -279.398984)
		)
		(stroke
			(width 0)
			(type solid)
		)
		(fill yes)
		(layer "In6.Cu")
		(net "M_D_CPU0_SA_DQ<2>")
	)
	(gr_poly
		(pts
			(xy 337.312762 -278.945848) (xy 337.312762 -278.901652) (xy 336.957162 -278.901652) (xy 336.957162 -278.945848)
			(xy 337.004152 -279.098248) (xy 337.265772 -279.098248)
		)
		(stroke
			(width 0)
			(type solid)
		)
		(fill yes)
		(layer "In6.Cu")
		(net "M_D_CPU0_SA_DQ<1>")
	)
	(gr_poly
		(pts
			(xy 337.312762 -270.806926) (xy 337.312762 -270.76273) (xy 336.957162 -270.76273) (xy 336.957162 -270.806926)
			(xy 337.004152 -270.959326) (xy 337.265772 -270.959326)
		)
		(stroke
			(width 0)
			(type solid)
		)
		(fill yes)
		(layer "In6.Cu")
		(net "M_C_CPU0_SA_DQS_DP<1>")
	)
	(gr_poly
		(pts
			(xy 337.312762 -269.587726) (xy 337.265772 -269.435326) (xy 337.004152 -269.435326) (xy 336.957162 -269.587726)
			(xy 336.957162 -269.632176) (xy 337.312762 -269.632176)
		)
		(stroke
			(width 0)
			(type solid)
		)
		(fill yes)
		(layer "In6.Cu")
		(net "M_C_CPU0_SA_DQS_DP<6>")
	)
	(gr_poly
		(pts
			(xy 337.312762 -269.179294) (xy 337.312762 -269.134844) (xy 336.957162 -269.134844) (xy 336.957162 -269.179294)
			(xy 337.004152 -269.331694) (xy 337.265772 -269.331694)
		)
		(stroke
			(width 0)
			(type solid)
		)
		(fill yes)
		(layer "In6.Cu")
		(net "M_C_CPU0_SA_DQ<12>")
	)
	(gr_poly
		(pts
			(xy 337.312762 -267.960094) (xy 337.265772 -267.807694) (xy 337.004152 -267.807694) (xy 336.957162 -267.960094)
			(xy 336.957162 -268.004544) (xy 337.312762 -268.004544)
		)
		(stroke
			(width 0)
			(type solid)
		)
		(fill yes)
		(layer "In6.Cu")
		(net "M_C_CPU0_SA_DQ<15>")
	)
	(gr_poly
		(pts
			(xy 337.312762 -267.551662) (xy 337.312762 -267.507212) (xy 336.957162 -267.507212) (xy 336.957162 -267.551662)
			(xy 337.004152 -267.704062) (xy 337.265772 -267.704062)
		)
		(stroke
			(width 0)
			(type solid)
		)
		(fill yes)
		(layer "In6.Cu")
		(net "M_C_CPU0_SA_DQ<24>")
	)
	(gr_poly
		(pts
			(xy 337.312762 -266.332462) (xy 337.265772 -266.180062) (xy 337.004152 -266.180062) (xy 336.957162 -266.332462)
			(xy 336.957162 -266.376658) (xy 337.312762 -266.376658)
		)
		(stroke
			(width 0)
			(type solid)
		)
		(fill yes)
		(layer "In6.Cu")
		(net "M_C_CPU0_SA_DQ<27>")
	)
	(gr_poly
		(pts
			(xy 337.312762 -265.923522) (xy 337.312762 -265.879326) (xy 336.957162 -265.879326) (xy 336.957162 -265.923522)
			(xy 337.004152 -266.075922) (xy 337.265772 -266.075922)
		)
		(stroke
			(width 0)
			(type solid)
		)
		(fill yes)
		(layer "In6.Cu")
		(net "M_C_CPU0_SA_DQS_DP<3>")
	)
	(gr_poly
		(pts
			(xy 337.312762 -264.70483) (xy 337.265772 -264.55243) (xy 337.004152 -264.55243) (xy 336.957162 -264.70483)
			(xy 336.957162 -264.749026) (xy 337.312762 -264.749026)
		)
		(stroke
			(width 0)
			(type solid)
		)
		(fill yes)
		(layer "In6.Cu")
		(net "M_C_CPU0_SA_DQS_DP<8>")
	)
	(gr_poly
		(pts
			(xy 337.312762 -264.29589) (xy 337.312762 -264.251694) (xy 336.957162 -264.251694) (xy 336.957162 -264.29589)
			(xy 337.004152 -264.44829) (xy 337.265772 -264.44829)
		)
		(stroke
			(width 0)
			(type solid)
		)
		(fill yes)
		(layer "In6.Cu")
		(net "M_C_CPU0_SA_DQ<28>")
	)
	(gr_poly
		(pts
			(xy 337.312762 -262.668258) (xy 337.312762 -262.623808) (xy 336.957162 -262.623808) (xy 336.957162 -262.668258)
			(xy 337.004152 -262.820658) (xy 337.265772 -262.820658)
		)
		(stroke
			(width 0)
			(type solid)
		)
		(fill yes)
		(layer "In6.Cu")
		(net "M_C_CPU0_SA_CB<2>")
	)
	(gr_poly
		(pts
			(xy 337.312762 -259.412486) (xy 337.312762 -259.36829) (xy 336.957162 -259.36829) (xy 336.957162 -259.412486)
			(xy 337.004152 -259.564886) (xy 337.265772 -259.564886)
		)
		(stroke
			(width 0)
			(type solid)
		)
		(fill yes)
		(layer "In6.Cu")
		(net "M_C_CPU0_SA_CB<6>")
	)
	(gr_poly
		(pts
			(xy 337.312762 -258.193286) (xy 337.265772 -258.040886) (xy 337.004152 -258.040886) (xy 336.957162 -258.193286)
			(xy 336.957162 -258.237736) (xy 337.312762 -258.237736)
		)
		(stroke
			(width 0)
			(type solid)
		)
		(fill yes)
		(layer "In6.Cu")
		(net "M_C_CPU0_SA_CB<5>")
	)
	(gr_poly
		(pts
			(xy 337.312762 -256.565654) (xy 337.265772 -256.413254) (xy 337.004152 -256.413254) (xy 336.957162 -256.565654)
			(xy 336.957162 -256.610104) (xy 337.312762 -256.610104)
		)
		(stroke
			(width 0)
			(type solid)
		)
		(fill yes)
		(layer "In6.Cu")
		(net "M_D_CPU0_SB_RSP<0>")
	)
	(gr_poly
		(pts
			(xy 337.312762 -254.529082) (xy 337.312762 -254.484886) (xy 336.957162 -254.484886) (xy 336.957162 -254.529082)
			(xy 337.004152 -254.681482) (xy 337.265772 -254.681482)
		)
		(stroke
			(width 0)
			(type solid)
		)
		(fill yes)
		(layer "In6.Cu")
		(net "M_C_CPU0_SA_RSP<1>")
	)
	(gr_poly
		(pts
			(xy 337.315556 -263.07669) (xy 337.268566 -262.92429) (xy 337.006946 -262.92429) (xy 336.959956 -263.07669)
			(xy 336.959956 -263.12114) (xy 337.315556 -263.12114)
		)
		(stroke
			(width 0)
			(type solid)
		)
		(fill yes)
		(layer "In6.Cu")
		(net "M_C_CPU0_SA_DQ<31>")
	)
	(gr_poly
		(pts
			(xy 337.318858 -272.843498) (xy 337.271868 -272.691098) (xy 337.010248 -272.691098) (xy 336.963258 -272.843498)
			(xy 336.963258 -272.887948) (xy 337.318858 -272.887948)
		)
		(stroke
			(width 0)
			(type solid)
		)
		(fill yes)
		(layer "In6.Cu")
		(net "M_D_CPU0_SA_DQ<7>")
	)
	(gr_poly
		(pts
			(xy 337.387692 -276.16658) (xy 337.279234 -276.04974) (xy 337.24088 -276.027642) (xy 337.06308 -276.33549)
			(xy 337.101434 -276.357588) (xy 337.256882 -276.393148)
		)
		(stroke
			(width 0)
			(type solid)
		)
		(fill yes)
		(layer "In6.Cu")
		(net "M_D_CPU0_SA_DQS_DN<5>")
	)
	(gr_poly
		(pts
			(xy 337.387692 -274.538694) (xy 337.279234 -274.421854) (xy 337.24088 -274.399756) (xy 337.06308 -274.707604)
			(xy 337.101434 -274.729702) (xy 337.256882 -274.765262)
		)
		(stroke
			(width 0)
			(type solid)
		)
		(fill yes)
		(layer "In6.Cu")
		(net "M_D_CPU0_SA_DQ<4>")
	)
	(gr_poly
		(pts
			(xy 337.39201 -277.7871) (xy 337.283552 -277.67026) (xy 337.245198 -277.648162) (xy 337.067398 -277.95601)
			(xy 337.105752 -277.978108) (xy 337.2612 -278.013668)
		)
		(stroke
			(width 0)
			(type solid)
		)
		(fill yes)
		(layer "In6.Cu")
		(net "M_D_CPU0_SA_DQS_DP<0>")
	)
	(gr_poly
		(pts
			(xy 337.528408 -224.85223) (xy 337.566762 -224.830132) (xy 337.388962 -224.522284) (xy 337.350608 -224.544382)
			(xy 337.24215 -224.661222) (xy 337.37296 -224.88779)
		)
		(stroke
			(width 0)
			(type solid)
		)
		(fill yes)
		(layer "In6.Cu")
		(net "M_C_CPU0_SB_DQ<31>")
	)
	(gr_poly
		(pts
			(xy 337.529678 -232.993692) (xy 337.568032 -232.971594) (xy 337.390232 -232.663746) (xy 337.351878 -232.685844)
			(xy 337.24342 -232.802684) (xy 337.37423 -233.029252)
		)
		(stroke
			(width 0)
			(type solid)
		)
		(fill yes)
		(layer "In6.Cu")
		(net "M_D_CPU0_SB_DQS_DP<2>")
	)
	(gr_poly
		(pts
			(xy 337.639406 -224.234502) (xy 337.747864 -224.117662) (xy 337.617054 -223.891094) (xy 337.461606 -223.926654)
			(xy 337.423252 -223.948752) (xy 337.601052 -224.2566)
		)
		(stroke
			(width 0)
			(type solid)
		)
		(fill yes)
		(layer "In6.Cu")
		(net "M_C_CPU0_SB_DQ<29>")
	)
	(gr_poly
		(pts
			(xy 337.643724 -232.380536) (xy 337.752182 -232.263696) (xy 337.621372 -232.037128) (xy 337.465924 -232.072688)
			(xy 337.42757 -232.094786) (xy 337.60537 -232.402634)
		)
		(stroke
			(width 0)
			(type solid)
		)
		(fill yes)
		(layer "In6.Cu")
		(net "M_D_CPU0_SB_DQS_DN<2>")
	)
	(gr_poly
		(pts
			(xy 337.666838 -247.382538) (xy 337.619848 -247.230138) (xy 337.358228 -247.230138) (xy 337.311238 -247.382538)
			(xy 337.311238 -247.426988) (xy 337.666838 -247.426988)
		)
		(stroke
			(width 0)
			(type solid)
		)
		(fill yes)
		(layer "In6.Cu")
		(net "M_A_CPU0_SB_RSP<1>")
	)
	(gr_poly
		(pts
			(xy 337.669378 -243.718334) (xy 337.669378 -243.674138) (xy 337.313778 -243.674138) (xy 337.313778 -243.718334)
			(xy 337.360768 -243.870734) (xy 337.622388 -243.870734)
		)
		(stroke
			(width 0)
			(type solid)
		)
		(fill yes)
		(layer "In6.Cu")
		(net "M_C_CPU0_SB_DQ<1>")
	)
	(gr_poly
		(pts
			(xy 337.672426 -242.499642) (xy 337.625436 -242.347242) (xy 337.363816 -242.347242) (xy 337.316826 -242.499642)
			(xy 337.316826 -242.543838) (xy 337.672426 -242.543838)
		)
		(stroke
			(width 0)
			(type solid)
		)
		(fill yes)
		(layer "In6.Cu")
		(net "M_C_CPU0_SB_DQS_DN<0>")
	)
	(gr_poly
		(pts
			(xy 337.672934 -248.601738) (xy 337.672934 -248.557542) (xy 337.317334 -248.557542) (xy 337.317334 -248.601738)
			(xy 337.364324 -248.754138) (xy 337.625944 -248.754138)
		)
		(stroke
			(width 0)
			(type solid)
		)
		(fill yes)
		(layer "In6.Cu")
		(net "M_A_CPU0_SB_RSP<0>")
	)
	(gr_poly
		(pts
			(xy 337.676744 -276.267926) (xy 337.63839 -276.245828) (xy 337.482942 -276.210268) (xy 337.352132 -276.436836)
			(xy 337.46059 -276.553676) (xy 337.498944 -276.575774)
		)
		(stroke
			(width 0)
			(type solid)
		)
		(fill yes)
		(layer "In6.Cu")
		(net "M_D_CPU0_SA_DQS_DN<0>")
	)
	(gr_poly
		(pts
			(xy 337.676744 -274.64004) (xy 337.63839 -274.617942) (xy 337.482942 -274.582382) (xy 337.352132 -274.80895)
			(xy 337.46059 -274.92579) (xy 337.498944 -274.947888)
		)
		(stroke
			(width 0)
			(type solid)
		)
		(fill yes)
		(layer "In6.Cu")
		(net "M_D_CPU0_SA_DQS_DP<5>")
	)
	(gr_poly
		(pts
			(xy 337.678776 -277.891748) (xy 337.640422 -277.86965) (xy 337.484974 -277.83409) (xy 337.354164 -278.060658)
			(xy 337.462622 -278.177498) (xy 337.500976 -278.199596)
		)
		(stroke
			(width 0)
			(type solid)
		)
		(fill yes)
		(layer "In6.Cu")
		(net "M_D_CPU0_SA_DQ<3>")
	)
	(gr_poly
		(pts
			(xy 337.681316 -245.754906) (xy 337.634326 -245.602506) (xy 337.372706 -245.602506) (xy 337.325716 -245.754906)
			(xy 337.325716 -245.799102) (xy 337.681316 -245.799102)
		)
		(stroke
			(width 0)
			(type solid)
		)
		(fill yes)
		(layer "In6.Cu")
		(net "M_D_CPU0_SB_CS_N<3>")
	)
	(gr_poly
		(pts
			(xy 337.681316 -245.346474) (xy 337.681316 -245.302278) (xy 337.325716 -245.302278) (xy 337.325716 -245.346474)
			(xy 337.372706 -245.498874) (xy 337.634326 -245.498874)
		)
		(stroke
			(width 0)
			(type solid)
		)
		(fill yes)
		(layer "In6.Cu")
		(net "M_D_CPU0_SB_CS_N<0>")
	)
	(gr_poly
		(pts
			(xy 337.681316 -244.126766) (xy 337.634326 -243.974366) (xy 337.372706 -243.974366) (xy 337.325716 -244.126766)
			(xy 337.325716 -244.171216) (xy 337.681316 -244.171216)
		)
		(stroke
			(width 0)
			(type solid)
		)
		(fill yes)
		(layer "In6.Cu")
		(net "M_C_CPU0_SB_DQ<2>")
	)
	(gr_poly
		(pts
			(xy 337.681316 -242.090702) (xy 337.681316 -242.046506) (xy 337.325716 -242.046506) (xy 337.325716 -242.090702)
			(xy 337.372706 -242.243102) (xy 337.634326 -242.243102)
		)
		(stroke
			(width 0)
			(type solid)
		)
		(fill yes)
		(layer "In6.Cu")
		(net "M_C_CPU0_SB_DQS_DN<5>")
	)
	(gr_poly
		(pts
			(xy 337.681316 -240.871502) (xy 337.634326 -240.719102) (xy 337.372706 -240.719102) (xy 337.325716 -240.871502)
			(xy 337.325716 -240.915698) (xy 337.681316 -240.915698)
		)
		(stroke
			(width 0)
			(type solid)
		)
		(fill yes)
		(layer "In6.Cu")
		(net "M_C_CPU0_SB_DQ<6>")
	)
	(gr_poly
		(pts
			(xy 337.681316 -240.46307) (xy 337.681316 -240.418874) (xy 337.325716 -240.418874) (xy 337.325716 -240.46307)
			(xy 337.372706 -240.61547) (xy 337.634326 -240.61547)
		)
		(stroke
			(width 0)
			(type solid)
		)
		(fill yes)
		(layer "In6.Cu")
		(net "M_C_CPU0_SB_DQ<5>")
	)
	(gr_poly
		(pts
			(xy 337.681316 -239.243362) (xy 337.634326 -239.090962) (xy 337.372706 -239.090962) (xy 337.325716 -239.243362)
			(xy 337.325716 -239.287812) (xy 337.681316 -239.287812)
		)
		(stroke
			(width 0)
			(type solid)
		)
		(fill yes)
		(layer "In6.Cu")
		(net "M_C_CPU0_SB_DQ<10>")
	)
	(gr_poly
		(pts
			(xy 337.681316 -238.835438) (xy 337.681316 -238.790988) (xy 337.325716 -238.790988) (xy 337.325716 -238.835438)
			(xy 337.372706 -238.987838) (xy 337.634326 -238.987838)
		)
		(stroke
			(width 0)
			(type solid)
		)
		(fill yes)
		(layer "In6.Cu")
		(net "M_C_CPU0_SB_DQ<9>")
	)
	(gr_poly
		(pts
			(xy 337.681316 -237.61573) (xy 337.634326 -237.46333) (xy 337.372706 -237.46333) (xy 337.325716 -237.61573)
			(xy 337.325716 -237.659926) (xy 337.681316 -237.659926)
		)
		(stroke
			(width 0)
			(type solid)
		)
		(fill yes)
		(layer "In6.Cu")
		(net "M_C_CPU0_SB_DQS_DN<1>")
	)
	(gr_poly
		(pts
			(xy 337.681316 -237.207806) (xy 337.681316 -237.163356) (xy 337.325716 -237.163356) (xy 337.325716 -237.207806)
			(xy 337.372706 -237.360206) (xy 337.634326 -237.360206)
		)
		(stroke
			(width 0)
			(type solid)
		)
		(fill yes)
		(layer "In6.Cu")
		(net "M_C_CPU0_SB_DQS_DN<6>")
	)
	(gr_poly
		(pts
			(xy 337.681316 -235.988098) (xy 337.634326 -235.835698) (xy 337.372706 -235.835698) (xy 337.325716 -235.988098)
			(xy 337.325716 -236.032294) (xy 337.681316 -236.032294)
		)
		(stroke
			(width 0)
			(type solid)
		)
		(fill yes)
		(layer "In6.Cu")
		(net "M_C_CPU0_SB_DQ<14>")
	)
	(gr_poly
		(pts
			(xy 337.681316 -235.579666) (xy 337.681316 -235.53547) (xy 337.325716 -235.53547) (xy 337.325716 -235.579666)
			(xy 337.372706 -235.732066) (xy 337.634326 -235.732066)
		)
		(stroke
			(width 0)
			(type solid)
		)
		(fill yes)
		(layer "In6.Cu")
		(net "M_C_CPU0_SB_DQ<13>")
	)
	(gr_poly
		(pts
			(xy 337.681316 -234.360466) (xy 337.634326 -234.208066) (xy 337.372706 -234.208066) (xy 337.325716 -234.360466)
			(xy 337.325716 -234.404662) (xy 337.681316 -234.404662)
		)
		(stroke
			(width 0)
			(type solid)
		)
		(fill yes)
		(layer "In6.Cu")
		(net "M_D_CPU0_SB_DQ<18>")
	)
	(gr_poly
		(pts
			(xy 337.681316 -233.952034) (xy 337.681316 -233.907838) (xy 337.325716 -233.907838) (xy 337.325716 -233.952034)
			(xy 337.372706 -234.104434) (xy 337.634326 -234.104434)
		)
		(stroke
			(width 0)
			(type solid)
		)
		(fill yes)
		(layer "In6.Cu")
		(net "M_D_CPU0_SB_DQ<17>")
	)
	(gr_poly
		(pts
			(xy 337.681316 -231.104694) (xy 337.634326 -230.952294) (xy 337.372706 -230.952294) (xy 337.325716 -231.104694)
			(xy 337.325716 -231.14889) (xy 337.681316 -231.14889)
		)
		(stroke
			(width 0)
			(type solid)
		)
		(fill yes)
		(layer "In6.Cu")
		(net "M_D_CPU0_SB_DQS_DP<7>")
	)
	(gr_poly
		(pts
			(xy 337.681316 -230.696262) (xy 337.681316 -230.652066) (xy 337.325716 -230.652066) (xy 337.325716 -230.696262)
			(xy 337.372706 -230.848662) (xy 337.634326 -230.848662)
		)
		(stroke
			(width 0)
			(type solid)
		)
		(fill yes)
		(layer "In6.Cu")
		(net "M_D_CPU0_SB_DQ<20>")
	)
	(gr_poly
		(pts
			(xy 337.681316 -229.477062) (xy 337.634326 -229.324662) (xy 337.372706 -229.324662) (xy 337.325716 -229.477062)
			(xy 337.325716 -229.521258) (xy 337.681316 -229.521258)
		)
		(stroke
			(width 0)
			(type solid)
		)
		(fill yes)
		(layer "In6.Cu")
		(net "M_D_CPU0_SB_DQ<23>")
	)
	(gr_poly
		(pts
			(xy 337.681316 -229.06863) (xy 337.681316 -229.024434) (xy 337.325716 -229.024434) (xy 337.325716 -229.06863)
			(xy 337.372706 -229.22103) (xy 337.634326 -229.22103)
		)
		(stroke
			(width 0)
			(type solid)
		)
		(fill yes)
		(layer "In6.Cu")
		(net "M_C_CPU0_SB_DQ<26>")
	)
	(gr_poly
		(pts
			(xy 337.681316 -227.848922) (xy 337.634326 -227.696522) (xy 337.372706 -227.696522) (xy 337.325716 -227.848922)
			(xy 337.325716 -227.893372) (xy 337.681316 -227.893372)
		)
		(stroke
			(width 0)
			(type solid)
		)
		(fill yes)
		(layer "In6.Cu")
		(net "M_C_CPU0_SB_DQ<27>")
	)
	(gr_poly
		(pts
			(xy 337.681316 -227.440998) (xy 337.681316 -227.396548) (xy 337.325716 -227.396548) (xy 337.325716 -227.440998)
			(xy 337.372706 -227.593398) (xy 337.634326 -227.593398)
		)
		(stroke
			(width 0)
			(type solid)
		)
		(fill yes)
		(layer "In6.Cu")
		(net "M_C_CPU0_SB_DQS_DP<3>")
	)
	(gr_poly
		(pts
			(xy 337.681316 -226.22129) (xy 337.634326 -226.06889) (xy 337.372706 -226.06889) (xy 337.325716 -226.22129)
			(xy 337.325716 -226.26574) (xy 337.681316 -226.26574)
		)
		(stroke
			(width 0)
			(type solid)
		)
		(fill yes)
		(layer "In6.Cu")
		(net "M_C_CPU0_SB_DQS_DP<8>")
	)
	(gr_poly
		(pts
			(xy 337.681316 -225.813366) (xy 337.681316 -225.768916) (xy 337.325716 -225.768916) (xy 337.325716 -225.813366)
			(xy 337.372706 -225.965766) (xy 337.634326 -225.965766)
		)
		(stroke
			(width 0)
			(type solid)
		)
		(fill yes)
		(layer "In6.Cu")
		(net "M_C_CPU0_SB_DQ<28>")
	)
	(gr_poly
		(pts
			(xy 337.782662 -273.657314) (xy 337.735672 -273.504914) (xy 337.474052 -273.504914) (xy 337.427062 -273.657314)
			(xy 337.427062 -273.701764) (xy 337.782662 -273.701764)
		)
		(stroke
			(width 0)
			(type solid)
		)
		(fill yes)
		(layer "In6.Cu")
		(net "M_D_CPU0_SA_DQ<6>")
	)
	(gr_poly
		(pts
			(xy 337.782662 -273.248882) (xy 337.782662 -273.204432) (xy 337.427062 -273.204432) (xy 337.427062 -273.248882)
			(xy 337.474052 -273.401282) (xy 337.735672 -273.401282)
		)
		(stroke
			(width 0)
			(type solid)
		)
		(fill yes)
		(layer "In6.Cu")
		(net "M_D_CPU0_SA_DQ<5>")
	)
	(gr_poly
		(pts
			(xy 337.782662 -270.40205) (xy 337.735672 -270.24965) (xy 337.474052 -270.24965) (xy 337.427062 -270.40205)
			(xy 337.427062 -270.446246) (xy 337.782662 -270.446246)
		)
		(stroke
			(width 0)
			(type solid)
		)
		(fill yes)
		(layer "In6.Cu")
		(net "M_C_CPU0_SA_DQS_DN<1>")
	)
	(gr_poly
		(pts
			(xy 337.782662 -269.99311) (xy 337.782662 -269.948914) (xy 337.427062 -269.948914) (xy 337.427062 -269.99311)
			(xy 337.474052 -270.14551) (xy 337.735672 -270.14551)
		)
		(stroke
			(width 0)
			(type solid)
		)
		(fill yes)
		(layer "In6.Cu")
		(net "M_C_CPU0_SA_DQS_DN<6>")
	)
	(gr_poly
		(pts
			(xy 337.782662 -268.77391) (xy 337.735672 -268.62151) (xy 337.474052 -268.62151) (xy 337.427062 -268.77391)
			(xy 337.427062 -268.81836) (xy 337.782662 -268.81836)
		)
		(stroke
			(width 0)
			(type solid)
		)
		(fill yes)
		(layer "In6.Cu")
		(net "M_C_CPU0_SA_DQ<14>")
	)
	(gr_poly
		(pts
			(xy 337.782662 -268.365478) (xy 337.782662 -268.321028) (xy 337.427062 -268.321028) (xy 337.427062 -268.365478)
			(xy 337.474052 -268.517878) (xy 337.735672 -268.517878)
		)
		(stroke
			(width 0)
			(type solid)
		)
		(fill yes)
		(layer "In6.Cu")
		(net "M_C_CPU0_SA_DQ<13>")
	)
	(gr_poly
		(pts
			(xy 337.782662 -266.737846) (xy 337.782662 -266.693396) (xy 337.427062 -266.693396) (xy 337.427062 -266.737846)
			(xy 337.474052 -266.890246) (xy 337.735672 -266.890246)
		)
		(stroke
			(width 0)
			(type solid)
		)
		(fill yes)
		(layer "In6.Cu")
		(net "M_C_CPU0_SA_DQ<25>")
	)
	(gr_poly
		(pts
			(xy 337.782662 -265.518646) (xy 337.735672 -265.366246) (xy 337.474052 -265.366246) (xy 337.427062 -265.518646)
			(xy 337.427062 -265.562842) (xy 337.782662 -265.562842)
		)
		(stroke
			(width 0)
			(type solid)
		)
		(fill yes)
		(layer "In6.Cu")
		(net "M_C_CPU0_SA_DQS_DN<3>")
	)
	(gr_poly
		(pts
			(xy 337.782662 -265.109706) (xy 337.782662 -265.06551) (xy 337.427062 -265.06551) (xy 337.427062 -265.109706)
			(xy 337.474052 -265.262106) (xy 337.735672 -265.262106)
		)
		(stroke
			(width 0)
			(type solid)
		)
		(fill yes)
		(layer "In6.Cu")
		(net "M_C_CPU0_SA_DQS_DN<8>")
	)
	(gr_poly
		(pts
			(xy 337.782662 -263.891014) (xy 337.735672 -263.738614) (xy 337.474052 -263.738614) (xy 337.427062 -263.891014)
			(xy 337.427062 -263.93521) (xy 337.782662 -263.93521)
		)
		(stroke
			(width 0)
			(type solid)
		)
		(fill yes)
		(layer "In6.Cu")
		(net "M_C_CPU0_SA_DQ<30>")
	)
	(gr_poly
		(pts
			(xy 337.782662 -262.262874) (xy 337.735672 -262.110474) (xy 337.474052 -262.110474) (xy 337.427062 -262.262874)
			(xy 337.427062 -262.307324) (xy 337.782662 -262.307324)
		)
		(stroke
			(width 0)
			(type solid)
		)
		(fill yes)
		(layer "In6.Cu")
		(net "M_C_CPU0_SA_CB<0>")
	)
	(gr_poly
		(pts
			(xy 337.782662 -259.00761) (xy 337.735672 -258.85521) (xy 337.474052 -258.85521) (xy 337.427062 -259.00761)
			(xy 337.427062 -259.051806) (xy 337.782662 -259.051806)
		)
		(stroke
			(width 0)
			(type solid)
		)
		(fill yes)
		(layer "In6.Cu")
		(net "M_C_CPU0_SA_CB<4>")
	)
	(gr_poly
		(pts
			(xy 337.782662 -258.59867) (xy 337.782662 -258.554474) (xy 337.427062 -258.554474) (xy 337.427062 -258.59867)
			(xy 337.474052 -258.75107) (xy 337.735672 -258.75107)
		)
		(stroke
			(width 0)
			(type solid)
		)
		(fill yes)
		(layer "In6.Cu")
		(net "M_C_CPU0_SA_CB<7>")
	)
	(gr_poly
		(pts
			(xy 337.782662 -256.971038) (xy 337.782662 -256.926588) (xy 337.427062 -256.926588) (xy 337.427062 -256.971038)
			(xy 337.474052 -257.123438) (xy 337.735672 -257.123438)
		)
		(stroke
			(width 0)
			(type solid)
		)
		(fill yes)
		(layer "In6.Cu")
		(net "M_D_CPU0_SA_RSP<0>")
	)
	(gr_poly
		(pts
			(xy 337.782662 -254.124206) (xy 337.735672 -253.971806) (xy 337.474052 -253.971806) (xy 337.427062 -254.124206)
			(xy 337.427062 -254.168402) (xy 337.782662 -254.168402)
		)
		(stroke
			(width 0)
			(type solid)
		)
		(fill yes)
		(layer "In6.Cu")
		(net "M_C_CPU0_SB_RSP<1>")
	)
	(gr_poly
		(pts
			(xy 337.782916 -263.482074) (xy 337.782916 -263.437624) (xy 337.427316 -263.437624) (xy 337.427316 -263.482074)
			(xy 337.474306 -263.634474) (xy 337.735926 -263.634474)
		)
		(stroke
			(width 0)
			(type solid)
		)
		(fill yes)
		(layer "In6.Cu")
		(net "M_C_CPU0_SA_DQ<29>")
	)
	(gr_poly
		(pts
			(xy 337.788758 -272.029682) (xy 337.741768 -271.877282) (xy 337.480148 -271.877282) (xy 337.433158 -272.029682)
			(xy 337.433158 -272.073878) (xy 337.788758 -272.073878)
		)
		(stroke
			(width 0)
			(type solid)
		)
		(fill yes)
		(layer "In6.Cu")
		(net "M_C_CPU0_SA_DQ<10>")
	)
	(gr_poly
		(pts
			(xy 337.788758 -271.620742) (xy 337.788758 -271.576546) (xy 337.433158 -271.576546) (xy 337.433158 -271.620742)
			(xy 337.480148 -271.773142) (xy 337.741768 -271.773142)
		)
		(stroke
			(width 0)
			(type solid)
		)
		(fill yes)
		(layer "In6.Cu")
		(net "M_C_CPU0_SA_DQ<9>")
	)
	(gr_poly
		(pts
			(xy 337.788758 -267.146278) (xy 337.741768 -266.993878) (xy 337.480148 -266.993878) (xy 337.433158 -267.146278)
			(xy 337.433158 -267.190474) (xy 337.788758 -267.190474)
		)
		(stroke
			(width 0)
			(type solid)
		)
		(fill yes)
		(layer "In6.Cu")
		(net "M_C_CPU0_SA_DQ<26>")
	)
	(gr_poly
		(pts
			(xy 337.788758 -261.854442) (xy 337.788758 -261.809992) (xy 337.433158 -261.809992) (xy 337.433158 -261.854442)
			(xy 337.480148 -262.006842) (xy 337.741768 -262.006842)
		)
		(stroke
			(width 0)
			(type solid)
		)
		(fill yes)
		(layer "In6.Cu")
		(net "M_C_CPU0_SA_CB<3>")
	)
	(gr_poly
		(pts
			(xy 337.788758 -255.751838) (xy 337.741768 -255.599438) (xy 337.480148 -255.599438) (xy 337.433158 -255.751838)
			(xy 337.433158 -255.796288) (xy 337.788758 -255.796288)
		)
		(stroke
			(width 0)
			(type solid)
		)
		(fill yes)
		(layer "In6.Cu")
		(net "M_D_CPU0_SB_RSP<1>")
	)
	(gr_poly
		(pts
			(xy 337.788758 -255.343406) (xy 337.788758 -255.298956) (xy 337.433158 -255.298956) (xy 337.433158 -255.343406)
			(xy 337.480148 -255.495806) (xy 337.741768 -255.495806)
		)
		(stroke
			(width 0)
			(type solid)
		)
		(fill yes)
		(layer "In6.Cu")
		(net "M_C_CPU0_SA_RSP<0>")
	)
	(gr_poly
		(pts
			(xy 337.791298 -260.634734) (xy 337.744308 -260.482334) (xy 337.482688 -260.482334) (xy 337.435698 -260.634734)
			(xy 337.435698 -260.679184) (xy 337.791298 -260.679184)
		)
		(stroke
			(width 0)
			(type solid)
		)
		(fill yes)
		(layer "In6.Cu")
		(net "M_C_CPU0_SA_DQS_DP<9>")
	)
	(gr_poly
		(pts
			(xy 337.791298 -260.22681) (xy 337.791298 -260.18236) (xy 337.435698 -260.18236) (xy 337.435698 -260.22681)
			(xy 337.482688 -260.37921) (xy 337.744308 -260.37921)
		)
		(stroke
			(width 0)
			(type solid)
		)
		(fill yes)
		(layer "In6.Cu")
		(net "M_C_CPU0_SA_DQS_DP<4>")
	)
	(gr_poly
		(pts
			(xy 337.85556 -275.356574) (xy 337.747102 -275.239734) (xy 337.708748 -275.217636) (xy 337.530948 -275.525484)
			(xy 337.569302 -275.547582) (xy 337.72475 -275.583142)
		)
		(stroke
			(width 0)
			(type solid)
		)
		(fill yes)
		(layer "In6.Cu")
		(net "M_D_CPU0_SA_DQS_DN<5>")
	)
	(gr_poly
		(pts
			(xy 337.857592 -278.608282) (xy 337.749134 -278.491442) (xy 337.71078 -278.469344) (xy 337.53298 -278.777192)
			(xy 337.571334 -278.79929) (xy 337.726782 -278.83485)
		)
		(stroke
			(width 0)
			(type solid)
		)
		(fill yes)
		(layer "In6.Cu")
		(net "M_D_CPU0_SA_DQ<1>")
	)
	(gr_poly
		(pts
			(xy 337.857592 -276.980396) (xy 337.749134 -276.863556) (xy 337.71078 -276.841458) (xy 337.53298 -277.149306)
			(xy 337.571334 -277.171404) (xy 337.726782 -277.206964)
		)
		(stroke
			(width 0)
			(type solid)
		)
		(fill yes)
		(layer "In6.Cu")
		(net "M_D_CPU0_SA_DQS_DP<0>")
	)
	(gr_poly
		(pts
			(xy 337.99399 -232.170224) (xy 338.032344 -232.148126) (xy 337.854544 -231.840278) (xy 337.81619 -231.862376)
			(xy 337.707732 -231.979216) (xy 337.838542 -232.205784)
		)
		(stroke
			(width 0)
			(type solid)
		)
		(fill yes)
		(layer "In6.Cu")
		(net "M_D_CPU0_SB_DQS_DN<7>")
	)
	(gr_poly
		(pts
			(xy 338.106258 -231.555544) (xy 338.214716 -231.438704) (xy 338.083906 -231.212136) (xy 337.928458 -231.247696)
			(xy 337.890104 -231.269794) (xy 338.067904 -231.577642)
		)
		(stroke
			(width 0)
			(type solid)
		)
		(fill yes)
		(layer "In6.Cu")
		(net "M_D_CPU0_SB_DQS_DP<7>")
	)
	(gr_poly
		(pts
			(xy 338.134198 -246.16029) (xy 338.134198 -246.116094) (xy 337.778598 -246.116094) (xy 337.778598 -246.16029)
			(xy 337.825588 -246.31269) (xy 338.087208 -246.31269)
		)
		(stroke
			(width 0)
			(type solid)
		)
		(fill yes)
		(layer "In6.Cu")
		(net "M_D_CPU0_SB_CS_N<2>")
	)
	(gr_poly
		(pts
			(xy 338.134198 -242.905026) (xy 338.134198 -242.860576) (xy 337.778598 -242.860576) (xy 337.778598 -242.905026)
			(xy 337.825588 -243.057426) (xy 338.087208 -243.057426)
		)
		(stroke
			(width 0)
			(type solid)
		)
		(fill yes)
		(layer "In6.Cu")
		(net "M_C_CPU0_SB_DQS_DP<0>")
	)
	(gr_poly
		(pts
			(xy 338.134198 -241.685318) (xy 338.087208 -241.532918) (xy 337.825588 -241.532918) (xy 337.778598 -241.685318)
			(xy 337.778598 -241.729514) (xy 338.134198 -241.729514)
		)
		(stroke
			(width 0)
			(type solid)
		)
		(fill yes)
		(layer "In6.Cu")
		(net "M_C_CPU0_SB_DQS_DP<5>")
	)
	(gr_poly
		(pts
			(xy 338.134198 -241.276886) (xy 338.134198 -241.23269) (xy 337.778598 -241.23269) (xy 337.778598 -241.276886)
			(xy 337.825588 -241.429286) (xy 338.087208 -241.429286)
		)
		(stroke
			(width 0)
			(type solid)
		)
		(fill yes)
		(layer "In6.Cu")
		(net "M_C_CPU0_SB_DQ<4>")
	)
	(gr_poly
		(pts
			(xy 338.134198 -238.429546) (xy 338.087208 -238.277146) (xy 337.825588 -238.277146) (xy 337.778598 -238.429546)
			(xy 337.778598 -238.473996) (xy 338.134198 -238.473996)
		)
		(stroke
			(width 0)
			(type solid)
		)
		(fill yes)
		(layer "In6.Cu")
		(net "M_C_CPU0_SB_DQ<11>")
	)
	(gr_poly
		(pts
			(xy 338.134198 -238.021622) (xy 338.134198 -237.977172) (xy 337.778598 -237.977172) (xy 337.778598 -238.021622)
			(xy 337.825588 -238.174022) (xy 338.087208 -238.174022)
		)
		(stroke
			(width 0)
			(type solid)
		)
		(fill yes)
		(layer "In6.Cu")
		(net "M_C_CPU0_SB_DQS_DP<1>")
	)
	(gr_poly
		(pts
			(xy 338.134198 -236.801914) (xy 338.087208 -236.649514) (xy 337.825588 -236.649514) (xy 337.778598 -236.801914)
			(xy 337.778598 -236.84611) (xy 338.134198 -236.84611)
		)
		(stroke
			(width 0)
			(type solid)
		)
		(fill yes)
		(layer "In6.Cu")
		(net "M_C_CPU0_SB_DQS_DP<6>")
	)
	(gr_poly
		(pts
			(xy 338.134198 -236.39399) (xy 338.134198 -236.34954) (xy 337.778598 -236.34954) (xy 337.778598 -236.39399)
			(xy 337.825588 -236.54639) (xy 338.087208 -236.54639)
		)
		(stroke
			(width 0)
			(type solid)
		)
		(fill yes)
		(layer "In6.Cu")
		(net "M_C_CPU0_SB_DQ<12>")
	)
	(gr_poly
		(pts
			(xy 338.134198 -233.546142) (xy 338.087208 -233.393742) (xy 337.825588 -233.393742) (xy 337.778598 -233.546142)
			(xy 337.778598 -233.590592) (xy 338.134198 -233.590592)
		)
		(stroke
			(width 0)
			(type solid)
		)
		(fill yes)
		(layer "In6.Cu")
		(net "M_D_CPU0_SB_DQ<19>")
	)
	(gr_poly
		(pts
			(xy 338.134198 -233.138218) (xy 338.134198 -233.093768) (xy 337.778598 -233.093768) (xy 337.778598 -233.138218)
			(xy 337.825588 -233.290618) (xy 338.087208 -233.290618)
		)
		(stroke
			(width 0)
			(type solid)
		)
		(fill yes)
		(layer "In6.Cu")
		(net "M_D_CPU0_SB_DQS_DP<2>")
	)
	(gr_poly
		(pts
			(xy 338.134198 -228.663246) (xy 338.087208 -228.510846) (xy 337.825588 -228.510846) (xy 337.778598 -228.663246)
			(xy 337.778598 -228.707442) (xy 338.134198 -228.707442)
		)
		(stroke
			(width 0)
			(type solid)
		)
		(fill yes)
		(layer "In6.Cu")
		(net "M_C_CPU0_SB_DQ<24>")
	)
	(gr_poly
		(pts
			(xy 338.134198 -228.254814) (xy 338.134198 -228.210618) (xy 337.778598 -228.210618) (xy 337.778598 -228.254814)
			(xy 337.825588 -228.407214) (xy 338.087208 -228.407214)
		)
		(stroke
			(width 0)
			(type solid)
		)
		(fill yes)
		(layer "In6.Cu")
		(net "M_C_CPU0_SB_DQ<25>")
	)
	(gr_poly
		(pts
			(xy 338.134198 -227.035106) (xy 338.087208 -226.882706) (xy 337.825588 -226.882706) (xy 337.778598 -227.035106)
			(xy 337.778598 -227.079556) (xy 338.134198 -227.079556)
		)
		(stroke
			(width 0)
			(type solid)
		)
		(fill yes)
		(layer "In6.Cu")
		(net "M_C_CPU0_SB_DQS_DN<3>")
	)
	(gr_poly
		(pts
			(xy 338.134198 -226.627182) (xy 338.134198 -226.582732) (xy 337.778598 -226.582732) (xy 337.778598 -226.627182)
			(xy 337.825588 -226.779582) (xy 338.087208 -226.779582)
		)
		(stroke
			(width 0)
			(type solid)
		)
		(fill yes)
		(layer "In6.Cu")
		(net "M_C_CPU0_SB_DQS_DN<8>")
	)
	(gr_poly
		(pts
			(xy 338.134198 -225.407474) (xy 338.087208 -225.255074) (xy 337.825588 -225.255074) (xy 337.778598 -225.407474)
			(xy 337.778598 -225.45167) (xy 338.134198 -225.45167)
		)
		(stroke
			(width 0)
			(type solid)
		)
		(fill yes)
		(layer "In6.Cu")
		(net "M_C_CPU0_SB_DQ<30>")
	)
	(gr_poly
		(pts
			(xy 338.136738 -248.196354) (xy 338.089748 -248.043954) (xy 337.828128 -248.043954) (xy 337.781138 -248.196354)
			(xy 337.781138 -248.240804) (xy 338.136738 -248.240804)
		)
		(stroke
			(width 0)
			(type solid)
		)
		(fill yes)
		(layer "In6.Cu")
		(net "M_A_CPU0_SA_RSP<0>")
	)
	(gr_poly
		(pts
			(xy 338.136738 -244.940582) (xy 338.089748 -244.788182) (xy 337.828128 -244.788182) (xy 337.781138 -244.940582)
			(xy 337.781138 -244.985032) (xy 338.136738 -244.985032)
		)
		(stroke
			(width 0)
			(type solid)
		)
		(fill yes)
		(layer "In6.Cu")
		(net "M_D_CPU0_SB_CS_N<1>")
	)
	(gr_poly
		(pts
			(xy 338.136738 -244.532658) (xy 338.136738 -244.488208) (xy 337.781138 -244.488208) (xy 337.781138 -244.532658)
			(xy 337.828128 -244.685058) (xy 338.089748 -244.685058)
		)
		(stroke
			(width 0)
			(type solid)
		)
		(fill yes)
		(layer "In6.Cu")
		(net "M_C_CPU0_SB_DQ<0>")
	)
	(gr_poly
		(pts
			(xy 338.136738 -240.057178) (xy 338.089748 -239.904778) (xy 337.828128 -239.904778) (xy 337.781138 -240.057178)
			(xy 337.781138 -240.101628) (xy 338.136738 -240.101628)
		)
		(stroke
			(width 0)
			(type solid)
		)
		(fill yes)
		(layer "In6.Cu")
		(net "M_C_CPU0_SB_DQ<7>")
	)
	(gr_poly
		(pts
			(xy 338.136738 -239.649254) (xy 338.136738 -239.604804) (xy 337.781138 -239.604804) (xy 337.781138 -239.649254)
			(xy 337.828128 -239.801654) (xy 338.089748 -239.801654)
		)
		(stroke
			(width 0)
			(type solid)
		)
		(fill yes)
		(layer "In6.Cu")
		(net "M_C_CPU0_SB_DQ<8>")
	)
	(gr_poly
		(pts
			(xy 338.136738 -235.174282) (xy 338.089748 -235.021882) (xy 337.828128 -235.021882) (xy 337.781138 -235.174282)
			(xy 337.781138 -235.218478) (xy 338.136738 -235.218478)
		)
		(stroke
			(width 0)
			(type solid)
		)
		(fill yes)
		(layer "In6.Cu")
		(net "M_C_CPU0_SB_DQ<15>")
	)
	(gr_poly
		(pts
			(xy 338.136738 -234.76585) (xy 338.136738 -234.721654) (xy 337.781138 -234.721654) (xy 337.781138 -234.76585)
			(xy 337.828128 -234.91825) (xy 338.089748 -234.91825)
		)
		(stroke
			(width 0)
			(type solid)
		)
		(fill yes)
		(layer "In6.Cu")
		(net "M_D_CPU0_SB_DQ<16>")
	)
	(gr_poly
		(pts
			(xy 338.136738 -230.290878) (xy 338.089748 -230.138478) (xy 337.828128 -230.138478) (xy 337.781138 -230.290878)
			(xy 337.781138 -230.335074) (xy 338.136738 -230.335074)
		)
		(stroke
			(width 0)
			(type solid)
		)
		(fill yes)
		(layer "In6.Cu")
		(net "M_D_CPU0_SB_DQ<22>")
	)
	(gr_poly
		(pts
			(xy 338.136738 -229.882446) (xy 338.136738 -229.83825) (xy 337.781138 -229.83825) (xy 337.781138 -229.882446)
			(xy 337.828128 -230.034846) (xy 338.089748 -230.034846)
		)
		(stroke
			(width 0)
			(type solid)
		)
		(fill yes)
		(layer "In6.Cu")
		(net "M_D_CPU0_SB_DQ<21>")
	)
	(gr_poly
		(pts
			(xy 338.142326 -277.089108) (xy 338.103972 -277.06701) (xy 337.948524 -277.03145) (xy 337.817714 -277.258018)
			(xy 337.926172 -277.374858) (xy 337.964526 -277.396956)
		)
		(stroke
			(width 0)
			(type solid)
		)
		(fill yes)
		(layer "In6.Cu")
		(net "M_D_CPU0_SA_DQ<3>")
	)
	(gr_poly
		(pts
			(xy 338.146136 -243.313458) (xy 338.099146 -243.161058) (xy 337.837526 -243.161058) (xy 337.790536 -243.313458)
			(xy 337.790536 -243.357654) (xy 338.146136 -243.357654)
		)
		(stroke
			(width 0)
			(type solid)
		)
		(fill yes)
		(layer "In6.Cu")
		(net "M_C_CPU0_SB_DQ<3>")
	)
	(gr_poly
		(pts
			(xy 338.146644 -278.709628) (xy 338.10829 -278.68753) (xy 337.952842 -278.65197) (xy 337.822032 -278.878538)
			(xy 337.93049 -278.995378) (xy 337.968844 -279.017476)
		)
		(stroke
			(width 0)
			(type solid)
		)
		(fill yes)
		(layer "In6.Cu")
		(net "M_D_CPU0_SA_DQ<2>")
	)
	(gr_poly
		(pts
			(xy 338.148676 -275.450046) (xy 338.110322 -275.427948) (xy 337.954874 -275.392388) (xy 337.824064 -275.618956)
			(xy 337.932522 -275.735796) (xy 337.970876 -275.757894)
		)
		(stroke
			(width 0)
			(type solid)
		)
		(fill yes)
		(layer "In6.Cu")
		(net "M_D_CPU0_SA_DQS_DN<0>")
	)
	(gr_poly
		(pts
			(xy 338.148676 -247.787922) (xy 338.148676 -247.743472) (xy 337.793076 -247.743472) (xy 337.793076 -247.787922)
			(xy 337.840066 -247.940322) (xy 338.101686 -247.940322)
		)
		(stroke
			(width 0)
			(type solid)
		)
		(fill yes)
		(layer "In6.Cu")
		(net "M_A_CPU0_SA_RSP<1>")
	)
	(gr_poly
		(pts
			(xy 338.24418 -261.040626) (xy 338.24418 -260.99643) (xy 337.88858 -260.99643) (xy 337.88858 -261.040626)
			(xy 337.93557 -261.193026) (xy 338.19719 -261.193026)
		)
		(stroke
			(width 0)
			(type solid)
		)
		(fill yes)
		(layer "In6.Cu")
		(net "M_C_CPU0_SA_DQS_DN<9>")
	)
	(gr_poly
		(pts
			(xy 338.24418 -259.820918) (xy 338.19719 -259.668518) (xy 337.93557 -259.668518) (xy 337.88858 -259.820918)
			(xy 337.88858 -259.865368) (xy 338.24418 -259.865368)
		)
		(stroke
			(width 0)
			(type solid)
		)
		(fill yes)
		(layer "In6.Cu")
		(net "M_C_CPU0_SA_DQS_DN<4>")
	)
	(gr_poly
		(pts
			(xy 338.252562 -274.47113) (xy 338.205572 -274.31873) (xy 337.943952 -274.31873) (xy 337.896962 -274.47113)
			(xy 337.896962 -274.51558) (xy 338.252562 -274.51558)
		)
		(stroke
			(width 0)
			(type solid)
		)
		(fill yes)
		(layer "In6.Cu")
		(net "M_D_CPU0_SA_DQS_DP<5>")
	)
	(gr_poly
		(pts
			(xy 338.252562 -274.062698) (xy 338.252562 -274.018248) (xy 337.896962 -274.018248) (xy 337.896962 -274.062698)
			(xy 337.943952 -274.215098) (xy 338.205572 -274.215098)
		)
		(stroke
			(width 0)
			(type solid)
		)
		(fill yes)
		(layer "In6.Cu")
		(net "M_D_CPU0_SA_DQ<4>")
	)
	(gr_poly
		(pts
			(xy 338.252562 -271.215866) (xy 338.205572 -271.063466) (xy 337.943952 -271.063466) (xy 337.896962 -271.215866)
			(xy 337.896962 -271.260062) (xy 338.252562 -271.260062)
		)
		(stroke
			(width 0)
			(type solid)
		)
		(fill yes)
		(layer "In6.Cu")
		(net "M_C_CPU0_SA_DQ<11>")
	)
	(gr_poly
		(pts
			(xy 338.252562 -270.806926) (xy 338.252562 -270.76273) (xy 337.896962 -270.76273) (xy 337.896962 -270.806926)
			(xy 337.943952 -270.959326) (xy 338.205572 -270.959326)
		)
		(stroke
			(width 0)
			(type solid)
		)
		(fill yes)
		(layer "In6.Cu")
		(net "M_C_CPU0_SA_DQS_DP<1>")
	)
	(gr_poly
		(pts
			(xy 338.252562 -269.587726) (xy 338.205572 -269.435326) (xy 337.943952 -269.435326) (xy 337.896962 -269.587726)
			(xy 337.896962 -269.632176) (xy 338.252562 -269.632176)
		)
		(stroke
			(width 0)
			(type solid)
		)
		(fill yes)
		(layer "In6.Cu")
		(net "M_C_CPU0_SA_DQS_DP<6>")
	)
	(gr_poly
		(pts
			(xy 338.252562 -269.179294) (xy 338.252562 -269.134844) (xy 337.896962 -269.134844) (xy 337.896962 -269.179294)
			(xy 337.943952 -269.331694) (xy 338.205572 -269.331694)
		)
		(stroke
			(width 0)
			(type solid)
		)
		(fill yes)
		(layer "In6.Cu")
		(net "M_C_CPU0_SA_DQ<12>")
	)
	(gr_poly
		(pts
			(xy 338.252562 -266.332462) (xy 338.205572 -266.180062) (xy 337.943952 -266.180062) (xy 337.896962 -266.332462)
			(xy 337.896962 -266.376658) (xy 338.252562 -266.376658)
		)
		(stroke
			(width 0)
			(type solid)
		)
		(fill yes)
		(layer "In6.Cu")
		(net "M_C_CPU0_SA_DQ<27>")
	)
	(gr_poly
		(pts
			(xy 338.252562 -265.923522) (xy 338.252562 -265.879326) (xy 337.896962 -265.879326) (xy 337.896962 -265.923522)
			(xy 337.943952 -266.075922) (xy 338.205572 -266.075922)
		)
		(stroke
			(width 0)
			(type solid)
		)
		(fill yes)
		(layer "In6.Cu")
		(net "M_C_CPU0_SA_DQS_DP<3>")
	)
	(gr_poly
		(pts
			(xy 338.252562 -264.70483) (xy 338.205572 -264.55243) (xy 337.943952 -264.55243) (xy 337.896962 -264.70483)
			(xy 337.896962 -264.749026) (xy 338.252562 -264.749026)
		)
		(stroke
			(width 0)
			(type solid)
		)
		(fill yes)
		(layer "In6.Cu")
		(net "M_C_CPU0_SA_DQS_DP<8>")
	)
	(gr_poly
		(pts
			(xy 338.252562 -264.29589) (xy 338.252562 -264.251694) (xy 337.896962 -264.251694) (xy 337.896962 -264.29589)
			(xy 337.943952 -264.44829) (xy 338.205572 -264.44829)
		)
		(stroke
			(width 0)
			(type solid)
		)
		(fill yes)
		(layer "In6.Cu")
		(net "M_C_CPU0_SA_DQ<28>")
	)
	(gr_poly
		(pts
			(xy 338.252562 -261.449058) (xy 338.205572 -261.296658) (xy 337.943952 -261.296658) (xy 337.896962 -261.449058)
			(xy 337.896962 -261.493508) (xy 338.252562 -261.493508)
		)
		(stroke
			(width 0)
			(type solid)
		)
		(fill yes)
		(layer "In6.Cu")
		(net "M_C_CPU0_SA_CB<1>")
	)
	(gr_poly
		(pts
			(xy 338.252562 -259.412486) (xy 338.252562 -259.36829) (xy 337.896962 -259.36829) (xy 337.896962 -259.412486)
			(xy 337.943952 -259.564886) (xy 338.205572 -259.564886)
		)
		(stroke
			(width 0)
			(type solid)
		)
		(fill yes)
		(layer "In6.Cu")
		(net "M_C_CPU0_SA_CB<6>")
	)
	(gr_poly
		(pts
			(xy 338.252562 -256.565654) (xy 338.205572 -256.413254) (xy 337.943952 -256.413254) (xy 337.896962 -256.565654)
			(xy 337.896962 -256.610104) (xy 338.252562 -256.610104)
		)
		(stroke
			(width 0)
			(type solid)
		)
		(fill yes)
		(layer "In6.Cu")
		(net "M_D_CPU0_SB_RSP<0>")
	)
	(gr_poly
		(pts
			(xy 338.252562 -256.157222) (xy 338.252562 -256.112772) (xy 337.896962 -256.112772) (xy 337.896962 -256.157222)
			(xy 337.943952 -256.309622) (xy 338.205572 -256.309622)
		)
		(stroke
			(width 0)
			(type solid)
		)
		(fill yes)
		(layer "In6.Cu")
		(net "M_D_CPU0_SA_RSP<1>")
	)
	(gr_poly
		(pts
			(xy 338.252562 -254.938022) (xy 338.205572 -254.785622) (xy 337.943952 -254.785622) (xy 337.896962 -254.938022)
			(xy 337.896962 -254.982218) (xy 338.252562 -254.982218)
		)
		(stroke
			(width 0)
			(type solid)
		)
		(fill yes)
		(layer "In6.Cu")
		(net "M_C_CPU0_SB_RSP<0>")
	)
	(gr_poly
		(pts
			(xy 338.252562 -254.529082) (xy 338.252562 -254.484886) (xy 337.896962 -254.484886) (xy 337.896962 -254.529082)
			(xy 337.943952 -254.681482) (xy 338.205572 -254.681482)
		)
		(stroke
			(width 0)
			(type solid)
		)
		(fill yes)
		(layer "In6.Cu")
		(net "M_C_CPU0_SA_RSP<1>")
	)
	(gr_poly
		(pts
			(xy 338.254848 -263.07669) (xy 338.207858 -262.92429) (xy 337.946238 -262.92429) (xy 337.899248 -263.07669)
			(xy 337.899248 -263.12114) (xy 338.254848 -263.12114)
		)
		(stroke
			(width 0)
			(type solid)
		)
		(fill yes)
		(layer "In6.Cu")
		(net "M_C_CPU0_SA_DQ<31>")
	)
	(gr_poly
		(pts
			(xy 338.258658 -272.843498) (xy 338.211668 -272.691098) (xy 337.950048 -272.691098) (xy 337.903058 -272.843498)
			(xy 337.903058 -272.887694) (xy 338.258658 -272.887694)
		)
		(stroke
			(width 0)
			(type solid)
		)
		(fill yes)
		(layer "In6.Cu")
		(net "M_D_CPU0_SA_DQ<7>")
	)
	(gr_poly
		(pts
			(xy 338.258658 -272.435066) (xy 338.258658 -272.39087) (xy 337.903058 -272.39087) (xy 337.903058 -272.435066)
			(xy 337.950048 -272.587466) (xy 338.211668 -272.587466)
		)
		(stroke
			(width 0)
			(type solid)
		)
		(fill yes)
		(layer "In6.Cu")
		(net "M_C_CPU0_SA_DQ<8>")
	)
	(gr_poly
		(pts
			(xy 338.258658 -267.960094) (xy 338.211668 -267.807694) (xy 337.950048 -267.807694) (xy 337.903058 -267.960094)
			(xy 337.903058 -268.00429) (xy 338.258658 -268.00429)
		)
		(stroke
			(width 0)
			(type solid)
		)
		(fill yes)
		(layer "In6.Cu")
		(net "M_C_CPU0_SA_DQ<15>")
	)
	(gr_poly
		(pts
			(xy 338.258658 -267.551662) (xy 338.258658 -267.507466) (xy 337.903058 -267.507466) (xy 337.903058 -267.551662)
			(xy 337.950048 -267.704062) (xy 338.211668 -267.704062)
		)
		(stroke
			(width 0)
			(type solid)
		)
		(fill yes)
		(layer "In6.Cu")
		(net "M_C_CPU0_SA_DQ<24>")
	)
	(gr_poly
		(pts
			(xy 338.258658 -262.668258) (xy 338.258658 -262.624062) (xy 337.903058 -262.624062) (xy 337.903058 -262.668258)
			(xy 337.950048 -262.820658) (xy 338.211668 -262.820658)
		)
		(stroke
			(width 0)
			(type solid)
		)
		(fill yes)
		(layer "In6.Cu")
		(net "M_C_CPU0_SA_CB<2>")
	)
	(gr_poly
		(pts
			(xy 338.258658 -258.193286) (xy 338.211668 -258.040886) (xy 337.950048 -258.040886) (xy 337.903058 -258.193286)
			(xy 337.903058 -258.237482) (xy 338.258658 -258.237482)
		)
		(stroke
			(width 0)
			(type solid)
		)
		(fill yes)
		(layer "In6.Cu")
		(net "M_C_CPU0_SA_CB<5>")
	)
	(gr_poly
		(pts
			(xy 338.327492 -279.422098) (xy 338.219034 -279.305258) (xy 338.18068 -279.28316) (xy 338.00288 -279.591008)
			(xy 338.041234 -279.613106) (xy 338.196682 -279.648666)
		)
		(stroke
			(width 0)
			(type solid)
		)
		(fill yes)
		(layer "In6.Cu")
		(net "M_D_CPU0_SA_DQ<0>")
	)
	(gr_poly
		(pts
			(xy 338.327492 -276.16658) (xy 338.219034 -276.04974) (xy 338.18068 -276.027642) (xy 338.00288 -276.33549)
			(xy 338.041234 -276.357588) (xy 338.196682 -276.393148)
		)
		(stroke
			(width 0)
			(type solid)
		)
		(fill yes)
		(layer "In6.Cu")
		(net "M_D_CPU0_SA_DQS_DP<0>")
	)
	(gr_poly
		(pts
			(xy 338.328254 -277.79345) (xy 338.219796 -277.67661) (xy 338.181442 -277.654512) (xy 338.003642 -277.96236)
			(xy 338.041996 -277.984458) (xy 338.197444 -278.020018)
		)
		(stroke
			(width 0)
			(type solid)
		)
		(fill yes)
		(layer "In6.Cu")
		(net "M_D_CPU0_SA_DQ<1>")
	)
	(gr_poly
		(pts
			(xy 338.47024 -231.36733) (xy 338.508594 -231.345232) (xy 338.330794 -231.037384) (xy 338.29244 -231.059482)
			(xy 338.183982 -231.176322) (xy 338.314792 -231.40289)
		)
		(stroke
			(width 0)
			(type solid)
		)
		(fill yes)
		(layer "In6.Cu")
		(net "M_D_CPU0_SB_DQ<20>")
	)
	(gr_poly
		(pts
			(xy 338.506816 -223.948752) (xy 338.468462 -223.926654) (xy 338.313014 -223.891094) (xy 338.182204 -224.117662)
			(xy 338.290662 -224.234502) (xy 338.329016 -224.2566)
		)
		(stroke
			(width 0)
			(type solid)
		)
		(fill yes)
		(layer "In6.Cu")
		(net "M_C_CPU0_SB_DQ<29>")
	)
	(gr_poly
		(pts
			(xy 338.579206 -230.745538) (xy 338.687664 -230.628698) (xy 338.556854 -230.40213) (xy 338.401406 -230.43769)
			(xy 338.363052 -230.459788) (xy 338.540852 -230.767636)
		)
		(stroke
			(width 0)
			(type solid)
		)
		(fill yes)
		(layer "In6.Cu")
		(net "M_D_CPU0_SB_DQ<22>")
	)
	(gr_poly
		(pts
			(xy 338.606638 -245.346474) (xy 338.606638 -245.302024) (xy 338.251038 -245.302024) (xy 338.251038 -245.346474)
			(xy 338.298028 -245.498874) (xy 338.559648 -245.498874)
		)
		(stroke
			(width 0)
			(type solid)
		)
		(fill yes)
		(layer "In6.Cu")
		(net "M_D_CPU0_SB_CS_N<0>")
	)
	(gr_poly
		(pts
			(xy 338.606638 -240.46307) (xy 338.606638 -240.41862) (xy 338.251038 -240.41862) (xy 338.251038 -240.46307)
			(xy 338.298028 -240.61547) (xy 338.559648 -240.61547)
		)
		(stroke
			(width 0)
			(type solid)
		)
		(fill yes)
		(layer "In6.Cu")
		(net "M_C_CPU0_SB_DQ<5>")
	)
	(gr_poly
		(pts
			(xy 338.606638 -235.579666) (xy 338.606638 -235.535216) (xy 338.251038 -235.535216) (xy 338.251038 -235.579666)
			(xy 338.298028 -235.732066) (xy 338.559648 -235.732066)
		)
		(stroke
			(width 0)
			(type solid)
		)
		(fill yes)
		(layer "In6.Cu")
		(net "M_C_CPU0_SB_DQ<13>")
	)
	(gr_poly
		(pts
			(xy 338.609178 -243.718334) (xy 338.609178 -243.674138) (xy 338.253578 -243.674138) (xy 338.253578 -243.718334)
			(xy 338.300568 -243.870734) (xy 338.562188 -243.870734)
		)
		(stroke
			(width 0)
			(type solid)
		)
		(fill yes)
		(layer "In6.Cu")
		(net "M_C_CPU0_SB_DQ<1>")
	)
	(gr_poly
		(pts
			(xy 338.611972 -242.499642) (xy 338.564982 -242.347242) (xy 338.303362 -242.347242) (xy 338.256372 -242.499642)
			(xy 338.256372 -242.543838) (xy 338.611972 -242.543838)
		)
		(stroke
			(width 0)
			(type solid)
		)
		(fill yes)
		(layer "In6.Cu")
		(net "M_C_CPU0_SB_DQS_DN<0>")
	)
	(gr_poly
		(pts
			(xy 338.612734 -244.127274) (xy 338.565744 -243.974874) (xy 338.304124 -243.974874) (xy 338.257134 -244.127274)
			(xy 338.257134 -244.17147) (xy 338.612734 -244.17147)
		)
		(stroke
			(width 0)
			(type solid)
		)
		(fill yes)
		(layer "In6.Cu")
		(net "M_C_CPU0_SB_DQ<2>")
	)
	(gr_poly
		(pts
			(xy 338.612734 -239.24387) (xy 338.565744 -239.09147) (xy 338.304124 -239.09147) (xy 338.257134 -239.24387)
			(xy 338.257134 -239.288066) (xy 338.612734 -239.288066)
		)
		(stroke
			(width 0)
			(type solid)
		)
		(fill yes)
		(layer "In6.Cu")
		(net "M_C_CPU0_SB_DQ<10>")
	)
	(gr_poly
		(pts
			(xy 338.612734 -234.360466) (xy 338.565744 -234.208066) (xy 338.304124 -234.208066) (xy 338.257134 -234.360466)
			(xy 338.257134 -234.404916) (xy 338.612734 -234.404916)
		)
		(stroke
			(width 0)
			(type solid)
		)
		(fill yes)
		(layer "In6.Cu")
		(net "M_D_CPU0_SB_DQ<18>")
	)
	(gr_poly
		(pts
			(xy 338.612734 -229.477062) (xy 338.565744 -229.324662) (xy 338.304124 -229.324662) (xy 338.257134 -229.477062)
			(xy 338.257134 -229.521512) (xy 338.612734 -229.521512)
		)
		(stroke
			(width 0)
			(type solid)
		)
		(fill yes)
		(layer "In6.Cu")
		(net "M_D_CPU0_SB_DQ<23>")
	)
	(gr_poly
		(pts
			(xy 338.616544 -276.267926) (xy 338.57819 -276.245828) (xy 338.422742 -276.210268) (xy 338.291932 -276.436836)
			(xy 338.40039 -276.553676) (xy 338.438744 -276.575774)
		)
		(stroke
			(width 0)
			(type solid)
		)
		(fill yes)
		(layer "In6.Cu")
		(net "M_D_CPU0_SA_DQ<3>")
	)
	(gr_poly
		(pts
			(xy 338.61756 -277.89378) (xy 338.579206 -277.871682) (xy 338.423758 -277.836122) (xy 338.292948 -278.06269)
			(xy 338.401406 -278.17953) (xy 338.43976 -278.201628)
		)
		(stroke
			(width 0)
			(type solid)
		)
		(fill yes)
		(layer "In6.Cu")
		(net "M_D_CPU0_SA_DQ<2>")
	)
	(gr_poly
		(pts
			(xy 338.618576 -247.382538) (xy 338.571586 -247.230138) (xy 338.309966 -247.230138) (xy 338.262976 -247.382538)
			(xy 338.262976 -247.426734) (xy 338.618576 -247.426734)
		)
		(stroke
			(width 0)
			(type solid)
		)
		(fill yes)
		(layer "In6.Cu")
		(net "M_A_CPU0_SB_RSP<1>")
	)
	(gr_poly
		(pts
			(xy 338.618576 -245.754906) (xy 338.571586 -245.602506) (xy 338.309966 -245.602506) (xy 338.262976 -245.754906)
			(xy 338.262976 -245.799356) (xy 338.618576 -245.799356)
		)
		(stroke
			(width 0)
			(type solid)
		)
		(fill yes)
		(layer "In6.Cu")
		(net "M_D_CPU0_SB_CS_N<3>")
	)
	(gr_poly
		(pts
			(xy 338.618576 -240.871502) (xy 338.571586 -240.719102) (xy 338.309966 -240.719102) (xy 338.262976 -240.871502)
			(xy 338.262976 -240.915952) (xy 338.618576 -240.915952)
		)
		(stroke
			(width 0)
			(type solid)
		)
		(fill yes)
		(layer "In6.Cu")
		(net "M_C_CPU0_SB_DQ<6>")
	)
	(gr_poly
		(pts
			(xy 338.618576 -235.988098) (xy 338.571586 -235.835698) (xy 338.309966 -235.835698) (xy 338.262976 -235.988098)
			(xy 338.262976 -236.032548) (xy 338.618576 -236.032548)
		)
		(stroke
			(width 0)
			(type solid)
		)
		(fill yes)
		(layer "In6.Cu")
		(net "M_C_CPU0_SB_DQ<14>")
	)
	(gr_poly
		(pts
			(xy 338.618576 -226.221798) (xy 338.571586 -226.069398) (xy 338.309966 -226.069398) (xy 338.262976 -226.221798)
			(xy 338.262976 -226.265994) (xy 338.618576 -226.265994)
		)
		(stroke
			(width 0)
			(type solid)
		)
		(fill yes)
		(layer "In6.Cu")
		(net "M_C_CPU0_SB_DQS_DP<8>")
	)
	(gr_poly
		(pts
			(xy 338.618576 -225.812858) (xy 338.618576 -225.768662) (xy 338.262976 -225.768662) (xy 338.262976 -225.812858)
			(xy 338.309966 -225.965258) (xy 338.571586 -225.965258)
		)
		(stroke
			(width 0)
			(type solid)
		)
		(fill yes)
		(layer "In6.Cu")
		(net "M_C_CPU0_SB_DQ<28>")
	)
	(gr_poly
		(pts
			(xy 338.621116 -248.602246) (xy 338.621116 -248.557796) (xy 338.265516 -248.557796) (xy 338.265516 -248.602246)
			(xy 338.312506 -248.754646) (xy 338.574126 -248.754646)
		)
		(stroke
			(width 0)
			(type solid)
		)
		(fill yes)
		(layer "In6.Cu")
		(net "M_A_CPU0_SB_RSP<0>")
	)
	(gr_poly
		(pts
			(xy 338.621116 -242.090702) (xy 338.621116 -242.046506) (xy 338.265516 -242.046506) (xy 338.265516 -242.090702)
			(xy 338.312506 -242.243102) (xy 338.574126 -242.243102)
		)
		(stroke
			(width 0)
			(type solid)
		)
		(fill yes)
		(layer "In6.Cu")
		(net "M_C_CPU0_SB_DQS_DN<5>")
	)
	(gr_poly
		(pts
			(xy 338.621116 -238.835438) (xy 338.621116 -238.790988) (xy 338.265516 -238.790988) (xy 338.265516 -238.835438)
			(xy 338.312506 -238.987838) (xy 338.574126 -238.987838)
		)
		(stroke
			(width 0)
			(type solid)
		)
		(fill yes)
		(layer "In6.Cu")
		(net "M_C_CPU0_SB_DQ<9>")
	)
	(gr_poly
		(pts
			(xy 338.621116 -237.61573) (xy 338.574126 -237.46333) (xy 338.312506 -237.46333) (xy 338.265516 -237.61573)
			(xy 338.265516 -237.66018) (xy 338.621116 -237.66018)
		)
		(stroke
			(width 0)
			(type solid)
		)
		(fill yes)
		(layer "In6.Cu")
		(net "M_C_CPU0_SB_DQS_DN<1>")
	)
	(gr_poly
		(pts
			(xy 338.621116 -237.207806) (xy 338.621116 -237.163356) (xy 338.265516 -237.163356) (xy 338.265516 -237.207806)
			(xy 338.312506 -237.360206) (xy 338.574126 -237.360206)
		)
		(stroke
			(width 0)
			(type solid)
		)
		(fill yes)
		(layer "In6.Cu")
		(net "M_C_CPU0_SB_DQS_DN<6>")
	)
	(gr_poly
		(pts
			(xy 338.621116 -233.952034) (xy 338.621116 -233.907838) (xy 338.265516 -233.907838) (xy 338.265516 -233.952034)
			(xy 338.312506 -234.104434) (xy 338.574126 -234.104434)
		)
		(stroke
			(width 0)
			(type solid)
		)
		(fill yes)
		(layer "In6.Cu")
		(net "M_D_CPU0_SB_DQ<17>")
	)
	(gr_poly
		(pts
			(xy 338.621116 -232.732326) (xy 338.574126 -232.579926) (xy 338.312506 -232.579926) (xy 338.265516 -232.732326)
			(xy 338.265516 -232.776776) (xy 338.621116 -232.776776)
		)
		(stroke
			(width 0)
			(type solid)
		)
		(fill yes)
		(layer "In6.Cu")
		(net "M_D_CPU0_SB_DQS_DN<2>")
	)
	(gr_poly
		(pts
			(xy 338.621116 -232.324402) (xy 338.621116 -232.279952) (xy 338.265516 -232.279952) (xy 338.265516 -232.324402)
			(xy 338.312506 -232.476802) (xy 338.574126 -232.476802)
		)
		(stroke
			(width 0)
			(type solid)
		)
		(fill yes)
		(layer "In6.Cu")
		(net "M_D_CPU0_SB_DQS_DN<7>")
	)
	(gr_poly
		(pts
			(xy 338.621116 -229.06863) (xy 338.621116 -229.024434) (xy 338.265516 -229.024434) (xy 338.265516 -229.06863)
			(xy 338.312506 -229.22103) (xy 338.574126 -229.22103)
		)
		(stroke
			(width 0)
			(type solid)
		)
		(fill yes)
		(layer "In6.Cu")
		(net "M_C_CPU0_SB_DQ<26>")
	)
	(gr_poly
		(pts
			(xy 338.621116 -227.848922) (xy 338.574126 -227.696522) (xy 338.312506 -227.696522) (xy 338.265516 -227.848922)
			(xy 338.265516 -227.893372) (xy 338.621116 -227.893372)
		)
		(stroke
			(width 0)
			(type solid)
		)
		(fill yes)
		(layer "In6.Cu")
		(net "M_C_CPU0_SB_DQ<27>")
	)
	(gr_poly
		(pts
			(xy 338.621116 -227.440998) (xy 338.621116 -227.396548) (xy 338.265516 -227.396548) (xy 338.265516 -227.440998)
			(xy 338.312506 -227.593398) (xy 338.574126 -227.593398)
		)
		(stroke
			(width 0)
			(type solid)
		)
		(fill yes)
		(layer "In6.Cu")
		(net "M_C_CPU0_SB_DQS_DP<3>")
	)
	(gr_poly
		(pts
			(xy 338.691982 -224.65411) (xy 338.583524 -224.53727) (xy 338.54517 -224.515172) (xy 338.36737 -224.82302)
			(xy 338.405724 -224.845118) (xy 338.561172 -224.880678)
		)
		(stroke
			(width 0)
			(type solid)
		)
		(fill yes)
		(layer "In6.Cu")
		(net "M_C_CPU0_SB_DQ<31>")
	)
	(gr_poly
		(pts
			(xy 338.71408 -272.029174) (xy 338.66709 -271.876774) (xy 338.40547 -271.876774) (xy 338.35848 -272.029174)
			(xy 338.35848 -272.073624) (xy 338.71408 -272.073624)
		)
		(stroke
			(width 0)
			(type solid)
		)
		(fill yes)
		(layer "In6.Cu")
		(net "M_C_CPU0_SA_DQ<10>")
	)
	(gr_poly
		(pts
			(xy 338.71408 -267.14577) (xy 338.66709 -266.99337) (xy 338.40547 -266.99337) (xy 338.35848 -267.14577)
			(xy 338.35848 -267.19022) (xy 338.71408 -267.19022)
		)
		(stroke
			(width 0)
			(type solid)
		)
		(fill yes)
		(layer "In6.Cu")
		(net "M_C_CPU0_SA_DQ<26>")
	)
	(gr_poly
		(pts
			(xy 338.71408 -262.262874) (xy 338.66709 -262.110474) (xy 338.40547 -262.110474) (xy 338.35848 -262.262874)
			(xy 338.35848 -262.30707) (xy 338.71408 -262.30707)
		)
		(stroke
			(width 0)
			(type solid)
		)
		(fill yes)
		(layer "In6.Cu")
		(net "M_C_CPU0_SA_CB<0>")
	)
	(gr_poly
		(pts
			(xy 338.71662 -273.248882) (xy 338.71662 -273.204686) (xy 338.36102 -273.204686) (xy 338.36102 -273.248882)
			(xy 338.40801 -273.401282) (xy 338.66963 -273.401282)
		)
		(stroke
			(width 0)
			(type solid)
		)
		(fill yes)
		(layer "In6.Cu")
		(net "M_D_CPU0_SA_DQ<5>")
	)
	(gr_poly
		(pts
			(xy 338.71662 -268.365478) (xy 338.71662 -268.321282) (xy 338.36102 -268.321282) (xy 338.36102 -268.365478)
			(xy 338.40801 -268.517878) (xy 338.66963 -268.517878)
		)
		(stroke
			(width 0)
			(type solid)
		)
		(fill yes)
		(layer "In6.Cu")
		(net "M_C_CPU0_SA_DQ<13>")
	)
	(gr_poly
		(pts
			(xy 338.71662 -258.599178) (xy 338.71662 -258.554728) (xy 338.36102 -258.554728) (xy 338.36102 -258.599178)
			(xy 338.40801 -258.751578) (xy 338.66963 -258.751578)
		)
		(stroke
			(width 0)
			(type solid)
		)
		(fill yes)
		(layer "In6.Cu")
		(net "M_C_CPU0_SA_CB<7>")
	)
	(gr_poly
		(pts
			(xy 338.71916 -263.482074) (xy 338.71916 -263.437624) (xy 338.36356 -263.437624) (xy 338.36356 -263.482074)
			(xy 338.41055 -263.634474) (xy 338.67217 -263.634474)
		)
		(stroke
			(width 0)
			(type solid)
		)
		(fill yes)
		(layer "In6.Cu")
		(net "M_C_CPU0_SA_DQ<29>")
	)
	(gr_poly
		(pts
			(xy 338.722462 -271.620742) (xy 338.722462 -271.576546) (xy 338.366862 -271.576546) (xy 338.366862 -271.620742)
			(xy 338.413852 -271.773142) (xy 338.675472 -271.773142)
		)
		(stroke
			(width 0)
			(type solid)
		)
		(fill yes)
		(layer "In6.Cu")
		(net "M_C_CPU0_SA_DQ<9>")
	)
	(gr_poly
		(pts
			(xy 338.722462 -266.737846) (xy 338.722462 -266.693396) (xy 338.366862 -266.693396) (xy 338.366862 -266.737846)
			(xy 338.413852 -266.890246) (xy 338.675472 -266.890246)
		)
		(stroke
			(width 0)
			(type solid)
		)
		(fill yes)
		(layer "In6.Cu")
		(net "M_C_CPU0_SA_DQ<25>")
	)
	(gr_poly
		(pts
			(xy 338.722462 -261.854442) (xy 338.722462 -261.809992) (xy 338.366862 -261.809992) (xy 338.366862 -261.854442)
			(xy 338.413852 -262.006842) (xy 338.675472 -262.006842)
		)
		(stroke
			(width 0)
			(type solid)
		)
		(fill yes)
		(layer "In6.Cu")
		(net "M_C_CPU0_SA_CB<3>")
	)
	(gr_poly
		(pts
			(xy 338.722462 -256.971038) (xy 338.722462 -256.926588) (xy 338.366862 -256.926588) (xy 338.366862 -256.971038)
			(xy 338.413852 -257.123438) (xy 338.675472 -257.123438)
		)
		(stroke
			(width 0)
			(type solid)
		)
		(fill yes)
		(layer "In6.Cu")
		(net "M_D_CPU0_SA_RSP<0>")
	)
	(gr_poly
		(pts
			(xy 338.728558 -275.284946) (xy 338.681568 -275.132546) (xy 338.419948 -275.132546) (xy 338.372958 -275.284946)
			(xy 338.372958 -275.329142) (xy 338.728558 -275.329142)
		)
		(stroke
			(width 0)
			(type solid)
		)
		(fill yes)
		(layer "In6.Cu")
		(net "M_D_CPU0_SA_DQS_DN<0>")
	)
	(gr_poly
		(pts
			(xy 338.728558 -274.876514) (xy 338.728558 -274.832318) (xy 338.372958 -274.832318) (xy 338.372958 -274.876514)
			(xy 338.419948 -275.028914) (xy 338.681568 -275.028914)
		)
		(stroke
			(width 0)
			(type solid)
		)
		(fill yes)
		(layer "In6.Cu")
		(net "M_D_CPU0_SA_DQS_DN<5>")
	)
	(gr_poly
		(pts
			(xy 338.728558 -273.657314) (xy 338.681568 -273.504914) (xy 338.419948 -273.504914) (xy 338.372958 -273.657314)
			(xy 338.372958 -273.70151) (xy 338.728558 -273.70151)
		)
		(stroke
			(width 0)
			(type solid)
		)
		(fill yes)
		(layer "In6.Cu")
		(net "M_D_CPU0_SA_DQ<6>")
	)
	(gr_poly
		(pts
			(xy 338.728558 -270.401542) (xy 338.681568 -270.249142) (xy 338.419948 -270.249142) (xy 338.372958 -270.401542)
			(xy 338.372958 -270.445992) (xy 338.728558 -270.445992)
		)
		(stroke
			(width 0)
			(type solid)
		)
		(fill yes)
		(layer "In6.Cu")
		(net "M_C_CPU0_SA_DQS_DN<1>")
	)
	(gr_poly
		(pts
			(xy 338.728558 -269.993618) (xy 338.728558 -269.949168) (xy 338.372958 -269.949168) (xy 338.372958 -269.993618)
			(xy 338.419948 -270.146018) (xy 338.681568 -270.146018)
		)
		(stroke
			(width 0)
			(type solid)
		)
		(fill yes)
		(layer "In6.Cu")
		(net "M_C_CPU0_SA_DQS_DN<6>")
	)
	(gr_poly
		(pts
			(xy 338.728558 -268.77391) (xy 338.681568 -268.62151) (xy 338.419948 -268.62151) (xy 338.372958 -268.77391)
			(xy 338.372958 -268.818106) (xy 338.728558 -268.818106)
		)
		(stroke
			(width 0)
			(type solid)
		)
		(fill yes)
		(layer "In6.Cu")
		(net "M_C_CPU0_SA_DQ<14>")
	)
	(gr_poly
		(pts
			(xy 338.728558 -265.518138) (xy 338.681568 -265.365738) (xy 338.419948 -265.365738) (xy 338.372958 -265.518138)
			(xy 338.372958 -265.562588) (xy 338.728558 -265.562588)
		)
		(stroke
			(width 0)
			(type solid)
		)
		(fill yes)
		(layer "In6.Cu")
		(net "M_C_CPU0_SA_DQS_DN<3>")
	)
	(gr_poly
		(pts
			(xy 338.728558 -265.110214) (xy 338.728558 -265.065764) (xy 338.372958 -265.065764) (xy 338.372958 -265.110214)
			(xy 338.419948 -265.262614) (xy 338.681568 -265.262614)
		)
		(stroke
			(width 0)
			(type solid)
		)
		(fill yes)
		(layer "In6.Cu")
		(net "M_C_CPU0_SA_DQS_DN<8>")
	)
	(gr_poly
		(pts
			(xy 338.728558 -263.890506) (xy 338.681568 -263.738106) (xy 338.419948 -263.738106) (xy 338.372958 -263.890506)
			(xy 338.372958 -263.934956) (xy 338.728558 -263.934956)
		)
		(stroke
			(width 0)
			(type solid)
		)
		(fill yes)
		(layer "In6.Cu")
		(net "M_C_CPU0_SA_DQ<30>")
	)
	(gr_poly
		(pts
			(xy 338.728558 -259.007102) (xy 338.681568 -258.854702) (xy 338.419948 -258.854702) (xy 338.372958 -259.007102)
			(xy 338.372958 -259.051552) (xy 338.728558 -259.051552)
		)
		(stroke
			(width 0)
			(type solid)
		)
		(fill yes)
		(layer "In6.Cu")
		(net "M_C_CPU0_SA_CB<4>")
	)
	(gr_poly
		(pts
			(xy 338.728558 -255.751838) (xy 338.681568 -255.599438) (xy 338.419948 -255.599438) (xy 338.372958 -255.751838)
			(xy 338.372958 -255.796034) (xy 338.728558 -255.796034)
		)
		(stroke
			(width 0)
			(type solid)
		)
		(fill yes)
		(layer "In6.Cu")
		(net "M_D_CPU0_SB_RSP<1>")
	)
	(gr_poly
		(pts
			(xy 338.728558 -255.343406) (xy 338.728558 -255.29921) (xy 338.372958 -255.29921) (xy 338.372958 -255.343406)
			(xy 338.419948 -255.495806) (xy 338.681568 -255.495806)
		)
		(stroke
			(width 0)
			(type solid)
		)
		(fill yes)
		(layer "In6.Cu")
		(net "M_C_CPU0_SA_RSP<0>")
	)
	(gr_poly
		(pts
			(xy 338.728558 -254.123698) (xy 338.681568 -253.971298) (xy 338.419948 -253.971298) (xy 338.372958 -254.123698)
			(xy 338.372958 -254.168148) (xy 338.728558 -254.168148)
		)
		(stroke
			(width 0)
			(type solid)
		)
		(fill yes)
		(layer "In6.Cu")
		(net "M_C_CPU0_SB_RSP<1>")
	)
	(gr_poly
		(pts
			(xy 338.731098 -260.634734) (xy 338.684108 -260.482334) (xy 338.422488 -260.482334) (xy 338.375498 -260.634734)
			(xy 338.375498 -260.679184) (xy 338.731098 -260.679184)
		)
		(stroke
			(width 0)
			(type solid)
		)
		(fill yes)
		(layer "In6.Cu")
		(net "M_C_CPU0_SA_DQS_DP<9>")
	)
	(gr_poly
		(pts
			(xy 338.731098 -260.22681) (xy 338.731098 -260.18236) (xy 338.375498 -260.18236) (xy 338.375498 -260.22681)
			(xy 338.422488 -260.37921) (xy 338.684108 -260.37921)
		)
		(stroke
			(width 0)
			(type solid)
		)
		(fill yes)
		(layer "In6.Cu")
		(net "M_C_CPU0_SA_DQS_DP<4>")
	)
	(gr_poly
		(pts
			(xy 338.796376 -276.982936) (xy 338.687918 -276.866096) (xy 338.649564 -276.843998) (xy 338.471764 -277.151846)
			(xy 338.510118 -277.173944) (xy 338.665566 -277.209504)
		)
		(stroke
			(width 0)
			(type solid)
		)
		(fill yes)
		(layer "In6.Cu")
		(net "M_D_CPU0_SA_DQ<1>")
	)
	(gr_poly
		(pts
			(xy 338.797392 -278.608282) (xy 338.688934 -278.491442) (xy 338.65058 -278.469344) (xy 338.47278 -278.777192)
			(xy 338.511134 -278.79929) (xy 338.666582 -278.83485)
		)
		(stroke
			(width 0)
			(type solid)
		)
		(fill yes)
		(layer "In6.Cu")
		(net "M_D_CPU0_SA_DQ<0>")
	)
	(gr_poly
		(pts
			(xy 338.938108 -230.54945) (xy 338.976462 -230.527352) (xy 338.798662 -230.219504) (xy 338.760308 -230.241602)
			(xy 338.65185 -230.358442) (xy 338.78266 -230.58501)
		)
		(stroke
			(width 0)
			(type solid)
		)
		(fill yes)
		(layer "In6.Cu")
		(net "M_D_CPU0_SB_DQ<21>")
	)
	(gr_poly
		(pts
			(xy 339.049106 -229.931722) (xy 339.157564 -229.814882) (xy 339.026754 -229.588314) (xy 338.871306 -229.623874)
			(xy 338.832952 -229.645972) (xy 339.010752 -229.95382)
		)
		(stroke
			(width 0)
			(type solid)
		)
		(fill yes)
		(layer "In6.Cu")
		(net "M_D_CPU0_SB_DQ<23>")
	)
	(gr_poly
		(pts
			(xy 339.073998 -241.685318) (xy 339.027008 -241.532918) (xy 338.765388 -241.532918) (xy 338.718398 -241.685318)
			(xy 338.718398 -241.729514) (xy 339.073998 -241.729514)
		)
		(stroke
			(width 0)
			(type solid)
		)
		(fill yes)
		(layer "In6.Cu")
		(net "M_C_CPU0_SB_DQS_DP<5>")
	)
	(gr_poly
		(pts
			(xy 339.073998 -236.801914) (xy 339.027008 -236.649514) (xy 338.765388 -236.649514) (xy 338.718398 -236.801914)
			(xy 338.718398 -236.84611) (xy 339.073998 -236.84611)
		)
		(stroke
			(width 0)
			(type solid)
		)
		(fill yes)
		(layer "In6.Cu")
		(net "M_C_CPU0_SB_DQS_DP<6>")
	)
	(gr_poly
		(pts
			(xy 339.073998 -231.91851) (xy 339.027008 -231.76611) (xy 338.765388 -231.76611) (xy 338.718398 -231.91851)
			(xy 338.718398 -231.96296) (xy 339.073998 -231.96296)
		)
		(stroke
			(width 0)
			(type solid)
		)
		(fill yes)
		(layer "In6.Cu")
		(net "M_D_CPU0_SB_DQS_DP<7>")
	)
	(gr_poly
		(pts
			(xy 339.076538 -248.196354) (xy 339.029548 -248.043954) (xy 338.767928 -248.043954) (xy 338.720938 -248.196354)
			(xy 338.720938 -248.24055) (xy 339.076538 -248.24055)
		)
		(stroke
			(width 0)
			(type solid)
		)
		(fill yes)
		(layer "In6.Cu")
		(net "M_A_CPU0_SA_RSP<0>")
	)
	(gr_poly
		(pts
			(xy 339.076538 -247.787922) (xy 339.076538 -247.743726) (xy 338.720938 -247.743726) (xy 338.720938 -247.787922)
			(xy 338.767928 -247.940322) (xy 339.029548 -247.940322)
		)
		(stroke
			(width 0)
			(type solid)
		)
		(fill yes)
		(layer "In6.Cu")
		(net "M_A_CPU0_SA_RSP<1>")
	)
	(gr_poly
		(pts
			(xy 339.076538 -244.53215) (xy 339.076538 -244.487954) (xy 338.720938 -244.487954) (xy 338.720938 -244.53215)
			(xy 338.767928 -244.68455) (xy 339.029548 -244.68455)
		)
		(stroke
			(width 0)
			(type solid)
		)
		(fill yes)
		(layer "In6.Cu")
		(net "M_C_CPU0_SB_DQ<0>")
	)
	(gr_poly
		(pts
			(xy 339.076538 -242.905026) (xy 339.076538 -242.860576) (xy 338.720938 -242.860576) (xy 338.720938 -242.905026)
			(xy 338.767928 -243.057426) (xy 339.029548 -243.057426)
		)
		(stroke
			(width 0)
			(type solid)
		)
		(fill yes)
		(layer "In6.Cu")
		(net "M_C_CPU0_SB_DQS_DP<0>")
	)
	(gr_poly
		(pts
			(xy 339.076538 -239.648746) (xy 339.076538 -239.60455) (xy 338.720938 -239.60455) (xy 338.720938 -239.648746)
			(xy 338.767928 -239.801146) (xy 339.029548 -239.801146)
		)
		(stroke
			(width 0)
			(type solid)
		)
		(fill yes)
		(layer "In6.Cu")
		(net "M_C_CPU0_SB_DQ<8>")
	)
	(gr_poly
		(pts
			(xy 339.076538 -238.429546) (xy 339.029548 -238.277146) (xy 338.767928 -238.277146) (xy 338.720938 -238.429546)
			(xy 338.720938 -238.473996) (xy 339.076538 -238.473996)
		)
		(stroke
			(width 0)
			(type solid)
		)
		(fill yes)
		(layer "In6.Cu")
		(net "M_C_CPU0_SB_DQ<11>")
	)
	(gr_poly
		(pts
			(xy 339.076538 -238.021622) (xy 339.076538 -237.977172) (xy 338.720938 -237.977172) (xy 338.720938 -238.021622)
			(xy 338.767928 -238.174022) (xy 339.029548 -238.174022)
		)
		(stroke
			(width 0)
			(type solid)
		)
		(fill yes)
		(layer "In6.Cu")
		(net "M_C_CPU0_SB_DQS_DP<1>")
	)
	(gr_poly
		(pts
			(xy 339.076538 -234.76585) (xy 339.076538 -234.7214) (xy 338.720938 -234.7214) (xy 338.720938 -234.76585)
			(xy 338.767928 -234.91825) (xy 339.029548 -234.91825)
		)
		(stroke
			(width 0)
			(type solid)
		)
		(fill yes)
		(layer "In6.Cu")
		(net "M_D_CPU0_SB_DQ<16>")
	)
	(gr_poly
		(pts
			(xy 339.076538 -233.546142) (xy 339.029548 -233.393742) (xy 338.767928 -233.393742) (xy 338.720938 -233.546142)
			(xy 338.720938 -233.590592) (xy 339.076538 -233.590592)
		)
		(stroke
			(width 0)
			(type solid)
		)
		(fill yes)
		(layer "In6.Cu")
		(net "M_D_CPU0_SB_DQ<19>")
	)
	(gr_poly
		(pts
			(xy 339.076538 -233.138218) (xy 339.076538 -233.093768) (xy 338.720938 -233.093768) (xy 338.720938 -233.138218)
			(xy 338.767928 -233.290618) (xy 339.029548 -233.290618)
		)
		(stroke
			(width 0)
			(type solid)
		)
		(fill yes)
		(layer "In6.Cu")
		(net "M_D_CPU0_SB_DQS_DP<2>")
	)
	(gr_poly
		(pts
			(xy 339.076538 -228.663246) (xy 339.029548 -228.510846) (xy 338.767928 -228.510846) (xy 338.720938 -228.663246)
			(xy 338.720938 -228.707442) (xy 339.076538 -228.707442)
		)
		(stroke
			(width 0)
			(type solid)
		)
		(fill yes)
		(layer "In6.Cu")
		(net "M_C_CPU0_SB_DQ<24>")
	)
	(gr_poly
		(pts
			(xy 339.076538 -228.254814) (xy 339.076538 -228.210618) (xy 338.720938 -228.210618) (xy 338.720938 -228.254814)
			(xy 338.767928 -228.407214) (xy 339.029548 -228.407214)
		)
		(stroke
			(width 0)
			(type solid)
		)
		(fill yes)
		(layer "In6.Cu")
		(net "M_C_CPU0_SB_DQ<25>")
	)
	(gr_poly
		(pts
			(xy 339.076538 -227.035106) (xy 339.029548 -226.882706) (xy 338.767928 -226.882706) (xy 338.720938 -227.035106)
			(xy 338.720938 -227.079556) (xy 339.076538 -227.079556)
		)
		(stroke
			(width 0)
			(type solid)
		)
		(fill yes)
		(layer "In6.Cu")
		(net "M_C_CPU0_SB_DQS_DN<3>")
	)
	(gr_poly
		(pts
			(xy 339.08238 -246.16029) (xy 339.08238 -246.11584) (xy 338.72678 -246.11584) (xy 338.72678 -246.16029)
			(xy 338.77377 -246.31269) (xy 339.03539 -246.31269)
		)
		(stroke
			(width 0)
			(type solid)
		)
		(fill yes)
		(layer "In6.Cu")
		(net "M_D_CPU0_SB_CS_N<2>")
	)
	(gr_poly
		(pts
			(xy 339.08238 -241.276886) (xy 339.08238 -241.232436) (xy 338.72678 -241.232436) (xy 338.72678 -241.276886)
			(xy 338.77377 -241.429286) (xy 339.03539 -241.429286)
		)
		(stroke
			(width 0)
			(type solid)
		)
		(fill yes)
		(layer "In6.Cu")
		(net "M_C_CPU0_SB_DQ<4>")
	)
	(gr_poly
		(pts
			(xy 339.08238 -236.393482) (xy 339.08238 -236.349286) (xy 338.72678 -236.349286) (xy 338.72678 -236.393482)
			(xy 338.77377 -236.545882) (xy 339.03539 -236.545882)
		)
		(stroke
			(width 0)
			(type solid)
		)
		(fill yes)
		(layer "In6.Cu")
		(net "M_C_CPU0_SB_DQ<12>")
	)
	(gr_poly
		(pts
			(xy 339.08238 -231.510078) (xy 339.08238 -231.465882) (xy 338.72678 -231.465882) (xy 338.72678 -231.510078)
			(xy 338.77377 -231.662478) (xy 339.03539 -231.662478)
		)
		(stroke
			(width 0)
			(type solid)
		)
		(fill yes)
		(layer "In6.Cu")
		(net "M_D_CPU0_SB_DQ<20>")
	)
	(gr_poly
		(pts
			(xy 339.08238 -225.407474) (xy 339.03539 -225.255074) (xy 338.77377 -225.255074) (xy 338.72678 -225.407474)
			(xy 338.72678 -225.451924) (xy 339.08238 -225.451924)
		)
		(stroke
			(width 0)
			(type solid)
		)
		(fill yes)
		(layer "In6.Cu")
		(net "M_C_CPU0_SB_DQ<30>")
	)
	(gr_poly
		(pts
			(xy 339.085936 -243.313458) (xy 339.038946 -243.161058) (xy 338.777326 -243.161058) (xy 338.730336 -243.313458)
			(xy 338.730336 -243.357654) (xy 339.085936 -243.357654)
		)
		(stroke
			(width 0)
			(type solid)
		)
		(fill yes)
		(layer "In6.Cu")
		(net "M_C_CPU0_SB_DQ<3>")
	)
	(gr_poly
		(pts
			(xy 339.086444 -277.081742) (xy 339.04809 -277.059644) (xy 338.892642 -277.024084) (xy 338.761832 -277.250652)
			(xy 338.87029 -277.367492) (xy 338.908644 -277.38959)
		)
		(stroke
			(width 0)
			(type solid)
		)
		(fill yes)
		(layer "In6.Cu")
		(net "M_D_CPU0_SA_DQ<2>")
	)
	(gr_poly
		(pts
			(xy 339.088476 -244.94109) (xy 339.041486 -244.78869) (xy 338.779866 -244.78869) (xy 338.732876 -244.94109)
			(xy 338.732876 -244.985286) (xy 339.088476 -244.985286)
		)
		(stroke
			(width 0)
			(type solid)
		)
		(fill yes)
		(layer "In6.Cu")
		(net "M_D_CPU0_SB_CS_N<1>")
	)
	(gr_poly
		(pts
			(xy 339.088476 -240.057686) (xy 339.041486 -239.905286) (xy 338.779866 -239.905286) (xy 338.732876 -240.057686)
			(xy 338.732876 -240.101882) (xy 339.088476 -240.101882)
		)
		(stroke
			(width 0)
			(type solid)
		)
		(fill yes)
		(layer "In6.Cu")
		(net "M_C_CPU0_SB_DQ<7>")
	)
	(gr_poly
		(pts
			(xy 339.088476 -235.174282) (xy 339.041486 -235.021882) (xy 338.779866 -235.021882) (xy 338.732876 -235.174282)
			(xy 338.732876 -235.218732) (xy 339.088476 -235.218732)
		)
		(stroke
			(width 0)
			(type solid)
		)
		(fill yes)
		(layer "In6.Cu")
		(net "M_C_CPU0_SB_DQ<15>")
	)
	(gr_poly
		(pts
			(xy 339.088476 -226.627182) (xy 339.088476 -226.582732) (xy 338.732876 -226.582732) (xy 338.732876 -226.627182)
			(xy 338.779866 -226.779582) (xy 339.041486 -226.779582)
		)
		(stroke
			(width 0)
			(type solid)
		)
		(fill yes)
		(layer "In6.Cu")
		(net "M_C_CPU0_SB_DQS_DN<8>")
	)
	(gr_poly
		(pts
			(xy 339.18398 -275.690584) (xy 339.18398 -275.646134) (xy 338.82838 -275.646134) (xy 338.82838 -275.690584)
			(xy 338.87537 -275.842984) (xy 339.13699 -275.842984)
		)
		(stroke
			(width 0)
			(type solid)
		)
		(fill yes)
		(layer "In6.Cu")
		(net "M_D_CPU0_SA_DQS_DP<0>")
	)
	(gr_poly
		(pts
			(xy 339.18398 -270.807434) (xy 339.18398 -270.762984) (xy 338.82838 -270.762984) (xy 338.82838 -270.807434)
			(xy 338.87537 -270.959834) (xy 339.13699 -270.959834)
		)
		(stroke
			(width 0)
			(type solid)
		)
		(fill yes)
		(layer "In6.Cu")
		(net "M_C_CPU0_SA_DQS_DP<1>")
	)
	(gr_poly
		(pts
			(xy 339.18398 -265.92403) (xy 339.18398 -265.87958) (xy 338.82838 -265.87958) (xy 338.82838 -265.92403)
			(xy 338.87537 -266.07643) (xy 339.13699 -266.07643)
		)
		(stroke
			(width 0)
			(type solid)
		)
		(fill yes)
		(layer "In6.Cu")
		(net "M_C_CPU0_SA_DQS_DP<3>")
	)
	(gr_poly
		(pts
			(xy 339.18398 -261.040626) (xy 339.18398 -260.99643) (xy 338.82838 -260.99643) (xy 338.82838 -261.040626)
			(xy 338.87537 -261.193026) (xy 339.13699 -261.193026)
		)
		(stroke
			(width 0)
			(type solid)
		)
		(fill yes)
		(layer "In6.Cu")
		(net "M_C_CPU0_SA_DQS_DN<9>")
	)
	(gr_poly
		(pts
			(xy 339.18398 -256.157222) (xy 339.18398 -256.113026) (xy 338.82838 -256.113026) (xy 338.82838 -256.157222)
			(xy 338.87537 -256.309622) (xy 339.13699 -256.309622)
		)
		(stroke
			(width 0)
			(type solid)
		)
		(fill yes)
		(layer "In6.Cu")
		(net "M_D_CPU0_SA_RSP<1>")
	)
	(gr_poly
		(pts
			(xy 339.18652 -274.47113) (xy 339.13953 -274.31873) (xy 338.87791 -274.31873) (xy 338.83092 -274.47113)
			(xy 338.83092 -274.515326) (xy 339.18652 -274.515326)
		)
		(stroke
			(width 0)
			(type solid)
		)
		(fill yes)
		(layer "In6.Cu")
		(net "M_D_CPU0_SA_DQS_DP<5>")
	)
	(gr_poly
		(pts
			(xy 339.18652 -274.062698) (xy 339.18652 -274.018502) (xy 338.83092 -274.018502) (xy 338.83092 -274.062698)
			(xy 338.87791 -274.215098) (xy 339.13953 -274.215098)
		)
		(stroke
			(width 0)
			(type solid)
		)
		(fill yes)
		(layer "In6.Cu")
		(net "M_D_CPU0_SA_DQ<4>")
	)
	(gr_poly
		(pts
			(xy 339.18652 -272.843498) (xy 339.13953 -272.691098) (xy 338.87791 -272.691098) (xy 338.83092 -272.843498)
			(xy 338.83092 -272.887948) (xy 339.18652 -272.887948)
		)
		(stroke
			(width 0)
			(type solid)
		)
		(fill yes)
		(layer "In6.Cu")
		(net "M_D_CPU0_SA_DQ<7>")
	)
	(gr_poly
		(pts
			(xy 339.18652 -269.587726) (xy 339.13953 -269.435326) (xy 338.87791 -269.435326) (xy 338.83092 -269.587726)
			(xy 338.83092 -269.631922) (xy 339.18652 -269.631922)
		)
		(stroke
			(width 0)
			(type solid)
		)
		(fill yes)
		(layer "In6.Cu")
		(net "M_C_CPU0_SA_DQS_DP<6>")
	)
	(gr_poly
		(pts
			(xy 339.18652 -269.179294) (xy 339.18652 -269.135098) (xy 338.83092 -269.135098) (xy 338.83092 -269.179294)
			(xy 338.87791 -269.331694) (xy 339.13953 -269.331694)
		)
		(stroke
			(width 0)
			(type solid)
		)
		(fill yes)
		(layer "In6.Cu")
		(net "M_C_CPU0_SA_DQ<12>")
	)
	(gr_poly
		(pts
			(xy 339.18652 -267.960094) (xy 339.13953 -267.807694) (xy 338.87791 -267.807694) (xy 338.83092 -267.960094)
			(xy 338.83092 -268.004544) (xy 339.18652 -268.004544)
		)
		(stroke
			(width 0)
			(type solid)
		)
		(fill yes)
		(layer "In6.Cu")
		(net "M_C_CPU0_SA_DQ<15>")
	)
	(gr_poly
		(pts
			(xy 339.18652 -264.704322) (xy 339.13953 -264.551922) (xy 338.87791 -264.551922) (xy 338.83092 -264.704322)
			(xy 338.83092 -264.748772) (xy 339.18652 -264.748772)
		)
		(stroke
			(width 0)
			(type solid)
		)
		(fill yes)
		(layer "In6.Cu")
		(net "M_C_CPU0_SA_DQS_DP<8>")
	)
	(gr_poly
		(pts
			(xy 339.18652 -264.296398) (xy 339.18652 -264.251948) (xy 338.83092 -264.251948) (xy 338.83092 -264.296398)
			(xy 338.87791 -264.448798) (xy 339.13953 -264.448798)
		)
		(stroke
			(width 0)
			(type solid)
		)
		(fill yes)
		(layer "In6.Cu")
		(net "M_C_CPU0_SA_DQ<28>")
	)
	(gr_poly
		(pts
			(xy 339.18652 -259.820918) (xy 339.13953 -259.668518) (xy 338.87791 -259.668518) (xy 338.83092 -259.820918)
			(xy 338.83092 -259.865368) (xy 339.18652 -259.865368)
		)
		(stroke
			(width 0)
			(type solid)
		)
		(fill yes)
		(layer "In6.Cu")
		(net "M_C_CPU0_SA_DQS_DN<4>")
	)
	(gr_poly
		(pts
			(xy 339.18652 -259.412994) (xy 339.18652 -259.368544) (xy 338.83092 -259.368544) (xy 338.83092 -259.412994)
			(xy 338.87791 -259.565394) (xy 339.13953 -259.565394)
		)
		(stroke
			(width 0)
			(type solid)
		)
		(fill yes)
		(layer "In6.Cu")
		(net "M_C_CPU0_SA_CB<6>")
	)
	(gr_poly
		(pts
			(xy 339.18652 -258.193286) (xy 339.13953 -258.040886) (xy 338.87791 -258.040886) (xy 338.83092 -258.193286)
			(xy 338.83092 -258.237736) (xy 339.18652 -258.237736)
		)
		(stroke
			(width 0)
			(type solid)
		)
		(fill yes)
		(layer "In6.Cu")
		(net "M_C_CPU0_SA_CB<5>")
	)
	(gr_poly
		(pts
			(xy 339.18652 -254.937514) (xy 339.13953 -254.785114) (xy 338.87791 -254.785114) (xy 338.83092 -254.937514)
			(xy 338.83092 -254.981964) (xy 339.18652 -254.981964)
		)
		(stroke
			(width 0)
			(type solid)
		)
		(fill yes)
		(layer "In6.Cu")
		(net "M_C_CPU0_SB_RSP<0>")
	)
	(gr_poly
		(pts
			(xy 339.18652 -254.52959) (xy 339.18652 -254.48514) (xy 338.83092 -254.48514) (xy 338.83092 -254.52959)
			(xy 338.87791 -254.68199) (xy 339.13953 -254.68199)
		)
		(stroke
			(width 0)
			(type solid)
		)
		(fill yes)
		(layer "In6.Cu")
		(net "M_C_CPU0_SA_RSP<1>")
	)
	(gr_poly
		(pts
			(xy 339.192362 -276.09927) (xy 339.145372 -275.94687) (xy 338.883752 -275.94687) (xy 338.836762 -276.09927)
			(xy 338.836762 -276.143466) (xy 339.192362 -276.143466)
		)
		(stroke
			(width 0)
			(type solid)
		)
		(fill yes)
		(layer "In6.Cu")
		(net "M_D_CPU0_SA_DQ<3>")
	)
	(gr_poly
		(pts
			(xy 339.192362 -271.215866) (xy 339.145372 -271.063466) (xy 338.883752 -271.063466) (xy 338.836762 -271.215866)
			(xy 338.836762 -271.260062) (xy 339.192362 -271.260062)
		)
		(stroke
			(width 0)
			(type solid)
		)
		(fill yes)
		(layer "In6.Cu")
		(net "M_C_CPU0_SA_DQ<11>")
	)
	(gr_poly
		(pts
			(xy 339.192362 -266.332462) (xy 339.145372 -266.180062) (xy 338.883752 -266.180062) (xy 338.836762 -266.332462)
			(xy 338.836762 -266.376658) (xy 339.192362 -266.376658)
		)
		(stroke
			(width 0)
			(type solid)
		)
		(fill yes)
		(layer "In6.Cu")
		(net "M_C_CPU0_SA_DQ<27>")
	)
	(gr_poly
		(pts
			(xy 339.192362 -261.449058) (xy 339.145372 -261.296658) (xy 338.883752 -261.296658) (xy 338.836762 -261.449058)
			(xy 338.836762 -261.493508) (xy 339.192362 -261.493508)
		)
		(stroke
			(width 0)
			(type solid)
		)
		(fill yes)
		(layer "In6.Cu")
		(net "M_C_CPU0_SA_CB<1>")
	)
	(gr_poly
		(pts
			(xy 339.192362 -256.565654) (xy 339.145372 -256.413254) (xy 338.883752 -256.413254) (xy 338.836762 -256.565654)
			(xy 338.836762 -256.610104) (xy 339.192362 -256.610104)
		)
		(stroke
			(width 0)
			(type solid)
		)
		(fill yes)
		(layer "In6.Cu")
		(net "M_D_CPU0_SB_RSP<0>")
	)
	(gr_poly
		(pts
			(xy 339.195918 -263.077198) (xy 339.148928 -262.924798) (xy 338.887308 -262.924798) (xy 338.840318 -263.077198)
			(xy 338.840318 -263.121394) (xy 339.195918 -263.121394)
		)
		(stroke
			(width 0)
			(type solid)
		)
		(fill yes)
		(layer "In6.Cu")
		(net "M_C_CPU0_SA_DQ<31>")
	)
	(gr_poly
		(pts
			(xy 339.198458 -272.435066) (xy 339.198458 -272.390616) (xy 338.842858 -272.390616) (xy 338.842858 -272.435066)
			(xy 338.889848 -272.587466) (xy 339.151468 -272.587466)
		)
		(stroke
			(width 0)
			(type solid)
		)
		(fill yes)
		(layer "In6.Cu")
		(net "M_C_CPU0_SA_DQ<8>")
	)
	(gr_poly
		(pts
			(xy 339.198458 -267.551662) (xy 339.198458 -267.507212) (xy 338.842858 -267.507212) (xy 338.842858 -267.551662)
			(xy 338.889848 -267.704062) (xy 339.151468 -267.704062)
		)
		(stroke
			(width 0)
			(type solid)
		)
		(fill yes)
		(layer "In6.Cu")
		(net "M_C_CPU0_SA_DQ<24>")
	)
	(gr_poly
		(pts
			(xy 339.198458 -262.668258) (xy 339.198458 -262.623808) (xy 338.842858 -262.623808) (xy 338.842858 -262.668258)
			(xy 338.889848 -262.820658) (xy 339.151468 -262.820658)
		)
		(stroke
			(width 0)
			(type solid)
		)
		(fill yes)
		(layer "In6.Cu")
		(net "M_C_CPU0_SA_CB<2>")
	)
	(gr_poly
		(pts
			(xy 339.26653 -277.796244) (xy 339.158072 -277.679404) (xy 339.119718 -277.657306) (xy 338.941918 -277.965154)
			(xy 338.980272 -277.987252) (xy 339.13572 -278.022812)
		)
		(stroke
			(width 0)
			(type solid)
		)
		(fill yes)
		(layer "In6.Cu")
		(net "M_D_CPU0_SA_DQ<0>")
	)
	(gr_poly
		(pts
			(xy 339.408008 -224.85223) (xy 339.446362 -224.830132) (xy 339.268562 -224.522284) (xy 339.230208 -224.544382)
			(xy 339.12175 -224.661222) (xy 339.25256 -224.88779)
		)
		(stroke
			(width 0)
			(type solid)
		)
		(fill yes)
		(layer "In6.Cu")
		(net "M_C_CPU0_SB_DQ<31>")
	)
	(gr_poly
		(pts
			(xy 339.409278 -229.738174) (xy 339.447632 -229.716076) (xy 339.269832 -229.408228) (xy 339.231478 -229.430326)
			(xy 339.12302 -229.547166) (xy 339.25383 -229.773734)
		)
		(stroke
			(width 0)
			(type solid)
		)
		(fill yes)
		(layer "In6.Cu")
		(net "M_C_CPU0_SB_DQ<26>")
	)
	(gr_poly
		(pts
			(xy 339.519006 -229.117906) (xy 339.627464 -229.001066) (xy 339.496654 -228.774498) (xy 339.341206 -228.810058)
			(xy 339.302852 -228.832156) (xy 339.480652 -229.140004)
		)
		(stroke
			(width 0)
			(type solid)
		)
		(fill yes)
		(layer "In6.Cu")
		(net "M_C_CPU0_SB_DQ<24>")
	)
	(gr_poly
		(pts
			(xy 339.519006 -224.234502) (xy 339.627464 -224.117662) (xy 339.496654 -223.891094) (xy 339.341206 -223.926654)
			(xy 339.302852 -223.948752) (xy 339.480652 -224.2566)
		)
		(stroke
			(width 0)
			(type solid)
		)
		(fill yes)
		(layer "In6.Cu")
		(net "M_C_CPU0_SB_DQ<29>")
	)
	(gr_poly
		(pts
			(xy 339.546438 -247.382538) (xy 339.499448 -247.230138) (xy 339.237828 -247.230138) (xy 339.190838 -247.382538)
			(xy 339.190838 -247.426988) (xy 339.546438 -247.426988)
		)
		(stroke
			(width 0)
			(type solid)
		)
		(fill yes)
		(layer "In6.Cu")
		(net "M_A_CPU0_SB_RSP<1>")
	)
	(gr_poly
		(pts
			(xy 339.546438 -237.616238) (xy 339.499448 -237.463838) (xy 339.237828 -237.463838) (xy 339.190838 -237.616238)
			(xy 339.190838 -237.660434) (xy 339.546438 -237.660434)
		)
		(stroke
			(width 0)
			(type solid)
		)
		(fill yes)
		(layer "In6.Cu")
		(net "M_C_CPU0_SB_DQS_DN<1>")
	)
	(gr_poly
		(pts
			(xy 339.546438 -232.732834) (xy 339.499448 -232.580434) (xy 339.237828 -232.580434) (xy 339.190838 -232.732834)
			(xy 339.190838 -232.77703) (xy 339.546438 -232.77703)
		)
		(stroke
			(width 0)
			(type solid)
		)
		(fill yes)
		(layer "In6.Cu")
		(net "M_D_CPU0_SB_DQS_DN<2>")
	)
	(gr_poly
		(pts
			(xy 339.546438 -227.84943) (xy 339.499448 -227.69703) (xy 339.237828 -227.69703) (xy 339.190838 -227.84943)
			(xy 339.190838 -227.893626) (xy 339.546438 -227.893626)
		)
		(stroke
			(width 0)
			(type solid)
		)
		(fill yes)
		(layer "In6.Cu")
		(net "M_C_CPU0_SB_DQ<27>")
	)
	(gr_poly
		(pts
			(xy 339.546438 -227.44049) (xy 339.546438 -227.396294) (xy 339.190838 -227.396294) (xy 339.190838 -227.44049)
			(xy 339.237828 -227.59289) (xy 339.499448 -227.59289)
		)
		(stroke
			(width 0)
			(type solid)
		)
		(fill yes)
		(layer "In6.Cu")
		(net "M_C_CPU0_SB_DQS_DP<3>")
	)
	(gr_poly
		(pts
			(xy 339.546438 -226.22129) (xy 339.499448 -226.06889) (xy 339.237828 -226.06889) (xy 339.190838 -226.22129)
			(xy 339.190838 -226.26574) (xy 339.546438 -226.26574)
		)
		(stroke
			(width 0)
			(type solid)
		)
		(fill yes)
		(layer "In6.Cu")
		(net "M_C_CPU0_SB_DQS_DP<8>")
	)
	(gr_poly
		(pts
			(xy 339.548978 -243.718334) (xy 339.548978 -243.674138) (xy 339.193378 -243.674138) (xy 339.193378 -243.718334)
			(xy 339.240368 -243.870734) (xy 339.501988 -243.870734)
		)
		(stroke
			(width 0)
			(type solid)
		)
		(fill yes)
		(layer "In6.Cu")
		(net "M_C_CPU0_SB_DQ<1>")
	)
	(gr_poly
		(pts
			(xy 339.55228 -242.499642) (xy 339.50529 -242.347242) (xy 339.24367 -242.347242) (xy 339.19668 -242.499642)
			(xy 339.19668 -242.543838) (xy 339.55228 -242.543838)
		)
		(stroke
			(width 0)
			(type solid)
		)
		(fill yes)
		(layer "In6.Cu")
		(net "M_C_CPU0_SB_DQS_DN<0>")
	)
	(gr_poly
		(pts
			(xy 339.552534 -248.601738) (xy 339.552534 -248.557542) (xy 339.196934 -248.557542) (xy 339.196934 -248.601738)
			(xy 339.243924 -248.754138) (xy 339.505544 -248.754138)
		)
		(stroke
			(width 0)
			(type solid)
		)
		(fill yes)
		(layer "In6.Cu")
		(net "M_A_CPU0_SB_RSP<0>")
	)
	(gr_poly
		(pts
			(xy 339.552534 -238.83493) (xy 339.552534 -238.790734) (xy 339.196934 -238.790734) (xy 339.196934 -238.83493)
			(xy 339.243924 -238.98733) (xy 339.505544 -238.98733)
		)
		(stroke
			(width 0)
			(type solid)
		)
		(fill yes)
		(layer "In6.Cu")
		(net "M_C_CPU0_SB_DQ<9>")
	)
	(gr_poly
		(pts
			(xy 339.552534 -233.952034) (xy 339.552534 -233.907584) (xy 339.196934 -233.907584) (xy 339.196934 -233.952034)
			(xy 339.243924 -234.104434) (xy 339.505544 -234.104434)
		)
		(stroke
			(width 0)
			(type solid)
		)
		(fill yes)
		(layer "In6.Cu")
		(net "M_D_CPU0_SB_DQ<17>")
	)
	(gr_poly
		(pts
			(xy 339.558376 -245.754906) (xy 339.511386 -245.602506) (xy 339.249766 -245.602506) (xy 339.202776 -245.754906)
			(xy 339.202776 -245.799102) (xy 339.558376 -245.799102)
		)
		(stroke
			(width 0)
			(type solid)
		)
		(fill yes)
		(layer "In6.Cu")
		(net "M_D_CPU0_SB_CS_N<3>")
	)
	(gr_poly
		(pts
			(xy 339.558376 -245.346474) (xy 339.558376 -245.302278) (xy 339.202776 -245.302278) (xy 339.202776 -245.346474)
			(xy 339.249766 -245.498874) (xy 339.511386 -245.498874)
		)
		(stroke
			(width 0)
			(type solid)
		)
		(fill yes)
		(layer "In6.Cu")
		(net "M_D_CPU0_SB_CS_N<0>")
	)
	(gr_poly
		(pts
			(xy 339.558376 -240.871502) (xy 339.511386 -240.719102) (xy 339.249766 -240.719102) (xy 339.202776 -240.871502)
			(xy 339.202776 -240.915698) (xy 339.558376 -240.915698)
		)
		(stroke
			(width 0)
			(type solid)
		)
		(fill yes)
		(layer "In6.Cu")
		(net "M_C_CPU0_SB_DQ<6>")
	)
	(gr_poly
		(pts
			(xy 339.558376 -240.46307) (xy 339.558376 -240.418874) (xy 339.202776 -240.418874) (xy 339.202776 -240.46307)
			(xy 339.249766 -240.61547) (xy 339.511386 -240.61547)
		)
		(stroke
			(width 0)
			(type solid)
		)
		(fill yes)
		(layer "In6.Cu")
		(net "M_C_CPU0_SB_DQ<5>")
	)
	(gr_poly
		(pts
			(xy 339.558376 -237.207298) (xy 339.558376 -237.163102) (xy 339.202776 -237.163102) (xy 339.202776 -237.207298)
			(xy 339.249766 -237.359698) (xy 339.511386 -237.359698)
		)
		(stroke
			(width 0)
			(type solid)
		)
		(fill yes)
		(layer "In6.Cu")
		(net "M_C_CPU0_SB_DQS_DN<6>")
	)
	(gr_poly
		(pts
			(xy 339.558376 -235.988098) (xy 339.511386 -235.835698) (xy 339.249766 -235.835698) (xy 339.202776 -235.988098)
			(xy 339.202776 -236.032294) (xy 339.558376 -236.032294)
		)
		(stroke
			(width 0)
			(type solid)
		)
		(fill yes)
		(layer "In6.Cu")
		(net "M_C_CPU0_SB_DQ<14>")
	)
	(gr_poly
		(pts
			(xy 339.558376 -235.579666) (xy 339.558376 -235.53547) (xy 339.202776 -235.53547) (xy 339.202776 -235.579666)
			(xy 339.249766 -235.732066) (xy 339.511386 -235.732066)
		)
		(stroke
			(width 0)
			(type solid)
		)
		(fill yes)
		(layer "In6.Cu")
		(net "M_C_CPU0_SB_DQ<13>")
	)
	(gr_poly
		(pts
			(xy 339.558376 -232.323894) (xy 339.558376 -232.279698) (xy 339.202776 -232.279698) (xy 339.202776 -232.323894)
			(xy 339.249766 -232.476294) (xy 339.511386 -232.476294)
		)
		(stroke
			(width 0)
			(type solid)
		)
		(fill yes)
		(layer "In6.Cu")
		(net "M_D_CPU0_SB_DQS_DN<7>")
	)
	(gr_poly
		(pts
			(xy 339.558376 -231.104694) (xy 339.511386 -230.952294) (xy 339.249766 -230.952294) (xy 339.202776 -231.104694)
			(xy 339.202776 -231.14889) (xy 339.558376 -231.14889)
		)
		(stroke
			(width 0)
			(type solid)
		)
		(fill yes)
		(layer "In6.Cu")
		(net "M_D_CPU0_SB_DQ<22>")
	)
	(gr_poly
		(pts
			(xy 339.558376 -230.696262) (xy 339.558376 -230.652066) (xy 339.202776 -230.652066) (xy 339.202776 -230.696262)
			(xy 339.249766 -230.848662) (xy 339.511386 -230.848662)
		)
		(stroke
			(width 0)
			(type solid)
		)
		(fill yes)
		(layer "In6.Cu")
		(net "M_D_CPU0_SB_DQ<21>")
	)
	(gr_poly
		(pts
			(xy 339.558376 -225.813366) (xy 339.558376 -225.768916) (xy 339.202776 -225.768916) (xy 339.202776 -225.813366)
			(xy 339.249766 -225.965766) (xy 339.511386 -225.965766)
		)
		(stroke
			(width 0)
			(type solid)
		)
		(fill yes)
		(layer "In6.Cu")
		(net "M_C_CPU0_SB_DQ<28>")
	)
	(gr_poly
		(pts
			(xy 339.560916 -244.126766) (xy 339.513926 -243.974366) (xy 339.252306 -243.974366) (xy 339.205316 -244.126766)
			(xy 339.205316 -244.171216) (xy 339.560916 -244.171216)
		)
		(stroke
			(width 0)
			(type solid)
		)
		(fill yes)
		(layer "In6.Cu")
		(net "M_C_CPU0_SB_DQ<2>")
	)
	(gr_poly
		(pts
			(xy 339.560916 -242.090702) (xy 339.560916 -242.046506) (xy 339.205316 -242.046506) (xy 339.205316 -242.090702)
			(xy 339.252306 -242.243102) (xy 339.513926 -242.243102)
		)
		(stroke
			(width 0)
			(type solid)
		)
		(fill yes)
		(layer "In6.Cu")
		(net "M_C_CPU0_SB_DQS_DN<5>")
	)
	(gr_poly
		(pts
			(xy 339.560916 -239.243362) (xy 339.513926 -239.090962) (xy 339.252306 -239.090962) (xy 339.205316 -239.243362)
			(xy 339.205316 -239.287812) (xy 339.560916 -239.287812)
		)
		(stroke
			(width 0)
			(type solid)
		)
		(fill yes)
		(layer "In6.Cu")
		(net "M_C_CPU0_SB_DQ<10>")
	)
	(gr_poly
		(pts
			(xy 339.560916 -234.360466) (xy 339.513926 -234.208066) (xy 339.252306 -234.208066) (xy 339.205316 -234.360466)
			(xy 339.205316 -234.404662) (xy 339.560916 -234.404662)
		)
		(stroke
			(width 0)
			(type solid)
		)
		(fill yes)
		(layer "In6.Cu")
		(net "M_D_CPU0_SB_DQ<18>")
	)
	(gr_poly
		(pts
			(xy 339.65642 -274.876514) (xy 339.65642 -274.832064) (xy 339.30082 -274.832064) (xy 339.30082 -274.876514)
			(xy 339.34781 -275.028914) (xy 339.60943 -275.028914)
		)
		(stroke
			(width 0)
			(type solid)
		)
		(fill yes)
		(layer "In6.Cu")
		(net "M_D_CPU0_SA_DQS_DN<5>")
	)
	(gr_poly
		(pts
			(xy 339.65642 -269.99311) (xy 339.65642 -269.948914) (xy 339.30082 -269.948914) (xy 339.30082 -269.99311)
			(xy 339.34781 -270.14551) (xy 339.60943 -270.14551)
		)
		(stroke
			(width 0)
			(type solid)
		)
		(fill yes)
		(layer "In6.Cu")
		(net "M_C_CPU0_SA_DQS_DN<6>")
	)
	(gr_poly
		(pts
			(xy 339.65642 -265.109706) (xy 339.65642 -265.06551) (xy 339.30082 -265.06551) (xy 339.30082 -265.109706)
			(xy 339.34781 -265.262106) (xy 339.60943 -265.262106)
		)
		(stroke
			(width 0)
			(type solid)
		)
		(fill yes)
		(layer "In6.Cu")
		(net "M_C_CPU0_SA_DQS_DN<8>")
	)
	(gr_poly
		(pts
			(xy 339.65642 -260.226302) (xy 339.65642 -260.182106) (xy 339.30082 -260.182106) (xy 339.30082 -260.226302)
			(xy 339.34781 -260.378702) (xy 339.60943 -260.378702)
		)
		(stroke
			(width 0)
			(type solid)
		)
		(fill yes)
		(layer "In6.Cu")
		(net "M_C_CPU0_SA_DQS_DP<4>")
	)
	(gr_poly
		(pts
			(xy 339.65642 -255.343406) (xy 339.65642 -255.298956) (xy 339.30082 -255.298956) (xy 339.30082 -255.343406)
			(xy 339.34781 -255.495806) (xy 339.60943 -255.495806)
		)
		(stroke
			(width 0)
			(type solid)
		)
		(fill yes)
		(layer "In6.Cu")
		(net "M_C_CPU0_SA_RSP<0>")
	)
	(gr_poly
		(pts
			(xy 339.65896 -263.482074) (xy 339.65896 -263.437624) (xy 339.30336 -263.437624) (xy 339.30336 -263.482074)
			(xy 339.35035 -263.634474) (xy 339.61197 -263.634474)
		)
		(stroke
			(width 0)
			(type solid)
		)
		(fill yes)
		(layer "In6.Cu")
		(net "M_C_CPU0_SA_DQ<29>")
	)
	(gr_poly
		(pts
			(xy 339.662516 -273.657314) (xy 339.615526 -273.504914) (xy 339.353906 -273.504914) (xy 339.306916 -273.657314)
			(xy 339.306916 -273.701764) (xy 339.662516 -273.701764)
		)
		(stroke
			(width 0)
			(type solid)
		)
		(fill yes)
		(layer "In6.Cu")
		(net "M_D_CPU0_SA_DQ<6>")
	)
	(gr_poly
		(pts
			(xy 339.662516 -268.77391) (xy 339.615526 -268.62151) (xy 339.353906 -268.62151) (xy 339.306916 -268.77391)
			(xy 339.306916 -268.81836) (xy 339.662516 -268.81836)
		)
		(stroke
			(width 0)
			(type solid)
		)
		(fill yes)
		(layer "In6.Cu")
		(net "M_C_CPU0_SA_DQ<14>")
	)
	(gr_poly
		(pts
			(xy 339.662516 -263.891014) (xy 339.615526 -263.738614) (xy 339.353906 -263.738614) (xy 339.306916 -263.891014)
			(xy 339.306916 -263.93521) (xy 339.662516 -263.93521)
		)
		(stroke
			(width 0)
			(type solid)
		)
		(fill yes)
		(layer "In6.Cu")
		(net "M_C_CPU0_SA_DQ<30>")
	)
	(gr_poly
		(pts
			(xy 339.662516 -259.00761) (xy 339.615526 -258.85521) (xy 339.353906 -258.85521) (xy 339.306916 -259.00761)
			(xy 339.306916 -259.051806) (xy 339.662516 -259.051806)
		)
		(stroke
			(width 0)
			(type solid)
		)
		(fill yes)
		(layer "In6.Cu")
		(net "M_C_CPU0_SA_CB<4>")
	)
	(gr_poly
		(pts
			(xy 339.662516 -254.124206) (xy 339.615526 -253.971806) (xy 339.353906 -253.971806) (xy 339.306916 -254.124206)
			(xy 339.306916 -254.168402) (xy 339.662516 -254.168402)
		)
		(stroke
			(width 0)
			(type solid)
		)
		(fill yes)
		(layer "In6.Cu")
		(net "M_C_CPU0_SB_RSP<1>")
	)
	(gr_poly
		(pts
			(xy 339.668358 -276.912578) (xy 339.621368 -276.760178) (xy 339.359748 -276.760178) (xy 339.312758 -276.912578)
			(xy 339.312758 -276.957028) (xy 339.668358 -276.957028)
		)
		(stroke
			(width 0)
			(type solid)
		)
		(fill yes)
		(layer "In6.Cu")
		(net "M_D_CPU0_SA_DQ<2>")
	)
	(gr_poly
		(pts
			(xy 339.668358 -276.5044) (xy 339.668358 -276.460204) (xy 339.312758 -276.460204) (xy 339.312758 -276.5044)
			(xy 339.359748 -276.6568) (xy 339.621368 -276.6568)
		)
		(stroke
			(width 0)
			(type solid)
		)
		(fill yes)
		(layer "In6.Cu")
		(net "M_D_CPU0_SA_DQ<1>")
	)
	(gr_poly
		(pts
			(xy 339.668358 -275.284946) (xy 339.621368 -275.132546) (xy 339.359748 -275.132546) (xy 339.312758 -275.284946)
			(xy 339.312758 -275.329396) (xy 339.668358 -275.329396)
		)
		(stroke
			(width 0)
			(type solid)
		)
		(fill yes)
		(layer "In6.Cu")
		(net "M_D_CPU0_SA_DQS_DN<0>")
	)
	(gr_poly
		(pts
			(xy 339.668358 -272.029174) (xy 339.621368 -271.876774) (xy 339.359748 -271.876774) (xy 339.312758 -272.029174)
			(xy 339.312758 -272.073624) (xy 339.668358 -272.073624)
		)
		(stroke
			(width 0)
			(type solid)
		)
		(fill yes)
		(layer "In6.Cu")
		(net "M_C_CPU0_SA_DQ<10>")
	)
	(gr_poly
		(pts
			(xy 339.668358 -271.62125) (xy 339.668358 -271.5768) (xy 339.312758 -271.5768) (xy 339.312758 -271.62125)
			(xy 339.359748 -271.77365) (xy 339.621368 -271.77365)
		)
		(stroke
			(width 0)
			(type solid)
		)
		(fill yes)
		(layer "In6.Cu")
		(net "M_C_CPU0_SA_DQ<9>")
	)
	(gr_poly
		(pts
			(xy 339.668358 -270.40205) (xy 339.621368 -270.24965) (xy 339.359748 -270.24965) (xy 339.312758 -270.40205)
			(xy 339.312758 -270.446246) (xy 339.668358 -270.446246)
		)
		(stroke
			(width 0)
			(type solid)
		)
		(fill yes)
		(layer "In6.Cu")
		(net "M_C_CPU0_SA_DQS_DN<1>")
	)
	(gr_poly
		(pts
			(xy 339.668358 -267.14577) (xy 339.621368 -266.99337) (xy 339.359748 -266.99337) (xy 339.312758 -267.14577)
			(xy 339.312758 -267.19022) (xy 339.668358 -267.19022)
		)
		(stroke
			(width 0)
			(type solid)
		)
		(fill yes)
		(layer "In6.Cu")
		(net "M_C_CPU0_SA_DQ<26>")
	)
	(gr_poly
		(pts
			(xy 339.668358 -266.737846) (xy 339.668358 -266.69365) (xy 339.312758 -266.69365) (xy 339.312758 -266.737846)
			(xy 339.359748 -266.890246) (xy 339.621368 -266.890246)
		)
		(stroke
			(width 0)
			(type solid)
		)
		(fill yes)
		(layer "In6.Cu")
		(net "M_C_CPU0_SA_DQ<25>")
	)
	(gr_poly
		(pts
			(xy 339.668358 -265.518646) (xy 339.621368 -265.366246) (xy 339.359748 -265.366246) (xy 339.312758 -265.518646)
			(xy 339.312758 -265.562842) (xy 339.668358 -265.562842)
		)
		(stroke
			(width 0)
			(type solid)
		)
		(fill yes)
		(layer "In6.Cu")
		(net "M_C_CPU0_SA_DQS_DN<3>")
	)
	(gr_poly
		(pts
			(xy 339.668358 -262.262874) (xy 339.621368 -262.110474) (xy 339.359748 -262.110474) (xy 339.312758 -262.262874)
			(xy 339.312758 -262.30707) (xy 339.668358 -262.30707)
		)
		(stroke
			(width 0)
			(type solid)
		)
		(fill yes)
		(layer "In6.Cu")
		(net "M_C_CPU0_SA_CB<0>")
	)
	(gr_poly
		(pts
			(xy 339.668358 -261.854442) (xy 339.668358 -261.810246) (xy 339.312758 -261.810246) (xy 339.312758 -261.854442)
			(xy 339.359748 -262.006842) (xy 339.621368 -262.006842)
		)
		(stroke
			(width 0)
			(type solid)
		)
		(fill yes)
		(layer "In6.Cu")
		(net "M_C_CPU0_SA_CB<3>")
	)
	(gr_poly
		(pts
			(xy 339.668358 -260.635242) (xy 339.621368 -260.482842) (xy 339.359748 -260.482842) (xy 339.312758 -260.635242)
			(xy 339.312758 -260.679438) (xy 339.668358 -260.679438)
		)
		(stroke
			(width 0)
			(type solid)
		)
		(fill yes)
		(layer "In6.Cu")
		(net "M_C_CPU0_SA_DQS_DP<9>")
	)
	(gr_poly
		(pts
			(xy 339.668358 -256.971038) (xy 339.668358 -256.926842) (xy 339.312758 -256.926842) (xy 339.312758 -256.971038)
			(xy 339.359748 -257.123438) (xy 339.621368 -257.123438)
		)
		(stroke
			(width 0)
			(type solid)
		)
		(fill yes)
		(layer "In6.Cu")
		(net "M_D_CPU0_SA_RSP<0>")
	)
	(gr_poly
		(pts
			(xy 339.668358 -255.751838) (xy 339.621368 -255.599438) (xy 339.359748 -255.599438) (xy 339.312758 -255.751838)
			(xy 339.312758 -255.796288) (xy 339.668358 -255.796288)
		)
		(stroke
			(width 0)
			(type solid)
		)
		(fill yes)
		(layer "In6.Cu")
		(net "M_D_CPU0_SB_RSP<1>")
	)
	(gr_poly
		(pts
			(xy 339.670898 -273.248882) (xy 339.670898 -273.204686) (xy 339.315298 -273.204686) (xy 339.315298 -273.248882)
			(xy 339.362288 -273.401282) (xy 339.623908 -273.401282)
		)
		(stroke
			(width 0)
			(type solid)
		)
		(fill yes)
		(layer "In6.Cu")
		(net "M_D_CPU0_SA_DQ<5>")
	)
	(gr_poly
		(pts
			(xy 339.670898 -268.365478) (xy 339.670898 -268.321282) (xy 339.315298 -268.321282) (xy 339.315298 -268.365478)
			(xy 339.362288 -268.517878) (xy 339.623908 -268.517878)
		)
		(stroke
			(width 0)
			(type solid)
		)
		(fill yes)
		(layer "In6.Cu")
		(net "M_C_CPU0_SA_DQ<13>")
	)
	(gr_poly
		(pts
			(xy 339.670898 -258.599178) (xy 339.670898 -258.554728) (xy 339.315298 -258.554728) (xy 339.315298 -258.599178)
			(xy 339.362288 -258.751578) (xy 339.623908 -258.751578)
		)
		(stroke
			(width 0)
			(type solid)
		)
		(fill yes)
		(layer "In6.Cu")
		(net "M_C_CPU0_SA_CB<7>")
	)
	(gr_poly
		(pts
			(xy 339.87359 -228.914706) (xy 339.911944 -228.892608) (xy 339.734144 -228.58476) (xy 339.69579 -228.606858)
			(xy 339.587332 -228.723698) (xy 339.718142 -228.950266)
		)
		(stroke
			(width 0)
			(type solid)
		)
		(fill yes)
		(layer "In6.Cu")
		(net "M_C_CPU0_SB_DQ<25>")
	)
	(gr_poly
		(pts
			(xy 339.98789 -228.302058) (xy 340.096348 -228.185218) (xy 339.965538 -227.95865) (xy 339.81009 -227.99421)
			(xy 339.771736 -228.016308) (xy 339.949536 -228.324156)
		)
		(stroke
			(width 0)
			(type solid)
		)
		(fill yes)
		(layer "In6.Cu")
		(net "M_C_CPU0_SB_DQ<27>")
	)
	(gr_poly
		(pts
			(xy 340.013798 -246.16029) (xy 340.013798 -246.116094) (xy 339.658198 -246.116094) (xy 339.658198 -246.16029)
			(xy 339.705188 -246.31269) (xy 339.966808 -246.31269)
		)
		(stroke
			(width 0)
			(type solid)
		)
		(fill yes)
		(layer "In6.Cu")
		(net "M_D_CPU0_SB_CS_N<2>")
	)
	(gr_poly
		(pts
			(xy 340.013798 -241.685318) (xy 339.966808 -241.532918) (xy 339.705188 -241.532918) (xy 339.658198 -241.685318)
			(xy 339.658198 -241.729514) (xy 340.013798 -241.729514)
		)
		(stroke
			(width 0)
			(type solid)
		)
		(fill yes)
		(layer "In6.Cu")
		(net "M_C_CPU0_SB_DQS_DP<5>")
	)
	(gr_poly
		(pts
			(xy 340.013798 -241.276886) (xy 340.013798 -241.23269) (xy 339.658198 -241.23269) (xy 339.658198 -241.276886)
			(xy 339.705188 -241.429286) (xy 339.966808 -241.429286)
		)
		(stroke
			(width 0)
			(type solid)
		)
		(fill yes)
		(layer "In6.Cu")
		(net "M_C_CPU0_SB_DQ<4>")
	)
	(gr_poly
		(pts
			(xy 340.013798 -240.057178) (xy 339.966808 -239.904778) (xy 339.705188 -239.904778) (xy 339.658198 -240.057178)
			(xy 339.658198 -240.101628) (xy 340.013798 -240.101628)
		)
		(stroke
			(width 0)
			(type solid)
		)
		(fill yes)
		(layer "In6.Cu")
		(net "M_C_CPU0_SB_DQ<7>")
	)
	(gr_poly
		(pts
			(xy 340.013798 -239.649254) (xy 340.013798 -239.604804) (xy 339.658198 -239.604804) (xy 339.658198 -239.649254)
			(xy 339.705188 -239.801654) (xy 339.966808 -239.801654)
		)
		(stroke
			(width 0)
			(type solid)
		)
		(fill yes)
		(layer "In6.Cu")
		(net "M_C_CPU0_SB_DQ<8>")
	)
	(gr_poly
		(pts
			(xy 340.013798 -236.39399) (xy 340.013798 -236.34954) (xy 339.658198 -236.34954) (xy 339.658198 -236.39399)
			(xy 339.705188 -236.54639) (xy 339.966808 -236.54639)
		)
		(stroke
			(width 0)
			(type solid)
		)
		(fill yes)
		(layer "In6.Cu")
		(net "M_C_CPU0_SB_DQ<12>")
	)
	(gr_poly
		(pts
			(xy 340.013798 -235.174282) (xy 339.966808 -235.021882) (xy 339.705188 -235.021882) (xy 339.658198 -235.174282)
			(xy 339.658198 -235.218478) (xy 340.013798 -235.218478)
		)
		(stroke
			(width 0)
			(type solid)
		)
		(fill yes)
		(layer "In6.Cu")
		(net "M_C_CPU0_SB_DQ<15>")
	)
	(gr_poly
		(pts
			(xy 340.013798 -234.76585) (xy 340.013798 -234.721654) (xy 339.658198 -234.721654) (xy 339.658198 -234.76585)
			(xy 339.705188 -234.91825) (xy 339.966808 -234.91825)
		)
		(stroke
			(width 0)
			(type solid)
		)
		(fill yes)
		(layer "In6.Cu")
		(net "M_D_CPU0_SB_DQ<16>")
	)
	(gr_poly
		(pts
			(xy 340.013798 -231.510586) (xy 340.013798 -231.466136) (xy 339.658198 -231.466136) (xy 339.658198 -231.510586)
			(xy 339.705188 -231.662986) (xy 339.966808 -231.662986)
		)
		(stroke
			(width 0)
			(type solid)
		)
		(fill yes)
		(layer "In6.Cu")
		(net "M_D_CPU0_SB_DQ<20>")
	)
	(gr_poly
		(pts
			(xy 340.013798 -230.290878) (xy 339.966808 -230.138478) (xy 339.705188 -230.138478) (xy 339.658198 -230.290878)
			(xy 339.658198 -230.335074) (xy 340.013798 -230.335074)
		)
		(stroke
			(width 0)
			(type solid)
		)
		(fill yes)
		(layer "In6.Cu")
		(net "M_D_CPU0_SB_DQ<23>")
	)
	(gr_poly
		(pts
			(xy 340.013798 -229.882446) (xy 340.013798 -229.83825) (xy 339.658198 -229.83825) (xy 339.658198 -229.882446)
			(xy 339.705188 -230.034846) (xy 339.966808 -230.034846)
		)
		(stroke
			(width 0)
			(type solid)
		)
		(fill yes)
		(layer "In6.Cu")
		(net "M_C_CPU0_SB_DQ<26>")
	)
	(gr_poly
		(pts
			(xy 340.013798 -225.407474) (xy 339.966808 -225.255074) (xy 339.705188 -225.255074) (xy 339.658198 -225.407474)
			(xy 339.658198 -225.45167) (xy 340.013798 -225.45167)
		)
		(stroke
			(width 0)
			(type solid)
		)
		(fill yes)
		(layer "In6.Cu")
		(net "M_C_CPU0_SB_DQ<30>")
	)
	(gr_poly
		(pts
			(xy 340.016338 -248.196354) (xy 339.969348 -248.043954) (xy 339.707728 -248.043954) (xy 339.660738 -248.196354)
			(xy 339.660738 -248.240804) (xy 340.016338 -248.240804)
		)
		(stroke
			(width 0)
			(type solid)
		)
		(fill yes)
		(layer "In6.Cu")
		(net "M_A_CPU0_SA_RSP<0>")
	)
	(gr_poly
		(pts
			(xy 340.016338 -244.940582) (xy 339.969348 -244.788182) (xy 339.707728 -244.788182) (xy 339.660738 -244.940582)
			(xy 339.660738 -244.985032) (xy 340.016338 -244.985032)
		)
		(stroke
			(width 0)
			(type solid)
		)
		(fill yes)
		(layer "In6.Cu")
		(net "M_D_CPU0_SB_CS_N<1>")
	)
	(gr_poly
		(pts
			(xy 340.016338 -244.532658) (xy 340.016338 -244.488208) (xy 339.660738 -244.488208) (xy 339.660738 -244.532658)
			(xy 339.707728 -244.685058) (xy 339.969348 -244.685058)
		)
		(stroke
			(width 0)
			(type solid)
		)
		(fill yes)
		(layer "In6.Cu")
		(net "M_C_CPU0_SB_DQ<0>")
	)
	(gr_poly
		(pts
			(xy 340.016338 -238.430054) (xy 339.969348 -238.277654) (xy 339.707728 -238.277654) (xy 339.660738 -238.430054)
			(xy 339.660738 -238.47425) (xy 340.016338 -238.47425)
		)
		(stroke
			(width 0)
			(type solid)
		)
		(fill yes)
		(layer "In6.Cu")
		(net "M_C_CPU0_SB_DQ<11>")
	)
	(gr_poly
		(pts
			(xy 340.016338 -233.54665) (xy 339.969348 -233.39425) (xy 339.707728 -233.39425) (xy 339.660738 -233.54665)
			(xy 339.660738 -233.590846) (xy 340.016338 -233.590846)
		)
		(stroke
			(width 0)
			(type solid)
		)
		(fill yes)
		(layer "In6.Cu")
		(net "M_D_CPU0_SB_DQ<19>")
	)
	(gr_poly
		(pts
			(xy 340.02218 -236.801914) (xy 339.97519 -236.649514) (xy 339.71357 -236.649514) (xy 339.66658 -236.801914)
			(xy 339.66658 -236.846364) (xy 340.02218 -236.846364)
		)
		(stroke
			(width 0)
			(type solid)
		)
		(fill yes)
		(layer "In6.Cu")
		(net "M_C_CPU0_SB_DQS_DP<6>")
	)
	(gr_poly
		(pts
			(xy 340.02218 -231.919018) (xy 339.97519 -231.766618) (xy 339.71357 -231.766618) (xy 339.66658 -231.919018)
			(xy 339.66658 -231.963214) (xy 340.02218 -231.963214)
		)
		(stroke
			(width 0)
			(type solid)
		)
		(fill yes)
		(layer "In6.Cu")
		(net "M_D_CPU0_SB_DQS_DP<7>")
	)
	(gr_poly
		(pts
			(xy 340.022434 -226.626674) (xy 340.022434 -226.582478) (xy 339.666834 -226.582478) (xy 339.666834 -226.626674)
			(xy 339.713824 -226.779074) (xy 339.975444 -226.779074)
		)
		(stroke
			(width 0)
			(type solid)
		)
		(fill yes)
		(layer "In6.Cu")
		(net "M_C_CPU0_SB_DQS_DN<8>")
	)
	(gr_poly
		(pts
			(xy 340.025736 -243.313458) (xy 339.978746 -243.161058) (xy 339.717126 -243.161058) (xy 339.670136 -243.313458)
			(xy 339.670136 -243.357654) (xy 340.025736 -243.357654)
		)
		(stroke
			(width 0)
			(type solid)
		)
		(fill yes)
		(layer "In6.Cu")
		(net "M_C_CPU0_SB_DQ<3>")
	)
	(gr_poly
		(pts
			(xy 340.028276 -247.787922) (xy 340.028276 -247.743472) (xy 339.672676 -247.743472) (xy 339.672676 -247.787922)
			(xy 339.719666 -247.940322) (xy 339.981286 -247.940322)
		)
		(stroke
			(width 0)
			(type solid)
		)
		(fill yes)
		(layer "In6.Cu")
		(net "M_A_CPU0_SA_RSP<1>")
	)
	(gr_poly
		(pts
			(xy 340.028276 -242.904518) (xy 340.028276 -242.860322) (xy 339.672676 -242.860322) (xy 339.672676 -242.904518)
			(xy 339.719666 -243.056918) (xy 339.981286 -243.056918)
		)
		(stroke
			(width 0)
			(type solid)
		)
		(fill yes)
		(layer "In6.Cu")
		(net "M_C_CPU0_SB_DQS_DP<0>")
	)
	(gr_poly
		(pts
			(xy 340.028276 -238.021114) (xy 340.028276 -237.976918) (xy 339.672676 -237.976918) (xy 339.672676 -238.021114)
			(xy 339.719666 -238.173514) (xy 339.981286 -238.173514)
		)
		(stroke
			(width 0)
			(type solid)
		)
		(fill yes)
		(layer "In6.Cu")
		(net "M_C_CPU0_SB_DQS_DP<1>")
	)
	(gr_poly
		(pts
			(xy 340.028276 -233.13771) (xy 340.028276 -233.093514) (xy 339.672676 -233.093514) (xy 339.672676 -233.13771)
			(xy 339.719666 -233.29011) (xy 339.981286 -233.29011)
		)
		(stroke
			(width 0)
			(type solid)
		)
		(fill yes)
		(layer "In6.Cu")
		(net "M_D_CPU0_SB_DQS_DP<2>")
	)
	(gr_poly
		(pts
			(xy 340.030816 -227.035106) (xy 339.983826 -226.882706) (xy 339.722206 -226.882706) (xy 339.675216 -227.035106)
			(xy 339.675216 -227.079556) (xy 340.030816 -227.079556)
		)
		(stroke
			(width 0)
			(type solid)
		)
		(fill yes)
		(layer "In6.Cu")
		(net "M_C_CPU0_SB_DQS_DN<3>")
	)
	(gr_poly
		(pts
			(xy 340.12378 -277.318216) (xy 340.12378 -277.27402) (xy 339.76818 -277.27402) (xy 339.76818 -277.318216)
			(xy 339.81517 -277.470616) (xy 340.07679 -277.470616)
		)
		(stroke
			(width 0)
			(type solid)
		)
		(fill yes)
		(layer "In6.Cu")
		(net "M_D_CPU0_SA_DQ<0>")
	)
	(gr_poly
		(pts
			(xy 340.12378 -276.098762) (xy 340.07679 -275.946362) (xy 339.81517 -275.946362) (xy 339.76818 -276.098762)
			(xy 339.76818 -276.143212) (xy 340.12378 -276.143212)
		)
		(stroke
			(width 0)
			(type solid)
		)
		(fill yes)
		(layer "In6.Cu")
		(net "M_D_CPU0_SA_DQ<3>")
	)
	(gr_poly
		(pts
			(xy 340.12378 -272.843498) (xy 340.07679 -272.691098) (xy 339.81517 -272.691098) (xy 339.76818 -272.843498)
			(xy 339.76818 -272.887694) (xy 340.12378 -272.887694)
		)
		(stroke
			(width 0)
			(type solid)
		)
		(fill yes)
		(layer "In6.Cu")
		(net "M_D_CPU0_SA_DQ<7>")
	)
	(gr_poly
		(pts
			(xy 340.12378 -272.435066) (xy 340.12378 -272.39087) (xy 339.76818 -272.39087) (xy 339.76818 -272.435066)
			(xy 339.81517 -272.587466) (xy 340.07679 -272.587466)
		)
		(stroke
			(width 0)
			(type solid)
		)
		(fill yes)
		(layer "In6.Cu")
		(net "M_C_CPU0_SA_DQ<8>")
	)
	(gr_poly
		(pts
			(xy 340.12378 -271.215358) (xy 340.07679 -271.062958) (xy 339.81517 -271.062958) (xy 339.76818 -271.215358)
			(xy 339.76818 -271.259808) (xy 340.12378 -271.259808)
		)
		(stroke
			(width 0)
			(type solid)
		)
		(fill yes)
		(layer "In6.Cu")
		(net "M_C_CPU0_SA_DQ<11>")
	)
	(gr_poly
		(pts
			(xy 340.12378 -267.960094) (xy 340.07679 -267.807694) (xy 339.81517 -267.807694) (xy 339.76818 -267.960094)
			(xy 339.76818 -268.00429) (xy 340.12378 -268.00429)
		)
		(stroke
			(width 0)
			(type solid)
		)
		(fill yes)
		(layer "In6.Cu")
		(net "M_C_CPU0_SA_DQ<15>")
	)
	(gr_poly
		(pts
			(xy 340.12378 -267.551662) (xy 340.12378 -267.507466) (xy 339.76818 -267.507466) (xy 339.76818 -267.551662)
			(xy 339.81517 -267.704062) (xy 340.07679 -267.704062)
		)
		(stroke
			(width 0)
			(type solid)
		)
		(fill yes)
		(layer "In6.Cu")
		(net "M_C_CPU0_SA_DQ<24>")
	)
	(gr_poly
		(pts
			(xy 340.12378 -266.331954) (xy 340.07679 -266.179554) (xy 339.81517 -266.179554) (xy 339.76818 -266.331954)
			(xy 339.76818 -266.376404) (xy 340.12378 -266.376404)
		)
		(stroke
			(width 0)
			(type solid)
		)
		(fill yes)
		(layer "In6.Cu")
		(net "M_C_CPU0_SA_DQ<27>")
	)
	(gr_poly
		(pts
			(xy 340.12378 -262.668258) (xy 340.12378 -262.624062) (xy 339.76818 -262.624062) (xy 339.76818 -262.668258)
			(xy 339.81517 -262.820658) (xy 340.07679 -262.820658)
		)
		(stroke
			(width 0)
			(type solid)
		)
		(fill yes)
		(layer "In6.Cu")
		(net "M_C_CPU0_SA_CB<2>")
	)
	(gr_poly
		(pts
			(xy 340.12378 -261.449058) (xy 340.07679 -261.296658) (xy 339.81517 -261.296658) (xy 339.76818 -261.449058)
			(xy 339.76818 -261.493254) (xy 340.12378 -261.493254)
		)
		(stroke
			(width 0)
			(type solid)
		)
		(fill yes)
		(layer "In6.Cu")
		(net "M_C_CPU0_SA_CB<1>")
	)
	(gr_poly
		(pts
			(xy 340.12378 -256.565654) (xy 340.07679 -256.413254) (xy 339.81517 -256.413254) (xy 339.76818 -256.565654)
			(xy 339.76818 -256.60985) (xy 340.12378 -256.60985)
		)
		(stroke
			(width 0)
			(type solid)
		)
		(fill yes)
		(layer "In6.Cu")
		(net "M_D_CPU0_SB_RSP<0>")
	)
	(gr_poly
		(pts
			(xy 340.12632 -274.062698) (xy 340.12632 -274.018248) (xy 339.77072 -274.018248) (xy 339.77072 -274.062698)
			(xy 339.81771 -274.215098) (xy 340.07933 -274.215098)
		)
		(stroke
			(width 0)
			(type solid)
		)
		(fill yes)
		(layer "In6.Cu")
		(net "M_D_CPU0_SA_DQ<4>")
	)
	(gr_poly
		(pts
			(xy 340.12632 -269.179294) (xy 340.12632 -269.134844) (xy 339.77072 -269.134844) (xy 339.77072 -269.179294)
			(xy 339.81771 -269.331694) (xy 340.07933 -269.331694)
		)
		(stroke
			(width 0)
			(type solid)
		)
		(fill yes)
		(layer "In6.Cu")
		(net "M_C_CPU0_SA_DQ<12>")
	)
	(gr_poly
		(pts
			(xy 340.12632 -264.29589) (xy 340.12632 -264.251694) (xy 339.77072 -264.251694) (xy 339.77072 -264.29589)
			(xy 339.81771 -264.44829) (xy 340.07933 -264.44829)
		)
		(stroke
			(width 0)
			(type solid)
		)
		(fill yes)
		(layer "In6.Cu")
		(net "M_C_CPU0_SA_DQ<28>")
	)
	(gr_poly
		(pts
			(xy 340.12632 -259.412486) (xy 340.12632 -259.36829) (xy 339.77072 -259.36829) (xy 339.77072 -259.412486)
			(xy 339.81771 -259.564886) (xy 340.07933 -259.564886)
		)
		(stroke
			(width 0)
			(type solid)
		)
		(fill yes)
		(layer "In6.Cu")
		(net "M_C_CPU0_SA_CB<6>")
	)
	(gr_poly
		(pts
			(xy 340.12632 -258.193286) (xy 340.07933 -258.040886) (xy 339.81771 -258.040886) (xy 339.77072 -258.193286)
			(xy 339.77072 -258.237482) (xy 340.12632 -258.237482)
		)
		(stroke
			(width 0)
			(type solid)
		)
		(fill yes)
		(layer "In6.Cu")
		(net "M_C_CPU0_SA_CB<5>")
	)
	(gr_poly
		(pts
			(xy 340.12632 -254.529082) (xy 340.12632 -254.484886) (xy 339.77072 -254.484886) (xy 339.77072 -254.529082)
			(xy 339.81771 -254.681482) (xy 340.07933 -254.681482)
		)
		(stroke
			(width 0)
			(type solid)
		)
		(fill yes)
		(layer "In6.Cu")
		(net "M_C_CPU0_SA_RSP<1>")
	)
	(gr_poly
		(pts
			(xy 340.132162 -275.69033) (xy 340.132162 -275.64588) (xy 339.776562 -275.64588) (xy 339.776562 -275.69033)
			(xy 339.823552 -275.84273) (xy 340.085172 -275.84273)
		)
		(stroke
			(width 0)
			(type solid)
		)
		(fill yes)
		(layer "In6.Cu")
		(net "M_D_CPU0_SA_DQS_DP<0>")
	)
	(gr_poly
		(pts
			(xy 340.132162 -270.806926) (xy 340.132162 -270.76273) (xy 339.776562 -270.76273) (xy 339.776562 -270.806926)
			(xy 339.823552 -270.959326) (xy 340.085172 -270.959326)
		)
		(stroke
			(width 0)
			(type solid)
		)
		(fill yes)
		(layer "In6.Cu")
		(net "M_C_CPU0_SA_DQS_DP<1>")
	)
	(gr_poly
		(pts
			(xy 340.132162 -265.923522) (xy 340.132162 -265.879326) (xy 339.776562 -265.879326) (xy 339.776562 -265.923522)
			(xy 339.823552 -266.075922) (xy 340.085172 -266.075922)
		)
		(stroke
			(width 0)
			(type solid)
		)
		(fill yes)
		(layer "In6.Cu")
		(net "M_C_CPU0_SA_DQS_DP<3>")
	)
	(gr_poly
		(pts
			(xy 340.132162 -261.040626) (xy 340.132162 -260.996176) (xy 339.776562 -260.996176) (xy 339.776562 -261.040626)
			(xy 339.823552 -261.193026) (xy 340.085172 -261.193026)
		)
		(stroke
			(width 0)
			(type solid)
		)
		(fill yes)
		(layer "In6.Cu")
		(net "M_C_CPU0_SA_DQS_DN<9>")
	)
	(gr_poly
		(pts
			(xy 340.132162 -256.157222) (xy 340.132162 -256.112772) (xy 339.776562 -256.112772) (xy 339.776562 -256.157222)
			(xy 339.823552 -256.309622) (xy 340.085172 -256.309622)
		)
		(stroke
			(width 0)
			(type solid)
		)
		(fill yes)
		(layer "In6.Cu")
		(net "M_D_CPU0_SA_RSP<1>")
	)
	(gr_poly
		(pts
			(xy 340.135718 -263.077198) (xy 340.088728 -262.924798) (xy 339.827108 -262.924798) (xy 339.780118 -263.077198)
			(xy 339.780118 -263.121394) (xy 340.135718 -263.121394)
		)
		(stroke
			(width 0)
			(type solid)
		)
		(fill yes)
		(layer "In6.Cu")
		(net "M_C_CPU0_SA_DQ<31>")
	)
	(gr_poly
		(pts
			(xy 340.138258 -274.47113) (xy 340.091268 -274.31873) (xy 339.829648 -274.31873) (xy 339.782658 -274.47113)
			(xy 339.782658 -274.51558) (xy 340.138258 -274.51558)
		)
		(stroke
			(width 0)
			(type solid)
		)
		(fill yes)
		(layer "In6.Cu")
		(net "M_D_CPU0_SA_DQS_DP<5>")
	)
	(gr_poly
		(pts
			(xy 340.138258 -269.587726) (xy 340.091268 -269.435326) (xy 339.829648 -269.435326) (xy 339.782658 -269.587726)
			(xy 339.782658 -269.632176) (xy 340.138258 -269.632176)
		)
		(stroke
			(width 0)
			(type solid)
		)
		(fill yes)
		(layer "In6.Cu")
		(net "M_C_CPU0_SA_DQS_DP<6>")
	)
	(gr_poly
		(pts
			(xy 340.138258 -264.70483) (xy 340.091268 -264.55243) (xy 339.829648 -264.55243) (xy 339.782658 -264.70483)
			(xy 339.782658 -264.749026) (xy 340.138258 -264.749026)
		)
		(stroke
			(width 0)
			(type solid)
		)
		(fill yes)
		(layer "In6.Cu")
		(net "M_C_CPU0_SA_DQS_DP<8>")
	)
	(gr_poly
		(pts
			(xy 340.138258 -259.821426) (xy 340.091268 -259.669026) (xy 339.829648 -259.669026) (xy 339.782658 -259.821426)
			(xy 339.782658 -259.865622) (xy 340.138258 -259.865622)
		)
		(stroke
			(width 0)
			(type solid)
		)
		(fill yes)
		(layer "In6.Cu")
		(net "M_C_CPU0_SA_DQS_DN<4>")
	)
	(gr_poly
		(pts
			(xy 340.138258 -254.938022) (xy 340.091268 -254.785622) (xy 339.829648 -254.785622) (xy 339.782658 -254.938022)
			(xy 339.782658 -254.982218) (xy 340.138258 -254.982218)
		)
		(stroke
			(width 0)
			(type solid)
		)
		(fill yes)
		(layer "In6.Cu")
		(net "M_C_CPU0_SB_RSP<0>")
	)
	(gr_poly
		(pts
			(xy 340.348824 -228.10978) (xy 340.387178 -228.087682) (xy 340.209378 -227.779834) (xy 340.171024 -227.801932)
			(xy 340.062566 -227.918772) (xy 340.193376 -228.14534)
		)
		(stroke
			(width 0)
			(type solid)
		)
		(fill yes)
		(layer "In6.Cu")
		(net "M_C_CPU0_SB_DQS_DP<3>")
	)
	(gr_poly
		(pts
			(xy 340.386416 -223.948752) (xy 340.348062 -223.926654) (xy 340.192614 -223.891094) (xy 340.061804 -224.117662)
			(xy 340.170262 -224.234502) (xy 340.208616 -224.2566)
		)
		(stroke
			(width 0)
			(type solid)
		)
		(fill yes)
		(layer "In6.Cu")
		(net "M_C_CPU0_SB_DQ<29>")
	)
	(gr_poly
		(pts
			(xy 340.463124 -227.497386) (xy 340.571582 -227.380546) (xy 340.440772 -227.153978) (xy 340.285324 -227.189538)
			(xy 340.24697 -227.211636) (xy 340.42477 -227.519484)
		)
		(stroke
			(width 0)
			(type solid)
		)
		(fill yes)
		(layer "In6.Cu")
		(net "M_C_CPU0_SB_DQS_DN<3>")
	)
	(gr_poly
		(pts
			(xy 340.485984 -237.616238) (xy 340.438994 -237.463838) (xy 340.177374 -237.463838) (xy 340.130384 -237.616238)
			(xy 340.130384 -237.660434) (xy 340.485984 -237.660434)
		)
		(stroke
			(width 0)
			(type solid)
		)
		(fill yes)
		(layer "In6.Cu")
		(net "M_C_CPU0_SB_DQS_DN<1>")
	)
	(gr_poly
		(pts
			(xy 340.486238 -245.346474) (xy 340.486238 -245.302024) (xy 340.130638 -245.302024) (xy 340.130638 -245.346474)
			(xy 340.177628 -245.498874) (xy 340.439248 -245.498874)
		)
		(stroke
			(width 0)
			(type solid)
		)
		(fill yes)
		(layer "In6.Cu")
		(net "M_D_CPU0_SB_CS_N<0>")
	)
	(gr_poly
		(pts
			(xy 340.488778 -243.718334) (xy 340.488778 -243.674138) (xy 340.133178 -243.674138) (xy 340.133178 -243.718334)
			(xy 340.180168 -243.870734) (xy 340.441788 -243.870734)
		)
		(stroke
			(width 0)
			(type solid)
		)
		(fill yes)
		(layer "In6.Cu")
		(net "M_C_CPU0_SB_DQ<1>")
	)
	(gr_poly
		(pts
			(xy 340.492334 -244.127274) (xy 340.445344 -243.974874) (xy 340.183724 -243.974874) (xy 340.136734 -244.127274)
			(xy 340.136734 -244.17147) (xy 340.492334 -244.17147)
		)
		(stroke
			(width 0)
			(type solid)
		)
		(fill yes)
		(layer "In6.Cu")
		(net "M_C_CPU0_SB_DQ<2>")
	)
	(gr_poly
		(pts
			(xy 340.492334 -226.221798) (xy 340.445344 -226.069398) (xy 340.183724 -226.069398) (xy 340.136734 -226.221798)
			(xy 340.136734 -226.265994) (xy 340.492334 -226.265994)
		)
		(stroke
			(width 0)
			(type solid)
		)
		(fill yes)
		(layer "In6.Cu")
		(net "M_C_CPU0_SB_DQS_DP<8>")
	)
	(gr_poly
		(pts
			(xy 340.498176 -247.382538) (xy 340.451186 -247.230138) (xy 340.189566 -247.230138) (xy 340.142576 -247.382538)
			(xy 340.142576 -247.426734) (xy 340.498176 -247.426734)
		)
		(stroke
			(width 0)
			(type solid)
		)
		(fill yes)
		(layer "In6.Cu")
		(net "M_A_CPU0_SB_RSP<1>")
	)
	(gr_poly
		(pts
			(xy 340.498176 -245.754906) (xy 340.451186 -245.602506) (xy 340.189566 -245.602506) (xy 340.142576 -245.754906)
			(xy 340.142576 -245.799356) (xy 340.498176 -245.799356)
		)
		(stroke
			(width 0)
			(type solid)
		)
		(fill yes)
		(layer "In6.Cu")
		(net "M_D_CPU0_SB_CS_N<3>")
	)
	(gr_poly
		(pts
			(xy 340.498176 -237.207806) (xy 340.498176 -237.163356) (xy 340.142576 -237.163356) (xy 340.142576 -237.207806)
			(xy 340.189566 -237.360206) (xy 340.451186 -237.360206)
		)
		(stroke
			(width 0)
			(type solid)
		)
		(fill yes)
		(layer "In6.Cu")
		(net "M_C_CPU0_SB_DQS_DN<6>")
	)
	(gr_poly
		(pts
			(xy 340.498176 -232.732326) (xy 340.451186 -232.579926) (xy 340.189566 -232.579926) (xy 340.142576 -232.732326)
			(xy 340.142576 -232.776776) (xy 340.498176 -232.776776)
		)
		(stroke
			(width 0)
			(type solid)
		)
		(fill yes)
		(layer "In6.Cu")
		(net "M_D_CPU0_SB_DQS_DN<2>")
	)
	(gr_poly
		(pts
			(xy 340.498176 -232.324402) (xy 340.498176 -232.279952) (xy 340.142576 -232.279952) (xy 340.142576 -232.324402)
			(xy 340.189566 -232.476802) (xy 340.451186 -232.476802)
		)
		(stroke
			(width 0)
			(type solid)
		)
		(fill yes)
		(layer "In6.Cu")
		(net "M_D_CPU0_SB_DQS_DN<7>")
	)
	(gr_poly
		(pts
			(xy 340.500716 -248.602246) (xy 340.500716 -248.557796) (xy 340.145116 -248.557796) (xy 340.145116 -248.602246)
			(xy 340.192106 -248.754646) (xy 340.453726 -248.754646)
		)
		(stroke
			(width 0)
			(type solid)
		)
		(fill yes)
		(layer "In6.Cu")
		(net "M_A_CPU0_SB_RSP<0>")
	)
	(gr_poly
		(pts
			(xy 340.500716 -242.499134) (xy 340.453726 -242.346734) (xy 340.192106 -242.346734) (xy 340.145116 -242.499134)
			(xy 340.145116 -242.54333) (xy 340.500716 -242.54333)
		)
		(stroke
			(width 0)
			(type solid)
		)
		(fill yes)
		(layer "In6.Cu")
		(net "M_C_CPU0_SB_DQS_DN<0>")
	)
	(gr_poly
		(pts
			(xy 340.500716 -242.090702) (xy 340.500716 -242.046506) (xy 340.145116 -242.046506) (xy 340.145116 -242.090702)
			(xy 340.192106 -242.243102) (xy 340.453726 -242.243102)
		)
		(stroke
			(width 0)
			(type solid)
		)
		(fill yes)
		(layer "In6.Cu")
		(net "M_C_CPU0_SB_DQS_DN<5>")
	)
	(gr_poly
		(pts
			(xy 340.500716 -240.871502) (xy 340.453726 -240.719102) (xy 340.192106 -240.719102) (xy 340.145116 -240.871502)
			(xy 340.145116 -240.915698) (xy 340.500716 -240.915698)
		)
		(stroke
			(width 0)
			(type solid)
		)
		(fill yes)
		(layer "In6.Cu")
		(net "M_C_CPU0_SB_DQ<6>")
	)
	(gr_poly
		(pts
			(xy 340.500716 -240.46307) (xy 340.500716 -240.418874) (xy 340.145116 -240.418874) (xy 340.145116 -240.46307)
			(xy 340.192106 -240.61547) (xy 340.453726 -240.61547)
		)
		(stroke
			(width 0)
			(type solid)
		)
		(fill yes)
		(layer "In6.Cu")
		(net "M_C_CPU0_SB_DQ<5>")
	)
	(gr_poly
		(pts
			(xy 340.500716 -239.243362) (xy 340.453726 -239.090962) (xy 340.192106 -239.090962) (xy 340.145116 -239.243362)
			(xy 340.145116 -239.287812) (xy 340.500716 -239.287812)
		)
		(stroke
			(width 0)
			(type solid)
		)
		(fill yes)
		(layer "In6.Cu")
		(net "M_C_CPU0_SB_DQ<10>")
	)
	(gr_poly
		(pts
			(xy 340.500716 -238.835438) (xy 340.500716 -238.790988) (xy 340.145116 -238.790988) (xy 340.145116 -238.835438)
			(xy 340.192106 -238.987838) (xy 340.453726 -238.987838)
		)
		(stroke
			(width 0)
			(type solid)
		)
		(fill yes)
		(layer "In6.Cu")
		(net "M_C_CPU0_SB_DQ<9>")
	)
	(gr_poly
		(pts
			(xy 340.500716 -235.988098) (xy 340.453726 -235.835698) (xy 340.192106 -235.835698) (xy 340.145116 -235.988098)
			(xy 340.145116 -236.032294) (xy 340.500716 -236.032294)
		)
		(stroke
			(width 0)
			(type solid)
		)
		(fill yes)
		(layer "In6.Cu")
		(net "M_C_CPU0_SB_DQ<14>")
	)
	(gr_poly
		(pts
			(xy 340.500716 -235.579666) (xy 340.500716 -235.53547) (xy 340.145116 -235.53547) (xy 340.145116 -235.579666)
			(xy 340.192106 -235.732066) (xy 340.453726 -235.732066)
		)
		(stroke
			(width 0)
			(type solid)
		)
		(fill yes)
		(layer "In6.Cu")
		(net "M_C_CPU0_SB_DQ<13>")
	)
	(gr_poly
		(pts
			(xy 340.500716 -234.360466) (xy 340.453726 -234.208066) (xy 340.192106 -234.208066) (xy 340.145116 -234.360466)
			(xy 340.145116 -234.404662) (xy 340.500716 -234.404662)
		)
		(stroke
			(width 0)
			(type solid)
		)
		(fill yes)
		(layer "In6.Cu")
		(net "M_D_CPU0_SB_DQ<18>")
	)
	(gr_poly
		(pts
			(xy 340.500716 -233.952034) (xy 340.500716 -233.907838) (xy 340.145116 -233.907838) (xy 340.145116 -233.952034)
			(xy 340.192106 -234.104434) (xy 340.453726 -234.104434)
		)
		(stroke
			(width 0)
			(type solid)
		)
		(fill yes)
		(layer "In6.Cu")
		(net "M_D_CPU0_SB_DQ<17>")
	)
	(gr_poly
		(pts
			(xy 340.500716 -231.104694) (xy 340.453726 -230.952294) (xy 340.192106 -230.952294) (xy 340.145116 -231.104694)
			(xy 340.145116 -231.14889) (xy 340.500716 -231.14889)
		)
		(stroke
			(width 0)
			(type solid)
		)
		(fill yes)
		(layer "In6.Cu")
		(net "M_D_CPU0_SB_DQ<22>")
	)
	(gr_poly
		(pts
			(xy 340.500716 -230.696262) (xy 340.500716 -230.652066) (xy 340.145116 -230.652066) (xy 340.145116 -230.696262)
			(xy 340.192106 -230.848662) (xy 340.453726 -230.848662)
		)
		(stroke
			(width 0)
			(type solid)
		)
		(fill yes)
		(layer "In6.Cu")
		(net "M_D_CPU0_SB_DQ<21>")
	)
	(gr_poly
		(pts
			(xy 340.500716 -229.477062) (xy 340.453726 -229.324662) (xy 340.192106 -229.324662) (xy 340.145116 -229.477062)
			(xy 340.145116 -229.521258) (xy 340.500716 -229.521258)
		)
		(stroke
			(width 0)
			(type solid)
		)
		(fill yes)
		(layer "In6.Cu")
		(net "M_C_CPU0_SB_DQ<24>")
	)
	(gr_poly
		(pts
			(xy 340.500716 -229.06863) (xy 340.500716 -229.024434) (xy 340.145116 -229.024434) (xy 340.145116 -229.06863)
			(xy 340.192106 -229.22103) (xy 340.453726 -229.22103)
		)
		(stroke
			(width 0)
			(type solid)
		)
		(fill yes)
		(layer "In6.Cu")
		(net "M_C_CPU0_SB_DQ<25>")
	)
	(gr_poly
		(pts
			(xy 340.500716 -225.813366) (xy 340.500716 -225.768916) (xy 340.145116 -225.768916) (xy 340.145116 -225.813366)
			(xy 340.192106 -225.965766) (xy 340.453726 -225.965766)
		)
		(stroke
			(width 0)
			(type solid)
		)
		(fill yes)
		(layer "In6.Cu")
		(net "M_C_CPU0_SB_DQ<28>")
	)
	(gr_poly
		(pts
			(xy 340.571582 -224.65411) (xy 340.463124 -224.53727) (xy 340.42477 -224.515172) (xy 340.24697 -224.82302)
			(xy 340.285324 -224.845118) (xy 340.440772 -224.880678)
		)
		(stroke
			(width 0)
			(type solid)
		)
		(fill yes)
		(layer "In6.Cu")
		(net "M_C_CPU0_SB_DQ<31>")
	)
	(gr_poly
		(pts
			(xy 340.59876 -263.482074) (xy 340.59876 -263.437624) (xy 340.24316 -263.437624) (xy 340.24316 -263.482074)
			(xy 340.29015 -263.634474) (xy 340.55177 -263.634474)
		)
		(stroke
			(width 0)
			(type solid)
		)
		(fill yes)
		(layer "In6.Cu")
		(net "M_C_CPU0_SA_DQ<29>")
	)
	(gr_poly
		(pts
			(xy 340.602316 -258.59867) (xy 340.602316 -258.554474) (xy 340.246716 -258.554474) (xy 340.246716 -258.59867)
			(xy 340.293706 -258.75107) (xy 340.555326 -258.75107)
		)
		(stroke
			(width 0)
			(type solid)
		)
		(fill yes)
		(layer "In6.Cu")
		(net "M_C_CPU0_SA_CB<7>")
	)
	(gr_poly
		(pts
			(xy 340.608158 -275.284946) (xy 340.561168 -275.132546) (xy 340.299548 -275.132546) (xy 340.252558 -275.284946)
			(xy 340.252558 -275.329142) (xy 340.608158 -275.329142)
		)
		(stroke
			(width 0)
			(type solid)
		)
		(fill yes)
		(layer "In6.Cu")
		(net "M_D_CPU0_SA_DQS_DN<0>")
	)
	(gr_poly
		(pts
			(xy 340.608158 -274.876514) (xy 340.608158 -274.832318) (xy 340.252558 -274.832318) (xy 340.252558 -274.876514)
			(xy 340.299548 -275.028914) (xy 340.561168 -275.028914)
		)
		(stroke
			(width 0)
			(type solid)
		)
		(fill yes)
		(layer "In6.Cu")
		(net "M_D_CPU0_SA_DQS_DN<5>")
	)
	(gr_poly
		(pts
			(xy 340.608158 -270.401542) (xy 340.561168 -270.249142) (xy 340.299548 -270.249142) (xy 340.252558 -270.401542)
			(xy 340.252558 -270.445992) (xy 340.608158 -270.445992)
		)
		(stroke
			(width 0)
			(type solid)
		)
		(fill yes)
		(layer "In6.Cu")
		(net "M_C_CPU0_SA_DQS_DN<1>")
	)
	(gr_poly
		(pts
			(xy 340.608158 -269.993618) (xy 340.608158 -269.949168) (xy 340.252558 -269.949168) (xy 340.252558 -269.993618)
			(xy 340.299548 -270.146018) (xy 340.561168 -270.146018)
		)
		(stroke
			(width 0)
			(type solid)
		)
		(fill yes)
		(layer "In6.Cu")
		(net "M_C_CPU0_SA_DQS_DN<6>")
	)
	(gr_poly
		(pts
			(xy 340.608158 -265.518138) (xy 340.561168 -265.365738) (xy 340.299548 -265.365738) (xy 340.252558 -265.518138)
			(xy 340.252558 -265.562588) (xy 340.608158 -265.562588)
		)
		(stroke
			(width 0)
			(type solid)
		)
		(fill yes)
		(layer "In6.Cu")
		(net "M_C_CPU0_SA_DQS_DN<3>")
	)
	(gr_poly
		(pts
			(xy 340.608158 -265.110214) (xy 340.608158 -265.065764) (xy 340.252558 -265.065764) (xy 340.252558 -265.110214)
			(xy 340.299548 -265.262614) (xy 340.561168 -265.262614)
		)
		(stroke
			(width 0)
			(type solid)
		)
		(fill yes)
		(layer "In6.Cu")
		(net "M_C_CPU0_SA_DQS_DN<8>")
	)
	(gr_poly
		(pts
			(xy 340.608158 -260.634734) (xy 340.561168 -260.482334) (xy 340.299548 -260.482334) (xy 340.252558 -260.634734)
			(xy 340.252558 -260.679184) (xy 340.608158 -260.679184)
		)
		(stroke
			(width 0)
			(type solid)
		)
		(fill yes)
		(layer "In6.Cu")
		(net "M_C_CPU0_SA_DQS_DP<9>")
	)
	(gr_poly
		(pts
			(xy 340.608158 -260.22681) (xy 340.608158 -260.18236) (xy 340.252558 -260.18236) (xy 340.252558 -260.22681)
			(xy 340.299548 -260.37921) (xy 340.561168 -260.37921)
		)
		(stroke
			(width 0)
			(type solid)
		)
		(fill yes)
		(layer "In6.Cu")
		(net "M_C_CPU0_SA_DQS_DP<4>")
	)
	(gr_poly
		(pts
			(xy 340.608158 -256.971038) (xy 340.608158 -256.926588) (xy 340.252558 -256.926588) (xy 340.252558 -256.971038)
			(xy 340.299548 -257.123438) (xy 340.561168 -257.123438)
		)
		(stroke
			(width 0)
			(type solid)
		)
		(fill yes)
		(layer "In6.Cu")
		(net "M_D_CPU0_SA_RSP<0>")
	)
	(gr_poly
		(pts
			(xy 340.608158 -255.751838) (xy 340.561168 -255.599438) (xy 340.299548 -255.599438) (xy 340.252558 -255.751838)
			(xy 340.252558 -255.796034) (xy 340.608158 -255.796034)
		)
		(stroke
			(width 0)
			(type solid)
		)
		(fill yes)
		(layer "In6.Cu")
		(net "M_D_CPU0_SB_RSP<1>")
	)
	(gr_poly
		(pts
			(xy 340.608158 -255.343406) (xy 340.608158 -255.29921) (xy 340.252558 -255.29921) (xy 340.252558 -255.343406)
			(xy 340.299548 -255.495806) (xy 340.561168 -255.495806)
		)
		(stroke
			(width 0)
			(type solid)
		)
		(fill yes)
		(layer "In6.Cu")
		(net "M_C_CPU0_SA_RSP<0>")
	)
	(gr_poly
		(pts
			(xy 340.610698 -276.912578) (xy 340.563708 -276.760178) (xy 340.302088 -276.760178) (xy 340.255098 -276.912578)
			(xy 340.255098 -276.957028) (xy 340.610698 -276.957028)
		)
		(stroke
			(width 0)
			(type solid)
		)
		(fill yes)
		(layer "In6.Cu")
		(net "M_D_CPU0_SA_DQ<2>")
	)
	(gr_poly
		(pts
			(xy 340.610698 -276.5044) (xy 340.610698 -276.460204) (xy 340.255098 -276.460204) (xy 340.255098 -276.5044)
			(xy 340.302088 -276.6568) (xy 340.563708 -276.6568)
		)
		(stroke
			(width 0)
			(type solid)
		)
		(fill yes)
		(layer "In6.Cu")
		(net "M_D_CPU0_SA_DQ<1>")
	)
	(gr_poly
		(pts
			(xy 340.610698 -273.657314) (xy 340.563708 -273.504914) (xy 340.302088 -273.504914) (xy 340.255098 -273.657314)
			(xy 340.255098 -273.70151) (xy 340.610698 -273.70151)
		)
		(stroke
			(width 0)
			(type solid)
		)
		(fill yes)
		(layer "In6.Cu")
		(net "M_D_CPU0_SA_DQ<6>")
	)
	(gr_poly
		(pts
			(xy 340.610698 -273.248882) (xy 340.610698 -273.204686) (xy 340.255098 -273.204686) (xy 340.255098 -273.248882)
			(xy 340.302088 -273.401282) (xy 340.563708 -273.401282)
		)
		(stroke
			(width 0)
			(type solid)
		)
		(fill yes)
		(layer "In6.Cu")
		(net "M_D_CPU0_SA_DQ<5>")
	)
	(gr_poly
		(pts
			(xy 340.610698 -272.029174) (xy 340.563708 -271.876774) (xy 340.302088 -271.876774) (xy 340.255098 -272.029174)
			(xy 340.255098 -272.073624) (xy 340.610698 -272.073624)
		)
		(stroke
			(width 0)
			(type solid)
		)
		(fill yes)
		(layer "In6.Cu")
		(net "M_C_CPU0_SA_DQ<10>")
	)
	(gr_poly
		(pts
			(xy 340.610698 -271.62125) (xy 340.610698 -271.5768) (xy 340.255098 -271.5768) (xy 340.255098 -271.62125)
			(xy 340.302088 -271.77365) (xy 340.563708 -271.77365)
		)
		(stroke
			(width 0)
			(type solid)
		)
		(fill yes)
		(layer "In6.Cu")
		(net "M_C_CPU0_SA_DQ<9>")
	)
	(gr_poly
		(pts
			(xy 340.610698 -268.77391) (xy 340.563708 -268.62151) (xy 340.302088 -268.62151) (xy 340.255098 -268.77391)
			(xy 340.255098 -268.818106) (xy 340.610698 -268.818106)
		)
		(stroke
			(width 0)
			(type solid)
		)
		(fill yes)
		(layer "In6.Cu")
		(net "M_C_CPU0_SA_DQ<14>")
	)
	(gr_poly
		(pts
			(xy 340.610698 -268.365478) (xy 340.610698 -268.321282) (xy 340.255098 -268.321282) (xy 340.255098 -268.365478)
			(xy 340.302088 -268.517878) (xy 340.563708 -268.517878)
		)
		(stroke
			(width 0)
			(type solid)
		)
		(fill yes)
		(layer "In6.Cu")
		(net "M_C_CPU0_SA_DQ<13>")
	)
	(gr_poly
		(pts
			(xy 340.610698 -267.14577) (xy 340.563708 -266.99337) (xy 340.302088 -266.99337) (xy 340.255098 -267.14577)
			(xy 340.255098 -267.19022) (xy 340.610698 -267.19022)
		)
		(stroke
			(width 0)
			(type solid)
		)
		(fill yes)
		(layer "In6.Cu")
		(net "M_C_CPU0_SA_DQ<26>")
	)
	(gr_poly
		(pts
			(xy 340.610698 -266.737846) (xy 340.610698 -266.69365) (xy 340.255098 -266.69365) (xy 340.255098 -266.737846)
			(xy 340.302088 -266.890246) (xy 340.563708 -266.890246)
		)
		(stroke
			(width 0)
			(type solid)
		)
		(fill yes)
		(layer "In6.Cu")
		(net "M_C_CPU0_SA_DQ<25>")
	)
	(gr_poly
		(pts
			(xy 340.610698 -263.890506) (xy 340.563708 -263.738106) (xy 340.302088 -263.738106) (xy 340.255098 -263.890506)
			(xy 340.255098 -263.934956) (xy 340.610698 -263.934956)
		)
		(stroke
			(width 0)
			(type solid)
		)
		(fill yes)
		(layer "In6.Cu")
		(net "M_C_CPU0_SA_DQ<30>")
	)
	(gr_poly
		(pts
			(xy 340.610698 -262.262874) (xy 340.563708 -262.110474) (xy 340.302088 -262.110474) (xy 340.255098 -262.262874)
			(xy 340.255098 -262.30707) (xy 340.610698 -262.30707)
		)
		(stroke
			(width 0)
			(type solid)
		)
		(fill yes)
		(layer "In6.Cu")
		(net "M_C_CPU0_SA_CB<0>")
	)
	(gr_poly
		(pts
			(xy 340.610698 -261.854442) (xy 340.610698 -261.810246) (xy 340.255098 -261.810246) (xy 340.255098 -261.854442)
			(xy 340.302088 -262.006842) (xy 340.563708 -262.006842)
		)
		(stroke
			(width 0)
			(type solid)
		)
		(fill yes)
		(layer "In6.Cu")
		(net "M_C_CPU0_SA_CB<3>")
	)
	(gr_poly
		(pts
			(xy 340.610698 -259.007102) (xy 340.563708 -258.854702) (xy 340.302088 -258.854702) (xy 340.255098 -259.007102)
			(xy 340.255098 -259.051552) (xy 340.610698 -259.051552)
		)
		(stroke
			(width 0)
			(type solid)
		)
		(fill yes)
		(layer "In6.Cu")
		(net "M_C_CPU0_SA_CB<4>")
	)
	(gr_poly
		(pts
			(xy 340.610698 -254.123698) (xy 340.563708 -253.971298) (xy 340.302088 -253.971298) (xy 340.255098 -254.123698)
			(xy 340.255098 -254.168148) (xy 340.610698 -254.168148)
		)
		(stroke
			(width 0)
			(type solid)
		)
		(fill yes)
		(layer "In6.Cu")
		(net "M_C_CPU0_SB_RSP<1>")
	)
	(gr_poly
		(pts
			(xy 340.817962 -227.293932) (xy 340.856316 -227.271834) (xy 340.678516 -226.963986) (xy 340.640162 -226.986084)
			(xy 340.531704 -227.102924) (xy 340.662514 -227.329492)
		)
		(stroke
			(width 0)
			(type solid)
		)
		(fill yes)
		(layer "In6.Cu")
		(net "M_C_CPU0_SB_DQS_DN<8>")
	)
	(gr_poly
		(pts
			(xy 340.928706 -226.676204) (xy 341.037164 -226.559364) (xy 340.906354 -226.332796) (xy 340.750906 -226.368356)
			(xy 340.712552 -226.390454) (xy 340.890352 -226.698302)
		)
		(stroke
			(width 0)
			(type solid)
		)
		(fill yes)
		(layer "In6.Cu")
		(net "M_C_CPU0_SB_DQS_DP<8>")
	)
	(gr_poly
		(pts
			(xy 340.953598 -248.196354) (xy 340.906608 -248.043954) (xy 340.644988 -248.043954) (xy 340.597998 -248.196354)
			(xy 340.597998 -248.24055) (xy 340.953598 -248.24055)
		)
		(stroke
			(width 0)
			(type solid)
		)
		(fill yes)
		(layer "In6.Cu")
		(net "M_A_CPU0_SA_RSP<0>")
	)
	(gr_poly
		(pts
			(xy 340.953598 -247.787922) (xy 340.953598 -247.743726) (xy 340.597998 -247.743726) (xy 340.597998 -247.787922)
			(xy 340.644988 -247.940322) (xy 340.906608 -247.940322)
		)
		(stroke
			(width 0)
			(type solid)
		)
		(fill yes)
		(layer "In6.Cu")
		(net "M_A_CPU0_SA_RSP<1>")
	)
	(gr_poly
		(pts
			(xy 340.953598 -242.905026) (xy 340.953598 -242.860576) (xy 340.597998 -242.860576) (xy 340.597998 -242.905026)
			(xy 340.644988 -243.057426) (xy 340.906608 -243.057426)
		)
		(stroke
			(width 0)
			(type solid)
		)
		(fill yes)
		(layer "In6.Cu")
		(net "M_C_CPU0_SB_DQS_DP<0>")
	)
	(gr_poly
		(pts
			(xy 340.953598 -241.685318) (xy 340.906608 -241.532918) (xy 340.644988 -241.532918) (xy 340.597998 -241.685318)
			(xy 340.597998 -241.729514) (xy 340.953598 -241.729514)
		)
		(stroke
			(width 0)
			(type solid)
		)
		(fill yes)
		(layer "In6.Cu")
		(net "M_C_CPU0_SB_DQS_DP<5>")
	)
	(gr_poly
		(pts
			(xy 340.953598 -241.276886) (xy 340.953598 -241.23269) (xy 340.597998 -241.23269) (xy 340.597998 -241.276886)
			(xy 340.644988 -241.429286) (xy 340.906608 -241.429286)
		)
		(stroke
			(width 0)
			(type solid)
		)
		(fill yes)
		(layer "In6.Cu")
		(net "M_C_CPU0_SB_DQ<4>")
	)
	(gr_poly
		(pts
			(xy 340.953598 -240.057178) (xy 340.906608 -239.904778) (xy 340.644988 -239.904778) (xy 340.597998 -240.057178)
			(xy 340.597998 -240.101628) (xy 340.953598 -240.101628)
		)
		(stroke
			(width 0)
			(type solid)
		)
		(fill yes)
		(layer "In6.Cu")
		(net "M_C_CPU0_SB_DQ<7>")
	)
	(gr_poly
		(pts
			(xy 340.953598 -239.649254) (xy 340.953598 -239.604804) (xy 340.597998 -239.604804) (xy 340.597998 -239.649254)
			(xy 340.644988 -239.801654) (xy 340.906608 -239.801654)
		)
		(stroke
			(width 0)
			(type solid)
		)
		(fill yes)
		(layer "In6.Cu")
		(net "M_C_CPU0_SB_DQ<8>")
	)
	(gr_poly
		(pts
			(xy 340.953598 -238.429546) (xy 340.906608 -238.277146) (xy 340.644988 -238.277146) (xy 340.597998 -238.429546)
			(xy 340.597998 -238.473996) (xy 340.953598 -238.473996)
		)
		(stroke
			(width 0)
			(type solid)
		)
		(fill yes)
		(layer "In6.Cu")
		(net "M_C_CPU0_SB_DQ<11>")
	)
	(gr_poly
		(pts
			(xy 340.953598 -238.021622) (xy 340.953598 -237.977172) (xy 340.597998 -237.977172) (xy 340.597998 -238.021622)
			(xy 340.644988 -238.174022) (xy 340.906608 -238.174022)
		)
		(stroke
			(width 0)
			(type solid)
		)
		(fill yes)
		(layer "In6.Cu")
		(net "M_C_CPU0_SB_DQS_DP<1>")
	)
	(gr_poly
		(pts
			(xy 340.953598 -236.801914) (xy 340.906608 -236.649514) (xy 340.644988 -236.649514) (xy 340.597998 -236.801914)
			(xy 340.597998 -236.84611) (xy 340.953598 -236.84611)
		)
		(stroke
			(width 0)
			(type solid)
		)
		(fill yes)
		(layer "In6.Cu")
		(net "M_C_CPU0_SB_DQS_DP<6>")
	)
	(gr_poly
		(pts
			(xy 340.953598 -236.39399) (xy 340.953598 -236.34954) (xy 340.597998 -236.34954) (xy 340.597998 -236.39399)
			(xy 340.644988 -236.54639) (xy 340.906608 -236.54639)
		)
		(stroke
			(width 0)
			(type solid)
		)
		(fill yes)
		(layer "In6.Cu")
		(net "M_C_CPU0_SB_DQ<12>")
	)
	(gr_poly
		(pts
			(xy 340.953598 -235.174282) (xy 340.906608 -235.021882) (xy 340.644988 -235.021882) (xy 340.597998 -235.174282)
			(xy 340.597998 -235.218478) (xy 340.953598 -235.218478)
		)
		(stroke
			(width 0)
			(type solid)
		)
		(fill yes)
		(layer "In6.Cu")
		(net "M_C_CPU0_SB_DQ<15>")
	)
	(gr_poly
		(pts
			(xy 340.953598 -234.76585) (xy 340.953598 -234.721654) (xy 340.597998 -234.721654) (xy 340.597998 -234.76585)
			(xy 340.644988 -234.91825) (xy 340.906608 -234.91825)
		)
		(stroke
			(width 0)
			(type solid)
		)
		(fill yes)
		(layer "In6.Cu")
		(net "M_D_CPU0_SB_DQ<16>")
	)
	(gr_poly
		(pts
			(xy 340.953598 -233.546142) (xy 340.906608 -233.393742) (xy 340.644988 -233.393742) (xy 340.597998 -233.546142)
			(xy 340.597998 -233.590592) (xy 340.953598 -233.590592)
		)
		(stroke
			(width 0)
			(type solid)
		)
		(fill yes)
		(layer "In6.Cu")
		(net "M_D_CPU0_SB_DQ<19>")
	)
	(gr_poly
		(pts
			(xy 340.953598 -233.138218) (xy 340.953598 -233.093768) (xy 340.597998 -233.093768) (xy 340.597998 -233.138218)
			(xy 340.644988 -233.290618) (xy 340.906608 -233.290618)
		)
		(stroke
			(width 0)
			(type solid)
		)
		(fill yes)
		(layer "In6.Cu")
		(net "M_D_CPU0_SB_DQS_DP<2>")
	)
	(gr_poly
		(pts
			(xy 340.953598 -231.91851) (xy 340.906608 -231.76611) (xy 340.644988 -231.76611) (xy 340.597998 -231.91851)
			(xy 340.597998 -231.96296) (xy 340.953598 -231.96296)
		)
		(stroke
			(width 0)
			(type solid)
		)
		(fill yes)
		(layer "In6.Cu")
		(net "M_D_CPU0_SB_DQS_DP<7>")
	)
	(gr_poly
		(pts
			(xy 340.953598 -231.510586) (xy 340.953598 -231.466136) (xy 340.597998 -231.466136) (xy 340.597998 -231.510586)
			(xy 340.644988 -231.662986) (xy 340.906608 -231.662986)
		)
		(stroke
			(width 0)
			(type solid)
		)
		(fill yes)
		(layer "In6.Cu")
		(net "M_D_CPU0_SB_DQ<20>")
	)
	(gr_poly
		(pts
			(xy 340.953598 -230.290878) (xy 340.906608 -230.138478) (xy 340.644988 -230.138478) (xy 340.597998 -230.290878)
			(xy 340.597998 -230.335074) (xy 340.953598 -230.335074)
		)
		(stroke
			(width 0)
			(type solid)
		)
		(fill yes)
		(layer "In6.Cu")
		(net "M_D_CPU0_SB_DQ<23>")
	)
	(gr_poly
		(pts
			(xy 340.953598 -229.882446) (xy 340.953598 -229.83825) (xy 340.597998 -229.83825) (xy 340.597998 -229.882446)
			(xy 340.644988 -230.034846) (xy 340.906608 -230.034846)
		)
		(stroke
			(width 0)
			(type solid)
		)
		(fill yes)
		(layer "In6.Cu")
		(net "M_C_CPU0_SB_DQ<26>")
	)
	(gr_poly
		(pts
			(xy 340.953598 -228.663246) (xy 340.906608 -228.510846) (xy 340.644988 -228.510846) (xy 340.597998 -228.663246)
			(xy 340.597998 -228.707442) (xy 340.953598 -228.707442)
		)
		(stroke
			(width 0)
			(type solid)
		)
		(fill yes)
		(layer "In6.Cu")
		(net "M_C_CPU0_SB_DQ<27>")
	)
	(gr_poly
		(pts
			(xy 340.953598 -228.254814) (xy 340.953598 -228.210618) (xy 340.597998 -228.210618) (xy 340.597998 -228.254814)
			(xy 340.644988 -228.407214) (xy 340.906608 -228.407214)
		)
		(stroke
			(width 0)
			(type solid)
		)
		(fill yes)
		(layer "In6.Cu")
		(net "M_C_CPU0_SB_DQS_DP<3>")
	)
	(gr_poly
		(pts
			(xy 340.953598 -225.407474) (xy 340.906608 -225.255074) (xy 340.644988 -225.255074) (xy 340.597998 -225.407474)
			(xy 340.597998 -225.45167) (xy 340.953598 -225.45167)
		)
		(stroke
			(width 0)
			(type solid)
		)
		(fill yes)
		(layer "In6.Cu")
		(net "M_C_CPU0_SB_DQ<30>")
	)
	(gr_poly
		(pts
			(xy 340.956138 -244.53215) (xy 340.956138 -244.487954) (xy 340.600538 -244.487954) (xy 340.600538 -244.53215)
			(xy 340.647528 -244.68455) (xy 340.909148 -244.68455)
		)
		(stroke
			(width 0)
			(type solid)
		)
		(fill yes)
		(layer "In6.Cu")
		(net "M_C_CPU0_SB_DQ<0>")
	)
	(gr_poly
		(pts
			(xy 340.96198 -246.16029) (xy 340.96198 -246.11584) (xy 340.60638 -246.11584) (xy 340.60638 -246.16029)
			(xy 340.65337 -246.31269) (xy 340.91499 -246.31269)
		)
		(stroke
			(width 0)
			(type solid)
		)
		(fill yes)
		(layer "In6.Cu")
		(net "M_D_CPU0_SB_CS_N<2>")
	)
	(gr_poly
		(pts
			(xy 340.965536 -243.313458) (xy 340.918546 -243.161058) (xy 340.656926 -243.161058) (xy 340.609936 -243.313458)
			(xy 340.609936 -243.357654) (xy 340.965536 -243.357654)
		)
		(stroke
			(width 0)
			(type solid)
		)
		(fill yes)
		(layer "In6.Cu")
		(net "M_C_CPU0_SB_DQ<3>")
	)
	(gr_poly
		(pts
			(xy 340.968076 -244.94109) (xy 340.921086 -244.78869) (xy 340.659466 -244.78869) (xy 340.612476 -244.94109)
			(xy 340.612476 -244.985286) (xy 340.968076 -244.985286)
		)
		(stroke
			(width 0)
			(type solid)
		)
		(fill yes)
		(layer "In6.Cu")
		(net "M_D_CPU0_SB_CS_N<1>")
	)
	(gr_poly
		(pts
			(xy 341.06358 -277.318216) (xy 341.06358 -277.27402) (xy 340.70798 -277.27402) (xy 340.70798 -277.318216)
			(xy 340.75497 -277.470616) (xy 341.01659 -277.470616)
		)
		(stroke
			(width 0)
			(type solid)
		)
		(fill yes)
		(layer "In6.Cu")
		(net "M_D_CPU0_SA_DQ<0>")
	)
	(gr_poly
		(pts
			(xy 341.06358 -276.098762) (xy 341.01659 -275.946362) (xy 340.75497 -275.946362) (xy 340.70798 -276.098762)
			(xy 340.70798 -276.143212) (xy 341.06358 -276.143212)
		)
		(stroke
			(width 0)
			(type solid)
		)
		(fill yes)
		(layer "In6.Cu")
		(net "M_D_CPU0_SA_DQ<3>")
	)
	(gr_poly
		(pts
			(xy 341.06358 -275.690584) (xy 341.06358 -275.646388) (xy 340.70798 -275.646388) (xy 340.70798 -275.690584)
			(xy 340.75497 -275.842984) (xy 341.01659 -275.842984)
		)
		(stroke
			(width 0)
			(type solid)
		)
		(fill yes)
		(layer "In6.Cu")
		(net "M_D_CPU0_SA_DQS_DP<0>")
	)
	(gr_poly
		(pts
			(xy 341.06358 -274.47113) (xy 341.01659 -274.31873) (xy 340.75497 -274.31873) (xy 340.70798 -274.47113)
			(xy 340.70798 -274.515326) (xy 341.06358 -274.515326)
		)
		(stroke
			(width 0)
			(type solid)
		)
		(fill yes)
		(layer "In6.Cu")
		(net "M_D_CPU0_SA_DQS_DP<5>")
	)
	(gr_poly
		(pts
			(xy 341.06358 -274.062698) (xy 341.06358 -274.018502) (xy 340.70798 -274.018502) (xy 340.70798 -274.062698)
			(xy 340.75497 -274.215098) (xy 341.01659 -274.215098)
		)
		(stroke
			(width 0)
			(type solid)
		)
		(fill yes)
		(layer "In6.Cu")
		(net "M_D_CPU0_SA_DQ<4>")
	)
	(gr_poly
		(pts
			(xy 341.06358 -272.843498) (xy 341.01659 -272.691098) (xy 340.75497 -272.691098) (xy 340.70798 -272.843498)
			(xy 340.70798 -272.887694) (xy 341.06358 -272.887694)
		)
		(stroke
			(width 0)
			(type solid)
		)
		(fill yes)
		(layer "In6.Cu")
		(net "M_D_CPU0_SA_DQ<7>")
	)
	(gr_poly
		(pts
			(xy 341.06358 -272.435066) (xy 341.06358 -272.39087) (xy 340.70798 -272.39087) (xy 340.70798 -272.435066)
			(xy 340.75497 -272.587466) (xy 341.01659 -272.587466)
		)
		(stroke
			(width 0)
			(type solid)
		)
		(fill yes)
		(layer "In6.Cu")
		(net "M_C_CPU0_SA_DQ<8>")
	)
	(gr_poly
		(pts
			(xy 341.06358 -271.215358) (xy 341.01659 -271.062958) (xy 340.75497 -271.062958) (xy 340.70798 -271.215358)
			(xy 340.70798 -271.259808) (xy 341.06358 -271.259808)
		)
		(stroke
			(width 0)
			(type solid)
		)
		(fill yes)
		(layer "In6.Cu")
		(net "M_C_CPU0_SA_DQ<11>")
	)
	(gr_poly
		(pts
			(xy 341.06358 -270.807434) (xy 341.06358 -270.762984) (xy 340.70798 -270.762984) (xy 340.70798 -270.807434)
			(xy 340.75497 -270.959834) (xy 341.01659 -270.959834)
		)
		(stroke
			(width 0)
			(type solid)
		)
		(fill yes)
		(layer "In6.Cu")
		(net "M_C_CPU0_SA_DQS_DP<1>")
	)
	(gr_poly
		(pts
			(xy 341.06358 -269.587726) (xy 341.01659 -269.435326) (xy 340.75497 -269.435326) (xy 340.70798 -269.587726)
			(xy 340.70798 -269.631922) (xy 341.06358 -269.631922)
		)
		(stroke
			(width 0)
			(type solid)
		)
		(fill yes)
		(layer "In6.Cu")
		(net "M_C_CPU0_SA_DQS_DP<6>")
	)
	(gr_poly
		(pts
			(xy 341.06358 -269.179294) (xy 341.06358 -269.135098) (xy 340.70798 -269.135098) (xy 340.70798 -269.179294)
			(xy 340.75497 -269.331694) (xy 341.01659 -269.331694)
		)
		(stroke
			(width 0)
			(type solid)
		)
		(fill yes)
		(layer "In6.Cu")
		(net "M_C_CPU0_SA_DQ<12>")
	)
	(gr_poly
		(pts
			(xy 341.06358 -267.960094) (xy 341.01659 -267.807694) (xy 340.75497 -267.807694) (xy 340.70798 -267.960094)
			(xy 340.70798 -268.00429) (xy 341.06358 -268.00429)
		)
		(stroke
			(width 0)
			(type solid)
		)
		(fill yes)
		(layer "In6.Cu")
		(net "M_C_CPU0_SA_DQ<15>")
	)
	(gr_poly
		(pts
			(xy 341.06358 -267.551662) (xy 341.06358 -267.507466) (xy 340.70798 -267.507466) (xy 340.70798 -267.551662)
			(xy 340.75497 -267.704062) (xy 341.01659 -267.704062)
		)
		(stroke
			(width 0)
			(type solid)
		)
		(fill yes)
		(layer "In6.Cu")
		(net "M_C_CPU0_SA_DQ<24>")
	)
	(gr_poly
		(pts
			(xy 341.06358 -266.331954) (xy 341.01659 -266.179554) (xy 340.75497 -266.179554) (xy 340.70798 -266.331954)
			(xy 340.70798 -266.376404) (xy 341.06358 -266.376404)
		)
		(stroke
			(width 0)
			(type solid)
		)
		(fill yes)
		(layer "In6.Cu")
		(net "M_C_CPU0_SA_DQ<27>")
	)
	(gr_poly
		(pts
			(xy 341.06358 -265.92403) (xy 341.06358 -265.879834) (xy 340.70798 -265.879834) (xy 340.70798 -265.92403)
			(xy 340.75497 -266.07643) (xy 341.01659 -266.07643)
		)
		(stroke
			(width 0)
			(type solid)
		)
		(fill yes)
		(layer "In6.Cu")
		(net "M_C_CPU0_SA_DQS_DP<3>")
	)
	(gr_poly
		(pts
			(xy 341.06358 -264.704322) (xy 341.01659 -264.551922) (xy 340.75497 -264.551922) (xy 340.70798 -264.704322)
			(xy 340.70798 -264.748772) (xy 341.06358 -264.748772)
		)
		(stroke
			(width 0)
			(type solid)
		)
		(fill yes)
		(layer "In6.Cu")
		(net "M_C_CPU0_SA_DQS_DP<8>")
	)
	(gr_poly
		(pts
			(xy 341.06358 -264.296398) (xy 341.06358 -264.251948) (xy 340.70798 -264.251948) (xy 340.70798 -264.296398)
			(xy 340.75497 -264.448798) (xy 341.01659 -264.448798)
		)
		(stroke
			(width 0)
			(type solid)
		)
		(fill yes)
		(layer "In6.Cu")
		(net "M_C_CPU0_SA_DQ<28>")
	)
	(gr_poly
		(pts
			(xy 341.06358 -262.668258) (xy 341.06358 -262.624062) (xy 340.70798 -262.624062) (xy 340.70798 -262.668258)
			(xy 340.75497 -262.820658) (xy 341.01659 -262.820658)
		)
		(stroke
			(width 0)
			(type solid)
		)
		(fill yes)
		(layer "In6.Cu")
		(net "M_C_CPU0_SA_CB<2>")
	)
	(gr_poly
		(pts
			(xy 341.06358 -261.449058) (xy 341.01659 -261.296658) (xy 340.75497 -261.296658) (xy 340.70798 -261.449058)
			(xy 340.70798 -261.493254) (xy 341.06358 -261.493254)
		)
		(stroke
			(width 0)
			(type solid)
		)
		(fill yes)
		(layer "In6.Cu")
		(net "M_C_CPU0_SA_CB<1>")
	)
	(gr_poly
		(pts
			(xy 341.06358 -261.040626) (xy 341.06358 -260.99643) (xy 340.70798 -260.99643) (xy 340.70798 -261.040626)
			(xy 340.75497 -261.193026) (xy 341.01659 -261.193026)
		)
		(stroke
			(width 0)
			(type solid)
		)
		(fill yes)
		(layer "In6.Cu")
		(net "M_C_CPU0_SA_DQS_DN<9>")
	)
	(gr_poly
		(pts
			(xy 341.06358 -259.820918) (xy 341.01659 -259.668518) (xy 340.75497 -259.668518) (xy 340.70798 -259.820918)
			(xy 340.70798 -259.865368) (xy 341.06358 -259.865368)
		)
		(stroke
			(width 0)
			(type solid)
		)
		(fill yes)
		(layer "In6.Cu")
		(net "M_C_CPU0_SA_DQS_DN<4>")
	)
	(gr_poly
		(pts
			(xy 341.06358 -259.412994) (xy 341.06358 -259.368544) (xy 340.70798 -259.368544) (xy 340.70798 -259.412994)
			(xy 340.75497 -259.565394) (xy 341.01659 -259.565394)
		)
		(stroke
			(width 0)
			(type solid)
		)
		(fill yes)
		(layer "In6.Cu")
		(net "M_C_CPU0_SA_CB<6>")
	)
	(gr_poly
		(pts
			(xy 341.06358 -256.157222) (xy 341.06358 -256.113026) (xy 340.70798 -256.113026) (xy 340.70798 -256.157222)
			(xy 340.75497 -256.309622) (xy 341.01659 -256.309622)
		)
		(stroke
			(width 0)
			(type solid)
		)
		(fill yes)
		(layer "In6.Cu")
		(net "M_D_CPU0_SA_RSP<1>")
	)
	(gr_poly
		(pts
			(xy 341.06358 -254.937514) (xy 341.01659 -254.785114) (xy 340.75497 -254.785114) (xy 340.70798 -254.937514)
			(xy 340.70798 -254.981964) (xy 341.06358 -254.981964)
		)
		(stroke
			(width 0)
			(type solid)
		)
		(fill yes)
		(layer "In6.Cu")
		(net "M_C_CPU0_SB_RSP<0>")
	)
	(gr_poly
		(pts
			(xy 341.06358 -254.52959) (xy 341.06358 -254.48514) (xy 340.70798 -254.48514) (xy 340.70798 -254.52959)
			(xy 340.75497 -254.68199) (xy 341.01659 -254.68199)
		)
		(stroke
			(width 0)
			(type solid)
		)
		(fill yes)
		(layer "In6.Cu")
		(net "M_C_CPU0_SA_RSP<1>")
	)
	(gr_poly
		(pts
			(xy 341.06612 -258.193286) (xy 341.01913 -258.040886) (xy 340.75751 -258.040886) (xy 340.71052 -258.193286)
			(xy 340.71052 -258.237736) (xy 341.06612 -258.237736)
		)
		(stroke
			(width 0)
			(type solid)
		)
		(fill yes)
		(layer "In6.Cu")
		(net "M_C_CPU0_SA_CB<5>")
	)
	(gr_poly
		(pts
			(xy 341.071962 -256.565654) (xy 341.024972 -256.413254) (xy 340.763352 -256.413254) (xy 340.716362 -256.565654)
			(xy 340.716362 -256.610104) (xy 341.071962 -256.610104)
		)
		(stroke
			(width 0)
			(type solid)
		)
		(fill yes)
		(layer "In6.Cu")
		(net "M_D_CPU0_SB_RSP<0>")
	)
	(gr_poly
		(pts
			(xy 341.075518 -263.077198) (xy 341.028528 -262.924798) (xy 340.766908 -262.924798) (xy 340.719918 -263.077198)
			(xy 340.719918 -263.121394) (xy 341.075518 -263.121394)
		)
		(stroke
			(width 0)
			(type solid)
		)
		(fill yes)
		(layer "In6.Cu")
		(net "M_C_CPU0_SA_DQ<31>")
	)
	(gr_poly
		(pts
			(xy 341.287862 -226.480116) (xy 341.326216 -226.458018) (xy 341.148416 -226.15017) (xy 341.110062 -226.172268)
			(xy 341.001604 -226.289108) (xy 341.132414 -226.515676)
		)
		(stroke
			(width 0)
			(type solid)
		)
		(fill yes)
		(layer "In6.Cu")
		(net "M_C_CPU0_SB_DQ<28>")
	)
	(gr_poly
		(pts
			(xy 341.288878 -224.85477) (xy 341.327232 -224.832672) (xy 341.149432 -224.524824) (xy 341.111078 -224.546922)
			(xy 341.00262 -224.663762) (xy 341.13343 -224.89033)
		)
		(stroke
			(width 0)
			(type solid)
		)
		(fill yes)
		(layer "In6.Cu")
		(net "M_C_CPU0_SB_DQ<31>")
	)
	(gr_poly
		(pts
			(xy 341.39759 -225.860356) (xy 341.506048 -225.743516) (xy 341.375238 -225.516948) (xy 341.21979 -225.552508)
			(xy 341.181436 -225.574606) (xy 341.359236 -225.882454)
		)
		(stroke
			(width 0)
			(type solid)
		)
		(fill yes)
		(layer "In6.Cu")
		(net "M_C_CPU0_SB_DQ<30>")
	)
	(gr_poly
		(pts
			(xy 341.39759 -224.231962) (xy 341.506048 -224.115122) (xy 341.375238 -223.888554) (xy 341.21979 -223.924114)
			(xy 341.181436 -223.946212) (xy 341.359236 -224.25406)
		)
		(stroke
			(width 0)
			(type solid)
		)
		(fill yes)
		(layer "In6.Cu")
		(net "M_C_CPU0_SB_DQ<29>")
	)
	(gr_poly
		(pts
			(xy 341.428578 -243.718334) (xy 341.428578 -243.674138) (xy 341.072978 -243.674138) (xy 341.072978 -243.718334)
			(xy 341.119968 -243.870734) (xy 341.381588 -243.870734)
		)
		(stroke
			(width 0)
			(type solid)
		)
		(fill yes)
		(layer "In6.Cu")
		(net "M_C_CPU0_SB_DQ<1>")
	)
	(gr_poly
		(pts
			(xy 341.437976 -245.754906) (xy 341.390986 -245.602506) (xy 341.129366 -245.602506) (xy 341.082376 -245.754906)
			(xy 341.082376 -245.799102) (xy 341.437976 -245.799102)
		)
		(stroke
			(width 0)
			(type solid)
		)
		(fill yes)
		(layer "In6.Cu")
		(net "M_D_CPU0_SB_CS_N<3>")
	)
	(gr_poly
		(pts
			(xy 341.437976 -245.346474) (xy 341.437976 -245.302278) (xy 341.082376 -245.302278) (xy 341.082376 -245.346474)
			(xy 341.129366 -245.498874) (xy 341.390986 -245.498874)
		)
		(stroke
			(width 0)
			(type solid)
		)
		(fill yes)
		(layer "In6.Cu")
		(net "M_D_CPU0_SB_CS_N<0>")
	)
	(gr_poly
		(pts
			(xy 341.440516 -248.602246) (xy 341.440516 -248.557796) (xy 341.084916 -248.557796) (xy 341.084916 -248.602246)
			(xy 341.131906 -248.754646) (xy 341.393526 -248.754646)
		)
		(stroke
			(width 0)
			(type solid)
		)
		(fill yes)
		(layer "In6.Cu")
		(net "M_A_CPU0_SB_RSP<0>")
	)
	(gr_poly
		(pts
			(xy 341.440516 -247.382538) (xy 341.393526 -247.230138) (xy 341.131906 -247.230138) (xy 341.084916 -247.382538)
			(xy 341.084916 -247.426734) (xy 341.440516 -247.426734)
		)
		(stroke
			(width 0)
			(type solid)
		)
		(fill yes)
		(layer "In6.Cu")
		(net "M_A_CPU0_SB_RSP<1>")
	)
	(gr_poly
		(pts
			(xy 341.440516 -244.126766) (xy 341.393526 -243.974366) (xy 341.131906 -243.974366) (xy 341.084916 -244.126766)
			(xy 341.084916 -244.171216) (xy 341.440516 -244.171216)
		)
		(stroke
			(width 0)
			(type solid)
		)
		(fill yes)
		(layer "In6.Cu")
		(net "M_C_CPU0_SB_DQ<2>")
	)
	(gr_poly
		(pts
			(xy 341.440516 -242.499134) (xy 341.393526 -242.346734) (xy 341.131906 -242.346734) (xy 341.084916 -242.499134)
			(xy 341.084916 -242.54333) (xy 341.440516 -242.54333)
		)
		(stroke
			(width 0)
			(type solid)
		)
		(fill yes)
		(layer "In6.Cu")
		(net "M_C_CPU0_SB_DQS_DN<0>")
	)
	(gr_poly
		(pts
			(xy 341.440516 -242.090702) (xy 341.440516 -242.046506) (xy 341.084916 -242.046506) (xy 341.084916 -242.090702)
			(xy 341.131906 -242.243102) (xy 341.393526 -242.243102)
		)
		(stroke
			(width 0)
			(type solid)
		)
		(fill yes)
		(layer "In6.Cu")
		(net "M_C_CPU0_SB_DQS_DN<5>")
	)
	(gr_poly
		(pts
			(xy 341.440516 -240.871502) (xy 341.393526 -240.719102) (xy 341.131906 -240.719102) (xy 341.084916 -240.871502)
			(xy 341.084916 -240.915698) (xy 341.440516 -240.915698)
		)
		(stroke
			(width 0)
			(type solid)
		)
		(fill yes)
		(layer "In6.Cu")
		(net "M_C_CPU0_SB_DQ<6>")
	)
	(gr_poly
		(pts
			(xy 341.440516 -240.46307) (xy 341.440516 -240.418874) (xy 341.084916 -240.418874) (xy 341.084916 -240.46307)
			(xy 341.131906 -240.61547) (xy 341.393526 -240.61547)
		)
		(stroke
			(width 0)
			(type solid)
		)
		(fill yes)
		(layer "In6.Cu")
		(net "M_C_CPU0_SB_DQ<5>")
	)
	(gr_poly
		(pts
			(xy 341.440516 -239.243362) (xy 341.393526 -239.090962) (xy 341.131906 -239.090962) (xy 341.084916 -239.243362)
			(xy 341.084916 -239.287812) (xy 341.440516 -239.287812)
		)
		(stroke
			(width 0)
			(type solid)
		)
		(fill yes)
		(layer "In6.Cu")
		(net "M_C_CPU0_SB_DQ<10>")
	)
	(gr_poly
		(pts
			(xy 341.440516 -238.835438) (xy 341.440516 -238.790988) (xy 341.084916 -238.790988) (xy 341.084916 -238.835438)
			(xy 341.131906 -238.987838) (xy 341.393526 -238.987838)
		)
		(stroke
			(width 0)
			(type solid)
		)
		(fill yes)
		(layer "In6.Cu")
		(net "M_C_CPU0_SB_DQ<9>")
	)
	(gr_poly
		(pts
			(xy 341.440516 -237.61573) (xy 341.393526 -237.46333) (xy 341.131906 -237.46333) (xy 341.084916 -237.61573)
			(xy 341.084916 -237.659926) (xy 341.440516 -237.659926)
		)
		(stroke
			(width 0)
			(type solid)
		)
		(fill yes)
		(layer "In6.Cu")
		(net "M_C_CPU0_SB_DQS_DN<1>")
	)
	(gr_poly
		(pts
			(xy 341.440516 -237.207806) (xy 341.440516 -237.163356) (xy 341.084916 -237.163356) (xy 341.084916 -237.207806)
			(xy 341.131906 -237.360206) (xy 341.393526 -237.360206)
		)
		(stroke
			(width 0)
			(type solid)
		)
		(fill yes)
		(layer "In6.Cu")
		(net "M_C_CPU0_SB_DQS_DN<6>")
	)
	(gr_poly
		(pts
			(xy 341.440516 -235.988098) (xy 341.393526 -235.835698) (xy 341.131906 -235.835698) (xy 341.084916 -235.988098)
			(xy 341.084916 -236.032294) (xy 341.440516 -236.032294)
		)
		(stroke
			(width 0)
			(type solid)
		)
		(fill yes)
		(layer "In6.Cu")
		(net "M_C_CPU0_SB_DQ<14>")
	)
	(gr_poly
		(pts
			(xy 341.440516 -235.579666) (xy 341.440516 -235.53547) (xy 341.084916 -235.53547) (xy 341.084916 -235.579666)
			(xy 341.131906 -235.732066) (xy 341.393526 -235.732066)
		)
		(stroke
			(width 0)
			(type solid)
		)
		(fill yes)
		(layer "In6.Cu")
		(net "M_C_CPU0_SB_DQ<13>")
	)
	(gr_poly
		(pts
			(xy 341.440516 -234.360466) (xy 341.393526 -234.208066) (xy 341.131906 -234.208066) (xy 341.084916 -234.360466)
			(xy 341.084916 -234.404662) (xy 341.440516 -234.404662)
		)
		(stroke
			(width 0)
			(type solid)
		)
		(fill yes)
		(layer "In6.Cu")
		(net "M_D_CPU0_SB_DQ<18>")
	)
	(gr_poly
		(pts
			(xy 341.440516 -233.952034) (xy 341.440516 -233.907838) (xy 341.084916 -233.907838) (xy 341.084916 -233.952034)
			(xy 341.131906 -234.104434) (xy 341.393526 -234.104434)
		)
		(stroke
			(width 0)
			(type solid)
		)
		(fill yes)
		(layer "In6.Cu")
		(net "M_D_CPU0_SB_DQ<17>")
	)
	(gr_poly
		(pts
			(xy 341.440516 -232.732326) (xy 341.393526 -232.579926) (xy 341.131906 -232.579926) (xy 341.084916 -232.732326)
			(xy 341.084916 -232.776776) (xy 341.440516 -232.776776)
		)
		(stroke
			(width 0)
			(type solid)
		)
		(fill yes)
		(layer "In6.Cu")
		(net "M_D_CPU0_SB_DQS_DN<2>")
	)
	(gr_poly
		(pts
			(xy 341.440516 -232.324402) (xy 341.440516 -232.279952) (xy 341.084916 -232.279952) (xy 341.084916 -232.324402)
			(xy 341.131906 -232.476802) (xy 341.393526 -232.476802)
		)
		(stroke
			(width 0)
			(type solid)
		)
		(fill yes)
		(layer "In6.Cu")
		(net "M_D_CPU0_SB_DQS_DN<7>")
	)
	(gr_poly
		(pts
			(xy 341.440516 -231.104694) (xy 341.393526 -230.952294) (xy 341.131906 -230.952294) (xy 341.084916 -231.104694)
			(xy 341.084916 -231.14889) (xy 341.440516 -231.14889)
		)
		(stroke
			(width 0)
			(type solid)
		)
		(fill yes)
		(layer "In6.Cu")
		(net "M_D_CPU0_SB_DQ<22>")
	)
	(gr_poly
		(pts
			(xy 341.440516 -230.696262) (xy 341.440516 -230.652066) (xy 341.084916 -230.652066) (xy 341.084916 -230.696262)
			(xy 341.131906 -230.848662) (xy 341.393526 -230.848662)
		)
		(stroke
			(width 0)
			(type solid)
		)
		(fill yes)
		(layer "In6.Cu")
		(net "M_D_CPU0_SB_DQ<21>")
	)
	(gr_poly
		(pts
			(xy 341.440516 -229.477062) (xy 341.393526 -229.324662) (xy 341.131906 -229.324662) (xy 341.084916 -229.477062)
			(xy 341.084916 -229.521258) (xy 341.440516 -229.521258)
		)
		(stroke
			(width 0)
			(type solid)
		)
		(fill yes)
		(layer "In6.Cu")
		(net "M_C_CPU0_SB_DQ<24>")
	)
	(gr_poly
		(pts
			(xy 341.440516 -229.06863) (xy 341.440516 -229.024434) (xy 341.084916 -229.024434) (xy 341.084916 -229.06863)
			(xy 341.131906 -229.22103) (xy 341.393526 -229.22103)
		)
		(stroke
			(width 0)
			(type solid)
		)
		(fill yes)
		(layer "In6.Cu")
		(net "M_C_CPU0_SB_DQ<25>")
	)
	(gr_poly
		(pts
			(xy 341.440516 -227.848922) (xy 341.393526 -227.696522) (xy 341.131906 -227.696522) (xy 341.084916 -227.848922)
			(xy 341.084916 -227.893372) (xy 341.440516 -227.893372)
		)
		(stroke
			(width 0)
			(type solid)
		)
		(fill yes)
		(layer "In6.Cu")
		(net "M_C_CPU0_SB_DQS_DN<3>")
	)
	(gr_poly
		(pts
			(xy 341.440516 -227.440998) (xy 341.440516 -227.396548) (xy 341.084916 -227.396548) (xy 341.084916 -227.440998)
			(xy 341.131906 -227.593398) (xy 341.393526 -227.593398)
		)
		(stroke
			(width 0)
			(type solid)
		)
		(fill yes)
		(layer "In6.Cu")
		(net "M_C_CPU0_SB_DQS_DN<8>")
	)
	(gr_poly
		(pts
			(xy 341.53856 -263.482074) (xy 341.53856 -263.437624) (xy 341.18296 -263.437624) (xy 341.18296 -263.482074)
			(xy 341.22995 -263.634474) (xy 341.49157 -263.634474)
		)
		(stroke
			(width 0)
			(type solid)
		)
		(fill yes)
		(layer "In6.Cu")
		(net "M_C_CPU0_SA_DQ<29>")
	)
	(gr_poly
		(pts
			(xy 341.547958 -256.971038) (xy 341.547958 -256.926842) (xy 341.192358 -256.926842) (xy 341.192358 -256.971038)
			(xy 341.239348 -257.123438) (xy 341.500968 -257.123438)
		)
		(stroke
			(width 0)
			(type solid)
		)
		(fill yes)
		(layer "In6.Cu")
		(net "M_D_CPU0_SA_RSP<0>")
	)
	(gr_poly
		(pts
			(xy 341.550498 -276.912578) (xy 341.503508 -276.760178) (xy 341.241888 -276.760178) (xy 341.194898 -276.912578)
			(xy 341.194898 -276.957028) (xy 341.550498 -276.957028)
		)
		(stroke
			(width 0)
			(type solid)
		)
		(fill yes)
		(layer "In6.Cu")
		(net "M_D_CPU0_SA_DQ<2>")
	)
	(gr_poly
		(pts
			(xy 341.550498 -276.5044) (xy 341.550498 -276.460204) (xy 341.194898 -276.460204) (xy 341.194898 -276.5044)
			(xy 341.241888 -276.6568) (xy 341.503508 -276.6568)
		)
		(stroke
			(width 0)
			(type solid)
		)
		(fill yes)
		(layer "In6.Cu")
		(net "M_D_CPU0_SA_DQ<1>")
	)
	(gr_poly
		(pts
			(xy 341.550498 -275.284946) (xy 341.503508 -275.132546) (xy 341.241888 -275.132546) (xy 341.194898 -275.284946)
			(xy 341.194898 -275.329142) (xy 341.550498 -275.329142)
		)
		(stroke
			(width 0)
			(type solid)
		)
		(fill yes)
		(layer "In6.Cu")
		(net "M_D_CPU0_SA_DQS_DN<0>")
	)
	(gr_poly
		(pts
			(xy 341.550498 -274.876514) (xy 341.550498 -274.832318) (xy 341.194898 -274.832318) (xy 341.194898 -274.876514)
			(xy 341.241888 -275.028914) (xy 341.503508 -275.028914)
		)
		(stroke
			(width 0)
			(type solid)
		)
		(fill yes)
		(layer "In6.Cu")
		(net "M_D_CPU0_SA_DQS_DN<5>")
	)
	(gr_poly
		(pts
			(xy 341.550498 -273.657314) (xy 341.503508 -273.504914) (xy 341.241888 -273.504914) (xy 341.194898 -273.657314)
			(xy 341.194898 -273.70151) (xy 341.550498 -273.70151)
		)
		(stroke
			(width 0)
			(type solid)
		)
		(fill yes)
		(layer "In6.Cu")
		(net "M_D_CPU0_SA_DQ<6>")
	)
	(gr_poly
		(pts
			(xy 341.550498 -273.248882) (xy 341.550498 -273.204686) (xy 341.194898 -273.204686) (xy 341.194898 -273.248882)
			(xy 341.241888 -273.401282) (xy 341.503508 -273.401282)
		)
		(stroke
			(width 0)
			(type solid)
		)
		(fill yes)
		(layer "In6.Cu")
		(net "M_D_CPU0_SA_DQ<5>")
	)
	(gr_poly
		(pts
			(xy 341.550498 -272.029174) (xy 341.503508 -271.876774) (xy 341.241888 -271.876774) (xy 341.194898 -272.029174)
			(xy 341.194898 -272.073624) (xy 341.550498 -272.073624)
		)
		(stroke
			(width 0)
			(type solid)
		)
		(fill yes)
		(layer "In6.Cu")
		(net "M_C_CPU0_SA_DQ<10>")
	)
	(gr_poly
		(pts
			(xy 341.550498 -271.62125) (xy 341.550498 -271.5768) (xy 341.194898 -271.5768) (xy 341.194898 -271.62125)
			(xy 341.241888 -271.77365) (xy 341.503508 -271.77365)
		)
		(stroke
			(width 0)
			(type solid)
		)
		(fill yes)
		(layer "In6.Cu")
		(net "M_C_CPU0_SA_DQ<9>")
	)
	(gr_poly
		(pts
			(xy 341.550498 -270.401542) (xy 341.503508 -270.249142) (xy 341.241888 -270.249142) (xy 341.194898 -270.401542)
			(xy 341.194898 -270.445992) (xy 341.550498 -270.445992)
		)
		(stroke
			(width 0)
			(type solid)
		)
		(fill yes)
		(layer "In6.Cu")
		(net "M_C_CPU0_SA_DQS_DN<1>")
	)
	(gr_poly
		(pts
			(xy 341.550498 -269.993618) (xy 341.550498 -269.949168) (xy 341.194898 -269.949168) (xy 341.194898 -269.993618)
			(xy 341.241888 -270.146018) (xy 341.503508 -270.146018)
		)
		(stroke
			(width 0)
			(type solid)
		)
		(fill yes)
		(layer "In6.Cu")
		(net "M_C_CPU0_SA_DQS_DN<6>")
	)
	(gr_poly
		(pts
			(xy 341.550498 -268.77391) (xy 341.503508 -268.62151) (xy 341.241888 -268.62151) (xy 341.194898 -268.77391)
			(xy 341.194898 -268.818106) (xy 341.550498 -268.818106)
		)
		(stroke
			(width 0)
			(type solid)
		)
		(fill yes)
		(layer "In6.Cu")
		(net "M_C_CPU0_SA_DQ<14>")
	)
	(gr_poly
		(pts
			(xy 341.550498 -268.365478) (xy 341.550498 -268.321282) (xy 341.194898 -268.321282) (xy 341.194898 -268.365478)
			(xy 341.241888 -268.517878) (xy 341.503508 -268.517878)
		)
		(stroke
			(width 0)
			(type solid)
		)
		(fill yes)
		(layer "In6.Cu")
		(net "M_C_CPU0_SA_DQ<13>")
	)
	(gr_poly
		(pts
			(xy 341.550498 -267.14577) (xy 341.503508 -266.99337) (xy 341.241888 -266.99337) (xy 341.194898 -267.14577)
			(xy 341.194898 -267.19022) (xy 341.550498 -267.19022)
		)
		(stroke
			(width 0)
			(type solid)
		)
		(fill yes)
		(layer "In6.Cu")
		(net "M_C_CPU0_SA_DQ<26>")
	)
	(gr_poly
		(pts
			(xy 341.550498 -266.737846) (xy 341.550498 -266.69365) (xy 341.194898 -266.69365) (xy 341.194898 -266.737846)
			(xy 341.241888 -266.890246) (xy 341.503508 -266.890246)
		)
		(stroke
			(width 0)
			(type solid)
		)
		(fill yes)
		(layer "In6.Cu")
		(net "M_C_CPU0_SA_DQ<25>")
	)
	(gr_poly
		(pts
			(xy 341.550498 -265.518138) (xy 341.503508 -265.365738) (xy 341.241888 -265.365738) (xy 341.194898 -265.518138)
			(xy 341.194898 -265.562588) (xy 341.550498 -265.562588)
		)
		(stroke
			(width 0)
			(type solid)
		)
		(fill yes)
		(layer "In6.Cu")
		(net "M_C_CPU0_SA_DQS_DN<3>")
	)
	(gr_poly
		(pts
			(xy 341.550498 -265.110214) (xy 341.550498 -265.065764) (xy 341.194898 -265.065764) (xy 341.194898 -265.110214)
			(xy 341.241888 -265.262614) (xy 341.503508 -265.262614)
		)
		(stroke
			(width 0)
			(type solid)
		)
		(fill yes)
		(layer "In6.Cu")
		(net "M_C_CPU0_SA_DQS_DN<8>")
	)
	(gr_poly
		(pts
			(xy 341.550498 -263.890506) (xy 341.503508 -263.738106) (xy 341.241888 -263.738106) (xy 341.194898 -263.890506)
			(xy 341.194898 -263.934956) (xy 341.550498 -263.934956)
		)
		(stroke
			(width 0)
			(type solid)
		)
		(fill yes)
		(layer "In6.Cu")
		(net "M_C_CPU0_SA_DQ<30>")
	)
	(gr_poly
		(pts
			(xy 341.550498 -262.262874) (xy 341.503508 -262.110474) (xy 341.241888 -262.110474) (xy 341.194898 -262.262874)
			(xy 341.194898 -262.30707) (xy 341.550498 -262.30707)
		)
		(stroke
			(width 0)
			(type solid)
		)
		(fill yes)
		(layer "In6.Cu")
		(net "M_C_CPU0_SA_CB<0>")
	)
	(gr_poly
		(pts
			(xy 341.550498 -261.854442) (xy 341.550498 -261.810246) (xy 341.194898 -261.810246) (xy 341.194898 -261.854442)
			(xy 341.241888 -262.006842) (xy 341.503508 -262.006842)
		)
		(stroke
			(width 0)
			(type solid)
		)
		(fill yes)
		(layer "In6.Cu")
		(net "M_C_CPU0_SA_CB<3>")
	)
	(gr_poly
		(pts
			(xy 341.550498 -260.634734) (xy 341.503508 -260.482334) (xy 341.241888 -260.482334) (xy 341.194898 -260.634734)
			(xy 341.194898 -260.679184) (xy 341.550498 -260.679184)
		)
		(stroke
			(width 0)
			(type solid)
		)
		(fill yes)
		(layer "In6.Cu")
		(net "M_C_CPU0_SA_DQS_DP<9>")
	)
	(gr_poly
		(pts
			(xy 341.550498 -260.22681) (xy 341.550498 -260.18236) (xy 341.194898 -260.18236) (xy 341.194898 -260.22681)
			(xy 341.241888 -260.37921) (xy 341.503508 -260.37921)
		)
		(stroke
			(width 0)
			(type solid)
		)
		(fill yes)
		(layer "In6.Cu")
		(net "M_C_CPU0_SA_DQS_DP<4>")
	)
	(gr_poly
		(pts
			(xy 341.550498 -259.007102) (xy 341.503508 -258.854702) (xy 341.241888 -258.854702) (xy 341.194898 -259.007102)
			(xy 341.194898 -259.051552) (xy 341.550498 -259.051552)
		)
		(stroke
			(width 0)
			(type solid)
		)
		(fill yes)
		(layer "In6.Cu")
		(net "M_C_CPU0_SA_CB<4>")
	)
	(gr_poly
		(pts
			(xy 341.550498 -258.599178) (xy 341.550498 -258.554728) (xy 341.194898 -258.554728) (xy 341.194898 -258.599178)
			(xy 341.241888 -258.751578) (xy 341.503508 -258.751578)
		)
		(stroke
			(width 0)
			(type solid)
		)
		(fill yes)
		(layer "In6.Cu")
		(net "M_C_CPU0_SA_CB<7>")
	)
	(gr_poly
		(pts
			(xy 341.550498 -255.751838) (xy 341.503508 -255.599438) (xy 341.241888 -255.599438) (xy 341.194898 -255.751838)
			(xy 341.194898 -255.796034) (xy 341.550498 -255.796034)
		)
		(stroke
			(width 0)
			(type solid)
		)
		(fill yes)
		(layer "In6.Cu")
		(net "M_D_CPU0_SB_RSP<1>")
	)
	(gr_poly
		(pts
			(xy 341.550498 -255.343406) (xy 341.550498 -255.29921) (xy 341.194898 -255.29921) (xy 341.194898 -255.343406)
			(xy 341.241888 -255.495806) (xy 341.503508 -255.495806)
		)
		(stroke
			(width 0)
			(type solid)
		)
		(fill yes)
		(layer "In6.Cu")
		(net "M_C_CPU0_SA_RSP<0>")
	)
	(gr_poly
		(pts
			(xy 341.550498 -254.123698) (xy 341.503508 -253.971298) (xy 341.241888 -253.971298) (xy 341.194898 -254.123698)
			(xy 341.194898 -254.168148) (xy 341.550498 -254.168148)
		)
		(stroke
			(width 0)
			(type solid)
		)
		(fill yes)
		(layer "In6.Cu")
		(net "M_C_CPU0_SB_RSP<1>")
	)
	(gr_poly
		(pts
			(xy 341.758524 -225.668078) (xy 341.796878 -225.64598) (xy 341.619078 -225.338132) (xy 341.580724 -225.36023)
			(xy 341.472266 -225.47707) (xy 341.603076 -225.703638)
		)
		(stroke
			(width 0)
			(type solid)
		)
		(fill yes)
		(layer "In6.Cu")
		(net "M_C_CPU0_SB_DQ<31>")
	)
	(gr_poly
		(pts
			(xy 341.867236 -225.045778) (xy 341.975694 -224.928938) (xy 341.844884 -224.70237) (xy 341.689436 -224.73793)
			(xy 341.651082 -224.760028) (xy 341.828882 -225.067876)
		)
		(stroke
			(width 0)
			(type solid)
		)
		(fill yes)
		(layer "In6.Cu")
		(net "M_C_CPU0_SB_DQ<29>")
	)
	(gr_poly
		(pts
			(xy 341.893398 -248.196354) (xy 341.846408 -248.043954) (xy 341.584788 -248.043954) (xy 341.537798 -248.196354)
			(xy 341.537798 -248.24055) (xy 341.893398 -248.24055)
		)
		(stroke
			(width 0)
			(type solid)
		)
		(fill yes)
		(layer "In6.Cu")
		(net "M_A_CPU0_SA_RSP<0>")
	)
	(gr_poly
		(pts
			(xy 341.893398 -247.787922) (xy 341.893398 -247.743726) (xy 341.537798 -247.743726) (xy 341.537798 -247.787922)
			(xy 341.584788 -247.940322) (xy 341.846408 -247.940322)
		)
		(stroke
			(width 0)
			(type solid)
		)
		(fill yes)
		(layer "In6.Cu")
		(net "M_A_CPU0_SA_RSP<1>")
	)
	(gr_poly
		(pts
			(xy 341.893398 -244.940582) (xy 341.846408 -244.788182) (xy 341.584788 -244.788182) (xy 341.537798 -244.940582)
			(xy 341.537798 -244.985032) (xy 341.893398 -244.985032)
		)
		(stroke
			(width 0)
			(type solid)
		)
		(fill yes)
		(layer "In6.Cu")
		(net "M_D_CPU0_SB_CS_N<1>")
	)
	(gr_poly
		(pts
			(xy 341.893398 -244.532658) (xy 341.893398 -244.488208) (xy 341.537798 -244.488208) (xy 341.537798 -244.532658)
			(xy 341.584788 -244.685058) (xy 341.846408 -244.685058)
		)
		(stroke
			(width 0)
			(type solid)
		)
		(fill yes)
		(layer "In6.Cu")
		(net "M_C_CPU0_SB_DQ<0>")
	)
	(gr_poly
		(pts
			(xy 341.893398 -240.057178) (xy 341.846408 -239.904778) (xy 341.584788 -239.904778) (xy 341.537798 -240.057178)
			(xy 341.537798 -240.101628) (xy 341.893398 -240.101628)
		)
		(stroke
			(width 0)
			(type solid)
		)
		(fill yes)
		(layer "In6.Cu")
		(net "M_C_CPU0_SB_DQ<7>")
	)
	(gr_poly
		(pts
			(xy 341.893398 -239.649254) (xy 341.893398 -239.604804) (xy 341.537798 -239.604804) (xy 341.537798 -239.649254)
			(xy 341.584788 -239.801654) (xy 341.846408 -239.801654)
		)
		(stroke
			(width 0)
			(type solid)
		)
		(fill yes)
		(layer "In6.Cu")
		(net "M_C_CPU0_SB_DQ<8>")
	)
	(gr_poly
		(pts
			(xy 341.893398 -238.429546) (xy 341.846408 -238.277146) (xy 341.584788 -238.277146) (xy 341.537798 -238.429546)
			(xy 341.537798 -238.473996) (xy 341.893398 -238.473996)
		)
		(stroke
			(width 0)
			(type solid)
		)
		(fill yes)
		(layer "In6.Cu")
		(net "M_C_CPU0_SB_DQ<11>")
	)
	(gr_poly
		(pts
			(xy 341.893398 -235.174282) (xy 341.846408 -235.021882) (xy 341.584788 -235.021882) (xy 341.537798 -235.174282)
			(xy 341.537798 -235.218478) (xy 341.893398 -235.218478)
		)
		(stroke
			(width 0)
			(type solid)
		)
		(fill yes)
		(layer "In6.Cu")
		(net "M_C_CPU0_SB_DQ<15>")
	)
	(gr_poly
		(pts
			(xy 341.893398 -234.76585) (xy 341.893398 -234.721654) (xy 341.537798 -234.721654) (xy 341.537798 -234.76585)
			(xy 341.584788 -234.91825) (xy 341.846408 -234.91825)
		)
		(stroke
			(width 0)
			(type solid)
		)
		(fill yes)
		(layer "In6.Cu")
		(net "M_D_CPU0_SB_DQ<16>")
	)
	(gr_poly
		(pts
			(xy 341.893398 -233.546142) (xy 341.846408 -233.393742) (xy 341.584788 -233.393742) (xy 341.537798 -233.546142)
			(xy 341.537798 -233.590592) (xy 341.893398 -233.590592)
		)
		(stroke
			(width 0)
			(type solid)
		)
		(fill yes)
		(layer "In6.Cu")
		(net "M_D_CPU0_SB_DQ<19>")
	)
	(gr_poly
		(pts
			(xy 341.893398 -233.138218) (xy 341.893398 -233.093768) (xy 341.537798 -233.093768) (xy 341.537798 -233.138218)
			(xy 341.584788 -233.290618) (xy 341.846408 -233.290618)
		)
		(stroke
			(width 0)
			(type solid)
		)
		(fill yes)
		(layer "In6.Cu")
		(net "M_D_CPU0_SB_DQS_DP<2>")
	)
	(gr_poly
		(pts
			(xy 341.893398 -230.290878) (xy 341.846408 -230.138478) (xy 341.584788 -230.138478) (xy 341.537798 -230.290878)
			(xy 341.537798 -230.335074) (xy 341.893398 -230.335074)
		)
		(stroke
			(width 0)
			(type solid)
		)
		(fill yes)
		(layer "In6.Cu")
		(net "M_D_CPU0_SB_DQ<23>")
	)
	(gr_poly
		(pts
			(xy 341.893398 -229.882446) (xy 341.893398 -229.83825) (xy 341.537798 -229.83825) (xy 341.537798 -229.882446)
			(xy 341.584788 -230.034846) (xy 341.846408 -230.034846)
		)
		(stroke
			(width 0)
			(type solid)
		)
		(fill yes)
		(layer "In6.Cu")
		(net "M_C_CPU0_SB_DQ<26>")
	)
	(gr_poly
		(pts
			(xy 341.893398 -228.663246) (xy 341.846408 -228.510846) (xy 341.584788 -228.510846) (xy 341.537798 -228.663246)
			(xy 341.537798 -228.707442) (xy 341.893398 -228.707442)
		)
		(stroke
			(width 0)
			(type solid)
		)
		(fill yes)
		(layer "In6.Cu")
		(net "M_C_CPU0_SB_DQ<27>")
	)
	(gr_poly
		(pts
			(xy 341.893398 -227.035106) (xy 341.846408 -226.882706) (xy 341.584788 -226.882706) (xy 341.537798 -227.035106)
			(xy 341.537798 -227.079556) (xy 341.893398 -227.079556)
		)
		(stroke
			(width 0)
			(type solid)
		)
		(fill yes)
		(layer "In6.Cu")
		(net "M_C_CPU0_SB_DQS_DP<8>")
	)
	(gr_poly
		(pts
			(xy 341.893398 -226.627182) (xy 341.893398 -226.582732) (xy 341.537798 -226.582732) (xy 341.537798 -226.627182)
			(xy 341.584788 -226.779582) (xy 341.846408 -226.779582)
		)
		(stroke
			(width 0)
			(type solid)
		)
		(fill yes)
		(layer "In6.Cu")
		(net "M_C_CPU0_SB_DQ<28>")
	)
	(gr_poly
		(pts
			(xy 341.893906 -242.904518) (xy 341.893906 -242.860322) (xy 341.538306 -242.860322) (xy 341.538306 -242.904518)
			(xy 341.585296 -243.056918) (xy 341.846916 -243.056918)
		)
		(stroke
			(width 0)
			(type solid)
		)
		(fill yes)
		(layer "In6.Cu")
		(net "M_C_CPU0_SB_DQS_DP<0>")
	)
	(gr_poly
		(pts
			(xy 341.893906 -238.021114) (xy 341.893906 -237.976918) (xy 341.538306 -237.976918) (xy 341.538306 -238.021114)
			(xy 341.585296 -238.173514) (xy 341.846916 -238.173514)
		)
		(stroke
			(width 0)
			(type solid)
		)
		(fill yes)
		(layer "In6.Cu")
		(net "M_C_CPU0_SB_DQS_DP<1>")
	)
	(gr_poly
		(pts
			(xy 341.895938 -246.16029) (xy 341.895938 -246.116094) (xy 341.540338 -246.116094) (xy 341.540338 -246.16029)
			(xy 341.587328 -246.31269) (xy 341.848948 -246.31269)
		)
		(stroke
			(width 0)
			(type solid)
		)
		(fill yes)
		(layer "In6.Cu")
		(net "M_D_CPU0_SB_CS_N<2>")
	)
	(gr_poly
		(pts
			(xy 341.895938 -241.685318) (xy 341.848948 -241.532918) (xy 341.587328 -241.532918) (xy 341.540338 -241.685318)
			(xy 341.540338 -241.729514) (xy 341.895938 -241.729514)
		)
		(stroke
			(width 0)
			(type solid)
		)
		(fill yes)
		(layer "In6.Cu")
		(net "M_C_CPU0_SB_DQS_DP<5>")
	)
	(gr_poly
		(pts
			(xy 341.895938 -241.276886) (xy 341.895938 -241.23269) (xy 341.540338 -241.23269) (xy 341.540338 -241.276886)
			(xy 341.587328 -241.429286) (xy 341.848948 -241.429286)
		)
		(stroke
			(width 0)
			(type solid)
		)
		(fill yes)
		(layer "In6.Cu")
		(net "M_C_CPU0_SB_DQ<4>")
	)
	(gr_poly
		(pts
			(xy 341.895938 -236.801914) (xy 341.848948 -236.649514) (xy 341.587328 -236.649514) (xy 341.540338 -236.801914)
			(xy 341.540338 -236.84611) (xy 341.895938 -236.84611)
		)
		(stroke
			(width 0)
			(type solid)
		)
		(fill yes)
		(layer "In6.Cu")
		(net "M_C_CPU0_SB_DQS_DP<6>")
	)
	(gr_poly
		(pts
			(xy 341.895938 -236.39399) (xy 341.895938 -236.34954) (xy 341.540338 -236.34954) (xy 341.540338 -236.39399)
			(xy 341.587328 -236.54639) (xy 341.848948 -236.54639)
		)
		(stroke
			(width 0)
			(type solid)
		)
		(fill yes)
		(layer "In6.Cu")
		(net "M_C_CPU0_SB_DQ<12>")
	)
	(gr_poly
		(pts
			(xy 341.895938 -231.91851) (xy 341.848948 -231.76611) (xy 341.587328 -231.76611) (xy 341.540338 -231.91851)
			(xy 341.540338 -231.96296) (xy 341.895938 -231.96296)
		)
		(stroke
			(width 0)
			(type solid)
		)
		(fill yes)
		(layer "In6.Cu")
		(net "M_D_CPU0_SB_DQS_DP<7>")
	)
	(gr_poly
		(pts
			(xy 341.895938 -231.510586) (xy 341.895938 -231.466136) (xy 341.540338 -231.466136) (xy 341.540338 -231.510586)
			(xy 341.587328 -231.662986) (xy 341.848948 -231.662986)
		)
		(stroke
			(width 0)
			(type solid)
		)
		(fill yes)
		(layer "In6.Cu")
		(net "M_D_CPU0_SB_DQ<20>")
	)
	(gr_poly
		(pts
			(xy 341.905336 -243.313458) (xy 341.858346 -243.161058) (xy 341.596726 -243.161058) (xy 341.549736 -243.313458)
			(xy 341.549736 -243.357654) (xy 341.905336 -243.357654)
		)
		(stroke
			(width 0)
			(type solid)
		)
		(fill yes)
		(layer "In6.Cu")
		(net "M_C_CPU0_SB_DQ<3>")
	)
	(gr_poly
		(pts
			(xy 342.00338 -277.318216) (xy 342.00338 -277.27402) (xy 341.64778 -277.27402) (xy 341.64778 -277.318216)
			(xy 341.69477 -277.470616) (xy 341.95639 -277.470616)
		)
		(stroke
			(width 0)
			(type solid)
		)
		(fill yes)
		(layer "In6.Cu")
		(net "M_D_CPU0_SA_DQ<0>")
	)
	(gr_poly
		(pts
			(xy 342.00338 -274.47113) (xy 341.95639 -274.31873) (xy 341.69477 -274.31873) (xy 341.64778 -274.47113)
			(xy 341.64778 -274.515326) (xy 342.00338 -274.515326)
		)
		(stroke
			(width 0)
			(type solid)
		)
		(fill yes)
		(layer "In6.Cu")
		(net "M_D_CPU0_SA_DQS_DP<5>")
	)
	(gr_poly
		(pts
			(xy 342.00338 -274.062698) (xy 342.00338 -274.018502) (xy 341.64778 -274.018502) (xy 341.64778 -274.062698)
			(xy 341.69477 -274.215098) (xy 341.95639 -274.215098)
		)
		(stroke
			(width 0)
			(type solid)
		)
		(fill yes)
		(layer "In6.Cu")
		(net "M_D_CPU0_SA_DQ<4>")
	)
	(gr_poly
		(pts
			(xy 342.00338 -272.843498) (xy 341.95639 -272.691098) (xy 341.69477 -272.691098) (xy 341.64778 -272.843498)
			(xy 341.64778 -272.887694) (xy 342.00338 -272.887694)
		)
		(stroke
			(width 0)
			(type solid)
		)
		(fill yes)
		(layer "In6.Cu")
		(net "M_D_CPU0_SA_DQ<7>")
	)
	(gr_poly
		(pts
			(xy 342.00338 -272.435066) (xy 342.00338 -272.39087) (xy 341.64778 -272.39087) (xy 341.64778 -272.435066)
			(xy 341.69477 -272.587466) (xy 341.95639 -272.587466)
		)
		(stroke
			(width 0)
			(type solid)
		)
		(fill yes)
		(layer "In6.Cu")
		(net "M_C_CPU0_SA_DQ<8>")
	)
	(gr_poly
		(pts
			(xy 342.00338 -269.587726) (xy 341.95639 -269.435326) (xy 341.69477 -269.435326) (xy 341.64778 -269.587726)
			(xy 341.64778 -269.631922) (xy 342.00338 -269.631922)
		)
		(stroke
			(width 0)
			(type solid)
		)
		(fill yes)
		(layer "In6.Cu")
		(net "M_C_CPU0_SA_DQS_DP<6>")
	)
	(gr_poly
		(pts
			(xy 342.00338 -269.179294) (xy 342.00338 -269.135098) (xy 341.64778 -269.135098) (xy 341.64778 -269.179294)
			(xy 341.69477 -269.331694) (xy 341.95639 -269.331694)
		)
		(stroke
			(width 0)
			(type solid)
		)
		(fill yes)
		(layer "In6.Cu")
		(net "M_C_CPU0_SA_DQ<12>")
	)
	(gr_poly
		(pts
			(xy 342.00338 -267.960094) (xy 341.95639 -267.807694) (xy 341.69477 -267.807694) (xy 341.64778 -267.960094)
			(xy 341.64778 -268.00429) (xy 342.00338 -268.00429)
		)
		(stroke
			(width 0)
			(type solid)
		)
		(fill yes)
		(layer "In6.Cu")
		(net "M_C_CPU0_SA_DQ<15>")
	)
	(gr_poly
		(pts
			(xy 342.00338 -267.551662) (xy 342.00338 -267.507466) (xy 341.64778 -267.507466) (xy 341.64778 -267.551662)
			(xy 341.69477 -267.704062) (xy 341.95639 -267.704062)
		)
		(stroke
			(width 0)
			(type solid)
		)
		(fill yes)
		(layer "In6.Cu")
		(net "M_C_CPU0_SA_DQ<24>")
	)
	(gr_poly
		(pts
			(xy 342.00338 -266.331954) (xy 341.95639 -266.179554) (xy 341.69477 -266.179554) (xy 341.64778 -266.331954)
			(xy 341.64778 -266.376404) (xy 342.00338 -266.376404)
		)
		(stroke
			(width 0)
			(type solid)
		)
		(fill yes)
		(layer "In6.Cu")
		(net "M_C_CPU0_SA_DQ<27>")
	)
	(gr_poly
		(pts
			(xy 342.00338 -264.704322) (xy 341.95639 -264.551922) (xy 341.69477 -264.551922) (xy 341.64778 -264.704322)
			(xy 341.64778 -264.748772) (xy 342.00338 -264.748772)
		)
		(stroke
			(width 0)
			(type solid)
		)
		(fill yes)
		(layer "In6.Cu")
		(net "M_C_CPU0_SA_DQS_DP<8>")
	)
	(gr_poly
		(pts
			(xy 342.00338 -264.296398) (xy 342.00338 -264.251948) (xy 341.64778 -264.251948) (xy 341.64778 -264.296398)
			(xy 341.69477 -264.448798) (xy 341.95639 -264.448798)
		)
		(stroke
			(width 0)
			(type solid)
		)
		(fill yes)
		(layer "In6.Cu")
		(net "M_C_CPU0_SA_DQ<28>")
	)
	(gr_poly
		(pts
			(xy 342.00338 -262.668258) (xy 342.00338 -262.624062) (xy 341.64778 -262.624062) (xy 341.64778 -262.668258)
			(xy 341.69477 -262.820658) (xy 341.95639 -262.820658)
		)
		(stroke
			(width 0)
			(type solid)
		)
		(fill yes)
		(layer "In6.Cu")
		(net "M_C_CPU0_SA_CB<2>")
	)
	(gr_poly
		(pts
			(xy 342.00338 -261.449058) (xy 341.95639 -261.296658) (xy 341.69477 -261.296658) (xy 341.64778 -261.449058)
			(xy 341.64778 -261.493254) (xy 342.00338 -261.493254)
		)
		(stroke
			(width 0)
			(type solid)
		)
		(fill yes)
		(layer "In6.Cu")
		(net "M_C_CPU0_SA_CB<1>")
	)
	(gr_poly
		(pts
			(xy 342.00338 -261.040626) (xy 342.00338 -260.99643) (xy 341.64778 -260.99643) (xy 341.64778 -261.040626)
			(xy 341.69477 -261.193026) (xy 341.95639 -261.193026)
		)
		(stroke
			(width 0)
			(type solid)
		)
		(fill yes)
		(layer "In6.Cu")
		(net "M_C_CPU0_SA_DQS_DN<9>")
	)
	(gr_poly
		(pts
			(xy 342.00338 -259.412994) (xy 342.00338 -259.368544) (xy 341.64778 -259.368544) (xy 341.64778 -259.412994)
			(xy 341.69477 -259.565394) (xy 341.95639 -259.565394)
		)
		(stroke
			(width 0)
			(type solid)
		)
		(fill yes)
		(layer "In6.Cu")
		(net "M_C_CPU0_SA_CB<6>")
	)
	(gr_poly
		(pts
			(xy 342.00338 -258.193286) (xy 341.95639 -258.040886) (xy 341.69477 -258.040886) (xy 341.64778 -258.193286)
			(xy 341.64778 -258.237482) (xy 342.00338 -258.237482)
		)
		(stroke
			(width 0)
			(type solid)
		)
		(fill yes)
		(layer "In6.Cu")
		(net "M_C_CPU0_SA_CB<5>")
	)
	(gr_poly
		(pts
			(xy 342.00338 -254.937514) (xy 341.95639 -254.785114) (xy 341.69477 -254.785114) (xy 341.64778 -254.937514)
			(xy 341.64778 -254.981964) (xy 342.00338 -254.981964)
		)
		(stroke
			(width 0)
			(type solid)
		)
		(fill yes)
		(layer "In6.Cu")
		(net "M_C_CPU0_SB_RSP<0>")
	)
	(gr_poly
		(pts
			(xy 342.00338 -254.52959) (xy 342.00338 -254.48514) (xy 341.64778 -254.48514) (xy 341.64778 -254.52959)
			(xy 341.69477 -254.68199) (xy 341.95639 -254.68199)
		)
		(stroke
			(width 0)
			(type solid)
		)
		(fill yes)
		(layer "In6.Cu")
		(net "M_C_CPU0_SA_RSP<1>")
	)
	(gr_poly
		(pts
			(xy 342.003888 -275.690584) (xy 342.003888 -275.646134) (xy 341.648288 -275.646134) (xy 341.648288 -275.690584)
			(xy 341.695278 -275.842984) (xy 341.956898 -275.842984)
		)
		(stroke
			(width 0)
			(type solid)
		)
		(fill yes)
		(layer "In6.Cu")
		(net "M_D_CPU0_SA_DQS_DP<0>")
	)
	(gr_poly
		(pts
			(xy 342.003888 -270.807434) (xy 342.003888 -270.762984) (xy 341.648288 -270.762984) (xy 341.648288 -270.807434)
			(xy 341.695278 -270.959834) (xy 341.956898 -270.959834)
		)
		(stroke
			(width 0)
			(type solid)
		)
		(fill yes)
		(layer "In6.Cu")
		(net "M_C_CPU0_SA_DQS_DP<1>")
	)
	(gr_poly
		(pts
			(xy 342.003888 -265.92403) (xy 342.003888 -265.87958) (xy 341.648288 -265.87958) (xy 341.648288 -265.92403)
			(xy 341.695278 -266.07643) (xy 341.956898 -266.07643)
		)
		(stroke
			(width 0)
			(type solid)
		)
		(fill yes)
		(layer "In6.Cu")
		(net "M_C_CPU0_SA_DQS_DP<3>")
	)
	(gr_poly
		(pts
			(xy 342.00592 -276.098762) (xy 341.95893 -275.946362) (xy 341.69731 -275.946362) (xy 341.65032 -276.098762)
			(xy 341.65032 -276.143212) (xy 342.00592 -276.143212)
		)
		(stroke
			(width 0)
			(type solid)
		)
		(fill yes)
		(layer "In6.Cu")
		(net "M_D_CPU0_SA_DQ<3>")
	)
	(gr_poly
		(pts
			(xy 342.00592 -271.215358) (xy 341.95893 -271.062958) (xy 341.69731 -271.062958) (xy 341.65032 -271.215358)
			(xy 341.65032 -271.259808) (xy 342.00592 -271.259808)
		)
		(stroke
			(width 0)
			(type solid)
		)
		(fill yes)
		(layer "In6.Cu")
		(net "M_C_CPU0_SA_DQ<11>")
	)
	(gr_poly
		(pts
			(xy 342.00592 -256.565654) (xy 341.95893 -256.413254) (xy 341.69731 -256.413254) (xy 341.65032 -256.565654)
			(xy 341.65032 -256.60985) (xy 342.00592 -256.60985)
		)
		(stroke
			(width 0)
			(type solid)
		)
		(fill yes)
		(layer "In6.Cu")
		(net "M_D_CPU0_SB_RSP<0>")
	)
	(gr_poly
		(pts
			(xy 342.00592 -256.157222) (xy 342.00592 -256.113026) (xy 341.65032 -256.113026) (xy 341.65032 -256.157222)
			(xy 341.69731 -256.309622) (xy 341.95893 -256.309622)
		)
		(stroke
			(width 0)
			(type solid)
		)
		(fill yes)
		(layer "In6.Cu")
		(net "M_D_CPU0_SA_RSP<1>")
	)
	(gr_poly
		(pts
			(xy 342.015318 -263.077198) (xy 341.968328 -262.924798) (xy 341.706708 -262.924798) (xy 341.659718 -263.077198)
			(xy 341.659718 -263.121394) (xy 342.015318 -263.121394)
		)
		(stroke
			(width 0)
			(type solid)
		)
		(fill yes)
		(layer "In6.Cu")
		(net "M_C_CPU0_SA_DQ<31>")
	)
	(gr_poly
		(pts
			(xy 342.368378 -243.718334) (xy 342.368378 -243.674138) (xy 342.012778 -243.674138) (xy 342.012778 -243.718334)
			(xy 342.059768 -243.870734) (xy 342.321388 -243.870734)
		)
		(stroke
			(width 0)
			(type solid)
		)
		(fill yes)
		(layer "In6.Cu")
		(net "M_C_CPU0_SB_DQ<1>")
	)
	(gr_poly
		(pts
			(xy 342.371934 -245.754906) (xy 342.324944 -245.602506) (xy 342.063324 -245.602506) (xy 342.016334 -245.754906)
			(xy 342.016334 -245.799356) (xy 342.371934 -245.799356)
		)
		(stroke
			(width 0)
			(type solid)
		)
		(fill yes)
		(layer "In6.Cu")
		(net "M_D_CPU0_SB_CS_N<3>")
	)
	(gr_poly
		(pts
			(xy 342.371934 -242.090702) (xy 342.371934 -242.046252) (xy 342.016334 -242.046252) (xy 342.016334 -242.090702)
			(xy 342.063324 -242.243102) (xy 342.324944 -242.243102)
		)
		(stroke
			(width 0)
			(type solid)
		)
		(fill yes)
		(layer "In6.Cu")
		(net "M_C_CPU0_SB_DQS_DN<5>")
	)
	(gr_poly
		(pts
			(xy 342.371934 -240.871502) (xy 342.324944 -240.719102) (xy 342.063324 -240.719102) (xy 342.016334 -240.871502)
			(xy 342.016334 -240.915952) (xy 342.371934 -240.915952)
		)
		(stroke
			(width 0)
			(type solid)
		)
		(fill yes)
		(layer "In6.Cu")
		(net "M_C_CPU0_SB_DQ<6>")
	)
	(gr_poly
		(pts
			(xy 342.371934 -237.207298) (xy 342.371934 -237.163102) (xy 342.016334 -237.163102) (xy 342.016334 -237.207298)
			(xy 342.063324 -237.359698) (xy 342.324944 -237.359698)
		)
		(stroke
			(width 0)
			(type solid)
		)
		(fill yes)
		(layer "In6.Cu")
		(net "M_C_CPU0_SB_DQS_DN<6>")
	)
	(gr_poly
		(pts
			(xy 342.371934 -235.988098) (xy 342.324944 -235.835698) (xy 342.063324 -235.835698) (xy 342.016334 -235.988098)
			(xy 342.016334 -236.032548) (xy 342.371934 -236.032548)
		)
		(stroke
			(width 0)
			(type solid)
		)
		(fill yes)
		(layer "In6.Cu")
		(net "M_C_CPU0_SB_DQ<14>")
	)
	(gr_poly
		(pts
			(xy 342.371934 -232.323894) (xy 342.371934 -232.279698) (xy 342.016334 -232.279698) (xy 342.016334 -232.323894)
			(xy 342.063324 -232.476294) (xy 342.324944 -232.476294)
		)
		(stroke
			(width 0)
			(type solid)
		)
		(fill yes)
		(layer "In6.Cu")
		(net "M_D_CPU0_SB_DQS_DN<7>")
	)
	(gr_poly
		(pts
			(xy 342.371934 -231.104694) (xy 342.324944 -230.952294) (xy 342.063324 -230.952294) (xy 342.016334 -231.104694)
			(xy 342.016334 -231.149144) (xy 342.371934 -231.149144)
		)
		(stroke
			(width 0)
			(type solid)
		)
		(fill yes)
		(layer "In6.Cu")
		(net "M_D_CPU0_SB_DQ<22>")
	)
	(gr_poly
		(pts
			(xy 342.37676 -253.476506) (xy 342.338406 -253.454408) (xy 342.182958 -253.418848) (xy 342.052148 -253.645416)
			(xy 342.160606 -253.762256) (xy 342.19896 -253.784354)
		)
		(stroke
			(width 0)
			(type solid)
		)
		(fill yes)
		(layer "In6.Cu")
		(net "M_C_CPU0_SB_RSP<1>")
	)
	(gr_poly
		(pts
			(xy 342.377776 -248.601738) (xy 342.377776 -248.557542) (xy 342.022176 -248.557542) (xy 342.022176 -248.601738)
			(xy 342.069166 -248.754138) (xy 342.330786 -248.754138)
		)
		(stroke
			(width 0)
			(type solid)
		)
		(fill yes)
		(layer "In6.Cu")
		(net "M_A_CPU0_SB_RSP<0>")
	)
	(gr_poly
		(pts
			(xy 342.377776 -244.127274) (xy 342.330786 -243.974874) (xy 342.069166 -243.974874) (xy 342.022176 -244.127274)
			(xy 342.022176 -244.17147) (xy 342.377776 -244.17147)
		)
		(stroke
			(width 0)
			(type solid)
		)
		(fill yes)
		(layer "In6.Cu")
		(net "M_C_CPU0_SB_DQ<2>")
	)
	(gr_poly
		(pts
			(xy 342.377776 -239.24387) (xy 342.330786 -239.09147) (xy 342.069166 -239.09147) (xy 342.022176 -239.24387)
			(xy 342.022176 -239.288066) (xy 342.377776 -239.288066)
		)
		(stroke
			(width 0)
			(type solid)
		)
		(fill yes)
		(layer "In6.Cu")
		(net "M_C_CPU0_SB_DQ<10>")
	)
	(gr_poly
		(pts
			(xy 342.377776 -238.83493) (xy 342.377776 -238.790734) (xy 342.022176 -238.790734) (xy 342.022176 -238.83493)
			(xy 342.069166 -238.98733) (xy 342.330786 -238.98733)
		)
		(stroke
			(width 0)
			(type solid)
		)
		(fill yes)
		(layer "In6.Cu")
		(net "M_C_CPU0_SB_DQ<9>")
	)
	(gr_poly
		(pts
			(xy 342.377776 -234.360466) (xy 342.330786 -234.208066) (xy 342.069166 -234.208066) (xy 342.022176 -234.360466)
			(xy 342.022176 -234.404916) (xy 342.377776 -234.404916)
		)
		(stroke
			(width 0)
			(type solid)
		)
		(fill yes)
		(layer "In6.Cu")
		(net "M_D_CPU0_SB_DQ<18>")
	)
	(gr_poly
		(pts
			(xy 342.377776 -233.952034) (xy 342.377776 -233.907584) (xy 342.022176 -233.907584) (xy 342.022176 -233.952034)
			(xy 342.069166 -234.104434) (xy 342.330786 -234.104434)
		)
		(stroke
			(width 0)
			(type solid)
		)
		(fill yes)
		(layer "In6.Cu")
		(net "M_D_CPU0_SB_DQ<17>")
	)
	(gr_poly
		(pts
			(xy 342.377776 -229.477062) (xy 342.330786 -229.324662) (xy 342.069166 -229.324662) (xy 342.022176 -229.477062)
			(xy 342.022176 -229.521512) (xy 342.377776 -229.521512)
		)
		(stroke
			(width 0)
			(type solid)
		)
		(fill yes)
		(layer "In6.Cu")
		(net "M_C_CPU0_SB_DQ<24>")
	)
	(gr_poly
		(pts
			(xy 342.377776 -229.06863) (xy 342.377776 -229.02418) (xy 342.022176 -229.02418) (xy 342.022176 -229.06863)
			(xy 342.069166 -229.22103) (xy 342.330786 -229.22103)
		)
		(stroke
			(width 0)
			(type solid)
		)
		(fill yes)
		(layer "In6.Cu")
		(net "M_C_CPU0_SB_DQ<25>")
	)
	(gr_poly
		(pts
			(xy 342.380316 -247.382538) (xy 342.333326 -247.230138) (xy 342.071706 -247.230138) (xy 342.024716 -247.382538)
			(xy 342.024716 -247.426734) (xy 342.380316 -247.426734)
		)
		(stroke
			(width 0)
			(type solid)
		)
		(fill yes)
		(layer "In6.Cu")
		(net "M_A_CPU0_SB_RSP<1>")
	)
	(gr_poly
		(pts
			(xy 342.380316 -245.346474) (xy 342.380316 -245.302278) (xy 342.024716 -245.302278) (xy 342.024716 -245.346474)
			(xy 342.071706 -245.498874) (xy 342.333326 -245.498874)
		)
		(stroke
			(width 0)
			(type solid)
		)
		(fill yes)
		(layer "In6.Cu")
		(net "M_D_CPU0_SB_CS_N<0>")
	)
	(gr_poly
		(pts
			(xy 342.380316 -240.46307) (xy 342.380316 -240.418874) (xy 342.024716 -240.418874) (xy 342.024716 -240.46307)
			(xy 342.071706 -240.61547) (xy 342.333326 -240.61547)
		)
		(stroke
			(width 0)
			(type solid)
		)
		(fill yes)
		(layer "In6.Cu")
		(net "M_C_CPU0_SB_DQ<5>")
	)
	(gr_poly
		(pts
			(xy 342.380316 -235.579666) (xy 342.380316 -235.53547) (xy 342.024716 -235.53547) (xy 342.024716 -235.579666)
			(xy 342.071706 -235.732066) (xy 342.333326 -235.732066)
		)
		(stroke
			(width 0)
			(type solid)
		)
		(fill yes)
		(layer "In6.Cu")
		(net "M_C_CPU0_SB_DQ<13>")
	)
	(gr_poly
		(pts
			(xy 342.380316 -230.696262) (xy 342.380316 -230.652066) (xy 342.024716 -230.652066) (xy 342.024716 -230.696262)
			(xy 342.071706 -230.848662) (xy 342.333326 -230.848662)
		)
		(stroke
			(width 0)
			(type solid)
		)
		(fill yes)
		(layer "In6.Cu")
		(net "M_D_CPU0_SB_DQ<21>")
	)
	(gr_poly
		(pts
			(xy 342.380316 -227.440998) (xy 342.380316 -227.396548) (xy 342.024716 -227.396548) (xy 342.024716 -227.440998)
			(xy 342.071706 -227.593398) (xy 342.333326 -227.593398)
		)
		(stroke
			(width 0)
			(type solid)
		)
		(fill yes)
		(layer "In6.Cu")
		(net "M_C_CPU0_SB_DQS_DN<8>")
	)
	(gr_poly
		(pts
			(xy 342.380316 -226.22129) (xy 342.333326 -226.06889) (xy 342.071706 -226.06889) (xy 342.024716 -226.22129)
			(xy 342.024716 -226.26574) (xy 342.380316 -226.26574)
		)
		(stroke
			(width 0)
			(type solid)
		)
		(fill yes)
		(layer "In6.Cu")
		(net "M_C_CPU0_SB_DQ<30>")
	)
	(gr_poly
		(pts
			(xy 342.380316 -225.813366) (xy 342.380316 -225.768916) (xy 342.024716 -225.768916) (xy 342.024716 -225.813366)
			(xy 342.071706 -225.965766) (xy 342.333326 -225.965766)
		)
		(stroke
			(width 0)
			(type solid)
		)
		(fill yes)
		(layer "In6.Cu")
		(net "M_C_CPU0_SB_DQ<31>")
	)
	(gr_poly
		(pts
			(xy 342.47836 -263.482074) (xy 342.47836 -263.437624) (xy 342.12276 -263.437624) (xy 342.12276 -263.482074)
			(xy 342.16975 -263.634474) (xy 342.43137 -263.634474)
		)
		(stroke
			(width 0)
			(type solid)
		)
		(fill yes)
		(layer "In6.Cu")
		(net "M_C_CPU0_SA_DQ<29>")
	)
	(gr_poly
		(pts
			(xy 342.481662 -260.635242) (xy 342.434672 -260.482842) (xy 342.173052 -260.482842) (xy 342.126062 -260.635242)
			(xy 342.126062 -260.679438) (xy 342.481662 -260.679438)
		)
		(stroke
			(width 0)
			(type solid)
		)
		(fill yes)
		(layer "In6.Cu")
		(net "M_C_CPU0_SA_DQS_DP<9>")
	)
	(gr_poly
		(pts
			(xy 342.481916 -271.620742) (xy 342.481916 -271.576546) (xy 342.126316 -271.576546) (xy 342.126316 -271.620742)
			(xy 342.173306 -271.773142) (xy 342.434926 -271.773142)
		)
		(stroke
			(width 0)
			(type solid)
		)
		(fill yes)
		(layer "In6.Cu")
		(net "M_C_CPU0_SA_DQ<9>")
	)
	(gr_poly
		(pts
			(xy 342.481916 -256.971038) (xy 342.481916 -256.926588) (xy 342.126316 -256.926588) (xy 342.126316 -256.971038)
			(xy 342.173306 -257.123438) (xy 342.434926 -257.123438)
		)
		(stroke
			(width 0)
			(type solid)
		)
		(fill yes)
		(layer "In6.Cu")
		(net "M_D_CPU0_SA_RSP<0>")
	)
	(gr_poly
		(pts
			(xy 342.481916 -255.751838) (xy 342.434926 -255.599438) (xy 342.173306 -255.599438) (xy 342.126316 -255.751838)
			(xy 342.126316 -255.796288) (xy 342.481916 -255.796288)
		)
		(stroke
			(width 0)
			(type solid)
		)
		(fill yes)
		(layer "In6.Cu")
		(net "M_D_CPU0_SB_RSP<1>")
	)
	(gr_poly
		(pts
			(xy 342.487758 -273.657314) (xy 342.440768 -273.504914) (xy 342.179148 -273.504914) (xy 342.132158 -273.657314)
			(xy 342.132158 -273.701764) (xy 342.487758 -273.701764)
		)
		(stroke
			(width 0)
			(type solid)
		)
		(fill yes)
		(layer "In6.Cu")
		(net "M_D_CPU0_SA_DQ<6>")
	)
	(gr_poly
		(pts
			(xy 342.487758 -273.248882) (xy 342.487758 -273.204432) (xy 342.132158 -273.204432) (xy 342.132158 -273.248882)
			(xy 342.179148 -273.401282) (xy 342.440768 -273.401282)
		)
		(stroke
			(width 0)
			(type solid)
		)
		(fill yes)
		(layer "In6.Cu")
		(net "M_D_CPU0_SA_DQ<5>")
	)
	(gr_poly
		(pts
			(xy 342.487758 -268.77391) (xy 342.440768 -268.62151) (xy 342.179148 -268.62151) (xy 342.132158 -268.77391)
			(xy 342.132158 -268.81836) (xy 342.487758 -268.81836)
		)
		(stroke
			(width 0)
			(type solid)
		)
		(fill yes)
		(layer "In6.Cu")
		(net "M_C_CPU0_SA_DQ<14>")
	)
	(gr_poly
		(pts
			(xy 342.487758 -268.365478) (xy 342.487758 -268.321028) (xy 342.132158 -268.321028) (xy 342.132158 -268.365478)
			(xy 342.179148 -268.517878) (xy 342.440768 -268.517878)
		)
		(stroke
			(width 0)
			(type solid)
		)
		(fill yes)
		(layer "In6.Cu")
		(net "M_C_CPU0_SA_DQ<13>")
	)
	(gr_poly
		(pts
			(xy 342.487758 -263.891014) (xy 342.440768 -263.738614) (xy 342.179148 -263.738614) (xy 342.132158 -263.891014)
			(xy 342.132158 -263.93521) (xy 342.487758 -263.93521)
		)
		(stroke
			(width 0)
			(type solid)
		)
		(fill yes)
		(layer "In6.Cu")
		(net "M_C_CPU0_SA_DQ<30>")
	)
	(gr_poly
		(pts
			(xy 342.487758 -259.00761) (xy 342.440768 -258.85521) (xy 342.179148 -258.85521) (xy 342.132158 -259.00761)
			(xy 342.132158 -259.051806) (xy 342.487758 -259.051806)
		)
		(stroke
			(width 0)
			(type solid)
		)
		(fill yes)
		(layer "In6.Cu")
		(net "M_C_CPU0_SA_CB<4>")
	)
	(gr_poly
		(pts
			(xy 342.487758 -258.59867) (xy 342.487758 -258.554474) (xy 342.132158 -258.554474) (xy 342.132158 -258.59867)
			(xy 342.179148 -258.75107) (xy 342.440768 -258.75107)
		)
		(stroke
			(width 0)
			(type solid)
		)
		(fill yes)
		(layer "In6.Cu")
		(net "M_C_CPU0_SA_CB<7>")
	)
	(gr_poly
		(pts
			(xy 342.490298 -274.876514) (xy 342.490298 -274.832318) (xy 342.134698 -274.832318) (xy 342.134698 -274.876514)
			(xy 342.181688 -275.028914) (xy 342.443308 -275.028914)
		)
		(stroke
			(width 0)
			(type solid)
		)
		(fill yes)
		(layer "In6.Cu")
		(net "M_D_CPU0_SA_DQS_DN<5>")
	)
	(gr_poly
		(pts
			(xy 342.490298 -272.029174) (xy 342.443308 -271.876774) (xy 342.181688 -271.876774) (xy 342.134698 -272.029174)
			(xy 342.134698 -272.073624) (xy 342.490298 -272.073624)
		)
		(stroke
			(width 0)
			(type solid)
		)
		(fill yes)
		(layer "In6.Cu")
		(net "M_C_CPU0_SA_DQ<10>")
	)
	(gr_poly
		(pts
			(xy 342.490298 -269.993618) (xy 342.490298 -269.949168) (xy 342.134698 -269.949168) (xy 342.134698 -269.993618)
			(xy 342.181688 -270.146018) (xy 342.443308 -270.146018)
		)
		(stroke
			(width 0)
			(type solid)
		)
		(fill yes)
		(layer "In6.Cu")
		(net "M_C_CPU0_SA_DQS_DN<6>")
	)
	(gr_poly
		(pts
			(xy 342.490298 -267.14577) (xy 342.443308 -266.99337) (xy 342.181688 -266.99337) (xy 342.134698 -267.14577)
			(xy 342.134698 -267.19022) (xy 342.490298 -267.19022)
		)
		(stroke
			(width 0)
			(type solid)
		)
		(fill yes)
		(layer "In6.Cu")
		(net "M_C_CPU0_SA_DQ<26>")
	)
	(gr_poly
		(pts
			(xy 342.490298 -266.737846) (xy 342.490298 -266.69365) (xy 342.134698 -266.69365) (xy 342.134698 -266.737846)
			(xy 342.181688 -266.890246) (xy 342.443308 -266.890246)
		)
		(stroke
			(width 0)
			(type solid)
		)
		(fill yes)
		(layer "In6.Cu")
		(net "M_C_CPU0_SA_DQ<25>")
	)
	(gr_poly
		(pts
			(xy 342.490298 -265.110214) (xy 342.490298 -265.065764) (xy 342.134698 -265.065764) (xy 342.134698 -265.110214)
			(xy 342.181688 -265.262614) (xy 342.443308 -265.262614)
		)
		(stroke
			(width 0)
			(type solid)
		)
		(fill yes)
		(layer "In6.Cu")
		(net "M_C_CPU0_SA_DQS_DN<8>")
	)
	(gr_poly
		(pts
			(xy 342.490298 -262.262874) (xy 342.443308 -262.110474) (xy 342.181688 -262.110474) (xy 342.134698 -262.262874)
			(xy 342.134698 -262.30707) (xy 342.490298 -262.30707)
		)
		(stroke
			(width 0)
			(type solid)
		)
		(fill yes)
		(layer "In6.Cu")
		(net "M_C_CPU0_SA_CB<0>")
	)
	(gr_poly
		(pts
			(xy 342.490298 -261.854442) (xy 342.490298 -261.810246) (xy 342.134698 -261.810246) (xy 342.134698 -261.854442)
			(xy 342.181688 -262.006842) (xy 342.443308 -262.006842)
		)
		(stroke
			(width 0)
			(type solid)
		)
		(fill yes)
		(layer "In6.Cu")
		(net "M_C_CPU0_SA_CB<3>")
	)
	(gr_poly
		(pts
			(xy 342.490298 -255.343406) (xy 342.490298 -255.29921) (xy 342.134698 -255.29921) (xy 342.134698 -255.343406)
			(xy 342.181688 -255.495806) (xy 342.443308 -255.495806)
		)
		(stroke
			(width 0)
			(type solid)
		)
		(fill yes)
		(layer "In6.Cu")
		(net "M_C_CPU0_SA_RSP<0>")
	)
	(gr_poly
		(pts
			(xy 342.561164 -254.184404) (xy 342.452706 -254.067564) (xy 342.414352 -254.045466) (xy 342.236552 -254.353314)
			(xy 342.274906 -254.375412) (xy 342.430354 -254.410972)
		)
		(stroke
			(width 0)
			(type solid)
		)
		(fill yes)
		(layer "In6.Cu")
		(net "M_C_CPU0_SA_RSP<1>")
	)
	(gr_poly
		(pts
			(xy 342.69299 -246.820182) (xy 342.731344 -246.798084) (xy 342.553544 -246.490236) (xy 342.51519 -246.512334)
			(xy 342.406732 -246.629174) (xy 342.537542 -246.855742)
		)
		(stroke
			(width 0)
			(type solid)
		)
		(fill yes)
		(layer "In6.Cu")
		(net "M_D_CPU0_SB_CS_N<2>")
	)
	(gr_poly
		(pts
			(xy 342.808306 -246.209566) (xy 342.916764 -246.092726) (xy 342.785954 -245.866158) (xy 342.630506 -245.901718)
			(xy 342.592152 -245.923816) (xy 342.769952 -246.231664)
		)
		(stroke
			(width 0)
			(type solid)
		)
		(fill yes)
		(layer "In6.Cu")
		(net "M_D_CPU0_SB_CS_N<3>")
	)
	(gr_poly
		(pts
			(xy 342.833198 -247.787922) (xy 342.833198 -247.743726) (xy 342.477598 -247.743726) (xy 342.477598 -247.787922)
			(xy 342.524588 -247.940322) (xy 342.786208 -247.940322)
		)
		(stroke
			(width 0)
			(type solid)
		)
		(fill yes)
		(layer "In6.Cu")
		(net "M_A_CPU0_SA_RSP<1>")
	)
	(gr_poly
		(pts
			(xy 342.833198 -244.940582) (xy 342.786208 -244.788182) (xy 342.524588 -244.788182) (xy 342.477598 -244.940582)
			(xy 342.477598 -244.985032) (xy 342.833198 -244.985032)
		)
		(stroke
			(width 0)
			(type solid)
		)
		(fill yes)
		(layer "In6.Cu")
		(net "M_D_CPU0_SB_CS_N<1>")
	)
	(gr_poly
		(pts
			(xy 342.833198 -240.057178) (xy 342.786208 -239.904778) (xy 342.524588 -239.904778) (xy 342.477598 -240.057178)
			(xy 342.477598 -240.101628) (xy 342.833198 -240.101628)
		)
		(stroke
			(width 0)
			(type solid)
		)
		(fill yes)
		(layer "In6.Cu")
		(net "M_C_CPU0_SB_DQ<7>")
	)
	(gr_poly
		(pts
			(xy 342.833198 -235.174282) (xy 342.786208 -235.021882) (xy 342.524588 -235.021882) (xy 342.477598 -235.174282)
			(xy 342.477598 -235.218478) (xy 342.833198 -235.218478)
		)
		(stroke
			(width 0)
			(type solid)
		)
		(fill yes)
		(layer "In6.Cu")
		(net "M_C_CPU0_SB_DQ<15>")
	)
	(gr_poly
		(pts
			(xy 342.833198 -230.290878) (xy 342.786208 -230.138478) (xy 342.524588 -230.138478) (xy 342.477598 -230.290878)
			(xy 342.477598 -230.335074) (xy 342.833198 -230.335074)
		)
		(stroke
			(width 0)
			(type solid)
		)
		(fill yes)
		(layer "In6.Cu")
		(net "M_D_CPU0_SB_DQ<23>")
	)
	(gr_poly
		(pts
			(xy 342.833198 -225.407474) (xy 342.786208 -225.255074) (xy 342.524588 -225.255074) (xy 342.477598 -225.407474)
			(xy 342.477598 -225.45167) (xy 342.833198 -225.45167)
		)
		(stroke
			(width 0)
			(type solid)
		)
		(fill yes)
		(layer "In6.Cu")
		(net "M_C_CPU0_SB_DQ<29>")
	)
	(gr_poly
		(pts
			(xy 342.835738 -241.685318) (xy 342.788748 -241.532918) (xy 342.527128 -241.532918) (xy 342.480138 -241.685318)
			(xy 342.480138 -241.729768) (xy 342.835738 -241.729768)
		)
		(stroke
			(width 0)
			(type solid)
		)
		(fill yes)
		(layer "In6.Cu")
		(net "M_C_CPU0_SB_DQS_DP<5>")
	)
	(gr_poly
		(pts
			(xy 342.84158 -248.196354) (xy 342.79459 -248.043954) (xy 342.53297 -248.043954) (xy 342.48598 -248.196354)
			(xy 342.48598 -248.240804) (xy 342.84158 -248.240804)
		)
		(stroke
			(width 0)
			(type solid)
		)
		(fill yes)
		(layer "In6.Cu")
		(net "M_A_CPU0_SA_RSP<0>")
	)
	(gr_poly
		(pts
			(xy 342.84158 -244.53215) (xy 342.84158 -244.487954) (xy 342.48598 -244.487954) (xy 342.48598 -244.53215)
			(xy 342.53297 -244.68455) (xy 342.79459 -244.68455)
		)
		(stroke
			(width 0)
			(type solid)
		)
		(fill yes)
		(layer "In6.Cu")
		(net "M_C_CPU0_SB_DQ<0>")
	)
	(gr_poly
		(pts
			(xy 342.84158 -234.76585) (xy 342.84158 -234.7214) (xy 342.48598 -234.7214) (xy 342.48598 -234.76585)
			(xy 342.53297 -234.91825) (xy 342.79459 -234.91825)
		)
		(stroke
			(width 0)
			(type solid)
		)
		(fill yes)
		(layer "In6.Cu")
		(net "M_D_CPU0_SB_DQ<16>")
	)
	(gr_poly
		(pts
			(xy 342.84158 -229.882446) (xy 342.84158 -229.837996) (xy 342.48598 -229.837996) (xy 342.48598 -229.882446)
			(xy 342.53297 -230.034846) (xy 342.79459 -230.034846)
		)
		(stroke
			(width 0)
			(type solid)
		)
		(fill yes)
		(layer "In6.Cu")
		(net "M_C_CPU0_SB_DQ<26>")
	)
	(gr_poly
		(pts
			(xy 342.942926 -253.309882) (xy 342.895936 -253.157482) (xy 342.634316 -253.157482) (xy 342.587326 -253.309882)
			(xy 342.587326 -253.354332) (xy 342.942926 -253.354332)
		)
		(stroke
			(width 0)
			(type solid)
		)
		(fill yes)
		(layer "In6.Cu")
		(net "M_C_CPU0_SB_RSP<1>")
	)
	(gr_poly
		(pts
			(xy 342.94318 -272.435066) (xy 342.94318 -272.39087) (xy 342.58758 -272.39087) (xy 342.58758 -272.435066)
			(xy 342.63457 -272.587466) (xy 342.89619 -272.587466)
		)
		(stroke
			(width 0)
			(type solid)
		)
		(fill yes)
		(layer "In6.Cu")
		(net "M_C_CPU0_SA_DQ<8>")
	)
	(gr_poly
		(pts
			(xy 342.94318 -267.551662) (xy 342.94318 -267.507466) (xy 342.58758 -267.507466) (xy 342.58758 -267.551662)
			(xy 342.63457 -267.704062) (xy 342.89619 -267.704062)
		)
		(stroke
			(width 0)
			(type solid)
		)
		(fill yes)
		(layer "In6.Cu")
		(net "M_C_CPU0_SA_DQ<24>")
	)
	(gr_poly
		(pts
			(xy 342.94318 -262.668258) (xy 342.94318 -262.624062) (xy 342.58758 -262.624062) (xy 342.58758 -262.668258)
			(xy 342.63457 -262.820658) (xy 342.89619 -262.820658)
		)
		(stroke
			(width 0)
			(type solid)
		)
		(fill yes)
		(layer "In6.Cu")
		(net "M_C_CPU0_SA_CB<2>")
	)
	(gr_poly
		(pts
			(xy 342.94572 -256.565654) (xy 342.89873 -256.413254) (xy 342.63711 -256.413254) (xy 342.59012 -256.565654)
			(xy 342.59012 -256.610104) (xy 342.94572 -256.610104)
		)
		(stroke
			(width 0)
			(type solid)
		)
		(fill yes)
		(layer "In6.Cu")
		(net "M_D_CPU0_SB_RSP<0>")
	)
	(gr_poly
		(pts
			(xy 342.951562 -272.843498) (xy 342.904572 -272.691098) (xy 342.642952 -272.691098) (xy 342.595962 -272.843498)
			(xy 342.595962 -272.887948) (xy 342.951562 -272.887948)
		)
		(stroke
			(width 0)
			(type solid)
		)
		(fill yes)
		(layer "In6.Cu")
		(net "M_D_CPU0_SA_DQ<7>")
	)
	(gr_poly
		(pts
			(xy 342.951562 -267.960094) (xy 342.904572 -267.807694) (xy 342.642952 -267.807694) (xy 342.595962 -267.960094)
			(xy 342.595962 -268.004544) (xy 342.951562 -268.004544)
		)
		(stroke
			(width 0)
			(type solid)
		)
		(fill yes)
		(layer "In6.Cu")
		(net "M_C_CPU0_SA_DQ<15>")
	)
	(gr_poly
		(pts
			(xy 342.951562 -258.193286) (xy 342.904572 -258.040886) (xy 342.642952 -258.040886) (xy 342.595962 -258.193286)
			(xy 342.595962 -258.237736) (xy 342.951562 -258.237736)
		)
		(stroke
			(width 0)
			(type solid)
		)
		(fill yes)
		(layer "In6.Cu")
		(net "M_C_CPU0_SA_CB<5>")
	)
	(gr_poly
		(pts
			(xy 342.951816 -277.317962) (xy 342.951816 -277.273766) (xy 342.596216 -277.273766) (xy 342.596216 -277.317962)
			(xy 342.643206 -277.470362) (xy 342.904826 -277.470362)
		)
		(stroke
			(width 0)
			(type solid)
		)
		(fill yes)
		(layer "In6.Cu")
		(net "M_D_CPU0_SA_DQ<0>")
	)
	(gr_poly
		(pts
			(xy 342.955118 -263.077198) (xy 342.908128 -262.924798) (xy 342.646508 -262.924798) (xy 342.599518 -263.077198)
			(xy 342.599518 -263.121394) (xy 342.955118 -263.121394)
		)
		(stroke
			(width 0)
			(type solid)
		)
		(fill yes)
		(layer "In6.Cu")
		(net "M_C_CPU0_SA_DQ<31>")
	)
	(gr_poly
		(pts
			(xy 342.959944 -261.040626) (xy 342.959944 -260.99643) (xy 342.604344 -260.99643) (xy 342.604344 -261.040626)
			(xy 342.651334 -261.193026) (xy 342.912954 -261.193026)
		)
		(stroke
			(width 0)
			(type solid)
		)
		(fill yes)
		(layer "In6.Cu")
		(net "M_C_CPU0_SA_DQS_DN<9>")
	)
	(gr_poly
		(pts
			(xy 343.272872 -259.258562) (xy 343.311226 -259.236464) (xy 343.133426 -258.928616) (xy 343.095072 -258.950714)
			(xy 342.986614 -259.067554) (xy 343.117424 -259.294122)
		)
		(stroke
			(width 0)
			(type solid)
		)
		(fill yes)
		(layer "In6.Cu")
		(net "M_C_CPU0_SA_CB<7>")
	)
	(gr_poly
		(pts
			(xy 343.27719 -225.860356) (xy 343.385648 -225.743516) (xy 343.254838 -225.516948) (xy 343.09939 -225.552508)
			(xy 343.061036 -225.574606) (xy 343.238836 -225.882454)
		)
		(stroke
			(width 0)
			(type solid)
		)
		(fill yes)
		(layer "In6.Cu")
		(net "M_C_CPU0_SB_DQ<29>")
	)
	(gr_poly
		(pts
			(xy 343.317576 -248.602246) (xy 343.317576 -248.557796) (xy 342.961976 -248.557796) (xy 342.961976 -248.602246)
			(xy 343.008966 -248.754646) (xy 343.270586 -248.754646)
		)
		(stroke
			(width 0)
			(type solid)
		)
		(fill yes)
		(layer "In6.Cu")
		(net "M_A_CPU0_SB_RSP<0>")
	)
	(gr_poly
		(pts
			(xy 343.320116 -247.382538) (xy 343.273126 -247.230138) (xy 343.011506 -247.230138) (xy 342.964516 -247.382538)
			(xy 342.964516 -247.426734) (xy 343.320116 -247.426734)
		)
		(stroke
			(width 0)
			(type solid)
		)
		(fill yes)
		(layer "In6.Cu")
		(net "M_A_CPU0_SB_RSP<1>")
	)
	(gr_poly
		(pts
			(xy 343.320116 -246.974106) (xy 343.320116 -246.92991) (xy 342.964516 -246.92991) (xy 342.964516 -246.974106)
			(xy 343.011506 -247.126506) (xy 343.273126 -247.126506)
		)
		(stroke
			(width 0)
			(type solid)
		)
		(fill yes)
		(layer "In6.Cu")
		(net "M_D_CPU0_SB_CS_N<2>")
	)
	(gr_poly
		(pts
			(xy 343.320116 -240.46307) (xy 343.320116 -240.418874) (xy 342.964516 -240.418874) (xy 342.964516 -240.46307)
			(xy 343.011506 -240.61547) (xy 343.273126 -240.61547)
		)
		(stroke
			(width 0)
			(type solid)
		)
		(fill yes)
		(layer "In6.Cu")
		(net "M_C_CPU0_SB_DQ<5>")
	)
	(gr_poly
		(pts
			(xy 343.388696 -258.648962) (xy 343.497154 -258.532122) (xy 343.366344 -258.305554) (xy 343.210896 -258.341114)
			(xy 343.172542 -258.363212) (xy 343.350342 -258.67106)
		)
		(stroke
			(width 0)
			(type solid)
		)
		(fill yes)
		(layer "In6.Cu")
		(net "M_C_CPU0_SA_CB<5>")
	)
	(gr_poly
		(pts
			(xy 343.41308 -273.657314) (xy 343.36609 -273.504914) (xy 343.10447 -273.504914) (xy 343.05748 -273.657314)
			(xy 343.05748 -273.70151) (xy 343.41308 -273.70151)
		)
		(stroke
			(width 0)
			(type solid)
		)
		(fill yes)
		(layer "In6.Cu")
		(net "M_D_CPU0_SA_DQ<6>")
	)
	(gr_poly
		(pts
			(xy 343.41308 -268.77391) (xy 343.36609 -268.62151) (xy 343.10447 -268.62151) (xy 343.05748 -268.77391)
			(xy 343.05748 -268.818106) (xy 343.41308 -268.818106)
		)
		(stroke
			(width 0)
			(type solid)
		)
		(fill yes)
		(layer "In6.Cu")
		(net "M_C_CPU0_SA_DQ<14>")
	)
	(gr_poly
		(pts
			(xy 343.421716 -254.124206) (xy 343.374726 -253.971806) (xy 343.113106 -253.971806) (xy 343.066116 -254.124206)
			(xy 343.066116 -254.168402) (xy 343.421716 -254.168402)
		)
		(stroke
			(width 0)
			(type solid)
		)
		(fill yes)
		(layer "In6.Cu")
		(net "M_C_CPU0_SB_RSP<0>")
	)
	(gr_poly
		(pts
			(xy 343.427558 -273.248882) (xy 343.427558 -273.204686) (xy 343.071958 -273.204686) (xy 343.071958 -273.248882)
			(xy 343.118948 -273.401282) (xy 343.380568 -273.401282)
		)
		(stroke
			(width 0)
			(type solid)
		)
		(fill yes)
		(layer "In6.Cu")
		(net "M_D_CPU0_SA_DQ<5>")
	)
	(gr_poly
		(pts
			(xy 343.427558 -268.365478) (xy 343.427558 -268.321282) (xy 343.071958 -268.321282) (xy 343.071958 -268.365478)
			(xy 343.118948 -268.517878) (xy 343.380568 -268.517878)
		)
		(stroke
			(width 0)
			(type solid)
		)
		(fill yes)
		(layer "In6.Cu")
		(net "M_C_CPU0_SA_DQ<13>")
	)
	(gr_poly
		(pts
			(xy 343.429844 -253.715774) (xy 343.429844 -253.671324) (xy 343.074244 -253.671324) (xy 343.074244 -253.715774)
			(xy 343.121234 -253.868174) (xy 343.382854 -253.868174)
		)
		(stroke
			(width 0)
			(type solid)
		)
		(fill yes)
		(layer "In6.Cu")
		(net "M_C_CPU0_SA_RSP<1>")
	)
	(gr_poly
		(pts
			(xy 343.430098 -274.876514) (xy 343.430098 -274.832318) (xy 343.074498 -274.832318) (xy 343.074498 -274.876514)
			(xy 343.121488 -275.028914) (xy 343.383108 -275.028914)
		)
		(stroke
			(width 0)
			(type solid)
		)
		(fill yes)
		(layer "In6.Cu")
		(net "M_D_CPU0_SA_DQS_DN<5>")
	)
	(gr_poly
		(pts
			(xy 343.430098 -262.262874) (xy 343.383108 -262.110474) (xy 343.121488 -262.110474) (xy 343.074498 -262.262874)
			(xy 343.074498 -262.30707) (xy 343.430098 -262.30707)
		)
		(stroke
			(width 0)
			(type solid)
		)
		(fill yes)
		(layer "In6.Cu")
		(net "M_C_CPU0_SA_CB<0>")
	)
	(gr_poly
		(pts
			(xy 343.430098 -261.854442) (xy 343.430098 -261.810246) (xy 343.074498 -261.810246) (xy 343.074498 -261.854442)
			(xy 343.121488 -262.006842) (xy 343.383108 -262.006842)
		)
		(stroke
			(width 0)
			(type solid)
		)
		(fill yes)
		(layer "In6.Cu")
		(net "M_C_CPU0_SA_CB<3>")
	)
	(gr_poly
		(pts
			(xy 343.430098 -256.971038) (xy 343.430098 -256.926842) (xy 343.074498 -256.926842) (xy 343.074498 -256.971038)
			(xy 343.121488 -257.123438) (xy 343.383108 -257.123438)
		)
		(stroke
			(width 0)
			(type solid)
		)
		(fill yes)
		(layer "In6.Cu")
		(net "M_D_CPU0_SA_RSP<0>")
	)
	(gr_poly
		(pts
			(xy 343.430098 -255.751838) (xy 343.383108 -255.599438) (xy 343.121488 -255.599438) (xy 343.074498 -255.751838)
			(xy 343.074498 -255.796034) (xy 343.430098 -255.796034)
		)
		(stroke
			(width 0)
			(type solid)
		)
		(fill yes)
		(layer "In6.Cu")
		(net "M_D_CPU0_SB_RSP<1>")
	)
	(gr_poly
		(pts
			(xy 343.671144 -245.930928) (xy 343.63279 -245.90883) (xy 343.477342 -245.87327) (xy 343.346532 -246.099838)
			(xy 343.45499 -246.216678) (xy 343.493344 -246.238776)
		)
		(stroke
			(width 0)
			(type solid)
		)
		(fill yes)
		(layer "In6.Cu")
		(net "M_D_CPU0_SB_CS_N<3>")
	)
	(gr_poly
		(pts
			(xy 343.772998 -241.685318) (xy 343.726008 -241.532918) (xy 343.464388 -241.532918) (xy 343.417398 -241.685318)
			(xy 343.417398 -241.729514) (xy 343.772998 -241.729514)
		)
		(stroke
			(width 0)
			(type solid)
		)
		(fill yes)
		(layer "In6.Cu")
		(net "M_C_CPU0_SB_DQS_DP<5>")
	)
	(gr_poly
		(pts
			(xy 343.772998 -240.057178) (xy 343.726008 -239.904778) (xy 343.464388 -239.904778) (xy 343.417398 -240.057178)
			(xy 343.417398 -240.101628) (xy 343.772998 -240.101628)
		)
		(stroke
			(width 0)
			(type solid)
		)
		(fill yes)
		(layer "In6.Cu")
		(net "M_C_CPU0_SB_DQ<7>")
	)
	(gr_poly
		(pts
			(xy 343.775538 -248.196354) (xy 343.728548 -248.043954) (xy 343.466928 -248.043954) (xy 343.419938 -248.196354)
			(xy 343.419938 -248.24055) (xy 343.775538 -248.24055)
		)
		(stroke
			(width 0)
			(type solid)
		)
		(fill yes)
		(layer "In6.Cu")
		(net "M_A_CPU0_SA_RSP<0>")
	)
	(gr_poly
		(pts
			(xy 343.775538 -247.787922) (xy 343.775538 -247.743726) (xy 343.419938 -247.743726) (xy 343.419938 -247.787922)
			(xy 343.466928 -247.940322) (xy 343.728548 -247.940322)
		)
		(stroke
			(width 0)
			(type solid)
		)
		(fill yes)
		(layer "In6.Cu")
		(net "M_A_CPU0_SA_RSP<1>")
	)
	(gr_poly
		(pts
			(xy 343.855294 -246.638826) (xy 343.746836 -246.521986) (xy 343.708482 -246.499888) (xy 343.530682 -246.807736)
			(xy 343.569036 -246.829834) (xy 343.724484 -246.865394)
		)
		(stroke
			(width 0)
			(type solid)
		)
		(fill yes)
		(layer "In6.Cu")
		(net "M_D_CPU0_SB_CS_N<2>")
	)
	(gr_poly
		(pts
			(xy 343.88298 -262.668258) (xy 343.88298 -262.624062) (xy 343.52738 -262.624062) (xy 343.52738 -262.668258)
			(xy 343.57437 -262.820658) (xy 343.83599 -262.820658)
		)
		(stroke
			(width 0)
			(type solid)
		)
		(fill yes)
		(layer "In6.Cu")
		(net "M_C_CPU0_SA_CB<2>")
	)
	(gr_poly
		(pts
			(xy 343.88298 -256.565654) (xy 343.83599 -256.413254) (xy 343.57437 -256.413254) (xy 343.52738 -256.565654)
			(xy 343.52738 -256.60985) (xy 343.88298 -256.60985)
		)
		(stroke
			(width 0)
			(type solid)
		)
		(fill yes)
		(layer "In6.Cu")
		(net "M_D_CPU0_SB_RSP<0>")
	)
	(gr_poly
		(pts
			(xy 343.88298 -253.309882) (xy 343.83599 -253.157482) (xy 343.57437 -253.157482) (xy 343.52738 -253.309882)
			(xy 343.52738 -253.354332) (xy 343.88298 -253.354332)
		)
		(stroke
			(width 0)
			(type solid)
		)
		(fill yes)
		(layer "In6.Cu")
		(net "M_C_CPU0_SB_RSP<1>")
	)
	(gr_poly
		(pts
			(xy 344.245438 -247.382538) (xy 344.198448 -247.230138) (xy 343.936828 -247.230138) (xy 343.889838 -247.382538)
			(xy 343.889838 -247.426988) (xy 344.245438 -247.426988)
		)
		(stroke
			(width 0)
			(type solid)
		)
		(fill yes)
		(layer "In6.Cu")
		(net "M_A_CPU0_SB_RSP<1>")
	)
	(gr_poly
		(pts
			(xy 344.251534 -248.601738) (xy 344.251534 -248.557542) (xy 343.895934 -248.557542) (xy 343.895934 -248.601738)
			(xy 343.942924 -248.754138) (xy 344.204544 -248.754138)
		)
		(stroke
			(width 0)
			(type solid)
		)
		(fill yes)
		(layer "In6.Cu")
		(net "M_A_CPU0_SB_RSP<0>")
	)
	(gr_poly
		(pts
			(xy 344.715338 -248.196354) (xy 344.668348 -248.043954) (xy 344.406728 -248.043954) (xy 344.359738 -248.196354)
			(xy 344.359738 -248.240804) (xy 344.715338 -248.240804)
		)
		(stroke
			(width 0)
			(type solid)
		)
		(fill yes)
		(layer "In6.Cu")
		(net "M_A_CPU0_SA_RSP<0>")
	)
	(gr_poly
		(pts
			(xy 344.727276 -247.787922) (xy 344.727276 -247.743472) (xy 344.371676 -247.743472) (xy 344.371676 -247.787922)
			(xy 344.418666 -247.940322) (xy 344.680286 -247.940322)
		)
		(stroke
			(width 0)
			(type solid)
		)
		(fill yes)
		(layer "In6.Cu")
		(net "M_A_CPU0_SA_RSP<1>")
	)
	(gr_poly
		(pts
			(xy 345.197176 -247.382538) (xy 345.150186 -247.230138) (xy 344.888566 -247.230138) (xy 344.841576 -247.382538)
			(xy 344.841576 -247.426734) (xy 345.197176 -247.426734)
		)
		(stroke
			(width 0)
			(type solid)
		)
		(fill yes)
		(layer "In6.Cu")
		(net "M_A_CPU0_SB_RSP<1>")
	)
	(gr_poly
		(pts
			(xy 345.199716 -248.602246) (xy 345.199716 -248.557796) (xy 344.844116 -248.557796) (xy 344.844116 -248.602246)
			(xy 344.891106 -248.754646) (xy 345.152726 -248.754646)
		)
		(stroke
			(width 0)
			(type solid)
		)
		(fill yes)
		(layer "In6.Cu")
		(net "M_A_CPU0_SB_RSP<0>")
	)
	(gr_poly
		(pts
			(xy 345.655138 -248.196354) (xy 345.608148 -248.043954) (xy 345.346528 -248.043954) (xy 345.299538 -248.196354)
			(xy 345.299538 -248.24055) (xy 345.655138 -248.24055)
		)
		(stroke
			(width 0)
			(type solid)
		)
		(fill yes)
		(layer "In6.Cu")
		(net "M_A_CPU0_SA_RSP<0>")
	)
	(gr_poly
		(pts
			(xy 345.655138 -247.787922) (xy 345.655138 -247.743726) (xy 345.299538 -247.743726) (xy 345.299538 -247.787922)
			(xy 345.346528 -247.940322) (xy 345.608148 -247.940322)
		)
		(stroke
			(width 0)
			(type solid)
		)
		(fill yes)
		(layer "In6.Cu")
		(net "M_A_CPU0_SA_RSP<1>")
	)
	(gr_poly
		(pts
			(xy 346.125038 -247.382538) (xy 346.078048 -247.230138) (xy 345.816428 -247.230138) (xy 345.769438 -247.382538)
			(xy 345.769438 -247.426988) (xy 346.125038 -247.426988)
		)
		(stroke
			(width 0)
			(type solid)
		)
		(fill yes)
		(layer "In6.Cu")
		(net "M_A_CPU0_SB_RSP<1>")
	)
	(gr_poly
		(pts
			(xy 346.131134 -248.601738) (xy 346.131134 -248.557542) (xy 345.775534 -248.557542) (xy 345.775534 -248.601738)
			(xy 345.822524 -248.754138) (xy 346.084144 -248.754138)
		)
		(stroke
			(width 0)
			(type solid)
		)
		(fill yes)
		(layer "In6.Cu")
		(net "M_A_CPU0_SB_RSP<0>")
	)
	(gr_poly
		(pts
			(xy 346.594938 -248.196354) (xy 346.547948 -248.043954) (xy 346.286328 -248.043954) (xy 346.239338 -248.196354)
			(xy 346.239338 -248.240804) (xy 346.594938 -248.240804)
		)
		(stroke
			(width 0)
			(type solid)
		)
		(fill yes)
		(layer "In6.Cu")
		(net "M_A_CPU0_SA_RSP<0>")
	)
	(gr_poly
		(pts
			(xy 346.606876 -247.787922) (xy 346.606876 -247.743472) (xy 346.251276 -247.743472) (xy 346.251276 -247.787922)
			(xy 346.298266 -247.940322) (xy 346.559886 -247.940322)
		)
		(stroke
			(width 0)
			(type solid)
		)
		(fill yes)
		(layer "In6.Cu")
		(net "M_A_CPU0_SA_RSP<1>")
	)
	(gr_poly
		(pts
			(xy 347.076776 -247.382538) (xy 347.029786 -247.230138) (xy 346.768166 -247.230138) (xy 346.721176 -247.382538)
			(xy 346.721176 -247.426734) (xy 347.076776 -247.426734)
		)
		(stroke
			(width 0)
			(type solid)
		)
		(fill yes)
		(layer "In6.Cu")
		(net "M_A_CPU0_SB_RSP<1>")
	)
	(gr_poly
		(pts
			(xy 347.079316 -248.602246) (xy 347.079316 -248.557796) (xy 346.723716 -248.557796) (xy 346.723716 -248.602246)
			(xy 346.770706 -248.754646) (xy 347.032326 -248.754646)
		)
		(stroke
			(width 0)
			(type solid)
		)
		(fill yes)
		(layer "In6.Cu")
		(net "M_A_CPU0_SB_RSP<0>")
	)
	(gr_poly
		(pts
			(xy 347.532198 -248.196354) (xy 347.485208 -248.043954) (xy 347.223588 -248.043954) (xy 347.176598 -248.196354)
			(xy 347.176598 -248.24055) (xy 347.532198 -248.24055)
		)
		(stroke
			(width 0)
			(type solid)
		)
		(fill yes)
		(layer "In6.Cu")
		(net "M_A_CPU0_SA_RSP<0>")
	)
	(gr_poly
		(pts
			(xy 347.532198 -247.787922) (xy 347.532198 -247.743726) (xy 347.176598 -247.743726) (xy 347.176598 -247.787922)
			(xy 347.223588 -247.940322) (xy 347.485208 -247.940322)
		)
		(stroke
			(width 0)
			(type solid)
		)
		(fill yes)
		(layer "In6.Cu")
		(net "M_A_CPU0_SA_RSP<1>")
	)
	(gr_poly
		(pts
			(xy 347.905832 -246.735092) (xy 347.867478 -246.712994) (xy 347.71203 -246.677434) (xy 347.58122 -246.904002)
			(xy 347.689678 -247.020842) (xy 347.728032 -247.04294)
		)
		(stroke
			(width 0)
			(type solid)
		)
		(fill yes)
		(layer "In6.Cu")
		(net "M_A_CPU0_SB_RSP<1>")
	)
	(gr_poly
		(pts
			(xy 348.019116 -248.602246) (xy 348.019116 -248.557796) (xy 347.663516 -248.557796) (xy 347.663516 -248.602246)
			(xy 347.710506 -248.754646) (xy 347.972126 -248.754646)
		)
		(stroke
			(width 0)
			(type solid)
		)
		(fill yes)
		(layer "In6.Cu")
		(net "M_A_CPU0_SB_RSP<0>")
	)
	(gr_poly
		(pts
			(xy 348.089982 -247.44299) (xy 347.981524 -247.32615) (xy 347.94317 -247.304052) (xy 347.76537 -247.6119)
			(xy 347.803724 -247.633998) (xy 347.959172 -247.669558)
		)
		(stroke
			(width 0)
			(type solid)
		)
		(fill yes)
		(layer "In6.Cu")
		(net "M_A_CPU0_SA_RSP<1>")
	)
	(gr_poly
		(pts
			(xy 348.474538 -246.568722) (xy 348.427548 -246.416322) (xy 348.165928 -246.416322) (xy 348.118938 -246.568722)
			(xy 348.118938 -246.612918) (xy 348.474538 -246.612918)
		)
		(stroke
			(width 0)
			(type solid)
		)
		(fill yes)
		(layer "In6.Cu")
		(net "M_A_CPU0_SB_RSP<1>")
	)
	(gr_poly
		(pts
			(xy 348.950534 -246.974106) (xy 348.950534 -246.929656) (xy 348.594934 -246.929656) (xy 348.594934 -246.974106)
			(xy 348.641924 -247.126506) (xy 348.903544 -247.126506)
		)
		(stroke
			(width 0)
			(type solid)
		)
		(fill yes)
		(layer "In6.Cu")
		(net "M_A_CPU0_SA_RSP<1>")
	)
	(gr_poly
		(pts
			(xy 349.414338 -246.568722) (xy 349.367348 -246.416322) (xy 349.105728 -246.416322) (xy 349.058738 -246.568722)
			(xy 349.058738 -246.613172) (xy 349.414338 -246.613172)
		)
		(stroke
			(width 0)
			(type solid)
		)
		(fill yes)
		(layer "In6.Cu")
		(net "M_A_CPU0_SB_RSP<1>")
	)
	(gr_poly
		(pts
			(xy 349.861124 -247.030494) (xy 349.969582 -246.913654) (xy 349.838772 -246.687086) (xy 349.683324 -246.722646)
			(xy 349.64497 -246.744744) (xy 349.82277 -247.052592)
		)
		(stroke
			(width 0)
			(type solid)
		)
		(fill yes)
		(layer "In6.Cu")
		(net "M_A_CPU0_SB_RSP<1>")
	)
	(gr_poly
		(pts
			(xy 372.909338 -249.416062) (xy 372.909338 -249.371612) (xy 372.553738 -249.371612) (xy 372.553738 -249.416062)
			(xy 372.600728 -249.568462) (xy 372.862348 -249.568462)
		)
		(stroke
			(width 0)
			(type solid)
		)
		(fill yes)
		(layer "In6.Cu")
		(net "M_E_CPU0_SA_RSP<0>")
	)
	(gr_poly
		(pts
			(xy 373.393716 -248.602246) (xy 373.393716 -248.557796) (xy 373.038116 -248.557796) (xy 373.038116 -248.602246)
			(xy 373.085106 -248.754646) (xy 373.346726 -248.754646)
		)
		(stroke
			(width 0)
			(type solid)
		)
		(fill yes)
		(layer "In6.Cu")
		(net "M_E_CPU0_SA_RSP<1>")
	)
	(gr_poly
		(pts
			(xy 373.849138 -249.415554) (xy 373.849138 -249.371358) (xy 373.493538 -249.371358) (xy 373.493538 -249.415554)
			(xy 373.540528 -249.567954) (xy 373.802148 -249.567954)
		)
		(stroke
			(width 0)
			(type solid)
		)
		(fill yes)
		(layer "In6.Cu")
		(net "M_E_CPU0_SA_RSP<0>")
	)
	(gr_poly
		(pts
			(xy 374.325134 -248.601738) (xy 374.325134 -248.557542) (xy 373.969534 -248.557542) (xy 373.969534 -248.601738)
			(xy 374.016524 -248.754138) (xy 374.278144 -248.754138)
		)
		(stroke
			(width 0)
			(type solid)
		)
		(fill yes)
		(layer "In6.Cu")
		(net "M_E_CPU0_SA_RSP<1>")
	)
	(gr_poly
		(pts
			(xy 374.333516 -249.01017) (xy 374.286526 -248.85777) (xy 374.024906 -248.85777) (xy 373.977916 -249.01017)
			(xy 373.977916 -249.05462) (xy 374.333516 -249.05462)
		)
		(stroke
			(width 0)
			(type solid)
		)
		(fill yes)
		(layer "In6.Cu")
		(net "M_E_CPU0_SB_RSP<0>")
	)
	(gr_poly
		(pts
			(xy 374.786398 -249.416062) (xy 374.786398 -249.371612) (xy 374.430798 -249.371612) (xy 374.430798 -249.416062)
			(xy 374.477788 -249.568462) (xy 374.739408 -249.568462)
		)
		(stroke
			(width 0)
			(type solid)
		)
		(fill yes)
		(layer "In6.Cu")
		(net "M_E_CPU0_SA_RSP<0>")
	)
	(gr_poly
		(pts
			(xy 374.788938 -248.196354) (xy 374.741948 -248.043954) (xy 374.480328 -248.043954) (xy 374.433338 -248.196354)
			(xy 374.433338 -248.240804) (xy 374.788938 -248.240804)
		)
		(stroke
			(width 0)
			(type solid)
		)
		(fill yes)
		(layer "In6.Cu")
		(net "M_E_CPU0_SB_RSP<1>")
	)
	(gr_poly
		(pts
			(xy 375.273316 -249.01017) (xy 375.226326 -248.85777) (xy 374.964706 -248.85777) (xy 374.917716 -249.01017)
			(xy 374.917716 -249.05462) (xy 375.273316 -249.05462)
		)
		(stroke
			(width 0)
			(type solid)
		)
		(fill yes)
		(layer "In6.Cu")
		(net "M_E_CPU0_SB_RSP<0>")
	)
	(gr_poly
		(pts
			(xy 375.273316 -248.602246) (xy 375.273316 -248.557796) (xy 374.917716 -248.557796) (xy 374.917716 -248.602246)
			(xy 374.964706 -248.754646) (xy 375.226326 -248.754646)
		)
		(stroke
			(width 0)
			(type solid)
		)
		(fill yes)
		(layer "In6.Cu")
		(net "M_E_CPU0_SA_RSP<1>")
	)
	(gr_poly
		(pts
			(xy 375.726198 -249.416062) (xy 375.726198 -249.371612) (xy 375.370598 -249.371612) (xy 375.370598 -249.416062)
			(xy 375.417588 -249.568462) (xy 375.679208 -249.568462)
		)
		(stroke
			(width 0)
			(type solid)
		)
		(fill yes)
		(layer "In6.Cu")
		(net "M_E_CPU0_SA_RSP<0>")
	)
	(gr_poly
		(pts
			(xy 375.726198 -248.196354) (xy 375.679208 -248.043954) (xy 375.417588 -248.043954) (xy 375.370598 -248.196354)
			(xy 375.370598 -248.24055) (xy 375.726198 -248.24055)
		)
		(stroke
			(width 0)
			(type solid)
		)
		(fill yes)
		(layer "In6.Cu")
		(net "M_E_CPU0_SB_RSP<1>")
	)
	(gr_poly
		(pts
			(xy 375.728738 -244.53215) (xy 375.728738 -244.487954) (xy 375.373138 -244.487954) (xy 375.373138 -244.53215)
			(xy 375.420128 -244.68455) (xy 375.681748 -244.68455)
		)
		(stroke
			(width 0)
			(type solid)
		)
		(fill yes)
		(layer "In6.Cu")
		(net "M_H_CPU0_SB_CS_N<2>")
	)
	(gr_poly
		(pts
			(xy 376.213116 -249.01017) (xy 376.166126 -248.85777) (xy 375.904506 -248.85777) (xy 375.857516 -249.01017)
			(xy 375.857516 -249.05462) (xy 376.213116 -249.05462)
		)
		(stroke
			(width 0)
			(type solid)
		)
		(fill yes)
		(layer "In6.Cu")
		(net "M_E_CPU0_SB_RSP<0>")
	)
	(gr_poly
		(pts
			(xy 376.213116 -248.602246) (xy 376.213116 -248.557796) (xy 375.857516 -248.557796) (xy 375.857516 -248.602246)
			(xy 375.904506 -248.754646) (xy 376.166126 -248.754646)
		)
		(stroke
			(width 0)
			(type solid)
		)
		(fill yes)
		(layer "In6.Cu")
		(net "M_E_CPU0_SA_RSP<1>")
	)
	(gr_poly
		(pts
			(xy 376.213116 -243.718842) (xy 376.213116 -243.674392) (xy 375.857516 -243.674392) (xy 375.857516 -243.718842)
			(xy 375.904506 -243.871242) (xy 376.166126 -243.871242)
		)
		(stroke
			(width 0)
			(type solid)
		)
		(fill yes)
		(layer "In6.Cu")
		(net "M_H_CPU0_SB_CS_N<0>")
	)
	(gr_poly
		(pts
			(xy 376.213116 -242.090702) (xy 376.213116 -242.046506) (xy 375.857516 -242.046506) (xy 375.857516 -242.090702)
			(xy 375.904506 -242.243102) (xy 376.166126 -242.243102)
		)
		(stroke
			(width 0)
			(type solid)
		)
		(fill yes)
		(layer "In6.Cu")
		(net "M_G_CPU0_SB_DQ<0>")
	)
	(gr_poly
		(pts
			(xy 376.213116 -232.732326) (xy 376.166126 -232.579926) (xy 375.904506 -232.579926) (xy 375.857516 -232.732326)
			(xy 375.857516 -232.776776) (xy 376.213116 -232.776776)
		)
		(stroke
			(width 0)
			(type solid)
		)
		(fill yes)
		(layer "In6.Cu")
		(net "M_G_CPU0_SB_DQ<13>")
	)
	(gr_poly
		(pts
			(xy 376.310398 -265.109706) (xy 376.310398 -265.06551) (xy 375.954798 -265.06551) (xy 375.954798 -265.109706)
			(xy 376.001788 -265.262106) (xy 376.263408 -265.262106)
		)
		(stroke
			(width 0)
			(type solid)
		)
		(fill yes)
		(layer "In6.Cu")
		(net "M_G_CPU0_SA_CB<0>")
	)
	(gr_poly
		(pts
			(xy 376.323098 -274.876514) (xy 376.323098 -274.832318) (xy 375.967498 -274.832318) (xy 375.967498 -274.876514)
			(xy 376.014488 -275.028914) (xy 376.276108 -275.028914)
		)
		(stroke
			(width 0)
			(type solid)
		)
		(fill yes)
		(layer "In6.Cu")
		(net "M_G_CPU0_SA_DQ<8>")
	)
	(gr_poly
		(pts
			(xy 376.323098 -269.993618) (xy 376.323098 -269.949168) (xy 375.967498 -269.949168) (xy 375.967498 -269.993618)
			(xy 376.014488 -270.146018) (xy 376.276108 -270.146018)
		)
		(stroke
			(width 0)
			(type solid)
		)
		(fill yes)
		(layer "In6.Cu")
		(net "M_G_CPU0_SA_DQ<24>")
	)
	(gr_poly
		(pts
			(xy 376.665998 -249.416062) (xy 376.665998 -249.371612) (xy 376.310398 -249.371612) (xy 376.310398 -249.416062)
			(xy 376.357388 -249.568462) (xy 376.619008 -249.568462)
		)
		(stroke
			(width 0)
			(type solid)
		)
		(fill yes)
		(layer "In6.Cu")
		(net "M_E_CPU0_SA_RSP<0>")
	)
	(gr_poly
		(pts
			(xy 376.665998 -248.196354) (xy 376.619008 -248.043954) (xy 376.357388 -248.043954) (xy 376.310398 -248.196354)
			(xy 376.310398 -248.24055) (xy 376.665998 -248.24055)
		)
		(stroke
			(width 0)
			(type solid)
		)
		(fill yes)
		(layer "In6.Cu")
		(net "M_E_CPU0_SB_RSP<1>")
	)
	(gr_poly
		(pts
			(xy 376.665998 -244.532658) (xy 376.665998 -244.488208) (xy 376.310398 -244.488208) (xy 376.310398 -244.532658)
			(xy 376.357388 -244.685058) (xy 376.619008 -244.685058)
		)
		(stroke
			(width 0)
			(type solid)
		)
		(fill yes)
		(layer "In6.Cu")
		(net "M_H_CPU0_SB_CS_N<2>")
	)
	(gr_poly
		(pts
			(xy 376.665998 -243.31295) (xy 376.619008 -243.16055) (xy 376.357388 -243.16055) (xy 376.310398 -243.31295)
			(xy 376.310398 -243.3574) (xy 376.665998 -243.3574)
		)
		(stroke
			(width 0)
			(type solid)
		)
		(fill yes)
		(layer "In6.Cu")
		(net "M_H_CPU0_SB_CS_N<1>")
	)
	(gr_poly
		(pts
			(xy 376.665998 -233.546142) (xy 376.619008 -233.393742) (xy 376.357388 -233.393742) (xy 376.310398 -233.546142)
			(xy 376.310398 -233.590592) (xy 376.665998 -233.590592)
		)
		(stroke
			(width 0)
			(type solid)
		)
		(fill yes)
		(layer "In6.Cu")
		(net "M_G_CPU0_SB_DQ<12>")
	)
	(gr_poly
		(pts
			(xy 376.665998 -233.138218) (xy 376.665998 -233.093768) (xy 376.310398 -233.093768) (xy 376.310398 -233.138218)
			(xy 376.357388 -233.290618) (xy 376.619008 -233.290618)
		)
		(stroke
			(width 0)
			(type solid)
		)
		(fill yes)
		(layer "In6.Cu")
		(net "M_G_CPU0_SB_DQ<15>")
	)
	(gr_poly
		(pts
			(xy 376.668538 -241.685318) (xy 376.621548 -241.532918) (xy 376.359928 -241.532918) (xy 376.312938 -241.685318)
			(xy 376.312938 -241.729514) (xy 376.668538 -241.729514)
		)
		(stroke
			(width 0)
			(type solid)
		)
		(fill yes)
		(layer "In6.Cu")
		(net "M_G_CPU0_SB_DQ<2>")
	)
	(gr_poly
		(pts
			(xy 376.668538 -241.276886) (xy 376.668538 -241.23269) (xy 376.312938 -241.23269) (xy 376.312938 -241.276886)
			(xy 376.359928 -241.429286) (xy 376.621548 -241.429286)
		)
		(stroke
			(width 0)
			(type solid)
		)
		(fill yes)
		(layer "In6.Cu")
		(net "M_G_CPU0_SB_DQ<1>")
	)
	(gr_poly
		(pts
			(xy 376.674126 -270.577818) (xy 376.635772 -270.55572) (xy 376.480324 -270.52016) (xy 376.349514 -270.746728)
			(xy 376.457972 -270.863568) (xy 376.496326 -270.885666)
		)
		(stroke
			(width 0)
			(type solid)
		)
		(fill yes)
		(layer "In6.Cu")
		(net "M_G_CPU0_SA_DQ<15>")
	)
	(gr_poly
		(pts
			(xy 376.67946 -260.80212) (xy 376.641106 -260.780022) (xy 376.485658 -260.744462) (xy 376.354848 -260.97103)
			(xy 376.463306 -261.08787) (xy 376.50166 -261.109968)
		)
		(stroke
			(width 0)
			(type solid)
		)
		(fill yes)
		(layer "In6.Cu")
		(net "M_G_CPU0_SA_CB<7>")
	)
	(gr_poly
		(pts
			(xy 376.77598 -274.47113) (xy 376.72899 -274.31873) (xy 376.46737 -274.31873) (xy 376.42038 -274.47113)
			(xy 376.42038 -274.515326) (xy 376.77598 -274.515326)
		)
		(stroke
			(width 0)
			(type solid)
		)
		(fill yes)
		(layer "In6.Cu")
		(net "M_G_CPU0_SA_DQ<10>")
	)
	(gr_poly
		(pts
			(xy 376.787918 -264.29589) (xy 376.787918 -264.25144) (xy 376.432318 -264.25144) (xy 376.432318 -264.29589)
			(xy 376.479308 -264.44829) (xy 376.740928 -264.44829)
		)
		(stroke
			(width 0)
			(type solid)
		)
		(fill yes)
		(layer "In6.Cu")
		(net "M_G_CPU0_SA_CB<1>")
	)
	(gr_poly
		(pts
			(xy 376.790712 -269.178278) (xy 376.790712 -269.134082) (xy 376.435112 -269.134082) (xy 376.435112 -269.178278)
			(xy 376.482102 -269.330678) (xy 376.743722 -269.330678)
		)
		(stroke
			(width 0)
			(type solid)
		)
		(fill yes)
		(layer "In6.Cu")
		(net "M_G_CPU0_SA_DQ<25>")
	)
	(gr_poly
		(pts
			(xy 376.858276 -271.285716) (xy 376.749818 -271.168876) (xy 376.711464 -271.146778) (xy 376.533664 -271.454626)
			(xy 376.572018 -271.476724) (xy 376.727466 -271.512284)
		)
		(stroke
			(width 0)
			(type solid)
		)
		(fill yes)
		(layer "In6.Cu")
		(net "M_G_CPU0_SA_DQ<13>")
	)
	(gr_poly
		(pts
			(xy 377.034044 -227.211636) (xy 376.99569 -227.189538) (xy 376.840242 -227.153978) (xy 376.709432 -227.380546)
			(xy 376.81789 -227.497386) (xy 376.856244 -227.519484)
		)
		(stroke
			(width 0)
			(type solid)
		)
		(fill yes)
		(layer "In6.Cu")
		(net "M_H_CPU0_SB_DQ<23>")
	)
	(gr_poly
		(pts
			(xy 377.140978 -237.616238) (xy 377.093988 -237.463838) (xy 376.832368 -237.463838) (xy 376.785378 -237.616238)
			(xy 376.785378 -237.660434) (xy 377.140978 -237.660434)
		)
		(stroke
			(width 0)
			(type solid)
		)
		(fill yes)
		(layer "In6.Cu")
		(net "M_G_CPU0_SB_DQ<7>")
	)
	(gr_poly
		(pts
			(xy 377.144534 -242.090702) (xy 377.144534 -242.046252) (xy 376.788934 -242.046252) (xy 376.788934 -242.090702)
			(xy 376.835924 -242.243102) (xy 377.097544 -242.243102)
		)
		(stroke
			(width 0)
			(type solid)
		)
		(fill yes)
		(layer "In6.Cu")
		(net "M_G_CPU0_SB_DQ<0>")
	)
	(gr_poly
		(pts
			(xy 377.144534 -240.871502) (xy 377.097544 -240.719102) (xy 376.835924 -240.719102) (xy 376.788934 -240.871502)
			(xy 376.788934 -240.915952) (xy 377.144534 -240.915952)
		)
		(stroke
			(width 0)
			(type solid)
		)
		(fill yes)
		(layer "In6.Cu")
		(net "M_G_CPU0_SB_DQ<3>")
	)
	(gr_poly
		(pts
			(xy 377.144534 -237.207298) (xy 377.144534 -237.163102) (xy 376.788934 -237.163102) (xy 376.788934 -237.207298)
			(xy 376.835924 -237.359698) (xy 377.097544 -237.359698)
		)
		(stroke
			(width 0)
			(type solid)
		)
		(fill yes)
		(layer "In6.Cu")
		(net "M_G_CPU0_SB_DQ<8>")
	)
	(gr_poly
		(pts
			(xy 377.144534 -232.323894) (xy 377.144534 -232.279698) (xy 376.788934 -232.279698) (xy 376.788934 -232.323894)
			(xy 376.835924 -232.476294) (xy 377.097544 -232.476294)
		)
		(stroke
			(width 0)
			(type solid)
		)
		(fill yes)
		(layer "In6.Cu")
		(net "M_H_CPU0_SB_DQ<16>")
	)
	(gr_poly
		(pts
			(xy 377.150376 -249.010678) (xy 377.103386 -248.858278) (xy 376.841766 -248.858278) (xy 376.794776 -249.010678)
			(xy 376.794776 -249.054874) (xy 377.150376 -249.054874)
		)
		(stroke
			(width 0)
			(type solid)
		)
		(fill yes)
		(layer "In6.Cu")
		(net "M_E_CPU0_SB_RSP<0>")
	)
	(gr_poly
		(pts
			(xy 377.150376 -248.601738) (xy 377.150376 -248.557542) (xy 376.794776 -248.557542) (xy 376.794776 -248.601738)
			(xy 376.841766 -248.754138) (xy 377.103386 -248.754138)
		)
		(stroke
			(width 0)
			(type solid)
		)
		(fill yes)
		(layer "In6.Cu")
		(net "M_E_CPU0_SA_RSP<1>")
	)
	(gr_poly
		(pts
			(xy 377.150376 -243.718334) (xy 377.150376 -243.674138) (xy 376.794776 -243.674138) (xy 376.794776 -243.718334)
			(xy 376.841766 -243.870734) (xy 377.103386 -243.870734)
		)
		(stroke
			(width 0)
			(type solid)
		)
		(fill yes)
		(layer "In6.Cu")
		(net "M_H_CPU0_SB_CS_N<0>")
	)
	(gr_poly
		(pts
			(xy 377.152916 -240.46307) (xy 377.152916 -240.418874) (xy 376.797316 -240.418874) (xy 376.797316 -240.46307)
			(xy 376.844306 -240.61547) (xy 377.105926 -240.61547)
		)
		(stroke
			(width 0)
			(type solid)
		)
		(fill yes)
		(layer "In6.Cu")
		(net "M_G_CPU0_SB_DQS_DP<0>")
	)
	(gr_poly
		(pts
			(xy 377.152916 -232.732326) (xy 377.105926 -232.579926) (xy 376.844306 -232.579926) (xy 376.797316 -232.732326)
			(xy 376.797316 -232.776776) (xy 377.152916 -232.776776)
		)
		(stroke
			(width 0)
			(type solid)
		)
		(fill yes)
		(layer "In6.Cu")
		(net "M_G_CPU0_SB_DQ<13>")
	)
	(gr_poly
		(pts
			(xy 377.152916 -230.696262) (xy 377.152916 -230.652066) (xy 376.797316 -230.652066) (xy 376.797316 -230.696262)
			(xy 376.844306 -230.848662) (xy 377.105926 -230.848662)
		)
		(stroke
			(width 0)
			(type solid)
		)
		(fill yes)
		(layer "In6.Cu")
		(net "M_H_CPU0_SB_DQS_DP<2>")
	)
	(gr_poly
		(pts
			(xy 377.219972 -227.915978) (xy 377.111514 -227.799138) (xy 377.07316 -227.77704) (xy 376.89536 -228.084888)
			(xy 376.933714 -228.106986) (xy 377.089162 -228.142546)
		)
		(stroke
			(width 0)
			(type solid)
		)
		(fill yes)
		(layer "In6.Cu")
		(net "M_H_CPU0_SB_DQ<21>")
	)
	(gr_poly
		(pts
			(xy 377.250198 -265.109706) (xy 377.250198 -265.06551) (xy 376.894598 -265.06551) (xy 376.894598 -265.109706)
			(xy 376.941588 -265.262106) (xy 377.203208 -265.262106)
		)
		(stroke
			(width 0)
			(type solid)
		)
		(fill yes)
		(layer "In6.Cu")
		(net "M_G_CPU0_SA_CB<0>")
	)
	(gr_poly
		(pts
			(xy 377.25096 -265.518646) (xy 377.20397 -265.366246) (xy 376.94235 -265.366246) (xy 376.89536 -265.518646)
			(xy 376.89536 -265.563096) (xy 377.25096 -265.563096)
		)
		(stroke
			(width 0)
			(type solid)
		)
		(fill yes)
		(layer "In6.Cu")
		(net "M_G_CPU0_SA_DQ<31>")
	)
	(gr_poly
		(pts
			(xy 377.254516 -275.284946) (xy 377.207526 -275.132546) (xy 376.945906 -275.132546) (xy 376.898916 -275.284946)
			(xy 376.898916 -275.329396) (xy 377.254516 -275.329396)
		)
		(stroke
			(width 0)
			(type solid)
		)
		(fill yes)
		(layer "In6.Cu")
		(net "M_H_CPU0_SA_DQ<7>")
	)
	(gr_poly
		(pts
			(xy 377.262898 -274.876514) (xy 377.262898 -274.832318) (xy 376.907298 -274.832318) (xy 376.907298 -274.876514)
			(xy 376.954288 -275.028914) (xy 377.215908 -275.028914)
		)
		(stroke
			(width 0)
			(type solid)
		)
		(fill yes)
		(layer "In6.Cu")
		(net "M_G_CPU0_SA_DQ<8>")
	)
	(gr_poly
		(pts
			(xy 377.262898 -270.401542) (xy 377.215908 -270.249142) (xy 376.954288 -270.249142) (xy 376.907298 -270.401542)
			(xy 376.907298 -270.445992) (xy 377.262898 -270.445992)
		)
		(stroke
			(width 0)
			(type solid)
		)
		(fill yes)
		(layer "In6.Cu")
		(net "M_G_CPU0_SA_DQ<15>")
	)
	(gr_poly
		(pts
			(xy 377.262898 -269.993618) (xy 377.262898 -269.949168) (xy 376.907298 -269.949168) (xy 376.907298 -269.993618)
			(xy 376.954288 -270.146018) (xy 377.215908 -270.146018)
		)
		(stroke
			(width 0)
			(type solid)
		)
		(fill yes)
		(layer "In6.Cu")
		(net "M_G_CPU0_SA_DQ<24>")
	)
	(gr_poly
		(pts
			(xy 377.262898 -268.365478) (xy 377.262898 -268.321282) (xy 376.907298 -268.321282) (xy 376.907298 -268.365478)
			(xy 376.954288 -268.517878) (xy 377.215908 -268.517878)
		)
		(stroke
			(width 0)
			(type solid)
		)
		(fill yes)
		(layer "In6.Cu")
		(net "M_G_CPU0_SA_DQS_DP<3>")
	)
	(gr_poly
		(pts
			(xy 377.262898 -260.634734) (xy 377.215908 -260.482334) (xy 376.954288 -260.482334) (xy 376.907298 -260.634734)
			(xy 376.907298 -260.679184) (xy 377.262898 -260.679184)
		)
		(stroke
			(width 0)
			(type solid)
		)
		(fill yes)
		(layer "In6.Cu")
		(net "M_G_CPU0_SA_CB<7>")
	)
	(gr_poly
		(pts
			(xy 377.509278 -228.016308) (xy 377.470924 -227.99421) (xy 377.315476 -227.95865) (xy 377.184666 -228.185218)
			(xy 377.293124 -228.302058) (xy 377.331478 -228.324156)
		)
		(stroke
			(width 0)
			(type solid)
		)
		(fill yes)
		(layer "In6.Cu")
		(net "M_H_CPU0_SB_DQ<22>")
	)
	(gr_poly
		(pts
			(xy 377.605798 -240.057178) (xy 377.558808 -239.904778) (xy 377.297188 -239.904778) (xy 377.250198 -240.057178)
			(xy 377.250198 -240.101628) (xy 377.605798 -240.101628)
		)
		(stroke
			(width 0)
			(type solid)
		)
		(fill yes)
		(layer "In6.Cu")
		(net "M_G_CPU0_SB_DQS_DN<0>")
	)
	(gr_poly
		(pts
			(xy 377.605798 -233.138218) (xy 377.605798 -233.093768) (xy 377.250198 -233.093768) (xy 377.250198 -233.138218)
			(xy 377.297188 -233.290618) (xy 377.558808 -233.290618)
		)
		(stroke
			(width 0)
			(type solid)
		)
		(fill yes)
		(layer "In6.Cu")
		(net "M_G_CPU0_SB_DQ<15>")
	)
	(gr_poly
		(pts
			(xy 377.605798 -230.290878) (xy 377.558808 -230.138478) (xy 377.297188 -230.138478) (xy 377.250198 -230.290878)
			(xy 377.250198 -230.335074) (xy 377.605798 -230.335074)
		)
		(stroke
			(width 0)
			(type solid)
		)
		(fill yes)
		(layer "In6.Cu")
		(net "M_H_CPU0_SB_DQS_DN<2>")
	)
	(gr_poly
		(pts
			(xy 377.605798 -227.035106) (xy 377.558808 -226.882706) (xy 377.297188 -226.882706) (xy 377.250198 -227.035106)
			(xy 377.250198 -227.079556) (xy 377.605798 -227.079556)
		)
		(stroke
			(width 0)
			(type solid)
		)
		(fill yes)
		(layer "In6.Cu")
		(net "M_H_CPU0_SB_DQ<23>")
	)
	(gr_poly
		(pts
			(xy 377.608338 -241.685318) (xy 377.561348 -241.532918) (xy 377.299728 -241.532918) (xy 377.252738 -241.685318)
			(xy 377.252738 -241.729768) (xy 377.608338 -241.729768)
		)
		(stroke
			(width 0)
			(type solid)
		)
		(fill yes)
		(layer "In6.Cu")
		(net "M_G_CPU0_SB_DQ<2>")
	)
	(gr_poly
		(pts
			(xy 377.608338 -241.276886) (xy 377.608338 -241.232436) (xy 377.252738 -241.232436) (xy 377.252738 -241.276886)
			(xy 377.299728 -241.429286) (xy 377.561348 -241.429286)
		)
		(stroke
			(width 0)
			(type solid)
		)
		(fill yes)
		(layer "In6.Cu")
		(net "M_G_CPU0_SB_DQ<1>")
	)
	(gr_poly
		(pts
			(xy 377.608338 -236.801914) (xy 377.561348 -236.649514) (xy 377.299728 -236.649514) (xy 377.252738 -236.801914)
			(xy 377.252738 -236.846364) (xy 377.608338 -236.846364)
		)
		(stroke
			(width 0)
			(type solid)
		)
		(fill yes)
		(layer "In6.Cu")
		(net "M_G_CPU0_SB_DQ<10>")
	)
	(gr_poly
		(pts
			(xy 377.608338 -236.393482) (xy 377.608338 -236.349286) (xy 377.252738 -236.349286) (xy 377.252738 -236.393482)
			(xy 377.299728 -236.545882) (xy 377.561348 -236.545882)
		)
		(stroke
			(width 0)
			(type solid)
		)
		(fill yes)
		(layer "In6.Cu")
		(net "M_G_CPU0_SB_DQ<11>")
	)
	(gr_poly
		(pts
			(xy 377.608338 -231.919018) (xy 377.561348 -231.766618) (xy 377.299728 -231.766618) (xy 377.252738 -231.919018)
			(xy 377.252738 -231.963214) (xy 377.608338 -231.963214)
		)
		(stroke
			(width 0)
			(type solid)
		)
		(fill yes)
		(layer "In6.Cu")
		(net "M_H_CPU0_SB_DQ<18>")
	)
	(gr_poly
		(pts
			(xy 377.608338 -231.510078) (xy 377.608338 -231.465882) (xy 377.252738 -231.465882) (xy 377.252738 -231.510078)
			(xy 377.299728 -231.662478) (xy 377.561348 -231.662478)
		)
		(stroke
			(width 0)
			(type solid)
		)
		(fill yes)
		(layer "In6.Cu")
		(net "M_H_CPU0_SB_DQ<17>")
	)
	(gr_poly
		(pts
			(xy 377.61418 -249.415554) (xy 377.61418 -249.371358) (xy 377.25858 -249.371358) (xy 377.25858 -249.415554)
			(xy 377.30557 -249.567954) (xy 377.56719 -249.567954)
		)
		(stroke
			(width 0)
			(type solid)
		)
		(fill yes)
		(layer "In6.Cu")
		(net "M_E_CPU0_SA_RSP<0>")
	)
	(gr_poly
		(pts
			(xy 377.61418 -248.196354) (xy 377.56719 -248.043954) (xy 377.30557 -248.043954) (xy 377.25858 -248.196354)
			(xy 377.25858 -248.240804) (xy 377.61418 -248.240804)
		)
		(stroke
			(width 0)
			(type solid)
		)
		(fill yes)
		(layer "In6.Cu")
		(net "M_E_CPU0_SB_RSP<1>")
	)
	(gr_poly
		(pts
			(xy 377.61418 -244.53215) (xy 377.61418 -244.487954) (xy 377.25858 -244.487954) (xy 377.25858 -244.53215)
			(xy 377.30557 -244.68455) (xy 377.56719 -244.68455)
		)
		(stroke
			(width 0)
			(type solid)
		)
		(fill yes)
		(layer "In6.Cu")
		(net "M_H_CPU0_SB_CS_N<2>")
	)
	(gr_poly
		(pts
			(xy 377.61418 -243.313458) (xy 377.56719 -243.161058) (xy 377.30557 -243.161058) (xy 377.25858 -243.313458)
			(xy 377.25858 -243.357654) (xy 377.61418 -243.357654)
		)
		(stroke
			(width 0)
			(type solid)
		)
		(fill yes)
		(layer "In6.Cu")
		(net "M_H_CPU0_SB_CS_N<1>")
	)
	(gr_poly
		(pts
			(xy 377.61418 -234.76585) (xy 377.61418 -234.7214) (xy 377.25858 -234.7214) (xy 377.25858 -234.76585)
			(xy 377.30557 -234.91825) (xy 377.56719 -234.91825)
		)
		(stroke
			(width 0)
			(type solid)
		)
		(fill yes)
		(layer "In6.Cu")
		(net "M_G_CPU0_SB_DQS_DP<1>")
	)
	(gr_poly
		(pts
			(xy 377.61418 -233.54665) (xy 377.56719 -233.39425) (xy 377.30557 -233.39425) (xy 377.25858 -233.54665)
			(xy 377.25858 -233.590846) (xy 377.61418 -233.590846)
		)
		(stroke
			(width 0)
			(type solid)
		)
		(fill yes)
		(layer "In6.Cu")
		(net "M_G_CPU0_SB_DQ<12>")
	)
	(gr_poly
		(pts
			(xy 377.617736 -238.021114) (xy 377.617736 -237.976664) (xy 377.262136 -237.976664) (xy 377.262136 -238.021114)
			(xy 377.309126 -238.173514) (xy 377.570746 -238.173514)
		)
		(stroke
			(width 0)
			(type solid)
		)
		(fill yes)
		(layer "In6.Cu")
		(net "M_G_CPU0_SB_DQ<5>")
	)
	(gr_poly
		(pts
			(xy 377.618498 -238.430054) (xy 377.571508 -238.277654) (xy 377.309888 -238.277654) (xy 377.262898 -238.430054)
			(xy 377.262898 -238.47425) (xy 377.618498 -238.47425)
		)
		(stroke
			(width 0)
			(type solid)
		)
		(fill yes)
		(layer "In6.Cu")
		(net "M_G_CPU0_SB_DQ<6>")
	)
	(gr_poly
		(pts
			(xy 377.68911 -228.73081) (xy 377.580652 -228.61397) (xy 377.542298 -228.591872) (xy 377.364498 -228.89972)
			(xy 377.402852 -228.921818) (xy 377.5583 -228.957378)
		)
		(stroke
			(width 0)
			(type solid)
		)
		(fill yes)
		(layer "In6.Cu")
		(net "M_H_CPU0_SB_DQ<20>")
	)
	(gr_poly
		(pts
			(xy 377.71578 -274.47113) (xy 377.66879 -274.31873) (xy 377.40717 -274.31873) (xy 377.36018 -274.47113)
			(xy 377.36018 -274.515326) (xy 377.71578 -274.515326)
		)
		(stroke
			(width 0)
			(type solid)
		)
		(fill yes)
		(layer "In6.Cu")
		(net "M_G_CPU0_SA_DQ<10>")
	)
	(gr_poly
		(pts
			(xy 377.71578 -272.843498) (xy 377.66879 -272.691098) (xy 377.40717 -272.691098) (xy 377.36018 -272.843498)
			(xy 377.36018 -272.887694) (xy 377.71578 -272.887694)
		)
		(stroke
			(width 0)
			(type solid)
		)
		(fill yes)
		(layer "In6.Cu")
		(net "M_G_CPU0_SA_DQS_DN<1>")
	)
	(gr_poly
		(pts
			(xy 377.71578 -270.807434) (xy 377.71578 -270.762984) (xy 377.36018 -270.762984) (xy 377.36018 -270.807434)
			(xy 377.40717 -270.959834) (xy 377.66879 -270.959834)
		)
		(stroke
			(width 0)
			(type solid)
		)
		(fill yes)
		(layer "In6.Cu")
		(net "M_G_CPU0_SA_DQ<13>")
	)
	(gr_poly
		(pts
			(xy 377.71578 -269.587726) (xy 377.66879 -269.435326) (xy 377.40717 -269.435326) (xy 377.36018 -269.587726)
			(xy 377.36018 -269.631922) (xy 377.71578 -269.631922)
		)
		(stroke
			(width 0)
			(type solid)
		)
		(fill yes)
		(layer "In6.Cu")
		(net "M_G_CPU0_SA_DQ<26>")
	)
	(gr_poly
		(pts
			(xy 377.71578 -267.960094) (xy 377.66879 -267.807694) (xy 377.40717 -267.807694) (xy 377.36018 -267.960094)
			(xy 377.36018 -268.00429) (xy 377.71578 -268.00429)
		)
		(stroke
			(width 0)
			(type solid)
		)
		(fill yes)
		(layer "In6.Cu")
		(net "M_G_CPU0_SA_DQS_DN<3>")
	)
	(gr_poly
		(pts
			(xy 377.71578 -261.449058) (xy 377.66879 -261.296658) (xy 377.40717 -261.296658) (xy 377.36018 -261.449058)
			(xy 377.36018 -261.493254) (xy 377.71578 -261.493254)
		)
		(stroke
			(width 0)
			(type solid)
		)
		(fill yes)
		(layer "In6.Cu")
		(net "M_G_CPU0_SA_CB<6>")
	)
	(gr_poly
		(pts
			(xy 377.71578 -261.040626) (xy 377.71578 -260.99643) (xy 377.36018 -260.99643) (xy 377.36018 -261.040626)
			(xy 377.40717 -261.193026) (xy 377.66879 -261.193026)
		)
		(stroke
			(width 0)
			(type solid)
		)
		(fill yes)
		(layer "In6.Cu")
		(net "M_G_CPU0_SA_CB<5>")
	)
	(gr_poly
		(pts
			(xy 377.71832 -277.726394) (xy 377.67133 -277.573994) (xy 377.40971 -277.573994) (xy 377.36272 -277.726394)
			(xy 377.36272 -277.770844) (xy 377.71832 -277.770844)
		)
		(stroke
			(width 0)
			(type solid)
		)
		(fill yes)
		(layer "In6.Cu")
		(net "M_H_CPU0_SA_DQS_DN<0>")
	)
	(gr_poly
		(pts
			(xy 377.71832 -276.09927) (xy 377.67133 -275.94687) (xy 377.40971 -275.94687) (xy 377.36272 -276.09927)
			(xy 377.36272 -276.143466) (xy 377.71832 -276.143466)
		)
		(stroke
			(width 0)
			(type solid)
		)
		(fill yes)
		(layer "In6.Cu")
		(net "M_H_CPU0_SA_DQ<6>")
	)
	(gr_poly
		(pts
			(xy 377.71832 -275.690584) (xy 377.71832 -275.646134) (xy 377.36272 -275.646134) (xy 377.36272 -275.690584)
			(xy 377.40971 -275.842984) (xy 377.67133 -275.842984)
		)
		(stroke
			(width 0)
			(type solid)
		)
		(fill yes)
		(layer "In6.Cu")
		(net "M_H_CPU0_SA_DQ<5>")
	)
	(gr_poly
		(pts
			(xy 377.71832 -265.923522) (xy 377.71832 -265.879326) (xy 377.36272 -265.879326) (xy 377.36272 -265.923522)
			(xy 377.40971 -266.075922) (xy 377.67133 -266.075922)
		)
		(stroke
			(width 0)
			(type solid)
		)
		(fill yes)
		(layer "In6.Cu")
		(net "M_G_CPU0_SA_DQ<29>")
	)
	(gr_poly
		(pts
			(xy 377.724162 -263.07669) (xy 377.677172 -262.92429) (xy 377.415552 -262.92429) (xy 377.368562 -263.07669)
			(xy 377.368562 -263.12114) (xy 377.724162 -263.12114)
		)
		(stroke
			(width 0)
			(type solid)
		)
		(fill yes)
		(layer "In6.Cu")
		(net "M_G_CPU0_SA_DQS_DN<4>")
	)
	(gr_poly
		(pts
			(xy 377.727718 -274.062698) (xy 377.727718 -274.018248) (xy 377.372118 -274.018248) (xy 377.372118 -274.062698)
			(xy 377.419108 -274.215098) (xy 377.680728 -274.215098)
		)
		(stroke
			(width 0)
			(type solid)
		)
		(fill yes)
		(layer "In6.Cu")
		(net "M_G_CPU0_SA_DQ<9>")
	)
	(gr_poly
		(pts
			(xy 377.727718 -271.215866) (xy 377.680728 -271.063466) (xy 377.419108 -271.063466) (xy 377.372118 -271.215866)
			(xy 377.372118 -271.260062) (xy 377.727718 -271.260062)
		)
		(stroke
			(width 0)
			(type solid)
		)
		(fill yes)
		(layer "In6.Cu")
		(net "M_G_CPU0_SA_DQ<14>")
	)
	(gr_poly
		(pts
			(xy 377.727718 -269.179294) (xy 377.727718 -269.134844) (xy 377.372118 -269.134844) (xy 377.372118 -269.179294)
			(xy 377.419108 -269.331694) (xy 377.680728 -269.331694)
		)
		(stroke
			(width 0)
			(type solid)
		)
		(fill yes)
		(layer "In6.Cu")
		(net "M_G_CPU0_SA_DQ<25>")
	)
	(gr_poly
		(pts
			(xy 377.727718 -266.332462) (xy 377.680728 -266.180062) (xy 377.419108 -266.180062) (xy 377.372118 -266.332462)
			(xy 377.372118 -266.376658) (xy 377.727718 -266.376658)
		)
		(stroke
			(width 0)
			(type solid)
		)
		(fill yes)
		(layer "In6.Cu")
		(net "M_G_CPU0_SA_DQ<30>")
	)
	(gr_poly
		(pts
			(xy 377.727718 -264.29589) (xy 377.727718 -264.25144) (xy 377.372118 -264.25144) (xy 377.372118 -264.29589)
			(xy 377.419108 -264.44829) (xy 377.680728 -264.44829)
		)
		(stroke
			(width 0)
			(type solid)
		)
		(fill yes)
		(layer "In6.Cu")
		(net "M_G_CPU0_SA_CB<1>")
	)
	(gr_poly
		(pts
			(xy 377.72848 -264.70483) (xy 377.68149 -264.55243) (xy 377.41987 -264.55243) (xy 377.37288 -264.70483)
			(xy 377.37288 -264.749026) (xy 377.72848 -264.749026)
		)
		(stroke
			(width 0)
			(type solid)
		)
		(fill yes)
		(layer "In6.Cu")
		(net "M_G_CPU0_SA_CB<2>")
	)
	(gr_poly
		(pts
			(xy 377.97232 -228.843332) (xy 377.933966 -228.821234) (xy 377.778518 -228.785674) (xy 377.647708 -229.012242)
			(xy 377.756166 -229.129082) (xy 377.79452 -229.15118)
		)
		(stroke
			(width 0)
			(type solid)
		)
		(fill yes)
		(layer "In6.Cu")
		(net "M_H_CPU0_SB_DQS_DP<7>")
	)
	(gr_poly
		(pts
			(xy 378.074682 -235.579158) (xy 378.074682 -235.534708) (xy 377.719082 -235.534708) (xy 377.719082 -235.579158)
			(xy 377.766072 -235.731558) (xy 378.027692 -235.731558)
		)
		(stroke
			(width 0)
			(type solid)
		)
		(fill yes)
		(layer "In6.Cu")
		(net "M_G_CPU0_SB_DQS_DN<6>")
	)
	(gr_poly
		(pts
			(xy 378.080016 -238.83493) (xy 378.080016 -238.790734) (xy 377.724416 -238.790734) (xy 377.724416 -238.83493)
			(xy 377.771406 -238.98733) (xy 378.033026 -238.98733)
		)
		(stroke
			(width 0)
			(type solid)
		)
		(fill yes)
		(layer "In6.Cu")
		(net "M_G_CPU0_SB_DQ<4>")
	)
	(gr_poly
		(pts
			(xy 378.080016 -233.951526) (xy 378.080016 -233.90733) (xy 377.724416 -233.90733) (xy 377.724416 -233.951526)
			(xy 377.771406 -234.103926) (xy 378.033026 -234.103926)
		)
		(stroke
			(width 0)
			(type solid)
		)
		(fill yes)
		(layer "In6.Cu")
		(net "M_G_CPU0_SB_DQ<14>")
	)
	(gr_poly
		(pts
			(xy 378.080778 -237.616238) (xy 378.033788 -237.463838) (xy 377.772168 -237.463838) (xy 377.725178 -237.616238)
			(xy 377.725178 -237.660434) (xy 378.080778 -237.660434)
		)
		(stroke
			(width 0)
			(type solid)
		)
		(fill yes)
		(layer "In6.Cu")
		(net "M_G_CPU0_SB_DQ<7>")
	)
	(gr_poly
		(pts
			(xy 378.08408 -239.24387) (xy 378.03709 -239.09147) (xy 377.77547 -239.09147) (xy 377.72848 -239.24387)
			(xy 377.72848 -239.28832) (xy 378.08408 -239.28832)
		)
		(stroke
			(width 0)
			(type solid)
		)
		(fill yes)
		(layer "In6.Cu")
		(net "M_G_CPU0_SB_DQS_DP<5>")
	)
	(gr_poly
		(pts
			(xy 378.090176 -249.01017) (xy 378.043186 -248.85777) (xy 377.781566 -248.85777) (xy 377.734576 -249.01017)
			(xy 377.734576 -249.05462) (xy 378.090176 -249.05462)
		)
		(stroke
			(width 0)
			(type solid)
		)
		(fill yes)
		(layer "In6.Cu")
		(net "M_E_CPU0_SB_RSP<0>")
	)
	(gr_poly
		(pts
			(xy 378.090176 -248.602246) (xy 378.090176 -248.557796) (xy 377.734576 -248.557796) (xy 377.734576 -248.602246)
			(xy 377.781566 -248.754646) (xy 378.043186 -248.754646)
		)
		(stroke
			(width 0)
			(type solid)
		)
		(fill yes)
		(layer "In6.Cu")
		(net "M_E_CPU0_SA_RSP<1>")
	)
	(gr_poly
		(pts
			(xy 378.090176 -244.126766) (xy 378.043186 -243.974366) (xy 377.781566 -243.974366) (xy 377.734576 -244.126766)
			(xy 377.734576 -244.171216) (xy 378.090176 -244.171216)
		)
		(stroke
			(width 0)
			(type solid)
		)
		(fill yes)
		(layer "In6.Cu")
		(net "M_H_CPU0_SB_CS_N<3>")
	)
	(gr_poly
		(pts
			(xy 378.090176 -243.718842) (xy 378.090176 -243.674392) (xy 377.734576 -243.674392) (xy 377.734576 -243.718842)
			(xy 377.781566 -243.871242) (xy 378.043186 -243.871242)
		)
		(stroke
			(width 0)
			(type solid)
		)
		(fill yes)
		(layer "In6.Cu")
		(net "M_H_CPU0_SB_CS_N<0>")
	)
	(gr_poly
		(pts
			(xy 378.090176 -234.360466) (xy 378.043186 -234.208066) (xy 377.781566 -234.208066) (xy 377.734576 -234.360466)
			(xy 377.734576 -234.404662) (xy 378.090176 -234.404662)
		)
		(stroke
			(width 0)
			(type solid)
		)
		(fill yes)
		(layer "In6.Cu")
		(net "M_G_CPU0_SB_DQS_DN<1>")
	)
	(gr_poly
		(pts
			(xy 378.092716 -242.090702) (xy 378.092716 -242.046506) (xy 377.737116 -242.046506) (xy 377.737116 -242.090702)
			(xy 377.784106 -242.243102) (xy 378.045726 -242.243102)
		)
		(stroke
			(width 0)
			(type solid)
		)
		(fill yes)
		(layer "In6.Cu")
		(net "M_G_CPU0_SB_DQ<0>")
	)
	(gr_poly
		(pts
			(xy 378.092716 -240.871502) (xy 378.045726 -240.719102) (xy 377.784106 -240.719102) (xy 377.737116 -240.871502)
			(xy 377.737116 -240.915698) (xy 378.092716 -240.915698)
		)
		(stroke
			(width 0)
			(type solid)
		)
		(fill yes)
		(layer "In6.Cu")
		(net "M_G_CPU0_SB_DQ<3>")
	)
	(gr_poly
		(pts
			(xy 378.092716 -240.46307) (xy 378.092716 -240.418874) (xy 377.737116 -240.418874) (xy 377.737116 -240.46307)
			(xy 377.784106 -240.61547) (xy 378.045726 -240.61547)
		)
		(stroke
			(width 0)
			(type solid)
		)
		(fill yes)
		(layer "In6.Cu")
		(net "M_G_CPU0_SB_DQS_DP<0>")
	)
	(gr_poly
		(pts
			(xy 378.092716 -237.207806) (xy 378.092716 -237.163356) (xy 377.737116 -237.163356) (xy 377.737116 -237.207806)
			(xy 377.784106 -237.360206) (xy 378.045726 -237.360206)
		)
		(stroke
			(width 0)
			(type solid)
		)
		(fill yes)
		(layer "In6.Cu")
		(net "M_G_CPU0_SB_DQ<8>")
	)
	(gr_poly
		(pts
			(xy 378.092716 -235.988098) (xy 378.045726 -235.835698) (xy 377.784106 -235.835698) (xy 377.737116 -235.988098)
			(xy 377.737116 -236.032294) (xy 378.092716 -236.032294)
		)
		(stroke
			(width 0)
			(type solid)
		)
		(fill yes)
		(layer "In6.Cu")
		(net "M_G_CPU0_SB_DQ<9>")
	)
	(gr_poly
		(pts
			(xy 378.092716 -232.732326) (xy 378.045726 -232.579926) (xy 377.784106 -232.579926) (xy 377.737116 -232.732326)
			(xy 377.737116 -232.776776) (xy 378.092716 -232.776776)
		)
		(stroke
			(width 0)
			(type solid)
		)
		(fill yes)
		(layer "In6.Cu")
		(net "M_G_CPU0_SB_DQ<13>")
	)
	(gr_poly
		(pts
			(xy 378.092716 -232.324402) (xy 378.092716 -232.279952) (xy 377.737116 -232.279952) (xy 377.737116 -232.324402)
			(xy 377.784106 -232.476802) (xy 378.045726 -232.476802)
		)
		(stroke
			(width 0)
			(type solid)
		)
		(fill yes)
		(layer "In6.Cu")
		(net "M_H_CPU0_SB_DQ<16>")
	)
	(gr_poly
		(pts
			(xy 378.092716 -231.104694) (xy 378.045726 -230.952294) (xy 377.784106 -230.952294) (xy 377.737116 -231.104694)
			(xy 377.737116 -231.14889) (xy 378.092716 -231.14889)
		)
		(stroke
			(width 0)
			(type solid)
		)
		(fill yes)
		(layer "In6.Cu")
		(net "M_H_CPU0_SB_DQ<19>")
	)
	(gr_poly
		(pts
			(xy 378.092716 -230.696262) (xy 378.092716 -230.652066) (xy 377.737116 -230.652066) (xy 377.737116 -230.696262)
			(xy 377.784106 -230.848662) (xy 378.045726 -230.848662)
		)
		(stroke
			(width 0)
			(type solid)
		)
		(fill yes)
		(layer "In6.Cu")
		(net "M_H_CPU0_SB_DQS_DP<2>")
	)
	(gr_poly
		(pts
			(xy 378.092716 -227.848922) (xy 378.045726 -227.696522) (xy 377.784106 -227.696522) (xy 377.737116 -227.848922)
			(xy 377.737116 -227.893372) (xy 378.092716 -227.893372)
		)
		(stroke
			(width 0)
			(type solid)
		)
		(fill yes)
		(layer "In6.Cu")
		(net "M_H_CPU0_SB_DQ<22>")
	)
	(gr_poly
		(pts
			(xy 378.092716 -227.440998) (xy 378.092716 -227.396548) (xy 377.737116 -227.396548) (xy 377.737116 -227.440998)
			(xy 377.784106 -227.593398) (xy 378.045726 -227.593398)
		)
		(stroke
			(width 0)
			(type solid)
		)
		(fill yes)
		(layer "In6.Cu")
		(net "M_H_CPU0_SB_DQ<21>")
	)
	(gr_poly
		(pts
			(xy 378.16536 -229.534466) (xy 378.056902 -229.417626) (xy 378.018548 -229.395528) (xy 377.840748 -229.703376)
			(xy 377.879102 -229.725474) (xy 378.03455 -229.761034)
		)
		(stroke
			(width 0)
			(type solid)
		)
		(fill yes)
		(layer "In6.Cu")
		(net "M_H_CPU0_SB_DQS_DN<7>")
	)
	(gr_poly
		(pts
			(xy 378.189998 -265.109706) (xy 378.189998 -265.06551) (xy 377.834398 -265.06551) (xy 377.834398 -265.109706)
			(xy 377.881388 -265.262106) (xy 378.143008 -265.262106)
		)
		(stroke
			(width 0)
			(type solid)
		)
		(fill yes)
		(layer "In6.Cu")
		(net "M_G_CPU0_SA_CB<0>")
	)
	(gr_poly
		(pts
			(xy 378.19076 -273.657314) (xy 378.14377 -273.504914) (xy 377.88215 -273.504914) (xy 377.83516 -273.657314)
			(xy 377.83516 -273.701764) (xy 378.19076 -273.701764)
		)
		(stroke
			(width 0)
			(type solid)
		)
		(fill yes)
		(layer "In6.Cu")
		(net "M_G_CPU0_SA_DQ<11>")
	)
	(gr_poly
		(pts
			(xy 378.19076 -271.62125) (xy 378.19076 -271.5768) (xy 377.83516 -271.5768) (xy 377.83516 -271.62125)
			(xy 377.88215 -271.77365) (xy 378.14377 -271.77365)
		)
		(stroke
			(width 0)
			(type solid)
		)
		(fill yes)
		(layer "In6.Cu")
		(net "M_G_CPU0_SA_DQ<12>")
	)
	(gr_poly
		(pts
			(xy 378.19076 -266.737846) (xy 378.19076 -266.693396) (xy 377.83516 -266.693396) (xy 377.83516 -266.737846)
			(xy 377.88215 -266.890246) (xy 378.14377 -266.890246)
		)
		(stroke
			(width 0)
			(type solid)
		)
		(fill yes)
		(layer "In6.Cu")
		(net "M_G_CPU0_SA_DQ<28>")
	)
	(gr_poly
		(pts
			(xy 378.19076 -265.518646) (xy 378.14377 -265.366246) (xy 377.88215 -265.366246) (xy 377.83516 -265.518646)
			(xy 377.83516 -265.563096) (xy 378.19076 -265.563096)
		)
		(stroke
			(width 0)
			(type solid)
		)
		(fill yes)
		(layer "In6.Cu")
		(net "M_G_CPU0_SA_DQ<31>")
	)
	(gr_poly
		(pts
			(xy 378.19076 -263.891014) (xy 378.14377 -263.738614) (xy 377.88215 -263.738614) (xy 377.83516 -263.891014)
			(xy 377.83516 -263.93521) (xy 378.19076 -263.93521)
		)
		(stroke
			(width 0)
			(type solid)
		)
		(fill yes)
		(layer "In6.Cu")
		(net "M_G_CPU0_SA_CB<3>")
	)
	(gr_poly
		(pts
			(xy 378.194062 -272.03019) (xy 378.147072 -271.87779) (xy 377.885452 -271.87779) (xy 377.838462 -272.03019)
			(xy 377.838462 -272.07464) (xy 378.194062 -272.07464)
		)
		(stroke
			(width 0)
			(type solid)
		)
		(fill yes)
		(layer "In6.Cu")
		(net "M_G_CPU0_SA_DQS_DP<6>")
	)
	(gr_poly
		(pts
			(xy 378.195586 -267.146786) (xy 378.148596 -266.994386) (xy 377.886976 -266.994386) (xy 377.839986 -267.146786)
			(xy 377.839986 -267.190982) (xy 378.195586 -267.190982)
		)
		(stroke
			(width 0)
			(type solid)
		)
		(fill yes)
		(layer "In6.Cu")
		(net "M_G_CPU0_SA_DQS_DP<8>")
	)
	(gr_poly
		(pts
			(xy 378.200158 -263.482582) (xy 378.200158 -263.438132) (xy 377.844558 -263.438132) (xy 377.844558 -263.482582)
			(xy 377.891548 -263.634982) (xy 378.153168 -263.634982)
		)
		(stroke
			(width 0)
			(type solid)
		)
		(fill yes)
		(layer "In6.Cu")
		(net "M_G_CPU0_SA_DQS_DP<4>")
	)
	(gr_poly
		(pts
			(xy 378.202698 -276.5044) (xy 378.202698 -276.460204) (xy 377.847098 -276.460204) (xy 377.847098 -276.5044)
			(xy 377.894088 -276.6568) (xy 378.155708 -276.6568)
		)
		(stroke
			(width 0)
			(type solid)
		)
		(fill yes)
		(layer "In6.Cu")
		(net "M_H_CPU0_SA_DQ<4>")
	)
	(gr_poly
		(pts
			(xy 378.202698 -275.284946) (xy 378.155708 -275.132546) (xy 377.894088 -275.132546) (xy 377.847098 -275.284946)
			(xy 377.847098 -275.329142) (xy 378.202698 -275.329142)
		)
		(stroke
			(width 0)
			(type solid)
		)
		(fill yes)
		(layer "In6.Cu")
		(net "M_H_CPU0_SA_DQ<7>")
	)
	(gr_poly
		(pts
			(xy 378.202698 -274.876514) (xy 378.202698 -274.832318) (xy 377.847098 -274.832318) (xy 377.847098 -274.876514)
			(xy 377.894088 -275.028914) (xy 378.155708 -275.028914)
		)
		(stroke
			(width 0)
			(type solid)
		)
		(fill yes)
		(layer "In6.Cu")
		(net "M_G_CPU0_SA_DQ<8>")
	)
	(gr_poly
		(pts
			(xy 378.202698 -273.248882) (xy 378.202698 -273.204686) (xy 377.847098 -273.204686) (xy 377.847098 -273.248882)
			(xy 377.894088 -273.401282) (xy 378.155708 -273.401282)
		)
		(stroke
			(width 0)
			(type solid)
		)
		(fill yes)
		(layer "In6.Cu")
		(net "M_G_CPU0_SA_DQS_DP<1>")
	)
	(gr_poly
		(pts
			(xy 378.202698 -270.401542) (xy 378.155708 -270.249142) (xy 377.894088 -270.249142) (xy 377.847098 -270.401542)
			(xy 377.847098 -270.445992) (xy 378.202698 -270.445992)
		)
		(stroke
			(width 0)
			(type solid)
		)
		(fill yes)
		(layer "In6.Cu")
		(net "M_G_CPU0_SA_DQ<15>")
	)
	(gr_poly
		(pts
			(xy 378.202698 -269.993618) (xy 378.202698 -269.949168) (xy 377.847098 -269.949168) (xy 377.847098 -269.993618)
			(xy 377.894088 -270.146018) (xy 378.155708 -270.146018)
		)
		(stroke
			(width 0)
			(type solid)
		)
		(fill yes)
		(layer "In6.Cu")
		(net "M_G_CPU0_SA_DQ<24>")
	)
	(gr_poly
		(pts
			(xy 378.202698 -268.77391) (xy 378.155708 -268.62151) (xy 377.894088 -268.62151) (xy 377.847098 -268.77391)
			(xy 377.847098 -268.818106) (xy 378.202698 -268.818106)
		)
		(stroke
			(width 0)
			(type solid)
		)
		(fill yes)
		(layer "In6.Cu")
		(net "M_G_CPU0_SA_DQ<27>")
	)
	(gr_poly
		(pts
			(xy 378.202698 -268.365478) (xy 378.202698 -268.321282) (xy 377.847098 -268.321282) (xy 377.847098 -268.365478)
			(xy 377.894088 -268.517878) (xy 378.155708 -268.517878)
		)
		(stroke
			(width 0)
			(type solid)
		)
		(fill yes)
		(layer "In6.Cu")
		(net "M_G_CPU0_SA_DQS_DP<3>")
	)
	(gr_poly
		(pts
			(xy 378.202698 -262.262874) (xy 378.155708 -262.110474) (xy 377.894088 -262.110474) (xy 377.847098 -262.262874)
			(xy 377.847098 -262.30707) (xy 378.202698 -262.30707)
		)
		(stroke
			(width 0)
			(type solid)
		)
		(fill yes)
		(layer "In6.Cu")
		(net "M_G_CPU0_SA_DQS_DP<9>")
	)
	(gr_poly
		(pts
			(xy 378.202698 -261.854442) (xy 378.202698 -261.810246) (xy 377.847098 -261.810246) (xy 377.847098 -261.854442)
			(xy 377.894088 -262.006842) (xy 378.155708 -262.006842)
		)
		(stroke
			(width 0)
			(type solid)
		)
		(fill yes)
		(layer "In6.Cu")
		(net "M_G_CPU0_SA_CB<4>")
	)
	(gr_poly
		(pts
			(xy 378.202698 -260.634734) (xy 378.155708 -260.482334) (xy 377.894088 -260.482334) (xy 377.847098 -260.634734)
			(xy 377.847098 -260.679184) (xy 378.202698 -260.679184)
		)
		(stroke
			(width 0)
			(type solid)
		)
		(fill yes)
		(layer "In6.Cu")
		(net "M_G_CPU0_SA_CB<7>")
	)
	(gr_poly
		(pts
			(xy 378.443744 -229.653084) (xy 378.40539 -229.630986) (xy 378.249942 -229.595426) (xy 378.119132 -229.821994)
			(xy 378.22759 -229.938834) (xy 378.265944 -229.960932)
		)
		(stroke
			(width 0)
			(type solid)
		)
		(fill yes)
		(layer "In6.Cu")
		(net "M_H_CPU0_SB_DQS_DN<2>")
	)
	(gr_poly
		(pts
			(xy 378.545598 -249.416062) (xy 378.545598 -249.371612) (xy 378.189998 -249.371612) (xy 378.189998 -249.416062)
			(xy 378.236988 -249.568462) (xy 378.498608 -249.568462)
		)
		(stroke
			(width 0)
			(type solid)
		)
		(fill yes)
		(layer "In6.Cu")
		(net "M_E_CPU0_SA_RSP<0>")
	)
	(gr_poly
		(pts
			(xy 378.545598 -244.532658) (xy 378.545598 -244.488208) (xy 378.189998 -244.488208) (xy 378.189998 -244.532658)
			(xy 378.236988 -244.685058) (xy 378.498608 -244.685058)
		)
		(stroke
			(width 0)
			(type solid)
		)
		(fill yes)
		(layer "In6.Cu")
		(net "M_H_CPU0_SB_CS_N<2>")
	)
	(gr_poly
		(pts
			(xy 378.545598 -243.31295) (xy 378.498608 -243.16055) (xy 378.236988 -243.16055) (xy 378.189998 -243.31295)
			(xy 378.189998 -243.3574) (xy 378.545598 -243.3574)
		)
		(stroke
			(width 0)
			(type solid)
		)
		(fill yes)
		(layer "In6.Cu")
		(net "M_H_CPU0_SB_CS_N<1>")
	)
	(gr_poly
		(pts
			(xy 378.545598 -241.685318) (xy 378.498608 -241.532918) (xy 378.236988 -241.532918) (xy 378.189998 -241.685318)
			(xy 378.189998 -241.729514) (xy 378.545598 -241.729514)
		)
		(stroke
			(width 0)
			(type solid)
		)
		(fill yes)
		(layer "In6.Cu")
		(net "M_G_CPU0_SB_DQ<2>")
	)
	(gr_poly
		(pts
			(xy 378.545598 -241.276886) (xy 378.545598 -241.23269) (xy 378.189998 -241.23269) (xy 378.189998 -241.276886)
			(xy 378.236988 -241.429286) (xy 378.498608 -241.429286)
		)
		(stroke
			(width 0)
			(type solid)
		)
		(fill yes)
		(layer "In6.Cu")
		(net "M_G_CPU0_SB_DQ<1>")
	)
	(gr_poly
		(pts
			(xy 378.545598 -240.057178) (xy 378.498608 -239.904778) (xy 378.236988 -239.904778) (xy 378.189998 -240.057178)
			(xy 378.189998 -240.101628) (xy 378.545598 -240.101628)
		)
		(stroke
			(width 0)
			(type solid)
		)
		(fill yes)
		(layer "In6.Cu")
		(net "M_G_CPU0_SB_DQS_DN<0>")
	)
	(gr_poly
		(pts
			(xy 378.545598 -239.649254) (xy 378.545598 -239.604804) (xy 378.189998 -239.604804) (xy 378.189998 -239.649254)
			(xy 378.236988 -239.801654) (xy 378.498608 -239.801654)
		)
		(stroke
			(width 0)
			(type solid)
		)
		(fill yes)
		(layer "In6.Cu")
		(net "M_G_CPU0_SB_DQS_DN<5>")
	)
	(gr_poly
		(pts
			(xy 378.545598 -236.801914) (xy 378.498608 -236.649514) (xy 378.236988 -236.649514) (xy 378.189998 -236.801914)
			(xy 378.189998 -236.84611) (xy 378.545598 -236.84611)
		)
		(stroke
			(width 0)
			(type solid)
		)
		(fill yes)
		(layer "In6.Cu")
		(net "M_G_CPU0_SB_DQ<10>")
	)
	(gr_poly
		(pts
			(xy 378.545598 -236.39399) (xy 378.545598 -236.34954) (xy 378.189998 -236.34954) (xy 378.189998 -236.39399)
			(xy 378.236988 -236.54639) (xy 378.498608 -236.54639)
		)
		(stroke
			(width 0)
			(type solid)
		)
		(fill yes)
		(layer "In6.Cu")
		(net "M_G_CPU0_SB_DQ<11>")
	)
	(gr_poly
		(pts
			(xy 378.545598 -234.76585) (xy 378.545598 -234.721654) (xy 378.189998 -234.721654) (xy 378.189998 -234.76585)
			(xy 378.236988 -234.91825) (xy 378.498608 -234.91825)
		)
		(stroke
			(width 0)
			(type solid)
		)
		(fill yes)
		(layer "In6.Cu")
		(net "M_G_CPU0_SB_DQS_DP<1>")
	)
	(gr_poly
		(pts
			(xy 378.545598 -233.546142) (xy 378.498608 -233.393742) (xy 378.236988 -233.393742) (xy 378.189998 -233.546142)
			(xy 378.189998 -233.590592) (xy 378.545598 -233.590592)
		)
		(stroke
			(width 0)
			(type solid)
		)
		(fill yes)
		(layer "In6.Cu")
		(net "M_G_CPU0_SB_DQ<12>")
	)
	(gr_poly
		(pts
			(xy 378.545598 -233.138218) (xy 378.545598 -233.093768) (xy 378.189998 -233.093768) (xy 378.189998 -233.138218)
			(xy 378.236988 -233.290618) (xy 378.498608 -233.290618)
		)
		(stroke
			(width 0)
			(type solid)
		)
		(fill yes)
		(layer "In6.Cu")
		(net "M_G_CPU0_SB_DQ<15>")
	)
	(gr_poly
		(pts
			(xy 378.545598 -231.91851) (xy 378.498608 -231.76611) (xy 378.236988 -231.76611) (xy 378.189998 -231.91851)
			(xy 378.189998 -231.96296) (xy 378.545598 -231.96296)
		)
		(stroke
			(width 0)
			(type solid)
		)
		(fill yes)
		(layer "In6.Cu")
		(net "M_H_CPU0_SB_DQ<18>")
	)
	(gr_poly
		(pts
			(xy 378.545598 -231.510586) (xy 378.545598 -231.466136) (xy 378.189998 -231.466136) (xy 378.189998 -231.510586)
			(xy 378.236988 -231.662986) (xy 378.498608 -231.662986)
		)
		(stroke
			(width 0)
			(type solid)
		)
		(fill yes)
		(layer "In6.Cu")
		(net "M_H_CPU0_SB_DQ<17>")
	)
	(gr_poly
		(pts
			(xy 378.545598 -228.663246) (xy 378.498608 -228.510846) (xy 378.236988 -228.510846) (xy 378.189998 -228.663246)
			(xy 378.189998 -228.707442) (xy 378.545598 -228.707442)
		)
		(stroke
			(width 0)
			(type solid)
		)
		(fill yes)
		(layer "In6.Cu")
		(net "M_H_CPU0_SB_DQS_DP<7>")
	)
	(gr_poly
		(pts
			(xy 378.545598 -228.254814) (xy 378.545598 -228.210618) (xy 378.189998 -228.210618) (xy 378.189998 -228.254814)
			(xy 378.236988 -228.407214) (xy 378.498608 -228.407214)
		)
		(stroke
			(width 0)
			(type solid)
		)
		(fill yes)
		(layer "In6.Cu")
		(net "M_H_CPU0_SB_DQ<20>")
	)
	(gr_poly
		(pts
			(xy 378.548138 -248.196354) (xy 378.501148 -248.043954) (xy 378.239528 -248.043954) (xy 378.192538 -248.196354)
			(xy 378.192538 -248.24055) (xy 378.548138 -248.24055)
		)
		(stroke
			(width 0)
			(type solid)
		)
		(fill yes)
		(layer "In6.Cu")
		(net "M_E_CPU0_SB_RSP<1>")
	)
	(gr_poly
		(pts
			(xy 378.548138 -227.035106) (xy 378.501148 -226.882706) (xy 378.239528 -226.882706) (xy 378.192538 -227.035106)
			(xy 378.192538 -227.079556) (xy 378.548138 -227.079556)
		)
		(stroke
			(width 0)
			(type solid)
		)
		(fill yes)
		(layer "In6.Cu")
		(net "M_H_CPU0_SB_DQ<23>")
	)
	(gr_poly
		(pts
			(xy 378.557536 -238.021114) (xy 378.557536 -237.976664) (xy 378.201936 -237.976664) (xy 378.201936 -238.021114)
			(xy 378.248926 -238.173514) (xy 378.510546 -238.173514)
		)
		(stroke
			(width 0)
			(type solid)
		)
		(fill yes)
		(layer "In6.Cu")
		(net "M_G_CPU0_SB_DQ<5>")
	)
	(gr_poly
		(pts
			(xy 378.557536 -235.174282) (xy 378.510546 -235.021882) (xy 378.248926 -235.021882) (xy 378.201936 -235.174282)
			(xy 378.201936 -235.218732) (xy 378.557536 -235.218732)
		)
		(stroke
			(width 0)
			(type solid)
		)
		(fill yes)
		(layer "In6.Cu")
		(net "M_G_CPU0_SB_DQS_DP<6>")
	)
	(gr_poly
		(pts
			(xy 378.558298 -238.430054) (xy 378.511308 -238.277654) (xy 378.249688 -238.277654) (xy 378.202698 -238.430054)
			(xy 378.202698 -238.47425) (xy 378.558298 -238.47425)
		)
		(stroke
			(width 0)
			(type solid)
		)
		(fill yes)
		(layer "In6.Cu")
		(net "M_G_CPU0_SB_DQ<6>")
	)
	(gr_poly
		(pts
			(xy 378.627894 -230.360982) (xy 378.519436 -230.244142) (xy 378.481082 -230.222044) (xy 378.303282 -230.529892)
			(xy 378.341636 -230.55199) (xy 378.497084 -230.58755)
		)
		(stroke
			(width 0)
			(type solid)
		)
		(fill yes)
		(layer "In6.Cu")
		(net "M_H_CPU0_SB_DQS_DP<2>")
	)
	(gr_poly
		(pts
			(xy 378.65558 -276.098762) (xy 378.60859 -275.946362) (xy 378.34697 -275.946362) (xy 378.29998 -276.098762)
			(xy 378.29998 -276.143212) (xy 378.65558 -276.143212)
		)
		(stroke
			(width 0)
			(type solid)
		)
		(fill yes)
		(layer "In6.Cu")
		(net "M_H_CPU0_SA_DQ<6>")
	)
	(gr_poly
		(pts
			(xy 378.65558 -275.690584) (xy 378.65558 -275.646388) (xy 378.29998 -275.646388) (xy 378.29998 -275.690584)
			(xy 378.34697 -275.842984) (xy 378.60859 -275.842984)
		)
		(stroke
			(width 0)
			(type solid)
		)
		(fill yes)
		(layer "In6.Cu")
		(net "M_H_CPU0_SA_DQ<5>")
	)
	(gr_poly
		(pts
			(xy 378.65558 -274.47113) (xy 378.60859 -274.31873) (xy 378.34697 -274.31873) (xy 378.29998 -274.47113)
			(xy 378.29998 -274.515326) (xy 378.65558 -274.515326)
		)
		(stroke
			(width 0)
			(type solid)
		)
		(fill yes)
		(layer "In6.Cu")
		(net "M_G_CPU0_SA_DQ<10>")
	)
	(gr_poly
		(pts
			(xy 378.65558 -272.843498) (xy 378.60859 -272.691098) (xy 378.34697 -272.691098) (xy 378.29998 -272.843498)
			(xy 378.29998 -272.887694) (xy 378.65558 -272.887694)
		)
		(stroke
			(width 0)
			(type solid)
		)
		(fill yes)
		(layer "In6.Cu")
		(net "M_G_CPU0_SA_DQS_DN<1>")
	)
	(gr_poly
		(pts
			(xy 378.65558 -272.435066) (xy 378.65558 -272.39087) (xy 378.29998 -272.39087) (xy 378.29998 -272.435066)
			(xy 378.34697 -272.587466) (xy 378.60859 -272.587466)
		)
		(stroke
			(width 0)
			(type solid)
		)
		(fill yes)
		(layer "In6.Cu")
		(net "M_G_CPU0_SA_DQS_DN<6>")
	)
	(gr_poly
		(pts
			(xy 378.65558 -270.807434) (xy 378.65558 -270.762984) (xy 378.29998 -270.762984) (xy 378.29998 -270.807434)
			(xy 378.34697 -270.959834) (xy 378.60859 -270.959834)
		)
		(stroke
			(width 0)
			(type solid)
		)
		(fill yes)
		(layer "In6.Cu")
		(net "M_G_CPU0_SA_DQ<13>")
	)
	(gr_poly
		(pts
			(xy 378.65558 -269.587726) (xy 378.60859 -269.435326) (xy 378.34697 -269.435326) (xy 378.29998 -269.587726)
			(xy 378.29998 -269.631922) (xy 378.65558 -269.631922)
		)
		(stroke
			(width 0)
			(type solid)
		)
		(fill yes)
		(layer "In6.Cu")
		(net "M_G_CPU0_SA_DQ<26>")
	)
	(gr_poly
		(pts
			(xy 378.65558 -267.960094) (xy 378.60859 -267.807694) (xy 378.34697 -267.807694) (xy 378.29998 -267.960094)
			(xy 378.29998 -268.00429) (xy 378.65558 -268.00429)
		)
		(stroke
			(width 0)
			(type solid)
		)
		(fill yes)
		(layer "In6.Cu")
		(net "M_G_CPU0_SA_DQS_DN<3>")
	)
	(gr_poly
		(pts
			(xy 378.65558 -267.551662) (xy 378.65558 -267.507466) (xy 378.29998 -267.507466) (xy 378.29998 -267.551662)
			(xy 378.34697 -267.704062) (xy 378.60859 -267.704062)
		)
		(stroke
			(width 0)
			(type solid)
		)
		(fill yes)
		(layer "In6.Cu")
		(net "M_G_CPU0_SA_DQS_DN<8>")
	)
	(gr_poly
		(pts
			(xy 378.65558 -263.07669) (xy 378.60859 -262.92429) (xy 378.34697 -262.92429) (xy 378.29998 -263.07669)
			(xy 378.29998 -263.120886) (xy 378.65558 -263.120886)
		)
		(stroke
			(width 0)
			(type solid)
		)
		(fill yes)
		(layer "In6.Cu")
		(net "M_G_CPU0_SA_DQS_DN<4>")
	)
	(gr_poly
		(pts
			(xy 378.65558 -262.668258) (xy 378.65558 -262.624062) (xy 378.29998 -262.624062) (xy 378.29998 -262.668258)
			(xy 378.34697 -262.820658) (xy 378.60859 -262.820658)
		)
		(stroke
			(width 0)
			(type solid)
		)
		(fill yes)
		(layer "In6.Cu")
		(net "M_G_CPU0_SA_DQS_DN<9>")
	)
	(gr_poly
		(pts
			(xy 378.65558 -261.449058) (xy 378.60859 -261.296658) (xy 378.34697 -261.296658) (xy 378.29998 -261.449058)
			(xy 378.29998 -261.493254) (xy 378.65558 -261.493254)
		)
		(stroke
			(width 0)
			(type solid)
		)
		(fill yes)
		(layer "In6.Cu")
		(net "M_G_CPU0_SA_CB<6>")
	)
	(gr_poly
		(pts
			(xy 378.65558 -261.040626) (xy 378.65558 -260.99643) (xy 378.29998 -260.99643) (xy 378.29998 -261.040626)
			(xy 378.34697 -261.193026) (xy 378.60859 -261.193026)
		)
		(stroke
			(width 0)
			(type solid)
		)
		(fill yes)
		(layer "In6.Cu")
		(net "M_G_CPU0_SA_CB<5>")
	)
	(gr_poly
		(pts
			(xy 378.66447 -277.318216) (xy 378.66447 -277.27402) (xy 378.30887 -277.27402) (xy 378.30887 -277.318216)
			(xy 378.35586 -277.470616) (xy 378.61748 -277.470616)
		)
		(stroke
			(width 0)
			(type solid)
		)
		(fill yes)
		(layer "In6.Cu")
		(net "M_H_CPU0_SA_DQS_DN<5>")
	)
	(gr_poly
		(pts
			(xy 378.667518 -274.062698) (xy 378.667518 -274.018248) (xy 378.311918 -274.018248) (xy 378.311918 -274.062698)
			(xy 378.358908 -274.215098) (xy 378.620528 -274.215098)
		)
		(stroke
			(width 0)
			(type solid)
		)
		(fill yes)
		(layer "In6.Cu")
		(net "M_G_CPU0_SA_DQ<9>")
	)
	(gr_poly
		(pts
			(xy 378.667518 -271.215866) (xy 378.620528 -271.063466) (xy 378.358908 -271.063466) (xy 378.311918 -271.215866)
			(xy 378.311918 -271.260062) (xy 378.667518 -271.260062)
		)
		(stroke
			(width 0)
			(type solid)
		)
		(fill yes)
		(layer "In6.Cu")
		(net "M_G_CPU0_SA_DQ<14>")
	)
	(gr_poly
		(pts
			(xy 378.667518 -269.179294) (xy 378.667518 -269.134844) (xy 378.311918 -269.134844) (xy 378.311918 -269.179294)
			(xy 378.358908 -269.331694) (xy 378.620528 -269.331694)
		)
		(stroke
			(width 0)
			(type solid)
		)
		(fill yes)
		(layer "In6.Cu")
		(net "M_G_CPU0_SA_DQ<25>")
	)
	(gr_poly
		(pts
			(xy 378.667518 -266.332462) (xy 378.620528 -266.180062) (xy 378.358908 -266.180062) (xy 378.311918 -266.332462)
			(xy 378.311918 -266.376658) (xy 378.667518 -266.376658)
		)
		(stroke
			(width 0)
			(type solid)
		)
		(fill yes)
		(layer "In6.Cu")
		(net "M_G_CPU0_SA_DQ<30>")
	)
	(gr_poly
		(pts
			(xy 378.667518 -265.923522) (xy 378.667518 -265.879326) (xy 378.311918 -265.879326) (xy 378.311918 -265.923522)
			(xy 378.358908 -266.075922) (xy 378.620528 -266.075922)
		)
		(stroke
			(width 0)
			(type solid)
		)
		(fill yes)
		(layer "In6.Cu")
		(net "M_G_CPU0_SA_DQ<29>")
	)
	(gr_poly
		(pts
			(xy 378.667518 -264.29589) (xy 378.667518 -264.25144) (xy 378.311918 -264.25144) (xy 378.311918 -264.29589)
			(xy 378.358908 -264.44829) (xy 378.620528 -264.44829)
		)
		(stroke
			(width 0)
			(type solid)
		)
		(fill yes)
		(layer "In6.Cu")
		(net "M_G_CPU0_SA_CB<1>")
	)
	(gr_poly
		(pts
			(xy 378.66828 -264.70483) (xy 378.62129 -264.55243) (xy 378.35967 -264.55243) (xy 378.31268 -264.70483)
			(xy 378.31268 -264.749026) (xy 378.66828 -264.749026)
		)
		(stroke
			(width 0)
			(type solid)
		)
		(fill yes)
		(layer "In6.Cu")
		(net "M_G_CPU0_SA_CB<2>")
	)
	(gr_poly
		(pts
			(xy 378.672598 -277.726394) (xy 378.625608 -277.573994) (xy 378.363988 -277.573994) (xy 378.316998 -277.726394)
			(xy 378.316998 -277.770844) (xy 378.672598 -277.770844)
		)
		(stroke
			(width 0)
			(type solid)
		)
		(fill yes)
		(layer "In6.Cu")
		(net "M_H_CPU0_SA_DQS_DN<0>")
	)
	(gr_poly
		(pts
			(xy 378.919232 -230.457248) (xy 378.880878 -230.43515) (xy 378.72543 -230.39959) (xy 378.59462 -230.626158)
			(xy 378.703078 -230.742998) (xy 378.741432 -230.765096)
		)
		(stroke
			(width 0)
			(type solid)
		)
		(fill yes)
		(layer "In6.Cu")
		(net "M_H_CPU0_SB_DQ<19>")
	)
	(gr_poly
		(pts
			(xy 379.019816 -238.83493) (xy 379.019816 -238.790734) (xy 378.664216 -238.790734) (xy 378.664216 -238.83493)
			(xy 378.711206 -238.98733) (xy 378.972826 -238.98733)
		)
		(stroke
			(width 0)
			(type solid)
		)
		(fill yes)
		(layer "In6.Cu")
		(net "M_G_CPU0_SB_DQ<4>")
	)
	(gr_poly
		(pts
			(xy 379.019816 -233.951526) (xy 379.019816 -233.90733) (xy 378.664216 -233.90733) (xy 378.664216 -233.951526)
			(xy 378.711206 -234.103926) (xy 378.972826 -234.103926)
		)
		(stroke
			(width 0)
			(type solid)
		)
		(fill yes)
		(layer "In6.Cu")
		(net "M_G_CPU0_SB_DQ<14>")
	)
	(gr_poly
		(pts
			(xy 379.020578 -237.616238) (xy 378.973588 -237.463838) (xy 378.711968 -237.463838) (xy 378.664978 -237.616238)
			(xy 378.664978 -237.660434) (xy 379.020578 -237.660434)
		)
		(stroke
			(width 0)
			(type solid)
		)
		(fill yes)
		(layer "In6.Cu")
		(net "M_G_CPU0_SB_DQ<7>")
	)
	(gr_poly
		(pts
			(xy 379.020578 -235.579666) (xy 379.020578 -235.535216) (xy 378.664978 -235.535216) (xy 378.664978 -235.579666)
			(xy 378.711968 -235.732066) (xy 378.973588 -235.732066)
		)
		(stroke
			(width 0)
			(type solid)
		)
		(fill yes)
		(layer "In6.Cu")
		(net "M_G_CPU0_SB_DQS_DN<6>")
	)
	(gr_poly
		(pts
			(xy 379.024134 -248.601738) (xy 379.024134 -248.557542) (xy 378.668534 -248.557542) (xy 378.668534 -248.601738)
			(xy 378.715524 -248.754138) (xy 378.977144 -248.754138)
		)
		(stroke
			(width 0)
			(type solid)
		)
		(fill yes)
		(layer "In6.Cu")
		(net "M_E_CPU0_SA_RSP<1>")
	)
	(gr_poly
		(pts
			(xy 379.024134 -227.44049) (xy 379.024134 -227.396294) (xy 378.668534 -227.396294) (xy 378.668534 -227.44049)
			(xy 378.715524 -227.59289) (xy 378.977144 -227.59289)
		)
		(stroke
			(width 0)
			(type solid)
		)
		(fill yes)
		(layer "In6.Cu")
		(net "M_H_CPU0_SB_DQ<21>")
	)
	(gr_poly
		(pts
			(xy 379.032516 -249.01017) (xy 378.985526 -248.85777) (xy 378.723906 -248.85777) (xy 378.676916 -249.01017)
			(xy 378.676916 -249.05462) (xy 379.032516 -249.05462)
		)
		(stroke
			(width 0)
			(type solid)
		)
		(fill yes)
		(layer "In6.Cu")
		(net "M_E_CPU0_SB_RSP<0>")
	)
	(gr_poly
		(pts
			(xy 379.032516 -244.126766) (xy 378.985526 -243.974366) (xy 378.723906 -243.974366) (xy 378.676916 -244.126766)
			(xy 378.676916 -244.171216) (xy 379.032516 -244.171216)
		)
		(stroke
			(width 0)
			(type solid)
		)
		(fill yes)
		(layer "In6.Cu")
		(net "M_H_CPU0_SB_CS_N<3>")
	)
	(gr_poly
		(pts
			(xy 379.032516 -243.718842) (xy 379.032516 -243.674392) (xy 378.676916 -243.674392) (xy 378.676916 -243.718842)
			(xy 378.723906 -243.871242) (xy 378.985526 -243.871242)
		)
		(stroke
			(width 0)
			(type solid)
		)
		(fill yes)
		(layer "In6.Cu")
		(net "M_H_CPU0_SB_CS_N<0>")
	)
	(gr_poly
		(pts
			(xy 379.032516 -242.090702) (xy 379.032516 -242.046506) (xy 378.676916 -242.046506) (xy 378.676916 -242.090702)
			(xy 378.723906 -242.243102) (xy 378.985526 -242.243102)
		)
		(stroke
			(width 0)
			(type solid)
		)
		(fill yes)
		(layer "In6.Cu")
		(net "M_G_CPU0_SB_DQ<0>")
	)
	(gr_poly
		(pts
			(xy 379.032516 -240.871502) (xy 378.985526 -240.719102) (xy 378.723906 -240.719102) (xy 378.676916 -240.871502)
			(xy 378.676916 -240.915698) (xy 379.032516 -240.915698)
		)
		(stroke
			(width 0)
			(type solid)
		)
		(fill yes)
		(layer "In6.Cu")
		(net "M_G_CPU0_SB_DQ<3>")
	)
	(gr_poly
		(pts
			(xy 379.032516 -240.46307) (xy 379.032516 -240.418874) (xy 378.676916 -240.418874) (xy 378.676916 -240.46307)
			(xy 378.723906 -240.61547) (xy 378.985526 -240.61547)
		)
		(stroke
			(width 0)
			(type solid)
		)
		(fill yes)
		(layer "In6.Cu")
		(net "M_G_CPU0_SB_DQS_DP<0>")
	)
	(gr_poly
		(pts
			(xy 379.032516 -239.243362) (xy 378.985526 -239.090962) (xy 378.723906 -239.090962) (xy 378.676916 -239.243362)
			(xy 378.676916 -239.287812) (xy 379.032516 -239.287812)
		)
		(stroke
			(width 0)
			(type solid)
		)
		(fill yes)
		(layer "In6.Cu")
		(net "M_G_CPU0_SB_DQS_DP<5>")
	)
	(gr_poly
		(pts
			(xy 379.032516 -237.207806) (xy 379.032516 -237.163356) (xy 378.676916 -237.163356) (xy 378.676916 -237.207806)
			(xy 378.723906 -237.360206) (xy 378.985526 -237.360206)
		)
		(stroke
			(width 0)
			(type solid)
		)
		(fill yes)
		(layer "In6.Cu")
		(net "M_G_CPU0_SB_DQ<8>")
	)
	(gr_poly
		(pts
			(xy 379.032516 -235.988098) (xy 378.985526 -235.835698) (xy 378.723906 -235.835698) (xy 378.676916 -235.988098)
			(xy 378.676916 -236.032294) (xy 379.032516 -236.032294)
		)
		(stroke
			(width 0)
			(type solid)
		)
		(fill yes)
		(layer "In6.Cu")
		(net "M_G_CPU0_SB_DQ<9>")
	)
	(gr_poly
		(pts
			(xy 379.032516 -234.360466) (xy 378.985526 -234.208066) (xy 378.723906 -234.208066) (xy 378.676916 -234.360466)
			(xy 378.676916 -234.404662) (xy 379.032516 -234.404662)
		)
		(stroke
			(width 0)
			(type solid)
		)
		(fill yes)
		(layer "In6.Cu")
		(net "M_G_CPU0_SB_DQS_DN<1>")
	)
	(gr_poly
		(pts
			(xy 379.032516 -232.732326) (xy 378.985526 -232.579926) (xy 378.723906 -232.579926) (xy 378.676916 -232.732326)
			(xy 378.676916 -232.776776) (xy 379.032516 -232.776776)
		)
		(stroke
			(width 0)
			(type solid)
		)
		(fill yes)
		(layer "In6.Cu")
		(net "M_G_CPU0_SB_DQ<13>")
	)
	(gr_poly
		(pts
			(xy 379.032516 -232.324402) (xy 379.032516 -232.279952) (xy 378.676916 -232.279952) (xy 378.676916 -232.324402)
			(xy 378.723906 -232.476802) (xy 378.985526 -232.476802)
		)
		(stroke
			(width 0)
			(type solid)
		)
		(fill yes)
		(layer "In6.Cu")
		(net "M_H_CPU0_SB_DQ<16>")
	)
	(gr_poly
		(pts
			(xy 379.032516 -229.477062) (xy 378.985526 -229.324662) (xy 378.723906 -229.324662) (xy 378.676916 -229.477062)
			(xy 378.676916 -229.521258) (xy 379.032516 -229.521258)
		)
		(stroke
			(width 0)
			(type solid)
		)
		(fill yes)
		(layer "In6.Cu")
		(net "M_H_CPU0_SB_DQS_DN<2>")
	)
	(gr_poly
		(pts
			(xy 379.032516 -229.06863) (xy 379.032516 -229.024434) (xy 378.676916 -229.024434) (xy 378.676916 -229.06863)
			(xy 378.723906 -229.22103) (xy 378.985526 -229.22103)
		)
		(stroke
			(width 0)
			(type solid)
		)
		(fill yes)
		(layer "In6.Cu")
		(net "M_H_CPU0_SB_DQS_DN<7>")
	)
	(gr_poly
		(pts
			(xy 379.032516 -227.848922) (xy 378.985526 -227.696522) (xy 378.723906 -227.696522) (xy 378.676916 -227.848922)
			(xy 378.676916 -227.893372) (xy 379.032516 -227.893372)
		)
		(stroke
			(width 0)
			(type solid)
		)
		(fill yes)
		(layer "In6.Cu")
		(net "M_H_CPU0_SB_DQ<22>")
	)
	(gr_poly
		(pts
			(xy 379.098048 -231.17429) (xy 378.98959 -231.05745) (xy 378.951236 -231.035352) (xy 378.773436 -231.3432)
			(xy 378.81179 -231.365298) (xy 378.967238 -231.400858)
		)
		(stroke
			(width 0)
			(type solid)
		)
		(fill yes)
		(layer "In6.Cu")
		(net "M_H_CPU0_SB_DQ<17>")
	)
	(gr_poly
		(pts
			(xy 379.12802 -278.132286) (xy 379.12802 -278.08809) (xy 378.77242 -278.08809) (xy 378.77242 -278.132286)
			(xy 378.81941 -278.284686) (xy 379.08103 -278.284686)
		)
		(stroke
			(width 0)
			(type solid)
		)
		(fill yes)
		(layer "In6.Cu")
		(net "M_H_CPU0_SA_DQS_DP<0>")
	)
	(gr_poly
		(pts
			(xy 379.129798 -265.109706) (xy 379.129798 -265.06551) (xy 378.774198 -265.06551) (xy 378.774198 -265.109706)
			(xy 378.821188 -265.262106) (xy 379.082808 -265.262106)
		)
		(stroke
			(width 0)
			(type solid)
		)
		(fill yes)
		(layer "In6.Cu")
		(net "M_G_CPU0_SA_CB<0>")
	)
	(gr_poly
		(pts
			(xy 379.13056 -271.62125) (xy 379.13056 -271.5768) (xy 378.77496 -271.5768) (xy 378.77496 -271.62125)
			(xy 378.82195 -271.77365) (xy 379.08357 -271.77365)
		)
		(stroke
			(width 0)
			(type solid)
		)
		(fill yes)
		(layer "In6.Cu")
		(net "M_G_CPU0_SA_DQ<12>")
	)
	(gr_poly
		(pts
			(xy 379.13056 -266.737846) (xy 379.13056 -266.693396) (xy 378.77496 -266.693396) (xy 378.77496 -266.737846)
			(xy 378.82195 -266.890246) (xy 379.08357 -266.890246)
		)
		(stroke
			(width 0)
			(type solid)
		)
		(fill yes)
		(layer "In6.Cu")
		(net "M_G_CPU0_SA_DQ<28>")
	)
	(gr_poly
		(pts
			(xy 379.13056 -265.518646) (xy 379.08357 -265.366246) (xy 378.82195 -265.366246) (xy 378.77496 -265.518646)
			(xy 378.77496 -265.563096) (xy 379.13056 -265.563096)
		)
		(stroke
			(width 0)
			(type solid)
		)
		(fill yes)
		(layer "In6.Cu")
		(net "M_G_CPU0_SA_DQ<31>")
	)
	(gr_poly
		(pts
			(xy 379.13056 -263.891014) (xy 379.08357 -263.738614) (xy 378.82195 -263.738614) (xy 378.77496 -263.891014)
			(xy 378.77496 -263.93521) (xy 379.13056 -263.93521)
		)
		(stroke
			(width 0)
			(type solid)
		)
		(fill yes)
		(layer "In6.Cu")
		(net "M_G_CPU0_SA_CB<3>")
	)
	(gr_poly
		(pts
			(xy 379.134116 -276.913086) (xy 379.087126 -276.760686) (xy 378.825506 -276.760686) (xy 378.778516 -276.913086)
			(xy 378.778516 -276.957282) (xy 379.134116 -276.957282)
		)
		(stroke
			(width 0)
			(type solid)
		)
		(fill yes)
		(layer "In6.Cu")
		(net "M_H_CPU0_SA_DQS_DP<5>")
	)
	(gr_poly
		(pts
			(xy 379.139958 -278.540718) (xy 379.092968 -278.388318) (xy 378.831348 -278.388318) (xy 378.784358 -278.540718)
			(xy 378.784358 -278.584914) (xy 379.139958 -278.584914)
		)
		(stroke
			(width 0)
			(type solid)
		)
		(fill yes)
		(layer "In6.Cu")
		(net "M_H_CPU0_SA_DQ<1>")
	)
	(gr_poly
		(pts
			(xy 379.142498 -276.5044) (xy 379.142498 -276.460204) (xy 378.786898 -276.460204) (xy 378.786898 -276.5044)
			(xy 378.833888 -276.6568) (xy 379.095508 -276.6568)
		)
		(stroke
			(width 0)
			(type solid)
		)
		(fill yes)
		(layer "In6.Cu")
		(net "M_H_CPU0_SA_DQ<4>")
	)
	(gr_poly
		(pts
			(xy 379.142498 -275.284946) (xy 379.095508 -275.132546) (xy 378.833888 -275.132546) (xy 378.786898 -275.284946)
			(xy 378.786898 -275.329142) (xy 379.142498 -275.329142)
		)
		(stroke
			(width 0)
			(type solid)
		)
		(fill yes)
		(layer "In6.Cu")
		(net "M_H_CPU0_SA_DQ<7>")
	)
	(gr_poly
		(pts
			(xy 379.142498 -274.876514) (xy 379.142498 -274.832318) (xy 378.786898 -274.832318) (xy 378.786898 -274.876514)
			(xy 378.833888 -275.028914) (xy 379.095508 -275.028914)
		)
		(stroke
			(width 0)
			(type solid)
		)
		(fill yes)
		(layer "In6.Cu")
		(net "M_G_CPU0_SA_DQ<8>")
	)
	(gr_poly
		(pts
			(xy 379.142498 -273.657314) (xy 379.095508 -273.504914) (xy 378.833888 -273.504914) (xy 378.786898 -273.657314)
			(xy 378.786898 -273.70151) (xy 379.142498 -273.70151)
		)
		(stroke
			(width 0)
			(type solid)
		)
		(fill yes)
		(layer "In6.Cu")
		(net "M_G_CPU0_SA_DQ<11>")
	)
	(gr_poly
		(pts
			(xy 379.142498 -273.248882) (xy 379.142498 -273.204686) (xy 378.786898 -273.204686) (xy 378.786898 -273.248882)
			(xy 378.833888 -273.401282) (xy 379.095508 -273.401282)
		)
		(stroke
			(width 0)
			(type solid)
		)
		(fill yes)
		(layer "In6.Cu")
		(net "M_G_CPU0_SA_DQS_DP<1>")
	)
	(gr_poly
		(pts
			(xy 379.142498 -272.029174) (xy 379.095508 -271.876774) (xy 378.833888 -271.876774) (xy 378.786898 -272.029174)
			(xy 378.786898 -272.073624) (xy 379.142498 -272.073624)
		)
		(stroke
			(width 0)
			(type solid)
		)
		(fill yes)
		(layer "In6.Cu")
		(net "M_G_CPU0_SA_DQS_DP<6>")
	)
	(gr_poly
		(pts
			(xy 379.142498 -270.401542) (xy 379.095508 -270.249142) (xy 378.833888 -270.249142) (xy 378.786898 -270.401542)
			(xy 378.786898 -270.445992) (xy 379.142498 -270.445992)
		)
		(stroke
			(width 0)
			(type solid)
		)
		(fill yes)
		(layer "In6.Cu")
		(net "M_G_CPU0_SA_DQ<15>")
	)
	(gr_poly
		(pts
			(xy 379.142498 -269.993618) (xy 379.142498 -269.949168) (xy 378.786898 -269.949168) (xy 378.786898 -269.993618)
			(xy 378.833888 -270.146018) (xy 379.095508 -270.146018)
		)
		(stroke
			(width 0)
			(type solid)
		)
		(fill yes)
		(layer "In6.Cu")
		(net "M_G_CPU0_SA_DQ<24>")
	)
	(gr_poly
		(pts
			(xy 379.142498 -268.77391) (xy 379.095508 -268.62151) (xy 378.833888 -268.62151) (xy 378.786898 -268.77391)
			(xy 378.786898 -268.818106) (xy 379.142498 -268.818106)
		)
		(stroke
			(width 0)
			(type solid)
		)
		(fill yes)
		(layer "In6.Cu")
		(net "M_G_CPU0_SA_DQ<27>")
	)
	(gr_poly
		(pts
			(xy 379.142498 -268.365478) (xy 379.142498 -268.321282) (xy 378.786898 -268.321282) (xy 378.786898 -268.365478)
			(xy 378.833888 -268.517878) (xy 379.095508 -268.517878)
		)
		(stroke
			(width 0)
			(type solid)
		)
		(fill yes)
		(layer "In6.Cu")
		(net "M_G_CPU0_SA_DQS_DP<3>")
	)
	(gr_poly
		(pts
			(xy 379.142498 -267.146278) (xy 379.095508 -266.993878) (xy 378.833888 -266.993878) (xy 378.786898 -267.146278)
			(xy 378.786898 -267.190474) (xy 379.142498 -267.190474)
		)
		(stroke
			(width 0)
			(type solid)
		)
		(fill yes)
		(layer "In6.Cu")
		(net "M_G_CPU0_SA_DQS_DP<8>")
	)
	(gr_poly
		(pts
			(xy 379.142498 -263.482582) (xy 379.142498 -263.438132) (xy 378.786898 -263.438132) (xy 378.786898 -263.482582)
			(xy 378.833888 -263.634982) (xy 379.095508 -263.634982)
		)
		(stroke
			(width 0)
			(type solid)
		)
		(fill yes)
		(layer "In6.Cu")
		(net "M_G_CPU0_SA_DQS_DP<4>")
	)
	(gr_poly
		(pts
			(xy 379.142498 -262.262874) (xy 379.095508 -262.110474) (xy 378.833888 -262.110474) (xy 378.786898 -262.262874)
			(xy 378.786898 -262.30707) (xy 379.142498 -262.30707)
		)
		(stroke
			(width 0)
			(type solid)
		)
		(fill yes)
		(layer "In6.Cu")
		(net "M_G_CPU0_SA_DQS_DP<9>")
	)
	(gr_poly
		(pts
			(xy 379.142498 -261.854442) (xy 379.142498 -261.810246) (xy 378.786898 -261.810246) (xy 378.786898 -261.854442)
			(xy 378.833888 -262.006842) (xy 379.095508 -262.006842)
		)
		(stroke
			(width 0)
			(type solid)
		)
		(fill yes)
		(layer "In6.Cu")
		(net "M_G_CPU0_SA_CB<4>")
	)
	(gr_poly
		(pts
			(xy 379.142498 -260.634734) (xy 379.095508 -260.482334) (xy 378.833888 -260.482334) (xy 378.786898 -260.634734)
			(xy 378.786898 -260.679184) (xy 379.142498 -260.679184)
		)
		(stroke
			(width 0)
			(type solid)
		)
		(fill yes)
		(layer "In6.Cu")
		(net "M_G_CPU0_SA_CB<7>")
	)
	(gr_poly
		(pts
			(xy 379.388878 -231.271826) (xy 379.350524 -231.249728) (xy 379.195076 -231.214168) (xy 379.064266 -231.440736)
			(xy 379.172724 -231.557576) (xy 379.211078 -231.579674)
		)
		(stroke
			(width 0)
			(type solid)
		)
		(fill yes)
		(layer "In6.Cu")
		(net "M_H_CPU0_SB_DQ<18>")
	)
	(gr_poly
		(pts
			(xy 379.485398 -243.31295) (xy 379.438408 -243.16055) (xy 379.176788 -243.16055) (xy 379.129798 -243.31295)
			(xy 379.129798 -243.3574) (xy 379.485398 -243.3574)
		)
		(stroke
			(width 0)
			(type solid)
		)
		(fill yes)
		(layer "In6.Cu")
		(net "M_H_CPU0_SB_CS_N<1>")
	)
	(gr_poly
		(pts
			(xy 379.485398 -241.685318) (xy 379.438408 -241.532918) (xy 379.176788 -241.532918) (xy 379.129798 -241.685318)
			(xy 379.129798 -241.729514) (xy 379.485398 -241.729514)
		)
		(stroke
			(width 0)
			(type solid)
		)
		(fill yes)
		(layer "In6.Cu")
		(net "M_G_CPU0_SB_DQ<2>")
	)
	(gr_poly
		(pts
			(xy 379.485398 -241.276886) (xy 379.485398 -241.23269) (xy 379.129798 -241.23269) (xy 379.129798 -241.276886)
			(xy 379.176788 -241.429286) (xy 379.438408 -241.429286)
		)
		(stroke
			(width 0)
			(type solid)
		)
		(fill yes)
		(layer "In6.Cu")
		(net "M_G_CPU0_SB_DQ<1>")
	)
	(gr_poly
		(pts
			(xy 379.485398 -236.801914) (xy 379.438408 -236.649514) (xy 379.176788 -236.649514) (xy 379.129798 -236.801914)
			(xy 379.129798 -236.84611) (xy 379.485398 -236.84611)
		)
		(stroke
			(width 0)
			(type solid)
		)
		(fill yes)
		(layer "In6.Cu")
		(net "M_G_CPU0_SB_DQ<10>")
	)
	(gr_poly
		(pts
			(xy 379.485398 -236.39399) (xy 379.485398 -236.34954) (xy 379.129798 -236.34954) (xy 379.129798 -236.39399)
			(xy 379.176788 -236.54639) (xy 379.438408 -236.54639)
		)
		(stroke
			(width 0)
			(type solid)
		)
		(fill yes)
		(layer "In6.Cu")
		(net "M_G_CPU0_SB_DQ<11>")
	)
	(gr_poly
		(pts
			(xy 379.485398 -233.546142) (xy 379.438408 -233.393742) (xy 379.176788 -233.393742) (xy 379.129798 -233.546142)
			(xy 379.129798 -233.590592) (xy 379.485398 -233.590592)
		)
		(stroke
			(width 0)
			(type solid)
		)
		(fill yes)
		(layer "In6.Cu")
		(net "M_G_CPU0_SB_DQ<12>")
	)
	(gr_poly
		(pts
			(xy 379.485398 -233.138218) (xy 379.485398 -233.093768) (xy 379.129798 -233.093768) (xy 379.129798 -233.138218)
			(xy 379.176788 -233.290618) (xy 379.438408 -233.290618)
		)
		(stroke
			(width 0)
			(type solid)
		)
		(fill yes)
		(layer "In6.Cu")
		(net "M_G_CPU0_SB_DQ<15>")
	)
	(gr_poly
		(pts
			(xy 379.485398 -228.663246) (xy 379.438408 -228.510846) (xy 379.176788 -228.510846) (xy 379.129798 -228.663246)
			(xy 379.129798 -228.707442) (xy 379.485398 -228.707442)
		)
		(stroke
			(width 0)
			(type solid)
		)
		(fill yes)
		(layer "In6.Cu")
		(net "M_H_CPU0_SB_DQS_DP<7>")
	)
	(gr_poly
		(pts
			(xy 379.485398 -228.254814) (xy 379.485398 -228.210618) (xy 379.129798 -228.210618) (xy 379.129798 -228.254814)
			(xy 379.176788 -228.407214) (xy 379.438408 -228.407214)
		)
		(stroke
			(width 0)
			(type solid)
		)
		(fill yes)
		(layer "In6.Cu")
		(net "M_H_CPU0_SB_DQ<20>")
	)
	(gr_poly
		(pts
			(xy 379.487938 -249.416062) (xy 379.487938 -249.371612) (xy 379.132338 -249.371612) (xy 379.132338 -249.416062)
			(xy 379.179328 -249.568462) (xy 379.440948 -249.568462)
		)
		(stroke
			(width 0)
			(type solid)
		)
		(fill yes)
		(layer "In6.Cu")
		(net "M_E_CPU0_SA_RSP<0>")
	)
	(gr_poly
		(pts
			(xy 379.487938 -248.196354) (xy 379.440948 -248.043954) (xy 379.179328 -248.043954) (xy 379.132338 -248.196354)
			(xy 379.132338 -248.240804) (xy 379.487938 -248.240804)
		)
		(stroke
			(width 0)
			(type solid)
		)
		(fill yes)
		(layer "In6.Cu")
		(net "M_E_CPU0_SB_RSP<1>")
	)
	(gr_poly
		(pts
			(xy 379.487938 -244.532658) (xy 379.487938 -244.488208) (xy 379.132338 -244.488208) (xy 379.132338 -244.532658)
			(xy 379.179328 -244.685058) (xy 379.440948 -244.685058)
		)
		(stroke
			(width 0)
			(type solid)
		)
		(fill yes)
		(layer "In6.Cu")
		(net "M_H_CPU0_SB_CS_N<2>")
	)
	(gr_poly
		(pts
			(xy 379.487938 -240.057178) (xy 379.440948 -239.904778) (xy 379.179328 -239.904778) (xy 379.132338 -240.057178)
			(xy 379.132338 -240.101628) (xy 379.487938 -240.101628)
		)
		(stroke
			(width 0)
			(type solid)
		)
		(fill yes)
		(layer "In6.Cu")
		(net "M_G_CPU0_SB_DQS_DN<0>")
	)
	(gr_poly
		(pts
			(xy 379.487938 -239.649254) (xy 379.487938 -239.604804) (xy 379.132338 -239.604804) (xy 379.132338 -239.649254)
			(xy 379.179328 -239.801654) (xy 379.440948 -239.801654)
		)
		(stroke
			(width 0)
			(type solid)
		)
		(fill yes)
		(layer "In6.Cu")
		(net "M_G_CPU0_SB_DQS_DN<5>")
	)
	(gr_poly
		(pts
			(xy 379.487938 -234.76585) (xy 379.487938 -234.721654) (xy 379.132338 -234.721654) (xy 379.132338 -234.76585)
			(xy 379.179328 -234.91825) (xy 379.440948 -234.91825)
		)
		(stroke
			(width 0)
			(type solid)
		)
		(fill yes)
		(layer "In6.Cu")
		(net "M_G_CPU0_SB_DQS_DP<1>")
	)
	(gr_poly
		(pts
			(xy 379.487938 -230.290878) (xy 379.440948 -230.138478) (xy 379.179328 -230.138478) (xy 379.132338 -230.290878)
			(xy 379.132338 -230.335074) (xy 379.487938 -230.335074)
		)
		(stroke
			(width 0)
			(type solid)
		)
		(fill yes)
		(layer "In6.Cu")
		(net "M_H_CPU0_SB_DQ<19>")
	)
	(gr_poly
		(pts
			(xy 379.487938 -229.882446) (xy 379.487938 -229.83825) (xy 379.132338 -229.83825) (xy 379.132338 -229.882446)
			(xy 379.179328 -230.034846) (xy 379.440948 -230.034846)
		)
		(stroke
			(width 0)
			(type solid)
		)
		(fill yes)
		(layer "In6.Cu")
		(net "M_H_CPU0_SB_DQS_DP<2>")
	)
	(gr_poly
		(pts
			(xy 379.487938 -227.035614) (xy 379.440948 -226.883214) (xy 379.179328 -226.883214) (xy 379.132338 -227.035614)
			(xy 379.132338 -227.07981) (xy 379.487938 -227.07981)
		)
		(stroke
			(width 0)
			(type solid)
		)
		(fill yes)
		(layer "In6.Cu")
		(net "M_H_CPU0_SB_DQ<23>")
	)
	(gr_poly
		(pts
			(xy 379.497336 -238.021114) (xy 379.497336 -237.976664) (xy 379.141736 -237.976664) (xy 379.141736 -238.021114)
			(xy 379.188726 -238.173514) (xy 379.450346 -238.173514)
		)
		(stroke
			(width 0)
			(type solid)
		)
		(fill yes)
		(layer "In6.Cu")
		(net "M_G_CPU0_SB_DQ<5>")
	)
	(gr_poly
		(pts
			(xy 379.497336 -235.174282) (xy 379.450346 -235.021882) (xy 379.188726 -235.021882) (xy 379.141736 -235.174282)
			(xy 379.141736 -235.218732) (xy 379.497336 -235.218732)
		)
		(stroke
			(width 0)
			(type solid)
		)
		(fill yes)
		(layer "In6.Cu")
		(net "M_G_CPU0_SB_DQS_DP<6>")
	)
	(gr_poly
		(pts
			(xy 379.498098 -238.430054) (xy 379.451108 -238.277654) (xy 379.189488 -238.277654) (xy 379.142498 -238.430054)
			(xy 379.142498 -238.47425) (xy 379.498098 -238.47425)
		)
		(stroke
			(width 0)
			(type solid)
		)
		(fill yes)
		(layer "In6.Cu")
		(net "M_G_CPU0_SB_DQ<6>")
	)
	(gr_poly
		(pts
			(xy 379.567694 -231.988868) (xy 379.459236 -231.872028) (xy 379.420882 -231.84993) (xy 379.243082 -232.157778)
			(xy 379.281436 -232.179876) (xy 379.436884 -232.215436)
		)
		(stroke
			(width 0)
			(type solid)
		)
		(fill yes)
		(layer "In6.Cu")
		(net "M_H_CPU0_SB_DQ<16>")
	)
	(gr_poly
		(pts
			(xy 379.59538 -276.098762) (xy 379.54839 -275.946362) (xy 379.28677 -275.946362) (xy 379.23978 -276.098762)
			(xy 379.23978 -276.143212) (xy 379.59538 -276.143212)
		)
		(stroke
			(width 0)
			(type solid)
		)
		(fill yes)
		(layer "In6.Cu")
		(net "M_H_CPU0_SA_DQ<6>")
	)
	(gr_poly
		(pts
			(xy 379.59538 -275.690584) (xy 379.59538 -275.646388) (xy 379.23978 -275.646388) (xy 379.23978 -275.690584)
			(xy 379.28677 -275.842984) (xy 379.54839 -275.842984)
		)
		(stroke
			(width 0)
			(type solid)
		)
		(fill yes)
		(layer "In6.Cu")
		(net "M_H_CPU0_SA_DQ<5>")
	)
	(gr_poly
		(pts
			(xy 379.59538 -274.47113) (xy 379.54839 -274.31873) (xy 379.28677 -274.31873) (xy 379.23978 -274.47113)
			(xy 379.23978 -274.515326) (xy 379.59538 -274.515326)
		)
		(stroke
			(width 0)
			(type solid)
		)
		(fill yes)
		(layer "In6.Cu")
		(net "M_G_CPU0_SA_DQ<10>")
	)
	(gr_poly
		(pts
			(xy 379.59538 -274.062698) (xy 379.59538 -274.018502) (xy 379.23978 -274.018502) (xy 379.23978 -274.062698)
			(xy 379.28677 -274.215098) (xy 379.54839 -274.215098)
		)
		(stroke
			(width 0)
			(type solid)
		)
		(fill yes)
		(layer "In6.Cu")
		(net "M_G_CPU0_SA_DQ<9>")
	)
	(gr_poly
		(pts
			(xy 379.59538 -270.807434) (xy 379.59538 -270.762984) (xy 379.23978 -270.762984) (xy 379.23978 -270.807434)
			(xy 379.28677 -270.959834) (xy 379.54839 -270.959834)
		)
		(stroke
			(width 0)
			(type solid)
		)
		(fill yes)
		(layer "In6.Cu")
		(net "M_G_CPU0_SA_DQ<13>")
	)
	(gr_poly
		(pts
			(xy 379.59538 -269.587726) (xy 379.54839 -269.435326) (xy 379.28677 -269.435326) (xy 379.23978 -269.587726)
			(xy 379.23978 -269.631922) (xy 379.59538 -269.631922)
		)
		(stroke
			(width 0)
			(type solid)
		)
		(fill yes)
		(layer "In6.Cu")
		(net "M_G_CPU0_SA_DQ<26>")
	)
	(gr_poly
		(pts
			(xy 379.59538 -261.449058) (xy 379.54839 -261.296658) (xy 379.28677 -261.296658) (xy 379.23978 -261.449058)
			(xy 379.23978 -261.493254) (xy 379.59538 -261.493254)
		)
		(stroke
			(width 0)
			(type solid)
		)
		(fill yes)
		(layer "In6.Cu")
		(net "M_G_CPU0_SA_CB<6>")
	)
	(gr_poly
		(pts
			(xy 379.59538 -261.040626) (xy 379.59538 -260.99643) (xy 379.23978 -260.99643) (xy 379.23978 -261.040626)
			(xy 379.28677 -261.193026) (xy 379.54839 -261.193026)
		)
		(stroke
			(width 0)
			(type solid)
		)
		(fill yes)
		(layer "In6.Cu")
		(net "M_G_CPU0_SA_CB<5>")
	)
	(gr_poly
		(pts
			(xy 379.59792 -278.946102) (xy 379.59792 -278.901906) (xy 379.24232 -278.901906) (xy 379.24232 -278.946102)
			(xy 379.28931 -279.098502) (xy 379.55093 -279.098502)
		)
		(stroke
			(width 0)
			(type solid)
		)
		(fill yes)
		(layer "In6.Cu")
		(net "M_H_CPU0_SA_DQ<3>")
	)
	(gr_poly
		(pts
			(xy 379.59792 -277.726902) (xy 379.55093 -277.574502) (xy 379.28931 -277.574502) (xy 379.24232 -277.726902)
			(xy 379.24232 -277.771098) (xy 379.59792 -277.771098)
		)
		(stroke
			(width 0)
			(type solid)
		)
		(fill yes)
		(layer "In6.Cu")
		(net "M_H_CPU0_SA_DQS_DN<0>")
	)
	(gr_poly
		(pts
			(xy 379.59792 -277.317962) (xy 379.59792 -277.273766) (xy 379.24232 -277.273766) (xy 379.24232 -277.317962)
			(xy 379.28931 -277.470362) (xy 379.55093 -277.470362)
		)
		(stroke
			(width 0)
			(type solid)
		)
		(fill yes)
		(layer "In6.Cu")
		(net "M_H_CPU0_SA_DQS_DN<5>")
	)
	(gr_poly
		(pts
			(xy 379.59792 -272.843498) (xy 379.55093 -272.691098) (xy 379.28931 -272.691098) (xy 379.24232 -272.843498)
			(xy 379.24232 -272.887694) (xy 379.59792 -272.887694)
		)
		(stroke
			(width 0)
			(type solid)
		)
		(fill yes)
		(layer "In6.Cu")
		(net "M_G_CPU0_SA_DQS_DN<1>")
	)
	(gr_poly
		(pts
			(xy 379.59792 -272.435066) (xy 379.59792 -272.39087) (xy 379.24232 -272.39087) (xy 379.24232 -272.435066)
			(xy 379.28931 -272.587466) (xy 379.55093 -272.587466)
		)
		(stroke
			(width 0)
			(type solid)
		)
		(fill yes)
		(layer "In6.Cu")
		(net "M_G_CPU0_SA_DQS_DN<6>")
	)
	(gr_poly
		(pts
			(xy 379.59792 -267.960094) (xy 379.55093 -267.807694) (xy 379.28931 -267.807694) (xy 379.24232 -267.960094)
			(xy 379.24232 -268.00429) (xy 379.59792 -268.00429)
		)
		(stroke
			(width 0)
			(type solid)
		)
		(fill yes)
		(layer "In6.Cu")
		(net "M_G_CPU0_SA_DQS_DN<3>")
	)
	(gr_poly
		(pts
			(xy 379.59792 -267.551662) (xy 379.59792 -267.507466) (xy 379.24232 -267.507466) (xy 379.24232 -267.551662)
			(xy 379.28931 -267.704062) (xy 379.55093 -267.704062)
		)
		(stroke
			(width 0)
			(type solid)
		)
		(fill yes)
		(layer "In6.Cu")
		(net "M_G_CPU0_SA_DQS_DN<8>")
	)
	(gr_poly
		(pts
			(xy 379.59792 -263.07669) (xy 379.55093 -262.92429) (xy 379.28931 -262.92429) (xy 379.24232 -263.07669)
			(xy 379.24232 -263.120886) (xy 379.59792 -263.120886)
		)
		(stroke
			(width 0)
			(type solid)
		)
		(fill yes)
		(layer "In6.Cu")
		(net "M_G_CPU0_SA_DQS_DN<4>")
	)
	(gr_poly
		(pts
			(xy 379.59792 -262.668258) (xy 379.59792 -262.624062) (xy 379.24232 -262.624062) (xy 379.24232 -262.668258)
			(xy 379.28931 -262.820658) (xy 379.55093 -262.820658)
		)
		(stroke
			(width 0)
			(type solid)
		)
		(fill yes)
		(layer "In6.Cu")
		(net "M_G_CPU0_SA_DQS_DN<9>")
	)
	(gr_poly
		(pts
			(xy 379.607318 -271.215866) (xy 379.560328 -271.063466) (xy 379.298708 -271.063466) (xy 379.251718 -271.215866)
			(xy 379.251718 -271.260062) (xy 379.607318 -271.260062)
		)
		(stroke
			(width 0)
			(type solid)
		)
		(fill yes)
		(layer "In6.Cu")
		(net "M_G_CPU0_SA_DQ<14>")
	)
	(gr_poly
		(pts
			(xy 379.607318 -269.179294) (xy 379.607318 -269.134844) (xy 379.251718 -269.134844) (xy 379.251718 -269.179294)
			(xy 379.298708 -269.331694) (xy 379.560328 -269.331694)
		)
		(stroke
			(width 0)
			(type solid)
		)
		(fill yes)
		(layer "In6.Cu")
		(net "M_G_CPU0_SA_DQ<25>")
	)
	(gr_poly
		(pts
			(xy 379.607318 -266.332462) (xy 379.560328 -266.180062) (xy 379.298708 -266.180062) (xy 379.251718 -266.332462)
			(xy 379.251718 -266.376658) (xy 379.607318 -266.376658)
		)
		(stroke
			(width 0)
			(type solid)
		)
		(fill yes)
		(layer "In6.Cu")
		(net "M_G_CPU0_SA_DQ<30>")
	)
	(gr_poly
		(pts
			(xy 379.607318 -265.923522) (xy 379.607318 -265.879326) (xy 379.251718 -265.879326) (xy 379.251718 -265.923522)
			(xy 379.298708 -266.075922) (xy 379.560328 -266.075922)
		)
		(stroke
			(width 0)
			(type solid)
		)
		(fill yes)
		(layer "In6.Cu")
		(net "M_G_CPU0_SA_DQ<29>")
	)
	(gr_poly
		(pts
			(xy 379.607318 -264.29589) (xy 379.607318 -264.25144) (xy 379.251718 -264.25144) (xy 379.251718 -264.29589)
			(xy 379.298708 -264.44829) (xy 379.560328 -264.44829)
		)
		(stroke
			(width 0)
			(type solid)
		)
		(fill yes)
		(layer "In6.Cu")
		(net "M_G_CPU0_SA_CB<1>")
	)
	(gr_poly
		(pts
			(xy 379.60808 -264.70483) (xy 379.56109 -264.55243) (xy 379.29947 -264.55243) (xy 379.25248 -264.70483)
			(xy 379.25248 -264.749026) (xy 379.60808 -264.749026)
		)
		(stroke
			(width 0)
			(type solid)
		)
		(fill yes)
		(layer "In6.Cu")
		(net "M_G_CPU0_SA_CB<2>")
	)
	(gr_poly
		(pts
			(xy 379.957838 -240.46307) (xy 379.957838 -240.41862) (xy 379.602238 -240.41862) (xy 379.602238 -240.46307)
			(xy 379.649228 -240.61547) (xy 379.910848 -240.61547)
		)
		(stroke
			(width 0)
			(type solid)
		)
		(fill yes)
		(layer "In6.Cu")
		(net "M_G_CPU0_SB_DQS_DP<0>")
	)
	(gr_poly
		(pts
			(xy 379.957838 -230.696262) (xy 379.957838 -230.651812) (xy 379.602238 -230.651812) (xy 379.602238 -230.696262)
			(xy 379.649228 -230.848662) (xy 379.910848 -230.848662)
		)
		(stroke
			(width 0)
			(type solid)
		)
		(fill yes)
		(layer "In6.Cu")
		(net "M_H_CPU0_SB_DQ<17>")
	)
	(gr_poly
		(pts
			(xy 379.959616 -238.83493) (xy 379.959616 -238.790734) (xy 379.604016 -238.790734) (xy 379.604016 -238.83493)
			(xy 379.651006 -238.98733) (xy 379.912626 -238.98733)
		)
		(stroke
			(width 0)
			(type solid)
		)
		(fill yes)
		(layer "In6.Cu")
		(net "M_G_CPU0_SB_DQ<4>")
	)
	(gr_poly
		(pts
			(xy 379.959616 -233.951526) (xy 379.959616 -233.90733) (xy 379.604016 -233.90733) (xy 379.604016 -233.951526)
			(xy 379.651006 -234.103926) (xy 379.912626 -234.103926)
		)
		(stroke
			(width 0)
			(type solid)
		)
		(fill yes)
		(layer "In6.Cu")
		(net "M_G_CPU0_SB_DQ<14>")
	)
	(gr_poly
		(pts
			(xy 379.960378 -237.616238) (xy 379.913388 -237.463838) (xy 379.651768 -237.463838) (xy 379.604778 -237.616238)
			(xy 379.604778 -237.660434) (xy 379.960378 -237.660434)
		)
		(stroke
			(width 0)
			(type solid)
		)
		(fill yes)
		(layer "In6.Cu")
		(net "M_G_CPU0_SB_DQ<7>")
	)
	(gr_poly
		(pts
			(xy 379.960378 -235.579666) (xy 379.960378 -235.535216) (xy 379.604778 -235.535216) (xy 379.604778 -235.579666)
			(xy 379.651768 -235.732066) (xy 379.913388 -235.732066)
		)
		(stroke
			(width 0)
			(type solid)
		)
		(fill yes)
		(layer "In6.Cu")
		(net "M_G_CPU0_SB_DQS_DN<6>")
	)
	(gr_poly
		(pts
			(xy 379.963934 -249.010678) (xy 379.916944 -248.858278) (xy 379.655324 -248.858278) (xy 379.608334 -249.010678)
			(xy 379.608334 -249.054874) (xy 379.963934 -249.054874)
		)
		(stroke
			(width 0)
			(type solid)
		)
		(fill yes)
		(layer "In6.Cu")
		(net "M_E_CPU0_SB_RSP<0>")
	)
	(gr_poly
		(pts
			(xy 379.963934 -244.127274) (xy 379.916944 -243.974874) (xy 379.655324 -243.974874) (xy 379.608334 -244.127274)
			(xy 379.608334 -244.17147) (xy 379.963934 -244.17147)
		)
		(stroke
			(width 0)
			(type solid)
		)
		(fill yes)
		(layer "In6.Cu")
		(net "M_H_CPU0_SB_CS_N<3>")
	)
	(gr_poly
		(pts
			(xy 379.963934 -239.24387) (xy 379.916944 -239.09147) (xy 379.655324 -239.09147) (xy 379.608334 -239.24387)
			(xy 379.608334 -239.288066) (xy 379.963934 -239.288066)
		)
		(stroke
			(width 0)
			(type solid)
		)
		(fill yes)
		(layer "In6.Cu")
		(net "M_G_CPU0_SB_DQS_DP<5>")
	)
	(gr_poly
		(pts
			(xy 379.963934 -234.360466) (xy 379.916944 -234.208066) (xy 379.655324 -234.208066) (xy 379.608334 -234.360466)
			(xy 379.608334 -234.404916) (xy 379.963934 -234.404916)
		)
		(stroke
			(width 0)
			(type solid)
		)
		(fill yes)
		(layer "In6.Cu")
		(net "M_G_CPU0_SB_DQS_DN<1>")
	)
	(gr_poly
		(pts
			(xy 379.963934 -229.477062) (xy 379.916944 -229.324662) (xy 379.655324 -229.324662) (xy 379.608334 -229.477062)
			(xy 379.608334 -229.521512) (xy 379.963934 -229.521512)
		)
		(stroke
			(width 0)
			(type solid)
		)
		(fill yes)
		(layer "In6.Cu")
		(net "M_H_CPU0_SB_DQS_DN<2>")
	)
	(gr_poly
		(pts
			(xy 379.969776 -240.871502) (xy 379.922786 -240.719102) (xy 379.661166 -240.719102) (xy 379.614176 -240.871502)
			(xy 379.614176 -240.915952) (xy 379.969776 -240.915952)
		)
		(stroke
			(width 0)
			(type solid)
		)
		(fill yes)
		(layer "In6.Cu")
		(net "M_G_CPU0_SB_DQ<3>")
	)
	(gr_poly
		(pts
			(xy 379.969776 -235.988098) (xy 379.922786 -235.835698) (xy 379.661166 -235.835698) (xy 379.614176 -235.988098)
			(xy 379.614176 -236.032548) (xy 379.969776 -236.032548)
		)
		(stroke
			(width 0)
			(type solid)
		)
		(fill yes)
		(layer "In6.Cu")
		(net "M_G_CPU0_SB_DQ<9>")
	)
	(gr_poly
		(pts
			(xy 379.969776 -231.104694) (xy 379.922786 -230.952294) (xy 379.661166 -230.952294) (xy 379.614176 -231.104694)
			(xy 379.614176 -231.149144) (xy 379.969776 -231.149144)
		)
		(stroke
			(width 0)
			(type solid)
		)
		(fill yes)
		(layer "In6.Cu")
		(net "M_H_CPU0_SB_DQ<18>")
	)
	(gr_poly
		(pts
			(xy 379.972316 -248.602246) (xy 379.972316 -248.557796) (xy 379.616716 -248.557796) (xy 379.616716 -248.602246)
			(xy 379.663706 -248.754646) (xy 379.925326 -248.754646)
		)
		(stroke
			(width 0)
			(type solid)
		)
		(fill yes)
		(layer "In6.Cu")
		(net "M_E_CPU0_SA_RSP<1>")
	)
	(gr_poly
		(pts
			(xy 379.972316 -243.718842) (xy 379.972316 -243.674392) (xy 379.616716 -243.674392) (xy 379.616716 -243.718842)
			(xy 379.663706 -243.871242) (xy 379.925326 -243.871242)
		)
		(stroke
			(width 0)
			(type solid)
		)
		(fill yes)
		(layer "In6.Cu")
		(net "M_H_CPU0_SB_CS_N<0>")
	)
	(gr_poly
		(pts
			(xy 379.972316 -242.090702) (xy 379.972316 -242.046506) (xy 379.616716 -242.046506) (xy 379.616716 -242.090702)
			(xy 379.663706 -242.243102) (xy 379.925326 -242.243102)
		)
		(stroke
			(width 0)
			(type solid)
		)
		(fill yes)
		(layer "In6.Cu")
		(net "M_G_CPU0_SB_DQ<0>")
	)
	(gr_poly
		(pts
			(xy 379.972316 -237.207806) (xy 379.972316 -237.163356) (xy 379.616716 -237.163356) (xy 379.616716 -237.207806)
			(xy 379.663706 -237.360206) (xy 379.925326 -237.360206)
		)
		(stroke
			(width 0)
			(type solid)
		)
		(fill yes)
		(layer "In6.Cu")
		(net "M_G_CPU0_SB_DQ<8>")
	)
	(gr_poly
		(pts
			(xy 379.972316 -232.732326) (xy 379.925326 -232.579926) (xy 379.663706 -232.579926) (xy 379.616716 -232.732326)
			(xy 379.616716 -232.776776) (xy 379.972316 -232.776776)
		)
		(stroke
			(width 0)
			(type solid)
		)
		(fill yes)
		(layer "In6.Cu")
		(net "M_G_CPU0_SB_DQ<13>")
	)
	(gr_poly
		(pts
			(xy 379.972316 -229.06863) (xy 379.972316 -229.024434) (xy 379.616716 -229.024434) (xy 379.616716 -229.06863)
			(xy 379.663706 -229.22103) (xy 379.925326 -229.22103)
		)
		(stroke
			(width 0)
			(type solid)
		)
		(fill yes)
		(layer "In6.Cu")
		(net "M_H_CPU0_SB_DQS_DN<7>")
	)
	(gr_poly
		(pts
			(xy 379.972316 -227.848922) (xy 379.925326 -227.696522) (xy 379.663706 -227.696522) (xy 379.616716 -227.848922)
			(xy 379.616716 -227.893372) (xy 379.972316 -227.893372)
		)
		(stroke
			(width 0)
			(type solid)
		)
		(fill yes)
		(layer "In6.Cu")
		(net "M_H_CPU0_SB_DQ<22>")
	)
	(gr_poly
		(pts
			(xy 379.972316 -227.440998) (xy 379.972316 -227.396548) (xy 379.616716 -227.396548) (xy 379.616716 -227.440998)
			(xy 379.663706 -227.593398) (xy 379.925326 -227.593398)
		)
		(stroke
			(width 0)
			(type solid)
		)
		(fill yes)
		(layer "In6.Cu")
		(net "M_H_CPU0_SB_DQ<21>")
	)
	(gr_poly
		(pts
			(xy 380.06782 -279.759664) (xy 380.06782 -279.715468) (xy 379.71222 -279.715468) (xy 379.71222 -279.759664)
			(xy 379.75921 -279.912064) (xy 380.02083 -279.912064)
		)
		(stroke
			(width 0)
			(type solid)
		)
		(fill yes)
		(layer "In6.Cu")
		(net "M_H_CPU0_SA_DQ<0>")
	)
	(gr_poly
		(pts
			(xy 380.06782 -272.029682) (xy 380.02083 -271.877282) (xy 379.75921 -271.877282) (xy 379.71222 -272.029682)
			(xy 379.71222 -272.073878) (xy 380.06782 -272.073878)
		)
		(stroke
			(width 0)
			(type solid)
		)
		(fill yes)
		(layer "In6.Cu")
		(net "M_G_CPU0_SA_DQS_DP<6>")
	)
	(gr_poly
		(pts
			(xy 380.06782 -267.146278) (xy 380.02083 -266.993878) (xy 379.75921 -266.993878) (xy 379.71222 -267.146278)
			(xy 379.71222 -267.190728) (xy 380.06782 -267.190728)
		)
		(stroke
			(width 0)
			(type solid)
		)
		(fill yes)
		(layer "In6.Cu")
		(net "M_G_CPU0_SA_DQS_DP<8>")
	)
	(gr_poly
		(pts
			(xy 380.06782 -262.262874) (xy 380.02083 -262.110474) (xy 379.75921 -262.110474) (xy 379.71222 -262.262874)
			(xy 379.71222 -262.307324) (xy 380.06782 -262.307324)
		)
		(stroke
			(width 0)
			(type solid)
		)
		(fill yes)
		(layer "In6.Cu")
		(net "M_G_CPU0_SA_DQS_DP<9>")
	)
	(gr_poly
		(pts
			(xy 380.069598 -265.109706) (xy 380.069598 -265.06551) (xy 379.713998 -265.06551) (xy 379.713998 -265.109706)
			(xy 379.760988 -265.262106) (xy 380.022608 -265.262106)
		)
		(stroke
			(width 0)
			(type solid)
		)
		(fill yes)
		(layer "In6.Cu")
		(net "M_G_CPU0_SA_CB<0>")
	)
	(gr_poly
		(pts
			(xy 380.07036 -271.62125) (xy 380.07036 -271.5768) (xy 379.71476 -271.5768) (xy 379.71476 -271.62125)
			(xy 379.76175 -271.77365) (xy 380.02337 -271.77365)
		)
		(stroke
			(width 0)
			(type solid)
		)
		(fill yes)
		(layer "In6.Cu")
		(net "M_G_CPU0_SA_DQ<12>")
	)
	(gr_poly
		(pts
			(xy 380.07036 -266.737846) (xy 380.07036 -266.693396) (xy 379.71476 -266.693396) (xy 379.71476 -266.737846)
			(xy 379.76175 -266.890246) (xy 380.02337 -266.890246)
		)
		(stroke
			(width 0)
			(type solid)
		)
		(fill yes)
		(layer "In6.Cu")
		(net "M_G_CPU0_SA_DQ<28>")
	)
	(gr_poly
		(pts
			(xy 380.07036 -265.518646) (xy 380.02337 -265.366246) (xy 379.76175 -265.366246) (xy 379.71476 -265.518646)
			(xy 379.71476 -265.563096) (xy 380.07036 -265.563096)
		)
		(stroke
			(width 0)
			(type solid)
		)
		(fill yes)
		(layer "In6.Cu")
		(net "M_G_CPU0_SA_DQ<31>")
	)
	(gr_poly
		(pts
			(xy 380.07036 -263.891014) (xy 380.02337 -263.738614) (xy 379.76175 -263.738614) (xy 379.71476 -263.891014)
			(xy 379.71476 -263.93521) (xy 380.07036 -263.93521)
		)
		(stroke
			(width 0)
			(type solid)
		)
		(fill yes)
		(layer "In6.Cu")
		(net "M_G_CPU0_SA_CB<3>")
	)
	(gr_poly
		(pts
			(xy 380.073916 -278.540718) (xy 380.026926 -278.388318) (xy 379.765306 -278.388318) (xy 379.718316 -278.540718)
			(xy 379.718316 -278.585168) (xy 380.073916 -278.585168)
		)
		(stroke
			(width 0)
			(type solid)
		)
		(fill yes)
		(layer "In6.Cu")
		(net "M_H_CPU0_SA_DQ<1>")
	)
	(gr_poly
		(pts
			(xy 380.073916 -273.248882) (xy 380.073916 -273.204432) (xy 379.718316 -273.204432) (xy 379.718316 -273.248882)
			(xy 379.765306 -273.401282) (xy 380.026926 -273.401282)
		)
		(stroke
			(width 0)
			(type solid)
		)
		(fill yes)
		(layer "In6.Cu")
		(net "M_G_CPU0_SA_DQS_DP<1>")
	)
	(gr_poly
		(pts
			(xy 380.073916 -268.365478) (xy 380.073916 -268.321028) (xy 379.718316 -268.321028) (xy 379.718316 -268.365478)
			(xy 379.765306 -268.517878) (xy 380.026926 -268.517878)
		)
		(stroke
			(width 0)
			(type solid)
		)
		(fill yes)
		(layer "In6.Cu")
		(net "M_G_CPU0_SA_DQS_DP<3>")
	)
	(gr_poly
		(pts
			(xy 380.073916 -263.482074) (xy 380.073916 -263.437878) (xy 379.718316 -263.437878) (xy 379.718316 -263.482074)
			(xy 379.765306 -263.634474) (xy 380.026926 -263.634474)
		)
		(stroke
			(width 0)
			(type solid)
		)
		(fill yes)
		(layer "In6.Cu")
		(net "M_G_CPU0_SA_DQS_DP<4>")
	)
	(gr_poly
		(pts
			(xy 380.079758 -276.913086) (xy 380.032768 -276.760686) (xy 379.771148 -276.760686) (xy 379.724158 -276.913086)
			(xy 379.724158 -276.957282) (xy 380.079758 -276.957282)
		)
		(stroke
			(width 0)
			(type solid)
		)
		(fill yes)
		(layer "In6.Cu")
		(net "M_H_CPU0_SA_DQS_DP<5>")
	)
	(gr_poly
		(pts
			(xy 380.079758 -276.504146) (xy 380.079758 -276.45995) (xy 379.724158 -276.45995) (xy 379.724158 -276.504146)
			(xy 379.771148 -276.656546) (xy 380.032768 -276.656546)
		)
		(stroke
			(width 0)
			(type solid)
		)
		(fill yes)
		(layer "In6.Cu")
		(net "M_H_CPU0_SA_DQ<4>")
	)
	(gr_poly
		(pts
			(xy 380.079758 -261.854442) (xy 380.079758 -261.809992) (xy 379.724158 -261.809992) (xy 379.724158 -261.854442)
			(xy 379.771148 -262.006842) (xy 380.032768 -262.006842)
		)
		(stroke
			(width 0)
			(type solid)
		)
		(fill yes)
		(layer "In6.Cu")
		(net "M_G_CPU0_SA_CB<4>")
	)
	(gr_poly
		(pts
			(xy 380.082298 -278.132286) (xy 380.082298 -278.08809) (xy 379.726698 -278.08809) (xy 379.726698 -278.132286)
			(xy 379.773688 -278.284686) (xy 380.035308 -278.284686)
		)
		(stroke
			(width 0)
			(type solid)
		)
		(fill yes)
		(layer "In6.Cu")
		(net "M_H_CPU0_SA_DQS_DP<0>")
	)
	(gr_poly
		(pts
			(xy 380.082298 -275.284946) (xy 380.035308 -275.132546) (xy 379.773688 -275.132546) (xy 379.726698 -275.284946)
			(xy 379.726698 -275.329142) (xy 380.082298 -275.329142)
		)
		(stroke
			(width 0)
			(type solid)
		)
		(fill yes)
		(layer "In6.Cu")
		(net "M_H_CPU0_SA_DQ<7>")
	)
	(gr_poly
		(pts
			(xy 380.082298 -274.876514) (xy 380.082298 -274.832318) (xy 379.726698 -274.832318) (xy 379.726698 -274.876514)
			(xy 379.773688 -275.028914) (xy 380.035308 -275.028914)
		)
		(stroke
			(width 0)
			(type solid)
		)
		(fill yes)
		(layer "In6.Cu")
		(net "M_G_CPU0_SA_DQ<8>")
	)
	(gr_poly
		(pts
			(xy 380.082298 -273.657314) (xy 380.035308 -273.504914) (xy 379.773688 -273.504914) (xy 379.726698 -273.657314)
			(xy 379.726698 -273.70151) (xy 380.082298 -273.70151)
		)
		(stroke
			(width 0)
			(type solid)
		)
		(fill yes)
		(layer "In6.Cu")
		(net "M_G_CPU0_SA_DQ<11>")
	)
	(gr_poly
		(pts
			(xy 380.082298 -270.401542) (xy 380.035308 -270.249142) (xy 379.773688 -270.249142) (xy 379.726698 -270.401542)
			(xy 379.726698 -270.445992) (xy 380.082298 -270.445992)
		)
		(stroke
			(width 0)
			(type solid)
		)
		(fill yes)
		(layer "In6.Cu")
		(net "M_G_CPU0_SA_DQ<15>")
	)
	(gr_poly
		(pts
			(xy 380.082298 -269.993618) (xy 380.082298 -269.949168) (xy 379.726698 -269.949168) (xy 379.726698 -269.993618)
			(xy 379.773688 -270.146018) (xy 380.035308 -270.146018)
		)
		(stroke
			(width 0)
			(type solid)
		)
		(fill yes)
		(layer "In6.Cu")
		(net "M_G_CPU0_SA_DQ<24>")
	)
	(gr_poly
		(pts
			(xy 380.082298 -268.77391) (xy 380.035308 -268.62151) (xy 379.773688 -268.62151) (xy 379.726698 -268.77391)
			(xy 379.726698 -268.818106) (xy 380.082298 -268.818106)
		)
		(stroke
			(width 0)
			(type solid)
		)
		(fill yes)
		(layer "In6.Cu")
		(net "M_G_CPU0_SA_DQ<27>")
	)
	(gr_poly
		(pts
			(xy 380.082298 -260.634734) (xy 380.035308 -260.482334) (xy 379.773688 -260.482334) (xy 379.726698 -260.634734)
			(xy 379.726698 -260.679184) (xy 380.082298 -260.679184)
		)
		(stroke
			(width 0)
			(type solid)
		)
		(fill yes)
		(layer "In6.Cu")
		(net "M_G_CPU0_SA_CB<7>")
	)
	(gr_poly
		(pts
			(xy 380.425198 -241.685318) (xy 380.378208 -241.532918) (xy 380.116588 -241.532918) (xy 380.069598 -241.685318)
			(xy 380.069598 -241.729514) (xy 380.425198 -241.729514)
		)
		(stroke
			(width 0)
			(type solid)
		)
		(fill yes)
		(layer "In6.Cu")
		(net "M_G_CPU0_SB_DQ<2>")
	)
	(gr_poly
		(pts
			(xy 380.425198 -236.801914) (xy 380.378208 -236.649514) (xy 380.116588 -236.649514) (xy 380.069598 -236.801914)
			(xy 380.069598 -236.84611) (xy 380.425198 -236.84611)
		)
		(stroke
			(width 0)
			(type solid)
		)
		(fill yes)
		(layer "In6.Cu")
		(net "M_G_CPU0_SB_DQ<10>")
	)
	(gr_poly
		(pts
			(xy 380.425198 -227.035106) (xy 380.378208 -226.882706) (xy 380.116588 -226.882706) (xy 380.069598 -227.035106)
			(xy 380.069598 -227.079556) (xy 380.425198 -227.079556)
		)
		(stroke
			(width 0)
			(type solid)
		)
		(fill yes)
		(layer "In6.Cu")
		(net "M_H_CPU0_SB_DQ<23>")
	)
	(gr_poly
		(pts
			(xy 380.427738 -248.196354) (xy 380.380748 -248.043954) (xy 380.119128 -248.043954) (xy 380.072138 -248.196354)
			(xy 380.072138 -248.24055) (xy 380.427738 -248.24055)
		)
		(stroke
			(width 0)
			(type solid)
		)
		(fill yes)
		(layer "In6.Cu")
		(net "M_E_CPU0_SB_RSP<1>")
	)
	(gr_poly
		(pts
			(xy 380.427738 -244.53215) (xy 380.427738 -244.487954) (xy 380.072138 -244.487954) (xy 380.072138 -244.53215)
			(xy 380.119128 -244.68455) (xy 380.380748 -244.68455)
		)
		(stroke
			(width 0)
			(type solid)
		)
		(fill yes)
		(layer "In6.Cu")
		(net "M_H_CPU0_SB_CS_N<2>")
	)
	(gr_poly
		(pts
			(xy 380.427738 -243.31295) (xy 380.380748 -243.16055) (xy 380.119128 -243.16055) (xy 380.072138 -243.31295)
			(xy 380.072138 -243.3574) (xy 380.427738 -243.3574)
		)
		(stroke
			(width 0)
			(type solid)
		)
		(fill yes)
		(layer "In6.Cu")
		(net "M_H_CPU0_SB_CS_N<1>")
	)
	(gr_poly
		(pts
			(xy 380.427738 -239.648746) (xy 380.427738 -239.60455) (xy 380.072138 -239.60455) (xy 380.072138 -239.648746)
			(xy 380.119128 -239.801146) (xy 380.380748 -239.801146)
		)
		(stroke
			(width 0)
			(type solid)
		)
		(fill yes)
		(layer "In6.Cu")
		(net "M_G_CPU0_SB_DQS_DN<5>")
	)
	(gr_poly
		(pts
			(xy 380.427738 -234.76585) (xy 380.427738 -234.7214) (xy 380.072138 -234.7214) (xy 380.072138 -234.76585)
			(xy 380.119128 -234.91825) (xy 380.380748 -234.91825)
		)
		(stroke
			(width 0)
			(type solid)
		)
		(fill yes)
		(layer "In6.Cu")
		(net "M_G_CPU0_SB_DQS_DP<1>")
	)
	(gr_poly
		(pts
			(xy 380.427738 -233.546142) (xy 380.380748 -233.393742) (xy 380.119128 -233.393742) (xy 380.072138 -233.546142)
			(xy 380.072138 -233.590592) (xy 380.427738 -233.590592)
		)
		(stroke
			(width 0)
			(type solid)
		)
		(fill yes)
		(layer "In6.Cu")
		(net "M_G_CPU0_SB_DQ<12>")
	)
	(gr_poly
		(pts
			(xy 380.427738 -233.138218) (xy 380.427738 -233.093768) (xy 380.072138 -233.093768) (xy 380.072138 -233.138218)
			(xy 380.119128 -233.290618) (xy 380.380748 -233.290618)
		)
		(stroke
			(width 0)
			(type solid)
		)
		(fill yes)
		(layer "In6.Cu")
		(net "M_G_CPU0_SB_DQ<15>")
	)
	(gr_poly
		(pts
			(xy 380.427738 -229.882446) (xy 380.427738 -229.837996) (xy 380.072138 -229.837996) (xy 380.072138 -229.882446)
			(xy 380.119128 -230.034846) (xy 380.380748 -230.034846)
		)
		(stroke
			(width 0)
			(type solid)
		)
		(fill yes)
		(layer "In6.Cu")
		(net "M_H_CPU0_SB_DQS_DP<2>")
	)
	(gr_poly
		(pts
			(xy 380.427738 -228.663246) (xy 380.380748 -228.510846) (xy 380.119128 -228.510846) (xy 380.072138 -228.663246)
			(xy 380.072138 -228.707442) (xy 380.427738 -228.707442)
		)
		(stroke
			(width 0)
			(type solid)
		)
		(fill yes)
		(layer "In6.Cu")
		(net "M_H_CPU0_SB_DQS_DP<7>")
	)
	(gr_poly
		(pts
			(xy 380.427738 -228.254814) (xy 380.427738 -228.210618) (xy 380.072138 -228.210618) (xy 380.072138 -228.254814)
			(xy 380.119128 -228.407214) (xy 380.380748 -228.407214)
		)
		(stroke
			(width 0)
			(type solid)
		)
		(fill yes)
		(layer "In6.Cu")
		(net "M_H_CPU0_SB_DQ<20>")
	)
	(gr_poly
		(pts
			(xy 380.43358 -241.276886) (xy 380.43358 -241.232436) (xy 380.07798 -241.232436) (xy 380.07798 -241.276886)
			(xy 380.12497 -241.429286) (xy 380.38659 -241.429286)
		)
		(stroke
			(width 0)
			(type solid)
		)
		(fill yes)
		(layer "In6.Cu")
		(net "M_G_CPU0_SB_DQ<1>")
	)
	(gr_poly
		(pts
			(xy 380.43358 -236.393482) (xy 380.43358 -236.349286) (xy 380.07798 -236.349286) (xy 380.07798 -236.393482)
			(xy 380.12497 -236.545882) (xy 380.38659 -236.545882)
		)
		(stroke
			(width 0)
			(type solid)
		)
		(fill yes)
		(layer "In6.Cu")
		(net "M_G_CPU0_SB_DQ<11>")
	)
	(gr_poly
		(pts
			(xy 380.43358 -231.510078) (xy 380.43358 -231.465882) (xy 380.07798 -231.465882) (xy 380.07798 -231.510078)
			(xy 380.12497 -231.662478) (xy 380.38659 -231.662478)
		)
		(stroke
			(width 0)
			(type solid)
		)
		(fill yes)
		(layer "In6.Cu")
		(net "M_H_CPU0_SB_DQ<16>")
	)
	(gr_poly
		(pts
			(xy 380.433834 -249.415554) (xy 380.433834 -249.371358) (xy 380.078234 -249.371358) (xy 380.078234 -249.415554)
			(xy 380.125224 -249.567954) (xy 380.386844 -249.567954)
		)
		(stroke
			(width 0)
			(type solid)
		)
		(fill yes)
		(layer "In6.Cu")
		(net "M_E_CPU0_SA_RSP<0>")
	)
	(gr_poly
		(pts
			(xy 380.437136 -238.021114) (xy 380.437136 -237.976664) (xy 380.081536 -237.976664) (xy 380.081536 -238.021114)
			(xy 380.128526 -238.173514) (xy 380.390146 -238.173514)
		)
		(stroke
			(width 0)
			(type solid)
		)
		(fill yes)
		(layer "In6.Cu")
		(net "M_G_CPU0_SB_DQ<5>")
	)
	(gr_poly
		(pts
			(xy 380.437136 -235.174282) (xy 380.390146 -235.021882) (xy 380.128526 -235.021882) (xy 380.081536 -235.174282)
			(xy 380.081536 -235.218732) (xy 380.437136 -235.218732)
		)
		(stroke
			(width 0)
			(type solid)
		)
		(fill yes)
		(layer "In6.Cu")
		(net "M_G_CPU0_SB_DQS_DP<6>")
	)
	(gr_poly
		(pts
			(xy 380.437898 -238.430054) (xy 380.390908 -238.277654) (xy 380.129288 -238.277654) (xy 380.082298 -238.430054)
			(xy 380.082298 -238.47425) (xy 380.437898 -238.47425)
		)
		(stroke
			(width 0)
			(type solid)
		)
		(fill yes)
		(layer "In6.Cu")
		(net "M_G_CPU0_SB_DQ<6>")
	)
	(gr_poly
		(pts
			(xy 380.439676 -240.057686) (xy 380.392686 -239.905286) (xy 380.131066 -239.905286) (xy 380.084076 -240.057686)
			(xy 380.084076 -240.101882) (xy 380.439676 -240.101882)
		)
		(stroke
			(width 0)
			(type solid)
		)
		(fill yes)
		(layer "In6.Cu")
		(net "M_G_CPU0_SB_DQS_DN<0>")
	)
	(gr_poly
		(pts
			(xy 380.439676 -230.290878) (xy 380.392686 -230.138478) (xy 380.131066 -230.138478) (xy 380.084076 -230.290878)
			(xy 380.084076 -230.335328) (xy 380.439676 -230.335328)
		)
		(stroke
			(width 0)
			(type solid)
		)
		(fill yes)
		(layer "In6.Cu")
		(net "M_H_CPU0_SB_DQ<19>")
	)
	(gr_poly
		(pts
			(xy 380.53518 -277.726394) (xy 380.48819 -277.573994) (xy 380.22657 -277.573994) (xy 380.17958 -277.726394)
			(xy 380.17958 -277.770844) (xy 380.53518 -277.770844)
		)
		(stroke
			(width 0)
			(type solid)
		)
		(fill yes)
		(layer "In6.Cu")
		(net "M_H_CPU0_SA_DQS_DN<0>")
	)
	(gr_poly
		(pts
			(xy 380.53518 -275.690584) (xy 380.53518 -275.646388) (xy 380.17958 -275.646388) (xy 380.17958 -275.690584)
			(xy 380.22657 -275.842984) (xy 380.48819 -275.842984)
		)
		(stroke
			(width 0)
			(type solid)
		)
		(fill yes)
		(layer "In6.Cu")
		(net "M_H_CPU0_SA_DQ<5>")
	)
	(gr_poly
		(pts
			(xy 380.53518 -270.807434) (xy 380.53518 -270.762984) (xy 380.17958 -270.762984) (xy 380.17958 -270.807434)
			(xy 380.22657 -270.959834) (xy 380.48819 -270.959834)
		)
		(stroke
			(width 0)
			(type solid)
		)
		(fill yes)
		(layer "In6.Cu")
		(net "M_G_CPU0_SA_DQ<13>")
	)
	(gr_poly
		(pts
			(xy 380.53518 -261.040626) (xy 380.53518 -260.99643) (xy 380.17958 -260.99643) (xy 380.17958 -261.040626)
			(xy 380.22657 -261.193026) (xy 380.48819 -261.193026)
		)
		(stroke
			(width 0)
			(type solid)
		)
		(fill yes)
		(layer "In6.Cu")
		(net "M_G_CPU0_SA_CB<5>")
	)
	(gr_poly
		(pts
			(xy 380.53772 -274.47113) (xy 380.49073 -274.31873) (xy 380.22911 -274.31873) (xy 380.18212 -274.47113)
			(xy 380.18212 -274.515326) (xy 380.53772 -274.515326)
		)
		(stroke
			(width 0)
			(type solid)
		)
		(fill yes)
		(layer "In6.Cu")
		(net "M_G_CPU0_SA_DQ<10>")
	)
	(gr_poly
		(pts
			(xy 380.53772 -274.062698) (xy 380.53772 -274.018502) (xy 380.18212 -274.018502) (xy 380.18212 -274.062698)
			(xy 380.22911 -274.215098) (xy 380.49073 -274.215098)
		)
		(stroke
			(width 0)
			(type solid)
		)
		(fill yes)
		(layer "In6.Cu")
		(net "M_G_CPU0_SA_DQ<9>")
	)
	(gr_poly
		(pts
			(xy 380.53772 -272.843498) (xy 380.49073 -272.691098) (xy 380.22911 -272.691098) (xy 380.18212 -272.843498)
			(xy 380.18212 -272.887948) (xy 380.53772 -272.887948)
		)
		(stroke
			(width 0)
			(type solid)
		)
		(fill yes)
		(layer "In6.Cu")
		(net "M_G_CPU0_SA_DQS_DN<1>")
	)
	(gr_poly
		(pts
			(xy 380.53772 -269.587726) (xy 380.49073 -269.435326) (xy 380.22911 -269.435326) (xy 380.18212 -269.587726)
			(xy 380.18212 -269.631922) (xy 380.53772 -269.631922)
		)
		(stroke
			(width 0)
			(type solid)
		)
		(fill yes)
		(layer "In6.Cu")
		(net "M_G_CPU0_SA_DQ<26>")
	)
	(gr_poly
		(pts
			(xy 380.53772 -267.960094) (xy 380.49073 -267.807694) (xy 380.22911 -267.807694) (xy 380.18212 -267.960094)
			(xy 380.18212 -268.004544) (xy 380.53772 -268.004544)
		)
		(stroke
			(width 0)
			(type solid)
		)
		(fill yes)
		(layer "In6.Cu")
		(net "M_G_CPU0_SA_DQS_DN<3>")
	)
	(gr_poly
		(pts
			(xy 380.53772 -263.07669) (xy 380.49073 -262.92429) (xy 380.22911 -262.92429) (xy 380.18212 -263.07669)
			(xy 380.18212 -263.12114) (xy 380.53772 -263.12114)
		)
		(stroke
			(width 0)
			(type solid)
		)
		(fill yes)
		(layer "In6.Cu")
		(net "M_G_CPU0_SA_DQS_DN<4>")
	)
	(gr_poly
		(pts
			(xy 380.543562 -277.317962) (xy 380.543562 -277.273766) (xy 380.187962 -277.273766) (xy 380.187962 -277.317962)
			(xy 380.234952 -277.470362) (xy 380.496572 -277.470362)
		)
		(stroke
			(width 0)
			(type solid)
		)
		(fill yes)
		(layer "In6.Cu")
		(net "M_H_CPU0_SA_DQS_DN<5>")
	)
	(gr_poly
		(pts
			(xy 380.543562 -276.09927) (xy 380.496572 -275.94687) (xy 380.234952 -275.94687) (xy 380.187962 -276.09927)
			(xy 380.187962 -276.143466) (xy 380.543562 -276.143466)
		)
		(stroke
			(width 0)
			(type solid)
		)
		(fill yes)
		(layer "In6.Cu")
		(net "M_H_CPU0_SA_DQ<6>")
	)
	(gr_poly
		(pts
			(xy 380.543562 -261.449058) (xy 380.496572 -261.296658) (xy 380.234952 -261.296658) (xy 380.187962 -261.449058)
			(xy 380.187962 -261.493508) (xy 380.543562 -261.493508)
		)
		(stroke
			(width 0)
			(type solid)
		)
		(fill yes)
		(layer "In6.Cu")
		(net "M_G_CPU0_SA_CB<6>")
	)
	(gr_poly
		(pts
			(xy 380.543816 -278.945848) (xy 380.543816 -278.901652) (xy 380.188216 -278.901652) (xy 380.188216 -278.945848)
			(xy 380.235206 -279.098248) (xy 380.496826 -279.098248)
		)
		(stroke
			(width 0)
			(type solid)
		)
		(fill yes)
		(layer "In6.Cu")
		(net "M_H_CPU0_SA_DQ<3>")
	)
	(gr_poly
		(pts
			(xy 380.547118 -271.215866) (xy 380.500128 -271.063466) (xy 380.238508 -271.063466) (xy 380.191518 -271.215866)
			(xy 380.191518 -271.260062) (xy 380.547118 -271.260062)
		)
		(stroke
			(width 0)
			(type solid)
		)
		(fill yes)
		(layer "In6.Cu")
		(net "M_G_CPU0_SA_DQ<14>")
	)
	(gr_poly
		(pts
			(xy 380.547118 -269.179294) (xy 380.547118 -269.134844) (xy 380.191518 -269.134844) (xy 380.191518 -269.179294)
			(xy 380.238508 -269.331694) (xy 380.500128 -269.331694)
		)
		(stroke
			(width 0)
			(type solid)
		)
		(fill yes)
		(layer "In6.Cu")
		(net "M_G_CPU0_SA_DQ<25>")
	)
	(gr_poly
		(pts
			(xy 380.547118 -266.332462) (xy 380.500128 -266.180062) (xy 380.238508 -266.180062) (xy 380.191518 -266.332462)
			(xy 380.191518 -266.376658) (xy 380.547118 -266.376658)
		)
		(stroke
			(width 0)
			(type solid)
		)
		(fill yes)
		(layer "In6.Cu")
		(net "M_G_CPU0_SA_DQ<30>")
	)
	(gr_poly
		(pts
			(xy 380.547118 -265.923522) (xy 380.547118 -265.879326) (xy 380.191518 -265.879326) (xy 380.191518 -265.923522)
			(xy 380.238508 -266.075922) (xy 380.500128 -266.075922)
		)
		(stroke
			(width 0)
			(type solid)
		)
		(fill yes)
		(layer "In6.Cu")
		(net "M_G_CPU0_SA_DQ<29>")
	)
	(gr_poly
		(pts
			(xy 380.547118 -264.29589) (xy 380.547118 -264.25144) (xy 380.191518 -264.25144) (xy 380.191518 -264.29589)
			(xy 380.238508 -264.44829) (xy 380.500128 -264.44829)
		)
		(stroke
			(width 0)
			(type solid)
		)
		(fill yes)
		(layer "In6.Cu")
		(net "M_G_CPU0_SA_CB<1>")
	)
	(gr_poly
		(pts
			(xy 380.54788 -264.70483) (xy 380.50089 -264.55243) (xy 380.23927 -264.55243) (xy 380.19228 -264.70483)
			(xy 380.19228 -264.749026) (xy 380.54788 -264.749026)
		)
		(stroke
			(width 0)
			(type solid)
		)
		(fill yes)
		(layer "In6.Cu")
		(net "M_G_CPU0_SA_CB<2>")
	)
	(gr_poly
		(pts
			(xy 380.549658 -272.435066) (xy 380.549658 -272.390616) (xy 380.194058 -272.390616) (xy 380.194058 -272.435066)
			(xy 380.241048 -272.587466) (xy 380.502668 -272.587466)
		)
		(stroke
			(width 0)
			(type solid)
		)
		(fill yes)
		(layer "In6.Cu")
		(net "M_G_CPU0_SA_DQS_DN<6>")
	)
	(gr_poly
		(pts
			(xy 380.549658 -267.551662) (xy 380.549658 -267.507212) (xy 380.194058 -267.507212) (xy 380.194058 -267.551662)
			(xy 380.241048 -267.704062) (xy 380.502668 -267.704062)
		)
		(stroke
			(width 0)
			(type solid)
		)
		(fill yes)
		(layer "In6.Cu")
		(net "M_G_CPU0_SA_DQS_DN<8>")
	)
	(gr_poly
		(pts
			(xy 380.549658 -262.668258) (xy 380.549658 -262.623808) (xy 380.194058 -262.623808) (xy 380.194058 -262.668258)
			(xy 380.241048 -262.820658) (xy 380.502668 -262.820658)
		)
		(stroke
			(width 0)
			(type solid)
		)
		(fill yes)
		(layer "In6.Cu")
		(net "M_G_CPU0_SA_DQS_DN<9>")
	)
	(gr_poly
		(pts
			(xy 380.552198 -279.354534) (xy 380.505208 -279.202134) (xy 380.243588 -279.202134) (xy 380.196598 -279.354534)
			(xy 380.196598 -279.39873) (xy 380.552198 -279.39873)
		)
		(stroke
			(width 0)
			(type solid)
		)
		(fill yes)
		(layer "In6.Cu")
		(net "M_H_CPU0_SA_DQ<2>")
	)
	(gr_poly
		(pts
			(xy 380.897638 -232.732834) (xy 380.850648 -232.580434) (xy 380.589028 -232.580434) (xy 380.542038 -232.732834)
			(xy 380.542038 -232.77703) (xy 380.897638 -232.77703)
		)
		(stroke
			(width 0)
			(type solid)
		)
		(fill yes)
		(layer "In6.Cu")
		(net "M_G_CPU0_SB_DQ<13>")
	)
	(gr_poly
		(pts
			(xy 380.899416 -238.83493) (xy 380.899416 -238.790734) (xy 380.543816 -238.790734) (xy 380.543816 -238.83493)
			(xy 380.590806 -238.98733) (xy 380.852426 -238.98733)
		)
		(stroke
			(width 0)
			(type solid)
		)
		(fill yes)
		(layer "In6.Cu")
		(net "M_G_CPU0_SB_DQ<4>")
	)
	(gr_poly
		(pts
			(xy 380.900178 -237.616238) (xy 380.853188 -237.463838) (xy 380.591568 -237.463838) (xy 380.544578 -237.616238)
			(xy 380.544578 -237.660434) (xy 380.900178 -237.660434)
		)
		(stroke
			(width 0)
			(type solid)
		)
		(fill yes)
		(layer "In6.Cu")
		(net "M_G_CPU0_SB_DQ<7>")
	)
	(gr_poly
		(pts
			(xy 380.903734 -249.010678) (xy 380.856744 -248.858278) (xy 380.595124 -248.858278) (xy 380.548134 -249.010678)
			(xy 380.548134 -249.054874) (xy 380.903734 -249.054874)
		)
		(stroke
			(width 0)
			(type solid)
		)
		(fill yes)
		(layer "In6.Cu")
		(net "M_E_CPU0_SB_RSP<0>")
	)
	(gr_poly
		(pts
			(xy 380.903734 -248.601738) (xy 380.903734 -248.557542) (xy 380.548134 -248.557542) (xy 380.548134 -248.601738)
			(xy 380.595124 -248.754138) (xy 380.856744 -248.754138)
		)
		(stroke
			(width 0)
			(type solid)
		)
		(fill yes)
		(layer "In6.Cu")
		(net "M_E_CPU0_SA_RSP<1>")
	)
	(gr_poly
		(pts
			(xy 380.903734 -243.718334) (xy 380.903734 -243.674138) (xy 380.548134 -243.674138) (xy 380.548134 -243.718334)
			(xy 380.595124 -243.870734) (xy 380.856744 -243.870734)
		)
		(stroke
			(width 0)
			(type solid)
		)
		(fill yes)
		(layer "In6.Cu")
		(net "M_H_CPU0_SB_CS_N<0>")
	)
	(gr_poly
		(pts
			(xy 380.903734 -233.952034) (xy 380.903734 -233.907584) (xy 380.548134 -233.907584) (xy 380.548134 -233.952034)
			(xy 380.595124 -234.104434) (xy 380.856744 -234.104434)
		)
		(stroke
			(width 0)
			(type solid)
		)
		(fill yes)
		(layer "In6.Cu")
		(net "M_G_CPU0_SB_DQ<14>")
	)
	(gr_poly
		(pts
			(xy 380.903734 -229.06863) (xy 380.903734 -229.02418) (xy 380.548134 -229.02418) (xy 380.548134 -229.06863)
			(xy 380.595124 -229.22103) (xy 380.856744 -229.22103)
		)
		(stroke
			(width 0)
			(type solid)
		)
		(fill yes)
		(layer "In6.Cu")
		(net "M_H_CPU0_SB_DQS_DN<7>")
	)
	(gr_poly
		(pts
			(xy 380.903734 -227.84943) (xy 380.856744 -227.69703) (xy 380.595124 -227.69703) (xy 380.548134 -227.84943)
			(xy 380.548134 -227.893626) (xy 380.903734 -227.893626)
		)
		(stroke
			(width 0)
			(type solid)
		)
		(fill yes)
		(layer "In6.Cu")
		(net "M_H_CPU0_SB_DQ<22>")
	)
	(gr_poly
		(pts
			(xy 380.909576 -240.871502) (xy 380.862586 -240.719102) (xy 380.600966 -240.719102) (xy 380.553976 -240.871502)
			(xy 380.553976 -240.915698) (xy 380.909576 -240.915698)
		)
		(stroke
			(width 0)
			(type solid)
		)
		(fill yes)
		(layer "In6.Cu")
		(net "M_G_CPU0_SB_DQ<3>")
	)
	(gr_poly
		(pts
			(xy 380.909576 -240.46307) (xy 380.909576 -240.418874) (xy 380.553976 -240.418874) (xy 380.553976 -240.46307)
			(xy 380.600966 -240.61547) (xy 380.862586 -240.61547)
		)
		(stroke
			(width 0)
			(type solid)
		)
		(fill yes)
		(layer "In6.Cu")
		(net "M_G_CPU0_SB_DQS_DP<0>")
	)
	(gr_poly
		(pts
			(xy 380.909576 -237.207298) (xy 380.909576 -237.163102) (xy 380.553976 -237.163102) (xy 380.553976 -237.207298)
			(xy 380.600966 -237.359698) (xy 380.862586 -237.359698)
		)
		(stroke
			(width 0)
			(type solid)
		)
		(fill yes)
		(layer "In6.Cu")
		(net "M_G_CPU0_SB_DQ<8>")
	)
	(gr_poly
		(pts
			(xy 380.909576 -235.988098) (xy 380.862586 -235.835698) (xy 380.600966 -235.835698) (xy 380.553976 -235.988098)
			(xy 380.553976 -236.032294) (xy 380.909576 -236.032294)
		)
		(stroke
			(width 0)
			(type solid)
		)
		(fill yes)
		(layer "In6.Cu")
		(net "M_G_CPU0_SB_DQ<9>")
	)
	(gr_poly
		(pts
			(xy 380.909576 -235.579666) (xy 380.909576 -235.53547) (xy 380.553976 -235.53547) (xy 380.553976 -235.579666)
			(xy 380.600966 -235.732066) (xy 380.862586 -235.732066)
		)
		(stroke
			(width 0)
			(type solid)
		)
		(fill yes)
		(layer "In6.Cu")
		(net "M_G_CPU0_SB_DQS_DN<6>")
	)
	(gr_poly
		(pts
			(xy 380.909576 -231.104694) (xy 380.862586 -230.952294) (xy 380.600966 -230.952294) (xy 380.553976 -231.104694)
			(xy 380.553976 -231.14889) (xy 380.909576 -231.14889)
		)
		(stroke
			(width 0)
			(type solid)
		)
		(fill yes)
		(layer "In6.Cu")
		(net "M_H_CPU0_SB_DQ<18>")
	)
	(gr_poly
		(pts
			(xy 380.909576 -230.696262) (xy 380.909576 -230.652066) (xy 380.553976 -230.652066) (xy 380.553976 -230.696262)
			(xy 380.600966 -230.848662) (xy 380.862586 -230.848662)
		)
		(stroke
			(width 0)
			(type solid)
		)
		(fill yes)
		(layer "In6.Cu")
		(net "M_H_CPU0_SB_DQ<17>")
	)
	(gr_poly
		(pts
			(xy 380.912116 -244.126766) (xy 380.865126 -243.974366) (xy 380.603506 -243.974366) (xy 380.556516 -244.126766)
			(xy 380.556516 -244.171216) (xy 380.912116 -244.171216)
		)
		(stroke
			(width 0)
			(type solid)
		)
		(fill yes)
		(layer "In6.Cu")
		(net "M_H_CPU0_SB_CS_N<3>")
	)
	(gr_poly
		(pts
			(xy 380.912116 -242.090702) (xy 380.912116 -242.046506) (xy 380.556516 -242.046506) (xy 380.556516 -242.090702)
			(xy 380.603506 -242.243102) (xy 380.865126 -242.243102)
		)
		(stroke
			(width 0)
			(type solid)
		)
		(fill yes)
		(layer "In6.Cu")
		(net "M_G_CPU0_SB_DQ<0>")
	)
	(gr_poly
		(pts
			(xy 380.912116 -239.243362) (xy 380.865126 -239.090962) (xy 380.603506 -239.090962) (xy 380.556516 -239.243362)
			(xy 380.556516 -239.287812) (xy 380.912116 -239.287812)
		)
		(stroke
			(width 0)
			(type solid)
		)
		(fill yes)
		(layer "In6.Cu")
		(net "M_G_CPU0_SB_DQS_DP<5>")
	)
	(gr_poly
		(pts
			(xy 380.912116 -234.360466) (xy 380.865126 -234.208066) (xy 380.603506 -234.208066) (xy 380.556516 -234.360466)
			(xy 380.556516 -234.404662) (xy 380.912116 -234.404662)
		)
		(stroke
			(width 0)
			(type solid)
		)
		(fill yes)
		(layer "In6.Cu")
		(net "M_G_CPU0_SB_DQS_DN<1>")
	)
	(gr_poly
		(pts
			(xy 380.912116 -229.477062) (xy 380.865126 -229.324662) (xy 380.603506 -229.324662) (xy 380.556516 -229.477062)
			(xy 380.556516 -229.521258) (xy 380.912116 -229.521258)
		)
		(stroke
			(width 0)
			(type solid)
		)
		(fill yes)
		(layer "In6.Cu")
		(net "M_H_CPU0_SB_DQS_DN<2>")
	)
	(gr_poly
		(pts
			(xy 380.912116 -227.440998) (xy 380.912116 -227.396548) (xy 380.556516 -227.396548) (xy 380.556516 -227.440998)
			(xy 380.603506 -227.593398) (xy 380.865126 -227.593398)
		)
		(stroke
			(width 0)
			(type solid)
		)
		(fill yes)
		(layer "In6.Cu")
		(net "M_H_CPU0_SB_DQ<21>")
	)
	(gr_poly
		(pts
			(xy 381.00762 -279.759918) (xy 381.00762 -279.715722) (xy 380.65202 -279.715722) (xy 380.65202 -279.759918)
			(xy 380.69901 -279.912318) (xy 380.96063 -279.912318)
		)
		(stroke
			(width 0)
			(type solid)
		)
		(fill yes)
		(layer "In6.Cu")
		(net "M_H_CPU0_SA_DQ<0>")
	)
	(gr_poly
		(pts
			(xy 381.00762 -274.876514) (xy 381.00762 -274.832064) (xy 380.65202 -274.832064) (xy 380.65202 -274.876514)
			(xy 380.69901 -275.028914) (xy 380.96063 -275.028914)
		)
		(stroke
			(width 0)
			(type solid)
		)
		(fill yes)
		(layer "In6.Cu")
		(net "M_G_CPU0_SA_DQ<8>")
	)
	(gr_poly
		(pts
			(xy 381.00762 -269.99311) (xy 381.00762 -269.948914) (xy 380.65202 -269.948914) (xy 380.65202 -269.99311)
			(xy 380.69901 -270.14551) (xy 380.96063 -270.14551)
		)
		(stroke
			(width 0)
			(type solid)
		)
		(fill yes)
		(layer "In6.Cu")
		(net "M_G_CPU0_SA_DQ<24>")
	)
	(gr_poly
		(pts
			(xy 381.009398 -265.109706) (xy 381.009398 -265.06551) (xy 380.653798 -265.06551) (xy 380.653798 -265.109706)
			(xy 380.700788 -265.262106) (xy 380.962408 -265.262106)
		)
		(stroke
			(width 0)
			(type solid)
		)
		(fill yes)
		(layer "In6.Cu")
		(net "M_G_CPU0_SA_CB<0>")
	)
	(gr_poly
		(pts
			(xy 381.01016 -271.62125) (xy 381.01016 -271.5768) (xy 380.65456 -271.5768) (xy 380.65456 -271.62125)
			(xy 380.70155 -271.77365) (xy 380.96317 -271.77365)
		)
		(stroke
			(width 0)
			(type solid)
		)
		(fill yes)
		(layer "In6.Cu")
		(net "M_G_CPU0_SA_DQ<12>")
	)
	(gr_poly
		(pts
			(xy 381.01016 -266.737846) (xy 381.01016 -266.693396) (xy 380.65456 -266.693396) (xy 380.65456 -266.737846)
			(xy 380.70155 -266.890246) (xy 380.96317 -266.890246)
		)
		(stroke
			(width 0)
			(type solid)
		)
		(fill yes)
		(layer "In6.Cu")
		(net "M_G_CPU0_SA_DQ<28>")
	)
	(gr_poly
		(pts
			(xy 381.01016 -265.518646) (xy 380.96317 -265.366246) (xy 380.70155 -265.366246) (xy 380.65456 -265.518646)
			(xy 380.65456 -265.563096) (xy 381.01016 -265.563096)
		)
		(stroke
			(width 0)
			(type solid)
		)
		(fill yes)
		(layer "In6.Cu")
		(net "M_G_CPU0_SA_DQ<31>")
	)
	(gr_poly
		(pts
			(xy 381.01016 -263.891014) (xy 380.96317 -263.738614) (xy 380.70155 -263.738614) (xy 380.65456 -263.891014)
			(xy 380.65456 -263.93521) (xy 381.01016 -263.93521)
		)
		(stroke
			(width 0)
			(type solid)
		)
		(fill yes)
		(layer "In6.Cu")
		(net "M_G_CPU0_SA_CB<3>")
	)
	(gr_poly
		(pts
			(xy 381.013716 -278.540718) (xy 380.966726 -278.388318) (xy 380.705106 -278.388318) (xy 380.658116 -278.540718)
			(xy 380.658116 -278.585168) (xy 381.013716 -278.585168)
		)
		(stroke
			(width 0)
			(type solid)
		)
		(fill yes)
		(layer "In6.Cu")
		(net "M_H_CPU0_SA_DQ<1>")
	)
	(gr_poly
		(pts
			(xy 381.013716 -273.657314) (xy 380.966726 -273.504914) (xy 380.705106 -273.504914) (xy 380.658116 -273.657314)
			(xy 380.658116 -273.701764) (xy 381.013716 -273.701764)
		)
		(stroke
			(width 0)
			(type solid)
		)
		(fill yes)
		(layer "In6.Cu")
		(net "M_G_CPU0_SA_DQ<11>")
	)
	(gr_poly
		(pts
			(xy 381.013716 -268.77391) (xy 380.966726 -268.62151) (xy 380.705106 -268.62151) (xy 380.658116 -268.77391)
			(xy 380.658116 -268.81836) (xy 381.013716 -268.81836)
		)
		(stroke
			(width 0)
			(type solid)
		)
		(fill yes)
		(layer "In6.Cu")
		(net "M_G_CPU0_SA_DQ<27>")
	)
	(gr_poly
		(pts
			(xy 381.019558 -276.912578) (xy 380.972568 -276.760178) (xy 380.710948 -276.760178) (xy 380.663958 -276.912578)
			(xy 380.663958 -276.957028) (xy 381.019558 -276.957028)
		)
		(stroke
			(width 0)
			(type solid)
		)
		(fill yes)
		(layer "In6.Cu")
		(net "M_H_CPU0_SA_DQS_DP<5>")
	)
	(gr_poly
		(pts
			(xy 381.019558 -276.5044) (xy 381.019558 -276.460204) (xy 380.663958 -276.460204) (xy 380.663958 -276.5044)
			(xy 380.710948 -276.6568) (xy 380.972568 -276.6568)
		)
		(stroke
			(width 0)
			(type solid)
		)
		(fill yes)
		(layer "In6.Cu")
		(net "M_H_CPU0_SA_DQ<4>")
	)
	(gr_poly
		(pts
			(xy 381.019558 -275.284946) (xy 380.972568 -275.132546) (xy 380.710948 -275.132546) (xy 380.663958 -275.284946)
			(xy 380.663958 -275.329396) (xy 381.019558 -275.329396)
		)
		(stroke
			(width 0)
			(type solid)
		)
		(fill yes)
		(layer "In6.Cu")
		(net "M_H_CPU0_SA_DQ<7>")
	)
	(gr_poly
		(pts
			(xy 381.019558 -272.029174) (xy 380.972568 -271.876774) (xy 380.710948 -271.876774) (xy 380.663958 -272.029174)
			(xy 380.663958 -272.073624) (xy 381.019558 -272.073624)
		)
		(stroke
			(width 0)
			(type solid)
		)
		(fill yes)
		(layer "In6.Cu")
		(net "M_G_CPU0_SA_DQS_DP<6>")
	)
	(gr_poly
		(pts
			(xy 381.019558 -270.40205) (xy 380.972568 -270.24965) (xy 380.710948 -270.24965) (xy 380.663958 -270.40205)
			(xy 380.663958 -270.446246) (xy 381.019558 -270.446246)
		)
		(stroke
			(width 0)
			(type solid)
		)
		(fill yes)
		(layer "In6.Cu")
		(net "M_G_CPU0_SA_DQ<15>")
	)
	(gr_poly
		(pts
			(xy 381.019558 -267.146278) (xy 380.972568 -266.993878) (xy 380.710948 -266.993878) (xy 380.663958 -267.146278)
			(xy 380.663958 -267.190474) (xy 381.019558 -267.190474)
		)
		(stroke
			(width 0)
			(type solid)
		)
		(fill yes)
		(layer "In6.Cu")
		(net "M_G_CPU0_SA_DQS_DP<8>")
	)
	(gr_poly
		(pts
			(xy 381.019558 -262.262874) (xy 380.972568 -262.110474) (xy 380.710948 -262.110474) (xy 380.663958 -262.262874)
			(xy 380.663958 -262.30707) (xy 381.019558 -262.30707)
		)
		(stroke
			(width 0)
			(type solid)
		)
		(fill yes)
		(layer "In6.Cu")
		(net "M_G_CPU0_SA_DQS_DP<9>")
	)
	(gr_poly
		(pts
			(xy 381.019558 -261.854442) (xy 381.019558 -261.810246) (xy 380.663958 -261.810246) (xy 380.663958 -261.854442)
			(xy 380.710948 -262.006842) (xy 380.972568 -262.006842)
		)
		(stroke
			(width 0)
			(type solid)
		)
		(fill yes)
		(layer "In6.Cu")
		(net "M_G_CPU0_SA_CB<4>")
	)
	(gr_poly
		(pts
			(xy 381.019558 -260.635242) (xy 380.972568 -260.482842) (xy 380.710948 -260.482842) (xy 380.663958 -260.635242)
			(xy 380.663958 -260.679438) (xy 381.019558 -260.679438)
		)
		(stroke
			(width 0)
			(type solid)
		)
		(fill yes)
		(layer "In6.Cu")
		(net "M_G_CPU0_SA_CB<7>")
	)
	(gr_poly
		(pts
			(xy 381.022098 -278.132286) (xy 381.022098 -278.08809) (xy 380.666498 -278.08809) (xy 380.666498 -278.132286)
			(xy 380.713488 -278.284686) (xy 380.975108 -278.284686)
		)
		(stroke
			(width 0)
			(type solid)
		)
		(fill yes)
		(layer "In6.Cu")
		(net "M_H_CPU0_SA_DQS_DP<0>")
	)
	(gr_poly
		(pts
			(xy 381.022098 -273.248882) (xy 381.022098 -273.204686) (xy 380.666498 -273.204686) (xy 380.666498 -273.248882)
			(xy 380.713488 -273.401282) (xy 380.975108 -273.401282)
		)
		(stroke
			(width 0)
			(type solid)
		)
		(fill yes)
		(layer "In6.Cu")
		(net "M_G_CPU0_SA_DQS_DP<1>")
	)
	(gr_poly
		(pts
			(xy 381.022098 -268.365478) (xy 381.022098 -268.321282) (xy 380.666498 -268.321282) (xy 380.666498 -268.365478)
			(xy 380.713488 -268.517878) (xy 380.975108 -268.517878)
		)
		(stroke
			(width 0)
			(type solid)
		)
		(fill yes)
		(layer "In6.Cu")
		(net "M_G_CPU0_SA_DQS_DP<3>")
	)
	(gr_poly
		(pts
			(xy 381.022098 -263.482582) (xy 381.022098 -263.438132) (xy 380.666498 -263.438132) (xy 380.666498 -263.482582)
			(xy 380.713488 -263.634982) (xy 380.975108 -263.634982)
		)
		(stroke
			(width 0)
			(type solid)
		)
		(fill yes)
		(layer "In6.Cu")
		(net "M_G_CPU0_SA_DQS_DP<4>")
	)
	(gr_poly
		(pts
			(xy 381.367538 -244.532658) (xy 381.367538 -244.488208) (xy 381.011938 -244.488208) (xy 381.011938 -244.532658)
			(xy 381.058928 -244.685058) (xy 381.320548 -244.685058)
		)
		(stroke
			(width 0)
			(type solid)
		)
		(fill yes)
		(layer "In6.Cu")
		(net "M_H_CPU0_SB_CS_N<2>")
	)
	(gr_poly
		(pts
			(xy 381.367538 -241.685318) (xy 381.320548 -241.532918) (xy 381.058928 -241.532918) (xy 381.011938 -241.685318)
			(xy 381.011938 -241.729514) (xy 381.367538 -241.729514)
		)
		(stroke
			(width 0)
			(type solid)
		)
		(fill yes)
		(layer "In6.Cu")
		(net "M_G_CPU0_SB_DQ<2>")
	)
	(gr_poly
		(pts
			(xy 381.367538 -241.276886) (xy 381.367538 -241.23269) (xy 381.011938 -241.23269) (xy 381.011938 -241.276886)
			(xy 381.058928 -241.429286) (xy 381.320548 -241.429286)
		)
		(stroke
			(width 0)
			(type solid)
		)
		(fill yes)
		(layer "In6.Cu")
		(net "M_G_CPU0_SB_DQ<1>")
	)
	(gr_poly
		(pts
			(xy 381.367538 -240.057178) (xy 381.320548 -239.904778) (xy 381.058928 -239.904778) (xy 381.011938 -240.057178)
			(xy 381.011938 -240.101628) (xy 381.367538 -240.101628)
		)
		(stroke
			(width 0)
			(type solid)
		)
		(fill yes)
		(layer "In6.Cu")
		(net "M_G_CPU0_SB_DQS_DN<0>")
	)
	(gr_poly
		(pts
			(xy 381.367538 -239.649254) (xy 381.367538 -239.604804) (xy 381.011938 -239.604804) (xy 381.011938 -239.649254)
			(xy 381.058928 -239.801654) (xy 381.320548 -239.801654)
		)
		(stroke
			(width 0)
			(type solid)
		)
		(fill yes)
		(layer "In6.Cu")
		(net "M_G_CPU0_SB_DQS_DN<5>")
	)
	(gr_poly
		(pts
			(xy 381.367538 -236.39399) (xy 381.367538 -236.34954) (xy 381.011938 -236.34954) (xy 381.011938 -236.39399)
			(xy 381.058928 -236.54639) (xy 381.320548 -236.54639)
		)
		(stroke
			(width 0)
			(type solid)
		)
		(fill yes)
		(layer "In6.Cu")
		(net "M_G_CPU0_SB_DQ<11>")
	)
	(gr_poly
		(pts
			(xy 381.367538 -235.174282) (xy 381.320548 -235.021882) (xy 381.058928 -235.021882) (xy 381.011938 -235.174282)
			(xy 381.011938 -235.218478) (xy 381.367538 -235.218478)
		)
		(stroke
			(width 0)
			(type solid)
		)
		(fill yes)
		(layer "In6.Cu")
		(net "M_G_CPU0_SB_DQS_DP<6>")
	)
	(gr_poly
		(pts
			(xy 381.367538 -234.76585) (xy 381.367538 -234.721654) (xy 381.011938 -234.721654) (xy 381.011938 -234.76585)
			(xy 381.058928 -234.91825) (xy 381.320548 -234.91825)
		)
		(stroke
			(width 0)
			(type solid)
		)
		(fill yes)
		(layer "In6.Cu")
		(net "M_G_CPU0_SB_DQS_DP<1>")
	)
	(gr_poly
		(pts
			(xy 381.367538 -231.510586) (xy 381.367538 -231.466136) (xy 381.011938 -231.466136) (xy 381.011938 -231.510586)
			(xy 381.058928 -231.662986) (xy 381.320548 -231.662986)
		)
		(stroke
			(width 0)
			(type solid)
		)
		(fill yes)
		(layer "In6.Cu")
		(net "M_H_CPU0_SB_DQ<16>")
	)
	(gr_poly
		(pts
			(xy 381.367538 -230.290878) (xy 381.320548 -230.138478) (xy 381.058928 -230.138478) (xy 381.011938 -230.290878)
			(xy 381.011938 -230.335074) (xy 381.367538 -230.335074)
		)
		(stroke
			(width 0)
			(type solid)
		)
		(fill yes)
		(layer "In6.Cu")
		(net "M_H_CPU0_SB_DQ<19>")
	)
	(gr_poly
		(pts
			(xy 381.367538 -229.882446) (xy 381.367538 -229.83825) (xy 381.011938 -229.83825) (xy 381.011938 -229.882446)
			(xy 381.058928 -230.034846) (xy 381.320548 -230.034846)
		)
		(stroke
			(width 0)
			(type solid)
		)
		(fill yes)
		(layer "In6.Cu")
		(net "M_H_CPU0_SB_DQS_DP<2>")
	)
	(gr_poly
		(pts
			(xy 381.367538 -227.035106) (xy 381.320548 -226.882706) (xy 381.058928 -226.882706) (xy 381.011938 -227.035106)
			(xy 381.011938 -227.079556) (xy 381.367538 -227.079556)
		)
		(stroke
			(width 0)
			(type solid)
		)
		(fill yes)
		(layer "In6.Cu")
		(net "M_H_CPU0_SB_DQ<23>")
	)
	(gr_poly
		(pts
			(xy 381.373634 -249.415554) (xy 381.373634 -249.371358) (xy 381.018034 -249.371358) (xy 381.018034 -249.415554)
			(xy 381.065024 -249.567954) (xy 381.326644 -249.567954)
		)
		(stroke
			(width 0)
			(type solid)
		)
		(fill yes)
		(layer "In6.Cu")
		(net "M_E_CPU0_SA_RSP<0>")
	)
	(gr_poly
		(pts
			(xy 381.373634 -248.196354) (xy 381.326644 -248.043954) (xy 381.065024 -248.043954) (xy 381.018034 -248.196354)
			(xy 381.018034 -248.240804) (xy 381.373634 -248.240804)
		)
		(stroke
			(width 0)
			(type solid)
		)
		(fill yes)
		(layer "In6.Cu")
		(net "M_E_CPU0_SB_RSP<1>")
	)
	(gr_poly
		(pts
			(xy 381.373634 -243.313458) (xy 381.326644 -243.161058) (xy 381.065024 -243.161058) (xy 381.018034 -243.313458)
			(xy 381.018034 -243.357654) (xy 381.373634 -243.357654)
		)
		(stroke
			(width 0)
			(type solid)
		)
		(fill yes)
		(layer "In6.Cu")
		(net "M_H_CPU0_SB_CS_N<1>")
	)
	(gr_poly
		(pts
			(xy 381.373634 -233.54665) (xy 381.326644 -233.39425) (xy 381.065024 -233.39425) (xy 381.018034 -233.54665)
			(xy 381.018034 -233.590846) (xy 381.373634 -233.590846)
		)
		(stroke
			(width 0)
			(type solid)
		)
		(fill yes)
		(layer "In6.Cu")
		(net "M_G_CPU0_SB_DQ<12>")
	)
	(gr_poly
		(pts
			(xy 381.373634 -228.663246) (xy 381.326644 -228.510846) (xy 381.065024 -228.510846) (xy 381.018034 -228.663246)
			(xy 381.018034 -228.707696) (xy 381.373634 -228.707696)
		)
		(stroke
			(width 0)
			(type solid)
		)
		(fill yes)
		(layer "In6.Cu")
		(net "M_H_CPU0_SB_DQS_DP<7>")
	)
	(gr_poly
		(pts
			(xy 381.373634 -228.254814) (xy 381.373634 -228.210364) (xy 381.018034 -228.210364) (xy 381.018034 -228.254814)
			(xy 381.065024 -228.407214) (xy 381.326644 -228.407214)
		)
		(stroke
			(width 0)
			(type solid)
		)
		(fill yes)
		(layer "In6.Cu")
		(net "M_H_CPU0_SB_DQ<20>")
	)
	(gr_poly
		(pts
			(xy 381.376936 -238.021114) (xy 381.376936 -237.976664) (xy 381.021336 -237.976664) (xy 381.021336 -238.021114)
			(xy 381.068326 -238.173514) (xy 381.329946 -238.173514)
		)
		(stroke
			(width 0)
			(type solid)
		)
		(fill yes)
		(layer "In6.Cu")
		(net "M_G_CPU0_SB_DQ<5>")
	)
	(gr_poly
		(pts
			(xy 381.377698 -238.430054) (xy 381.330708 -238.277654) (xy 381.069088 -238.277654) (xy 381.022098 -238.430054)
			(xy 381.022098 -238.47425) (xy 381.377698 -238.47425)
		)
		(stroke
			(width 0)
			(type solid)
		)
		(fill yes)
		(layer "In6.Cu")
		(net "M_G_CPU0_SB_DQ<6>")
	)
	(gr_poly
		(pts
			(xy 381.379476 -236.801914) (xy 381.332486 -236.649514) (xy 381.070866 -236.649514) (xy 381.023876 -236.801914)
			(xy 381.023876 -236.84611) (xy 381.379476 -236.84611)
		)
		(stroke
			(width 0)
			(type solid)
		)
		(fill yes)
		(layer "In6.Cu")
		(net "M_G_CPU0_SB_DQ<10>")
	)
	(gr_poly
		(pts
			(xy 381.382016 -233.138218) (xy 381.382016 -233.093768) (xy 381.026416 -233.093768) (xy 381.026416 -233.138218)
			(xy 381.073406 -233.290618) (xy 381.335026 -233.290618)
		)
		(stroke
			(width 0)
			(type solid)
		)
		(fill yes)
		(layer "In6.Cu")
		(net "M_G_CPU0_SB_DQ<15>")
	)
	(gr_poly
		(pts
			(xy 381.47498 -277.726394) (xy 381.42799 -277.573994) (xy 381.16637 -277.573994) (xy 381.11938 -277.726394)
			(xy 381.11938 -277.770844) (xy 381.47498 -277.770844)
		)
		(stroke
			(width 0)
			(type solid)
		)
		(fill yes)
		(layer "In6.Cu")
		(net "M_H_CPU0_SA_DQS_DN<0>")
	)
	(gr_poly
		(pts
			(xy 381.47498 -277.318216) (xy 381.47498 -277.27402) (xy 381.11938 -277.27402) (xy 381.11938 -277.318216)
			(xy 381.16637 -277.470616) (xy 381.42799 -277.470616)
		)
		(stroke
			(width 0)
			(type solid)
		)
		(fill yes)
		(layer "In6.Cu")
		(net "M_H_CPU0_SA_DQS_DN<5>")
	)
	(gr_poly
		(pts
			(xy 381.47498 -276.098762) (xy 381.42799 -275.946362) (xy 381.16637 -275.946362) (xy 381.11938 -276.098762)
			(xy 381.11938 -276.143212) (xy 381.47498 -276.143212)
		)
		(stroke
			(width 0)
			(type solid)
		)
		(fill yes)
		(layer "In6.Cu")
		(net "M_H_CPU0_SA_DQ<6>")
	)
	(gr_poly
		(pts
			(xy 381.47498 -272.843498) (xy 381.42799 -272.691098) (xy 381.16637 -272.691098) (xy 381.11938 -272.843498)
			(xy 381.11938 -272.887694) (xy 381.47498 -272.887694)
		)
		(stroke
			(width 0)
			(type solid)
		)
		(fill yes)
		(layer "In6.Cu")
		(net "M_G_CPU0_SA_DQS_DN<1>")
	)
	(gr_poly
		(pts
			(xy 381.47498 -272.435066) (xy 381.47498 -272.39087) (xy 381.11938 -272.39087) (xy 381.11938 -272.435066)
			(xy 381.16637 -272.587466) (xy 381.42799 -272.587466)
		)
		(stroke
			(width 0)
			(type solid)
		)
		(fill yes)
		(layer "In6.Cu")
		(net "M_G_CPU0_SA_DQS_DN<6>")
	)
	(gr_poly
		(pts
			(xy 381.47498 -267.960094) (xy 381.42799 -267.807694) (xy 381.16637 -267.807694) (xy 381.11938 -267.960094)
			(xy 381.11938 -268.00429) (xy 381.47498 -268.00429)
		)
		(stroke
			(width 0)
			(type solid)
		)
		(fill yes)
		(layer "In6.Cu")
		(net "M_G_CPU0_SA_DQS_DN<3>")
	)
	(gr_poly
		(pts
			(xy 381.47498 -267.551662) (xy 381.47498 -267.507466) (xy 381.11938 -267.507466) (xy 381.11938 -267.551662)
			(xy 381.16637 -267.704062) (xy 381.42799 -267.704062)
		)
		(stroke
			(width 0)
			(type solid)
		)
		(fill yes)
		(layer "In6.Cu")
		(net "M_G_CPU0_SA_DQS_DN<8>")
	)
	(gr_poly
		(pts
			(xy 381.47498 -263.07669) (xy 381.42799 -262.92429) (xy 381.16637 -262.92429) (xy 381.11938 -263.07669)
			(xy 381.11938 -263.120886) (xy 381.47498 -263.120886)
		)
		(stroke
			(width 0)
			(type solid)
		)
		(fill yes)
		(layer "In6.Cu")
		(net "M_G_CPU0_SA_DQS_DN<4>")
	)
	(gr_poly
		(pts
			(xy 381.47498 -262.668258) (xy 381.47498 -262.624062) (xy 381.11938 -262.624062) (xy 381.11938 -262.668258)
			(xy 381.16637 -262.820658) (xy 381.42799 -262.820658)
		)
		(stroke
			(width 0)
			(type solid)
		)
		(fill yes)
		(layer "In6.Cu")
		(net "M_G_CPU0_SA_DQS_DN<9>")
	)
	(gr_poly
		(pts
			(xy 381.47498 -261.449058) (xy 381.42799 -261.296658) (xy 381.16637 -261.296658) (xy 381.11938 -261.449058)
			(xy 381.11938 -261.493254) (xy 381.47498 -261.493254)
		)
		(stroke
			(width 0)
			(type solid)
		)
		(fill yes)
		(layer "In6.Cu")
		(net "M_G_CPU0_SA_CB<6>")
	)
	(gr_poly
		(pts
			(xy 381.47752 -279.354788) (xy 381.43053 -279.202388) (xy 381.16891 -279.202388) (xy 381.12192 -279.354788)
			(xy 381.12192 -279.398984) (xy 381.47752 -279.398984)
		)
		(stroke
			(width 0)
			(type solid)
		)
		(fill yes)
		(layer "In6.Cu")
		(net "M_H_CPU0_SA_DQ<2>")
	)
	(gr_poly
		(pts
			(xy 381.47752 -278.945848) (xy 381.47752 -278.901652) (xy 381.12192 -278.901652) (xy 381.12192 -278.945848)
			(xy 381.16891 -279.098248) (xy 381.43053 -279.098248)
		)
		(stroke
			(width 0)
			(type solid)
		)
		(fill yes)
		(layer "In6.Cu")
		(net "M_H_CPU0_SA_DQ<3>")
	)
	(gr_poly
		(pts
			(xy 381.47752 -274.062698) (xy 381.47752 -274.018248) (xy 381.12192 -274.018248) (xy 381.12192 -274.062698)
			(xy 381.16891 -274.215098) (xy 381.43053 -274.215098)
		)
		(stroke
			(width 0)
			(type solid)
		)
		(fill yes)
		(layer "In6.Cu")
		(net "M_G_CPU0_SA_DQ<9>")
	)
	(gr_poly
		(pts
			(xy 381.47752 -269.179294) (xy 381.47752 -269.134844) (xy 381.12192 -269.134844) (xy 381.12192 -269.179294)
			(xy 381.16891 -269.331694) (xy 381.43053 -269.331694)
		)
		(stroke
			(width 0)
			(type solid)
		)
		(fill yes)
		(layer "In6.Cu")
		(net "M_G_CPU0_SA_DQ<25>")
	)
	(gr_poly
		(pts
			(xy 381.483362 -275.690584) (xy 381.483362 -275.646134) (xy 381.127762 -275.646134) (xy 381.127762 -275.690584)
			(xy 381.174752 -275.842984) (xy 381.436372 -275.842984)
		)
		(stroke
			(width 0)
			(type solid)
		)
		(fill yes)
		(layer "In6.Cu")
		(net "M_H_CPU0_SA_DQ<5>")
	)
	(gr_poly
		(pts
			(xy 381.483362 -270.806926) (xy 381.483362 -270.76273) (xy 381.127762 -270.76273) (xy 381.127762 -270.806926)
			(xy 381.174752 -270.959326) (xy 381.436372 -270.959326)
		)
		(stroke
			(width 0)
			(type solid)
		)
		(fill yes)
		(layer "In6.Cu")
		(net "M_G_CPU0_SA_DQ<13>")
	)
	(gr_poly
		(pts
			(xy 381.483362 -261.040626) (xy 381.483362 -260.996176) (xy 381.127762 -260.996176) (xy 381.127762 -261.040626)
			(xy 381.174752 -261.193026) (xy 381.436372 -261.193026)
		)
		(stroke
			(width 0)
			(type solid)
		)
		(fill yes)
		(layer "In6.Cu")
		(net "M_G_CPU0_SA_CB<5>")
	)
	(gr_poly
		(pts
			(xy 381.486918 -271.215866) (xy 381.439928 -271.063466) (xy 381.178308 -271.063466) (xy 381.131318 -271.215866)
			(xy 381.131318 -271.260062) (xy 381.486918 -271.260062)
		)
		(stroke
			(width 0)
			(type solid)
		)
		(fill yes)
		(layer "In6.Cu")
		(net "M_G_CPU0_SA_DQ<14>")
	)
	(gr_poly
		(pts
			(xy 381.486918 -266.332462) (xy 381.439928 -266.180062) (xy 381.178308 -266.180062) (xy 381.131318 -266.332462)
			(xy 381.131318 -266.376658) (xy 381.486918 -266.376658)
		)
		(stroke
			(width 0)
			(type solid)
		)
		(fill yes)
		(layer "In6.Cu")
		(net "M_G_CPU0_SA_DQ<30>")
	)
	(gr_poly
		(pts
			(xy 381.486918 -265.923522) (xy 381.486918 -265.879326) (xy 381.131318 -265.879326) (xy 381.131318 -265.923522)
			(xy 381.178308 -266.075922) (xy 381.439928 -266.075922)
		)
		(stroke
			(width 0)
			(type solid)
		)
		(fill yes)
		(layer "In6.Cu")
		(net "M_G_CPU0_SA_DQ<29>")
	)
	(gr_poly
		(pts
			(xy 381.486918 -264.29589) (xy 381.486918 -264.25144) (xy 381.131318 -264.25144) (xy 381.131318 -264.29589)
			(xy 381.178308 -264.44829) (xy 381.439928 -264.44829)
		)
		(stroke
			(width 0)
			(type solid)
		)
		(fill yes)
		(layer "In6.Cu")
		(net "M_G_CPU0_SA_CB<1>")
	)
	(gr_poly
		(pts
			(xy 381.48768 -264.70483) (xy 381.44069 -264.55243) (xy 381.17907 -264.55243) (xy 381.13208 -264.70483)
			(xy 381.13208 -264.749026) (xy 381.48768 -264.749026)
		)
		(stroke
			(width 0)
			(type solid)
		)
		(fill yes)
		(layer "In6.Cu")
		(net "M_G_CPU0_SA_CB<2>")
	)
	(gr_poly
		(pts
			(xy 381.489458 -274.47113) (xy 381.442468 -274.31873) (xy 381.180848 -274.31873) (xy 381.133858 -274.47113)
			(xy 381.133858 -274.51558) (xy 381.489458 -274.51558)
		)
		(stroke
			(width 0)
			(type solid)
		)
		(fill yes)
		(layer "In6.Cu")
		(net "M_G_CPU0_SA_DQ<10>")
	)
	(gr_poly
		(pts
			(xy 381.489458 -269.587726) (xy 381.442468 -269.435326) (xy 381.180848 -269.435326) (xy 381.133858 -269.587726)
			(xy 381.133858 -269.632176) (xy 381.489458 -269.632176)
		)
		(stroke
			(width 0)
			(type solid)
		)
		(fill yes)
		(layer "In6.Cu")
		(net "M_G_CPU0_SA_DQ<26>")
	)
	(gr_poly
		(pts
			(xy 381.837438 -237.207806) (xy 381.837438 -237.163356) (xy 381.481838 -237.163356) (xy 381.481838 -237.207806)
			(xy 381.528828 -237.360206) (xy 381.790448 -237.360206)
		)
		(stroke
			(width 0)
			(type solid)
		)
		(fill yes)
		(layer "In6.Cu")
		(net "M_G_CPU0_SB_DQ<8>")
	)
	(gr_poly
		(pts
			(xy 381.837438 -232.732326) (xy 381.790448 -232.579926) (xy 381.528828 -232.579926) (xy 381.481838 -232.732326)
			(xy 381.481838 -232.776776) (xy 381.837438 -232.776776)
		)
		(stroke
			(width 0)
			(type solid)
		)
		(fill yes)
		(layer "In6.Cu")
		(net "M_G_CPU0_SB_DQ<13>")
	)
	(gr_poly
		(pts
			(xy 381.840232 -238.83493) (xy 381.840232 -238.790734) (xy 381.484632 -238.790734) (xy 381.484632 -238.83493)
			(xy 381.531622 -238.98733) (xy 381.793242 -238.98733)
		)
		(stroke
			(width 0)
			(type solid)
		)
		(fill yes)
		(layer "In6.Cu")
		(net "M_G_CPU0_SB_DQ<4>")
	)
	(gr_poly
		(pts
			(xy 381.841248 -237.61573) (xy 381.794258 -237.46333) (xy 381.532638 -237.46333) (xy 381.485648 -237.61573)
			(xy 381.485648 -237.66018) (xy 381.841248 -237.66018)
		)
		(stroke
			(width 0)
			(type solid)
		)
		(fill yes)
		(layer "In6.Cu")
		(net "M_G_CPU0_SB_DQ<7>")
	)
	(gr_poly
		(pts
			(xy 381.843534 -249.010678) (xy 381.796544 -248.858278) (xy 381.534924 -248.858278) (xy 381.487934 -249.010678)
			(xy 381.487934 -249.054874) (xy 381.843534 -249.054874)
		)
		(stroke
			(width 0)
			(type solid)
		)
		(fill yes)
		(layer "In6.Cu")
		(net "M_E_CPU0_SB_RSP<0>")
	)
	(gr_poly
		(pts
			(xy 381.843534 -248.601738) (xy 381.843534 -248.557542) (xy 381.487934 -248.557542) (xy 381.487934 -248.601738)
			(xy 381.534924 -248.754138) (xy 381.796544 -248.754138)
		)
		(stroke
			(width 0)
			(type solid)
		)
		(fill yes)
		(layer "In6.Cu")
		(net "M_E_CPU0_SA_RSP<1>")
	)
	(gr_poly
		(pts
			(xy 381.843534 -244.127274) (xy 381.796544 -243.974874) (xy 381.534924 -243.974874) (xy 381.487934 -244.127274)
			(xy 381.487934 -244.17147) (xy 381.843534 -244.17147)
		)
		(stroke
			(width 0)
			(type solid)
		)
		(fill yes)
		(layer "In6.Cu")
		(net "M_H_CPU0_SB_CS_N<3>")
	)
	(gr_poly
		(pts
			(xy 381.843534 -243.718334) (xy 381.843534 -243.674138) (xy 381.487934 -243.674138) (xy 381.487934 -243.718334)
			(xy 381.534924 -243.870734) (xy 381.796544 -243.870734)
		)
		(stroke
			(width 0)
			(type solid)
		)
		(fill yes)
		(layer "In6.Cu")
		(net "M_H_CPU0_SB_CS_N<0>")
	)
	(gr_poly
		(pts
			(xy 381.843534 -242.090702) (xy 381.843534 -242.046252) (xy 381.487934 -242.046252) (xy 381.487934 -242.090702)
			(xy 381.534924 -242.243102) (xy 381.796544 -242.243102)
		)
		(stroke
			(width 0)
			(type solid)
		)
		(fill yes)
		(layer "In6.Cu")
		(net "M_G_CPU0_SB_DQ<0>")
	)
	(gr_poly
		(pts
			(xy 381.843534 -240.871502) (xy 381.796544 -240.719102) (xy 381.534924 -240.719102) (xy 381.487934 -240.871502)
			(xy 381.487934 -240.915952) (xy 381.843534 -240.915952)
		)
		(stroke
			(width 0)
			(type solid)
		)
		(fill yes)
		(layer "In6.Cu")
		(net "M_G_CPU0_SB_DQ<3>")
	)
	(gr_poly
		(pts
			(xy 381.843534 -240.46307) (xy 381.843534 -240.41862) (xy 381.487934 -240.41862) (xy 381.487934 -240.46307)
			(xy 381.534924 -240.61547) (xy 381.796544 -240.61547)
		)
		(stroke
			(width 0)
			(type solid)
		)
		(fill yes)
		(layer "In6.Cu")
		(net "M_G_CPU0_SB_DQS_DP<0>")
	)
	(gr_poly
		(pts
			(xy 381.843534 -239.24387) (xy 381.796544 -239.09147) (xy 381.534924 -239.09147) (xy 381.487934 -239.24387)
			(xy 381.487934 -239.288066) (xy 381.843534 -239.288066)
		)
		(stroke
			(width 0)
			(type solid)
		)
		(fill yes)
		(layer "In6.Cu")
		(net "M_G_CPU0_SB_DQS_DP<5>")
	)
	(gr_poly
		(pts
			(xy 381.843534 -235.988098) (xy 381.796544 -235.835698) (xy 381.534924 -235.835698) (xy 381.487934 -235.988098)
			(xy 381.487934 -236.032548) (xy 381.843534 -236.032548)
		)
		(stroke
			(width 0)
			(type solid)
		)
		(fill yes)
		(layer "In6.Cu")
		(net "M_G_CPU0_SB_DQ<9>")
	)
	(gr_poly
		(pts
			(xy 381.843534 -235.579666) (xy 381.843534 -235.535216) (xy 381.487934 -235.535216) (xy 381.487934 -235.579666)
			(xy 381.534924 -235.732066) (xy 381.796544 -235.732066)
		)
		(stroke
			(width 0)
			(type solid)
		)
		(fill yes)
		(layer "In6.Cu")
		(net "M_G_CPU0_SB_DQS_DN<6>")
	)
	(gr_poly
		(pts
			(xy 381.843534 -234.360466) (xy 381.796544 -234.208066) (xy 381.534924 -234.208066) (xy 381.487934 -234.360466)
			(xy 381.487934 -234.404916) (xy 381.843534 -234.404916)
		)
		(stroke
			(width 0)
			(type solid)
		)
		(fill yes)
		(layer "In6.Cu")
		(net "M_G_CPU0_SB_DQS_DN<1>")
	)
	(gr_poly
		(pts
			(xy 381.843534 -233.952034) (xy 381.843534 -233.907584) (xy 381.487934 -233.907584) (xy 381.487934 -233.952034)
			(xy 381.534924 -234.104434) (xy 381.796544 -234.104434)
		)
		(stroke
			(width 0)
			(type solid)
		)
		(fill yes)
		(layer "In6.Cu")
		(net "M_G_CPU0_SB_DQ<14>")
	)
	(gr_poly
		(pts
			(xy 381.843534 -231.104694) (xy 381.796544 -230.952294) (xy 381.534924 -230.952294) (xy 381.487934 -231.104694)
			(xy 381.487934 -231.149144) (xy 381.843534 -231.149144)
		)
		(stroke
			(width 0)
			(type solid)
		)
		(fill yes)
		(layer "In6.Cu")
		(net "M_H_CPU0_SB_DQ<18>")
	)
	(gr_poly
		(pts
			(xy 381.843534 -230.696262) (xy 381.843534 -230.651812) (xy 381.487934 -230.651812) (xy 381.487934 -230.696262)
			(xy 381.534924 -230.848662) (xy 381.796544 -230.848662)
		)
		(stroke
			(width 0)
			(type solid)
		)
		(fill yes)
		(layer "In6.Cu")
		(net "M_H_CPU0_SB_DQ<17>")
	)
	(gr_poly
		(pts
			(xy 381.843534 -229.477062) (xy 381.796544 -229.324662) (xy 381.534924 -229.324662) (xy 381.487934 -229.477062)
			(xy 381.487934 -229.521512) (xy 381.843534 -229.521512)
		)
		(stroke
			(width 0)
			(type solid)
		)
		(fill yes)
		(layer "In6.Cu")
		(net "M_H_CPU0_SB_DQS_DN<2>")
	)
	(gr_poly
		(pts
			(xy 381.843534 -229.06863) (xy 381.843534 -229.02418) (xy 381.487934 -229.02418) (xy 381.487934 -229.06863)
			(xy 381.534924 -229.22103) (xy 381.796544 -229.22103)
		)
		(stroke
			(width 0)
			(type solid)
		)
		(fill yes)
		(layer "In6.Cu")
		(net "M_H_CPU0_SB_DQS_DN<7>")
	)
	(gr_poly
		(pts
			(xy 381.843534 -227.84943) (xy 381.796544 -227.69703) (xy 381.534924 -227.69703) (xy 381.487934 -227.84943)
			(xy 381.487934 -227.893626) (xy 381.843534 -227.893626)
		)
		(stroke
			(width 0)
			(type solid)
		)
		(fill yes)
		(layer "In6.Cu")
		(net "M_H_CPU0_SB_DQ<22>")
	)
	(gr_poly
		(pts
			(xy 381.843534 -227.44049) (xy 381.843534 -227.396294) (xy 381.487934 -227.396294) (xy 381.487934 -227.44049)
			(xy 381.534924 -227.59289) (xy 381.796544 -227.59289)
		)
		(stroke
			(width 0)
			(type solid)
		)
		(fill yes)
		(layer "In6.Cu")
		(net "M_H_CPU0_SB_DQ<21>")
	)
	(gr_poly
		(pts
			(xy 381.949198 -265.109706) (xy 381.949198 -265.06551) (xy 381.593598 -265.06551) (xy 381.593598 -265.109706)
			(xy 381.640588 -265.262106) (xy 381.902208 -265.262106)
		)
		(stroke
			(width 0)
			(type solid)
		)
		(fill yes)
		(layer "In6.Cu")
		(net "M_G_CPU0_SA_CB<0>")
	)
	(gr_poly
		(pts
			(xy 381.94996 -271.62125) (xy 381.94996 -271.5768) (xy 381.59436 -271.5768) (xy 381.59436 -271.62125)
			(xy 381.64135 -271.77365) (xy 381.90297 -271.77365)
		)
		(stroke
			(width 0)
			(type solid)
		)
		(fill yes)
		(layer "In6.Cu")
		(net "M_G_CPU0_SA_DQ<12>")
	)
	(gr_poly
		(pts
			(xy 381.94996 -266.737846) (xy 381.94996 -266.693396) (xy 381.59436 -266.693396) (xy 381.59436 -266.737846)
			(xy 381.64135 -266.890246) (xy 381.90297 -266.890246)
		)
		(stroke
			(width 0)
			(type solid)
		)
		(fill yes)
		(layer "In6.Cu")
		(net "M_G_CPU0_SA_DQ<28>")
	)
	(gr_poly
		(pts
			(xy 381.94996 -265.518646) (xy 381.90297 -265.366246) (xy 381.64135 -265.366246) (xy 381.59436 -265.518646)
			(xy 381.59436 -265.563096) (xy 381.94996 -265.563096)
		)
		(stroke
			(width 0)
			(type solid)
		)
		(fill yes)
		(layer "In6.Cu")
		(net "M_G_CPU0_SA_DQ<31>")
	)
	(gr_poly
		(pts
			(xy 381.959358 -278.540718) (xy 381.912368 -278.388318) (xy 381.650748 -278.388318) (xy 381.603758 -278.540718)
			(xy 381.603758 -278.585168) (xy 381.959358 -278.585168)
		)
		(stroke
			(width 0)
			(type solid)
		)
		(fill yes)
		(layer "In6.Cu")
		(net "M_H_CPU0_SA_DQ<1>")
	)
	(gr_poly
		(pts
			(xy 381.959358 -278.132032) (xy 381.959358 -278.087836) (xy 381.603758 -278.087836) (xy 381.603758 -278.132032)
			(xy 381.650748 -278.284432) (xy 381.912368 -278.284432)
		)
		(stroke
			(width 0)
			(type solid)
		)
		(fill yes)
		(layer "In6.Cu")
		(net "M_H_CPU0_SA_DQS_DP<0>")
	)
	(gr_poly
		(pts
			(xy 381.959358 -275.284946) (xy 381.912368 -275.132546) (xy 381.650748 -275.132546) (xy 381.603758 -275.284946)
			(xy 381.603758 -275.329142) (xy 381.959358 -275.329142)
		)
		(stroke
			(width 0)
			(type solid)
		)
		(fill yes)
		(layer "In6.Cu")
		(net "M_H_CPU0_SA_DQ<7>")
	)
	(gr_poly
		(pts
			(xy 381.959358 -274.876514) (xy 381.959358 -274.832318) (xy 381.603758 -274.832318) (xy 381.603758 -274.876514)
			(xy 381.650748 -275.028914) (xy 381.912368 -275.028914)
		)
		(stroke
			(width 0)
			(type solid)
		)
		(fill yes)
		(layer "In6.Cu")
		(net "M_G_CPU0_SA_DQ<8>")
	)
	(gr_poly
		(pts
			(xy 381.959358 -270.401542) (xy 381.912368 -270.249142) (xy 381.650748 -270.249142) (xy 381.603758 -270.401542)
			(xy 381.603758 -270.445992) (xy 381.959358 -270.445992)
		)
		(stroke
			(width 0)
			(type solid)
		)
		(fill yes)
		(layer "In6.Cu")
		(net "M_G_CPU0_SA_DQ<15>")
	)
	(gr_poly
		(pts
			(xy 381.959358 -269.993618) (xy 381.959358 -269.949168) (xy 381.603758 -269.949168) (xy 381.603758 -269.993618)
			(xy 381.650748 -270.146018) (xy 381.912368 -270.146018)
		)
		(stroke
			(width 0)
			(type solid)
		)
		(fill yes)
		(layer "In6.Cu")
		(net "M_G_CPU0_SA_DQ<24>")
	)
	(gr_poly
		(pts
			(xy 381.959358 -260.634734) (xy 381.912368 -260.482334) (xy 381.650748 -260.482334) (xy 381.603758 -260.634734)
			(xy 381.603758 -260.679184) (xy 381.959358 -260.679184)
		)
		(stroke
			(width 0)
			(type solid)
		)
		(fill yes)
		(layer "In6.Cu")
		(net "M_G_CPU0_SA_CB<7>")
	)
	(gr_poly
		(pts
			(xy 381.961898 -279.759918) (xy 381.961898 -279.715722) (xy 381.606298 -279.715722) (xy 381.606298 -279.759918)
			(xy 381.653288 -279.912318) (xy 381.914908 -279.912318)
		)
		(stroke
			(width 0)
			(type solid)
		)
		(fill yes)
		(layer "In6.Cu")
		(net "M_H_CPU0_SA_DQ<0>")
	)
	(gr_poly
		(pts
			(xy 381.961898 -276.912578) (xy 381.914908 -276.760178) (xy 381.653288 -276.760178) (xy 381.606298 -276.912578)
			(xy 381.606298 -276.957028) (xy 381.961898 -276.957028)
		)
		(stroke
			(width 0)
			(type solid)
		)
		(fill yes)
		(layer "In6.Cu")
		(net "M_H_CPU0_SA_DQS_DP<5>")
	)
	(gr_poly
		(pts
			(xy 381.961898 -276.5044) (xy 381.961898 -276.460204) (xy 381.606298 -276.460204) (xy 381.606298 -276.5044)
			(xy 381.653288 -276.6568) (xy 381.914908 -276.6568)
		)
		(stroke
			(width 0)
			(type solid)
		)
		(fill yes)
		(layer "In6.Cu")
		(net "M_H_CPU0_SA_DQ<4>")
	)
	(gr_poly
		(pts
			(xy 381.961898 -273.657314) (xy 381.914908 -273.504914) (xy 381.653288 -273.504914) (xy 381.606298 -273.657314)
			(xy 381.606298 -273.70151) (xy 381.961898 -273.70151)
		)
		(stroke
			(width 0)
			(type solid)
		)
		(fill yes)
		(layer "In6.Cu")
		(net "M_G_CPU0_SA_DQ<11>")
	)
	(gr_poly
		(pts
			(xy 381.961898 -273.248882) (xy 381.961898 -273.204686) (xy 381.606298 -273.204686) (xy 381.606298 -273.248882)
			(xy 381.653288 -273.401282) (xy 381.914908 -273.401282)
		)
		(stroke
			(width 0)
			(type solid)
		)
		(fill yes)
		(layer "In6.Cu")
		(net "M_G_CPU0_SA_DQS_DP<1>")
	)
	(gr_poly
		(pts
			(xy 381.961898 -272.029174) (xy 381.914908 -271.876774) (xy 381.653288 -271.876774) (xy 381.606298 -272.029174)
			(xy 381.606298 -272.073624) (xy 381.961898 -272.073624)
		)
		(stroke
			(width 0)
			(type solid)
		)
		(fill yes)
		(layer "In6.Cu")
		(net "M_G_CPU0_SA_DQS_DP<6>")
	)
	(gr_poly
		(pts
			(xy 381.961898 -268.77391) (xy 381.914908 -268.62151) (xy 381.653288 -268.62151) (xy 381.606298 -268.77391)
			(xy 381.606298 -268.818106) (xy 381.961898 -268.818106)
		)
		(stroke
			(width 0)
			(type solid)
		)
		(fill yes)
		(layer "In6.Cu")
		(net "M_G_CPU0_SA_DQ<27>")
	)
	(gr_poly
		(pts
			(xy 381.961898 -268.365478) (xy 381.961898 -268.321282) (xy 381.606298 -268.321282) (xy 381.606298 -268.365478)
			(xy 381.653288 -268.517878) (xy 381.914908 -268.517878)
		)
		(stroke
			(width 0)
			(type solid)
		)
		(fill yes)
		(layer "In6.Cu")
		(net "M_G_CPU0_SA_DQS_DP<3>")
	)
	(gr_poly
		(pts
			(xy 381.961898 -267.146278) (xy 381.914908 -266.993878) (xy 381.653288 -266.993878) (xy 381.606298 -267.146278)
			(xy 381.606298 -267.190474) (xy 381.961898 -267.190474)
		)
		(stroke
			(width 0)
			(type solid)
		)
		(fill yes)
		(layer "In6.Cu")
		(net "M_G_CPU0_SA_DQS_DP<8>")
	)
	(gr_poly
		(pts
			(xy 381.961898 -263.890506) (xy 381.914908 -263.738106) (xy 381.653288 -263.738106) (xy 381.606298 -263.890506)
			(xy 381.606298 -263.934956) (xy 381.961898 -263.934956)
		)
		(stroke
			(width 0)
			(type solid)
		)
		(fill yes)
		(layer "In6.Cu")
		(net "M_G_CPU0_SA_CB<3>")
	)
	(gr_poly
		(pts
			(xy 381.961898 -263.482582) (xy 381.961898 -263.438132) (xy 381.606298 -263.438132) (xy 381.606298 -263.482582)
			(xy 381.653288 -263.634982) (xy 381.914908 -263.634982)
		)
		(stroke
			(width 0)
			(type solid)
		)
		(fill yes)
		(layer "In6.Cu")
		(net "M_G_CPU0_SA_DQS_DP<4>")
	)
	(gr_poly
		(pts
			(xy 381.961898 -262.262874) (xy 381.914908 -262.110474) (xy 381.653288 -262.110474) (xy 381.606298 -262.262874)
			(xy 381.606298 -262.30707) (xy 381.961898 -262.30707)
		)
		(stroke
			(width 0)
			(type solid)
		)
		(fill yes)
		(layer "In6.Cu")
		(net "M_G_CPU0_SA_DQS_DP<9>")
	)
	(gr_poly
		(pts
			(xy 381.961898 -261.854442) (xy 381.961898 -261.810246) (xy 381.606298 -261.810246) (xy 381.606298 -261.854442)
			(xy 381.653288 -262.006842) (xy 381.914908 -262.006842)
		)
		(stroke
			(width 0)
			(type solid)
		)
		(fill yes)
		(layer "In6.Cu")
		(net "M_G_CPU0_SA_CB<4>")
	)
	(gr_poly
		(pts
			(xy 382.307338 -244.53215) (xy 382.307338 -244.487954) (xy 381.951738 -244.487954) (xy 381.951738 -244.53215)
			(xy 381.998728 -244.68455) (xy 382.260348 -244.68455)
		)
		(stroke
			(width 0)
			(type solid)
		)
		(fill yes)
		(layer "In6.Cu")
		(net "M_H_CPU0_SB_CS_N<2>")
	)
	(gr_poly
		(pts
			(xy 382.307338 -243.313458) (xy 382.260348 -243.161058) (xy 381.998728 -243.161058) (xy 381.951738 -243.313458)
			(xy 381.951738 -243.357654) (xy 382.307338 -243.357654)
		)
		(stroke
			(width 0)
			(type solid)
		)
		(fill yes)
		(layer "In6.Cu")
		(net "M_H_CPU0_SB_CS_N<1>")
	)
	(gr_poly
		(pts
			(xy 382.307338 -241.685318) (xy 382.260348 -241.532918) (xy 381.998728 -241.532918) (xy 381.951738 -241.685318)
			(xy 381.951738 -241.729768) (xy 382.307338 -241.729768)
		)
		(stroke
			(width 0)
			(type solid)
		)
		(fill yes)
		(layer "In6.Cu")
		(net "M_G_CPU0_SB_DQ<2>")
	)
	(gr_poly
		(pts
			(xy 382.307338 -241.276886) (xy 382.307338 -241.232436) (xy 381.951738 -241.232436) (xy 381.951738 -241.276886)
			(xy 381.998728 -241.429286) (xy 382.260348 -241.429286)
		)
		(stroke
			(width 0)
			(type solid)
		)
		(fill yes)
		(layer "In6.Cu")
		(net "M_G_CPU0_SB_DQ<1>")
	)
	(gr_poly
		(pts
			(xy 382.307338 -240.057686) (xy 382.260348 -239.905286) (xy 381.998728 -239.905286) (xy 381.951738 -240.057686)
			(xy 381.951738 -240.101882) (xy 382.307338 -240.101882)
		)
		(stroke
			(width 0)
			(type solid)
		)
		(fill yes)
		(layer "In6.Cu")
		(net "M_G_CPU0_SB_DQS_DN<0>")
	)
	(gr_poly
		(pts
			(xy 382.307338 -239.648746) (xy 382.307338 -239.60455) (xy 381.951738 -239.60455) (xy 381.951738 -239.648746)
			(xy 381.998728 -239.801146) (xy 382.260348 -239.801146)
		)
		(stroke
			(width 0)
			(type solid)
		)
		(fill yes)
		(layer "In6.Cu")
		(net "M_G_CPU0_SB_DQS_DN<5>")
	)
	(gr_poly
		(pts
			(xy 382.307338 -228.663246) (xy 382.260348 -228.510846) (xy 381.998728 -228.510846) (xy 381.951738 -228.663246)
			(xy 381.951738 -228.707696) (xy 382.307338 -228.707696)
		)
		(stroke
			(width 0)
			(type solid)
		)
		(fill yes)
		(layer "In6.Cu")
		(net "M_H_CPU0_SB_DQS_DP<7>")
	)
	(gr_poly
		(pts
			(xy 382.307338 -228.254814) (xy 382.307338 -228.210364) (xy 381.951738 -228.210364) (xy 381.951738 -228.254814)
			(xy 381.998728 -228.407214) (xy 382.260348 -228.407214)
		)
		(stroke
			(width 0)
			(type solid)
		)
		(fill yes)
		(layer "In6.Cu")
		(net "M_H_CPU0_SB_DQ<20>")
	)
	(gr_poly
		(pts
			(xy 382.307338 -227.035614) (xy 382.260348 -226.883214) (xy 381.998728 -226.883214) (xy 381.951738 -227.035614)
			(xy 381.951738 -227.07981) (xy 382.307338 -227.07981)
		)
		(stroke
			(width 0)
			(type solid)
		)
		(fill yes)
		(layer "In6.Cu")
		(net "M_H_CPU0_SB_DQ<23>")
	)
	(gr_poly
		(pts
			(xy 382.31318 -238.430054) (xy 382.26619 -238.277654) (xy 382.00457 -238.277654) (xy 381.95758 -238.430054)
			(xy 381.95758 -238.47425) (xy 382.31318 -238.47425)
		)
		(stroke
			(width 0)
			(type solid)
		)
		(fill yes)
		(layer "In6.Cu")
		(net "M_G_CPU0_SB_DQ<6>")
	)
	(gr_poly
		(pts
			(xy 382.31318 -238.021114) (xy 382.31318 -237.976664) (xy 381.95758 -237.976664) (xy 381.95758 -238.021114)
			(xy 382.00457 -238.173514) (xy 382.26619 -238.173514)
		)
		(stroke
			(width 0)
			(type solid)
		)
		(fill yes)
		(layer "In6.Cu")
		(net "M_G_CPU0_SB_DQ<5>")
	)
	(gr_poly
		(pts
			(xy 382.313434 -249.415554) (xy 382.313434 -249.371358) (xy 381.957834 -249.371358) (xy 381.957834 -249.415554)
			(xy 382.004824 -249.567954) (xy 382.266444 -249.567954)
		)
		(stroke
			(width 0)
			(type solid)
		)
		(fill yes)
		(layer "In6.Cu")
		(net "M_E_CPU0_SA_RSP<0>")
	)
	(gr_poly
		(pts
			(xy 382.313434 -248.196354) (xy 382.266444 -248.043954) (xy 382.004824 -248.043954) (xy 381.957834 -248.196354)
			(xy 381.957834 -248.240804) (xy 382.313434 -248.240804)
		)
		(stroke
			(width 0)
			(type solid)
		)
		(fill yes)
		(layer "In6.Cu")
		(net "M_E_CPU0_SB_RSP<1>")
	)
	(gr_poly
		(pts
			(xy 382.313434 -236.801914) (xy 382.266444 -236.649514) (xy 382.004824 -236.649514) (xy 381.957834 -236.801914)
			(xy 381.957834 -236.846364) (xy 382.313434 -236.846364)
		)
		(stroke
			(width 0)
			(type solid)
		)
		(fill yes)
		(layer "In6.Cu")
		(net "M_G_CPU0_SB_DQ<10>")
	)
	(gr_poly
		(pts
			(xy 382.313434 -236.393482) (xy 382.313434 -236.349286) (xy 381.957834 -236.349286) (xy 381.957834 -236.393482)
			(xy 382.004824 -236.545882) (xy 382.266444 -236.545882)
		)
		(stroke
			(width 0)
			(type solid)
		)
		(fill yes)
		(layer "In6.Cu")
		(net "M_G_CPU0_SB_DQ<11>")
	)
	(gr_poly
		(pts
			(xy 382.313434 -235.174282) (xy 382.266444 -235.021882) (xy 382.004824 -235.021882) (xy 381.957834 -235.174282)
			(xy 381.957834 -235.218732) (xy 382.313434 -235.218732)
		)
		(stroke
			(width 0)
			(type solid)
		)
		(fill yes)
		(layer "In6.Cu")
		(net "M_G_CPU0_SB_DQS_DP<6>")
	)
	(gr_poly
		(pts
			(xy 382.313434 -234.76585) (xy 382.313434 -234.7214) (xy 381.957834 -234.7214) (xy 381.957834 -234.76585)
			(xy 382.004824 -234.91825) (xy 382.266444 -234.91825)
		)
		(stroke
			(width 0)
			(type solid)
		)
		(fill yes)
		(layer "In6.Cu")
		(net "M_G_CPU0_SB_DQS_DP<1>")
	)
	(gr_poly
		(pts
			(xy 382.313434 -233.54665) (xy 382.266444 -233.39425) (xy 382.004824 -233.39425) (xy 381.957834 -233.54665)
			(xy 381.957834 -233.590846) (xy 382.313434 -233.590846)
		)
		(stroke
			(width 0)
			(type solid)
		)
		(fill yes)
		(layer "In6.Cu")
		(net "M_G_CPU0_SB_DQ<12>")
	)
	(gr_poly
		(pts
			(xy 382.313434 -233.13771) (xy 382.313434 -233.093514) (xy 381.957834 -233.093514) (xy 381.957834 -233.13771)
			(xy 382.004824 -233.29011) (xy 382.266444 -233.29011)
		)
		(stroke
			(width 0)
			(type solid)
		)
		(fill yes)
		(layer "In6.Cu")
		(net "M_G_CPU0_SB_DQ<15>")
	)
	(gr_poly
		(pts
			(xy 382.313434 -231.510078) (xy 382.313434 -231.465882) (xy 381.957834 -231.465882) (xy 381.957834 -231.510078)
			(xy 382.004824 -231.662478) (xy 382.266444 -231.662478)
		)
		(stroke
			(width 0)
			(type solid)
		)
		(fill yes)
		(layer "In6.Cu")
		(net "M_H_CPU0_SB_DQ<16>")
	)
	(gr_poly
		(pts
			(xy 382.313434 -230.290878) (xy 382.266444 -230.138478) (xy 382.004824 -230.138478) (xy 381.957834 -230.290878)
			(xy 381.957834 -230.335328) (xy 382.313434 -230.335328)
		)
		(stroke
			(width 0)
			(type solid)
		)
		(fill yes)
		(layer "In6.Cu")
		(net "M_H_CPU0_SB_DQ<19>")
	)
	(gr_poly
		(pts
			(xy 382.313434 -229.882446) (xy 382.313434 -229.837996) (xy 381.957834 -229.837996) (xy 381.957834 -229.882446)
			(xy 382.004824 -230.034846) (xy 382.266444 -230.034846)
		)
		(stroke
			(width 0)
			(type solid)
		)
		(fill yes)
		(layer "In6.Cu")
		(net "M_H_CPU0_SB_DQS_DP<2>")
	)
	(gr_poly
		(pts
			(xy 382.41478 -279.354534) (xy 382.36779 -279.202134) (xy 382.10617 -279.202134) (xy 382.05918 -279.354534)
			(xy 382.05918 -279.39873) (xy 382.41478 -279.39873)
		)
		(stroke
			(width 0)
			(type solid)
		)
		(fill yes)
		(layer "In6.Cu")
		(net "M_H_CPU0_SA_DQ<2>")
	)
	(gr_poly
		(pts
			(xy 382.41478 -277.318216) (xy 382.41478 -277.27402) (xy 382.05918 -277.27402) (xy 382.05918 -277.318216)
			(xy 382.10617 -277.470616) (xy 382.36779 -277.470616)
		)
		(stroke
			(width 0)
			(type solid)
		)
		(fill yes)
		(layer "In6.Cu")
		(net "M_H_CPU0_SA_DQS_DN<5>")
	)
	(gr_poly
		(pts
			(xy 382.41478 -276.098762) (xy 382.36779 -275.946362) (xy 382.10617 -275.946362) (xy 382.05918 -276.098762)
			(xy 382.05918 -276.143212) (xy 382.41478 -276.143212)
		)
		(stroke
			(width 0)
			(type solid)
		)
		(fill yes)
		(layer "In6.Cu")
		(net "M_H_CPU0_SA_DQ<6>")
	)
	(gr_poly
		(pts
			(xy 382.41478 -275.690584) (xy 382.41478 -275.646388) (xy 382.05918 -275.646388) (xy 382.05918 -275.690584)
			(xy 382.10617 -275.842984) (xy 382.36779 -275.842984)
		)
		(stroke
			(width 0)
			(type solid)
		)
		(fill yes)
		(layer "In6.Cu")
		(net "M_H_CPU0_SA_DQ<5>")
	)
	(gr_poly
		(pts
			(xy 382.41478 -274.47113) (xy 382.36779 -274.31873) (xy 382.10617 -274.31873) (xy 382.05918 -274.47113)
			(xy 382.05918 -274.515326) (xy 382.41478 -274.515326)
		)
		(stroke
			(width 0)
			(type solid)
		)
		(fill yes)
		(layer "In6.Cu")
		(net "M_G_CPU0_SA_DQ<10>")
	)
	(gr_poly
		(pts
			(xy 382.41478 -274.062698) (xy 382.41478 -274.018502) (xy 382.05918 -274.018502) (xy 382.05918 -274.062698)
			(xy 382.10617 -274.215098) (xy 382.36779 -274.215098)
		)
		(stroke
			(width 0)
			(type solid)
		)
		(fill yes)
		(layer "In6.Cu")
		(net "M_G_CPU0_SA_DQ<9>")
	)
	(gr_poly
		(pts
			(xy 382.41478 -272.843498) (xy 382.36779 -272.691098) (xy 382.10617 -272.691098) (xy 382.05918 -272.843498)
			(xy 382.05918 -272.887694) (xy 382.41478 -272.887694)
		)
		(stroke
			(width 0)
			(type solid)
		)
		(fill yes)
		(layer "In6.Cu")
		(net "M_G_CPU0_SA_DQS_DN<1>")
	)
	(gr_poly
		(pts
			(xy 382.41478 -272.435066) (xy 382.41478 -272.39087) (xy 382.05918 -272.39087) (xy 382.05918 -272.435066)
			(xy 382.10617 -272.587466) (xy 382.36779 -272.587466)
		)
		(stroke
			(width 0)
			(type solid)
		)
		(fill yes)
		(layer "In6.Cu")
		(net "M_G_CPU0_SA_DQS_DN<6>")
	)
	(gr_poly
		(pts
			(xy 382.41478 -270.807434) (xy 382.41478 -270.762984) (xy 382.05918 -270.762984) (xy 382.05918 -270.807434)
			(xy 382.10617 -270.959834) (xy 382.36779 -270.959834)
		)
		(stroke
			(width 0)
			(type solid)
		)
		(fill yes)
		(layer "In6.Cu")
		(net "M_G_CPU0_SA_DQ<13>")
	)
	(gr_poly
		(pts
			(xy 382.41478 -269.587726) (xy 382.36779 -269.435326) (xy 382.10617 -269.435326) (xy 382.05918 -269.587726)
			(xy 382.05918 -269.631922) (xy 382.41478 -269.631922)
		)
		(stroke
			(width 0)
			(type solid)
		)
		(fill yes)
		(layer "In6.Cu")
		(net "M_G_CPU0_SA_DQ<26>")
	)
	(gr_poly
		(pts
			(xy 382.41478 -269.179294) (xy 382.41478 -269.135098) (xy 382.05918 -269.135098) (xy 382.05918 -269.179294)
			(xy 382.10617 -269.331694) (xy 382.36779 -269.331694)
		)
		(stroke
			(width 0)
			(type solid)
		)
		(fill yes)
		(layer "In6.Cu")
		(net "M_G_CPU0_SA_DQ<25>")
	)
	(gr_poly
		(pts
			(xy 382.41478 -267.960094) (xy 382.36779 -267.807694) (xy 382.10617 -267.807694) (xy 382.05918 -267.960094)
			(xy 382.05918 -268.00429) (xy 382.41478 -268.00429)
		)
		(stroke
			(width 0)
			(type solid)
		)
		(fill yes)
		(layer "In6.Cu")
		(net "M_G_CPU0_SA_DQS_DN<3>")
	)
	(gr_poly
		(pts
			(xy 382.41478 -267.551662) (xy 382.41478 -267.507466) (xy 382.05918 -267.507466) (xy 382.05918 -267.551662)
			(xy 382.10617 -267.704062) (xy 382.36779 -267.704062)
		)
		(stroke
			(width 0)
			(type solid)
		)
		(fill yes)
		(layer "In6.Cu")
		(net "M_G_CPU0_SA_DQS_DN<8>")
	)
	(gr_poly
		(pts
			(xy 382.41478 -264.296398) (xy 382.41478 -264.251948) (xy 382.05918 -264.251948) (xy 382.05918 -264.296398)
			(xy 382.10617 -264.448798) (xy 382.36779 -264.448798)
		)
		(stroke
			(width 0)
			(type solid)
		)
		(fill yes)
		(layer "In6.Cu")
		(net "M_G_CPU0_SA_CB<1>")
	)
	(gr_poly
		(pts
			(xy 382.41478 -263.07669) (xy 382.36779 -262.92429) (xy 382.10617 -262.92429) (xy 382.05918 -263.07669)
			(xy 382.05918 -263.120886) (xy 382.41478 -263.120886)
		)
		(stroke
			(width 0)
			(type solid)
		)
		(fill yes)
		(layer "In6.Cu")
		(net "M_G_CPU0_SA_DQS_DN<4>")
	)
	(gr_poly
		(pts
			(xy 382.41478 -262.668258) (xy 382.41478 -262.624062) (xy 382.05918 -262.624062) (xy 382.05918 -262.668258)
			(xy 382.10617 -262.820658) (xy 382.36779 -262.820658)
		)
		(stroke
			(width 0)
			(type solid)
		)
		(fill yes)
		(layer "In6.Cu")
		(net "M_G_CPU0_SA_DQS_DN<9>")
	)
	(gr_poly
		(pts
			(xy 382.41478 -261.449058) (xy 382.36779 -261.296658) (xy 382.10617 -261.296658) (xy 382.05918 -261.449058)
			(xy 382.05918 -261.493254) (xy 382.41478 -261.493254)
		)
		(stroke
			(width 0)
			(type solid)
		)
		(fill yes)
		(layer "In6.Cu")
		(net "M_G_CPU0_SA_CB<6>")
	)
	(gr_poly
		(pts
			(xy 382.41478 -261.040626) (xy 382.41478 -260.99643) (xy 382.05918 -260.99643) (xy 382.05918 -261.040626)
			(xy 382.10617 -261.193026) (xy 382.36779 -261.193026)
		)
		(stroke
			(width 0)
			(type solid)
		)
		(fill yes)
		(layer "In6.Cu")
		(net "M_G_CPU0_SA_CB<5>")
	)
	(gr_poly
		(pts
			(xy 382.423162 -278.945848) (xy 382.423162 -278.901652) (xy 382.067562 -278.901652) (xy 382.067562 -278.945848)
			(xy 382.114552 -279.098248) (xy 382.376172 -279.098248)
		)
		(stroke
			(width 0)
			(type solid)
		)
		(fill yes)
		(layer "In6.Cu")
		(net "M_H_CPU0_SA_DQ<3>")
	)
	(gr_poly
		(pts
			(xy 382.423162 -277.726902) (xy 382.376172 -277.574502) (xy 382.114552 -277.574502) (xy 382.067562 -277.726902)
			(xy 382.067562 -277.771098) (xy 382.423162 -277.771098)
		)
		(stroke
			(width 0)
			(type solid)
		)
		(fill yes)
		(layer "In6.Cu")
		(net "M_H_CPU0_SA_DQS_DN<0>")
	)
	(gr_poly
		(pts
			(xy 382.426718 -271.215866) (xy 382.379728 -271.063466) (xy 382.118108 -271.063466) (xy 382.071118 -271.215866)
			(xy 382.071118 -271.260062) (xy 382.426718 -271.260062)
		)
		(stroke
			(width 0)
			(type solid)
		)
		(fill yes)
		(layer "In6.Cu")
		(net "M_G_CPU0_SA_DQ<14>")
	)
	(gr_poly
		(pts
			(xy 382.426718 -266.332462) (xy 382.379728 -266.180062) (xy 382.118108 -266.180062) (xy 382.071118 -266.332462)
			(xy 382.071118 -266.376658) (xy 382.426718 -266.376658)
		)
		(stroke
			(width 0)
			(type solid)
		)
		(fill yes)
		(layer "In6.Cu")
		(net "M_G_CPU0_SA_DQ<30>")
	)
	(gr_poly
		(pts
			(xy 382.426718 -265.923522) (xy 382.426718 -265.879326) (xy 382.071118 -265.879326) (xy 382.071118 -265.923522)
			(xy 382.118108 -266.075922) (xy 382.379728 -266.075922)
		)
		(stroke
			(width 0)
			(type solid)
		)
		(fill yes)
		(layer "In6.Cu")
		(net "M_G_CPU0_SA_DQ<29>")
	)
	(gr_poly
		(pts
			(xy 382.42748 -264.70483) (xy 382.38049 -264.55243) (xy 382.11887 -264.55243) (xy 382.07188 -264.70483)
			(xy 382.07188 -264.749026) (xy 382.42748 -264.749026)
		)
		(stroke
			(width 0)
			(type solid)
		)
		(fill yes)
		(layer "In6.Cu")
		(net "M_G_CPU0_SA_CB<2>")
	)
	(gr_poly
		(pts
			(xy 382.74879 -256.01041) (xy 382.787144 -255.988312) (xy 382.609344 -255.680464) (xy 382.57099 -255.702562)
			(xy 382.462532 -255.819402) (xy 382.593342 -256.04597)
		)
		(stroke
			(width 0)
			(type solid)
		)
		(fill yes)
		(layer "In6.Cu")
		(net "M_H_CPU0_SB_RSP<0>")
	)
	(gr_poly
		(pts
			(xy 382.783334 -249.010678) (xy 382.736344 -248.858278) (xy 382.474724 -248.858278) (xy 382.427734 -249.010678)
			(xy 382.427734 -249.054874) (xy 382.783334 -249.054874)
		)
		(stroke
			(width 0)
			(type solid)
		)
		(fill yes)
		(layer "In6.Cu")
		(net "M_E_CPU0_SB_RSP<0>")
	)
	(gr_poly
		(pts
			(xy 382.783334 -248.601738) (xy 382.783334 -248.557542) (xy 382.427734 -248.557542) (xy 382.427734 -248.601738)
			(xy 382.474724 -248.754138) (xy 382.736344 -248.754138)
		)
		(stroke
			(width 0)
			(type solid)
		)
		(fill yes)
		(layer "In6.Cu")
		(net "M_E_CPU0_SA_RSP<1>")
	)
	(gr_poly
		(pts
			(xy 382.783334 -238.83493) (xy 382.783334 -238.790734) (xy 382.427734 -238.790734) (xy 382.427734 -238.83493)
			(xy 382.474724 -238.98733) (xy 382.736344 -238.98733)
		)
		(stroke
			(width 0)
			(type solid)
		)
		(fill yes)
		(layer "In6.Cu")
		(net "M_G_CPU0_SB_DQ<4>")
	)
	(gr_poly
		(pts
			(xy 382.783334 -237.61573) (xy 382.736344 -237.46333) (xy 382.474724 -237.46333) (xy 382.427734 -237.61573)
			(xy 382.427734 -237.66018) (xy 382.783334 -237.66018)
		)
		(stroke
			(width 0)
			(type solid)
		)
		(fill yes)
		(layer "In6.Cu")
		(net "M_G_CPU0_SB_DQ<7>")
	)
	(gr_poly
		(pts
			(xy 382.783334 -237.207298) (xy 382.783334 -237.163102) (xy 382.427734 -237.163102) (xy 382.427734 -237.207298)
			(xy 382.474724 -237.359698) (xy 382.736344 -237.359698)
		)
		(stroke
			(width 0)
			(type solid)
		)
		(fill yes)
		(layer "In6.Cu")
		(net "M_G_CPU0_SB_DQ<8>")
	)
	(gr_poly
		(pts
			(xy 382.783334 -235.988098) (xy 382.736344 -235.835698) (xy 382.474724 -235.835698) (xy 382.427734 -235.988098)
			(xy 382.427734 -236.032548) (xy 382.783334 -236.032548)
		)
		(stroke
			(width 0)
			(type solid)
		)
		(fill yes)
		(layer "In6.Cu")
		(net "M_G_CPU0_SB_DQ<9>")
	)
	(gr_poly
		(pts
			(xy 382.783334 -235.579666) (xy 382.783334 -235.535216) (xy 382.427734 -235.535216) (xy 382.427734 -235.579666)
			(xy 382.474724 -235.732066) (xy 382.736344 -235.732066)
		)
		(stroke
			(width 0)
			(type solid)
		)
		(fill yes)
		(layer "In6.Cu")
		(net "M_G_CPU0_SB_DQS_DN<6>")
	)
	(gr_poly
		(pts
			(xy 382.783334 -234.360466) (xy 382.736344 -234.208066) (xy 382.474724 -234.208066) (xy 382.427734 -234.360466)
			(xy 382.427734 -234.404916) (xy 382.783334 -234.404916)
		)
		(stroke
			(width 0)
			(type solid)
		)
		(fill yes)
		(layer "In6.Cu")
		(net "M_G_CPU0_SB_DQS_DN<1>")
	)
	(gr_poly
		(pts
			(xy 382.783334 -233.952034) (xy 382.783334 -233.907584) (xy 382.427734 -233.907584) (xy 382.427734 -233.952034)
			(xy 382.474724 -234.104434) (xy 382.736344 -234.104434)
		)
		(stroke
			(width 0)
			(type solid)
		)
		(fill yes)
		(layer "In6.Cu")
		(net "M_G_CPU0_SB_DQ<14>")
	)
	(gr_poly
		(pts
			(xy 382.783334 -232.732834) (xy 382.736344 -232.580434) (xy 382.474724 -232.580434) (xy 382.427734 -232.732834)
			(xy 382.427734 -232.77703) (xy 382.783334 -232.77703)
		)
		(stroke
			(width 0)
			(type solid)
		)
		(fill yes)
		(layer "In6.Cu")
		(net "M_G_CPU0_SB_DQ<13>")
	)
	(gr_poly
		(pts
			(xy 382.783334 -231.104694) (xy 382.736344 -230.952294) (xy 382.474724 -230.952294) (xy 382.427734 -231.104694)
			(xy 382.427734 -231.149144) (xy 382.783334 -231.149144)
		)
		(stroke
			(width 0)
			(type solid)
		)
		(fill yes)
		(layer "In6.Cu")
		(net "M_H_CPU0_SB_DQ<18>")
	)
	(gr_poly
		(pts
			(xy 382.783334 -230.696262) (xy 382.783334 -230.651812) (xy 382.427734 -230.651812) (xy 382.427734 -230.696262)
			(xy 382.474724 -230.848662) (xy 382.736344 -230.848662)
		)
		(stroke
			(width 0)
			(type solid)
		)
		(fill yes)
		(layer "In6.Cu")
		(net "M_H_CPU0_SB_DQ<17>")
	)
	(gr_poly
		(pts
			(xy 382.783334 -229.477062) (xy 382.736344 -229.324662) (xy 382.474724 -229.324662) (xy 382.427734 -229.477062)
			(xy 382.427734 -229.521512) (xy 382.783334 -229.521512)
		)
		(stroke
			(width 0)
			(type solid)
		)
		(fill yes)
		(layer "In6.Cu")
		(net "M_H_CPU0_SB_DQS_DN<2>")
	)
	(gr_poly
		(pts
			(xy 382.791716 -244.126766) (xy 382.744726 -243.974366) (xy 382.483106 -243.974366) (xy 382.436116 -244.126766)
			(xy 382.436116 -244.171216) (xy 382.791716 -244.171216)
		)
		(stroke
			(width 0)
			(type solid)
		)
		(fill yes)
		(layer "In6.Cu")
		(net "M_H_CPU0_SB_CS_N<3>")
	)
	(gr_poly
		(pts
			(xy 382.791716 -243.718842) (xy 382.791716 -243.674392) (xy 382.436116 -243.674392) (xy 382.436116 -243.718842)
			(xy 382.483106 -243.871242) (xy 382.744726 -243.871242)
		)
		(stroke
			(width 0)
			(type solid)
		)
		(fill yes)
		(layer "In6.Cu")
		(net "M_H_CPU0_SB_CS_N<0>")
	)
	(gr_poly
		(pts
			(xy 382.791716 -242.090702) (xy 382.791716 -242.046506) (xy 382.436116 -242.046506) (xy 382.436116 -242.090702)
			(xy 382.483106 -242.243102) (xy 382.744726 -242.243102)
		)
		(stroke
			(width 0)
			(type solid)
		)
		(fill yes)
		(layer "In6.Cu")
		(net "M_G_CPU0_SB_DQ<0>")
	)
	(gr_poly
		(pts
			(xy 382.791716 -240.871502) (xy 382.744726 -240.719102) (xy 382.483106 -240.719102) (xy 382.436116 -240.871502)
			(xy 382.436116 -240.915698) (xy 382.791716 -240.915698)
		)
		(stroke
			(width 0)
			(type solid)
		)
		(fill yes)
		(layer "In6.Cu")
		(net "M_G_CPU0_SB_DQ<3>")
	)
	(gr_poly
		(pts
			(xy 382.791716 -240.46307) (xy 382.791716 -240.418874) (xy 382.436116 -240.418874) (xy 382.436116 -240.46307)
			(xy 382.483106 -240.61547) (xy 382.744726 -240.61547)
		)
		(stroke
			(width 0)
			(type solid)
		)
		(fill yes)
		(layer "In6.Cu")
		(net "M_G_CPU0_SB_DQS_DP<0>")
	)
	(gr_poly
		(pts
			(xy 382.791716 -239.243362) (xy 382.744726 -239.090962) (xy 382.483106 -239.090962) (xy 382.436116 -239.243362)
			(xy 382.436116 -239.287812) (xy 382.791716 -239.287812)
		)
		(stroke
			(width 0)
			(type solid)
		)
		(fill yes)
		(layer "In6.Cu")
		(net "M_G_CPU0_SB_DQS_DP<5>")
	)
	(gr_poly
		(pts
			(xy 382.791716 -229.06863) (xy 382.791716 -229.024434) (xy 382.436116 -229.024434) (xy 382.436116 -229.06863)
			(xy 382.483106 -229.22103) (xy 382.744726 -229.22103)
		)
		(stroke
			(width 0)
			(type solid)
		)
		(fill yes)
		(layer "In6.Cu")
		(net "M_H_CPU0_SB_DQS_DN<7>")
	)
	(gr_poly
		(pts
			(xy 382.791716 -227.848922) (xy 382.744726 -227.696522) (xy 382.483106 -227.696522) (xy 382.436116 -227.848922)
			(xy 382.436116 -227.893372) (xy 382.791716 -227.893372)
		)
		(stroke
			(width 0)
			(type solid)
		)
		(fill yes)
		(layer "In6.Cu")
		(net "M_H_CPU0_SB_DQ<22>")
	)
	(gr_poly
		(pts
			(xy 382.791716 -227.440998) (xy 382.791716 -227.396548) (xy 382.436116 -227.396548) (xy 382.436116 -227.440998)
			(xy 382.483106 -227.593398) (xy 382.744726 -227.593398)
		)
		(stroke
			(width 0)
			(type solid)
		)
		(fill yes)
		(layer "In6.Cu")
		(net "M_H_CPU0_SB_DQ<21>")
	)
	(gr_poly
		(pts
			(xy 382.858772 -255.39065) (xy 382.96723 -255.27381) (xy 382.83642 -255.047242) (xy 382.680972 -255.082802)
			(xy 382.642618 -255.1049) (xy 382.820418 -255.412748)
		)
		(stroke
			(width 0)
			(type solid)
		)
		(fill yes)
		(layer "In6.Cu")
		(net "M_H_CPU0_SA_RSP<0>")
	)
	(gr_poly
		(pts
			(xy 382.88976 -271.62125) (xy 382.88976 -271.5768) (xy 382.53416 -271.5768) (xy 382.53416 -271.62125)
			(xy 382.58115 -271.77365) (xy 382.84277 -271.77365)
		)
		(stroke
			(width 0)
			(type solid)
		)
		(fill yes)
		(layer "In6.Cu")
		(net "M_G_CPU0_SA_DQ<12>")
	)
	(gr_poly
		(pts
			(xy 382.88976 -266.737846) (xy 382.88976 -266.693396) (xy 382.53416 -266.693396) (xy 382.53416 -266.737846)
			(xy 382.58115 -266.890246) (xy 382.84277 -266.890246)
		)
		(stroke
			(width 0)
			(type solid)
		)
		(fill yes)
		(layer "In6.Cu")
		(net "M_G_CPU0_SA_DQ<28>")
	)
	(gr_poly
		(pts
			(xy 382.88976 -265.518646) (xy 382.84277 -265.366246) (xy 382.58115 -265.366246) (xy 382.53416 -265.518646)
			(xy 382.53416 -265.563096) (xy 382.88976 -265.563096)
		)
		(stroke
			(width 0)
			(type solid)
		)
		(fill yes)
		(layer "In6.Cu")
		(net "M_G_CPU0_SA_DQ<31>")
	)
	(gr_poly
		(pts
			(xy 382.893062 -279.759664) (xy 382.893062 -279.715468) (xy 382.537462 -279.715468) (xy 382.537462 -279.759664)
			(xy 382.584452 -279.912064) (xy 382.846072 -279.912064)
		)
		(stroke
			(width 0)
			(type solid)
		)
		(fill yes)
		(layer "In6.Cu")
		(net "M_H_CPU0_SA_DQ<0>")
	)
	(gr_poly
		(pts
			(xy 382.893062 -278.540718) (xy 382.846072 -278.388318) (xy 382.584452 -278.388318) (xy 382.537462 -278.540718)
			(xy 382.537462 -278.585168) (xy 382.893062 -278.585168)
		)
		(stroke
			(width 0)
			(type solid)
		)
		(fill yes)
		(layer "In6.Cu")
		(net "M_H_CPU0_SA_DQ<1>")
	)
	(gr_poly
		(pts
			(xy 382.893062 -278.132032) (xy 382.893062 -278.087836) (xy 382.537462 -278.087836) (xy 382.537462 -278.132032)
			(xy 382.584452 -278.284432) (xy 382.846072 -278.284432)
		)
		(stroke
			(width 0)
			(type solid)
		)
		(fill yes)
		(layer "In6.Cu")
		(net "M_H_CPU0_SA_DQS_DP<0>")
	)
	(gr_poly
		(pts
			(xy 382.896618 -275.284946) (xy 382.849628 -275.132546) (xy 382.588008 -275.132546) (xy 382.541018 -275.284946)
			(xy 382.541018 -275.329396) (xy 382.896618 -275.329396)
		)
		(stroke
			(width 0)
			(type solid)
		)
		(fill yes)
		(layer "In6.Cu")
		(net "M_H_CPU0_SA_DQ<7>")
	)
	(gr_poly
		(pts
			(xy 382.899158 -263.891014) (xy 382.852168 -263.738614) (xy 382.590548 -263.738614) (xy 382.543558 -263.891014)
			(xy 382.543558 -263.93521) (xy 382.899158 -263.93521)
		)
		(stroke
			(width 0)
			(type solid)
		)
		(fill yes)
		(layer "In6.Cu")
		(net "M_G_CPU0_SA_CB<3>")
	)
	(gr_poly
		(pts
			(xy 382.899158 -263.482074) (xy 382.899158 -263.437878) (xy 382.543558 -263.437878) (xy 382.543558 -263.482074)
			(xy 382.590548 -263.634474) (xy 382.852168 -263.634474)
		)
		(stroke
			(width 0)
			(type solid)
		)
		(fill yes)
		(layer "In6.Cu")
		(net "M_G_CPU0_SA_DQS_DP<4>")
	)
	(gr_poly
		(pts
			(xy 382.899158 -262.262874) (xy 382.852168 -262.110474) (xy 382.590548 -262.110474) (xy 382.543558 -262.262874)
			(xy 382.543558 -262.307324) (xy 382.899158 -262.307324)
		)
		(stroke
			(width 0)
			(type solid)
		)
		(fill yes)
		(layer "In6.Cu")
		(net "M_G_CPU0_SA_DQS_DP<9>")
	)
	(gr_poly
		(pts
			(xy 382.899158 -261.854442) (xy 382.899158 -261.809992) (xy 382.543558 -261.809992) (xy 382.543558 -261.854442)
			(xy 382.590548 -262.006842) (xy 382.852168 -262.006842)
		)
		(stroke
			(width 0)
			(type solid)
		)
		(fill yes)
		(layer "In6.Cu")
		(net "M_G_CPU0_SA_CB<4>")
	)
	(gr_poly
		(pts
			(xy 382.899158 -260.635242) (xy 382.852168 -260.482842) (xy 382.590548 -260.482842) (xy 382.543558 -260.635242)
			(xy 382.543558 -260.679438) (xy 382.899158 -260.679438)
		)
		(stroke
			(width 0)
			(type solid)
		)
		(fill yes)
		(layer "In6.Cu")
		(net "M_G_CPU0_SA_CB<7>")
	)
	(gr_poly
		(pts
			(xy 382.901698 -276.912578) (xy 382.854708 -276.760178) (xy 382.593088 -276.760178) (xy 382.546098 -276.912578)
			(xy 382.546098 -276.957028) (xy 382.901698 -276.957028)
		)
		(stroke
			(width 0)
			(type solid)
		)
		(fill yes)
		(layer "In6.Cu")
		(net "M_H_CPU0_SA_DQS_DP<5>")
	)
	(gr_poly
		(pts
			(xy 382.901698 -276.5044) (xy 382.901698 -276.460204) (xy 382.546098 -276.460204) (xy 382.546098 -276.5044)
			(xy 382.593088 -276.6568) (xy 382.854708 -276.6568)
		)
		(stroke
			(width 0)
			(type solid)
		)
		(fill yes)
		(layer "In6.Cu")
		(net "M_H_CPU0_SA_DQ<4>")
	)
	(gr_poly
		(pts
			(xy 382.901698 -273.657314) (xy 382.854708 -273.504914) (xy 382.593088 -273.504914) (xy 382.546098 -273.657314)
			(xy 382.546098 -273.70151) (xy 382.901698 -273.70151)
		)
		(stroke
			(width 0)
			(type solid)
		)
		(fill yes)
		(layer "In6.Cu")
		(net "M_G_CPU0_SA_DQ<11>")
	)
	(gr_poly
		(pts
			(xy 382.901698 -273.248882) (xy 382.901698 -273.204686) (xy 382.546098 -273.204686) (xy 382.546098 -273.248882)
			(xy 382.593088 -273.401282) (xy 382.854708 -273.401282)
		)
		(stroke
			(width 0)
			(type solid)
		)
		(fill yes)
		(layer "In6.Cu")
		(net "M_G_CPU0_SA_DQS_DP<1>")
	)
	(gr_poly
		(pts
			(xy 382.901698 -272.029174) (xy 382.854708 -271.876774) (xy 382.593088 -271.876774) (xy 382.546098 -272.029174)
			(xy 382.546098 -272.073624) (xy 382.901698 -272.073624)
		)
		(stroke
			(width 0)
			(type solid)
		)
		(fill yes)
		(layer "In6.Cu")
		(net "M_G_CPU0_SA_DQS_DP<6>")
	)
	(gr_poly
		(pts
			(xy 382.901698 -270.401542) (xy 382.854708 -270.249142) (xy 382.593088 -270.249142) (xy 382.546098 -270.401542)
			(xy 382.546098 -270.445992) (xy 382.901698 -270.445992)
		)
		(stroke
			(width 0)
			(type solid)
		)
		(fill yes)
		(layer "In6.Cu")
		(net "M_G_CPU0_SA_DQ<15>")
	)
	(gr_poly
		(pts
			(xy 382.901698 -269.993618) (xy 382.901698 -269.949168) (xy 382.546098 -269.949168) (xy 382.546098 -269.993618)
			(xy 382.593088 -270.146018) (xy 382.854708 -270.146018)
		)
		(stroke
			(width 0)
			(type solid)
		)
		(fill yes)
		(layer "In6.Cu")
		(net "M_G_CPU0_SA_DQ<24>")
	)
	(gr_poly
		(pts
			(xy 382.901698 -268.77391) (xy 382.854708 -268.62151) (xy 382.593088 -268.62151) (xy 382.546098 -268.77391)
			(xy 382.546098 -268.818106) (xy 382.901698 -268.818106)
		)
		(stroke
			(width 0)
			(type solid)
		)
		(fill yes)
		(layer "In6.Cu")
		(net "M_G_CPU0_SA_DQ<27>")
	)
	(gr_poly
		(pts
			(xy 382.901698 -268.365478) (xy 382.901698 -268.321282) (xy 382.546098 -268.321282) (xy 382.546098 -268.365478)
			(xy 382.593088 -268.517878) (xy 382.854708 -268.517878)
		)
		(stroke
			(width 0)
			(type solid)
		)
		(fill yes)
		(layer "In6.Cu")
		(net "M_G_CPU0_SA_DQS_DP<3>")
	)
	(gr_poly
		(pts
			(xy 382.901698 -267.14577) (xy 382.854708 -266.99337) (xy 382.593088 -266.99337) (xy 382.546098 -267.14577)
			(xy 382.546098 -267.19022) (xy 382.901698 -267.19022)
		)
		(stroke
			(width 0)
			(type solid)
		)
		(fill yes)
		(layer "In6.Cu")
		(net "M_G_CPU0_SA_DQS_DP<8>")
	)
	(gr_poly
		(pts
			(xy 382.901698 -265.110214) (xy 382.901698 -265.065764) (xy 382.546098 -265.065764) (xy 382.546098 -265.110214)
			(xy 382.593088 -265.262614) (xy 382.854708 -265.262614)
		)
		(stroke
			(width 0)
			(type solid)
		)
		(fill yes)
		(layer "In6.Cu")
		(net "M_G_CPU0_SA_CB<0>")
	)
	(gr_poly
		(pts
			(xy 382.902714 -274.876514) (xy 382.902714 -274.832318) (xy 382.547114 -274.832318) (xy 382.547114 -274.876514)
			(xy 382.594104 -275.028914) (xy 382.855724 -275.028914)
		)
		(stroke
			(width 0)
			(type solid)
		)
		(fill yes)
		(layer "In6.Cu")
		(net "M_G_CPU0_SA_DQ<8>")
	)
	(gr_poly
		(pts
			(xy 383.220722 -255.200404) (xy 383.259076 -255.178306) (xy 383.081276 -254.870458) (xy 383.042922 -254.892556)
			(xy 382.934464 -255.009396) (xy 383.065274 -255.235964)
		)
		(stroke
			(width 0)
			(type solid)
		)
		(fill yes)
		(layer "In6.Cu")
		(net "M_H_CPU0_SB_RSP<1>")
	)
	(gr_poly
		(pts
			(xy 383.247138 -244.532658) (xy 383.247138 -244.488208) (xy 382.891538 -244.488208) (xy 382.891538 -244.532658)
			(xy 382.938528 -244.685058) (xy 383.200148 -244.685058)
		)
		(stroke
			(width 0)
			(type solid)
		)
		(fill yes)
		(layer "In6.Cu")
		(net "M_H_CPU0_SB_CS_N<2>")
	)
	(gr_poly
		(pts
			(xy 383.247138 -243.31295) (xy 383.200148 -243.16055) (xy 382.938528 -243.16055) (xy 382.891538 -243.31295)
			(xy 382.891538 -243.3574) (xy 383.247138 -243.3574)
		)
		(stroke
			(width 0)
			(type solid)
		)
		(fill yes)
		(layer "In6.Cu")
		(net "M_H_CPU0_SB_CS_N<1>")
	)
	(gr_poly
		(pts
			(xy 383.247138 -241.685318) (xy 383.200148 -241.532918) (xy 382.938528 -241.532918) (xy 382.891538 -241.685318)
			(xy 382.891538 -241.729514) (xy 383.247138 -241.729514)
		)
		(stroke
			(width 0)
			(type solid)
		)
		(fill yes)
		(layer "In6.Cu")
		(net "M_G_CPU0_SB_DQ<2>")
	)
	(gr_poly
		(pts
			(xy 383.247138 -241.276886) (xy 383.247138 -241.23269) (xy 382.891538 -241.23269) (xy 382.891538 -241.276886)
			(xy 382.938528 -241.429286) (xy 383.200148 -241.429286)
		)
		(stroke
			(width 0)
			(type solid)
		)
		(fill yes)
		(layer "In6.Cu")
		(net "M_G_CPU0_SB_DQ<1>")
	)
	(gr_poly
		(pts
			(xy 383.247138 -239.649254) (xy 383.247138 -239.604804) (xy 382.891538 -239.604804) (xy 382.891538 -239.649254)
			(xy 382.938528 -239.801654) (xy 383.200148 -239.801654)
		)
		(stroke
			(width 0)
			(type solid)
		)
		(fill yes)
		(layer "In6.Cu")
		(net "M_G_CPU0_SB_DQS_DN<5>")
	)
	(gr_poly
		(pts
			(xy 383.247138 -236.801914) (xy 383.200148 -236.649514) (xy 382.938528 -236.649514) (xy 382.891538 -236.801914)
			(xy 382.891538 -236.846364) (xy 383.247138 -236.846364)
		)
		(stroke
			(width 0)
			(type solid)
		)
		(fill yes)
		(layer "In6.Cu")
		(net "M_G_CPU0_SB_DQ<10>")
	)
	(gr_poly
		(pts
			(xy 383.247138 -236.393482) (xy 383.247138 -236.349286) (xy 382.891538 -236.349286) (xy 382.891538 -236.393482)
			(xy 382.938528 -236.545882) (xy 383.200148 -236.545882)
		)
		(stroke
			(width 0)
			(type solid)
		)
		(fill yes)
		(layer "In6.Cu")
		(net "M_G_CPU0_SB_DQ<11>")
	)
	(gr_poly
		(pts
			(xy 383.247138 -228.663246) (xy 383.200148 -228.510846) (xy 382.938528 -228.510846) (xy 382.891538 -228.663246)
			(xy 382.891538 -228.707442) (xy 383.247138 -228.707442)
		)
		(stroke
			(width 0)
			(type solid)
		)
		(fill yes)
		(layer "In6.Cu")
		(net "M_H_CPU0_SB_DQS_DP<7>")
	)
	(gr_poly
		(pts
			(xy 383.247138 -228.254814) (xy 383.247138 -228.210618) (xy 382.891538 -228.210618) (xy 382.891538 -228.254814)
			(xy 382.938528 -228.407214) (xy 383.200148 -228.407214)
		)
		(stroke
			(width 0)
			(type solid)
		)
		(fill yes)
		(layer "In6.Cu")
		(net "M_H_CPU0_SB_DQ<20>")
	)
	(gr_poly
		(pts
			(xy 383.247138 -227.035106) (xy 383.200148 -226.882706) (xy 382.938528 -226.882706) (xy 382.891538 -227.035106)
			(xy 382.891538 -227.079556) (xy 383.247138 -227.079556)
		)
		(stroke
			(width 0)
			(type solid)
		)
		(fill yes)
		(layer "In6.Cu")
		(net "M_H_CPU0_SB_DQ<23>")
	)
	(gr_poly
		(pts
			(xy 383.253234 -248.196354) (xy 383.206244 -248.043954) (xy 382.944624 -248.043954) (xy 382.897634 -248.196354)
			(xy 382.897634 -248.240804) (xy 383.253234 -248.240804)
		)
		(stroke
			(width 0)
			(type solid)
		)
		(fill yes)
		(layer "In6.Cu")
		(net "M_E_CPU0_SB_RSP<1>")
	)
	(gr_poly
		(pts
			(xy 383.253234 -240.057686) (xy 383.206244 -239.905286) (xy 382.944624 -239.905286) (xy 382.897634 -240.057686)
			(xy 382.897634 -240.102136) (xy 383.253234 -240.102136)
		)
		(stroke
			(width 0)
			(type solid)
		)
		(fill yes)
		(layer "In6.Cu")
		(net "M_G_CPU0_SB_DQS_DN<0>")
	)
	(gr_poly
		(pts
			(xy 383.253234 -238.430054) (xy 383.206244 -238.277654) (xy 382.944624 -238.277654) (xy 382.897634 -238.430054)
			(xy 382.897634 -238.47425) (xy 383.253234 -238.47425)
		)
		(stroke
			(width 0)
			(type solid)
		)
		(fill yes)
		(layer "In6.Cu")
		(net "M_G_CPU0_SB_DQ<6>")
	)
	(gr_poly
		(pts
			(xy 383.253234 -238.021114) (xy 383.253234 -237.976918) (xy 382.897634 -237.976918) (xy 382.897634 -238.021114)
			(xy 382.944624 -238.173514) (xy 383.206244 -238.173514)
		)
		(stroke
			(width 0)
			(type solid)
		)
		(fill yes)
		(layer "In6.Cu")
		(net "M_G_CPU0_SB_DQ<5>")
	)
	(gr_poly
		(pts
			(xy 383.253234 -235.174282) (xy 383.206244 -235.021882) (xy 382.944624 -235.021882) (xy 382.897634 -235.174282)
			(xy 382.897634 -235.218732) (xy 383.253234 -235.218732)
		)
		(stroke
			(width 0)
			(type solid)
		)
		(fill yes)
		(layer "In6.Cu")
		(net "M_G_CPU0_SB_DQS_DP<6>")
	)
	(gr_poly
		(pts
			(xy 383.253234 -234.76585) (xy 383.253234 -234.7214) (xy 382.897634 -234.7214) (xy 382.897634 -234.76585)
			(xy 382.944624 -234.91825) (xy 383.206244 -234.91825)
		)
		(stroke
			(width 0)
			(type solid)
		)
		(fill yes)
		(layer "In6.Cu")
		(net "M_G_CPU0_SB_DQS_DP<1>")
	)
	(gr_poly
		(pts
			(xy 383.253234 -233.54665) (xy 383.206244 -233.39425) (xy 382.944624 -233.39425) (xy 382.897634 -233.54665)
			(xy 382.897634 -233.590846) (xy 383.253234 -233.590846)
		)
		(stroke
			(width 0)
			(type solid)
		)
		(fill yes)
		(layer "In6.Cu")
		(net "M_G_CPU0_SB_DQ<12>")
	)
	(gr_poly
		(pts
			(xy 383.253234 -233.13771) (xy 383.253234 -233.093514) (xy 382.897634 -233.093514) (xy 382.897634 -233.13771)
			(xy 382.944624 -233.29011) (xy 383.206244 -233.29011)
		)
		(stroke
			(width 0)
			(type solid)
		)
		(fill yes)
		(layer "In6.Cu")
		(net "M_G_CPU0_SB_DQ<15>")
	)
	(gr_poly
		(pts
			(xy 383.253234 -231.510078) (xy 383.253234 -231.465882) (xy 382.897634 -231.465882) (xy 382.897634 -231.510078)
			(xy 382.944624 -231.662478) (xy 383.206244 -231.662478)
		)
		(stroke
			(width 0)
			(type solid)
		)
		(fill yes)
		(layer "In6.Cu")
		(net "M_H_CPU0_SB_DQ<16>")
	)
	(gr_poly
		(pts
			(xy 383.253234 -230.290878) (xy 383.206244 -230.138478) (xy 382.944624 -230.138478) (xy 382.897634 -230.290878)
			(xy 382.897634 -230.335328) (xy 383.253234 -230.335328)
		)
		(stroke
			(width 0)
			(type solid)
		)
		(fill yes)
		(layer "In6.Cu")
		(net "M_H_CPU0_SB_DQ<19>")
	)
	(gr_poly
		(pts
			(xy 383.253234 -229.882446) (xy 383.253234 -229.837996) (xy 382.897634 -229.837996) (xy 382.897634 -229.882446)
			(xy 382.944624 -230.034846) (xy 383.206244 -230.034846)
		)
		(stroke
			(width 0)
			(type solid)
		)
		(fill yes)
		(layer "In6.Cu")
		(net "M_H_CPU0_SB_DQS_DP<2>")
	)
	(gr_poly
		(pts
			(xy 383.35458 -277.318216) (xy 383.35458 -277.27402) (xy 382.99898 -277.27402) (xy 382.99898 -277.318216)
			(xy 383.04597 -277.470616) (xy 383.30759 -277.470616)
		)
		(stroke
			(width 0)
			(type solid)
		)
		(fill yes)
		(layer "In6.Cu")
		(net "M_H_CPU0_SA_DQS_DN<5>")
	)
	(gr_poly
		(pts
			(xy 383.35458 -276.098762) (xy 383.30759 -275.946362) (xy 383.04597 -275.946362) (xy 382.99898 -276.098762)
			(xy 382.99898 -276.143212) (xy 383.35458 -276.143212)
		)
		(stroke
			(width 0)
			(type solid)
		)
		(fill yes)
		(layer "In6.Cu")
		(net "M_H_CPU0_SA_DQ<6>")
	)
	(gr_poly
		(pts
			(xy 383.35458 -275.690584) (xy 383.35458 -275.646388) (xy 382.99898 -275.646388) (xy 382.99898 -275.690584)
			(xy 383.04597 -275.842984) (xy 383.30759 -275.842984)
		)
		(stroke
			(width 0)
			(type solid)
		)
		(fill yes)
		(layer "In6.Cu")
		(net "M_H_CPU0_SA_DQ<5>")
	)
	(gr_poly
		(pts
			(xy 383.35458 -274.47113) (xy 383.30759 -274.31873) (xy 383.04597 -274.31873) (xy 382.99898 -274.47113)
			(xy 382.99898 -274.515326) (xy 383.35458 -274.515326)
		)
		(stroke
			(width 0)
			(type solid)
		)
		(fill yes)
		(layer "In6.Cu")
		(net "M_G_CPU0_SA_DQ<10>")
	)
	(gr_poly
		(pts
			(xy 383.35458 -274.062698) (xy 383.35458 -274.018502) (xy 382.99898 -274.018502) (xy 382.99898 -274.062698)
			(xy 383.04597 -274.215098) (xy 383.30759 -274.215098)
		)
		(stroke
			(width 0)
			(type solid)
		)
		(fill yes)
		(layer "In6.Cu")
		(net "M_G_CPU0_SA_DQ<9>")
	)
	(gr_poly
		(pts
			(xy 383.35458 -272.843498) (xy 383.30759 -272.691098) (xy 383.04597 -272.691098) (xy 382.99898 -272.843498)
			(xy 382.99898 -272.887694) (xy 383.35458 -272.887694)
		)
		(stroke
			(width 0)
			(type solid)
		)
		(fill yes)
		(layer "In6.Cu")
		(net "M_G_CPU0_SA_DQS_DN<1>")
	)
	(gr_poly
		(pts
			(xy 383.35458 -272.435066) (xy 383.35458 -272.39087) (xy 382.99898 -272.39087) (xy 382.99898 -272.435066)
			(xy 383.04597 -272.587466) (xy 383.30759 -272.587466)
		)
		(stroke
			(width 0)
			(type solid)
		)
		(fill yes)
		(layer "In6.Cu")
		(net "M_G_CPU0_SA_DQS_DN<6>")
	)
	(gr_poly
		(pts
			(xy 383.35458 -270.807434) (xy 383.35458 -270.762984) (xy 382.99898 -270.762984) (xy 382.99898 -270.807434)
			(xy 383.04597 -270.959834) (xy 383.30759 -270.959834)
		)
		(stroke
			(width 0)
			(type solid)
		)
		(fill yes)
		(layer "In6.Cu")
		(net "M_G_CPU0_SA_DQ<13>")
	)
	(gr_poly
		(pts
			(xy 383.35458 -269.587726) (xy 383.30759 -269.435326) (xy 383.04597 -269.435326) (xy 382.99898 -269.587726)
			(xy 382.99898 -269.631922) (xy 383.35458 -269.631922)
		)
		(stroke
			(width 0)
			(type solid)
		)
		(fill yes)
		(layer "In6.Cu")
		(net "M_G_CPU0_SA_DQ<26>")
	)
	(gr_poly
		(pts
			(xy 383.35458 -269.179294) (xy 383.35458 -269.135098) (xy 382.99898 -269.135098) (xy 382.99898 -269.179294)
			(xy 383.04597 -269.331694) (xy 383.30759 -269.331694)
		)
		(stroke
			(width 0)
			(type solid)
		)
		(fill yes)
		(layer "In6.Cu")
		(net "M_G_CPU0_SA_DQ<25>")
	)
	(gr_poly
		(pts
			(xy 383.35458 -267.960094) (xy 383.30759 -267.807694) (xy 383.04597 -267.807694) (xy 382.99898 -267.960094)
			(xy 382.99898 -268.00429) (xy 383.35458 -268.00429)
		)
		(stroke
			(width 0)
			(type solid)
		)
		(fill yes)
		(layer "In6.Cu")
		(net "M_G_CPU0_SA_DQS_DN<3>")
	)
	(gr_poly
		(pts
			(xy 383.35458 -267.551662) (xy 383.35458 -267.507466) (xy 382.99898 -267.507466) (xy 382.99898 -267.551662)
			(xy 383.04597 -267.704062) (xy 383.30759 -267.704062)
		)
		(stroke
			(width 0)
			(type solid)
		)
		(fill yes)
		(layer "In6.Cu")
		(net "M_G_CPU0_SA_DQS_DN<8>")
	)
	(gr_poly
		(pts
			(xy 383.35458 -266.331954) (xy 383.30759 -266.179554) (xy 383.04597 -266.179554) (xy 382.99898 -266.331954)
			(xy 382.99898 -266.376404) (xy 383.35458 -266.376404)
		)
		(stroke
			(width 0)
			(type solid)
		)
		(fill yes)
		(layer "In6.Cu")
		(net "M_G_CPU0_SA_DQ<30>")
	)
	(gr_poly
		(pts
			(xy 383.35458 -265.92403) (xy 383.35458 -265.879834) (xy 382.99898 -265.879834) (xy 382.99898 -265.92403)
			(xy 383.04597 -266.07643) (xy 383.30759 -266.07643)
		)
		(stroke
			(width 0)
			(type solid)
		)
		(fill yes)
		(layer "In6.Cu")
		(net "M_G_CPU0_SA_DQ<29>")
	)
	(gr_poly
		(pts
			(xy 383.35458 -264.704322) (xy 383.30759 -264.551922) (xy 383.04597 -264.551922) (xy 382.99898 -264.704322)
			(xy 382.99898 -264.748772) (xy 383.35458 -264.748772)
		)
		(stroke
			(width 0)
			(type solid)
		)
		(fill yes)
		(layer "In6.Cu")
		(net "M_G_CPU0_SA_CB<2>")
	)
	(gr_poly
		(pts
			(xy 383.356866 -277.726902) (xy 383.309876 -277.574502) (xy 383.048256 -277.574502) (xy 383.001266 -277.726902)
			(xy 383.001266 -277.771098) (xy 383.356866 -277.771098)
		)
		(stroke
			(width 0)
			(type solid)
		)
		(fill yes)
		(layer "In6.Cu")
		(net "M_H_CPU0_SA_DQS_DN<0>")
	)
	(gr_poly
		(pts
			(xy 383.362962 -278.945848) (xy 383.362962 -278.901652) (xy 383.007362 -278.901652) (xy 383.007362 -278.945848)
			(xy 383.054352 -279.098248) (xy 383.315972 -279.098248)
		)
		(stroke
			(width 0)
			(type solid)
		)
		(fill yes)
		(layer "In6.Cu")
		(net "M_H_CPU0_SA_DQ<3>")
	)
	(gr_poly
		(pts
			(xy 383.362962 -264.29589) (xy 383.362962 -264.251694) (xy 383.007362 -264.251694) (xy 383.007362 -264.29589)
			(xy 383.054352 -264.44829) (xy 383.315972 -264.44829)
		)
		(stroke
			(width 0)
			(type solid)
		)
		(fill yes)
		(layer "In6.Cu")
		(net "M_G_CPU0_SA_CB<1>")
	)
	(gr_poly
		(pts
			(xy 383.362962 -263.07669) (xy 383.315972 -262.92429) (xy 383.054352 -262.92429) (xy 383.007362 -263.07669)
			(xy 383.007362 -263.12114) (xy 383.362962 -263.12114)
		)
		(stroke
			(width 0)
			(type solid)
		)
		(fill yes)
		(layer "In6.Cu")
		(net "M_G_CPU0_SA_DQS_DN<4>")
	)
	(gr_poly
		(pts
			(xy 383.362962 -262.668258) (xy 383.362962 -262.623808) (xy 383.007362 -262.623808) (xy 383.007362 -262.668258)
			(xy 383.054352 -262.820658) (xy 383.315972 -262.820658)
		)
		(stroke
			(width 0)
			(type solid)
		)
		(fill yes)
		(layer "In6.Cu")
		(net "M_G_CPU0_SA_DQS_DN<9>")
	)
	(gr_poly
		(pts
			(xy 383.362962 -261.449058) (xy 383.315972 -261.296658) (xy 383.054352 -261.296658) (xy 383.007362 -261.449058)
			(xy 383.007362 -261.493508) (xy 383.362962 -261.493508)
		)
		(stroke
			(width 0)
			(type solid)
		)
		(fill yes)
		(layer "In6.Cu")
		(net "M_G_CPU0_SA_CB<6>")
	)
	(gr_poly
		(pts
			(xy 383.362962 -261.040626) (xy 383.362962 -260.996176) (xy 383.007362 -260.996176) (xy 383.007362 -261.040626)
			(xy 383.054352 -261.193026) (xy 383.315972 -261.193026)
		)
		(stroke
			(width 0)
			(type solid)
		)
		(fill yes)
		(layer "In6.Cu")
		(net "M_G_CPU0_SA_CB<5>")
	)
	(gr_poly
		(pts
			(xy 383.362962 -256.157222) (xy 383.362962 -256.112772) (xy 383.007362 -256.112772) (xy 383.007362 -256.157222)
			(xy 383.054352 -256.309622) (xy 383.315972 -256.309622)
		)
		(stroke
			(width 0)
			(type solid)
		)
		(fill yes)
		(layer "In6.Cu")
		(net "M_H_CPU0_SB_RSP<0>")
	)
	(gr_poly
		(pts
			(xy 383.365248 -271.215866) (xy 383.318258 -271.063466) (xy 383.056638 -271.063466) (xy 383.009648 -271.215866)
			(xy 383.009648 -271.260316) (xy 383.365248 -271.260316)
		)
		(stroke
			(width 0)
			(type solid)
		)
		(fill yes)
		(layer "In6.Cu")
		(net "M_G_CPU0_SA_DQ<14>")
	)
	(gr_poly
		(pts
			(xy 383.371344 -279.354534) (xy 383.324354 -279.202134) (xy 383.062734 -279.202134) (xy 383.015744 -279.354534)
			(xy 383.015744 -279.39873) (xy 383.371344 -279.39873)
		)
		(stroke
			(width 0)
			(type solid)
		)
		(fill yes)
		(layer "In6.Cu")
		(net "M_H_CPU0_SA_DQ<2>")
	)
	(gr_poly
		(pts
			(xy 383.723134 -244.127274) (xy 383.676144 -243.974874) (xy 383.414524 -243.974874) (xy 383.367534 -244.127274)
			(xy 383.367534 -244.17147) (xy 383.723134 -244.17147)
		)
		(stroke
			(width 0)
			(type solid)
		)
		(fill yes)
		(layer "In6.Cu")
		(net "M_H_CPU0_SB_CS_N<3>")
	)
	(gr_poly
		(pts
			(xy 383.723134 -243.718334) (xy 383.723134 -243.674138) (xy 383.367534 -243.674138) (xy 383.367534 -243.718334)
			(xy 383.414524 -243.870734) (xy 383.676144 -243.870734)
		)
		(stroke
			(width 0)
			(type solid)
		)
		(fill yes)
		(layer "In6.Cu")
		(net "M_H_CPU0_SB_CS_N<0>")
	)
	(gr_poly
		(pts
			(xy 383.723134 -242.090702) (xy 383.723134 -242.046252) (xy 383.367534 -242.046252) (xy 383.367534 -242.090702)
			(xy 383.414524 -242.243102) (xy 383.676144 -242.243102)
		)
		(stroke
			(width 0)
			(type solid)
		)
		(fill yes)
		(layer "In6.Cu")
		(net "M_G_CPU0_SB_DQ<0>")
	)
	(gr_poly
		(pts
			(xy 383.723134 -240.871502) (xy 383.676144 -240.719102) (xy 383.414524 -240.719102) (xy 383.367534 -240.871502)
			(xy 383.367534 -240.915952) (xy 383.723134 -240.915952)
		)
		(stroke
			(width 0)
			(type solid)
		)
		(fill yes)
		(layer "In6.Cu")
		(net "M_G_CPU0_SB_DQ<3>")
	)
	(gr_poly
		(pts
			(xy 383.723134 -240.46307) (xy 383.723134 -240.41862) (xy 383.367534 -240.41862) (xy 383.367534 -240.46307)
			(xy 383.414524 -240.61547) (xy 383.676144 -240.61547)
		)
		(stroke
			(width 0)
			(type solid)
		)
		(fill yes)
		(layer "In6.Cu")
		(net "M_G_CPU0_SB_DQS_DP<0>")
	)
	(gr_poly
		(pts
			(xy 383.723134 -239.24387) (xy 383.676144 -239.09147) (xy 383.414524 -239.09147) (xy 383.367534 -239.24387)
			(xy 383.367534 -239.288066) (xy 383.723134 -239.288066)
		)
		(stroke
			(width 0)
			(type solid)
		)
		(fill yes)
		(layer "In6.Cu")
		(net "M_G_CPU0_SB_DQS_DP<5>")
	)
	(gr_poly
		(pts
			(xy 383.723134 -238.83493) (xy 383.723134 -238.790734) (xy 383.367534 -238.790734) (xy 383.367534 -238.83493)
			(xy 383.414524 -238.98733) (xy 383.676144 -238.98733)
		)
		(stroke
			(width 0)
			(type solid)
		)
		(fill yes)
		(layer "In6.Cu")
		(net "M_G_CPU0_SB_DQ<4>")
	)
	(gr_poly
		(pts
			(xy 383.723134 -237.61573) (xy 383.676144 -237.46333) (xy 383.414524 -237.46333) (xy 383.367534 -237.61573)
			(xy 383.367534 -237.66018) (xy 383.723134 -237.66018)
		)
		(stroke
			(width 0)
			(type solid)
		)
		(fill yes)
		(layer "In6.Cu")
		(net "M_G_CPU0_SB_DQ<7>")
	)
	(gr_poly
		(pts
			(xy 383.723134 -235.579666) (xy 383.723134 -235.535216) (xy 383.367534 -235.535216) (xy 383.367534 -235.579666)
			(xy 383.414524 -235.732066) (xy 383.676144 -235.732066)
		)
		(stroke
			(width 0)
			(type solid)
		)
		(fill yes)
		(layer "In6.Cu")
		(net "M_G_CPU0_SB_DQS_DN<6>")
	)
	(gr_poly
		(pts
			(xy 383.723134 -234.360466) (xy 383.676144 -234.208066) (xy 383.414524 -234.208066) (xy 383.367534 -234.360466)
			(xy 383.367534 -234.404916) (xy 383.723134 -234.404916)
		)
		(stroke
			(width 0)
			(type solid)
		)
		(fill yes)
		(layer "In6.Cu")
		(net "M_G_CPU0_SB_DQS_DN<1>")
	)
	(gr_poly
		(pts
			(xy 383.723134 -233.952034) (xy 383.723134 -233.907584) (xy 383.367534 -233.907584) (xy 383.367534 -233.952034)
			(xy 383.414524 -234.104434) (xy 383.676144 -234.104434)
		)
		(stroke
			(width 0)
			(type solid)
		)
		(fill yes)
		(layer "In6.Cu")
		(net "M_G_CPU0_SB_DQ<14>")
	)
	(gr_poly
		(pts
			(xy 383.723134 -232.732834) (xy 383.676144 -232.580434) (xy 383.414524 -232.580434) (xy 383.367534 -232.732834)
			(xy 383.367534 -232.77703) (xy 383.723134 -232.77703)
		)
		(stroke
			(width 0)
			(type solid)
		)
		(fill yes)
		(layer "In6.Cu")
		(net "M_G_CPU0_SB_DQ<13>")
	)
	(gr_poly
		(pts
			(xy 383.723134 -231.104694) (xy 383.676144 -230.952294) (xy 383.414524 -230.952294) (xy 383.367534 -231.104694)
			(xy 383.367534 -231.149144) (xy 383.723134 -231.149144)
		)
		(stroke
			(width 0)
			(type solid)
		)
		(fill yes)
		(layer "In6.Cu")
		(net "M_H_CPU0_SB_DQ<18>")
	)
	(gr_poly
		(pts
			(xy 383.723134 -230.696262) (xy 383.723134 -230.651812) (xy 383.367534 -230.651812) (xy 383.367534 -230.696262)
			(xy 383.414524 -230.848662) (xy 383.676144 -230.848662)
		)
		(stroke
			(width 0)
			(type solid)
		)
		(fill yes)
		(layer "In6.Cu")
		(net "M_H_CPU0_SB_DQ<17>")
	)
	(gr_poly
		(pts
			(xy 383.723134 -229.477062) (xy 383.676144 -229.324662) (xy 383.414524 -229.324662) (xy 383.367534 -229.477062)
			(xy 383.367534 -229.521512) (xy 383.723134 -229.521512)
		)
		(stroke
			(width 0)
			(type solid)
		)
		(fill yes)
		(layer "In6.Cu")
		(net "M_H_CPU0_SB_DQS_DN<2>")
	)
	(gr_poly
		(pts
			(xy 383.723134 -229.06863) (xy 383.723134 -229.02418) (xy 383.367534 -229.02418) (xy 383.367534 -229.06863)
			(xy 383.414524 -229.22103) (xy 383.676144 -229.22103)
		)
		(stroke
			(width 0)
			(type solid)
		)
		(fill yes)
		(layer "In6.Cu")
		(net "M_H_CPU0_SB_DQS_DN<7>")
	)
	(gr_poly
		(pts
			(xy 383.723134 -227.84943) (xy 383.676144 -227.69703) (xy 383.414524 -227.69703) (xy 383.367534 -227.84943)
			(xy 383.367534 -227.893626) (xy 383.723134 -227.893626)
		)
		(stroke
			(width 0)
			(type solid)
		)
		(fill yes)
		(layer "In6.Cu")
		(net "M_H_CPU0_SB_DQ<22>")
	)
	(gr_poly
		(pts
			(xy 383.723134 -227.44049) (xy 383.723134 -227.396294) (xy 383.367534 -227.396294) (xy 383.367534 -227.44049)
			(xy 383.414524 -227.59289) (xy 383.676144 -227.59289)
		)
		(stroke
			(width 0)
			(type solid)
		)
		(fill yes)
		(layer "In6.Cu")
		(net "M_H_CPU0_SB_DQ<21>")
	)
	(gr_poly
		(pts
			(xy 383.731516 -237.207806) (xy 383.731516 -237.163356) (xy 383.375916 -237.163356) (xy 383.375916 -237.207806)
			(xy 383.422906 -237.360206) (xy 383.684526 -237.360206)
		)
		(stroke
			(width 0)
			(type solid)
		)
		(fill yes)
		(layer "In6.Cu")
		(net "M_G_CPU0_SB_DQ<8>")
	)
	(gr_poly
		(pts
			(xy 383.731516 -235.988098) (xy 383.684526 -235.835698) (xy 383.422906 -235.835698) (xy 383.375916 -235.988098)
			(xy 383.375916 -236.032294) (xy 383.731516 -236.032294)
		)
		(stroke
			(width 0)
			(type solid)
		)
		(fill yes)
		(layer "In6.Cu")
		(net "M_G_CPU0_SB_DQ<9>")
	)
	(gr_poly
		(pts
			(xy 383.826766 -279.759918) (xy 383.826766 -279.715722) (xy 383.471166 -279.715722) (xy 383.471166 -279.759918)
			(xy 383.518156 -279.912318) (xy 383.779776 -279.912318)
		)
		(stroke
			(width 0)
			(type solid)
		)
		(fill yes)
		(layer "In6.Cu")
		(net "M_H_CPU0_SA_DQ<0>")
	)
	(gr_poly
		(pts
			(xy 383.832608 -262.262874) (xy 383.785618 -262.110474) (xy 383.523998 -262.110474) (xy 383.477008 -262.262874)
			(xy 383.477008 -262.30707) (xy 383.832608 -262.30707)
		)
		(stroke
			(width 0)
			(type solid)
		)
		(fill yes)
		(layer "In6.Cu")
		(net "M_G_CPU0_SA_DQS_DP<9>")
	)
	(gr_poly
		(pts
			(xy 383.832862 -278.540718) (xy 383.785872 -278.388318) (xy 383.524252 -278.388318) (xy 383.477262 -278.540718)
			(xy 383.477262 -278.585168) (xy 383.832862 -278.585168)
		)
		(stroke
			(width 0)
			(type solid)
		)
		(fill yes)
		(layer "In6.Cu")
		(net "M_H_CPU0_SA_DQ<1>")
	)
	(gr_poly
		(pts
			(xy 383.832862 -263.891014) (xy 383.785872 -263.738614) (xy 383.524252 -263.738614) (xy 383.477262 -263.891014)
			(xy 383.477262 -263.93521) (xy 383.832862 -263.93521)
		)
		(stroke
			(width 0)
			(type solid)
		)
		(fill yes)
		(layer "In6.Cu")
		(net "M_G_CPU0_SA_CB<3>")
	)
	(gr_poly
		(pts
			(xy 383.832862 -263.481566) (xy 383.832862 -263.437116) (xy 383.477262 -263.437116) (xy 383.477262 -263.481566)
			(xy 383.524252 -263.633966) (xy 383.785872 -263.633966)
		)
		(stroke
			(width 0)
			(type solid)
		)
		(fill yes)
		(layer "In6.Cu")
		(net "M_G_CPU0_SA_DQS_DP<4>")
	)
	(gr_poly
		(pts
			(xy 383.832862 -261.854442) (xy 383.832862 -261.809992) (xy 383.477262 -261.809992) (xy 383.477262 -261.854442)
			(xy 383.524252 -262.006842) (xy 383.785872 -262.006842)
		)
		(stroke
			(width 0)
			(type solid)
		)
		(fill yes)
		(layer "In6.Cu")
		(net "M_G_CPU0_SA_CB<4>")
	)
	(gr_poly
		(pts
			(xy 383.832862 -260.635242) (xy 383.785872 -260.482842) (xy 383.524252 -260.482842) (xy 383.477262 -260.635242)
			(xy 383.477262 -260.679438) (xy 383.832862 -260.679438)
		)
		(stroke
			(width 0)
			(type solid)
		)
		(fill yes)
		(layer "In6.Cu")
		(net "M_G_CPU0_SA_CB<7>")
	)
	(gr_poly
		(pts
			(xy 383.832862 -255.751838) (xy 383.785872 -255.599438) (xy 383.524252 -255.599438) (xy 383.477262 -255.751838)
			(xy 383.477262 -255.796288) (xy 383.832862 -255.796288)
		)
		(stroke
			(width 0)
			(type solid)
		)
		(fill yes)
		(layer "In6.Cu")
		(net "M_H_CPU0_SA_RSP<0>")
	)
	(gr_poly
		(pts
			(xy 383.832862 -255.343406) (xy 383.832862 -255.298956) (xy 383.477262 -255.298956) (xy 383.477262 -255.343406)
			(xy 383.524252 -255.495806) (xy 383.785872 -255.495806)
		)
		(stroke
			(width 0)
			(type solid)
		)
		(fill yes)
		(layer "In6.Cu")
		(net "M_H_CPU0_SB_RSP<1>")
	)
	(gr_poly
		(pts
			(xy 383.833116 -271.620742) (xy 383.833116 -271.576546) (xy 383.477516 -271.576546) (xy 383.477516 -271.620742)
			(xy 383.524506 -271.773142) (xy 383.786126 -271.773142)
		)
		(stroke
			(width 0)
			(type solid)
		)
		(fill yes)
		(layer "In6.Cu")
		(net "M_G_CPU0_SA_DQ<12>")
	)
	(gr_poly
		(pts
			(xy 383.838958 -276.504146) (xy 383.838958 -276.45995) (xy 383.483358 -276.45995) (xy 383.483358 -276.504146)
			(xy 383.530348 -276.656546) (xy 383.791968 -276.656546)
		)
		(stroke
			(width 0)
			(type solid)
		)
		(fill yes)
		(layer "In6.Cu")
		(net "M_H_CPU0_SA_DQ<4>")
	)
	(gr_poly
		(pts
			(xy 383.838958 -273.657314) (xy 383.791968 -273.504914) (xy 383.530348 -273.504914) (xy 383.483358 -273.657314)
			(xy 383.483358 -273.701764) (xy 383.838958 -273.701764)
		)
		(stroke
			(width 0)
			(type solid)
		)
		(fill yes)
		(layer "In6.Cu")
		(net "M_G_CPU0_SA_DQ<11>")
	)
	(gr_poly
		(pts
			(xy 383.838958 -273.248882) (xy 383.838958 -273.204432) (xy 383.483358 -273.204432) (xy 383.483358 -273.248882)
			(xy 383.530348 -273.401282) (xy 383.791968 -273.401282)
		)
		(stroke
			(width 0)
			(type solid)
		)
		(fill yes)
		(layer "In6.Cu")
		(net "M_G_CPU0_SA_DQS_DP<1>")
	)
	(gr_poly
		(pts
			(xy 383.838958 -268.77391) (xy 383.791968 -268.62151) (xy 383.530348 -268.62151) (xy 383.483358 -268.77391)
			(xy 383.483358 -268.81836) (xy 383.838958 -268.81836)
		)
		(stroke
			(width 0)
			(type solid)
		)
		(fill yes)
		(layer "In6.Cu")
		(net "M_G_CPU0_SA_DQ<27>")
	)
	(gr_poly
		(pts
			(xy 383.838958 -268.365478) (xy 383.838958 -268.321028) (xy 383.483358 -268.321028) (xy 383.483358 -268.365478)
			(xy 383.530348 -268.517878) (xy 383.791968 -268.517878)
		)
		(stroke
			(width 0)
			(type solid)
		)
		(fill yes)
		(layer "In6.Cu")
		(net "M_G_CPU0_SA_DQS_DP<3>")
	)
	(gr_poly
		(pts
			(xy 383.838958 -267.146278) (xy 383.791968 -266.993878) (xy 383.530348 -266.993878) (xy 383.483358 -267.146278)
			(xy 383.483358 -267.190474) (xy 383.838958 -267.190474)
		)
		(stroke
			(width 0)
			(type solid)
		)
		(fill yes)
		(layer "In6.Cu")
		(net "M_G_CPU0_SA_DQS_DP<8>")
	)
	(gr_poly
		(pts
			(xy 383.838958 -266.737846) (xy 383.838958 -266.693396) (xy 383.483358 -266.693396) (xy 383.483358 -266.737846)
			(xy 383.530348 -266.890246) (xy 383.791968 -266.890246)
		)
		(stroke
			(width 0)
			(type solid)
		)
		(fill yes)
		(layer "In6.Cu")
		(net "M_G_CPU0_SA_DQ<28>")
	)
	(gr_poly
		(pts
			(xy 383.841244 -278.132286) (xy 383.841244 -278.08809) (xy 383.485644 -278.08809) (xy 383.485644 -278.132286)
			(xy 383.532634 -278.284686) (xy 383.794254 -278.284686)
		)
		(stroke
			(width 0)
			(type solid)
		)
		(fill yes)
		(layer "In6.Cu")
		(net "M_H_CPU0_SA_DQS_DP<0>")
	)
	(gr_poly
		(pts
			(xy 383.841244 -276.912578) (xy 383.794254 -276.760178) (xy 383.532634 -276.760178) (xy 383.485644 -276.912578)
			(xy 383.485644 -276.957028) (xy 383.841244 -276.957028)
		)
		(stroke
			(width 0)
			(type solid)
		)
		(fill yes)
		(layer "In6.Cu")
		(net "M_H_CPU0_SA_DQS_DP<5>")
	)
	(gr_poly
		(pts
			(xy 383.841498 -275.284946) (xy 383.794508 -275.132546) (xy 383.532888 -275.132546) (xy 383.485898 -275.284946)
			(xy 383.485898 -275.329396) (xy 383.841498 -275.329396)
		)
		(stroke
			(width 0)
			(type solid)
		)
		(fill yes)
		(layer "In6.Cu")
		(net "M_H_CPU0_SA_DQ<7>")
	)
	(gr_poly
		(pts
			(xy 383.841498 -274.876768) (xy 383.841498 -274.832572) (xy 383.485898 -274.832572) (xy 383.485898 -274.876768)
			(xy 383.532888 -275.029168) (xy 383.794508 -275.029168)
		)
		(stroke
			(width 0)
			(type solid)
		)
		(fill yes)
		(layer "In6.Cu")
		(net "M_G_CPU0_SA_DQ<8>")
	)
	(gr_poly
		(pts
			(xy 383.841498 -272.029174) (xy 383.794508 -271.876774) (xy 383.532888 -271.876774) (xy 383.485898 -272.029174)
			(xy 383.485898 -272.073624) (xy 383.841498 -272.073624)
		)
		(stroke
			(width 0)
			(type solid)
		)
		(fill yes)
		(layer "In6.Cu")
		(net "M_G_CPU0_SA_DQS_DP<6>")
	)
	(gr_poly
		(pts
			(xy 383.841498 -270.401542) (xy 383.794508 -270.249142) (xy 383.532888 -270.249142) (xy 383.485898 -270.401542)
			(xy 383.485898 -270.445992) (xy 383.841498 -270.445992)
		)
		(stroke
			(width 0)
			(type solid)
		)
		(fill yes)
		(layer "In6.Cu")
		(net "M_G_CPU0_SA_DQ<15>")
	)
	(gr_poly
		(pts
			(xy 383.841498 -269.993618) (xy 383.841498 -269.949168) (xy 383.485898 -269.949168) (xy 383.485898 -269.993618)
			(xy 383.532888 -270.146018) (xy 383.794508 -270.146018)
		)
		(stroke
			(width 0)
			(type solid)
		)
		(fill yes)
		(layer "In6.Cu")
		(net "M_G_CPU0_SA_DQ<24>")
	)
	(gr_poly
		(pts
			(xy 383.841498 -265.518138) (xy 383.794508 -265.365738) (xy 383.532888 -265.365738) (xy 383.485898 -265.518138)
			(xy 383.485898 -265.562588) (xy 383.841498 -265.562588)
		)
		(stroke
			(width 0)
			(type solid)
		)
		(fill yes)
		(layer "In6.Cu")
		(net "M_G_CPU0_SA_DQ<31>")
	)
	(gr_poly
		(pts
			(xy 383.841498 -265.110214) (xy 383.841498 -265.065764) (xy 383.485898 -265.065764) (xy 383.485898 -265.110214)
			(xy 383.532888 -265.262614) (xy 383.794508 -265.262614)
		)
		(stroke
			(width 0)
			(type solid)
		)
		(fill yes)
		(layer "In6.Cu")
		(net "M_G_CPU0_SA_CB<0>")
	)
	(gr_poly
		(pts
			(xy 384.184398 -236.801914) (xy 384.137408 -236.649514) (xy 383.875788 -236.649514) (xy 383.828798 -236.801914)
			(xy 383.828798 -236.84611) (xy 384.184398 -236.84611)
		)
		(stroke
			(width 0)
			(type solid)
		)
		(fill yes)
		(layer "In6.Cu")
		(net "M_G_CPU0_SB_DQ<10>")
	)
	(gr_poly
		(pts
			(xy 384.184398 -236.39399) (xy 384.184398 -236.34954) (xy 383.828798 -236.34954) (xy 383.828798 -236.39399)
			(xy 383.875788 -236.54639) (xy 384.137408 -236.54639)
		)
		(stroke
			(width 0)
			(type solid)
		)
		(fill yes)
		(layer "In6.Cu")
		(net "M_G_CPU0_SB_DQ<11>")
	)
	(gr_poly
		(pts
			(xy 384.186938 -244.53215) (xy 384.186938 -244.487954) (xy 383.831338 -244.487954) (xy 383.831338 -244.53215)
			(xy 383.878328 -244.68455) (xy 384.139948 -244.68455)
		)
		(stroke
			(width 0)
			(type solid)
		)
		(fill yes)
		(layer "In6.Cu")
		(net "M_H_CPU0_SB_CS_N<2>")
	)
	(gr_poly
		(pts
			(xy 384.186938 -235.174282) (xy 384.139948 -235.021882) (xy 383.878328 -235.021882) (xy 383.831338 -235.174282)
			(xy 383.831338 -235.218732) (xy 384.186938 -235.218732)
		)
		(stroke
			(width 0)
			(type solid)
		)
		(fill yes)
		(layer "In6.Cu")
		(net "M_G_CPU0_SB_DQS_DP<6>")
	)
	(gr_poly
		(pts
			(xy 384.186938 -234.76585) (xy 384.186938 -234.7214) (xy 383.831338 -234.7214) (xy 383.831338 -234.76585)
			(xy 383.878328 -234.91825) (xy 384.139948 -234.91825)
		)
		(stroke
			(width 0)
			(type solid)
		)
		(fill yes)
		(layer "In6.Cu")
		(net "M_G_CPU0_SB_DQS_DP<1>")
	)
	(gr_poly
		(pts
			(xy 384.189732 -240.057686) (xy 384.142742 -239.905286) (xy 383.881122 -239.905286) (xy 383.834132 -240.057686)
			(xy 383.834132 -240.101882) (xy 384.189732 -240.101882)
		)
		(stroke
			(width 0)
			(type solid)
		)
		(fill yes)
		(layer "In6.Cu")
		(net "M_G_CPU0_SB_DQS_DN<0>")
	)
	(gr_poly
		(pts
			(xy 384.19278 -228.663246) (xy 384.14579 -228.510846) (xy 383.88417 -228.510846) (xy 383.83718 -228.663246)
			(xy 383.83718 -228.707442) (xy 384.19278 -228.707442)
		)
		(stroke
			(width 0)
			(type solid)
		)
		(fill yes)
		(layer "In6.Cu")
		(net "M_H_CPU0_SB_DQS_DP<7>")
	)
	(gr_poly
		(pts
			(xy 384.193034 -243.313458) (xy 384.146044 -243.161058) (xy 383.884424 -243.161058) (xy 383.837434 -243.313458)
			(xy 383.837434 -243.357654) (xy 384.193034 -243.357654)
		)
		(stroke
			(width 0)
			(type solid)
		)
		(fill yes)
		(layer "In6.Cu")
		(net "M_H_CPU0_SB_CS_N<1>")
	)
	(gr_poly
		(pts
			(xy 384.193034 -241.685318) (xy 384.146044 -241.532918) (xy 383.884424 -241.532918) (xy 383.837434 -241.685318)
			(xy 383.837434 -241.729768) (xy 384.193034 -241.729768)
		)
		(stroke
			(width 0)
			(type solid)
		)
		(fill yes)
		(layer "In6.Cu")
		(net "M_G_CPU0_SB_DQ<2>")
	)
	(gr_poly
		(pts
			(xy 384.193034 -241.276886) (xy 384.193034 -241.232436) (xy 383.837434 -241.232436) (xy 383.837434 -241.276886)
			(xy 383.884424 -241.429286) (xy 384.146044 -241.429286)
		)
		(stroke
			(width 0)
			(type solid)
		)
		(fill yes)
		(layer "In6.Cu")
		(net "M_G_CPU0_SB_DQ<1>")
	)
	(gr_poly
		(pts
			(xy 384.193034 -239.648746) (xy 384.193034 -239.604296) (xy 383.837434 -239.604296) (xy 383.837434 -239.648746)
			(xy 383.884424 -239.801146) (xy 384.146044 -239.801146)
		)
		(stroke
			(width 0)
			(type solid)
		)
		(fill yes)
		(layer "In6.Cu")
		(net "M_G_CPU0_SB_DQS_DN<5>")
	)
	(gr_poly
		(pts
			(xy 384.193034 -238.430054) (xy 384.146044 -238.277654) (xy 383.884424 -238.277654) (xy 383.837434 -238.430054)
			(xy 383.837434 -238.47425) (xy 384.193034 -238.47425)
		)
		(stroke
			(width 0)
			(type solid)
		)
		(fill yes)
		(layer "In6.Cu")
		(net "M_G_CPU0_SB_DQ<6>")
	)
	(gr_poly
		(pts
			(xy 384.193034 -238.021114) (xy 384.193034 -237.976918) (xy 383.837434 -237.976918) (xy 383.837434 -238.021114)
			(xy 383.884424 -238.173514) (xy 384.146044 -238.173514)
		)
		(stroke
			(width 0)
			(type solid)
		)
		(fill yes)
		(layer "In6.Cu")
		(net "M_G_CPU0_SB_DQ<5>")
	)
	(gr_poly
		(pts
			(xy 384.193034 -233.54665) (xy 384.146044 -233.39425) (xy 383.884424 -233.39425) (xy 383.837434 -233.54665)
			(xy 383.837434 -233.590846) (xy 384.193034 -233.590846)
		)
		(stroke
			(width 0)
			(type solid)
		)
		(fill yes)
		(layer "In6.Cu")
		(net "M_G_CPU0_SB_DQ<12>")
	)
	(gr_poly
		(pts
			(xy 384.193034 -233.13771) (xy 384.193034 -233.093514) (xy 383.837434 -233.093514) (xy 383.837434 -233.13771)
			(xy 383.884424 -233.29011) (xy 384.146044 -233.29011)
		)
		(stroke
			(width 0)
			(type solid)
		)
		(fill yes)
		(layer "In6.Cu")
		(net "M_G_CPU0_SB_DQ<15>")
	)
	(gr_poly
		(pts
			(xy 384.193034 -231.510078) (xy 384.193034 -231.465882) (xy 383.837434 -231.465882) (xy 383.837434 -231.510078)
			(xy 383.884424 -231.662478) (xy 384.146044 -231.662478)
		)
		(stroke
			(width 0)
			(type solid)
		)
		(fill yes)
		(layer "In6.Cu")
		(net "M_H_CPU0_SB_DQ<16>")
	)
	(gr_poly
		(pts
			(xy 384.193034 -230.290878) (xy 384.146044 -230.138478) (xy 383.884424 -230.138478) (xy 383.837434 -230.290878)
			(xy 383.837434 -230.335328) (xy 384.193034 -230.335328)
		)
		(stroke
			(width 0)
			(type solid)
		)
		(fill yes)
		(layer "In6.Cu")
		(net "M_H_CPU0_SB_DQ<19>")
	)
	(gr_poly
		(pts
			(xy 384.193034 -229.882446) (xy 384.193034 -229.837996) (xy 383.837434 -229.837996) (xy 383.837434 -229.882446)
			(xy 383.884424 -230.034846) (xy 384.146044 -230.034846)
		)
		(stroke
			(width 0)
			(type solid)
		)
		(fill yes)
		(layer "In6.Cu")
		(net "M_H_CPU0_SB_DQS_DP<2>")
	)
	(gr_poly
		(pts
			(xy 384.193034 -228.254814) (xy 384.193034 -228.210364) (xy 383.837434 -228.210364) (xy 383.837434 -228.254814)
			(xy 383.884424 -228.407214) (xy 384.146044 -228.407214)
		)
		(stroke
			(width 0)
			(type solid)
		)
		(fill yes)
		(layer "In6.Cu")
		(net "M_H_CPU0_SB_DQ<20>")
	)
	(gr_poly
		(pts
			(xy 384.193034 -227.035614) (xy 384.146044 -226.883214) (xy 383.884424 -226.883214) (xy 383.837434 -227.035614)
			(xy 383.837434 -227.07981) (xy 384.193034 -227.07981)
		)
		(stroke
			(width 0)
			(type solid)
		)
		(fill yes)
		(layer "In6.Cu")
		(net "M_H_CPU0_SB_DQ<23>")
	)
	(gr_poly
		(pts
			(xy 384.29438 -275.690584) (xy 384.29438 -275.646388) (xy 383.93878 -275.646388) (xy 383.93878 -275.690584)
			(xy 383.98577 -275.842984) (xy 384.24739 -275.842984)
		)
		(stroke
			(width 0)
			(type solid)
		)
		(fill yes)
		(layer "In6.Cu")
		(net "M_H_CPU0_SA_DQ<5>")
	)
	(gr_poly
		(pts
			(xy 384.29438 -274.47113) (xy 384.24739 -274.31873) (xy 383.98577 -274.31873) (xy 383.93878 -274.47113)
			(xy 383.93878 -274.515326) (xy 384.29438 -274.515326)
		)
		(stroke
			(width 0)
			(type solid)
		)
		(fill yes)
		(layer "In6.Cu")
		(net "M_G_CPU0_SA_DQ<10>")
	)
	(gr_poly
		(pts
			(xy 384.29438 -272.435066) (xy 384.29438 -272.39087) (xy 383.93878 -272.39087) (xy 383.93878 -272.435066)
			(xy 383.98577 -272.587466) (xy 384.24739 -272.587466)
		)
		(stroke
			(width 0)
			(type solid)
		)
		(fill yes)
		(layer "In6.Cu")
		(net "M_G_CPU0_SA_DQS_DN<6>")
	)
	(gr_poly
		(pts
			(xy 384.29438 -271.215358) (xy 384.24739 -271.062958) (xy 383.98577 -271.062958) (xy 383.93878 -271.215358)
			(xy 383.93878 -271.259808) (xy 384.29438 -271.259808)
		)
		(stroke
			(width 0)
			(type solid)
		)
		(fill yes)
		(layer "In6.Cu")
		(net "M_G_CPU0_SA_DQ<14>")
	)
	(gr_poly
		(pts
			(xy 384.29438 -270.807434) (xy 384.29438 -270.762984) (xy 383.93878 -270.762984) (xy 383.93878 -270.807434)
			(xy 383.98577 -270.959834) (xy 384.24739 -270.959834)
		)
		(stroke
			(width 0)
			(type solid)
		)
		(fill yes)
		(layer "In6.Cu")
		(net "M_G_CPU0_SA_DQ<13>")
	)
	(gr_poly
		(pts
			(xy 384.29438 -269.587726) (xy 384.24739 -269.435326) (xy 383.98577 -269.435326) (xy 383.93878 -269.587726)
			(xy 383.93878 -269.631922) (xy 384.29438 -269.631922)
		)
		(stroke
			(width 0)
			(type solid)
		)
		(fill yes)
		(layer "In6.Cu")
		(net "M_G_CPU0_SA_DQ<26>")
	)
	(gr_poly
		(pts
			(xy 384.29438 -265.92403) (xy 384.29438 -265.879834) (xy 383.93878 -265.879834) (xy 383.93878 -265.92403)
			(xy 383.98577 -266.07643) (xy 384.24739 -266.07643)
		)
		(stroke
			(width 0)
			(type solid)
		)
		(fill yes)
		(layer "In6.Cu")
		(net "M_G_CPU0_SA_DQ<29>")
	)
	(gr_poly
		(pts
			(xy 384.29438 -264.704322) (xy 384.24739 -264.551922) (xy 383.98577 -264.551922) (xy 383.93878 -264.704322)
			(xy 383.93878 -264.748772) (xy 384.29438 -264.748772)
		)
		(stroke
			(width 0)
			(type solid)
		)
		(fill yes)
		(layer "In6.Cu")
		(net "M_G_CPU0_SA_CB<2>")
	)
	(gr_poly
		(pts
			(xy 384.296666 -277.726394) (xy 384.249676 -277.573994) (xy 383.988056 -277.573994) (xy 383.941066 -277.726394)
			(xy 383.941066 -277.770844) (xy 384.296666 -277.770844)
		)
		(stroke
			(width 0)
			(type solid)
		)
		(fill yes)
		(layer "In6.Cu")
		(net "M_H_CPU0_SA_DQS_DN<0>")
	)
	(gr_poly
		(pts
			(xy 384.296666 -277.318216) (xy 384.296666 -277.27402) (xy 383.941066 -277.27402) (xy 383.941066 -277.318216)
			(xy 383.988056 -277.470616) (xy 384.249676 -277.470616)
		)
		(stroke
			(width 0)
			(type solid)
		)
		(fill yes)
		(layer "In6.Cu")
		(net "M_H_CPU0_SA_DQS_DN<5>")
	)
	(gr_poly
		(pts
			(xy 384.302762 -279.354788) (xy 384.255772 -279.202388) (xy 383.994152 -279.202388) (xy 383.947162 -279.354788)
			(xy 383.947162 -279.398984) (xy 384.302762 -279.398984)
		)
		(stroke
			(width 0)
			(type solid)
		)
		(fill yes)
		(layer "In6.Cu")
		(net "M_H_CPU0_SA_DQ<2>")
	)
	(gr_poly
		(pts
			(xy 384.302762 -278.945848) (xy 384.302762 -278.901652) (xy 383.947162 -278.901652) (xy 383.947162 -278.945848)
			(xy 383.994152 -279.098248) (xy 384.255772 -279.098248)
		)
		(stroke
			(width 0)
			(type solid)
		)
		(fill yes)
		(layer "In6.Cu")
		(net "M_H_CPU0_SA_DQ<3>")
	)
	(gr_poly
		(pts
			(xy 384.302762 -276.09927) (xy 384.255772 -275.94687) (xy 383.994152 -275.94687) (xy 383.947162 -276.09927)
			(xy 383.947162 -276.143466) (xy 384.302762 -276.143466)
		)
		(stroke
			(width 0)
			(type solid)
		)
		(fill yes)
		(layer "In6.Cu")
		(net "M_H_CPU0_SA_DQ<6>")
	)
	(gr_poly
		(pts
			(xy 384.302762 -274.062698) (xy 384.302762 -274.018248) (xy 383.947162 -274.018248) (xy 383.947162 -274.062698)
			(xy 383.994152 -274.215098) (xy 384.255772 -274.215098)
		)
		(stroke
			(width 0)
			(type solid)
		)
		(fill yes)
		(layer "In6.Cu")
		(net "M_G_CPU0_SA_DQ<9>")
	)
	(gr_poly
		(pts
			(xy 384.302762 -272.843498) (xy 384.255772 -272.691098) (xy 383.994152 -272.691098) (xy 383.947162 -272.843498)
			(xy 383.947162 -272.887948) (xy 384.302762 -272.887948)
		)
		(stroke
			(width 0)
			(type solid)
		)
		(fill yes)
		(layer "In6.Cu")
		(net "M_G_CPU0_SA_DQS_DN<1>")
	)
	(gr_poly
		(pts
			(xy 384.302762 -269.179294) (xy 384.302762 -269.134844) (xy 383.947162 -269.134844) (xy 383.947162 -269.179294)
			(xy 383.994152 -269.331694) (xy 384.255772 -269.331694)
		)
		(stroke
			(width 0)
			(type solid)
		)
		(fill yes)
		(layer "In6.Cu")
		(net "M_G_CPU0_SA_DQ<25>")
	)
	(gr_poly
		(pts
			(xy 384.302762 -267.960094) (xy 384.255772 -267.807694) (xy 383.994152 -267.807694) (xy 383.947162 -267.960094)
			(xy 383.947162 -268.004544) (xy 384.302762 -268.004544)
		)
		(stroke
			(width 0)
			(type solid)
		)
		(fill yes)
		(layer "In6.Cu")
		(net "M_G_CPU0_SA_DQS_DN<3>")
	)
	(gr_poly
		(pts
			(xy 384.302762 -267.551662) (xy 384.302762 -267.507212) (xy 383.947162 -267.507212) (xy 383.947162 -267.551662)
			(xy 383.994152 -267.704062) (xy 384.255772 -267.704062)
		)
		(stroke
			(width 0)
			(type solid)
		)
		(fill yes)
		(layer "In6.Cu")
		(net "M_G_CPU0_SA_DQS_DN<8>")
	)
	(gr_poly
		(pts
			(xy 384.302762 -266.332462) (xy 384.255772 -266.180062) (xy 383.994152 -266.180062) (xy 383.947162 -266.332462)
			(xy 383.947162 -266.376658) (xy 384.302762 -266.376658)
		)
		(stroke
			(width 0)
			(type solid)
		)
		(fill yes)
		(layer "In6.Cu")
		(net "M_G_CPU0_SA_DQ<30>")
	)
	(gr_poly
		(pts
			(xy 384.302762 -264.29589) (xy 384.302762 -264.251694) (xy 383.947162 -264.251694) (xy 383.947162 -264.29589)
			(xy 383.994152 -264.44829) (xy 384.255772 -264.44829)
		)
		(stroke
			(width 0)
			(type solid)
		)
		(fill yes)
		(layer "In6.Cu")
		(net "M_G_CPU0_SA_CB<1>")
	)
	(gr_poly
		(pts
			(xy 384.302762 -263.07669) (xy 384.255772 -262.92429) (xy 383.994152 -262.92429) (xy 383.947162 -263.07669)
			(xy 383.947162 -263.12114) (xy 384.302762 -263.12114)
		)
		(stroke
			(width 0)
			(type solid)
		)
		(fill yes)
		(layer "In6.Cu")
		(net "M_G_CPU0_SA_DQS_DN<4>")
	)
	(gr_poly
		(pts
			(xy 384.302762 -262.668258) (xy 384.302762 -262.623808) (xy 383.947162 -262.623808) (xy 383.947162 -262.668258)
			(xy 383.994152 -262.820658) (xy 384.255772 -262.820658)
		)
		(stroke
			(width 0)
			(type solid)
		)
		(fill yes)
		(layer "In6.Cu")
		(net "M_G_CPU0_SA_DQS_DN<9>")
	)
	(gr_poly
		(pts
			(xy 384.302762 -261.449058) (xy 384.255772 -261.296658) (xy 383.994152 -261.296658) (xy 383.947162 -261.449058)
			(xy 383.947162 -261.493508) (xy 384.302762 -261.493508)
		)
		(stroke
			(width 0)
			(type solid)
		)
		(fill yes)
		(layer "In6.Cu")
		(net "M_G_CPU0_SA_CB<6>")
	)
	(gr_poly
		(pts
			(xy 384.302762 -261.040626) (xy 384.302762 -260.996176) (xy 383.947162 -260.996176) (xy 383.947162 -261.040626)
			(xy 383.994152 -261.193026) (xy 384.255772 -261.193026)
		)
		(stroke
			(width 0)
			(type solid)
		)
		(fill yes)
		(layer "In6.Cu")
		(net "M_G_CPU0_SA_CB<5>")
	)
	(gr_poly
		(pts
			(xy 384.302762 -256.157222) (xy 384.302762 -256.112772) (xy 383.947162 -256.112772) (xy 383.947162 -256.157222)
			(xy 383.994152 -256.309622) (xy 384.255772 -256.309622)
		)
		(stroke
			(width 0)
			(type solid)
		)
		(fill yes)
		(layer "In6.Cu")
		(net "M_H_CPU0_SB_RSP<0>")
	)
	(gr_poly
		(pts
			(xy 384.302762 -254.938022) (xy 384.255772 -254.785622) (xy 383.994152 -254.785622) (xy 383.947162 -254.938022)
			(xy 383.947162 -254.982218) (xy 384.302762 -254.982218)
		)
		(stroke
			(width 0)
			(type solid)
		)
		(fill yes)
		(layer "In6.Cu")
		(net "M_H_CPU0_SA_RSP<1>")
	)
	(gr_poly
		(pts
			(xy 384.557016 -232.087674) (xy 384.518662 -232.065576) (xy 384.363214 -232.030016) (xy 384.232404 -232.256584)
			(xy 384.340862 -232.373424) (xy 384.379216 -232.395522)
		)
		(stroke
			(width 0)
			(type solid)
		)
		(fill yes)
		(layer "In6.Cu")
		(net "M_G_CPU0_SB_DQ<13>")
	)
	(gr_poly
		(pts
			(xy 384.630422 -280.430986) (xy 384.668776 -280.408888) (xy 384.490976 -280.10104) (xy 384.452622 -280.123138)
			(xy 384.344164 -280.239978) (xy 384.474974 -280.466546)
		)
		(stroke
			(width 0)
			(type solid)
		)
		(fill yes)
		(layer "In6.Cu")
		(net "M_H_CPU0_SA_DQ<0>")
	)
	(gr_poly
		(pts
			(xy 384.662934 -243.718334) (xy 384.662934 -243.674138) (xy 384.307334 -243.674138) (xy 384.307334 -243.718334)
			(xy 384.354324 -243.870734) (xy 384.615944 -243.870734)
		)
		(stroke
			(width 0)
			(type solid)
		)
		(fill yes)
		(layer "In6.Cu")
		(net "M_H_CPU0_SB_CS_N<0>")
	)
	(gr_poly
		(pts
			(xy 384.662934 -242.090702) (xy 384.662934 -242.046252) (xy 384.307334 -242.046252) (xy 384.307334 -242.090702)
			(xy 384.354324 -242.243102) (xy 384.615944 -242.243102)
		)
		(stroke
			(width 0)
			(type solid)
		)
		(fill yes)
		(layer "In6.Cu")
		(net "M_G_CPU0_SB_DQ<0>")
	)
	(gr_poly
		(pts
			(xy 384.662934 -240.871502) (xy 384.615944 -240.719102) (xy 384.354324 -240.719102) (xy 384.307334 -240.871502)
			(xy 384.307334 -240.915952) (xy 384.662934 -240.915952)
		)
		(stroke
			(width 0)
			(type solid)
		)
		(fill yes)
		(layer "In6.Cu")
		(net "M_G_CPU0_SB_DQ<3>")
	)
	(gr_poly
		(pts
			(xy 384.662934 -238.83493) (xy 384.662934 -238.790734) (xy 384.307334 -238.790734) (xy 384.307334 -238.83493)
			(xy 384.354324 -238.98733) (xy 384.615944 -238.98733)
		)
		(stroke
			(width 0)
			(type solid)
		)
		(fill yes)
		(layer "In6.Cu")
		(net "M_G_CPU0_SB_DQ<4>")
	)
	(gr_poly
		(pts
			(xy 384.662934 -237.61573) (xy 384.615944 -237.46333) (xy 384.354324 -237.46333) (xy 384.307334 -237.61573)
			(xy 384.307334 -237.66018) (xy 384.662934 -237.66018)
		)
		(stroke
			(width 0)
			(type solid)
		)
		(fill yes)
		(layer "In6.Cu")
		(net "M_G_CPU0_SB_DQ<7>")
	)
	(gr_poly
		(pts
			(xy 384.662934 -233.952034) (xy 384.662934 -233.907584) (xy 384.307334 -233.907584) (xy 384.307334 -233.952034)
			(xy 384.354324 -234.104434) (xy 384.615944 -234.104434)
		)
		(stroke
			(width 0)
			(type solid)
		)
		(fill yes)
		(layer "In6.Cu")
		(net "M_G_CPU0_SB_DQ<14>")
	)
	(gr_poly
		(pts
			(xy 384.662934 -231.104694) (xy 384.615944 -230.952294) (xy 384.354324 -230.952294) (xy 384.307334 -231.104694)
			(xy 384.307334 -231.149144) (xy 384.662934 -231.149144)
		)
		(stroke
			(width 0)
			(type solid)
		)
		(fill yes)
		(layer "In6.Cu")
		(net "M_H_CPU0_SB_DQ<18>")
	)
	(gr_poly
		(pts
			(xy 384.662934 -230.696262) (xy 384.662934 -230.651812) (xy 384.307334 -230.651812) (xy 384.307334 -230.696262)
			(xy 384.354324 -230.848662) (xy 384.615944 -230.848662)
		)
		(stroke
			(width 0)
			(type solid)
		)
		(fill yes)
		(layer "In6.Cu")
		(net "M_H_CPU0_SB_DQ<17>")
	)
	(gr_poly
		(pts
			(xy 384.662934 -229.477062) (xy 384.615944 -229.324662) (xy 384.354324 -229.324662) (xy 384.307334 -229.477062)
			(xy 384.307334 -229.521512) (xy 384.662934 -229.521512)
		)
		(stroke
			(width 0)
			(type solid)
		)
		(fill yes)
		(layer "In6.Cu")
		(net "M_H_CPU0_SB_DQS_DN<2>")
	)
	(gr_poly
		(pts
			(xy 384.662934 -229.06863) (xy 384.662934 -229.02418) (xy 384.307334 -229.02418) (xy 384.307334 -229.06863)
			(xy 384.354324 -229.22103) (xy 384.615944 -229.22103)
		)
		(stroke
			(width 0)
			(type solid)
		)
		(fill yes)
		(layer "In6.Cu")
		(net "M_H_CPU0_SB_DQS_DN<7>")
	)
	(gr_poly
		(pts
			(xy 384.662934 -227.84943) (xy 384.615944 -227.69703) (xy 384.354324 -227.69703) (xy 384.307334 -227.84943)
			(xy 384.307334 -227.893626) (xy 384.662934 -227.893626)
		)
		(stroke
			(width 0)
			(type solid)
		)
		(fill yes)
		(layer "In6.Cu")
		(net "M_H_CPU0_SB_DQ<22>")
	)
	(gr_poly
		(pts
			(xy 384.662934 -227.44049) (xy 384.662934 -227.396294) (xy 384.307334 -227.396294) (xy 384.307334 -227.44049)
			(xy 384.354324 -227.59289) (xy 384.615944 -227.59289)
		)
		(stroke
			(width 0)
			(type solid)
		)
		(fill yes)
		(layer "In6.Cu")
		(net "M_H_CPU0_SB_DQ<21>")
	)
	(gr_poly
		(pts
			(xy 384.665474 -216.454736) (xy 384.618484 -216.302336) (xy 384.356864 -216.302336) (xy 384.309874 -216.454736)
			(xy 384.309874 -216.498932) (xy 384.665474 -216.498932)
		)
		(stroke
			(width 0)
			(type solid)
		)
		(fill yes)
		(layer "In6.Cu")
		(net "M_G_CPU0_SB_DQ<29>")
	)
	(gr_poly
		(pts
			(xy 384.671316 -240.46307) (xy 384.671316 -240.418874) (xy 384.315716 -240.418874) (xy 384.315716 -240.46307)
			(xy 384.362706 -240.61547) (xy 384.624326 -240.61547)
		)
		(stroke
			(width 0)
			(type solid)
		)
		(fill yes)
		(layer "In6.Cu")
		(net "M_G_CPU0_SB_DQS_DP<0>")
	)
	(gr_poly
		(pts
			(xy 384.671316 -239.243362) (xy 384.624326 -239.090962) (xy 384.362706 -239.090962) (xy 384.315716 -239.243362)
			(xy 384.315716 -239.287812) (xy 384.671316 -239.287812)
		)
		(stroke
			(width 0)
			(type solid)
		)
		(fill yes)
		(layer "In6.Cu")
		(net "M_G_CPU0_SB_DQS_DP<5>")
	)
	(gr_poly
		(pts
			(xy 384.671316 -237.207806) (xy 384.671316 -237.163356) (xy 384.315716 -237.163356) (xy 384.315716 -237.207806)
			(xy 384.362706 -237.360206) (xy 384.624326 -237.360206)
		)
		(stroke
			(width 0)
			(type solid)
		)
		(fill yes)
		(layer "In6.Cu")
		(net "M_G_CPU0_SB_DQ<8>")
	)
	(gr_poly
		(pts
			(xy 384.671316 -235.988098) (xy 384.624326 -235.835698) (xy 384.362706 -235.835698) (xy 384.315716 -235.988098)
			(xy 384.315716 -236.032294) (xy 384.671316 -236.032294)
		)
		(stroke
			(width 0)
			(type solid)
		)
		(fill yes)
		(layer "In6.Cu")
		(net "M_G_CPU0_SB_DQ<9>")
	)
	(gr_poly
		(pts
			(xy 384.671316 -235.579666) (xy 384.671316 -235.53547) (xy 384.315716 -235.53547) (xy 384.315716 -235.579666)
			(xy 384.362706 -235.732066) (xy 384.624326 -235.732066)
		)
		(stroke
			(width 0)
			(type solid)
		)
		(fill yes)
		(layer "In6.Cu")
		(net "M_G_CPU0_SB_DQS_DN<6>")
	)
	(gr_poly
		(pts
			(xy 384.671316 -234.360466) (xy 384.624326 -234.208066) (xy 384.362706 -234.208066) (xy 384.315716 -234.360466)
			(xy 384.315716 -234.404662) (xy 384.671316 -234.404662)
		)
		(stroke
			(width 0)
			(type solid)
		)
		(fill yes)
		(layer "In6.Cu")
		(net "M_G_CPU0_SB_DQS_DN<1>")
	)
	(gr_poly
		(pts
			(xy 384.737864 -232.800144) (xy 384.629406 -232.683304) (xy 384.591052 -232.661206) (xy 384.413252 -232.969054)
			(xy 384.451606 -232.991152) (xy 384.607054 -233.026712)
		)
		(stroke
			(width 0)
			(type solid)
		)
		(fill yes)
		(layer "In6.Cu")
		(net "M_G_CPU0_SB_DQ<15>")
	)
	(gr_poly
		(pts
			(xy 384.739134 -279.809194) (xy 384.847592 -279.692354) (xy 384.716782 -279.465786) (xy 384.561334 -279.501346)
			(xy 384.52298 -279.523444) (xy 384.70078 -279.831292)
		)
		(stroke
			(width 0)
			(type solid)
		)
		(fill yes)
		(layer "In6.Cu")
		(net "M_H_CPU0_SA_DQ<2>")
	)
	(gr_poly
		(pts
			(xy 384.766566 -268.77391) (xy 384.719576 -268.62151) (xy 384.457956 -268.62151) (xy 384.410966 -268.77391)
			(xy 384.410966 -268.81836) (xy 384.766566 -268.81836)
		)
		(stroke
			(width 0)
			(type solid)
		)
		(fill yes)
		(layer "In6.Cu")
		(net "M_G_CPU0_SA_DQ<27>")
	)
	(gr_poly
		(pts
			(xy 384.766566 -268.365478) (xy 384.766566 -268.321028) (xy 384.410966 -268.321028) (xy 384.410966 -268.365478)
			(xy 384.457956 -268.517878) (xy 384.719576 -268.517878)
		)
		(stroke
			(width 0)
			(type solid)
		)
		(fill yes)
		(layer "In6.Cu")
		(net "M_G_CPU0_SA_DQS_DP<3>")
	)
	(gr_poly
		(pts
			(xy 384.766566 -267.146278) (xy 384.719576 -266.993878) (xy 384.457956 -266.993878) (xy 384.410966 -267.146278)
			(xy 384.410966 -267.190474) (xy 384.766566 -267.190474)
		)
		(stroke
			(width 0)
			(type solid)
		)
		(fill yes)
		(layer "In6.Cu")
		(net "M_G_CPU0_SA_DQS_DP<8>")
	)
	(gr_poly
		(pts
			(xy 384.766566 -266.737846) (xy 384.766566 -266.693396) (xy 384.410966 -266.693396) (xy 384.410966 -266.737846)
			(xy 384.457956 -266.890246) (xy 384.719576 -266.890246)
		)
		(stroke
			(width 0)
			(type solid)
		)
		(fill yes)
		(layer "In6.Cu")
		(net "M_G_CPU0_SA_DQ<28>")
	)
	(gr_poly
		(pts
			(xy 384.767582 -255.343406) (xy 384.767582 -255.298956) (xy 384.411982 -255.298956) (xy 384.411982 -255.343406)
			(xy 384.458972 -255.495806) (xy 384.720592 -255.495806)
		)
		(stroke
			(width 0)
			(type solid)
		)
		(fill yes)
		(layer "In6.Cu")
		(net "M_H_CPU0_SB_RSP<1>")
	)
	(gr_poly
		(pts
			(xy 384.772408 -262.262874) (xy 384.725418 -262.110474) (xy 384.463798 -262.110474) (xy 384.416808 -262.262874)
			(xy 384.416808 -262.30707) (xy 384.772408 -262.30707)
		)
		(stroke
			(width 0)
			(type solid)
		)
		(fill yes)
		(layer "In6.Cu")
		(net "M_G_CPU0_SA_DQS_DP<9>")
	)
	(gr_poly
		(pts
			(xy 384.772662 -278.540718) (xy 384.725672 -278.388318) (xy 384.464052 -278.388318) (xy 384.417062 -278.540718)
			(xy 384.417062 -278.585168) (xy 384.772662 -278.585168)
		)
		(stroke
			(width 0)
			(type solid)
		)
		(fill yes)
		(layer "In6.Cu")
		(net "M_H_CPU0_SA_DQ<1>")
	)
	(gr_poly
		(pts
			(xy 384.772662 -278.132032) (xy 384.772662 -278.087836) (xy 384.417062 -278.087836) (xy 384.417062 -278.132032)
			(xy 384.464052 -278.284432) (xy 384.725672 -278.284432)
		)
		(stroke
			(width 0)
			(type solid)
		)
		(fill yes)
		(layer "In6.Cu")
		(net "M_H_CPU0_SA_DQS_DP<0>")
	)
	(gr_poly
		(pts
			(xy 384.772662 -276.913086) (xy 384.725672 -276.760686) (xy 384.464052 -276.760686) (xy 384.417062 -276.913086)
			(xy 384.417062 -276.957282) (xy 384.772662 -276.957282)
		)
		(stroke
			(width 0)
			(type solid)
		)
		(fill yes)
		(layer "In6.Cu")
		(net "M_H_CPU0_SA_DQS_DP<5>")
	)
	(gr_poly
		(pts
			(xy 384.772662 -276.504146) (xy 384.772662 -276.45995) (xy 384.417062 -276.45995) (xy 384.417062 -276.504146)
			(xy 384.464052 -276.656546) (xy 384.725672 -276.656546)
		)
		(stroke
			(width 0)
			(type solid)
		)
		(fill yes)
		(layer "In6.Cu")
		(net "M_H_CPU0_SA_DQ<4>")
	)
	(gr_poly
		(pts
			(xy 384.772662 -273.657314) (xy 384.725672 -273.504914) (xy 384.464052 -273.504914) (xy 384.417062 -273.657314)
			(xy 384.417062 -273.701764) (xy 384.772662 -273.701764)
		)
		(stroke
			(width 0)
			(type solid)
		)
		(fill yes)
		(layer "In6.Cu")
		(net "M_G_CPU0_SA_DQ<11>")
	)
	(gr_poly
		(pts
			(xy 384.772662 -273.248882) (xy 384.772662 -273.204432) (xy 384.417062 -273.204432) (xy 384.417062 -273.248882)
			(xy 384.464052 -273.401282) (xy 384.725672 -273.401282)
		)
		(stroke
			(width 0)
			(type solid)
		)
		(fill yes)
		(layer "In6.Cu")
		(net "M_G_CPU0_SA_DQS_DP<1>")
	)
	(gr_poly
		(pts
			(xy 384.772662 -263.891014) (xy 384.725672 -263.738614) (xy 384.464052 -263.738614) (xy 384.417062 -263.891014)
			(xy 384.417062 -263.93521) (xy 384.772662 -263.93521)
		)
		(stroke
			(width 0)
			(type solid)
		)
		(fill yes)
		(layer "In6.Cu")
		(net "M_G_CPU0_SA_CB<3>")
	)
	(gr_poly
		(pts
			(xy 384.772662 -263.482074) (xy 384.772662 -263.437878) (xy 384.417062 -263.437878) (xy 384.417062 -263.482074)
			(xy 384.464052 -263.634474) (xy 384.725672 -263.634474)
		)
		(stroke
			(width 0)
			(type solid)
		)
		(fill yes)
		(layer "In6.Cu")
		(net "M_G_CPU0_SA_DQS_DP<4>")
	)
	(gr_poly
		(pts
			(xy 384.772662 -261.854442) (xy 384.772662 -261.809992) (xy 384.417062 -261.809992) (xy 384.417062 -261.854442)
			(xy 384.464052 -262.006842) (xy 384.725672 -262.006842)
		)
		(stroke
			(width 0)
			(type solid)
		)
		(fill yes)
		(layer "In6.Cu")
		(net "M_G_CPU0_SA_CB<4>")
	)
	(gr_poly
		(pts
			(xy 384.772662 -260.635242) (xy 384.725672 -260.482842) (xy 384.464052 -260.482842) (xy 384.417062 -260.635242)
			(xy 384.417062 -260.679438) (xy 384.772662 -260.679438)
		)
		(stroke
			(width 0)
			(type solid)
		)
		(fill yes)
		(layer "In6.Cu")
		(net "M_G_CPU0_SA_CB<7>")
	)
	(gr_poly
		(pts
			(xy 384.781298 -275.284946) (xy 384.734308 -275.132546) (xy 384.472688 -275.132546) (xy 384.425698 -275.284946)
			(xy 384.425698 -275.329396) (xy 384.781298 -275.329396)
		)
		(stroke
			(width 0)
			(type solid)
		)
		(fill yes)
		(layer "In6.Cu")
		(net "M_H_CPU0_SA_DQ<7>")
	)
	(gr_poly
		(pts
			(xy 384.781298 -274.876768) (xy 384.781298 -274.832572) (xy 384.425698 -274.832572) (xy 384.425698 -274.876768)
			(xy 384.472688 -275.029168) (xy 384.734308 -275.029168)
		)
		(stroke
			(width 0)
			(type solid)
		)
		(fill yes)
		(layer "In6.Cu")
		(net "M_G_CPU0_SA_DQ<8>")
	)
	(gr_poly
		(pts
			(xy 384.781298 -272.029174) (xy 384.734308 -271.876774) (xy 384.472688 -271.876774) (xy 384.425698 -272.029174)
			(xy 384.425698 -272.073624) (xy 384.781298 -272.073624)
		)
		(stroke
			(width 0)
			(type solid)
		)
		(fill yes)
		(layer "In6.Cu")
		(net "M_G_CPU0_SA_DQS_DP<6>")
	)
	(gr_poly
		(pts
			(xy 384.781298 -271.62125) (xy 384.781298 -271.5768) (xy 384.425698 -271.5768) (xy 384.425698 -271.62125)
			(xy 384.472688 -271.77365) (xy 384.734308 -271.77365)
		)
		(stroke
			(width 0)
			(type solid)
		)
		(fill yes)
		(layer "In6.Cu")
		(net "M_G_CPU0_SA_DQ<12>")
	)
	(gr_poly
		(pts
			(xy 384.781298 -270.401542) (xy 384.734308 -270.249142) (xy 384.472688 -270.249142) (xy 384.425698 -270.401542)
			(xy 384.425698 -270.445992) (xy 384.781298 -270.445992)
		)
		(stroke
			(width 0)
			(type solid)
		)
		(fill yes)
		(layer "In6.Cu")
		(net "M_G_CPU0_SA_DQ<15>")
	)
	(gr_poly
		(pts
			(xy 384.781298 -269.993618) (xy 384.781298 -269.949168) (xy 384.425698 -269.949168) (xy 384.425698 -269.993618)
			(xy 384.472688 -270.146018) (xy 384.734308 -270.146018)
		)
		(stroke
			(width 0)
			(type solid)
		)
		(fill yes)
		(layer "In6.Cu")
		(net "M_G_CPU0_SA_DQ<24>")
	)
	(gr_poly
		(pts
			(xy 384.781298 -265.518138) (xy 384.734308 -265.365738) (xy 384.472688 -265.365738) (xy 384.425698 -265.518138)
			(xy 384.425698 -265.562588) (xy 384.781298 -265.562588)
		)
		(stroke
			(width 0)
			(type solid)
		)
		(fill yes)
		(layer "In6.Cu")
		(net "M_G_CPU0_SA_DQ<31>")
	)
	(gr_poly
		(pts
			(xy 384.781298 -265.110214) (xy 384.781298 -265.065764) (xy 384.425698 -265.065764) (xy 384.425698 -265.110214)
			(xy 384.472688 -265.262614) (xy 384.734308 -265.262614)
		)
		(stroke
			(width 0)
			(type solid)
		)
		(fill yes)
		(layer "In6.Cu")
		(net "M_G_CPU0_SA_CB<0>")
	)
	(gr_poly
		(pts
			(xy 384.782822 -255.75133) (xy 384.735832 -255.59893) (xy 384.474212 -255.59893) (xy 384.427222 -255.75133)
			(xy 384.427222 -255.79578) (xy 384.782822 -255.79578)
		)
		(stroke
			(width 0)
			(type solid)
		)
		(fill yes)
		(layer "In6.Cu")
		(net "M_H_CPU0_SA_RSP<0>")
	)
	(gr_poly
		(pts
			(xy 385.026916 -232.90149) (xy 384.988562 -232.879392) (xy 384.833114 -232.843832) (xy 384.702304 -233.0704)
			(xy 384.810762 -233.18724) (xy 384.849116 -233.209338)
		)
		(stroke
			(width 0)
			(type solid)
		)
		(fill yes)
		(layer "In6.Cu")
		(net "M_G_CPU0_SB_DQ<12>")
	)
	(gr_poly
		(pts
			(xy 385.09829 -281.240992) (xy 385.136644 -281.218894) (xy 384.958844 -280.911046) (xy 384.92049 -280.933144)
			(xy 384.812032 -281.049984) (xy 384.942842 -281.276552)
		)
		(stroke
			(width 0)
			(type solid)
		)
		(fill yes)
		(layer "In6.Cu")
		(net "M_H_CPU0_SA_DQ<0>")
	)
	(gr_poly
		(pts
			(xy 385.09829 -279.613106) (xy 385.136644 -279.591008) (xy 384.958844 -279.28316) (xy 384.92049 -279.305258)
			(xy 384.812032 -279.422098) (xy 384.942842 -279.648666)
		)
		(stroke
			(width 0)
			(type solid)
		)
		(fill yes)
		(layer "In6.Cu")
		(net "M_H_CPU0_SA_DQ<3>")
	)
	(gr_poly
		(pts
			(xy 385.124198 -240.057178) (xy 385.077208 -239.904778) (xy 384.815588 -239.904778) (xy 384.768598 -240.057178)
			(xy 384.768598 -240.101628) (xy 385.124198 -240.101628)
		)
		(stroke
			(width 0)
			(type solid)
		)
		(fill yes)
		(layer "In6.Cu")
		(net "M_G_CPU0_SB_DQS_DN<0>")
	)
	(gr_poly
		(pts
			(xy 385.124198 -239.649254) (xy 385.124198 -239.604804) (xy 384.768598 -239.604804) (xy 384.768598 -239.649254)
			(xy 384.815588 -239.801654) (xy 385.077208 -239.801654)
		)
		(stroke
			(width 0)
			(type solid)
		)
		(fill yes)
		(layer "In6.Cu")
		(net "M_G_CPU0_SB_DQS_DN<5>")
	)
	(gr_poly
		(pts
			(xy 385.124198 -236.801914) (xy 385.077208 -236.649514) (xy 384.815588 -236.649514) (xy 384.768598 -236.801914)
			(xy 384.768598 -236.84611) (xy 385.124198 -236.84611)
		)
		(stroke
			(width 0)
			(type solid)
		)
		(fill yes)
		(layer "In6.Cu")
		(net "M_G_CPU0_SB_DQ<10>")
	)
	(gr_poly
		(pts
			(xy 385.124198 -236.39399) (xy 385.124198 -236.34954) (xy 384.768598 -236.34954) (xy 384.768598 -236.39399)
			(xy 384.815588 -236.54639) (xy 385.077208 -236.54639)
		)
		(stroke
			(width 0)
			(type solid)
		)
		(fill yes)
		(layer "In6.Cu")
		(net "M_G_CPU0_SB_DQ<11>")
	)
	(gr_poly
		(pts
			(xy 385.124198 -235.174282) (xy 385.077208 -235.021882) (xy 384.815588 -235.021882) (xy 384.768598 -235.174282)
			(xy 384.768598 -235.218478) (xy 385.124198 -235.218478)
		)
		(stroke
			(width 0)
			(type solid)
		)
		(fill yes)
		(layer "In6.Cu")
		(net "M_G_CPU0_SB_DQS_DP<6>")
	)
	(gr_poly
		(pts
			(xy 385.124198 -234.76585) (xy 385.124198 -234.721654) (xy 384.768598 -234.721654) (xy 384.768598 -234.76585)
			(xy 384.815588 -234.91825) (xy 385.077208 -234.91825)
		)
		(stroke
			(width 0)
			(type solid)
		)
		(fill yes)
		(layer "In6.Cu")
		(net "M_G_CPU0_SB_DQS_DP<1>")
	)
	(gr_poly
		(pts
			(xy 385.132834 -241.685318) (xy 385.085844 -241.532918) (xy 384.824224 -241.532918) (xy 384.777234 -241.685318)
			(xy 384.777234 -241.729768) (xy 385.132834 -241.729768)
		)
		(stroke
			(width 0)
			(type solid)
		)
		(fill yes)
		(layer "In6.Cu")
		(net "M_G_CPU0_SB_DQ<2>")
	)
	(gr_poly
		(pts
			(xy 385.132834 -241.276886) (xy 385.132834 -241.232436) (xy 384.777234 -241.232436) (xy 384.777234 -241.276886)
			(xy 384.824224 -241.429286) (xy 385.085844 -241.429286)
		)
		(stroke
			(width 0)
			(type solid)
		)
		(fill yes)
		(layer "In6.Cu")
		(net "M_G_CPU0_SB_DQ<1>")
	)
	(gr_poly
		(pts
			(xy 385.132834 -238.430054) (xy 385.085844 -238.277654) (xy 384.824224 -238.277654) (xy 384.777234 -238.430054)
			(xy 384.777234 -238.47425) (xy 385.132834 -238.47425)
		)
		(stroke
			(width 0)
			(type solid)
		)
		(fill yes)
		(layer "In6.Cu")
		(net "M_G_CPU0_SB_DQ<6>")
	)
	(gr_poly
		(pts
			(xy 385.132834 -238.021114) (xy 385.132834 -237.976918) (xy 384.777234 -237.976918) (xy 384.777234 -238.021114)
			(xy 384.824224 -238.173514) (xy 385.085844 -238.173514)
		)
		(stroke
			(width 0)
			(type solid)
		)
		(fill yes)
		(layer "In6.Cu")
		(net "M_G_CPU0_SB_DQ<5>")
	)
	(gr_poly
		(pts
			(xy 385.132834 -231.919018) (xy 385.085844 -231.766618) (xy 384.824224 -231.766618) (xy 384.777234 -231.919018)
			(xy 384.777234 -231.963214) (xy 385.132834 -231.963214)
		)
		(stroke
			(width 0)
			(type solid)
		)
		(fill yes)
		(layer "In6.Cu")
		(net "M_G_CPU0_SB_DQ<13>")
	)
	(gr_poly
		(pts
			(xy 385.132834 -231.510078) (xy 385.132834 -231.465882) (xy 384.777234 -231.465882) (xy 384.777234 -231.510078)
			(xy 384.824224 -231.662478) (xy 385.085844 -231.662478)
		)
		(stroke
			(width 0)
			(type solid)
		)
		(fill yes)
		(layer "In6.Cu")
		(net "M_H_CPU0_SB_DQ<16>")
	)
	(gr_poly
		(pts
			(xy 385.132834 -230.290878) (xy 385.085844 -230.138478) (xy 384.824224 -230.138478) (xy 384.777234 -230.290878)
			(xy 384.777234 -230.335328) (xy 385.132834 -230.335328)
		)
		(stroke
			(width 0)
			(type solid)
		)
		(fill yes)
		(layer "In6.Cu")
		(net "M_H_CPU0_SB_DQ<19>")
	)
	(gr_poly
		(pts
			(xy 385.132834 -229.882446) (xy 385.132834 -229.837996) (xy 384.777234 -229.837996) (xy 384.777234 -229.882446)
			(xy 384.824224 -230.034846) (xy 385.085844 -230.034846)
		)
		(stroke
			(width 0)
			(type solid)
		)
		(fill yes)
		(layer "In6.Cu")
		(net "M_H_CPU0_SB_DQS_DP<2>")
	)
	(gr_poly
		(pts
			(xy 385.132834 -228.663754) (xy 385.085844 -228.511354) (xy 384.824224 -228.511354) (xy 384.777234 -228.663754)
			(xy 384.777234 -228.70795) (xy 385.132834 -228.70795)
		)
		(stroke
			(width 0)
			(type solid)
		)
		(fill yes)
		(layer "In6.Cu")
		(net "M_H_CPU0_SB_DQS_DP<7>")
	)
	(gr_poly
		(pts
			(xy 385.132834 -228.254814) (xy 385.132834 -228.210364) (xy 384.777234 -228.210364) (xy 384.777234 -228.254814)
			(xy 384.824224 -228.407214) (xy 385.085844 -228.407214)
		)
		(stroke
			(width 0)
			(type solid)
		)
		(fill yes)
		(layer "In6.Cu")
		(net "M_H_CPU0_SB_DQ<20>")
	)
	(gr_poly
		(pts
			(xy 385.205732 -233.618024) (xy 385.097274 -233.501184) (xy 385.05892 -233.479086) (xy 384.88112 -233.786934)
			(xy 384.919474 -233.809032) (xy 385.074922 -233.844592)
		)
		(stroke
			(width 0)
			(type solid)
		)
		(fill yes)
		(layer "In6.Cu")
		(net "M_G_CPU0_SB_DQ<14>")
	)
	(gr_poly
		(pts
			(xy 385.207002 -280.6192) (xy 385.31546 -280.50236) (xy 385.18465 -280.275792) (xy 385.029202 -280.311352)
			(xy 384.990848 -280.33345) (xy 385.168648 -280.641298)
		)
		(stroke
			(width 0)
			(type solid)
		)
		(fill yes)
		(layer "In6.Cu")
		(net "M_H_CPU0_SA_DQ<2>")
	)
	(gr_poly
		(pts
			(xy 385.209034 -278.995378) (xy 385.317492 -278.878538) (xy 385.186682 -278.65197) (xy 385.031234 -278.68753)
			(xy 384.99288 -278.709628) (xy 385.17068 -279.017476)
		)
		(stroke
			(width 0)
			(type solid)
		)
		(fill yes)
		(layer "In6.Cu")
		(net "M_H_CPU0_SA_DQ<1>")
	)
	(gr_poly
		(pts
			(xy 385.23418 -275.690584) (xy 385.23418 -275.646388) (xy 384.87858 -275.646388) (xy 384.87858 -275.690584)
			(xy 384.92557 -275.842984) (xy 385.18719 -275.842984)
		)
		(stroke
			(width 0)
			(type solid)
		)
		(fill yes)
		(layer "In6.Cu")
		(net "M_H_CPU0_SA_DQ<5>")
	)
	(gr_poly
		(pts
			(xy 385.23418 -274.47113) (xy 385.18719 -274.31873) (xy 384.92557 -274.31873) (xy 384.87858 -274.47113)
			(xy 384.87858 -274.515326) (xy 385.23418 -274.515326)
		)
		(stroke
			(width 0)
			(type solid)
		)
		(fill yes)
		(layer "In6.Cu")
		(net "M_G_CPU0_SA_DQ<10>")
	)
	(gr_poly
		(pts
			(xy 385.23418 -272.435066) (xy 385.23418 -272.39087) (xy 384.87858 -272.39087) (xy 384.87858 -272.435066)
			(xy 384.92557 -272.587466) (xy 385.18719 -272.587466)
		)
		(stroke
			(width 0)
			(type solid)
		)
		(fill yes)
		(layer "In6.Cu")
		(net "M_G_CPU0_SA_DQS_DN<6>")
	)
	(gr_poly
		(pts
			(xy 385.23418 -271.215358) (xy 385.18719 -271.062958) (xy 384.92557 -271.062958) (xy 384.87858 -271.215358)
			(xy 384.87858 -271.259808) (xy 385.23418 -271.259808)
		)
		(stroke
			(width 0)
			(type solid)
		)
		(fill yes)
		(layer "In6.Cu")
		(net "M_G_CPU0_SA_DQ<14>")
	)
	(gr_poly
		(pts
			(xy 385.23418 -270.807434) (xy 385.23418 -270.762984) (xy 384.87858 -270.762984) (xy 384.87858 -270.807434)
			(xy 384.92557 -270.959834) (xy 385.18719 -270.959834)
		)
		(stroke
			(width 0)
			(type solid)
		)
		(fill yes)
		(layer "In6.Cu")
		(net "M_G_CPU0_SA_DQ<13>")
	)
	(gr_poly
		(pts
			(xy 385.23418 -269.587726) (xy 385.18719 -269.435326) (xy 384.92557 -269.435326) (xy 384.87858 -269.587726)
			(xy 384.87858 -269.631922) (xy 385.23418 -269.631922)
		)
		(stroke
			(width 0)
			(type solid)
		)
		(fill yes)
		(layer "In6.Cu")
		(net "M_G_CPU0_SA_DQ<26>")
	)
	(gr_poly
		(pts
			(xy 385.23418 -265.92403) (xy 385.23418 -265.879834) (xy 384.87858 -265.879834) (xy 384.87858 -265.92403)
			(xy 384.92557 -266.07643) (xy 385.18719 -266.07643)
		)
		(stroke
			(width 0)
			(type solid)
		)
		(fill yes)
		(layer "In6.Cu")
		(net "M_G_CPU0_SA_DQ<29>")
	)
	(gr_poly
		(pts
			(xy 385.23418 -264.704322) (xy 385.18719 -264.551922) (xy 384.92557 -264.551922) (xy 384.87858 -264.704322)
			(xy 384.87858 -264.748772) (xy 385.23418 -264.748772)
		)
		(stroke
			(width 0)
			(type solid)
		)
		(fill yes)
		(layer "In6.Cu")
		(net "M_G_CPU0_SA_CB<2>")
	)
	(gr_poly
		(pts
			(xy 385.23418 -256.157222) (xy 385.23418 -256.113026) (xy 384.87858 -256.113026) (xy 384.87858 -256.157222)
			(xy 384.92557 -256.309622) (xy 385.18719 -256.309622)
		)
		(stroke
			(width 0)
			(type solid)
		)
		(fill yes)
		(layer "In6.Cu")
		(net "M_H_CPU0_SB_RSP<0>")
	)
	(gr_poly
		(pts
			(xy 385.23418 -254.937514) (xy 385.18719 -254.785114) (xy 384.92557 -254.785114) (xy 384.87858 -254.937514)
			(xy 384.87858 -254.981964) (xy 385.23418 -254.981964)
		)
		(stroke
			(width 0)
			(type solid)
		)
		(fill yes)
		(layer "In6.Cu")
		(net "M_H_CPU0_SA_RSP<1>")
	)
	(gr_poly
		(pts
			(xy 385.242308 -269.179294) (xy 385.242308 -269.134844) (xy 384.886708 -269.134844) (xy 384.886708 -269.179294)
			(xy 384.933698 -269.331694) (xy 385.195318 -269.331694)
		)
		(stroke
			(width 0)
			(type solid)
		)
		(fill yes)
		(layer "In6.Cu")
		(net "M_G_CPU0_SA_DQ<25>")
	)
	(gr_poly
		(pts
			(xy 385.242562 -277.726902) (xy 385.195572 -277.574502) (xy 384.933952 -277.574502) (xy 384.886962 -277.726902)
			(xy 384.886962 -277.771098) (xy 385.242562 -277.771098)
		)
		(stroke
			(width 0)
			(type solid)
		)
		(fill yes)
		(layer "In6.Cu")
		(net "M_H_CPU0_SA_DQS_DN<0>")
	)
	(gr_poly
		(pts
			(xy 385.242562 -277.317962) (xy 385.242562 -277.273766) (xy 384.886962 -277.273766) (xy 384.886962 -277.317962)
			(xy 384.933952 -277.470362) (xy 385.195572 -277.470362)
		)
		(stroke
			(width 0)
			(type solid)
		)
		(fill yes)
		(layer "In6.Cu")
		(net "M_H_CPU0_SA_DQS_DN<5>")
	)
	(gr_poly
		(pts
			(xy 385.242562 -276.09927) (xy 385.195572 -275.94687) (xy 384.933952 -275.94687) (xy 384.886962 -276.09927)
			(xy 384.886962 -276.143466) (xy 385.242562 -276.143466)
		)
		(stroke
			(width 0)
			(type solid)
		)
		(fill yes)
		(layer "In6.Cu")
		(net "M_H_CPU0_SA_DQ<6>")
	)
	(gr_poly
		(pts
			(xy 385.242562 -274.062698) (xy 385.242562 -274.018248) (xy 384.886962 -274.018248) (xy 384.886962 -274.062698)
			(xy 384.933952 -274.215098) (xy 385.195572 -274.215098)
		)
		(stroke
			(width 0)
			(type solid)
		)
		(fill yes)
		(layer "In6.Cu")
		(net "M_G_CPU0_SA_DQ<9>")
	)
	(gr_poly
		(pts
			(xy 385.242562 -272.843498) (xy 385.195572 -272.691098) (xy 384.933952 -272.691098) (xy 384.886962 -272.843498)
			(xy 384.886962 -272.887948) (xy 385.242562 -272.887948)
		)
		(stroke
			(width 0)
			(type solid)
		)
		(fill yes)
		(layer "In6.Cu")
		(net "M_G_CPU0_SA_DQS_DN<1>")
	)
	(gr_poly
		(pts
			(xy 385.242562 -264.29589) (xy 385.242562 -264.251694) (xy 384.886962 -264.251694) (xy 384.886962 -264.29589)
			(xy 384.933952 -264.44829) (xy 385.195572 -264.44829)
		)
		(stroke
			(width 0)
			(type solid)
		)
		(fill yes)
		(layer "In6.Cu")
		(net "M_G_CPU0_SA_CB<1>")
	)
	(gr_poly
		(pts
			(xy 385.242562 -263.07669) (xy 385.195572 -262.92429) (xy 384.933952 -262.92429) (xy 384.886962 -263.07669)
			(xy 384.886962 -263.12114) (xy 385.242562 -263.12114)
		)
		(stroke
			(width 0)
			(type solid)
		)
		(fill yes)
		(layer "In6.Cu")
		(net "M_G_CPU0_SA_DQS_DN<4>")
	)
	(gr_poly
		(pts
			(xy 385.242562 -262.668258) (xy 385.242562 -262.623808) (xy 384.886962 -262.623808) (xy 384.886962 -262.668258)
			(xy 384.933952 -262.820658) (xy 385.195572 -262.820658)
		)
		(stroke
			(width 0)
			(type solid)
		)
		(fill yes)
		(layer "In6.Cu")
		(net "M_G_CPU0_SA_DQS_DN<9>")
	)
	(gr_poly
		(pts
			(xy 385.242562 -261.449058) (xy 385.195572 -261.296658) (xy 384.933952 -261.296658) (xy 384.886962 -261.449058)
			(xy 384.886962 -261.493508) (xy 385.242562 -261.493508)
		)
		(stroke
			(width 0)
			(type solid)
		)
		(fill yes)
		(layer "In6.Cu")
		(net "M_G_CPU0_SA_CB<6>")
	)
	(gr_poly
		(pts
			(xy 385.242562 -261.040626) (xy 385.242562 -260.996176) (xy 384.886962 -260.996176) (xy 384.886962 -261.040626)
			(xy 384.933952 -261.193026) (xy 385.195572 -261.193026)
		)
		(stroke
			(width 0)
			(type solid)
		)
		(fill yes)
		(layer "In6.Cu")
		(net "M_G_CPU0_SA_CB<5>")
	)
	(gr_poly
		(pts
			(xy 385.248404 -266.332462) (xy 385.201414 -266.180062) (xy 384.939794 -266.180062) (xy 384.892804 -266.332462)
			(xy 384.892804 -266.376658) (xy 385.248404 -266.376658)
		)
		(stroke
			(width 0)
			(type solid)
		)
		(fill yes)
		(layer "In6.Cu")
		(net "M_G_CPU0_SA_DQ<30>")
	)
	(gr_poly
		(pts
			(xy 385.250944 -267.960094) (xy 385.203954 -267.807694) (xy 384.942334 -267.807694) (xy 384.895344 -267.960094)
			(xy 384.895344 -268.00429) (xy 385.250944 -268.00429)
		)
		(stroke
			(width 0)
			(type solid)
		)
		(fill yes)
		(layer "In6.Cu")
		(net "M_G_CPU0_SA_DQS_DN<3>")
	)
	(gr_poly
		(pts
			(xy 385.250944 -267.551662) (xy 385.250944 -267.507466) (xy 384.895344 -267.507466) (xy 384.895344 -267.551662)
			(xy 384.942334 -267.704062) (xy 385.203954 -267.704062)
		)
		(stroke
			(width 0)
			(type solid)
		)
		(fill yes)
		(layer "In6.Cu")
		(net "M_G_CPU0_SA_DQS_DN<8>")
	)
	(gr_poly
		(pts
			(xy 385.498848 -233.711496) (xy 385.460494 -233.689398) (xy 385.305046 -233.653838) (xy 385.174236 -233.880406)
			(xy 385.282694 -233.997246) (xy 385.321048 -234.019344)
		)
		(stroke
			(width 0)
			(type solid)
		)
		(fill yes)
		(layer "In6.Cu")
		(net "M_G_CPU0_SB_DQS_DN<1>")
	)
	(gr_poly
		(pts
			(xy 385.56819 -278.79929) (xy 385.606544 -278.777192) (xy 385.428744 -278.469344) (xy 385.39039 -278.491442)
			(xy 385.281932 -278.608282) (xy 385.412742 -278.83485)
		)
		(stroke
			(width 0)
			(type solid)
		)
		(fill yes)
		(layer "In6.Cu")
		(net "M_H_CPU0_SA_DQS_DP<0>")
	)
	(gr_poly
		(pts
			(xy 385.570222 -280.430986) (xy 385.608576 -280.408888) (xy 385.430776 -280.10104) (xy 385.392422 -280.123138)
			(xy 385.283964 -280.239978) (xy 385.414774 -280.466546)
		)
		(stroke
			(width 0)
			(type solid)
		)
		(fill yes)
		(layer "In6.Cu")
		(net "M_H_CPU0_SA_DQ<3>")
	)
	(gr_poly
		(pts
			(xy 385.602734 -242.090702) (xy 385.602734 -242.046252) (xy 385.247134 -242.046252) (xy 385.247134 -242.090702)
			(xy 385.294124 -242.243102) (xy 385.555744 -242.243102)
		)
		(stroke
			(width 0)
			(type solid)
		)
		(fill yes)
		(layer "In6.Cu")
		(net "M_G_CPU0_SB_DQ<0>")
	)
	(gr_poly
		(pts
			(xy 385.602734 -240.871502) (xy 385.555744 -240.719102) (xy 385.294124 -240.719102) (xy 385.247134 -240.871502)
			(xy 385.247134 -240.915952) (xy 385.602734 -240.915952)
		)
		(stroke
			(width 0)
			(type solid)
		)
		(fill yes)
		(layer "In6.Cu")
		(net "M_G_CPU0_SB_DQ<3>")
	)
	(gr_poly
		(pts
			(xy 385.602734 -238.83493) (xy 385.602734 -238.790734) (xy 385.247134 -238.790734) (xy 385.247134 -238.83493)
			(xy 385.294124 -238.98733) (xy 385.555744 -238.98733)
		)
		(stroke
			(width 0)
			(type solid)
		)
		(fill yes)
		(layer "In6.Cu")
		(net "M_G_CPU0_SB_DQ<4>")
	)
	(gr_poly
		(pts
			(xy 385.602734 -237.61573) (xy 385.555744 -237.46333) (xy 385.294124 -237.46333) (xy 385.247134 -237.61573)
			(xy 385.247134 -237.66018) (xy 385.602734 -237.66018)
		)
		(stroke
			(width 0)
			(type solid)
		)
		(fill yes)
		(layer "In6.Cu")
		(net "M_G_CPU0_SB_DQ<7>")
	)
	(gr_poly
		(pts
			(xy 385.602734 -232.732834) (xy 385.555744 -232.580434) (xy 385.294124 -232.580434) (xy 385.247134 -232.732834)
			(xy 385.247134 -232.77703) (xy 385.602734 -232.77703)
		)
		(stroke
			(width 0)
			(type solid)
		)
		(fill yes)
		(layer "In6.Cu")
		(net "M_G_CPU0_SB_DQ<12>")
	)
	(gr_poly
		(pts
			(xy 385.602734 -232.323894) (xy 385.602734 -232.279698) (xy 385.247134 -232.279698) (xy 385.247134 -232.323894)
			(xy 385.294124 -232.476294) (xy 385.555744 -232.476294)
		)
		(stroke
			(width 0)
			(type solid)
		)
		(fill yes)
		(layer "In6.Cu")
		(net "M_G_CPU0_SB_DQ<15>")
	)
	(gr_poly
		(pts
			(xy 385.602734 -231.104694) (xy 385.555744 -230.952294) (xy 385.294124 -230.952294) (xy 385.247134 -231.104694)
			(xy 385.247134 -231.149144) (xy 385.602734 -231.149144)
		)
		(stroke
			(width 0)
			(type solid)
		)
		(fill yes)
		(layer "In6.Cu")
		(net "M_H_CPU0_SB_DQ<18>")
	)
	(gr_poly
		(pts
			(xy 385.602734 -230.696262) (xy 385.602734 -230.651812) (xy 385.247134 -230.651812) (xy 385.247134 -230.696262)
			(xy 385.294124 -230.848662) (xy 385.555744 -230.848662)
		)
		(stroke
			(width 0)
			(type solid)
		)
		(fill yes)
		(layer "In6.Cu")
		(net "M_H_CPU0_SB_DQ<17>")
	)
	(gr_poly
		(pts
			(xy 385.611116 -240.46307) (xy 385.611116 -240.418874) (xy 385.255516 -240.418874) (xy 385.255516 -240.46307)
			(xy 385.302506 -240.61547) (xy 385.564126 -240.61547)
		)
		(stroke
			(width 0)
			(type solid)
		)
		(fill yes)
		(layer "In6.Cu")
		(net "M_G_CPU0_SB_DQS_DP<0>")
	)
	(gr_poly
		(pts
			(xy 385.611116 -239.243362) (xy 385.564126 -239.090962) (xy 385.302506 -239.090962) (xy 385.255516 -239.243362)
			(xy 385.255516 -239.287812) (xy 385.611116 -239.287812)
		)
		(stroke
			(width 0)
			(type solid)
		)
		(fill yes)
		(layer "In6.Cu")
		(net "M_G_CPU0_SB_DQS_DP<5>")
	)
	(gr_poly
		(pts
			(xy 385.611116 -237.207806) (xy 385.611116 -237.163356) (xy 385.255516 -237.163356) (xy 385.255516 -237.207806)
			(xy 385.302506 -237.360206) (xy 385.564126 -237.360206)
		)
		(stroke
			(width 0)
			(type solid)
		)
		(fill yes)
		(layer "In6.Cu")
		(net "M_G_CPU0_SB_DQ<8>")
	)
	(gr_poly
		(pts
			(xy 385.611116 -235.988098) (xy 385.564126 -235.835698) (xy 385.302506 -235.835698) (xy 385.255516 -235.988098)
			(xy 385.255516 -236.032294) (xy 385.611116 -236.032294)
		)
		(stroke
			(width 0)
			(type solid)
		)
		(fill yes)
		(layer "In6.Cu")
		(net "M_G_CPU0_SB_DQ<9>")
	)
	(gr_poly
		(pts
			(xy 385.611116 -235.579666) (xy 385.611116 -235.53547) (xy 385.255516 -235.53547) (xy 385.255516 -235.579666)
			(xy 385.302506 -235.732066) (xy 385.564126 -235.732066)
		)
		(stroke
			(width 0)
			(type solid)
		)
		(fill yes)
		(layer "In6.Cu")
		(net "M_G_CPU0_SB_DQS_DN<6>")
	)
	(gr_poly
		(pts
			(xy 385.676902 -278.177498) (xy 385.78536 -278.060658) (xy 385.65455 -277.83409) (xy 385.499102 -277.86965)
			(xy 385.460748 -277.891748) (xy 385.638548 -278.199596)
		)
		(stroke
			(width 0)
			(type solid)
		)
		(fill yes)
		(layer "In6.Cu")
		(net "M_H_CPU0_SA_DQS_DN<0>")
	)
	(gr_poly
		(pts
			(xy 385.678934 -279.809194) (xy 385.787392 -279.692354) (xy 385.656582 -279.465786) (xy 385.501134 -279.501346)
			(xy 385.46278 -279.523444) (xy 385.64058 -279.831292)
		)
		(stroke
			(width 0)
			(type solid)
		)
		(fill yes)
		(layer "In6.Cu")
		(net "M_H_CPU0_SA_DQ<1>")
	)
	(gr_poly
		(pts
			(xy 385.681982 -234.420918) (xy 385.573524 -234.304078) (xy 385.53517 -234.28198) (xy 385.35737 -234.589828)
			(xy 385.395724 -234.611926) (xy 385.551172 -234.647486)
		)
		(stroke
			(width 0)
			(type solid)
		)
		(fill yes)
		(layer "In6.Cu")
		(net "M_G_CPU0_SB_DQS_DP<1>")
	)
	(gr_poly
		(pts
			(xy 385.703826 -268.365478) (xy 385.703826 -268.321282) (xy 385.348226 -268.321282) (xy 385.348226 -268.365478)
			(xy 385.395216 -268.517878) (xy 385.656836 -268.517878)
		)
		(stroke
			(width 0)
			(type solid)
		)
		(fill yes)
		(layer "In6.Cu")
		(net "M_G_CPU0_SA_DQS_DP<3>")
	)
	(gr_poly
		(pts
			(xy 385.703826 -267.14577) (xy 385.656836 -266.99337) (xy 385.395216 -266.99337) (xy 385.348226 -267.14577)
			(xy 385.348226 -267.19022) (xy 385.703826 -267.19022)
		)
		(stroke
			(width 0)
			(type solid)
		)
		(fill yes)
		(layer "In6.Cu")
		(net "M_G_CPU0_SA_DQS_DP<8>")
	)
	(gr_poly
		(pts
			(xy 385.706112 -266.737846) (xy 385.706112 -266.693396) (xy 385.350512 -266.693396) (xy 385.350512 -266.737846)
			(xy 385.397502 -266.890246) (xy 385.659122 -266.890246)
		)
		(stroke
			(width 0)
			(type solid)
		)
		(fill yes)
		(layer "In6.Cu")
		(net "M_G_CPU0_SA_DQ<28>")
	)
	(gr_poly
		(pts
			(xy 385.706366 -273.248882) (xy 385.706366 -273.204432) (xy 385.350766 -273.204432) (xy 385.350766 -273.248882)
			(xy 385.397756 -273.401282) (xy 385.659376 -273.401282)
		)
		(stroke
			(width 0)
			(type solid)
		)
		(fill yes)
		(layer "In6.Cu")
		(net "M_G_CPU0_SA_DQS_DP<1>")
	)
	(gr_poly
		(pts
			(xy 385.712462 -281.38755) (xy 385.712462 -281.343354) (xy 385.356862 -281.343354) (xy 385.356862 -281.38755)
			(xy 385.403852 -281.53995) (xy 385.665472 -281.53995)
		)
		(stroke
			(width 0)
			(type solid)
		)
		(fill yes)
		(layer "In6.Cu")
		(net "M_H_CPU0_SA_DQ<0>")
	)
	(gr_poly
		(pts
			(xy 385.712462 -276.913086) (xy 385.665472 -276.760686) (xy 385.403852 -276.760686) (xy 385.356862 -276.913086)
			(xy 385.356862 -276.957282) (xy 385.712462 -276.957282)
		)
		(stroke
			(width 0)
			(type solid)
		)
		(fill yes)
		(layer "In6.Cu")
		(net "M_H_CPU0_SA_DQS_DP<5>")
	)
	(gr_poly
		(pts
			(xy 385.712462 -276.504146) (xy 385.712462 -276.45995) (xy 385.356862 -276.45995) (xy 385.356862 -276.504146)
			(xy 385.403852 -276.656546) (xy 385.665472 -276.656546)
		)
		(stroke
			(width 0)
			(type solid)
		)
		(fill yes)
		(layer "In6.Cu")
		(net "M_H_CPU0_SA_DQ<4>")
	)
	(gr_poly
		(pts
			(xy 385.712462 -273.657314) (xy 385.665472 -273.504914) (xy 385.403852 -273.504914) (xy 385.356862 -273.657314)
			(xy 385.356862 -273.701764) (xy 385.712462 -273.701764)
		)
		(stroke
			(width 0)
			(type solid)
		)
		(fill yes)
		(layer "In6.Cu")
		(net "M_G_CPU0_SA_DQ<11>")
	)
	(gr_poly
		(pts
			(xy 385.712462 -263.482074) (xy 385.712462 -263.437878) (xy 385.356862 -263.437878) (xy 385.356862 -263.482074)
			(xy 385.403852 -263.634474) (xy 385.665472 -263.634474)
		)
		(stroke
			(width 0)
			(type solid)
		)
		(fill yes)
		(layer "In6.Cu")
		(net "M_G_CPU0_SA_DQS_DP<4>")
	)
	(gr_poly
		(pts
			(xy 385.712462 -262.262874) (xy 385.665472 -262.110474) (xy 385.403852 -262.110474) (xy 385.356862 -262.262874)
			(xy 385.356862 -262.307324) (xy 385.712462 -262.307324)
		)
		(stroke
			(width 0)
			(type solid)
		)
		(fill yes)
		(layer "In6.Cu")
		(net "M_G_CPU0_SA_DQS_DP<9>")
	)
	(gr_poly
		(pts
			(xy 385.712462 -261.854442) (xy 385.712462 -261.809992) (xy 385.356862 -261.809992) (xy 385.356862 -261.854442)
			(xy 385.403852 -262.006842) (xy 385.665472 -262.006842)
		)
		(stroke
			(width 0)
			(type solid)
		)
		(fill yes)
		(layer "In6.Cu")
		(net "M_G_CPU0_SA_CB<4>")
	)
	(gr_poly
		(pts
			(xy 385.712462 -260.635242) (xy 385.665472 -260.482842) (xy 385.403852 -260.482842) (xy 385.356862 -260.635242)
			(xy 385.356862 -260.679438) (xy 385.712462 -260.679438)
		)
		(stroke
			(width 0)
			(type solid)
		)
		(fill yes)
		(layer "In6.Cu")
		(net "M_G_CPU0_SA_CB<7>")
	)
	(gr_poly
		(pts
			(xy 385.71805 -268.77391) (xy 385.67106 -268.62151) (xy 385.40944 -268.62151) (xy 385.36245 -268.77391)
			(xy 385.36245 -268.81836) (xy 385.71805 -268.81836)
		)
		(stroke
			(width 0)
			(type solid)
		)
		(fill yes)
		(layer "In6.Cu")
		(net "M_G_CPU0_SA_DQ<27>")
	)
	(gr_poly
		(pts
			(xy 385.718558 -263.890506) (xy 385.671568 -263.738106) (xy 385.409948 -263.738106) (xy 385.362958 -263.890506)
			(xy 385.362958 -263.934956) (xy 385.718558 -263.934956)
		)
		(stroke
			(width 0)
			(type solid)
		)
		(fill yes)
		(layer "In6.Cu")
		(net "M_G_CPU0_SA_CB<3>")
	)
	(gr_poly
		(pts
			(xy 385.721098 -275.284946) (xy 385.674108 -275.132546) (xy 385.412488 -275.132546) (xy 385.365498 -275.284946)
			(xy 385.365498 -275.329396) (xy 385.721098 -275.329396)
		)
		(stroke
			(width 0)
			(type solid)
		)
		(fill yes)
		(layer "In6.Cu")
		(net "M_H_CPU0_SA_DQ<7>")
	)
	(gr_poly
		(pts
			(xy 385.721098 -274.876768) (xy 385.721098 -274.832572) (xy 385.365498 -274.832572) (xy 385.365498 -274.876768)
			(xy 385.412488 -275.029168) (xy 385.674108 -275.029168)
		)
		(stroke
			(width 0)
			(type solid)
		)
		(fill yes)
		(layer "In6.Cu")
		(net "M_G_CPU0_SA_DQ<8>")
	)
	(gr_poly
		(pts
			(xy 385.721098 -272.029174) (xy 385.674108 -271.876774) (xy 385.412488 -271.876774) (xy 385.365498 -272.029174)
			(xy 385.365498 -272.073624) (xy 385.721098 -272.073624)
		)
		(stroke
			(width 0)
			(type solid)
		)
		(fill yes)
		(layer "In6.Cu")
		(net "M_G_CPU0_SA_DQS_DP<6>")
	)
	(gr_poly
		(pts
			(xy 385.721098 -271.62125) (xy 385.721098 -271.5768) (xy 385.365498 -271.5768) (xy 385.365498 -271.62125)
			(xy 385.412488 -271.77365) (xy 385.674108 -271.77365)
		)
		(stroke
			(width 0)
			(type solid)
		)
		(fill yes)
		(layer "In6.Cu")
		(net "M_G_CPU0_SA_DQ<12>")
	)
	(gr_poly
		(pts
			(xy 385.721098 -270.401542) (xy 385.674108 -270.249142) (xy 385.412488 -270.249142) (xy 385.365498 -270.401542)
			(xy 385.365498 -270.445992) (xy 385.721098 -270.445992)
		)
		(stroke
			(width 0)
			(type solid)
		)
		(fill yes)
		(layer "In6.Cu")
		(net "M_G_CPU0_SA_DQ<15>")
	)
	(gr_poly
		(pts
			(xy 385.721098 -269.993618) (xy 385.721098 -269.949168) (xy 385.365498 -269.949168) (xy 385.365498 -269.993618)
			(xy 385.412488 -270.146018) (xy 385.674108 -270.146018)
		)
		(stroke
			(width 0)
			(type solid)
		)
		(fill yes)
		(layer "In6.Cu")
		(net "M_G_CPU0_SA_DQ<24>")
	)
	(gr_poly
		(pts
			(xy 385.721098 -265.518138) (xy 385.674108 -265.365738) (xy 385.412488 -265.365738) (xy 385.365498 -265.518138)
			(xy 385.365498 -265.562588) (xy 385.721098 -265.562588)
		)
		(stroke
			(width 0)
			(type solid)
		)
		(fill yes)
		(layer "In6.Cu")
		(net "M_G_CPU0_SA_DQ<31>")
	)
	(gr_poly
		(pts
			(xy 385.721098 -265.110214) (xy 385.721098 -265.065764) (xy 385.365498 -265.065764) (xy 385.365498 -265.110214)
			(xy 385.412488 -265.262614) (xy 385.674108 -265.262614)
		)
		(stroke
			(width 0)
			(type solid)
		)
		(fill yes)
		(layer "In6.Cu")
		(net "M_G_CPU0_SA_CB<0>")
	)
	(gr_poly
		(pts
			(xy 385.721098 -255.75133) (xy 385.674108 -255.59893) (xy 385.412488 -255.59893) (xy 385.365498 -255.75133)
			(xy 385.365498 -255.79578) (xy 385.721098 -255.79578)
		)
		(stroke
			(width 0)
			(type solid)
		)
		(fill yes)
		(layer "In6.Cu")
		(net "M_H_CPU0_SA_RSP<0>")
	)
	(gr_poly
		(pts
			(xy 385.721098 -255.343406) (xy 385.721098 -255.298956) (xy 385.365498 -255.298956) (xy 385.365498 -255.343406)
			(xy 385.412488 -255.495806) (xy 385.674108 -255.495806)
		)
		(stroke
			(width 0)
			(type solid)
		)
		(fill yes)
		(layer "In6.Cu")
		(net "M_H_CPU0_SB_RSP<1>")
	)
	(gr_poly
		(pts
			(xy 385.962144 -234.536488) (xy 385.92379 -234.51439) (xy 385.768342 -234.47883) (xy 385.637532 -234.705398)
			(xy 385.74599 -234.822238) (xy 385.784344 -234.844336)
		)
		(stroke
			(width 0)
			(type solid)
		)
		(fill yes)
		(layer "In6.Cu")
		(net "M_G_CPU0_SB_DQS_DP<6>")
	)
	(gr_poly
		(pts
			(xy 386.03809 -279.613106) (xy 386.076444 -279.591008) (xy 385.898644 -279.28316) (xy 385.86029 -279.305258)
			(xy 385.751832 -279.422098) (xy 385.882642 -279.648666)
		)
		(stroke
			(width 0)
			(type solid)
		)
		(fill yes)
		(layer "In6.Cu")
		(net "M_H_CPU0_SA_DQS_DP<0>")
	)
	(gr_poly
		(pts
			(xy 386.040122 -277.989284) (xy 386.078476 -277.967186) (xy 385.900676 -277.659338) (xy 385.862322 -277.681436)
			(xy 385.753864 -277.798276) (xy 385.884674 -278.024844)
		)
		(stroke
			(width 0)
			(type solid)
		)
		(fill yes)
		(layer "In6.Cu")
		(net "M_H_CPU0_SA_DQS_DN<5>")
	)
	(gr_poly
		(pts
			(xy 386.063998 -240.057178) (xy 386.017008 -239.904778) (xy 385.755388 -239.904778) (xy 385.708398 -240.057178)
			(xy 385.708398 -240.101628) (xy 386.063998 -240.101628)
		)
		(stroke
			(width 0)
			(type solid)
		)
		(fill yes)
		(layer "In6.Cu")
		(net "M_G_CPU0_SB_DQS_DN<0>")
	)
	(gr_poly
		(pts
			(xy 386.063998 -239.649254) (xy 386.063998 -239.604804) (xy 385.708398 -239.604804) (xy 385.708398 -239.649254)
			(xy 385.755388 -239.801654) (xy 386.017008 -239.801654)
		)
		(stroke
			(width 0)
			(type solid)
		)
		(fill yes)
		(layer "In6.Cu")
		(net "M_G_CPU0_SB_DQS_DN<5>")
	)
	(gr_poly
		(pts
			(xy 386.063998 -236.801914) (xy 386.017008 -236.649514) (xy 385.755388 -236.649514) (xy 385.708398 -236.801914)
			(xy 385.708398 -236.84611) (xy 386.063998 -236.84611)
		)
		(stroke
			(width 0)
			(type solid)
		)
		(fill yes)
		(layer "In6.Cu")
		(net "M_G_CPU0_SB_DQ<10>")
	)
	(gr_poly
		(pts
			(xy 386.063998 -236.39399) (xy 386.063998 -236.34954) (xy 385.708398 -236.34954) (xy 385.708398 -236.39399)
			(xy 385.755388 -236.54639) (xy 386.017008 -236.54639)
		)
		(stroke
			(width 0)
			(type solid)
		)
		(fill yes)
		(layer "In6.Cu")
		(net "M_G_CPU0_SB_DQ<11>")
	)
	(gr_poly
		(pts
			(xy 386.064252 -217.268298) (xy 386.017262 -217.115898) (xy 385.755642 -217.115898) (xy 385.708652 -217.268298)
			(xy 385.708652 -217.312748) (xy 386.064252 -217.312748)
		)
		(stroke
			(width 0)
			(type solid)
		)
		(fill yes)
		(layer "In6.Cu")
		(net "M_G_CPU0_SB_DQS_DP<8>")
	)
	(gr_poly
		(pts
			(xy 386.072634 -241.685318) (xy 386.025644 -241.532918) (xy 385.764024 -241.532918) (xy 385.717034 -241.685318)
			(xy 385.717034 -241.729768) (xy 386.072634 -241.729768)
		)
		(stroke
			(width 0)
			(type solid)
		)
		(fill yes)
		(layer "In6.Cu")
		(net "M_G_CPU0_SB_DQ<2>")
	)
	(gr_poly
		(pts
			(xy 386.072634 -241.276886) (xy 386.072634 -241.232436) (xy 385.717034 -241.232436) (xy 385.717034 -241.276886)
			(xy 385.764024 -241.429286) (xy 386.025644 -241.429286)
		)
		(stroke
			(width 0)
			(type solid)
		)
		(fill yes)
		(layer "In6.Cu")
		(net "M_G_CPU0_SB_DQ<1>")
	)
	(gr_poly
		(pts
			(xy 386.072634 -238.430054) (xy 386.025644 -238.277654) (xy 385.764024 -238.277654) (xy 385.717034 -238.430054)
			(xy 385.717034 -238.47425) (xy 386.072634 -238.47425)
		)
		(stroke
			(width 0)
			(type solid)
		)
		(fill yes)
		(layer "In6.Cu")
		(net "M_G_CPU0_SB_DQ<6>")
	)
	(gr_poly
		(pts
			(xy 386.072634 -238.021114) (xy 386.072634 -237.976918) (xy 385.717034 -237.976918) (xy 385.717034 -238.021114)
			(xy 385.764024 -238.173514) (xy 386.025644 -238.173514)
		)
		(stroke
			(width 0)
			(type solid)
		)
		(fill yes)
		(layer "In6.Cu")
		(net "M_G_CPU0_SB_DQ<5>")
	)
	(gr_poly
		(pts
			(xy 386.072634 -233.54665) (xy 386.025644 -233.39425) (xy 385.764024 -233.39425) (xy 385.717034 -233.54665)
			(xy 385.717034 -233.590846) (xy 386.072634 -233.590846)
		)
		(stroke
			(width 0)
			(type solid)
		)
		(fill yes)
		(layer "In6.Cu")
		(net "M_G_CPU0_SB_DQS_DN<1>")
	)
	(gr_poly
		(pts
			(xy 386.072634 -233.13771) (xy 386.072634 -233.093514) (xy 385.717034 -233.093514) (xy 385.717034 -233.13771)
			(xy 385.764024 -233.29011) (xy 386.025644 -233.29011)
		)
		(stroke
			(width 0)
			(type solid)
		)
		(fill yes)
		(layer "In6.Cu")
		(net "M_G_CPU0_SB_DQ<14>")
	)
	(gr_poly
		(pts
			(xy 386.072634 -231.919018) (xy 386.025644 -231.766618) (xy 385.764024 -231.766618) (xy 385.717034 -231.919018)
			(xy 385.717034 -231.963214) (xy 386.072634 -231.963214)
		)
		(stroke
			(width 0)
			(type solid)
		)
		(fill yes)
		(layer "In6.Cu")
		(net "M_G_CPU0_SB_DQ<13>")
	)
	(gr_poly
		(pts
			(xy 386.072634 -216.859866) (xy 386.072634 -216.815416) (xy 385.717034 -216.815416) (xy 385.717034 -216.859866)
			(xy 385.764024 -217.012266) (xy 386.025644 -217.012266)
		)
		(stroke
			(width 0)
			(type solid)
		)
		(fill yes)
		(layer "In6.Cu")
		(net "M_G_CPU0_SB_DQ<28>")
	)
	(gr_poly
		(pts
			(xy 386.072634 -215.638888) (xy 386.025644 -215.486488) (xy 385.764024 -215.486488) (xy 385.717034 -215.638888)
			(xy 385.717034 -215.683084) (xy 386.072634 -215.683084)
		)
		(stroke
			(width 0)
			(type solid)
		)
		(fill yes)
		(layer "In6.Cu")
		(net "M_G_CPU0_SB_DQ<31>")
	)
	(gr_poly
		(pts
			(xy 386.146294 -235.244386) (xy 386.037836 -235.127546) (xy 385.999482 -235.105448) (xy 385.821682 -235.413296)
			(xy 385.860036 -235.435394) (xy 386.015484 -235.470954)
		)
		(stroke
			(width 0)
			(type solid)
		)
		(fill yes)
		(layer "In6.Cu")
		(net "M_G_CPU0_SB_DQS_DN<6>")
	)
	(gr_poly
		(pts
			(xy 386.148834 -278.995378) (xy 386.257292 -278.878538) (xy 386.126482 -278.65197) (xy 385.971034 -278.68753)
			(xy 385.93268 -278.709628) (xy 386.11048 -279.017476)
		)
		(stroke
			(width 0)
			(type solid)
		)
		(fill yes)
		(layer "In6.Cu")
		(net "M_H_CPU0_SA_DQS_DN<0>")
	)
	(gr_poly
		(pts
			(xy 386.148834 -277.367492) (xy 386.257292 -277.250652) (xy 386.126482 -277.024084) (xy 385.971034 -277.059644)
			(xy 385.93268 -277.081742) (xy 386.11048 -277.38959)
		)
		(stroke
			(width 0)
			(type solid)
		)
		(fill yes)
		(layer "In6.Cu")
		(net "M_H_CPU0_SA_DQS_DP<5>")
	)
	(gr_poly
		(pts
			(xy 386.17398 -275.690584) (xy 386.17398 -275.646388) (xy 385.81838 -275.646388) (xy 385.81838 -275.690584)
			(xy 385.86537 -275.842984) (xy 386.12699 -275.842984)
		)
		(stroke
			(width 0)
			(type solid)
		)
		(fill yes)
		(layer "In6.Cu")
		(net "M_H_CPU0_SA_DQ<5>")
	)
	(gr_poly
		(pts
			(xy 386.17398 -272.435066) (xy 386.17398 -272.39087) (xy 385.81838 -272.39087) (xy 385.81838 -272.435066)
			(xy 385.86537 -272.587466) (xy 386.12699 -272.587466)
		)
		(stroke
			(width 0)
			(type solid)
		)
		(fill yes)
		(layer "In6.Cu")
		(net "M_G_CPU0_SA_DQS_DN<6>")
	)
	(gr_poly
		(pts
			(xy 386.17398 -271.215358) (xy 386.12699 -271.062958) (xy 385.86537 -271.062958) (xy 385.81838 -271.215358)
			(xy 385.81838 -271.259808) (xy 386.17398 -271.259808)
		)
		(stroke
			(width 0)
			(type solid)
		)
		(fill yes)
		(layer "In6.Cu")
		(net "M_G_CPU0_SA_DQ<14>")
	)
	(gr_poly
		(pts
			(xy 386.17398 -270.807434) (xy 386.17398 -270.762984) (xy 385.81838 -270.762984) (xy 385.81838 -270.807434)
			(xy 385.86537 -270.959834) (xy 386.12699 -270.959834)
		)
		(stroke
			(width 0)
			(type solid)
		)
		(fill yes)
		(layer "In6.Cu")
		(net "M_G_CPU0_SA_DQ<13>")
	)
	(gr_poly
		(pts
			(xy 386.17398 -269.587726) (xy 386.12699 -269.435326) (xy 385.86537 -269.435326) (xy 385.81838 -269.587726)
			(xy 385.81838 -269.631922) (xy 386.17398 -269.631922)
		)
		(stroke
			(width 0)
			(type solid)
		)
		(fill yes)
		(layer "In6.Cu")
		(net "M_G_CPU0_SA_DQ<26>")
	)
	(gr_poly
		(pts
			(xy 386.17398 -265.92403) (xy 386.17398 -265.879834) (xy 385.81838 -265.879834) (xy 385.81838 -265.92403)
			(xy 385.86537 -266.07643) (xy 386.12699 -266.07643)
		)
		(stroke
			(width 0)
			(type solid)
		)
		(fill yes)
		(layer "In6.Cu")
		(net "M_G_CPU0_SA_DQ<29>")
	)
	(gr_poly
		(pts
			(xy 386.17398 -264.704322) (xy 386.12699 -264.551922) (xy 385.86537 -264.551922) (xy 385.81838 -264.704322)
			(xy 385.81838 -264.748772) (xy 386.17398 -264.748772)
		)
		(stroke
			(width 0)
			(type solid)
		)
		(fill yes)
		(layer "In6.Cu")
		(net "M_G_CPU0_SA_CB<2>")
	)
	(gr_poly
		(pts
			(xy 386.17398 -264.296398) (xy 386.17398 -264.251948) (xy 385.81838 -264.251948) (xy 385.81838 -264.296398)
			(xy 385.86537 -264.448798) (xy 386.12699 -264.448798)
		)
		(stroke
			(width 0)
			(type solid)
		)
		(fill yes)
		(layer "In6.Cu")
		(net "M_G_CPU0_SA_CB<1>")
	)
	(gr_poly
		(pts
			(xy 386.17398 -254.937514) (xy 386.12699 -254.785114) (xy 385.86537 -254.785114) (xy 385.81838 -254.937514)
			(xy 385.81838 -254.981964) (xy 386.17398 -254.981964)
		)
		(stroke
			(width 0)
			(type solid)
		)
		(fill yes)
		(layer "In6.Cu")
		(net "M_H_CPU0_SA_RSP<1>")
	)
	(gr_poly
		(pts
			(xy 386.174234 -256.157222) (xy 386.174234 -256.113026) (xy 385.818634 -256.113026) (xy 385.818634 -256.157222)
			(xy 385.865624 -256.309622) (xy 386.127244 -256.309622)
		)
		(stroke
			(width 0)
			(type solid)
		)
		(fill yes)
		(layer "In6.Cu")
		(net "M_H_CPU0_SB_RSP<0>")
	)
	(gr_poly
		(pts
			(xy 386.175758 -269.179294) (xy 386.175758 -269.134844) (xy 385.820158 -269.134844) (xy 385.820158 -269.179294)
			(xy 385.867148 -269.331694) (xy 386.128768 -269.331694)
		)
		(stroke
			(width 0)
			(type solid)
		)
		(fill yes)
		(layer "In6.Cu")
		(net "M_G_CPU0_SA_DQ<25>")
	)
	(gr_poly
		(pts
			(xy 386.17652 -280.574242) (xy 386.17652 -280.529792) (xy 385.82092 -280.529792) (xy 385.82092 -280.574242)
			(xy 385.86791 -280.726642) (xy 386.12953 -280.726642)
		)
		(stroke
			(width 0)
			(type solid)
		)
		(fill yes)
		(layer "In6.Cu")
		(net "M_H_CPU0_SA_DQ<3>")
	)
	(gr_poly
		(pts
			(xy 386.182362 -276.09927) (xy 386.135372 -275.94687) (xy 385.873752 -275.94687) (xy 385.826762 -276.09927)
			(xy 385.826762 -276.143466) (xy 386.182362 -276.143466)
		)
		(stroke
			(width 0)
			(type solid)
		)
		(fill yes)
		(layer "In6.Cu")
		(net "M_H_CPU0_SA_DQ<6>")
	)
	(gr_poly
		(pts
			(xy 386.182362 -274.062698) (xy 386.182362 -274.018248) (xy 385.826762 -274.018248) (xy 385.826762 -274.062698)
			(xy 385.873752 -274.215098) (xy 386.135372 -274.215098)
		)
		(stroke
			(width 0)
			(type solid)
		)
		(fill yes)
		(layer "In6.Cu")
		(net "M_G_CPU0_SA_DQ<9>")
	)
	(gr_poly
		(pts
			(xy 386.182362 -261.449058) (xy 386.135372 -261.296658) (xy 385.873752 -261.296658) (xy 385.826762 -261.449058)
			(xy 385.826762 -261.493508) (xy 386.182362 -261.493508)
		)
		(stroke
			(width 0)
			(type solid)
		)
		(fill yes)
		(layer "In6.Cu")
		(net "M_G_CPU0_SA_CB<6>")
	)
	(gr_poly
		(pts
			(xy 386.182362 -261.040626) (xy 386.182362 -260.996176) (xy 385.826762 -260.996176) (xy 385.826762 -261.040626)
			(xy 385.873752 -261.193026) (xy 386.135372 -261.193026)
		)
		(stroke
			(width 0)
			(type solid)
		)
		(fill yes)
		(layer "In6.Cu")
		(net "M_G_CPU0_SA_CB<5>")
	)
	(gr_poly
		(pts
			(xy 386.18795 -272.843498) (xy 386.14096 -272.691098) (xy 385.87934 -272.691098) (xy 385.83235 -272.843498)
			(xy 385.83235 -272.887948) (xy 386.18795 -272.887948)
		)
		(stroke
			(width 0)
			(type solid)
		)
		(fill yes)
		(layer "In6.Cu")
		(net "M_G_CPU0_SA_DQS_DN<1>")
	)
	(gr_poly
		(pts
			(xy 386.18795 -266.332462) (xy 386.14096 -266.180062) (xy 385.87934 -266.180062) (xy 385.83235 -266.332462)
			(xy 385.83235 -266.376658) (xy 386.18795 -266.376658)
		)
		(stroke
			(width 0)
			(type solid)
		)
		(fill yes)
		(layer "In6.Cu")
		(net "M_G_CPU0_SA_DQ<30>")
	)
	(gr_poly
		(pts
			(xy 386.188458 -280.98242) (xy 386.141468 -280.83002) (xy 385.879848 -280.83002) (xy 385.832858 -280.98242)
			(xy 385.832858 -281.026616) (xy 386.188458 -281.026616)
		)
		(stroke
			(width 0)
			(type solid)
		)
		(fill yes)
		(layer "In6.Cu")
		(net "M_H_CPU0_SA_DQ<2>")
	)
	(gr_poly
		(pts
			(xy 386.188458 -263.07669) (xy 386.141468 -262.92429) (xy 385.879848 -262.92429) (xy 385.832858 -263.07669)
			(xy 385.832858 -263.120886) (xy 386.188458 -263.120886)
		)
		(stroke
			(width 0)
			(type solid)
		)
		(fill yes)
		(layer "In6.Cu")
		(net "M_G_CPU0_SA_DQS_DN<4>")
	)
	(gr_poly
		(pts
			(xy 386.188458 -262.668258) (xy 386.188458 -262.624062) (xy 385.832858 -262.624062) (xy 385.832858 -262.668258)
			(xy 385.879848 -262.820658) (xy 386.141468 -262.820658)
		)
		(stroke
			(width 0)
			(type solid)
		)
		(fill yes)
		(layer "In6.Cu")
		(net "M_G_CPU0_SA_DQS_DN<9>")
	)
	(gr_poly
		(pts
			(xy 386.19049 -267.960094) (xy 386.1435 -267.807694) (xy 385.88188 -267.807694) (xy 385.83489 -267.960094)
			(xy 385.83489 -268.00429) (xy 386.19049 -268.00429)
		)
		(stroke
			(width 0)
			(type solid)
		)
		(fill yes)
		(layer "In6.Cu")
		(net "M_G_CPU0_SA_DQS_DN<3>")
	)
	(gr_poly
		(pts
			(xy 386.19049 -267.551662) (xy 386.19049 -267.507466) (xy 385.83489 -267.507466) (xy 385.83489 -267.551662)
			(xy 385.88188 -267.704062) (xy 386.1435 -267.704062)
		)
		(stroke
			(width 0)
			(type solid)
		)
		(fill yes)
		(layer "In6.Cu")
		(net "M_G_CPU0_SA_DQS_DN<8>")
	)
	(gr_poly
		(pts
			(xy 386.437632 -235.340652) (xy 386.399278 -235.318554) (xy 386.24383 -235.282994) (xy 386.11302 -235.509562)
			(xy 386.221478 -235.626402) (xy 386.259832 -235.6485)
		)
		(stroke
			(width 0)
			(type solid)
		)
		(fill yes)
		(layer "In6.Cu")
		(net "M_G_CPU0_SB_DQ<9>")
	)
	(gr_poly
		(pts
			(xy 386.50799 -277.171404) (xy 386.546344 -277.149306) (xy 386.368544 -276.841458) (xy 386.33019 -276.863556)
			(xy 386.221732 -276.980396) (xy 386.352542 -277.206964)
		)
		(stroke
			(width 0)
			(type solid)
		)
		(fill yes)
		(layer "In6.Cu")
		(net "M_H_CPU0_SA_DQ<4>")
	)
	(gr_poly
		(pts
			(xy 386.510022 -278.803354) (xy 386.548376 -278.781256) (xy 386.370576 -278.473408) (xy 386.332222 -278.495506)
			(xy 386.223764 -278.612346) (xy 386.354574 -278.838914)
		)
		(stroke
			(width 0)
			(type solid)
		)
		(fill yes)
		(layer "In6.Cu")
		(net "M_H_CPU0_SA_DQS_DN<5>")
	)
	(gr_poly
		(pts
			(xy 386.542534 -242.090702) (xy 386.542534 -242.046252) (xy 386.186934 -242.046252) (xy 386.186934 -242.090702)
			(xy 386.233924 -242.243102) (xy 386.495544 -242.243102)
		)
		(stroke
			(width 0)
			(type solid)
		)
		(fill yes)
		(layer "In6.Cu")
		(net "M_G_CPU0_SB_DQ<0>")
	)
	(gr_poly
		(pts
			(xy 386.542534 -240.871502) (xy 386.495544 -240.719102) (xy 386.233924 -240.719102) (xy 386.186934 -240.871502)
			(xy 386.186934 -240.915952) (xy 386.542534 -240.915952)
		)
		(stroke
			(width 0)
			(type solid)
		)
		(fill yes)
		(layer "In6.Cu")
		(net "M_G_CPU0_SB_DQ<3>")
	)
	(gr_poly
		(pts
			(xy 386.542534 -238.83493) (xy 386.542534 -238.790734) (xy 386.186934 -238.790734) (xy 386.186934 -238.83493)
			(xy 386.233924 -238.98733) (xy 386.495544 -238.98733)
		)
		(stroke
			(width 0)
			(type solid)
		)
		(fill yes)
		(layer "In6.Cu")
		(net "M_G_CPU0_SB_DQ<4>")
	)
	(gr_poly
		(pts
			(xy 386.542534 -237.61573) (xy 386.495544 -237.46333) (xy 386.233924 -237.46333) (xy 386.186934 -237.61573)
			(xy 386.186934 -237.66018) (xy 386.542534 -237.66018)
		)
		(stroke
			(width 0)
			(type solid)
		)
		(fill yes)
		(layer "In6.Cu")
		(net "M_G_CPU0_SB_DQ<7>")
	)
	(gr_poly
		(pts
			(xy 386.542534 -233.952034) (xy 386.542534 -233.907584) (xy 386.186934 -233.907584) (xy 386.186934 -233.952034)
			(xy 386.233924 -234.104434) (xy 386.495544 -234.104434)
		)
		(stroke
			(width 0)
			(type solid)
		)
		(fill yes)
		(layer "In6.Cu")
		(net "M_G_CPU0_SB_DQS_DP<1>")
	)
	(gr_poly
		(pts
			(xy 386.542534 -232.732834) (xy 386.495544 -232.580434) (xy 386.233924 -232.580434) (xy 386.186934 -232.732834)
			(xy 386.186934 -232.77703) (xy 386.542534 -232.77703)
		)
		(stroke
			(width 0)
			(type solid)
		)
		(fill yes)
		(layer "In6.Cu")
		(net "M_G_CPU0_SB_DQ<12>")
	)
	(gr_poly
		(pts
			(xy 386.542534 -232.323894) (xy 386.542534 -232.279698) (xy 386.186934 -232.279698) (xy 386.186934 -232.323894)
			(xy 386.233924 -232.476294) (xy 386.495544 -232.476294)
		)
		(stroke
			(width 0)
			(type solid)
		)
		(fill yes)
		(layer "In6.Cu")
		(net "M_G_CPU0_SB_DQ<15>")
	)
	(gr_poly
		(pts
			(xy 386.542534 -220.929454) (xy 386.542534 -220.885258) (xy 386.186934 -220.885258) (xy 386.186934 -220.929454)
			(xy 386.233924 -221.081854) (xy 386.495544 -221.081854)
		)
		(stroke
			(width 0)
			(type solid)
		)
		(fill yes)
		(layer "In6.Cu")
		(net "M_G_CPU0_SB_DQ<24>")
	)
	(gr_poly
		(pts
			(xy 386.542534 -218.082622) (xy 386.495544 -217.930222) (xy 386.233924 -217.930222) (xy 386.186934 -218.082622)
			(xy 386.186934 -218.127072) (xy 386.542534 -218.127072)
		)
		(stroke
			(width 0)
			(type solid)
		)
		(fill yes)
		(layer "In6.Cu")
		(net "M_G_CPU0_SB_DQS_DN<3>")
	)
	(gr_poly
		(pts
			(xy 386.542534 -217.67419) (xy 386.542534 -217.62974) (xy 386.186934 -217.62974) (xy 386.186934 -217.67419)
			(xy 386.233924 -217.82659) (xy 386.495544 -217.82659)
		)
		(stroke
			(width 0)
			(type solid)
		)
		(fill yes)
		(layer "In6.Cu")
		(net "M_G_CPU0_SB_DQS_DN<8>")
	)
	(gr_poly
		(pts
			(xy 386.54482 -216.045542) (xy 386.54482 -216.001346) (xy 386.18922 -216.001346) (xy 386.18922 -216.045542)
			(xy 386.23621 -216.197942) (xy 386.49783 -216.197942)
		)
		(stroke
			(width 0)
			(type solid)
		)
		(fill yes)
		(layer "In6.Cu")
		(net "M_G_CPU0_SB_DQ<29>")
	)
	(gr_poly
		(pts
			(xy 386.550916 -240.46307) (xy 386.550916 -240.418874) (xy 386.195316 -240.418874) (xy 386.195316 -240.46307)
			(xy 386.242306 -240.61547) (xy 386.503926 -240.61547)
		)
		(stroke
			(width 0)
			(type solid)
		)
		(fill yes)
		(layer "In6.Cu")
		(net "M_G_CPU0_SB_DQS_DP<0>")
	)
	(gr_poly
		(pts
			(xy 386.550916 -239.243362) (xy 386.503926 -239.090962) (xy 386.242306 -239.090962) (xy 386.195316 -239.243362)
			(xy 386.195316 -239.287812) (xy 386.550916 -239.287812)
		)
		(stroke
			(width 0)
			(type solid)
		)
		(fill yes)
		(layer "In6.Cu")
		(net "M_G_CPU0_SB_DQS_DP<5>")
	)
	(gr_poly
		(pts
			(xy 386.550916 -237.207806) (xy 386.550916 -237.163356) (xy 386.195316 -237.163356) (xy 386.195316 -237.207806)
			(xy 386.242306 -237.360206) (xy 386.503926 -237.360206)
		)
		(stroke
			(width 0)
			(type solid)
		)
		(fill yes)
		(layer "In6.Cu")
		(net "M_G_CPU0_SB_DQ<8>")
	)
	(gr_poly
		(pts
			(xy 386.550916 -234.360466) (xy 386.503926 -234.208066) (xy 386.242306 -234.208066) (xy 386.195316 -234.360466)
			(xy 386.195316 -234.404662) (xy 386.550916 -234.404662)
		)
		(stroke
			(width 0)
			(type solid)
		)
		(fill yes)
		(layer "In6.Cu")
		(net "M_G_CPU0_SB_DQS_DP<6>")
	)
	(gr_poly
		(pts
			(xy 386.616448 -236.057694) (xy 386.50799 -235.940854) (xy 386.469636 -235.918756) (xy 386.291836 -236.226604)
			(xy 386.33019 -236.248702) (xy 386.485638 -236.284262)
		)
		(stroke
			(width 0)
			(type solid)
		)
		(fill yes)
		(layer "In6.Cu")
		(net "M_G_CPU0_SB_DQ<11>")
	)
	(gr_poly
		(pts
			(xy 386.616702 -278.177498) (xy 386.72516 -278.060658) (xy 386.59435 -277.83409) (xy 386.438902 -277.86965)
			(xy 386.400548 -277.891748) (xy 386.578348 -278.199596)
		)
		(stroke
			(width 0)
			(type solid)
		)
		(fill yes)
		(layer "In6.Cu")
		(net "M_H_CPU0_SA_DQS_DP<5>")
	)
	(gr_poly
		(pts
			(xy 386.618734 -276.553676) (xy 386.727192 -276.436836) (xy 386.596382 -276.210268) (xy 386.440934 -276.245828)
			(xy 386.40258 -276.267926) (xy 386.58038 -276.575774)
		)
		(stroke
			(width 0)
			(type solid)
		)
		(fill yes)
		(layer "In6.Cu")
		(net "M_H_CPU0_SA_DQ<6>")
	)
	(gr_poly
		(pts
			(xy 386.641594 -268.365478) (xy 386.641594 -268.321028) (xy 386.285994 -268.321028) (xy 386.285994 -268.365478)
			(xy 386.332984 -268.517878) (xy 386.594604 -268.517878)
		)
		(stroke
			(width 0)
			(type solid)
		)
		(fill yes)
		(layer "In6.Cu")
		(net "M_G_CPU0_SA_DQS_DP<3>")
	)
	(gr_poly
		(pts
			(xy 386.641594 -267.146278) (xy 386.594604 -266.993878) (xy 386.332984 -266.993878) (xy 386.285994 -267.146278)
			(xy 386.285994 -267.190474) (xy 386.641594 -267.190474)
		)
		(stroke
			(width 0)
			(type solid)
		)
		(fill yes)
		(layer "In6.Cu")
		(net "M_G_CPU0_SA_DQS_DP<8>")
	)
	(gr_poly
		(pts
			(xy 386.64388 -263.482582) (xy 386.64388 -263.438132) (xy 386.28828 -263.438132) (xy 386.28828 -263.482582)
			(xy 386.33527 -263.634982) (xy 386.59689 -263.634982)
		)
		(stroke
			(width 0)
			(type solid)
		)
		(fill yes)
		(layer "In6.Cu")
		(net "M_G_CPU0_SA_DQS_DP<4>")
	)
	(gr_poly
		(pts
			(xy 386.64388 -262.262874) (xy 386.59689 -262.110474) (xy 386.33527 -262.110474) (xy 386.28828 -262.262874)
			(xy 386.28828 -262.30707) (xy 386.64388 -262.30707)
		)
		(stroke
			(width 0)
			(type solid)
		)
		(fill yes)
		(layer "In6.Cu")
		(net "M_G_CPU0_SA_DQS_DP<9>")
	)
	(gr_poly
		(pts
			(xy 386.645658 -266.737846) (xy 386.645658 -266.693396) (xy 386.290058 -266.693396) (xy 386.290058 -266.737846)
			(xy 386.337048 -266.890246) (xy 386.598668 -266.890246)
		)
		(stroke
			(width 0)
			(type solid)
		)
		(fill yes)
		(layer "In6.Cu")
		(net "M_G_CPU0_SA_DQ<28>")
	)
	(gr_poly
		(pts
			(xy 386.64642 -281.388058) (xy 386.64642 -281.343608) (xy 386.29082 -281.343608) (xy 386.29082 -281.388058)
			(xy 386.33781 -281.540458) (xy 386.59943 -281.540458)
		)
		(stroke
			(width 0)
			(type solid)
		)
		(fill yes)
		(layer "In6.Cu")
		(net "M_H_CPU0_SA_DQ<0>")
	)
	(gr_poly
		(pts
			(xy 386.652262 -279.759664) (xy 386.652262 -279.715468) (xy 386.296662 -279.715468) (xy 386.296662 -279.759664)
			(xy 386.343652 -279.912064) (xy 386.605272 -279.912064)
		)
		(stroke
			(width 0)
			(type solid)
		)
		(fill yes)
		(layer "In6.Cu")
		(net "M_H_CPU0_SA_DQS_DP<0>")
	)
	(gr_poly
		(pts
			(xy 386.652262 -261.854442) (xy 386.652262 -261.809992) (xy 386.296662 -261.809992) (xy 386.296662 -261.854442)
			(xy 386.343652 -262.006842) (xy 386.605272 -262.006842)
		)
		(stroke
			(width 0)
			(type solid)
		)
		(fill yes)
		(layer "In6.Cu")
		(net "M_G_CPU0_SA_CB<4>")
	)
	(gr_poly
		(pts
			(xy 386.657596 -268.77391) (xy 386.610606 -268.62151) (xy 386.348986 -268.62151) (xy 386.301996 -268.77391)
			(xy 386.301996 -268.81836) (xy 386.657596 -268.81836)
		)
		(stroke
			(width 0)
			(type solid)
		)
		(fill yes)
		(layer "In6.Cu")
		(net "M_G_CPU0_SA_DQ<27>")
	)
	(gr_poly
		(pts
			(xy 386.658612 -280.16835) (xy 386.611622 -280.01595) (xy 386.350002 -280.01595) (xy 386.303012 -280.16835)
			(xy 386.303012 -280.212546) (xy 386.658612 -280.212546)
		)
		(stroke
			(width 0)
			(type solid)
		)
		(fill yes)
		(layer "In6.Cu")
		(net "M_H_CPU0_SA_DQ<1>")
	)
	(gr_poly
		(pts
			(xy 386.660898 -275.284946) (xy 386.613908 -275.132546) (xy 386.352288 -275.132546) (xy 386.305298 -275.284946)
			(xy 386.305298 -275.329396) (xy 386.660898 -275.329396)
		)
		(stroke
			(width 0)
			(type solid)
		)
		(fill yes)
		(layer "In6.Cu")
		(net "M_H_CPU0_SA_DQ<7>")
	)
	(gr_poly
		(pts
			(xy 386.660898 -271.62125) (xy 386.660898 -271.5768) (xy 386.305298 -271.5768) (xy 386.305298 -271.62125)
			(xy 386.352288 -271.77365) (xy 386.613908 -271.77365)
		)
		(stroke
			(width 0)
			(type solid)
		)
		(fill yes)
		(layer "In6.Cu")
		(net "M_G_CPU0_SA_DQ<12>")
	)
	(gr_poly
		(pts
			(xy 386.660898 -269.993618) (xy 386.660898 -269.949168) (xy 386.305298 -269.949168) (xy 386.305298 -269.993618)
			(xy 386.352288 -270.146018) (xy 386.613908 -270.146018)
		)
		(stroke
			(width 0)
			(type solid)
		)
		(fill yes)
		(layer "In6.Cu")
		(net "M_G_CPU0_SA_DQ<24>")
	)
	(gr_poly
		(pts
			(xy 386.660898 -265.518138) (xy 386.613908 -265.365738) (xy 386.352288 -265.365738) (xy 386.305298 -265.518138)
			(xy 386.305298 -265.562588) (xy 386.660898 -265.562588)
		)
		(stroke
			(width 0)
			(type solid)
		)
		(fill yes)
		(layer "In6.Cu")
		(net "M_G_CPU0_SA_DQ<31>")
	)
	(gr_poly
		(pts
			(xy 386.660898 -265.110214) (xy 386.660898 -265.065764) (xy 386.305298 -265.065764) (xy 386.305298 -265.110214)
			(xy 386.352288 -265.262614) (xy 386.613908 -265.262614)
		)
		(stroke
			(width 0)
			(type solid)
		)
		(fill yes)
		(layer "In6.Cu")
		(net "M_G_CPU0_SA_CB<0>")
	)
	(gr_poly
		(pts
			(xy 386.660898 -263.890506) (xy 386.613908 -263.738106) (xy 386.352288 -263.738106) (xy 386.305298 -263.890506)
			(xy 386.305298 -263.934956) (xy 386.660898 -263.934956)
		)
		(stroke
			(width 0)
			(type solid)
		)
		(fill yes)
		(layer "In6.Cu")
		(net "M_G_CPU0_SA_CB<3>")
	)
	(gr_poly
		(pts
			(xy 386.660898 -255.343406) (xy 386.660898 -255.298956) (xy 386.305298 -255.298956) (xy 386.305298 -255.343406)
			(xy 386.352288 -255.495806) (xy 386.613908 -255.495806)
		)
		(stroke
			(width 0)
			(type solid)
		)
		(fill yes)
		(layer "In6.Cu")
		(net "M_H_CPU0_SB_RSP<1>")
	)
	(gr_poly
		(pts
			(xy 386.72516 -260.706616) (xy 386.616702 -260.589776) (xy 386.578348 -260.567678) (xy 386.400548 -260.875526)
			(xy 386.438902 -260.897624) (xy 386.59435 -260.933184)
		)
		(stroke
			(width 0)
			(type solid)
		)
		(fill yes)
		(layer "In6.Cu")
		(net "M_G_CPU0_SA_CB<5>")
	)
	(gr_poly
		(pts
			(xy 386.907278 -236.15523) (xy 386.868924 -236.133132) (xy 386.713476 -236.097572) (xy 386.582666 -236.32414)
			(xy 386.691124 -236.44098) (xy 386.729478 -236.463078)
		)
		(stroke
			(width 0)
			(type solid)
		)
		(fill yes)
		(layer "In6.Cu")
		(net "M_G_CPU0_SB_DQ<10>")
	)
	(gr_poly
		(pts
			(xy 386.97789 -276.357588) (xy 387.016244 -276.33549) (xy 386.838444 -276.027642) (xy 386.80009 -276.04974)
			(xy 386.691632 -276.16658) (xy 386.822442 -276.393148)
		)
		(stroke
			(width 0)
			(type solid)
		)
		(fill yes)
		(layer "In6.Cu")
		(net "M_H_CPU0_SA_DQ<5>")
	)
	(gr_poly
		(pts
			(xy 387.003798 -240.057178) (xy 386.956808 -239.904778) (xy 386.695188 -239.904778) (xy 386.648198 -240.057178)
			(xy 386.648198 -240.101628) (xy 387.003798 -240.101628)
		)
		(stroke
			(width 0)
			(type solid)
		)
		(fill yes)
		(layer "In6.Cu")
		(net "M_G_CPU0_SB_DQS_DN<0>")
	)
	(gr_poly
		(pts
			(xy 387.003798 -239.649254) (xy 387.003798 -239.604804) (xy 386.648198 -239.604804) (xy 386.648198 -239.649254)
			(xy 386.695188 -239.801654) (xy 386.956808 -239.801654)
		)
		(stroke
			(width 0)
			(type solid)
		)
		(fill yes)
		(layer "In6.Cu")
		(net "M_G_CPU0_SB_DQS_DN<5>")
	)
	(gr_poly
		(pts
			(xy 387.003798 -235.174282) (xy 386.956808 -235.021882) (xy 386.695188 -235.021882) (xy 386.648198 -235.174282)
			(xy 386.648198 -235.218478) (xy 387.003798 -235.218478)
		)
		(stroke
			(width 0)
			(type solid)
		)
		(fill yes)
		(layer "In6.Cu")
		(net "M_G_CPU0_SB_DQ<9>")
	)
	(gr_poly
		(pts
			(xy 387.004306 -216.859866) (xy 387.004306 -216.81567) (xy 386.648706 -216.81567) (xy 386.648706 -216.859866)
			(xy 386.695696 -217.012266) (xy 386.957316 -217.012266)
		)
		(stroke
			(width 0)
			(type solid)
		)
		(fill yes)
		(layer "In6.Cu")
		(net "M_G_CPU0_SB_DQ<28>")
	)
	(gr_poly
		(pts
			(xy 387.006592 -215.64092) (xy 386.959602 -215.48852) (xy 386.697982 -215.48852) (xy 386.650992 -215.64092)
			(xy 386.650992 -215.68537) (xy 387.006592 -215.68537)
		)
		(stroke
			(width 0)
			(type solid)
		)
		(fill yes)
		(layer "In6.Cu")
		(net "M_G_CPU0_SB_DQ<31>")
	)
	(gr_poly
		(pts
			(xy 387.012434 -241.685318) (xy 386.965444 -241.532918) (xy 386.703824 -241.532918) (xy 386.656834 -241.685318)
			(xy 386.656834 -241.729768) (xy 387.012434 -241.729768)
		)
		(stroke
			(width 0)
			(type solid)
		)
		(fill yes)
		(layer "In6.Cu")
		(net "M_G_CPU0_SB_DQ<2>")
	)
	(gr_poly
		(pts
			(xy 387.012434 -238.430054) (xy 386.965444 -238.277654) (xy 386.703824 -238.277654) (xy 386.656834 -238.430054)
			(xy 386.656834 -238.47425) (xy 387.012434 -238.47425)
		)
		(stroke
			(width 0)
			(type solid)
		)
		(fill yes)
		(layer "In6.Cu")
		(net "M_G_CPU0_SB_DQ<6>")
	)
	(gr_poly
		(pts
			(xy 387.012434 -233.54665) (xy 386.965444 -233.39425) (xy 386.703824 -233.39425) (xy 386.656834 -233.54665)
			(xy 386.656834 -233.590846) (xy 387.012434 -233.590846)
		)
		(stroke
			(width 0)
			(type solid)
		)
		(fill yes)
		(layer "In6.Cu")
		(net "M_G_CPU0_SB_DQS_DN<1>")
	)
	(gr_poly
		(pts
			(xy 387.012434 -220.52407) (xy 386.965444 -220.37167) (xy 386.703824 -220.37167) (xy 386.656834 -220.52407)
			(xy 386.656834 -220.56852) (xy 387.012434 -220.56852)
		)
		(stroke
			(width 0)
			(type solid)
		)
		(fill yes)
		(layer "In6.Cu")
		(net "M_G_CPU0_SB_DQ<26>")
	)
	(gr_poly
		(pts
			(xy 387.018276 -260.800088) (xy 386.979922 -260.77799) (xy 386.824474 -260.74243) (xy 386.693664 -260.968998)
			(xy 386.802122 -261.085838) (xy 386.840476 -261.107936)
		)
		(stroke
			(width 0)
			(type solid)
		)
		(fill yes)
		(layer "In6.Cu")
		(net "M_G_CPU0_SA_CB<6>")
	)
	(gr_poly
		(pts
			(xy 387.020816 -218.488006) (xy 387.020816 -218.44381) (xy 386.665216 -218.44381) (xy 386.665216 -218.488006)
			(xy 386.712206 -218.640406) (xy 386.973826 -218.640406)
		)
		(stroke
			(width 0)
			(type solid)
		)
		(fill yes)
		(layer "In6.Cu")
		(net "M_G_CPU0_SB_DQS_DP<3>")
	)
	(gr_poly
		(pts
			(xy 387.020816 -217.268298) (xy 386.973826 -217.115898) (xy 386.712206 -217.115898) (xy 386.665216 -217.268298)
			(xy 386.665216 -217.312748) (xy 387.020816 -217.312748)
		)
		(stroke
			(width 0)
			(type solid)
		)
		(fill yes)
		(layer "In6.Cu")
		(net "M_G_CPU0_SB_DQS_DP<8>")
	)
	(gr_poly
		(pts
			(xy 387.086094 -236.872272) (xy 386.977636 -236.755432) (xy 386.939282 -236.733334) (xy 386.761482 -237.041182)
			(xy 386.799836 -237.06328) (xy 386.955284 -237.09884)
		)
		(stroke
			(width 0)
			(type solid)
		)
		(fill yes)
		(layer "In6.Cu")
		(net "M_G_CPU0_SB_DQ<8>")
	)
	(gr_poly
		(pts
			(xy 387.11378 -269.587726) (xy 387.06679 -269.435326) (xy 386.80517 -269.435326) (xy 386.75818 -269.587726)
			(xy 386.75818 -269.631922) (xy 387.11378 -269.631922)
		)
		(stroke
			(width 0)
			(type solid)
		)
		(fill yes)
		(layer "In6.Cu")
		(net "M_G_CPU0_SA_DQ<26>")
	)
	(gr_poly
		(pts
			(xy 387.11378 -265.92403) (xy 387.11378 -265.879834) (xy 386.75818 -265.879834) (xy 386.75818 -265.92403)
			(xy 386.80517 -266.07643) (xy 387.06679 -266.07643)
		)
		(stroke
			(width 0)
			(type solid)
		)
		(fill yes)
		(layer "In6.Cu")
		(net "M_G_CPU0_SA_DQ<29>")
	)
	(gr_poly
		(pts
			(xy 387.11378 -264.704322) (xy 387.06679 -264.551922) (xy 386.80517 -264.551922) (xy 386.75818 -264.704322)
			(xy 386.75818 -264.748772) (xy 387.11378 -264.748772)
		)
		(stroke
			(width 0)
			(type solid)
		)
		(fill yes)
		(layer "In6.Cu")
		(net "M_G_CPU0_SA_CB<2>")
	)
	(gr_poly
		(pts
			(xy 387.11378 -264.296398) (xy 387.11378 -264.251948) (xy 386.75818 -264.251948) (xy 386.75818 -264.296398)
			(xy 386.80517 -264.448798) (xy 387.06679 -264.448798)
		)
		(stroke
			(width 0)
			(type solid)
		)
		(fill yes)
		(layer "In6.Cu")
		(net "M_G_CPU0_SA_CB<1>")
	)
	(gr_poly
		(pts
			(xy 387.115304 -269.179294) (xy 387.115304 -269.134844) (xy 386.759704 -269.134844) (xy 386.759704 -269.179294)
			(xy 386.806694 -269.331694) (xy 387.068314 -269.331694)
		)
		(stroke
			(width 0)
			(type solid)
		)
		(fill yes)
		(layer "In6.Cu")
		(net "M_G_CPU0_SA_DQ<25>")
	)
	(gr_poly
		(pts
			(xy 387.127496 -267.551662) (xy 387.127496 -267.507212) (xy 386.771896 -267.507212) (xy 386.771896 -267.551662)
			(xy 386.818886 -267.704062) (xy 387.080506 -267.704062)
		)
		(stroke
			(width 0)
			(type solid)
		)
		(fill yes)
		(layer "In6.Cu")
		(net "M_G_CPU0_SA_DQS_DN<8>")
	)
	(gr_poly
		(pts
			(xy 387.127496 -266.332462) (xy 387.080506 -266.180062) (xy 386.818886 -266.180062) (xy 386.771896 -266.332462)
			(xy 386.771896 -266.376658) (xy 387.127496 -266.376658)
		)
		(stroke
			(width 0)
			(type solid)
		)
		(fill yes)
		(layer "In6.Cu")
		(net "M_G_CPU0_SA_DQ<30>")
	)
	(gr_poly
		(pts
			(xy 387.128512 -280.98242) (xy 387.081522 -280.83002) (xy 386.819902 -280.83002) (xy 386.772912 -280.98242)
			(xy 386.772912 -281.026616) (xy 387.128512 -281.026616)
		)
		(stroke
			(width 0)
			(type solid)
		)
		(fill yes)
		(layer "In6.Cu")
		(net "M_H_CPU0_SA_DQ<2>")
	)
	(gr_poly
		(pts
			(xy 387.130036 -267.960094) (xy 387.083046 -267.807694) (xy 386.821426 -267.807694) (xy 386.774436 -267.960094)
			(xy 386.774436 -268.004544) (xy 387.130036 -268.004544)
		)
		(stroke
			(width 0)
			(type solid)
		)
		(fill yes)
		(layer "In6.Cu")
		(net "M_G_CPU0_SA_DQS_DN<3>")
	)
	(gr_poly
		(pts
			(xy 387.130798 -263.07669) (xy 387.083808 -262.92429) (xy 386.822188 -262.92429) (xy 386.775198 -263.07669)
			(xy 386.775198 -263.120886) (xy 387.130798 -263.120886)
		)
		(stroke
			(width 0)
			(type solid)
		)
		(fill yes)
		(layer "In6.Cu")
		(net "M_G_CPU0_SA_DQS_DN<4>")
	)
	(gr_poly
		(pts
			(xy 387.130798 -262.668258) (xy 387.130798 -262.624062) (xy 386.775198 -262.624062) (xy 386.775198 -262.668258)
			(xy 386.822188 -262.820658) (xy 387.083808 -262.820658)
		)
		(stroke
			(width 0)
			(type solid)
		)
		(fill yes)
		(layer "In6.Cu")
		(net "M_G_CPU0_SA_DQS_DN<9>")
	)
	(gr_poly
		(pts
			(xy 387.197092 -261.516622) (xy 387.088634 -261.399782) (xy 387.05028 -261.377684) (xy 386.87248 -261.685532)
			(xy 386.910834 -261.70763) (xy 387.066282 -261.74319)
		)
		(stroke
			(width 0)
			(type solid)
		)
		(fill yes)
		(layer "In6.Cu")
		(net "M_G_CPU0_SA_CB<4>")
	)
	(gr_poly
		(pts
			(xy 387.473698 -218.082622) (xy 387.426708 -217.930222) (xy 387.165088 -217.930222) (xy 387.118098 -218.082622)
			(xy 387.118098 -218.126818) (xy 387.473698 -218.126818)
		)
		(stroke
			(width 0)
			(type solid)
		)
		(fill yes)
		(layer "In6.Cu")
		(net "M_G_CPU0_SB_DQS_DN<3>")
	)
	(gr_poly
		(pts
			(xy 387.473698 -217.67419) (xy 387.473698 -217.629994) (xy 387.118098 -217.629994) (xy 387.118098 -217.67419)
			(xy 387.165088 -217.82659) (xy 387.426708 -217.82659)
		)
		(stroke
			(width 0)
			(type solid)
		)
		(fill yes)
		(layer "In6.Cu")
		(net "M_G_CPU0_SB_DQS_DN<8>")
	)
	(gr_poly
		(pts
			(xy 387.479794 -261.628382) (xy 387.44144 -261.606284) (xy 387.285992 -261.570724) (xy 387.155182 -261.797292)
			(xy 387.26364 -261.914132) (xy 387.301994 -261.93623)
		)
		(stroke
			(width 0)
			(type solid)
		)
		(fill yes)
		(layer "In6.Cu")
		(net "M_G_CPU0_SA_DQS_DP<9>")
	)
	(gr_poly
		(pts
			(xy 387.482334 -220.929454) (xy 387.482334 -220.885258) (xy 387.126734 -220.885258) (xy 387.126734 -220.929454)
			(xy 387.173724 -221.081854) (xy 387.435344 -221.081854)
		)
		(stroke
			(width 0)
			(type solid)
		)
		(fill yes)
		(layer "In6.Cu")
		(net "M_G_CPU0_SB_DQ<24>")
	)
	(gr_poly
		(pts
			(xy 387.488176 -216.453974) (xy 387.441186 -216.301574) (xy 387.179566 -216.301574) (xy 387.132576 -216.453974)
			(xy 387.132576 -216.498424) (xy 387.488176 -216.498424)
		)
		(stroke
			(width 0)
			(type solid)
		)
		(fill yes)
		(layer "In6.Cu")
		(net "M_G_CPU0_SB_DQ<30>")
	)
	(gr_poly
		(pts
			(xy 387.585204 -268.365478) (xy 387.585204 -268.321028) (xy 387.229604 -268.321028) (xy 387.229604 -268.365478)
			(xy 387.276594 -268.517878) (xy 387.538214 -268.517878)
		)
		(stroke
			(width 0)
			(type solid)
		)
		(fill yes)
		(layer "In6.Cu")
		(net "M_G_CPU0_SA_DQS_DP<3>")
	)
	(gr_poly
		(pts
			(xy 387.585204 -266.737846) (xy 387.585204 -266.693396) (xy 387.229604 -266.693396) (xy 387.229604 -266.737846)
			(xy 387.276594 -266.890246) (xy 387.538214 -266.890246)
		)
		(stroke
			(width 0)
			(type solid)
		)
		(fill yes)
		(layer "In6.Cu")
		(net "M_G_CPU0_SA_DQ<28>")
	)
	(gr_poly
		(pts
			(xy 387.592062 -263.481566) (xy 387.592062 -263.43737) (xy 387.236462 -263.43737) (xy 387.236462 -263.481566)
			(xy 387.283452 -263.633966) (xy 387.545072 -263.633966)
		)
		(stroke
			(width 0)
			(type solid)
		)
		(fill yes)
		(layer "In6.Cu")
		(net "M_G_CPU0_SA_DQS_DP<4>")
	)
	(gr_poly
		(pts
			(xy 387.597142 -268.77391) (xy 387.550152 -268.62151) (xy 387.288532 -268.62151) (xy 387.241542 -268.77391)
			(xy 387.241542 -268.81836) (xy 387.597142 -268.81836)
		)
		(stroke
			(width 0)
			(type solid)
		)
		(fill yes)
		(layer "In6.Cu")
		(net "M_G_CPU0_SA_DQ<27>")
	)
	(gr_poly
		(pts
			(xy 387.597142 -267.146278) (xy 387.550152 -266.993878) (xy 387.288532 -266.993878) (xy 387.241542 -267.146278)
			(xy 387.241542 -267.190474) (xy 387.597142 -267.190474)
		)
		(stroke
			(width 0)
			(type solid)
		)
		(fill yes)
		(layer "In6.Cu")
		(net "M_G_CPU0_SA_DQS_DP<8>")
	)
	(gr_poly
		(pts
			(xy 387.600698 -265.518138) (xy 387.553708 -265.365738) (xy 387.292088 -265.365738) (xy 387.245098 -265.518138)
			(xy 387.245098 -265.562588) (xy 387.600698 -265.562588)
		)
		(stroke
			(width 0)
			(type solid)
		)
		(fill yes)
		(layer "In6.Cu")
		(net "M_G_CPU0_SA_DQ<31>")
	)
	(gr_poly
		(pts
			(xy 387.665976 -262.332978) (xy 387.557518 -262.216138) (xy 387.519164 -262.19404) (xy 387.341364 -262.501888)
			(xy 387.379718 -262.523986) (xy 387.535166 -262.559546)
		)
		(stroke
			(width 0)
			(type solid)
		)
		(fill yes)
		(layer "In6.Cu")
		(net "M_G_CPU0_SA_DQS_DN<9>")
	)
	(gr_poly
		(pts
			(xy 387.944106 -216.859866) (xy 387.944106 -216.81567) (xy 387.588506 -216.81567) (xy 387.588506 -216.859866)
			(xy 387.635496 -217.012266) (xy 387.897116 -217.012266)
		)
		(stroke
			(width 0)
			(type solid)
		)
		(fill yes)
		(layer "In6.Cu")
		(net "M_G_CPU0_SB_DQ<28>")
	)
	(gr_poly
		(pts
			(xy 387.952234 -220.52407) (xy 387.905244 -220.37167) (xy 387.643624 -220.37167) (xy 387.596634 -220.52407)
			(xy 387.596634 -220.56852) (xy 387.952234 -220.56852)
		)
		(stroke
			(width 0)
			(type solid)
		)
		(fill yes)
		(layer "In6.Cu")
		(net "M_G_CPU0_SB_DQ<26>")
	)
	(gr_poly
		(pts
			(xy 387.960616 -218.896438) (xy 387.913626 -218.744038) (xy 387.652006 -218.744038) (xy 387.605016 -218.896438)
			(xy 387.605016 -218.940634) (xy 387.960616 -218.940634)
		)
		(stroke
			(width 0)
			(type solid)
		)
		(fill yes)
		(layer "In6.Cu")
		(net "M_G_CPU0_SB_DQ<27>")
	)
	(gr_poly
		(pts
			(xy 387.960616 -218.488006) (xy 387.960616 -218.44381) (xy 387.605016 -218.44381) (xy 387.605016 -218.488006)
			(xy 387.652006 -218.640406) (xy 387.913626 -218.640406)
		)
		(stroke
			(width 0)
			(type solid)
		)
		(fill yes)
		(layer "In6.Cu")
		(net "M_G_CPU0_SB_DQS_DP<3>")
	)
	(gr_poly
		(pts
			(xy 387.960616 -217.268298) (xy 387.913626 -217.115898) (xy 387.652006 -217.115898) (xy 387.605016 -217.268298)
			(xy 387.605016 -217.312748) (xy 387.960616 -217.312748)
		)
		(stroke
			(width 0)
			(type solid)
		)
		(fill yes)
		(layer "In6.Cu")
		(net "M_G_CPU0_SB_DQS_DP<8>")
	)
	(gr_poly
		(pts
			(xy 388.067042 -266.332462) (xy 388.020052 -266.180062) (xy 387.758432 -266.180062) (xy 387.711442 -266.332462)
			(xy 387.711442 -266.376658) (xy 388.067042 -266.376658)
		)
		(stroke
			(width 0)
			(type solid)
		)
		(fill yes)
		(layer "In6.Cu")
		(net "M_G_CPU0_SA_DQ<30>")
	)
	(gr_poly
		(pts
			(xy 388.413498 -219.301822) (xy 388.413498 -219.257626) (xy 388.057898 -219.257626) (xy 388.057898 -219.301822)
			(xy 388.104888 -219.454222) (xy 388.366508 -219.454222)
		)
		(stroke
			(width 0)
			(type solid)
		)
		(fill yes)
		(layer "In6.Cu")
		(net "M_G_CPU0_SB_DQ<25>")
	)
	(gr_poly
		(pts
			(xy 388.413498 -218.082622) (xy 388.366508 -217.930222) (xy 388.104888 -217.930222) (xy 388.057898 -218.082622)
			(xy 388.057898 -218.126818) (xy 388.413498 -218.126818)
		)
		(stroke
			(width 0)
			(type solid)
		)
		(fill yes)
		(layer "In6.Cu")
		(net "M_G_CPU0_SB_DQS_DN<3>")
	)
	(gr_poly
		(pts
			(xy 388.413498 -217.67419) (xy 388.413498 -217.629994) (xy 388.057898 -217.629994) (xy 388.057898 -217.67419)
			(xy 388.104888 -217.82659) (xy 388.366508 -217.82659)
		)
		(stroke
			(width 0)
			(type solid)
		)
		(fill yes)
		(layer "In6.Cu")
		(net "M_G_CPU0_SB_DQS_DN<8>")
	)
	(gr_poly
		(pts
			(xy 388.481316 -221.051374) (xy 388.501128 -220.893132) (xy 388.493254 -220.849444) (xy 388.143242 -220.91142)
			(xy 388.150862 -220.954854) (xy 388.223506 -221.09684)
		)
		(stroke
			(width 0)
			(type solid)
		)
		(fill yes)
		(layer "In6.Cu")
		(net "M_G_CPU0_SB_DQ<24>")
	)
	(gr_poly
		(pts
			(xy 388.900416 -218.896438) (xy 388.853426 -218.744038) (xy 388.591806 -218.744038) (xy 388.544816 -218.896438)
			(xy 388.544816 -218.940634) (xy 388.900416 -218.940634)
		)
		(stroke
			(width 0)
			(type solid)
		)
		(fill yes)
		(layer "In6.Cu")
		(net "M_G_CPU0_SB_DQ<27>")
	)
	(gr_poly
		(pts
			(xy 388.900416 -218.488006) (xy 388.900416 -218.44381) (xy 388.544816 -218.44381) (xy 388.544816 -218.488006)
			(xy 388.591806 -218.640406) (xy 388.853426 -218.640406)
		)
		(stroke
			(width 0)
			(type solid)
		)
		(fill yes)
		(layer "In6.Cu")
		(net "M_G_CPU0_SB_DQS_DP<3>")
	)
	(gr_poly
		(pts
			(xy 389.353298 -219.301822) (xy 389.353298 -219.257626) (xy 388.997698 -219.257626) (xy 388.997698 -219.301822)
			(xy 389.044688 -219.454222) (xy 389.306308 -219.454222)
		)
		(stroke
			(width 0)
			(type solid)
		)
		(fill yes)
		(layer "In6.Cu")
		(net "M_G_CPU0_SB_DQ<25>")
	)
	(gr_poly
		(pts
			(xy 110.813596 -361.032806) (xy 110.813596 -356.664006) (xy 110.762796 -356.613206) (xy 106.393996 -356.613206)
			(xy 106.343196 -356.664006) (xy 106.343196 -360.684064) (xy 106.742738 -361.083606) (xy 110.762796 -361.083606)
		)
		(stroke
			(width 0)
			(type solid)
		)
		(fill yes)
		(layer "In6.Cu")
		(net "GND")
	)
	(gr_poly
		(pts
			(xy 249.511312 -89.374472) (xy 249.511312 -86.478872) (xy 249.333512 -86.301072) (xy 246.477536 -86.301072)
			(xy 245.752112 -87.026496) (xy 245.752112 -89.653872) (xy 245.79326 -89.69502) (xy 249.190764 -89.69502)
		)
		(stroke
			(width 0)
			(type solid)
		)
		(fill yes)
		(layer "In6.Cu")
		(net "GND")
	)
	(gr_poly
		(pts
			(xy 326.70242 -32.253428) (xy 326.70242 -31.360872) (xy 324.176644 -28.835096) (xy 323.624194 -28.835096)
			(xy 321.00901 -31.45028) (xy 321.00901 -31.812484) (xy 323.807074 -34.610548) (xy 324.3453 -34.610548)
		)
		(stroke
			(width 0)
			(type solid)
		)
		(fill yes)
		(layer "In6.Cu")
		(net "GND")
	)
	(gr_poly
		(pts
			(xy 337.936586 -69.898514) (xy 337.936586 -67.25412) (xy 337.568032 -66.885566) (xy 333.806038 -66.885566)
			(xy 333.422244 -67.26936) (xy 333.422244 -70.586092) (xy 333.54518 -70.709028) (xy 337.126072 -70.709028)
		)
		(stroke
			(width 0)
			(type solid)
		)
		(fill yes)
		(layer "In6.Cu")
		(net "GND")
	)
	(gr_poly
		(pts
			(xy 427.559216 -138.21791) (xy 427.559216 -134.61111) (xy 427.508416 -134.56031) (xy 423.901616 -134.56031)
			(xy 423.850816 -134.61111) (xy 423.850816 -138.21791) (xy 423.901616 -138.26871) (xy 427.508416 -138.26871)
		)
		(stroke
			(width 0)
			(type solid)
		)
		(fill yes)
		(layer "In6.Cu")
		(net "GND")
	)
	(gr_poly
		(pts
			(xy 281.26436 -393.41806) (xy 281.26436 -392.811) (xy 282.9687 -391.10666) (xy 289.99688 -391.10666)
			(xy 290.5379 -391.64768) (xy 291.2237 -391.64768) (xy 291.28974 -391.58164) (xy 291.28974 -391.05078)
			(xy 290.54806 -390.3091) (xy 282.64104 -390.3091) (xy 280.30932 -392.64082) (xy 280.30932 -393.78636)
			(xy 280.36774 -393.84478) (xy 280.83764 -393.84478)
		)
		(stroke
			(width 0)
			(type solid)
		)
		(fill yes)
		(layer "In6.Cu")
		(net "P12V_HSC_GATE1")
	)
	(gr_poly
		(pts
			(xy 230.38054 -434.93182) (xy 230.38054 -427.00194) (xy 230.38689 -426.99559) (xy 230.38689 -423.32275)
			(xy 233.07548 -420.63416) (xy 270.3576 -420.63416) (xy 275.73224 -415.25952) (xy 279.97912 -415.25952)
			(xy 280.19756 -415.04108) (xy 280.19756 -408.29992) (xy 279.96896 -408.07132) (xy 239.84458 -408.07132)
			(xy 233.0704 -414.8455) (xy 207.34528 -414.8455) (xy 206.49184 -415.69894) (xy 206.49184 -435.39156)
			(xy 207.63484 -436.53456) (xy 228.7778 -436.53456)
		)
		(stroke
			(width 0)
			(type solid)
		)
		(fill yes)
		(layer "In6.Cu")
		(net "P12V_PSU")
	)
	(gr_poly
		(pts
			(arc
				(start 150.250652 -39.515288)
				(mid 150.54834 -39.354795)
				(end 150.846028 -39.515288)
			)
			(xy 151.5364 -39.515288) (xy 151.70658 -39.345108) (xy 151.70658 -35.753548) (xy 151.491188 -35.538156)
			(xy 148.950172 -35.538156) (xy 148.73732 -35.751008) (xy 148.73732 -39.258748) (xy 148.99386 -39.515288)
		)
		(stroke
			(width 0)
			(type solid)
		)
		(fill yes)
		(layer "In6.Cu")
		(net "GND")
	)
	(gr_poly
		(pts
			(arc
				(start 6.88721 -170.189144)
				(mid 6.63321 -170.189144)
				(end 6.88721 -170.189144)
			)
		)
		(stroke
			(width 0)
			(type solid)
		)
		(fill yes)
		(layer "In6.Cu")
		(net "GND")
	)
	(gr_poly
		(pts
			(arc
				(start 9.83488 -151.348948)
				(mid 9.58088 -151.348948)
				(end 9.83488 -151.348948)
			)
		)
		(stroke
			(width 0)
			(type solid)
		)
		(fill yes)
		(layer "In6.Cu")
		(net "GND")
	)
	(gr_poly
		(pts
			(arc
				(start 342.232742 -21.059648)
				(mid 341.901018 -21.059648)
				(end 342.232742 -21.059648)
			)
		)
		(stroke
			(width 0)
			(type solid)
		)
		(fill yes)
		(layer "In6.Cu")
		(net "GND")
	)
	(gr_poly
		(pts
			(arc
				(start 343.205562 -25.814528)
				(mid 342.873838 -25.814528)
				(end 343.205562 -25.814528)
			)
		)
		(stroke
			(width 0)
			(type solid)
		)
		(fill yes)
		(layer "In6.Cu")
		(net "GND")
	)
	(gr_poly
		(pts
			(xy 217.33256 -26.947368) (xy 217.33256 -25.212548) (xy 216.7382 -24.618188)
			(arc
				(start 213.378288 -24.618188)
				(mid 213.29959 -24.655529)
				(end 213.27872 -24.740108)
			)
			(arc
				(start 213.27872 -24.740108)
				(mid 213.293585 -24.838289)
				(end 213.298532 -24.937466)
			)
			(arc
				(start 213.298532 -26.891234)
				(mid 213.313411 -26.927155)
				(end 213.349332 -26.942034)
			)
			(arc
				(start 213.349332 -26.942034)
				(mid 213.72514 -27.01805)
				(end 214.043768 -27.23134)
			)
			(xy 214.442802 -27.630628) (xy 216.6493 -27.630628)
		)
		(stroke
			(width 0)
			(type solid)
		)
		(fill yes)
		(layer "In6.Cu")
		(net "GND")
	)
	(gr_poly
		(pts
			(arc
				(start 357.198676 -362.65866)
				(mid 357.30946 -362.680696)
				(end 357.372158 -362.586778)
			)
			(xy 357.372158 -357.11003) (xy 358.408224 -356.073964) (xy 358.408224 -356.058978)
			(arc
				(start 358.315006 -355.965506)
				(mid 358.276115 -355.907631)
				(end 358.262428 -355.839268)
			)
			(xy 358.262428 -355.55682)
			(arc
				(start 358.19588 -355.490272)
				(mid 358.183232 -355.397804)
				(end 358.100376 -355.354636)
			)
			(xy 357.051356 -355.354636) (xy 356.149148 -356.256844) (xy 356.149148 -361.608878)
		)
		(stroke
			(width 0)
			(type solid)
		)
		(fill yes)
		(layer "In6.Cu")
		(net "GND")
	)
	(gr_poly
		(pts
			(xy 245.05412 -251.739908) (xy 245.05412 -247.264428) (xy 244.602 -246.812308) (xy 240.55578 -246.812308)
			(xy 240.2205 -247.147588) (xy 240.2205 -249.273568) (xy 240.806222 -249.273568) (xy 240.810293 -249.217946)
			(xy 240.822419 -249.163509) (xy 240.842342 -249.111418) (xy 240.869638 -249.062783) (xy 240.903724 -249.01864)
			(xy 240.943873 -248.979931) (xy 240.989231 -248.94748) (xy 241.038831 -248.921979) (xy 241.091615 -248.903972)
			(xy 241.146458 -248.893842) (xy 241.202192 -248.891805) (xy 241.257629 -248.897905) (xy 241.311586 -248.912011)
			(xy 241.362915 -248.933823) (xy 241.410521 -248.962877) (xy 241.453389 -248.998552) (xy 241.490606 -249.040089)
			(xy 241.521379 -249.086602) (xy 241.545051 -249.137099) (xy 241.561119 -249.190506) (xy 241.569239 -249.245682)
			(xy 241.569748 -249.273568) (xy 241.569239 -249.301454) (xy 241.561119 -249.35663) (xy 241.545051 -249.410037)
			(xy 241.521379 -249.460534) (xy 241.490606 -249.507047) (xy 241.453389 -249.548584) (xy 241.410521 -249.584259)
			(xy 241.362915 -249.613313) (xy 241.311586 -249.635125) (xy 241.257629 -249.649231) (xy 241.202192 -249.655331)
			(xy 241.146458 -249.653294) (xy 241.091615 -249.643164) (xy 241.038831 -249.625157) (xy 240.989231 -249.599656)
			(xy 240.943873 -249.567205) (xy 240.903724 -249.528496) (xy 240.869638 -249.484353) (xy 240.842342 -249.435718)
			(xy 240.822419 -249.383627) (xy 240.810293 -249.32919) (xy 240.806222 -249.273568) (xy 240.2205 -249.273568)
			(xy 240.2205 -251.935488) (xy 240.48974 -252.204728) (xy 244.5893 -252.204728)
		)
		(stroke
			(width 0)
			(type solid)
		)
		(fill yes)
		(layer "In6.Cu")
		(net "GND")
	)
	(gr_poly
		(pts
			(xy 290.50742 -396.47368) (xy 290.50742 -393.59332) (xy 290.36264 -393.44854) (xy 289.64382 -393.44854)
			(xy 289.4457 -393.64666) (xy 289.4457 -395.82598) (xy 288.81451 -396.45717) (xy 279.99817 -396.45717)
			(xy 279.9842 -396.47114) (xy 275.7043 -396.47114) (xy 275.2344 -396.00124) (xy 275.2344 -394.70838)
			(xy 275.10232 -394.5763) (xy 274.83562 -394.5763) (xy 274.61718 -394.79474) (xy 274.61718 -396.01648)
			(xy 274.17776 -396.4559) (xy 269.7353 -396.4559) (xy 269.3543 -396.0749) (xy 269.3543 -394.6652)
			(xy 269.2654 -394.5763) (xy 268.95806 -394.5763) (xy 268.81074 -394.72362) (xy 268.81074 -396.02918)
			(xy 268.45768 -396.38224) (xy 263.67994 -396.38224) (xy 263.40054 -396.10284) (xy 263.40054 -394.63472)
			(xy 263.26846 -394.50264) (xy 263.01954 -394.50264) (xy 262.78332 -394.73886) (xy 262.78332 -396.11808)
			(xy 262.5471 -396.3543) (xy 257.90398 -396.3543) (xy 257.46202 -395.91234) (xy 257.46202 -394.69314)
			(xy 257.34518 -394.5763) (xy 257.08102 -394.5763) (xy 256.87528 -394.78204) (xy 256.87528 -395.86916)
			(xy 256.43586 -396.30858) (xy 251.83338 -396.30858) (xy 251.55398 -396.02918) (xy 251.55398 -394.70838)
			(xy 251.44984 -394.60424) (xy 251.0409 -394.60424) (xy 250.99518 -394.64996) (xy 250.99518 -395.64818)
			(xy 250.3043 -396.33906) (xy 246.0879 -396.33906) (xy 245.58752 -395.83868) (xy 245.58752 -394.70838)
			(xy 245.38178 -394.50264) (xy 245.14302 -394.50264) (xy 245.01094 -394.63472) (xy 245.01094 -396.80642)
			(xy 245.53164 -397.32712) (xy 289.65398 -397.32712)
		)
		(stroke
			(width 0)
			(type solid)
		)
		(fill yes)
		(layer "In6.Cu")
		(net "P12V_HSC_GATE2")
	)
	(gr_poly
		(pts
			(xy 350.297496 -365.166402) (xy 349.739712 -364.608364)
			(arc
				(start 348.0435 -364.608364)
				(mid 347.728922 -364.478114)
				(end 347.598492 -364.16361)
			)
			(arc
				(start 347.599 -364.14456)
				(mid 347.570709 -364.070136)
				(end 347.4974 -364.038896)
			)
			(xy 347.37548 -364.038896)
			(arc
				(start 347.334332 -364.036864)
				(mid 347.233035 -364.094799)
				(end 347.253052 -364.209838)
			)
			(arc
				(start 349.741744 -366.698784)
				(mid 349.821772 -366.818321)
				(end 349.849948 -366.959388)
			)
			(arc
				(start 349.849948 -371.574568)
				(mid 349.821776 -371.715637)
				(end 349.741744 -371.835172)
			)
			(arc
				(start 346.698316 -374.8786)
				(mid 346.578779 -374.958628)
				(end 346.437712 -374.986804)
			)
			(xy 331.431646 -374.986804)
			(arc
				(start 325.75754 -380.66091)
				(mid 325.735381 -380.771543)
				(end 325.829168 -380.834392)
			)
			(xy 350.297496 -380.834392)
		)
		(stroke
			(width 0)
			(type solid)
		)
		(fill yes)
		(layer "In6.Cu")
		(net "GND")
	)
	(gr_poly
		(pts
			(xy 467.789514 -176.753774)
			(arc
				(start 467.789514 -82.82813)
				(mid 467.980666 -81.867526)
				(end 468.524844 -81.053178)
			)
			(arc
				(start 470.853262 -78.72476)
				(mid 471.176045 -78.241587)
				(end 471.28938 -77.671676)
			)
			(arc
				(start 471.28938 -26.830528)
				(mid 471.282263 -26.804596)
				(end 471.262964 -26.785824)
			)
			(xy 471.17254 -26.736294) (xy 471.145108 -26.73731)
			(arc
				(start 471.13317 -26.744676)
				(mid 470.972569 -26.843078)
				(end 470.808558 -26.935684)
			)
			(arc
				(start 470.808558 -26.935684)
				(mid 470.789062 -26.95436)
				(end 470.781888 -26.980388)
			)
			(arc
				(start 470.781888 -77.67193)
				(mid 470.707224 -78.04756)
				(end 470.494614 -78.366112)
			)
			(arc
				(start 468.166196 -80.69453)
				(mid 467.512084 -81.673433)
				(end 467.282276 -82.82813)
			)
			(xy 467.282276 -115.104926) (xy 467.284816 -115.116356)
			(arc
				(start 467.287864 -115.121944)
				(mid 467.319142 -115.206449)
				(end 467.329774 -115.295934)
			)
			(arc
				(start 467.329774 -115.295934)
				(mid 467.31919 -115.38543)
				(end 467.287864 -115.469924)
			)
			(xy 467.284816 -115.475512) (xy 467.282276 -115.486942) (xy 467.282276 -176.774348) (xy 467.338156 -176.830228)
			(xy 467.71306 -176.830228)
		)
		(stroke
			(width 0)
			(type solid)
		)
		(fill yes)
		(layer "In6.Cu")
		(net "GND")
	)
	(gr_poly
		(pts
			(xy 10.35558 -100.975668)
			(arc
				(start 10.35558 -100.736908)
				(mid 10.269496 -100.495608)
				(end 10.35558 -100.254308)
			)
			(arc
				(start 10.35558 -100.03917)
				(mid 10.302076 -99.949675)
				(end 10.197846 -99.954334)
			)
			(arc
				(start 10.197846 -99.954334)
				(mid 10.09724 -100.001603)
				(end 9.98728 -100.017834)
			)
			(arc
				(start 9.98728 -100.017834)
				(mid 9.605772 -99.636326)
				(end 9.98728 -99.254818)
			)
			(arc
				(start 9.98728 -99.254818)
				(mid 10.097231 -99.271082)
				(end 10.197846 -99.318318)
			)
			(arc
				(start 10.197846 -99.318318)
				(mid 10.302135 -99.323088)
				(end 10.35558 -99.233482)
			)
			(xy 10.35558 -98.755962)
			(arc
				(start 10.315702 -98.747072)
				(mid 10.017245 -98.374708)
				(end 10.315702 -98.002344)
			)
			(xy 10.35558 -97.993454) (xy 10.35558 -97.711768) (xy 9.72566 -97.081848) (xy 6.02742 -97.081848)
			(xy 5.44576 -97.663508) (xy 5.44576 -100.912168) (xy 5.91312 -101.379528) (xy 9.95172 -101.379528)
		)
		(stroke
			(width 0)
			(type solid)
		)
		(fill yes)
		(layer "In6.Cu")
		(net "GND")
	)
	(gr_poly
		(pts
			(xy 251.75464 -51.589686) (xy 251.75464 -47.231046)
			(arc
				(start 251.697236 -47.173642)
				(mid 251.601114 -47.147047)
				(end 251.52858 -47.215552)
			)
			(arc
				(start 251.52858 -47.215552)
				(mid 251.390416 -47.409616)
				(end 251.16409 -47.48403)
			)
			(arc
				(start 251.16409 -47.48403)
				(mid 250.894323 -47.372289)
				(end 250.782582 -47.102522)
			)
			(arc
				(start 250.782582 -47.102522)
				(mid 250.794735 -47.006741)
				(end 250.830588 -46.917102)
			)
			(arc
				(start 250.830588 -46.917102)
				(mid 250.829331 -46.816347)
				(end 250.741942 -46.766226)
			)
			(xy 248.65076 -46.766226) (xy 245.98122 -44.096686) (xy 245.98122 -41.490646) (xy 245.30558 -40.815006)
			(xy 243.1034 -40.815006) (xy 241.36604 -42.552366) (xy 238.40948 -42.552366) (xy 237.20298 -43.758866)
			(xy 237.20298 -44.853606) (xy 237.47476 -45.125386) (xy 240.65992 -45.125386) (xy 240.99774 -45.463206)
			(arc
				(start 240.99774 -46.485048)
				(mid 241.025813 -46.555165)
				(end 241.094514 -46.586648)
			)
			(arc
				(start 241.094514 -46.586648)
				(mid 241.457907 -46.967648)
				(end 241.094514 -47.348648)
			)
			(arc
				(start 241.094514 -47.348648)
				(mid 241.02573 -47.380052)
				(end 240.99774 -47.450248)
			)
			(arc
				(start 240.99774 -48.500792)
				(mid 241.034196 -48.578759)
				(end 241.117374 -48.600614)
			)
			(arc
				(start 241.117374 -48.600614)
				(mid 241.1514 -48.596037)
				(end 241.1857 -48.594518)
			)
			(arc
				(start 241.1857 -48.594518)
				(mid 241.455467 -48.706259)
				(end 241.567208 -48.976026)
			)
			(arc
				(start 241.567208 -48.976026)
				(mid 241.541521 -49.113696)
				(end 241.467894 -49.23282)
			)
			(arc
				(start 241.467894 -49.23282)
				(mid 241.450173 -49.342254)
				(end 241.543078 -49.402746)
			)
			(xy 244.25402 -49.402746) (xy 246.66702 -51.815746) (xy 251.52858 -51.815746)
		)
		(stroke
			(width 0)
			(type solid)
		)
		(fill yes)
		(layer "In6.Cu")
		(net "P12V_E1S_0")
	)
	(gr_poly
		(pts
			(xy 71.71944 -180.194204) (xy 71.71944 -173.891448) (xy 71.279004 -173.451012) (xy 68.248276 -173.451012)
			(xy 66.52006 -171.72305) (xy 65.85966 -171.06265) (xy 61.143134 -171.06265) (xy 61.110114 -171.09567)
			(xy 61.061854 -171.09567) (xy 60.661804 -171.49572) (xy 60.661804 -177.947504) (xy 67.755004 -177.947504)
			(xy 67.755004 -177.862808) (xy 67.763055 -177.778494) (xy 67.779084 -177.695328) (xy 67.802945 -177.614061)
			(xy 67.834424 -177.535431) (xy 67.873235 -177.46015) (xy 67.919025 -177.388898) (xy 67.971381 -177.322322)
			(xy 68.029829 -177.261024) (xy 68.093839 -177.205559) (xy 68.162831 -177.15643) (xy 68.236181 -177.114081)
			(xy 68.313224 -177.078897) (xy 68.393263 -177.051195) (xy 68.475572 -177.031227) (xy 68.559407 -177.019174)
			(xy 68.644008 -177.015144) (xy 68.728609 -177.019174) (xy 68.812444 -177.031227) (xy 68.894753 -177.051195)
			(xy 68.974792 -177.078897) (xy 69.051835 -177.114081) (xy 69.125185 -177.15643) (xy 69.194177 -177.205559)
			(xy 69.258187 -177.261024) (xy 69.316635 -177.322322) (xy 69.368991 -177.388898) (xy 69.414781 -177.46015)
			(xy 69.453592 -177.535431) (xy 69.485071 -177.614061) (xy 69.508932 -177.695328) (xy 69.524961 -177.778494)
			(xy 69.533012 -177.862808) (xy 69.533516 -177.905156) (xy 69.728593 -177.905156) (xy 69.732615 -177.819436)
			(xy 69.744646 -177.734468) (xy 69.764582 -177.651001) (xy 69.792245 -177.569767) (xy 69.827394 -177.491481)
			(xy 69.86972 -177.41683) (xy 69.918849 -177.346471) (xy 69.974352 -177.281021) (xy 70.035739 -177.221057)
			(xy 70.102472 -177.167104) (xy 70.173964 -177.119637) (xy 70.249586 -177.079073) (xy 70.328675 -177.045769)
			(xy 70.410535 -177.020017) (xy 70.494446 -177.002044) (xy 70.579672 -176.992008) (xy 70.665464 -176.989996)
			(xy 70.751066 -176.996027) (xy 70.835728 -177.010047) (xy 70.918705 -177.031933) (xy 70.999268 -177.061494)
			(xy 71.076708 -177.098468) (xy 71.150347 -177.142532) (xy 71.219535 -177.193298) (xy 71.283666 -177.250319)
			(xy 71.342175 -177.313095) (xy 71.394548 -177.381075) (xy 71.440326 -177.45366) (xy 71.479106 -177.530212)
			(xy 71.510547 -177.61006) (xy 71.534373 -177.692501) (xy 71.550374 -177.776811) (xy 71.558409 -177.862249)
			(xy 71.558912 -177.905156) (xy 71.558409 -177.948063) (xy 71.550374 -178.033501) (xy 71.534373 -178.117811)
			(xy 71.510547 -178.200252) (xy 71.479106 -178.2801) (xy 71.440326 -178.356652) (xy 71.394548 -178.429237)
			(xy 71.342175 -178.497217) (xy 71.283666 -178.559993) (xy 71.219535 -178.617014) (xy 71.150347 -178.66778)
			(xy 71.076708 -178.711844) (xy 70.999268 -178.748818) (xy 70.918705 -178.778379) (xy 70.835728 -178.800265)
			(xy 70.751066 -178.814285) (xy 70.665464 -178.820316) (xy 70.579672 -178.818304) (xy 70.494446 -178.808268)
			(xy 70.410535 -178.790295) (xy 70.328675 -178.764543) (xy 70.249586 -178.731239) (xy 70.173964 -178.690675)
			(xy 70.102472 -178.643208) (xy 70.035739 -178.589255) (xy 69.974352 -178.529291) (xy 69.918849 -178.463841)
			(xy 69.86972 -178.393482) (xy 69.827394 -178.318831) (xy 69.792245 -178.240545) (xy 69.764582 -178.159311)
			(xy 69.744646 -178.075844) (xy 69.732615 -177.990876) (xy 69.728593 -177.905156) (xy 69.533516 -177.905156)
			(xy 69.533012 -177.947504) (xy 69.524961 -178.031818) (xy 69.508932 -178.114984) (xy 69.485071 -178.196251)
			(xy 69.453592 -178.274881) (xy 69.414781 -178.350162) (xy 69.368991 -178.421414) (xy 69.316635 -178.48799)
			(xy 69.258187 -178.549288) (xy 69.194177 -178.604753) (xy 69.125185 -178.653882) (xy 69.051835 -178.696231)
			(xy 68.974792 -178.731415) (xy 68.894753 -178.759117) (xy 68.812444 -178.779085) (xy 68.728609 -178.791138)
			(xy 68.644008 -178.795169) (xy 68.559407 -178.791138) (xy 68.475572 -178.779085) (xy 68.393263 -178.759117)
			(xy 68.313224 -178.731415) (xy 68.236181 -178.696231) (xy 68.162831 -178.653882) (xy 68.093839 -178.604753)
			(xy 68.029829 -178.549288) (xy 67.971381 -178.48799) (xy 67.919025 -178.421414) (xy 67.873235 -178.350162)
			(xy 67.834424 -178.274881) (xy 67.802945 -178.196251) (xy 67.779084 -178.114984) (xy 67.763055 -178.031818)
			(xy 67.755004 -177.947504) (xy 60.661804 -177.947504) (xy 60.661804 -180.67401) (xy 61.148468 -181.160674)
			(xy 70.75297 -181.160674)
		)
		(stroke
			(width 0)
			(type solid)
		)
		(fill yes)
		(layer "In6.Cu")
		(net "PVCCFA_EHV_CPU1")
	)
	(gr_poly
		(pts
			(xy 201.7014 -31.156148) (xy 201.7014 -28.539948) (xy 198.14794 -24.986488) (xy 198.14794 -22.749256)
			(xy 198.147686 -22.74697) (xy 198.138762 -22.635425) (xy 198.129232 -22.411829) (xy 198.128636 -22.29993)
			(xy 198.129245 -22.188031) (xy 198.138772 -21.964435) (xy 198.147686 -21.85289) (xy 198.14794 -21.850604)
			(xy 198.14794 -18.179288) (xy 195.477892 -15.50924) (xy 192.954148 -15.007336) (xy 191.574166 -15.007336)
			(xy 191.567054 -15.0495) (xy 191.562174 -15.075861) (xy 191.545997 -15.126972) (xy 191.522825 -15.175315)
			(xy 191.493116 -15.21994) (xy 191.457453 -15.259968) (xy 191.416539 -15.29461) (xy 191.371179 -15.323184)
			(xy 191.322266 -15.345129) (xy 191.270764 -15.360012) (xy 191.217685 -15.36754) (xy 191.19088 -15.368016)
			(xy 191.174737 -15.367886) (xy 191.142561 -15.365219) (xy 191.126618 -15.362682) (xy 191.111992 -15.360701)
			(xy 191.082708 -15.364274) (xy 191.055663 -15.37606) (xy 191.03311 -15.395079) (xy 191.016928 -15.419747)
			(xy 191.008464 -15.448008) (xy 191.008 -15.462758) (xy 191.008 -17.503648) (xy 196.228968 -17.503648)
			(xy 196.233039 -17.448026) (xy 196.245165 -17.393589) (xy 196.265088 -17.341498) (xy 196.292384 -17.292863)
			(xy 196.32647 -17.24872) (xy 196.366619 -17.210011) (xy 196.411977 -17.17756) (xy 196.461577 -17.152059)
			(xy 196.514361 -17.134052) (xy 196.569204 -17.123922) (xy 196.624938 -17.121885) (xy 196.680375 -17.127985)
			(xy 196.734332 -17.142091) (xy 196.785661 -17.163903) (xy 196.833267 -17.192957) (xy 196.876135 -17.228632)
			(xy 196.913352 -17.270169) (xy 196.944125 -17.316682) (xy 196.967797 -17.367179) (xy 196.983865 -17.420586)
			(xy 196.991985 -17.475762) (xy 196.992494 -17.503648) (xy 196.991985 -17.531534) (xy 196.983865 -17.58671)
			(xy 196.967797 -17.640117) (xy 196.944125 -17.690614) (xy 196.913352 -17.737127) (xy 196.876135 -17.778664)
			(xy 196.833267 -17.814339) (xy 196.785661 -17.843393) (xy 196.734332 -17.865205) (xy 196.680375 -17.879311)
			(xy 196.624938 -17.885411) (xy 196.569204 -17.883374) (xy 196.514361 -17.873244) (xy 196.461577 -17.855237)
			(xy 196.411977 -17.829736) (xy 196.366619 -17.797285) (xy 196.32647 -17.758576) (xy 196.292384 -17.714433)
			(xy 196.265088 -17.665798) (xy 196.245165 -17.613707) (xy 196.233039 -17.55927) (xy 196.228968 -17.503648)
			(xy 191.008 -17.503648) (xy 191.008 -17.628108) (xy 192.521332 -19.14144) (xy 195.064378 -19.14144)
			(xy 195.068449 -19.085818) (xy 195.080575 -19.031381) (xy 195.100498 -18.97929) (xy 195.127794 -18.930655)
			(xy 195.16188 -18.886512) (xy 195.202029 -18.847803) (xy 195.247387 -18.815352) (xy 195.296987 -18.789851)
			(xy 195.349771 -18.771844) (xy 195.404614 -18.761714) (xy 195.460348 -18.759677) (xy 195.515785 -18.765777)
			(xy 195.569742 -18.779883) (xy 195.621071 -18.801695) (xy 195.668677 -18.830749) (xy 195.711545 -18.866424)
			(xy 195.748762 -18.907961) (xy 195.779535 -18.954474) (xy 195.803207 -19.004971) (xy 195.819275 -19.058378)
			(xy 195.827395 -19.113554) (xy 195.827904 -19.14144) (xy 195.827395 -19.169326) (xy 195.819275 -19.224502)
			(xy 195.803207 -19.277909) (xy 195.779535 -19.328406) (xy 195.748762 -19.374919) (xy 195.711545 -19.416456)
			(xy 195.668677 -19.452131) (xy 195.621071 -19.481185) (xy 195.569742 -19.502997) (xy 195.515785 -19.517103)
			(xy 195.460348 -19.523203) (xy 195.404614 -19.521166) (xy 195.349771 -19.511036) (xy 195.296987 -19.493029)
			(xy 195.247387 -19.467528) (xy 195.202029 -19.435077) (xy 195.16188 -19.396368) (xy 195.127794 -19.352225)
			(xy 195.100498 -19.30359) (xy 195.080575 -19.251499) (xy 195.068449 -19.197062) (xy 195.064378 -19.14144)
			(xy 192.521332 -19.14144) (xy 195.3514 -21.971508) (xy 195.3514 -25.803352) (xy 195.667884 -26.119582)
			(xy 195.688663 -26.141197) (xy 195.7239 -26.189702) (xy 195.751118 -26.243121) (xy 195.769648 -26.300139)
			(xy 195.779034 -26.359353) (xy 195.779644 -26.38933) (xy 195.779644 -27.143964) (xy 195.798899 -27.162132)
			(xy 195.832712 -27.202866) (xy 195.860566 -27.247885) (xy 195.881925 -27.296324) (xy 195.89638 -27.347251)
			(xy 195.903653 -27.399688) (xy 195.904104 -27.426158) (xy 195.904104 -27.48661) (xy 196.158104 -28.099512)
			(xy 198.238618 -30.180026) (xy 198.251826 -30.183582) (xy 198.275948 -30.19039) (xy 198.322294 -30.209475)
			(xy 198.36574 -30.234469) (xy 198.405537 -30.26494) (xy 198.42353 -30.282388) (xy 199.06869 -30.927548)
			(xy 199.070468 -30.929072) (xy 199.096122 -30.95244) (xy 199.346566 -31.202884) (xy 201.654664 -31.202884)
		)
		(stroke
			(width 0)
			(type solid)
		)
		(fill yes)
		(layer "In6.Cu")
		(net "P12V_SCM")
	)
	(gr_poly
		(pts
			(xy 222.789496 -32.275018)
			(arc
				(start 222.789496 -13.780008)
				(mid 222.353244 -12.726804)
				(end 221.30004 -12.290552)
			)
			(arc
				(start 196.701918 -12.290552)
				(mid 194.926701 -11.555233)
				(end 194.191382 -9.780016)
			)
			(xy 194.191382 -6.53796) (xy 194.193668 -6.53796)
			(arc
				(start 194.193668 -6.279896)
				(mid 194.04964 -5.93218)
				(end 193.701924 -5.788152)
			)
			(arc
				(start 127.102108 -5.788152)
				(mid 126.754392 -5.93218)
				(end 126.610364 -6.279896)
			)
			(xy 126.610364 -6.53796) (xy 126.61265 -6.53796)
			(arc
				(start 126.61265 -7.744206)
				(mid 126.627618 -7.779963)
				(end 126.66345 -7.794752)
			)
			(arc
				(start 126.687326 -7.78891)
				(mid 126.774244 -7.75555)
				(end 126.86665 -7.744206)
			)
			(arc
				(start 126.86665 -7.744206)
				(mid 126.931475 -7.749794)
				(end 126.994412 -7.766304)
			)
			(arc
				(start 126.994412 -7.766304)
				(mid 127.020815 -7.768359)
				(end 127.044704 -7.756906)
			)
			(arc
				(start 127.044704 -7.756906)
				(mid 127.071589 -7.734537)
				(end 127.099314 -7.713218)
			)
			(xy 127.119888 -7.672832) (xy 127.119888 -6.295898) (xy 193.684144 -6.295898) (xy 193.684144 -7.673086)
			(arc
				(start 193.704718 -7.713472)
				(mid 194.076604 -8.449818)
				(end 193.704718 -9.186164)
			)
			(xy 193.684144 -9.22655)
			(arc
				(start 193.684144 -9.780016)
				(mid 193.685767 -9.876714)
				(end 193.690494 -9.97331)
			)
			(xy 193.690494 -9.972802) (xy 194.15887 -10.441178)
			(arc
				(start 194.15887 -11.4046)
				(mid 194.195836 -11.461027)
				(end 194.234054 -11.516614)
			)
			(xy 194.236848 -11.519662) (xy 194.962272 -12.245086)
			(arc
				(start 194.96532 -12.24788)
				(mid 195.096232 -12.335047)
				(end 195.231512 -12.415266)
			)
			(xy 195.23456 -12.416536)
			(arc
				(start 195.87337 -12.681712)
				(mid 196.283107 -12.768412)
				(end 196.700902 -12.797536)
			)
			(arc
				(start 221.30004 -12.797536)
				(mid 221.994753 -13.085295)
				(end 222.282512 -13.780008)
			)
			(xy 222.282512 -32.275018) (xy 222.344742 -32.337248) (xy 222.727266 -32.337248)
		)
		(stroke
			(width 0)
			(type solid)
		)
		(fill yes)
		(layer "In6.Cu")
		(net "GND")
	)
	(gr_poly
		(pts
			(xy 399.644362 -156.515308) (xy 399.647117 -156.471953) (xy 399.659809 -156.386007) (xy 399.680591 -156.30165)
			(xy 399.709278 -156.219644) (xy 399.745609 -156.140727) (xy 399.789258 -156.06561) (xy 399.839832 -155.994969)
			(xy 399.896876 -155.929441) (xy 399.959874 -155.869615) (xy 400.028261 -155.816032) (xy 400.101419 -155.769174)
			(xy 400.178691 -155.729462) (xy 400.259379 -155.697254) (xy 400.342757 -155.672841) (xy 400.428073 -155.656442)
			(xy 400.514561 -155.648206) (xy 400.601439 -155.648206) (xy 400.687927 -155.656442) (xy 400.773243 -155.672841)
			(xy 400.856621 -155.697254) (xy 400.937309 -155.729462) (xy 401.014581 -155.769174) (xy 401.087739 -155.816032)
			(xy 401.156126 -155.869615) (xy 401.219124 -155.929441) (xy 401.276168 -155.994969) (xy 401.326742 -156.06561)
			(xy 401.370391 -156.140727) (xy 401.406722 -156.219644) (xy 401.435409 -156.30165) (xy 401.456191 -156.386007)
			(xy 401.468883 -156.471953) (xy 401.471638 -156.515308) (xy 401.474178 -156.563568) (xy 408.75458 -156.563568)
			(xy 409.22956 -156.088588) (xy 409.22956 -148.760688) (xy 408.62758 -148.158708) (xy 398.10944 -148.158708)
			(xy 397.942816 -148.325332) (xy 397.942816 -150.339552) (xy 399.642589 -150.339552) (xy 399.646611 -150.253832)
			(xy 399.658642 -150.168864) (xy 399.678578 -150.085397) (xy 399.706241 -150.004163) (xy 399.74139 -149.925877)
			(xy 399.783716 -149.851226) (xy 399.832845 -149.780867) (xy 399.888348 -149.715417) (xy 399.949735 -149.655453)
			(xy 400.016468 -149.6015) (xy 400.08796 -149.554033) (xy 400.163582 -149.513469) (xy 400.242671 -149.480165)
			(xy 400.324531 -149.454413) (xy 400.408442 -149.43644) (xy 400.493668 -149.426404) (xy 400.57946 -149.424392)
			(xy 400.665062 -149.430423) (xy 400.749724 -149.444443) (xy 400.832701 -149.466329) (xy 400.913264 -149.49589)
			(xy 400.990704 -149.532864) (xy 401.064343 -149.576928) (xy 401.133531 -149.627694) (xy 401.197662 -149.684715)
			(xy 401.256171 -149.747491) (xy 401.308544 -149.815471) (xy 401.354322 -149.888056) (xy 401.393102 -149.964608)
			(xy 401.424543 -150.044456) (xy 401.448369 -150.126897) (xy 401.46437 -150.211207) (xy 401.472405 -150.296645)
			(xy 401.472908 -150.339552) (xy 401.472405 -150.382459) (xy 401.46437 -150.467897) (xy 401.448369 -150.552207)
			(xy 401.424543 -150.634648) (xy 401.393102 -150.714496) (xy 401.354322 -150.791048) (xy 401.308544 -150.863633)
			(xy 401.256171 -150.931613) (xy 401.197662 -150.994389) (xy 401.133531 -151.05141) (xy 401.064343 -151.102176)
			(xy 400.990704 -151.14624) (xy 400.913264 -151.183214) (xy 400.832701 -151.212775) (xy 400.749724 -151.234661)
			(xy 400.665062 -151.248681) (xy 400.57946 -151.254712) (xy 400.493668 -151.2527) (xy 400.408442 -151.242664)
			(xy 400.324531 -151.224691) (xy 400.242671 -151.198939) (xy 400.163582 -151.165635) (xy 400.08796 -151.125071)
			(xy 400.016468 -151.077604) (xy 399.949735 -151.023651) (xy 399.888348 -150.963687) (xy 399.832845 -150.898237)
			(xy 399.783716 -150.827878) (xy 399.74139 -150.753227) (xy 399.706241 -150.674941) (xy 399.678578 -150.593707)
			(xy 399.658642 -150.51024) (xy 399.646611 -150.425272) (xy 399.642589 -150.339552) (xy 397.942816 -150.339552)
			(xy 397.942816 -152.381896) (xy 399.668996 -152.381896) (xy 399.668996 -152.2972) (xy 399.677047 -152.212886)
			(xy 399.693076 -152.12972) (xy 399.716937 -152.048453) (xy 399.748416 -151.969823) (xy 399.787227 -151.894542)
			(xy 399.833017 -151.82329) (xy 399.885373 -151.756714) (xy 399.943821 -151.695416) (xy 400.007831 -151.639951)
			(xy 400.076823 -151.590822) (xy 400.150173 -151.548473) (xy 400.227216 -151.513289) (xy 400.307255 -151.485587)
			(xy 400.389564 -151.465619) (xy 400.473399 -151.453566) (xy 400.558 -151.449536) (xy 400.642601 -151.453566)
			(xy 400.726436 -151.465619) (xy 400.808745 -151.485587) (xy 400.888784 -151.513289) (xy 400.965827 -151.548473)
			(xy 401.039177 -151.590822) (xy 401.108169 -151.639951) (xy 401.172179 -151.695416) (xy 401.230627 -151.756714)
			(xy 401.282983 -151.82329) (xy 401.328773 -151.894542) (xy 401.367584 -151.969823) (xy 401.399063 -152.048453)
			(xy 401.422924 -152.12972) (xy 401.438953 -152.212886) (xy 401.447004 -152.2972) (xy 401.447508 -152.339548)
			(xy 401.447004 -152.381896) (xy 401.438953 -152.46621) (xy 401.422924 -152.549376) (xy 401.399063 -152.630643)
			(xy 401.367584 -152.709273) (xy 401.328773 -152.784554) (xy 401.282983 -152.855806) (xy 401.230627 -152.922382)
			(xy 401.172179 -152.98368) (xy 401.108169 -153.039145) (xy 401.039177 -153.088274) (xy 400.965827 -153.130623)
			(xy 400.888784 -153.165807) (xy 400.808745 -153.193509) (xy 400.726436 -153.213477) (xy 400.642601 -153.22553)
			(xy 400.558 -153.229561) (xy 400.473399 -153.22553) (xy 400.389564 -153.213477) (xy 400.307255 -153.193509)
			(xy 400.227216 -153.165807) (xy 400.150173 -153.130623) (xy 400.076823 -153.088274) (xy 400.007831 -153.039145)
			(xy 399.943821 -152.98368) (xy 399.885373 -152.922382) (xy 399.833017 -152.855806) (xy 399.787227 -152.784554)
			(xy 399.748416 -152.709273) (xy 399.716937 -152.630643) (xy 399.693076 -152.549376) (xy 399.677047 -152.46621)
			(xy 399.668996 -152.381896) (xy 397.942816 -152.381896) (xy 397.942816 -155.878784) (xy 398.6276 -156.563568)
			(xy 399.641822 -156.563568)
		)
		(stroke
			(width 0)
			(type solid)
		)
		(fill yes)
		(layer "In6.Cu")
		(net "PVCCFA_EHV_CPU0")
	)
	(gr_poly
		(pts
			(xy 198.43496 -113.538762) (xy 198.434485 -113.5241) (xy 198.426171 -113.495981) (xy 198.41021 -113.471384)
			(xy 198.387918 -113.452334) (xy 198.361132 -113.440404) (xy 198.332061 -113.436575) (xy 198.3031 -113.441165)
			(xy 198.289672 -113.447068) (xy 198.263848 -113.458844) (xy 198.209585 -113.475481) (xy 198.153458 -113.483899)
			(xy 198.12508 -113.484406) (xy 198.09783 -113.483919) (xy 198.043885 -113.47616) (xy 197.991592 -113.460803)
			(xy 197.942018 -113.438161) (xy 197.89617 -113.408694) (xy 197.854983 -113.373003) (xy 197.819294 -113.331814)
			(xy 197.789829 -113.285964) (xy 197.76719 -113.236389) (xy 197.751836 -113.184096) (xy 197.74408 -113.13015)
			(xy 197.74408 -113.07565) (xy 197.751836 -113.021704) (xy 197.76719 -112.969411) (xy 197.789829 -112.919836)
			(xy 197.819294 -112.873986) (xy 197.854983 -112.832797) (xy 197.89617 -112.797106) (xy 197.942018 -112.767639)
			(xy 197.991592 -112.744997) (xy 198.043885 -112.72964) (xy 198.09783 -112.721881) (xy 198.12508 -112.72139)
			(xy 198.153458 -112.72191) (xy 198.209586 -112.730317) (xy 198.26385 -112.746949) (xy 198.289672 -112.758728)
			(xy 198.303113 -112.7646) (xy 198.332072 -112.769183) (xy 198.361141 -112.765354) (xy 198.387926 -112.75343)
			(xy 198.410222 -112.73439) (xy 198.426195 -112.709804) (xy 198.43453 -112.681694) (xy 198.43496 -112.667034)
			(xy 198.43496 -112.560862) (xy 198.434485 -112.5462) (xy 198.426171 -112.518081) (xy 198.41021 -112.493484)
			(xy 198.387918 -112.474434) (xy 198.361132 -112.462504) (xy 198.332061 -112.458675) (xy 198.3031 -112.463265)
			(xy 198.289672 -112.469168) (xy 198.263848 -112.480944) (xy 198.209585 -112.497581) (xy 198.153458 -112.505999)
			(xy 198.12508 -112.506506) (xy 198.09783 -112.506019) (xy 198.043885 -112.49826) (xy 197.991592 -112.482903)
			(xy 197.942018 -112.460261) (xy 197.89617 -112.430794) (xy 197.854983 -112.395103) (xy 197.819294 -112.353914)
			(xy 197.789829 -112.308064) (xy 197.76719 -112.258489) (xy 197.751836 -112.206196) (xy 197.74408 -112.15225)
			(xy 197.74408 -112.09775) (xy 197.751836 -112.043804) (xy 197.76719 -111.991511) (xy 197.789829 -111.941936)
			(xy 197.819294 -111.896086) (xy 197.854983 -111.854897) (xy 197.89617 -111.819206) (xy 197.942018 -111.789739)
			(xy 197.991592 -111.767097) (xy 198.043885 -111.75174) (xy 198.09783 -111.743981) (xy 198.12508 -111.74349)
			(xy 198.153458 -111.74401) (xy 198.209586 -111.752417) (xy 198.26385 -111.769049) (xy 198.289672 -111.780828)
			(xy 198.303113 -111.7867) (xy 198.332072 -111.791283) (xy 198.361141 -111.787454) (xy 198.387926 -111.77553)
			(xy 198.410222 -111.75649) (xy 198.426195 -111.731904) (xy 198.43453 -111.703794) (xy 198.43496 -111.689134)
			(xy 198.43496 -111.3536) (xy 198.189088 -111.107728) (xy 193.471038 -111.107728) (xy 193.455829 -111.108287)
			(xy 193.426755 -111.117234) (xy 193.401606 -111.134345) (xy 193.382611 -111.158104) (xy 193.371454 -111.186403)
			(xy 193.369125 -111.216732) (xy 193.371978 -111.23168) (xy 193.376136 -111.251228) (xy 193.380591 -111.290945)
			(xy 193.380868 -111.310928) (xy 193.38035 -111.338136) (xy 193.372067 -111.391917) (xy 193.355696 -111.443812)
			(xy 193.331621 -111.492611) (xy 193.3004 -111.537179) (xy 193.262762 -111.576478) (xy 193.219583 -111.609593)
			(xy 193.195956 -111.623094) (xy 193.16954 -111.637572) (xy 193.16954 -112.048544) (xy 193.213228 -112.05464)
			(xy 193.240149 -112.058967) (xy 193.292471 -112.074307) (xy 193.342077 -112.09694) (xy 193.387955 -112.126404)
			(xy 193.429171 -112.1621) (xy 193.464887 -112.203299) (xy 193.494373 -112.249164) (xy 193.517029 -112.298758)
			(xy 193.532395 -112.351073) (xy 193.540156 -112.405043) (xy 193.540155 -112.459568) (xy 193.532392 -112.513537)
			(xy 193.517025 -112.565852) (xy 193.494367 -112.615446) (xy 193.46488 -112.661309) (xy 193.429164 -112.702508)
			(xy 193.387946 -112.738202) (xy 193.342067 -112.767665) (xy 193.292461 -112.790297) (xy 193.240138 -112.805636)
			(xy 193.213228 -112.810036) (xy 193.16954 -112.816132) (xy 193.16954 -113.514632) (xy 196.46341 -113.514632)
			(xy 196.467481 -113.45901) (xy 196.479607 -113.404573) (xy 196.49953 -113.352482) (xy 196.526826 -113.303847)
			(xy 196.560912 -113.259704) (xy 196.601061 -113.220995) (xy 196.646419 -113.188544) (xy 196.696019 -113.163043)
			(xy 196.748803 -113.145036) (xy 196.803646 -113.134906) (xy 196.85938 -113.132869) (xy 196.914817 -113.138969)
			(xy 196.968774 -113.153075) (xy 197.020103 -113.174887) (xy 197.067709 -113.203941) (xy 197.110577 -113.239616)
			(xy 197.147794 -113.281153) (xy 197.178567 -113.327666) (xy 197.202239 -113.378163) (xy 197.218307 -113.43157)
			(xy 197.226427 -113.486746) (xy 197.226936 -113.514632) (xy 197.226427 -113.542518) (xy 197.218307 -113.597694)
			(xy 197.202239 -113.651101) (xy 197.178567 -113.701598) (xy 197.147794 -113.748111) (xy 197.110577 -113.789648)
			(xy 197.067709 -113.825323) (xy 197.020103 -113.854377) (xy 196.968774 -113.876189) (xy 196.914817 -113.890295)
			(xy 196.85938 -113.896395) (xy 196.803646 -113.894358) (xy 196.748803 -113.884228) (xy 196.696019 -113.866221)
			(xy 196.646419 -113.84072) (xy 196.601061 -113.808269) (xy 196.560912 -113.76956) (xy 196.526826 -113.725417)
			(xy 196.49953 -113.676782) (xy 196.479607 -113.624691) (xy 196.467481 -113.570254) (xy 196.46341 -113.514632)
			(xy 193.16954 -113.514632) (xy 193.16954 -114.18062) (xy 196.55028 -114.18062) (xy 196.575261 -114.181137)
			(xy 196.624603 -114.188998) (xy 196.672111 -114.204468) (xy 196.716621 -114.227167) (xy 196.757041 -114.256538)
			(xy 196.77507 -114.273838) (xy 196.80428 -114.303048) (xy 198.43496 -114.303048)
		)
		(stroke
			(width 0)
			(type solid)
		)
		(fill yes)
		(layer "In6.Cu")
		(net "GND")
	)
	(gr_poly
		(pts
			(arc
				(start 251.65812 -39.510208)
				(mid 251.689054 -39.583208)
				(end 251.763022 -39.611808)
			)
			(xy 251.780294 -39.6113) (xy 253.743714 -39.6113)
			(arc
				(start 253.846076 -39.509192)
				(mid 254.010975 -39.39901)
				(end 254.205486 -39.360348)
			)
			(xy 255.104138 -39.360348) (xy 255.723136 -38.74135)
			(arc
				(start 255.750822 -38.715696)
				(mid 255.785632 -38.648531)
				(end 255.764284 -38.575996)
			)
			(arc
				(start 255.764284 -38.575996)
				(mid 255.704023 -38.46519)
				(end 255.683258 -38.340792)
			)
			(arc
				(start 255.683258 -38.340792)
				(mid 255.692996 -38.25489)
				(end 255.721866 -38.173406)
			)
			(arc
				(start 255.721866 -38.173406)
				(mid 255.716703 -38.07519)
				(end 255.63068 -38.027356)
			)
			(arc
				(start 254.822706 -38.027356)
				(mid 254.737805 -38.073537)
				(end 254.729996 -38.16985)
			)
			(arc
				(start 254.729996 -38.16985)
				(mid 254.754338 -38.245365)
				(end 254.762508 -38.324282)
			)
			(arc
				(start 254.762508 -38.324282)
				(mid 254.381 -38.70579)
				(end 253.999492 -38.324282)
			)
			(arc
				(start 253.999492 -38.324282)
				(mid 254.007689 -38.245371)
				(end 254.032004 -38.16985)
			)
			(arc
				(start 254.032004 -38.16985)
				(mid 254.024162 -38.073558)
				(end 253.939294 -38.027356)
			)
			(arc
				(start 253.171706 -38.027356)
				(mid 253.086805 -38.073537)
				(end 253.078996 -38.16985)
			)
			(arc
				(start 253.078996 -38.16985)
				(mid 253.103338 -38.245365)
				(end 253.111508 -38.324282)
			)
			(arc
				(start 253.111508 -38.324282)
				(mid 253.083759 -38.46712)
				(end 253.004574 -38.589204)
			)
			(arc
				(start 253.004574 -38.589204)
				(mid 252.976183 -38.666196)
				(end 253.013972 -38.739064)
			)
			(arc
				(start 253.013972 -38.739064)
				(mid 253.11954 -38.871714)
				(end 253.157228 -39.037006)
			)
			(arc
				(start 253.157228 -39.037006)
				(mid 252.77572 -39.418514)
				(end 252.394212 -39.037006)
			)
			(arc
				(start 252.394212 -39.037006)
				(mid 252.421961 -38.894168)
				(end 252.501146 -38.772084)
			)
			(arc
				(start 252.501146 -38.772084)
				(mid 252.529537 -38.695092)
				(end 252.491748 -38.622224)
			)
			(arc
				(start 252.491748 -38.622224)
				(mid 252.38618 -38.489574)
				(end 252.348492 -38.324282)
			)
			(arc
				(start 252.348492 -38.324282)
				(mid 252.356689 -38.245371)
				(end 252.381004 -38.16985)
			)
			(arc
				(start 252.381004 -38.16985)
				(mid 252.373162 -38.073558)
				(end 252.288294 -38.027356)
			)
			(xy 251.65812 -38.027356) (xy 251.65812 -38.332156)
			(arc
				(start 251.694696 -38.342824)
				(mid 251.968712 -38.708838)
				(end 251.694696 -39.074852)
			)
			(xy 251.65812 -39.08552)
		)
		(stroke
			(width 0)
			(type solid)
		)
		(fill yes)
		(layer "In6.Cu")
		(net "GND")
	)
	(gr_poly
		(pts
			(xy 260.53288 -93.716348) (xy 264.90168 -93.716348) (xy 265.46048 -93.157548) (xy 265.46048 -92.192348)
			(xy 259.89407 -92.192348) (xy 259.879922 -92.192803) (xy 259.852709 -92.20056) (xy 259.828676 -92.215497)
			(xy 259.809673 -92.236462) (xy 259.797163 -92.261843) (xy 259.79211 -92.289685) (xy 259.794901 -92.317843)
			(xy 259.805324 -92.34415) (xy 259.813552 -92.35567) (xy 259.828376 -92.375721) (xy 259.853249 -92.418937)
			(xy 259.872283 -92.465025) (xy 259.885151 -92.5132) (xy 259.891636 -92.56264) (xy 259.892038 -92.587572)
			(xy 259.891552 -92.614823) (xy 259.883796 -92.668771) (xy 259.868441 -92.721066) (xy 259.845799 -92.770643)
			(xy 259.816333 -92.816493) (xy 259.780642 -92.857684) (xy 259.739451 -92.893375) (xy 259.693601 -92.922841)
			(xy 259.644024 -92.945483) (xy 259.591729 -92.960838) (xy 259.537781 -92.968594) (xy 259.483279 -92.968594)
			(xy 259.429331 -92.960838) (xy 259.377036 -92.945483) (xy 259.327459 -92.922841) (xy 259.281609 -92.893375)
			(xy 259.240418 -92.857684) (xy 259.204727 -92.816493) (xy 259.175261 -92.770643) (xy 259.152619 -92.721066)
			(xy 259.137264 -92.668771) (xy 259.129508 -92.614823) (xy 259.129022 -92.587572) (xy 259.129428 -92.562641)
			(xy 259.135921 -92.513204) (xy 259.148794 -92.465032) (xy 259.167827 -92.418945) (xy 259.192696 -92.375728)
			(xy 259.207508 -92.35567) (xy 259.215737 -92.344159) (xy 259.22611 -92.317845) (xy 259.228869 -92.289695)
			(xy 259.223804 -92.261867) (xy 259.211301 -92.236495) (xy 259.192321 -92.215524) (xy 259.168318 -92.200562)
			(xy 259.141132 -92.192755) (xy 259.12699 -92.192348) (xy 255.96088 -92.192348) (xy 255.17348 -92.979748)
			(xy 255.17348 -93.46057) (xy 256.128264 -93.46057) (xy 256.132335 -93.404948) (xy 256.144461 -93.350511)
			(xy 256.164384 -93.29842) (xy 256.19168 -93.249785) (xy 256.225766 -93.205642) (xy 256.265915 -93.166933)
			(xy 256.311273 -93.134482) (xy 256.360873 -93.108981) (xy 256.413657 -93.090974) (xy 256.4685 -93.080844)
			(xy 256.524234 -93.078807) (xy 256.579671 -93.084907) (xy 256.633628 -93.099013) (xy 256.684957 -93.120825)
			(xy 256.732563 -93.149879) (xy 256.775431 -93.185554) (xy 256.812648 -93.227091) (xy 256.843421 -93.273604)
			(xy 256.867093 -93.324101) (xy 256.883161 -93.377508) (xy 256.891281 -93.432684) (xy 256.89179 -93.46057)
			(xy 256.891753 -93.462602) (xy 257.977384 -93.462602) (xy 257.981455 -93.40698) (xy 257.993581 -93.352543)
			(xy 258.013504 -93.300452) (xy 258.0408 -93.251817) (xy 258.074886 -93.207674) (xy 258.115035 -93.168965)
			(xy 258.160393 -93.136514) (xy 258.209993 -93.111013) (xy 258.262777 -93.093006) (xy 258.31762 -93.082876)
			(xy 258.373354 -93.080839) (xy 258.428791 -93.086939) (xy 258.482748 -93.101045) (xy 258.534077 -93.122857)
			(xy 258.581683 -93.151911) (xy 258.624551 -93.187586) (xy 258.661768 -93.229123) (xy 258.692541 -93.275636)
			(xy 258.716213 -93.326133) (xy 258.732281 -93.37954) (xy 258.740401 -93.434716) (xy 258.74091 -93.462602)
			(xy 258.740401 -93.490488) (xy 258.732281 -93.545664) (xy 258.716213 -93.599071) (xy 258.692541 -93.649568)
			(xy 258.661768 -93.696081) (xy 258.624551 -93.737618) (xy 258.581683 -93.773293) (xy 258.534077 -93.802347)
			(xy 258.482748 -93.824159) (xy 258.428791 -93.838265) (xy 258.373354 -93.844365) (xy 258.31762 -93.842328)
			(xy 258.262777 -93.832198) (xy 258.209993 -93.814191) (xy 258.160393 -93.78869) (xy 258.115035 -93.756239)
			(xy 258.074886 -93.71753) (xy 258.0408 -93.673387) (xy 258.013504 -93.624752) (xy 257.993581 -93.572661)
			(xy 257.981455 -93.518224) (xy 257.977384 -93.462602) (xy 256.891753 -93.462602) (xy 256.891281 -93.488456)
			(xy 256.883161 -93.543632) (xy 256.867093 -93.597039) (xy 256.843421 -93.647536) (xy 256.812648 -93.694049)
			(xy 256.775431 -93.735586) (xy 256.732563 -93.771261) (xy 256.684957 -93.800315) (xy 256.633628 -93.822127)
			(xy 256.579671 -93.836233) (xy 256.524234 -93.842333) (xy 256.4685 -93.840296) (xy 256.413657 -93.830166)
			(xy 256.360873 -93.812159) (xy 256.311273 -93.786658) (xy 256.265915 -93.754207) (xy 256.225766 -93.715498)
			(xy 256.19168 -93.671355) (xy 256.164384 -93.62272) (xy 256.144461 -93.570629) (xy 256.132335 -93.516192)
			(xy 256.128264 -93.46057) (xy 255.17348 -93.46057) (xy 255.17348 -94.934532) (xy 257.452366 -94.934532)
			(xy 257.456437 -94.87891) (xy 257.468563 -94.824473) (xy 257.488486 -94.772382) (xy 257.515782 -94.723747)
			(xy 257.549868 -94.679604) (xy 257.590017 -94.640895) (xy 257.635375 -94.608444) (xy 257.684975 -94.582943)
			(xy 257.737759 -94.564936) (xy 257.792602 -94.554806) (xy 257.848336 -94.552769) (xy 257.903773 -94.558869)
			(xy 257.95773 -94.572975) (xy 258.009059 -94.594787) (xy 258.056665 -94.623841) (xy 258.099533 -94.659516)
			(xy 258.13675 -94.701053) (xy 258.167523 -94.747566) (xy 258.191195 -94.798063) (xy 258.207263 -94.85147)
			(xy 258.215383 -94.906646) (xy 258.215892 -94.934532) (xy 258.215383 -94.962418) (xy 258.207263 -95.017594)
			(xy 258.191195 -95.071001) (xy 258.167523 -95.121498) (xy 258.13675 -95.168011) (xy 258.099533 -95.209548)
			(xy 258.056665 -95.245223) (xy 258.009059 -95.274277) (xy 257.95773 -95.296089) (xy 257.903773 -95.310195)
			(xy 257.848336 -95.316295) (xy 257.792602 -95.314258) (xy 257.737759 -95.304128) (xy 257.684975 -95.286121)
			(xy 257.635375 -95.26062) (xy 257.590017 -95.228169) (xy 257.549868 -95.18946) (xy 257.515782 -95.145317)
			(xy 257.488486 -95.096682) (xy 257.468563 -95.044591) (xy 257.456437 -94.990154) (xy 257.452366 -94.934532)
			(xy 255.17348 -94.934532) (xy 255.17348 -95.087948) (xy 255.50368 -95.418148) (xy 258.83108 -95.418148)
		)
		(stroke
			(width 0)
			(type solid)
		)
		(fill yes)
		(layer "In6.Cu")
		(net "P3V3_AUX_CLK_GEN_VDDA100M_CK440")
	)
	(gr_poly
		(pts
			(arc
				(start 471.13317 -17.855184)
				(mid 471.158695 -17.863037)
				(end 471.184732 -17.856962)
			)
			(arc
				(start 471.262964 -17.814036)
				(mid 471.282207 -17.795414)
				(end 471.28938 -17.769586)
			)
			(arc
				(start 471.28938 -13.780008)
				(mid 470.853128 -12.726804)
				(end 469.799924 -12.290552)
			)
			(arc
				(start 458.20203 -12.290552)
				(mid 456.426813 -11.555233)
				(end 455.691494 -9.780016)
			)
			(xy 455.691494 -1.30556) (xy 455.69378 -1.30556)
			(arc
				(start 455.69378 -0.999998)
				(mid 455.549752 -0.652282)
				(end 455.202036 -0.508254)
			)
			(arc
				(start 388.601966 -0.508254)
				(mid 388.25425 -0.652282)
				(end 388.110222 -0.999998)
			)
			(xy 388.110222 -1.30556) (xy 388.112508 -1.30556)
			(arc
				(start 388.112508 -9.780016)
				(mid 387.377189 -11.555233)
				(end 385.601972 -12.290552)
			)
			(arc
				(start 331.518514 -12.290552)
				(mid 331.486288 -12.302082)
				(end 331.46873 -12.331446)
			)
			(arc
				(start 331.46873 -12.331446)
				(mid 331.473782 -12.365344)
				(end 331.49921 -12.388342)
			)
			(xy 332.478888 -12.794234) (xy 332.492096 -12.797536)
			(arc
				(start 385.601972 -12.797536)
				(mid 387.735681 -11.913725)
				(end 388.619492 -9.780016)
			)
			(xy 388.619492 -3.928364)
			(arc
				(start 388.614158 -3.917442)
				(mid 388.329377 -3.590886)
				(end 388.226808 -3.16992)
			)
			(arc
				(start 388.226808 -3.16992)
				(mid 388.275543 -2.875216)
				(end 388.416546 -2.611882)
			)
			(arc
				(start 388.416546 -2.611882)
				(mid 388.501545 -2.513276)
				(end 388.59968 -2.427732)
			)
			(xy 388.619492 -2.388108) (xy 388.619492 -1.016) (xy 455.184256 -1.016) (xy 455.184256 -2.375154)
			(arc
				(start 455.205338 -2.416048)
				(mid 455.573689 -3.012402)
				(end 455.41184 -3.69443)
			)
			(arc
				(start 455.41184 -3.69443)
				(mid 455.315091 -3.810755)
				(end 455.200512 -3.909568)
			)
			(xy 455.184256 -3.941318)
			(arc
				(start 455.184256 -9.780016)
				(mid 456.068231 -11.91374)
				(end 458.20203 -12.797536)
			)
			(arc
				(start 469.799924 -12.797536)
				(mid 470.494637 -13.085295)
				(end 470.782396 -13.780008)
			)
			(xy 470.782396 -17.620234)
			(arc
				(start 470.808558 -17.664176)
				(mid 470.972568 -17.756784)
				(end 471.13317 -17.855184)
			)
		)
		(stroke
			(width 0)
			(type solid)
		)
		(fill yes)
		(layer "In6.Cu")
		(net "GND")
	)
	(gr_poly
		(pts
			(xy 0.654812 -17.86255)
			(arc
				(start 0.66675 -17.85493)
				(mid 0.827347 -17.756522)
				(end 0.991362 -17.663922)
			)
			(xy 1.017524 -17.61998)
			(arc
				(start 1.017524 -13.780008)
				(mid 1.305283 -13.085295)
				(end 1.999996 -12.797536)
			)
			(arc
				(start 11.102594 -12.797536)
				(mid 13.236139 -11.913635)
				(end 14.11986 -9.780016)
			)
			(xy 14.11986 -3.945382)
			(arc
				(start 14.10081 -3.90779)
				(mid 13.825764 -3.583504)
				(end 13.726922 -3.16992)
			)
			(arc
				(start 13.726922 -3.16992)
				(mid 13.825371 -2.757062)
				(end 14.09954 -2.433066)
			)
			(xy 14.11986 -2.392934) (xy 14.11986 -1.016) (xy 80.684116 -1.016) (xy 80.684116 -2.39141)
			(arc
				(start 80.704944 -2.43205)
				(mid 81.07796 -3.169158)
				(end 80.704944 -3.906266)
			)
			(xy 80.684116 -3.946906)
			(arc
				(start 80.684116 -9.780016)
				(mid 81.568091 -11.91374)
				(end 83.70189 -12.797536)
			)
			(arc
				(start 92.083636 -12.797536)
				(mid 92.115604 -12.780916)
				(end 92.12834 -12.747244)
			)
			(arc
				(start 92.12834 -12.499848)
				(mid 92.130733 -12.457406)
				(end 92.137992 -12.41552)
			)
			(arc
				(start 92.137992 -12.415266)
				(mid 92.138142 -12.392555)
				(end 92.12834 -12.372086)
			)
			(arc
				(start 92.07881 -12.309856)
				(mid 92.061088 -12.29562)
				(end 92.038932 -12.290552)
			)
			(arc
				(start 83.70189 -12.290552)
				(mid 81.926673 -11.555233)
				(end 81.191354 -9.780016)
			)
			(xy 81.191354 -1.28524) (xy 81.19364 -1.28524)
			(arc
				(start 81.19364 -0.999998)
				(mid 81.049612 -0.652282)
				(end 80.701896 -0.508254)
			)
			(arc
				(start 14.10208 -0.508254)
				(mid 13.754364 -0.652282)
				(end 13.610336 -0.999998)
			)
			(xy 13.610336 -1.28524) (xy 13.612622 -1.28524)
			(arc
				(start 13.612622 -9.780016)
				(mid 12.877303 -11.555233)
				(end 11.102086 -12.290552)
			)
			(arc
				(start 1.999996 -12.290552)
				(mid 0.946792 -12.726804)
				(end 0.51054 -13.780008)
			)
			(arc
				(start 0.51054 -17.769332)
				(mid 0.517626 -17.795211)
				(end 0.536956 -17.813782)
			)
			(xy 0.62738 -17.863566)
		)
		(stroke
			(width 0)
			(type solid)
		)
		(fill yes)
		(layer "In6.Cu")
		(net "GND")
	)
	(gr_poly
		(pts
			(xy 32.429958 -134.567168) (xy 33.81248 -134.567168) (xy 33.890966 -134.488682) (xy 33.890966 -134.320534)
			(xy 33.890966 -134.0866) (xy 33.763712 -133.959346) (xy 33.763712 -132.107178) (xy 33.360106 -131.703064)
			(xy 30.237938 -131.703064) (xy 29.8704 -131.335526) (xy 29.8704 -126.402846) (xy 29.568902 -126.101348)
			(xy 28.90139 -126.101348) (xy 28.886871 -126.101851) (xy 28.859002 -126.110002) (xy 28.834555 -126.125672)
			(xy 28.81551 -126.14759) (xy 28.803407 -126.173985) (xy 28.799226 -126.202719) (xy 28.803305 -126.231469)
			(xy 28.808934 -126.244858) (xy 28.82534 -126.282149) (xy 28.851014 -126.359471) (xy 28.868296 -126.43909)
			(xy 28.876991 -126.520098) (xy 28.877514 -126.560834) (xy 28.87699 -126.600767) (xy 28.868638 -126.680195)
			(xy 28.85203 -126.758315) (xy 28.827348 -126.834271) (xy 28.794861 -126.907231) (xy 28.754926 -126.976396)
			(xy 28.707981 -127.041008) (xy 28.654539 -127.100359) (xy 28.595186 -127.153798) (xy 28.530572 -127.200741)
			(xy 28.461406 -127.240674) (xy 28.388445 -127.273158) (xy 28.312488 -127.297837) (xy 28.234367 -127.314442)
			(xy 28.154939 -127.322791) (xy 28.115006 -127.323342) (xy 28.077268 -127.322883) (xy 28.002163 -127.315427)
			(xy 27.928161 -127.300587) (xy 27.855987 -127.278509) (xy 27.786348 -127.249409) (xy 27.719924 -127.21357)
			(xy 27.657366 -127.171345) (xy 27.599286 -127.123146) (xy 27.546251 -127.069445) (xy 27.52217 -127.040386)
			(xy 27.512866 -127.029611) (xy 27.489574 -127.013264) (xy 27.462673 -127.003987) (xy 27.434256 -127.002504)
			(xy 27.406535 -127.008929) (xy 27.381668 -127.022763) (xy 27.371294 -127.032512) (xy 26.72588 -127.677926)
			(xy 26.72588 -128.04775) (xy 26.725288 -128.07668) (xy 26.715885 -128.133771) (xy 26.697382 -128.188594)
			(xy 26.670266 -128.239707) (xy 26.635249 -128.285769) (xy 26.614628 -128.306068) (xy 26.59888 -128.321054)
			(xy 26.59888 -128.364996) (xy 27.676348 -128.364996) (xy 27.676874 -128.337747) (xy 27.68463 -128.283803)
			(xy 27.699983 -128.231511) (xy 27.722622 -128.181937) (xy 27.752084 -128.136089) (xy 27.787771 -128.0949)
			(xy 27.828957 -128.059208) (xy 27.874802 -128.029741) (xy 27.924374 -128.007097) (xy 27.976664 -127.991738)
			(xy 28.030607 -127.983977) (xy 28.057856 -127.983488) (xy 28.086862 -127.983986) (xy 28.144206 -127.992755)
			(xy 28.199558 -128.010112) (xy 28.251642 -128.035657) (xy 28.299253 -128.0688) (xy 28.341291 -128.108775)
			(xy 28.376787 -128.154659) (xy 28.404919 -128.205391) (xy 28.415488 -128.232408) (xy 28.453668 -128.225025)
			(xy 28.531035 -128.217133) (xy 28.56992 -128.21666) (xy 28.609853 -128.217196) (xy 28.689282 -128.225546)
			(xy 28.767403 -128.242152) (xy 28.84336 -128.266833) (xy 28.916322 -128.299319) (xy 28.985488 -128.339252)
			(xy 29.050102 -128.386196) (xy 29.109454 -128.439637) (xy 29.162896 -128.498989) (xy 29.209841 -128.563602)
			(xy 29.249776 -128.632767) (xy 29.282262 -128.705728) (xy 29.306945 -128.781685) (xy 29.323552 -128.859806)
			(xy 29.331904 -128.939235) (xy 29.332428 -128.979168) (xy 29.331905 -129.019319) (xy 29.323475 -129.099177)
			(xy 29.306696 -129.177706) (xy 29.281752 -129.254036) (xy 29.248921 -129.327319) (xy 29.208566 -129.396745)
			(xy 29.161135 -129.461542) (xy 29.107154 -129.520993) (xy 29.047221 -129.574438) (xy 28.982001 -129.621286)
			(xy 28.947364 -129.6416) (xy 28.949618 -129.656547) (xy 28.952032 -129.686682) (xy 28.95219 -129.701798)
			(xy 28.951704 -129.729049) (xy 28.943948 -129.782997) (xy 28.928593 -129.835292) (xy 28.905951 -129.884869)
			(xy 28.876485 -129.930719) (xy 28.840794 -129.97191) (xy 28.799603 -130.007601) (xy 28.753753 -130.037067)
			(xy 28.704176 -130.059709) (xy 28.651881 -130.075064) (xy 28.597933 -130.08282) (xy 28.543431 -130.08282)
			(xy 28.489483 -130.075064) (xy 28.437188 -130.059709) (xy 28.387611 -130.037067) (xy 28.341761 -130.007601)
			(xy 28.30057 -129.97191) (xy 28.264879 -129.930719) (xy 28.235413 -129.884869) (xy 28.212771 -129.835292)
			(xy 28.197416 -129.782997) (xy 28.18966 -129.729049) (xy 28.189174 -129.701798) (xy 28.189291 -129.686878)
			(xy 28.191582 -129.657125) (xy 28.193746 -129.642362) (xy 28.159024 -129.622048) (xy 28.093606 -129.575222)
			(xy 28.033484 -129.521768) (xy 27.979325 -129.462279) (xy 27.931733 -129.397418) (xy 27.891236 -129.327905)
			(xy 27.858285 -129.254513) (xy 27.833247 -129.17806) (xy 27.8164 -129.099395) (xy 27.807931 -129.019393)
			(xy 27.807412 -128.979168) (xy 27.807847 -128.942515) (xy 27.814858 -128.869544) (xy 27.828849 -128.797585)
			(xy 27.849693 -128.727304) (xy 27.863038 -128.693164) (xy 27.839041 -128.6783) (xy 27.795296 -128.642628)
			(xy 27.75728 -128.600904) (xy 27.725822 -128.554036) (xy 27.701609 -128.503048) (xy 27.685167 -128.44905)
			(xy 27.676856 -128.393219) (xy 27.676348 -128.364996) (xy 26.59888 -128.364996) (xy 26.59888 -128.408938)
			(xy 26.614628 -128.423924) (xy 26.63526 -128.444216) (xy 26.67031 -128.49026) (xy 26.69744 -128.541373)
			(xy 26.715932 -128.596205) (xy 26.725298 -128.653309) (xy 26.72588 -128.682242) (xy 26.72588 -130.880866)
			(xy 27.573222 -130.880866) (xy 27.577293 -130.825244) (xy 27.589419 -130.770807) (xy 27.609342 -130.718716)
			(xy 27.636638 -130.670081) (xy 27.670724 -130.625938) (xy 27.710873 -130.587229) (xy 27.756231 -130.554778)
			(xy 27.805831 -130.529277) (xy 27.858615 -130.51127) (xy 27.913458 -130.50114) (xy 27.969192 -130.499103)
			(xy 28.024629 -130.505203) (xy 28.078586 -130.519309) (xy 28.129915 -130.541121) (xy 28.177521 -130.570175)
			(xy 28.220389 -130.60585) (xy 28.257606 -130.647387) (xy 28.288379 -130.6939) (xy 28.312051 -130.744397)
			(xy 28.328119 -130.797804) (xy 28.336239 -130.85298) (xy 28.336748 -130.880866) (xy 28.336239 -130.908752)
			(xy 28.328119 -130.963928) (xy 28.312051 -131.017335) (xy 28.288379 -131.067832) (xy 28.257606 -131.114345)
			(xy 28.220389 -131.155882) (xy 28.177521 -131.191557) (xy 28.129915 -131.220611) (xy 28.078586 -131.242423)
			(xy 28.024629 -131.256529) (xy 27.969192 -131.262629) (xy 27.913458 -131.260592) (xy 27.858615 -131.250462)
			(xy 27.805831 -131.232455) (xy 27.756231 -131.206954) (xy 27.710873 -131.174503) (xy 27.670724 -131.135794)
			(xy 27.636638 -131.091651) (xy 27.609342 -131.043016) (xy 27.589419 -130.990925) (xy 27.577293 -130.936488)
			(xy 27.573222 -130.880866) (xy 26.72588 -130.880866) (xy 26.72588 -132.093208) (xy 27.83408 -132.093208)
			(xy 27.838151 -132.037586) (xy 27.850277 -131.983149) (xy 27.8702 -131.931058) (xy 27.897496 -131.882423)
			(xy 27.931582 -131.83828) (xy 27.971731 -131.799571) (xy 28.017089 -131.76712) (xy 28.066689 -131.741619)
			(xy 28.119473 -131.723612) (xy 28.174316 -131.713482) (xy 28.23005 -131.711445) (xy 28.285487 -131.717545)
			(xy 28.339444 -131.731651) (xy 28.390773 -131.753463) (xy 28.438379 -131.782517) (xy 28.481247 -131.818192)
			(xy 28.518464 -131.859729) (xy 28.549237 -131.906242) (xy 28.572909 -131.956739) (xy 28.588977 -132.010146)
			(xy 28.597097 -132.065322) (xy 28.597606 -132.093208) (xy 28.597097 -132.121094) (xy 28.588977 -132.17627)
			(xy 28.572909 -132.229677) (xy 28.549237 -132.280174) (xy 28.518464 -132.326687) (xy 28.481247 -132.368224)
			(xy 28.438379 -132.403899) (xy 28.390773 -132.432953) (xy 28.339444 -132.454765) (xy 28.285487 -132.468871)
			(xy 28.23005 -132.474971) (xy 28.174316 -132.472934) (xy 28.119473 -132.462804) (xy 28.066689 -132.444797)
			(xy 28.017089 -132.419296) (xy 27.971731 -132.386845) (xy 27.931582 -132.348136) (xy 27.897496 -132.303993)
			(xy 27.8702 -132.255358) (xy 27.850277 -132.203267) (xy 27.838151 -132.14883) (xy 27.83408 -132.093208)
			(xy 26.72588 -132.093208) (xy 26.72588 -132.156708) (xy 26.702766 -132.213858) (xy 26.702004 -132.215382)
			(xy 26.697365 -132.227168) (xy 26.692365 -132.251995) (xy 26.692098 -132.264658) (xy 26.6924 -132.277318)
			(xy 26.697383 -132.302144) (xy 26.702004 -132.313934) (xy 26.702766 -132.315458) (xy 26.72588 -132.372608)
			(xy 26.72588 -132.88137) (xy 27.159458 -133.314948) (xy 31.223458 -133.314948) (xy 31.416752 -133.508242)
			(xy 31.416752 -135.086344) (xy 31.482792 -135.152384) (xy 31.844488 -135.152384)
		)
		(stroke
			(width 0)
			(type solid)
		)
		(fill yes)
		(layer "In6.Cu")
		(net "PVCCINFAON_CPU1_VREF")
	)
	(gr_poly
		(pts
			(xy 409.455366 -165.563042) (xy 409.464968 -165.552825) (xy 409.478672 -165.528374) (xy 409.485218 -165.501121)
			(xy 409.484116 -165.473114) (xy 409.475447 -165.44646) (xy 409.459864 -165.423162) (xy 409.449524 -165.41369)
			(xy 409.428885 -165.395489) (xy 409.392543 -165.354167) (xy 409.362521 -165.30805) (xy 409.339443 -165.258094)
			(xy 409.323787 -165.20534) (xy 409.315879 -165.150882) (xy 409.315412 -165.123368) (xy 409.315907 -165.095699)
			(xy 409.323905 -165.040942) (xy 409.339729 -164.987914) (xy 409.363046 -164.937729) (xy 409.393368 -164.891437)
			(xy 409.430058 -164.850011) (xy 409.472348 -164.81432) (xy 409.51935 -164.785111) (xy 409.54452 -164.77361)
			(xy 409.575 -164.760402) (xy 409.575 -159.458914) (xy 409.54452 -159.445706) (xy 409.519352 -159.434201)
			(xy 409.472347 -159.404997) (xy 409.430056 -159.369309) (xy 409.393365 -159.327883) (xy 409.363045 -159.281591)
			(xy 409.339732 -159.231404) (xy 409.323915 -159.178375) (xy 409.315927 -159.123617) (xy 409.315412 -159.095948)
			(xy 409.315929 -159.067208) (xy 409.324546 -159.010376) (xy 409.341591 -158.955481) (xy 409.366679 -158.903765)
			(xy 409.399242 -158.856397) (xy 409.418536 -158.83509) (xy 409.428618 -158.823557) (xy 409.441978 -158.796007)
			(xy 409.446577 -158.765735) (xy 409.441999 -158.73546) (xy 409.428658 -158.707901) (xy 409.418536 -158.696406)
			(xy 409.399262 -158.67508) (xy 409.36669 -158.62772) (xy 409.341591 -158.576008) (xy 409.324533 -158.521117)
			(xy 409.315903 -158.464288) (xy 409.315412 -158.435548) (xy 409.315908 -158.40788) (xy 409.323909 -158.353125)
			(xy 409.339734 -158.300099) (xy 409.363053 -158.249916) (xy 409.393376 -158.203627) (xy 409.430067 -158.162203)
			(xy 409.472356 -158.126513) (xy 409.519357 -158.097307) (xy 409.54452 -158.08579) (xy 409.575 -158.072582)
			(xy 409.575 -157.599888) (xy 408.97048 -156.995368) (xy 401.363942 -156.995368) (xy 401.343218 -157.032919)
			(xy 401.295757 -157.104366) (xy 401.241816 -157.171056) (xy 401.181868 -157.232404) (xy 401.11644 -157.28787)
			(xy 401.046107 -157.336966) (xy 400.971487 -157.379263) (xy 400.893234 -157.414388) (xy 400.812036 -157.442032)
			(xy 400.728608 -157.461953) (xy 400.64368 -157.473977) (xy 400.558 -157.477996) (xy 400.47232 -157.473977)
			(xy 400.387392 -157.461953) (xy 400.303964 -157.442032) (xy 400.222766 -157.414388) (xy 400.144513 -157.379263)
			(xy 400.069893 -157.336966) (xy 399.99956 -157.28787) (xy 399.934132 -157.232404) (xy 399.874184 -157.171056)
			(xy 399.820243 -157.104366) (xy 399.772782 -157.032919) (xy 399.752058 -156.995368) (xy 398.36852 -156.995368)
			(xy 397.80718 -157.556708) (xy 397.80718 -158.604896) (xy 399.668996 -158.604896) (xy 399.668996 -158.5202)
			(xy 399.677047 -158.435886) (xy 399.693076 -158.35272) (xy 399.716937 -158.271453) (xy 399.748416 -158.192823)
			(xy 399.787227 -158.117542) (xy 399.833017 -158.04629) (xy 399.885373 -157.979714) (xy 399.943821 -157.918416)
			(xy 400.007831 -157.862951) (xy 400.076823 -157.813822) (xy 400.150173 -157.771473) (xy 400.227216 -157.736289)
			(xy 400.307255 -157.708587) (xy 400.389564 -157.688619) (xy 400.473399 -157.676566) (xy 400.558 -157.672536)
			(xy 400.642601 -157.676566) (xy 400.726436 -157.688619) (xy 400.808745 -157.708587) (xy 400.888784 -157.736289)
			(xy 400.965827 -157.771473) (xy 401.039177 -157.813822) (xy 401.108169 -157.862951) (xy 401.172179 -157.918416)
			(xy 401.230627 -157.979714) (xy 401.282983 -158.04629) (xy 401.328773 -158.117542) (xy 401.367584 -158.192823)
			(xy 401.399063 -158.271453) (xy 401.422924 -158.35272) (xy 401.438953 -158.435886) (xy 401.447004 -158.5202)
			(xy 401.447508 -158.562548) (xy 401.447004 -158.604896) (xy 401.438953 -158.68921) (xy 401.422924 -158.772376)
			(xy 401.399063 -158.853643) (xy 401.367584 -158.932273) (xy 401.328773 -159.007554) (xy 401.282983 -159.078806)
			(xy 401.230627 -159.145382) (xy 401.172179 -159.20668) (xy 401.108169 -159.262145) (xy 401.039177 -159.311274)
			(xy 400.965827 -159.353623) (xy 400.888784 -159.388807) (xy 400.808745 -159.416509) (xy 400.726436 -159.436477)
			(xy 400.642601 -159.44853) (xy 400.558 -159.452561) (xy 400.473399 -159.44853) (xy 400.389564 -159.436477)
			(xy 400.307255 -159.416509) (xy 400.227216 -159.388807) (xy 400.150173 -159.353623) (xy 400.076823 -159.311274)
			(xy 400.007831 -159.262145) (xy 399.943821 -159.20668) (xy 399.885373 -159.145382) (xy 399.833017 -159.078806)
			(xy 399.787227 -159.007554) (xy 399.748416 -158.932273) (xy 399.716937 -158.853643) (xy 399.693076 -158.772376)
			(xy 399.677047 -158.68921) (xy 399.668996 -158.604896) (xy 397.80718 -158.604896) (xy 397.80718 -162.785552)
			(xy 399.642589 -162.785552) (xy 399.646611 -162.699832) (xy 399.658642 -162.614864) (xy 399.678578 -162.531397)
			(xy 399.706241 -162.450163) (xy 399.74139 -162.371877) (xy 399.783716 -162.297226) (xy 399.832845 -162.226867)
			(xy 399.888348 -162.161417) (xy 399.949735 -162.101453) (xy 400.016468 -162.0475) (xy 400.08796 -162.000033)
			(xy 400.163582 -161.959469) (xy 400.242671 -161.926165) (xy 400.324531 -161.900413) (xy 400.408442 -161.88244)
			(xy 400.493668 -161.872404) (xy 400.57946 -161.870392) (xy 400.665062 -161.876423) (xy 400.749724 -161.890443)
			(xy 400.832701 -161.912329) (xy 400.913264 -161.94189) (xy 400.990704 -161.978864) (xy 401.064343 -162.022928)
			(xy 401.133531 -162.073694) (xy 401.197662 -162.130715) (xy 401.256171 -162.193491) (xy 401.308544 -162.261471)
			(xy 401.354322 -162.334056) (xy 401.393102 -162.410608) (xy 401.424543 -162.490456) (xy 401.448369 -162.572897)
			(xy 401.46437 -162.657207) (xy 401.472405 -162.742645) (xy 401.472908 -162.785552) (xy 401.472405 -162.828459)
			(xy 401.46437 -162.913897) (xy 401.448369 -162.998207) (xy 401.424543 -163.080648) (xy 401.393102 -163.160496)
			(xy 401.354322 -163.237048) (xy 401.308544 -163.309633) (xy 401.256171 -163.377613) (xy 401.197662 -163.440389)
			(xy 401.133531 -163.49741) (xy 401.064343 -163.548176) (xy 400.990704 -163.59224) (xy 400.913264 -163.629214)
			(xy 400.832701 -163.658775) (xy 400.749724 -163.680661) (xy 400.665062 -163.694681) (xy 400.57946 -163.700712)
			(xy 400.493668 -163.6987) (xy 400.408442 -163.688664) (xy 400.324531 -163.670691) (xy 400.242671 -163.644939)
			(xy 400.163582 -163.611635) (xy 400.08796 -163.571071) (xy 400.016468 -163.523604) (xy 399.949735 -163.469651)
			(xy 399.888348 -163.409687) (xy 399.832845 -163.344237) (xy 399.783716 -163.273878) (xy 399.74139 -163.199227)
			(xy 399.706241 -163.120941) (xy 399.678578 -163.039707) (xy 399.658642 -162.95624) (xy 399.646611 -162.871272)
			(xy 399.642589 -162.785552) (xy 397.80718 -162.785552) (xy 397.80718 -164.827896) (xy 399.668996 -164.827896)
			(xy 399.668996 -164.7432) (xy 399.677047 -164.658886) (xy 399.693076 -164.57572) (xy 399.716937 -164.494453)
			(xy 399.748416 -164.415823) (xy 399.787227 -164.340542) (xy 399.833017 -164.26929) (xy 399.885373 -164.202714)
			(xy 399.943821 -164.141416) (xy 400.007831 -164.085951) (xy 400.076823 -164.036822) (xy 400.150173 -163.994473)
			(xy 400.227216 -163.959289) (xy 400.307255 -163.931587) (xy 400.389564 -163.911619) (xy 400.473399 -163.899566)
			(xy 400.558 -163.895536) (xy 400.642601 -163.899566) (xy 400.726436 -163.911619) (xy 400.808745 -163.931587)
			(xy 400.888784 -163.959289) (xy 400.965827 -163.994473) (xy 401.039177 -164.036822) (xy 401.108169 -164.085951)
			(xy 401.172179 -164.141416) (xy 401.230627 -164.202714) (xy 401.282983 -164.26929) (xy 401.328773 -164.340542)
			(xy 401.367584 -164.415823) (xy 401.399063 -164.494453) (xy 401.422924 -164.57572) (xy 401.438953 -164.658886)
			(xy 401.447004 -164.7432) (xy 401.447508 -164.785548) (xy 401.447004 -164.827896) (xy 401.438953 -164.91221)
			(xy 401.422924 -164.995376) (xy 401.399063 -165.076643) (xy 401.367584 -165.155273) (xy 401.328773 -165.230554)
			(xy 401.282983 -165.301806) (xy 401.230627 -165.368382) (xy 401.172179 -165.42968) (xy 401.108169 -165.485145)
			(xy 401.039177 -165.534274) (xy 400.965827 -165.576623) (xy 400.888784 -165.611807) (xy 400.808745 -165.639509)
			(xy 400.726436 -165.659477) (xy 400.642601 -165.67153) (xy 400.558 -165.675561) (xy 400.473399 -165.67153)
			(xy 400.389564 -165.659477) (xy 400.307255 -165.639509) (xy 400.227216 -165.611807) (xy 400.150173 -165.576623)
			(xy 400.076823 -165.534274) (xy 400.007831 -165.485145) (xy 399.943821 -165.42968) (xy 399.885373 -165.368382)
			(xy 399.833017 -165.301806) (xy 399.787227 -165.230554) (xy 399.748416 -165.155273) (xy 399.716937 -165.076643)
			(xy 399.693076 -164.995376) (xy 399.677047 -164.91221) (xy 399.668996 -164.827896) (xy 397.80718 -164.827896)
			(xy 397.80718 -164.965888) (xy 399.01622 -166.174928) (xy 408.84348 -166.174928)
		)
		(stroke
			(width 0)
			(type solid)
		)
		(fill yes)
		(layer "In6.Cu")
		(net "PVCCD_HV_CPU0")
	)
	(gr_poly
		(pts
			(xy 70.037706 -172.687488) (xy 70.051862 -172.687036) (xy 70.079091 -172.67928) (xy 70.103139 -172.664338)
			(xy 70.122154 -172.643363) (xy 70.134671 -172.617969) (xy 70.139727 -172.590112) (xy 70.136932 -172.561939)
			(xy 70.126501 -172.535619) (xy 70.109237 -172.51318) (xy 70.098158 -172.504354) (xy 70.064249 -172.478525)
			(xy 70.000873 -172.421512) (xy 69.943073 -172.358852) (xy 69.891349 -172.29109) (xy 69.84615 -172.218813)
			(xy 69.807868 -172.142645) (xy 69.776833 -172.063248) (xy 69.753316 -171.98131) (xy 69.737519 -171.89754)
			(xy 69.72958 -171.812663) (xy 69.729096 -171.77004) (xy 69.729584 -171.727764) (xy 69.737386 -171.643572)
			(xy 69.752922 -171.560459) (xy 69.776061 -171.479135) (xy 69.806605 -171.400292) (xy 69.844293 -171.324604)
			(xy 69.888804 -171.252716) (xy 69.939758 -171.185242) (xy 69.996721 -171.122757) (xy 70.059206 -171.065794)
			(xy 70.12668 -171.01484) (xy 70.198568 -170.970329) (xy 70.274256 -170.932641) (xy 70.353099 -170.902097)
			(xy 70.434423 -170.878958) (xy 70.517536 -170.863422) (xy 70.601728 -170.85562) (xy 70.68628 -170.85562)
			(xy 70.770472 -170.863422) (xy 70.853585 -170.878958) (xy 70.934909 -170.902097) (xy 71.013752 -170.932641)
			(xy 71.08944 -170.970329) (xy 71.161328 -171.01484) (xy 71.228802 -171.065794) (xy 71.291287 -171.122757)
			(xy 71.34825 -171.185242) (xy 71.399204 -171.252716) (xy 71.443715 -171.324604) (xy 71.481403 -171.400292)
			(xy 71.511947 -171.479135) (xy 71.535086 -171.560459) (xy 71.550622 -171.643572) (xy 71.558424 -171.727764)
			(xy 71.558912 -171.77004) (xy 71.558425 -171.812664) (xy 71.550501 -171.897544) (xy 71.534715 -171.981318)
			(xy 71.511204 -172.063261) (xy 71.480172 -172.142661) (xy 71.441889 -172.21883) (xy 71.396686 -172.291107)
			(xy 71.344956 -172.358867) (xy 71.287147 -172.42152) (xy 71.22376 -172.478524) (xy 71.18985 -172.504354)
			(xy 71.17877 -172.513158) (xy 71.161557 -172.535608) (xy 71.151167 -172.561919) (xy 71.148395 -172.590072)
			(xy 71.153456 -172.617904) (xy 71.165961 -172.643279) (xy 71.184949 -172.664249) (xy 71.208963 -172.679202)
			(xy 71.236158 -172.686992) (xy 71.250302 -172.687488) (xy 73.30186 -172.687488) (xy 75.946 -170.043348)
			(xy 75.946 -168.906444) (xy 75.95108 -168.884346) (xy 75.95108 -163.167568) (xy 75.08494 -162.301428)
			(xy 75.050396 -162.32378) (xy 75.027134 -162.338272) (xy 74.977336 -162.36116) (xy 74.924776 -162.376688)
			(xy 74.870535 -162.384535) (xy 74.843132 -162.384994) (xy 74.815878 -162.384533) (xy 74.761924 -162.376779)
			(xy 74.709623 -162.361426) (xy 74.66004 -162.338785) (xy 74.614184 -162.309318) (xy 74.572989 -162.273624)
			(xy 74.537293 -162.23243) (xy 74.507823 -162.186576) (xy 74.48518 -162.136993) (xy 74.469824 -162.084693)
			(xy 74.462068 -162.03074) (xy 74.461624 -162.003486) (xy 74.462064 -161.977486) (xy 74.469122 -161.925968)
			(xy 74.483105 -161.875884) (xy 74.503755 -161.828161) (xy 74.53069 -161.783681) (xy 74.546714 -161.763202)
			(xy 73.61936 -160.835848) (xy 72.17918 -160.835848) (xy 70.910704 -162.104324) (xy 68.959476 -162.104324)
			(xy 67.888612 -161.03346) (xy 63.270638 -161.03346) (xy 63.123572 -161.180526) (xy 63.123572 -164.634926)
			(xy 69.007995 -164.634926) (xy 69.012017 -164.549206) (xy 69.024048 -164.464238) (xy 69.043984 -164.380771)
			(xy 69.071647 -164.299537) (xy 69.106796 -164.221251) (xy 69.149122 -164.1466) (xy 69.198251 -164.076241)
			(xy 69.253754 -164.010791) (xy 69.315141 -163.950827) (xy 69.381874 -163.896874) (xy 69.453366 -163.849407)
			(xy 69.528988 -163.808843) (xy 69.608077 -163.775539) (xy 69.689937 -163.749787) (xy 69.773848 -163.731814)
			(xy 69.859074 -163.721778) (xy 69.944866 -163.719766) (xy 70.030468 -163.725797) (xy 70.11513 -163.739817)
			(xy 70.198107 -163.761703) (xy 70.27867 -163.791264) (xy 70.35611 -163.828238) (xy 70.429749 -163.872302)
			(xy 70.498937 -163.923068) (xy 70.563068 -163.980089) (xy 70.621577 -164.042865) (xy 70.67395 -164.110845)
			(xy 70.719728 -164.18343) (xy 70.758508 -164.259982) (xy 70.789949 -164.33983) (xy 70.813775 -164.422271)
			(xy 70.829776 -164.506581) (xy 70.837811 -164.592019) (xy 70.838314 -164.634926) (xy 70.837811 -164.677833)
			(xy 70.829776 -164.763271) (xy 70.813775 -164.847581) (xy 70.789949 -164.930022) (xy 70.758508 -165.00987)
			(xy 70.719728 -165.086422) (xy 70.67395 -165.159007) (xy 70.621577 -165.226987) (xy 70.563068 -165.289763)
			(xy 70.498937 -165.346784) (xy 70.429749 -165.39755) (xy 70.35611 -165.441614) (xy 70.27867 -165.478588)
			(xy 70.198107 -165.508149) (xy 70.11513 -165.530035) (xy 70.030468 -165.544055) (xy 69.944866 -165.550086)
			(xy 69.859074 -165.548074) (xy 69.773848 -165.538038) (xy 69.689937 -165.520065) (xy 69.608077 -165.494313)
			(xy 69.528988 -165.461009) (xy 69.453366 -165.420445) (xy 69.381874 -165.372978) (xy 69.315141 -165.319025)
			(xy 69.253754 -165.259061) (xy 69.198251 -165.193611) (xy 69.149122 -165.123252) (xy 69.106796 -165.048601)
			(xy 69.071647 -164.970315) (xy 69.043984 -164.889081) (xy 69.024048 -164.805614) (xy 69.012017 -164.720646)
			(xy 69.007995 -164.634926) (xy 63.123572 -164.634926) (xy 63.123572 -166.67727) (xy 69.034402 -166.67727)
			(xy 69.034402 -166.592574) (xy 69.042453 -166.50826) (xy 69.058482 -166.425094) (xy 69.082343 -166.343827)
			(xy 69.113822 -166.265197) (xy 69.152633 -166.189916) (xy 69.198423 -166.118664) (xy 69.250779 -166.052088)
			(xy 69.309227 -165.99079) (xy 69.373237 -165.935325) (xy 69.442229 -165.886196) (xy 69.515579 -165.843847)
			(xy 69.592622 -165.808663) (xy 69.672661 -165.780961) (xy 69.75497 -165.760993) (xy 69.838805 -165.74894)
			(xy 69.923406 -165.74491) (xy 70.008007 -165.74894) (xy 70.091842 -165.760993) (xy 70.174151 -165.780961)
			(xy 70.25419 -165.808663) (xy 70.331233 -165.843847) (xy 70.404583 -165.886196) (xy 70.473575 -165.935325)
			(xy 70.537585 -165.99079) (xy 70.596033 -166.052088) (xy 70.648389 -166.118664) (xy 70.694179 -166.189916)
			(xy 70.73299 -166.265197) (xy 70.764469 -166.343827) (xy 70.78833 -166.425094) (xy 70.804359 -166.50826)
			(xy 70.81241 -166.592574) (xy 70.812914 -166.634922) (xy 70.81241 -166.67727) (xy 70.804359 -166.761584)
			(xy 70.78833 -166.84475) (xy 70.764469 -166.926017) (xy 70.73299 -167.004647) (xy 70.694179 -167.079928)
			(xy 70.648389 -167.15118) (xy 70.596033 -167.217756) (xy 70.537585 -167.279054) (xy 70.473575 -167.334519)
			(xy 70.404583 -167.383648) (xy 70.331233 -167.425997) (xy 70.25419 -167.461181) (xy 70.174151 -167.488883)
			(xy 70.091842 -167.508851) (xy 70.008007 -167.520904) (xy 69.923406 -167.524935) (xy 69.838805 -167.520904)
			(xy 69.75497 -167.508851) (xy 69.672661 -167.488883) (xy 69.592622 -167.461181) (xy 69.515579 -167.425997)
			(xy 69.442229 -167.383648) (xy 69.373237 -167.334519) (xy 69.309227 -167.279054) (xy 69.250779 -167.217756)
			(xy 69.198423 -167.15118) (xy 69.152633 -167.079928) (xy 69.113822 -167.004647) (xy 69.082343 -166.926017)
			(xy 69.058482 -166.84475) (xy 69.042453 -166.761584) (xy 69.034402 -166.67727) (xy 63.123572 -166.67727)
			(xy 63.123572 -169.185844) (xy 63.284608 -169.34688) (xy 64.9986 -169.34688) (xy 67.585336 -171.933616)
			(xy 67.59545 -171.943089) (xy 67.619569 -171.956709) (xy 67.646464 -171.963337) (xy 67.67415 -171.962486)
			(xy 67.700586 -171.954217) (xy 67.723823 -171.939141) (xy 67.742148 -171.918369) (xy 67.754208 -171.893433)
			(xy 67.759114 -171.866171) (xy 67.75831 -171.852336) (xy 67.756521 -171.831809) (xy 67.754615 -171.790644)
			(xy 67.7545 -171.77004) (xy 67.755004 -171.727692) (xy 67.763055 -171.643378) (xy 67.779084 -171.560212)
			(xy 67.802945 -171.478945) (xy 67.834424 -171.400315) (xy 67.873235 -171.325034) (xy 67.919025 -171.253782)
			(xy 67.971381 -171.187206) (xy 68.029829 -171.125908) (xy 68.093839 -171.070443) (xy 68.162831 -171.021314)
			(xy 68.236181 -170.978965) (xy 68.313224 -170.943781) (xy 68.393263 -170.916079) (xy 68.475572 -170.896111)
			(xy 68.559407 -170.884058) (xy 68.644008 -170.880028) (xy 68.728609 -170.884058) (xy 68.812444 -170.896111)
			(xy 68.894753 -170.916079) (xy 68.974792 -170.943781) (xy 69.051835 -170.978965) (xy 69.125185 -171.021314)
			(xy 69.194177 -171.070443) (xy 69.258187 -171.125908) (xy 69.316635 -171.187206) (xy 69.368991 -171.253782)
			(xy 69.414781 -171.325034) (xy 69.453592 -171.400315) (xy 69.485071 -171.478945) (xy 69.508932 -171.560212)
			(xy 69.524961 -171.643378) (xy 69.533012 -171.727692) (xy 69.533516 -171.77004) (xy 69.53301 -171.813061)
			(xy 69.524698 -171.898701) (xy 69.508156 -171.983138) (xy 69.483538 -172.065583) (xy 69.451074 -172.145266)
			(xy 69.411068 -172.221441) (xy 69.363894 -172.293399) (xy 69.309992 -172.360464) (xy 69.249866 -172.422012)
			(xy 69.184078 -172.477467) (xy 69.14896 -172.502322) (xy 69.13744 -172.510875) (xy 69.119309 -172.533095)
			(xy 69.108071 -172.55948) (xy 69.104615 -172.587949) (xy 69.109211 -172.616257) (xy 69.121499 -172.64217)
			(xy 69.140507 -172.663644) (xy 69.164738 -172.678985) (xy 69.192279 -172.686982) (xy 69.206618 -172.687488)
		)
		(stroke
			(width 0)
			(type solid)
		)
		(fill yes)
		(layer "In6.Cu")
		(net "PVCCD_HV_CPU1")
	)
	(gr_poly
		(pts
			(xy 63.514478 -25.911048) (xy 63.528923 -25.910533) (xy 63.556651 -25.902425) (xy 63.581002 -25.886879)
			(xy 63.600028 -25.865138) (xy 63.612207 -25.838941) (xy 63.616566 -25.810382) (xy 63.612756 -25.781744)
			(xy 63.607442 -25.7683) (xy 63.59717 -25.743909) (xy 63.582696 -25.693002) (xy 63.575394 -25.640584)
			(xy 63.57493 -25.614122) (xy 63.575416 -25.586871) (xy 63.583172 -25.532923) (xy 63.598527 -25.480628)
			(xy 63.621169 -25.431051) (xy 63.650635 -25.385201) (xy 63.686326 -25.34401) (xy 63.727517 -25.308319)
			(xy 63.773367 -25.278853) (xy 63.822944 -25.256211) (xy 63.875239 -25.240856) (xy 63.929187 -25.2331)
			(xy 63.983689 -25.2331) (xy 64.037637 -25.240856) (xy 64.089932 -25.256211) (xy 64.139509 -25.278853)
			(xy 64.185359 -25.308319) (xy 64.22655 -25.34401) (xy 64.262241 -25.385201) (xy 64.291707 -25.431051)
			(xy 64.314349 -25.480628) (xy 64.329704 -25.532923) (xy 64.33746 -25.586871) (xy 64.337946 -25.614122)
			(xy 64.337494 -25.640584) (xy 64.330184 -25.693002) (xy 64.315707 -25.743909) (xy 64.305434 -25.7683)
			(xy 64.300033 -25.781724) (xy 64.296186 -25.810391) (xy 64.300532 -25.838985) (xy 64.312721 -25.865215)
			(xy 64.331775 -25.886975) (xy 64.356165 -25.90252) (xy 64.383936 -25.910602) (xy 64.398398 -25.911048)
			(xy 69.65696 -25.911048) (xy 70.34022 -25.227788) (xy 70.34022 -17.033748) (xy 67.51828 -14.211808)
			(xy 67.51828 -11.946128) (xy 67.19062 -11.618468) (xy 62.28588 -11.618468) (xy 62.28588 -14.87805)
			(xy 62.306762 -14.894789) (xy 62.344083 -14.933148) (xy 62.375671 -14.976349) (xy 62.400907 -15.023544)
			(xy 62.419295 -15.073804) (xy 62.430472 -15.126142) (xy 62.43422 -15.179529) (xy 62.430464 -15.232916)
			(xy 62.419278 -15.285252) (xy 62.400883 -15.33551) (xy 62.37564 -15.382701) (xy 62.344045 -15.425897)
			(xy 62.306718 -15.464251) (xy 62.28588 -15.481046) (xy 62.28588 -16.8529) (xy 62.330584 -16.85798)
			(xy 62.358075 -16.861723) (xy 62.411651 -16.876132) (xy 62.462576 -16.898149) (xy 62.509775 -16.927309)
			(xy 62.552253 -16.962997) (xy 62.589115 -17.004462) (xy 62.619582 -17.050827) (xy 62.643013 -17.101117)
			(xy 62.658914 -17.15427) (xy 62.666948 -17.209165) (xy 62.666947 -17.264646) (xy 62.658911 -17.319541)
			(xy 62.643009 -17.372693) (xy 62.619577 -17.422982) (xy 62.589108 -17.469347) (xy 62.552245 -17.510811)
			(xy 62.509766 -17.546498) (xy 62.462566 -17.575656) (xy 62.411641 -17.597672) (xy 62.358064 -17.612079)
			(xy 62.330584 -17.615916) (xy 62.28588 -17.620996) (xy 62.28588 -18.280144) (xy 62.539926 -18.280144)
			(xy 62.539926 -18.225651) (xy 62.547682 -18.171712) (xy 62.563034 -18.119426) (xy 62.585671 -18.069856)
			(xy 62.615132 -18.024013) (xy 62.650817 -17.982829) (xy 62.691999 -17.947142) (xy 62.737841 -17.917679)
			(xy 62.787409 -17.89504) (xy 62.839695 -17.879685) (xy 62.893633 -17.871928) (xy 62.92088 -17.87144)
			(xy 62.935864 -17.871546) (xy 62.965744 -17.873838) (xy 62.98057 -17.876012) (xy 62.994395 -17.877749)
			(xy 63.022057 -17.874491) (xy 63.047809 -17.863876) (xy 63.069732 -17.846695) (xy 63.086194 -17.824227)
			(xy 63.09597 -17.798146) (xy 63.09833 -17.770392) (xy 63.09614 -17.756632) (xy 63.09292 -17.738708)
			(xy 63.089488 -17.702452) (xy 63.089282 -17.684242) (xy 63.08971 -17.656985) (xy 63.097462 -17.603026)
			(xy 63.112815 -17.550719) (xy 63.135456 -17.50113) (xy 63.164924 -17.455268) (xy 63.200619 -17.414066)
			(xy 63.241814 -17.378364) (xy 63.287671 -17.348888) (xy 63.337257 -17.326239) (xy 63.389561 -17.310877)
			(xy 63.443519 -17.303115) (xy 63.498032 -17.303111) (xy 63.551991 -17.310866) (xy 63.604297 -17.326221)
			(xy 63.653885 -17.348864) (xy 63.699746 -17.378334) (xy 63.740946 -17.414031) (xy 63.776647 -17.455228)
			(xy 63.80612 -17.501087) (xy 63.828768 -17.550673) (xy 63.844127 -17.602978) (xy 63.851886 -17.656936)
			(xy 63.851888 -17.711449) (xy 63.84413 -17.765408) (xy 63.828773 -17.817713) (xy 63.806127 -17.867301)
			(xy 63.776655 -17.91316) (xy 63.740957 -17.954359) (xy 63.699758 -17.990057) (xy 63.653898 -18.019529)
			(xy 63.604311 -18.042174) (xy 63.552005 -18.057531) (xy 63.498047 -18.065288) (xy 63.47079 -18.06575)
			(xy 63.455806 -18.065635) (xy 63.425926 -18.063349) (xy 63.4111 -18.061178) (xy 63.397278 -18.059423)
			(xy 63.369615 -18.062688) (xy 63.343865 -18.073307) (xy 63.321942 -18.090491) (xy 63.305481 -18.112961)
			(xy 63.295705 -18.139043) (xy 63.293342 -18.166797) (xy 63.29553 -18.180558) (xy 63.298748 -18.198482)
			(xy 63.302181 -18.234739) (xy 63.302388 -18.252948) (xy 63.30187 -18.280195) (xy 63.294109 -18.334133)
			(xy 63.27875 -18.386417) (xy 63.256107 -18.435984) (xy 63.226641 -18.481823) (xy 63.190951 -18.523003)
			(xy 63.149765 -18.558685) (xy 63.103919 -18.588142) (xy 63.054348 -18.610776) (xy 63.002061 -18.626124)
			(xy 62.948121 -18.633876) (xy 62.893628 -18.633872) (xy 62.83969 -18.626114) (xy 62.787404 -18.610758)
			(xy 62.737836 -18.588118) (xy 62.691995 -18.558655) (xy 62.650813 -18.522967) (xy 62.615129 -18.481783)
			(xy 62.585668 -18.435939) (xy 62.563032 -18.386369) (xy 62.54768 -18.334083) (xy 62.539926 -18.280144)
			(xy 62.28588 -18.280144) (xy 62.28588 -19.268948) (xy 62.538862 -19.268948) (xy 62.542933 -19.213326)
			(xy 62.555059 -19.158889) (xy 62.574982 -19.106798) (xy 62.602278 -19.058163) (xy 62.636364 -19.01402)
			(xy 62.676513 -18.975311) (xy 62.721871 -18.94286) (xy 62.771471 -18.917359) (xy 62.824255 -18.899352)
			(xy 62.879098 -18.889222) (xy 62.934832 -18.887185) (xy 62.990269 -18.893285) (xy 63.044226 -18.907391)
			(xy 63.095555 -18.929203) (xy 63.143161 -18.958257) (xy 63.186029 -18.993932) (xy 63.223246 -19.035469)
			(xy 63.254019 -19.081982) (xy 63.277691 -19.132479) (xy 63.293759 -19.185886) (xy 63.301879 -19.241062)
			(xy 63.302388 -19.268948) (xy 63.301879 -19.296834) (xy 63.293759 -19.35201) (xy 63.277691 -19.405417)
			(xy 63.254019 -19.455914) (xy 63.223246 -19.502427) (xy 63.186029 -19.543964) (xy 63.143161 -19.579639)
			(xy 63.095555 -19.608693) (xy 63.044226 -19.630505) (xy 62.990269 -19.644611) (xy 62.934832 -19.650711)
			(xy 62.879098 -19.648674) (xy 62.824255 -19.638544) (xy 62.771471 -19.620537) (xy 62.721871 -19.595036)
			(xy 62.676513 -19.562585) (xy 62.636364 -19.523876) (xy 62.602278 -19.479733) (xy 62.574982 -19.431098)
			(xy 62.555059 -19.379007) (xy 62.542933 -19.32457) (xy 62.538862 -19.268948) (xy 62.28588 -19.268948)
			(xy 62.28588 -23.404322) (xy 62.63462 -23.404322) (xy 62.638691 -23.3487) (xy 62.650817 -23.294263)
			(xy 62.67074 -23.242172) (xy 62.698036 -23.193537) (xy 62.732122 -23.149394) (xy 62.772271 -23.110685)
			(xy 62.817629 -23.078234) (xy 62.867229 -23.052733) (xy 62.920013 -23.034726) (xy 62.974856 -23.024596)
			(xy 63.03059 -23.022559) (xy 63.086027 -23.028659) (xy 63.139984 -23.042765) (xy 63.191313 -23.064577)
			(xy 63.238919 -23.093631) (xy 63.281787 -23.129306) (xy 63.319004 -23.170843) (xy 63.349777 -23.217356)
			(xy 63.373449 -23.267853) (xy 63.389517 -23.32126) (xy 63.397637 -23.376436) (xy 63.398146 -23.404322)
			(xy 63.397637 -23.432208) (xy 63.389517 -23.487384) (xy 63.373449 -23.540791) (xy 63.349777 -23.591288)
			(xy 63.319004 -23.637801) (xy 63.281787 -23.679338) (xy 63.238919 -23.715013) (xy 63.191313 -23.744067)
			(xy 63.139984 -23.765879) (xy 63.086027 -23.779985) (xy 63.03059 -23.786085) (xy 62.974856 -23.784048)
			(xy 62.920013 -23.773918) (xy 62.867229 -23.755911) (xy 62.817629 -23.73041) (xy 62.772271 -23.697959)
			(xy 62.732122 -23.65925) (xy 62.698036 -23.615107) (xy 62.67074 -23.566472) (xy 62.650817 -23.514381)
			(xy 62.638691 -23.459944) (xy 62.63462 -23.404322) (xy 62.28588 -23.404322) (xy 62.28588 -25.481788)
			(xy 62.410848 -25.606756) (xy 62.42179 -25.616955) (xy 62.448144 -25.631071) (xy 62.477457 -25.636956)
			(xy 62.507218 -25.634106) (xy 62.53488 -25.622765) (xy 62.558076 -25.603903) (xy 62.574821 -25.579135)
			(xy 62.583681 -25.55058) (xy 62.58433 -25.535636) (xy 62.58497 -25.508491) (xy 62.592988 -25.454791)
			(xy 62.608538 -25.402769) (xy 62.631308 -25.353479) (xy 62.660836 -25.307914) (xy 62.696527 -25.266997)
			(xy 62.737659 -25.231554) (xy 62.7834 -25.202301) (xy 62.832828 -25.179829) (xy 62.884942 -25.164593)
			(xy 62.93869 -25.1569) (xy 62.965838 -25.156414) (xy 62.993087 -25.156903) (xy 63.047029 -25.164664)
			(xy 63.099318 -25.180023) (xy 63.148889 -25.202666) (xy 63.194733 -25.232134) (xy 63.235917 -25.267826)
			(xy 63.271602 -25.309015) (xy 63.301063 -25.354864) (xy 63.323698 -25.404438) (xy 63.339049 -25.456729)
			(xy 63.346801 -25.510673) (xy 63.347346 -25.537922) (xy 63.346797 -25.566394) (xy 63.338297 -25.622702)
			(xy 63.321533 -25.677124) (xy 63.296877 -25.728455) (xy 63.281306 -25.752298) (xy 63.273933 -25.763959)
			(xy 63.265101 -25.790084) (xy 63.263588 -25.81762) (xy 63.269504 -25.844555) (xy 63.282415 -25.868923)
			(xy 63.301381 -25.888944) (xy 63.325015 -25.903155) (xy 63.351591 -25.910518) (xy 63.36538 -25.911048)
		)
		(stroke
			(width 0)
			(type solid)
		)
		(fill yes)
		(layer "In6.Cu")
		(net "P12V_OCP_V3_2")
	)
	(gr_poly
		(pts
			(xy 279.057862 -438.522618) (xy 279.067531 -438.512323) (xy 279.081293 -438.48767) (xy 279.087778 -438.460192)
			(xy 279.086491 -438.431988) (xy 279.07753 -438.405215) (xy 279.061582 -438.381918) (xy 279.039863 -438.363879)
			(xy 279.027128 -438.357772) (xy 278.987658 -438.339737) (xy 278.912041 -438.297151) (xy 278.840862 -438.247501)
			(xy 278.774781 -438.191246) (xy 278.714406 -438.128905) (xy 278.660297 -438.061055) (xy 278.612953 -437.988322)
			(xy 278.572813 -437.911379) (xy 278.540246 -437.830937) (xy 278.515555 -437.747739) (xy 278.498966 -437.662555)
			(xy 278.490635 -437.576172) (xy 278.490172 -437.53278) (xy 278.490654 -437.491091) (xy 278.498349 -437.408069)
			(xy 278.513671 -437.32611) (xy 278.53649 -437.245915) (xy 278.56661 -437.168168) (xy 278.603776 -437.093531)
			(xy 278.647669 -437.022642) (xy 278.697916 -436.956105) (xy 278.754088 -436.894488) (xy 278.815705 -436.838316)
			(xy 278.882242 -436.788069) (xy 278.953131 -436.744176) (xy 279.027768 -436.70701) (xy 279.105515 -436.67689)
			(xy 279.18571 -436.654071) (xy 279.267669 -436.638749) (xy 279.350691 -436.631054) (xy 279.39238 -436.630572)
			(xy 279.433624 -436.631033) (xy 279.515769 -436.638564) (xy 279.596882 -436.653566) (xy 279.676286 -436.675912)
			(xy 279.753318 -436.705417) (xy 279.827333 -436.741834) (xy 279.897714 -436.784857) (xy 279.963871 -436.834128)
			(xy 280.025252 -436.889235) (xy 280.081344 -436.949718) (xy 280.106882 -436.982108) (xy 280.115826 -436.992981)
			(xy 280.13843 -437.009747) (xy 280.164752 -437.019708) (xy 280.192794 -437.022107) (xy 280.220425 -437.016764)
			(xy 280.24555 -437.004083) (xy 280.266261 -436.985027) (xy 280.280986 -436.961043) (xy 280.288607 -436.933951)
			(xy 280.289 -436.919878) (xy 280.289 -435.605682) (xy 280.288587 -435.591607) (xy 280.280978 -435.564507)
			(xy 280.266259 -435.540513) (xy 280.24555 -435.52145) (xy 280.220423 -435.508764) (xy 280.192786 -435.503419)
			(xy 280.164741 -435.505823) (xy 280.138417 -435.515791) (xy 280.115815 -435.532567) (xy 280.106882 -435.543452)
			(xy 280.081345 -435.575842) (xy 280.025247 -435.636315) (xy 279.963861 -435.691414) (xy 279.897702 -435.740679)
			(xy 279.827321 -435.783698) (xy 279.753307 -435.820111) (xy 279.676277 -435.849616) (xy 279.596875 -435.871964)
			(xy 279.515765 -435.88697) (xy 279.433623 -435.894508) (xy 279.39238 -435.894988) (xy 279.349428 -435.894476)
			(xy 279.263914 -435.886309) (xy 279.179564 -435.87005) (xy 279.097141 -435.845847) (xy 279.017392 -435.813918)
			(xy 278.941039 -435.774554) (xy 278.868773 -435.72811) (xy 278.801249 -435.675008) (xy 278.739079 -435.615727)
			(xy 278.682825 -435.550805) (xy 278.632997 -435.48083) (xy 278.590046 -435.406435) (xy 278.554361 -435.328295)
			(xy 278.526265 -435.247116) (xy 278.506013 -435.163635) (xy 278.493788 -435.078606) (xy 278.4897 -434.9928)
			(xy 278.493788 -434.906994) (xy 278.506013 -434.821965) (xy 278.526265 -434.738484) (xy 278.554361 -434.657305)
			(xy 278.590046 -434.579165) (xy 278.632997 -434.50477) (xy 278.682825 -434.434795) (xy 278.739079 -434.369873)
			(xy 278.801249 -434.310592) (xy 278.868773 -434.25749) (xy 278.941039 -434.211046) (xy 279.017392 -434.171682)
			(xy 279.097141 -434.139753) (xy 279.179564 -434.11555) (xy 279.263914 -434.099291) (xy 279.349428 -434.091124)
			(xy 279.39238 -434.090572) (xy 279.433624 -434.091033) (xy 279.515769 -434.098564) (xy 279.596882 -434.113566)
			(xy 279.676286 -434.135912) (xy 279.753318 -434.165417) (xy 279.827333 -434.201834) (xy 279.897714 -434.244857)
			(xy 279.963871 -434.294128) (xy 280.025252 -434.349235) (xy 280.081344 -434.409718) (xy 280.106882 -434.442108)
			(xy 280.115826 -434.452981) (xy 280.13843 -434.469747) (xy 280.164752 -434.479708) (xy 280.192794 -434.482107)
			(xy 280.220425 -434.476764) (xy 280.24555 -434.464083) (xy 280.266261 -434.445027) (xy 280.280986 -434.421043)
			(xy 280.288607 -434.393951) (xy 280.289 -434.379878) (xy 280.289 -427.25594) (xy 279.58034 -426.54728)
			(xy 274.94738 -426.54728) (xy 273.86788 -425.46778) (xy 273.86788 -422.6687) (xy 273.31416 -422.11498)
			(xy 243.33835 -422.11498) (xy 243.324552 -422.115446) (xy 243.297968 -422.12285) (xy 243.274337 -422.137103)
			(xy 243.255387 -422.157163) (xy 243.242501 -422.181567) (xy 243.236622 -422.208529) (xy 243.238178 -422.236082)
			(xy 243.247057 -422.262211) (xy 243.262609 -422.285007) (xy 243.272818 -422.294304) (xy 243.293707 -422.312515)
			(xy 243.330514 -422.353944) (xy 243.360932 -422.400267) (xy 243.384319 -422.450507) (xy 243.400183 -422.503605)
			(xy 243.408188 -422.558441) (xy 243.408708 -422.58615) (xy 243.408189 -422.614558) (xy 243.39977 -422.670747)
			(xy 243.383112 -422.725065) (xy 243.358582 -422.776313) (xy 243.326723 -422.823356) (xy 243.288239 -422.865154)
			(xy 243.243983 -422.900782) (xy 243.219732 -422.915588) (xy 243.2077 -422.923181) (xy 243.188072 -422.943761)
			(xy 243.174877 -422.968954) (xy 243.169137 -422.996808) (xy 243.171298 -423.025165) (xy 243.181191 -423.051828)
			(xy 243.198051 -423.074731) (xy 243.209064 -423.083736) (xy 243.231804 -423.101929) (xy 243.272023 -423.144043)
			(xy 243.305378 -423.191778) (xy 243.331094 -423.244026) (xy 243.348575 -423.299574) (xy 243.357414 -423.357133)
			(xy 243.357908 -423.38625) (xy 243.357422 -423.413501) (xy 243.349666 -423.467449) (xy 243.334311 -423.519744)
			(xy 243.311669 -423.569321) (xy 243.282203 -423.615171) (xy 243.246512 -423.656362) (xy 243.205321 -423.692053)
			(xy 243.159471 -423.721519) (xy 243.109894 -423.744161) (xy 243.057599 -423.759516) (xy 243.003651 -423.767272)
			(xy 242.949149 -423.767272) (xy 242.895201 -423.759516) (xy 242.842906 -423.744161) (xy 242.793329 -423.721519)
			(xy 242.747479 -423.692053) (xy 242.706288 -423.656362) (xy 242.670597 -423.615171) (xy 242.641131 -423.569321)
			(xy 242.618489 -423.519744) (xy 242.603134 -423.467449) (xy 242.595378 -423.413501) (xy 242.594892 -423.38625)
			(xy 242.595411 -423.357842) (xy 242.60383 -423.301653) (xy 242.620488 -423.247335) (xy 242.645018 -423.196087)
			(xy 242.676877 -423.149044) (xy 242.715361 -423.107246) (xy 242.759617 -423.071618) (xy 242.783868 -423.056812)
			(xy 242.7959 -423.049219) (xy 242.815528 -423.028639) (xy 242.828723 -423.003446) (xy 242.834463 -422.975592)
			(xy 242.832302 -422.947235) (xy 242.822409 -422.920572) (xy 242.805549 -422.897669) (xy 242.794536 -422.888664)
			(xy 242.771364 -422.870139) (xy 242.7305 -422.827136) (xy 242.69679 -422.778322) (xy 242.671048 -422.724876)
			(xy 242.661948 -422.69664) (xy 242.657104 -422.682453) (xy 242.640479 -422.657523) (xy 242.617331 -422.638497)
			(xy 242.589655 -422.627012) (xy 242.559837 -422.62406) (xy 242.530446 -422.629895) (xy 242.504017 -422.644013)
			(xy 242.493038 -422.654222) (xy 241.09426 -424.053) (xy 241.09426 -433.04206) (xy 267.01141 -433.04206)
			(xy 267.01543 -432.866756) (xy 267.027484 -432.69182) (xy 267.047545 -432.517622) (xy 267.075571 -432.344526)
			(xy 267.111504 -432.172897) (xy 267.155267 -432.003095) (xy 267.20677 -431.835479) (xy 267.265903 -431.6704)
			(xy 267.332542 -431.508206) (xy 267.406547 -431.349238) (xy 267.487762 -431.19383) (xy 267.576017 -431.042308)
			(xy 267.671126 -430.894992) (xy 267.772888 -430.752191) (xy 267.881091 -430.614206) (xy 267.995506 -430.481327)
			(xy 268.115893 -430.353833) (xy 268.241998 -430.231992) (xy 268.373557 -430.116061) (xy 268.510292 -430.006284)
			(xy 268.651917 -429.902891) (xy 268.798133 -429.806099) (xy 268.948632 -429.716113) (xy 269.103099 -429.633121)
			(xy 269.261209 -429.557298) (xy 269.422628 -429.488804) (xy 269.587018 -429.427782) (xy 269.754033 -429.374362)
			(xy 269.923321 -429.328654) (xy 270.094527 -429.290756) (xy 270.26729 -429.260747) (xy 270.441247 -429.23869)
			(xy 270.616033 -429.224631) (xy 270.79128 -429.218601) (xy 270.966618 -429.220611) (xy 271.14168 -429.230658)
			(xy 271.316098 -429.248721) (xy 271.489504 -429.274761) (xy 271.661533 -429.308723) (xy 271.831825 -429.350537)
			(xy 272.000021 -429.400114) (xy 272.165767 -429.457351) (xy 272.328714 -429.522126) (xy 272.488521 -429.594303)
			(xy 272.64485 -429.673731) (xy 272.797374 -429.760243) (xy 272.94577 -429.853656) (xy 273.089728 -429.953775)
			(xy 273.228945 -430.060389) (xy 273.363127 -430.173273) (xy 273.491993 -430.29219) (xy 273.615272 -430.41689)
			(xy 273.732703 -430.547111) (xy 273.844042 -430.682578) (xy 273.949052 -430.823008) (xy 274.047513 -430.968105)
			(xy 274.139219 -431.117563) (xy 274.223977 -431.271068) (xy 274.301607 -431.428298) (xy 274.371948 -431.588921)
			(xy 274.43485 -431.752601) (xy 274.490182 -431.918992) (xy 274.537828 -432.087745) (xy 274.577686 -432.258505)
			(xy 274.609674 -432.430913) (xy 274.633724 -432.604606) (xy 274.649786 -432.779219) (xy 274.657825 -432.954385)
			(xy 274.658328 -433.04206) (xy 274.657825 -433.129735) (xy 274.649786 -433.304901) (xy 274.633724 -433.479514)
			(xy 274.609674 -433.653207) (xy 274.577686 -433.825615) (xy 274.537828 -433.996375) (xy 274.490182 -434.165128)
			(xy 274.43485 -434.331519) (xy 274.371948 -434.495199) (xy 274.301607 -434.655822) (xy 274.223977 -434.813052)
			(xy 274.139219 -434.966557) (xy 274.047513 -435.116015) (xy 273.949052 -435.261112) (xy 273.844042 -435.401542)
			(xy 273.732703 -435.537009) (xy 273.615272 -435.66723) (xy 273.491993 -435.79193) (xy 273.363127 -435.910847)
			(xy 273.228945 -436.023731) (xy 273.089728 -436.130345) (xy 272.94577 -436.230464) (xy 272.797374 -436.323877)
			(xy 272.64485 -436.410389) (xy 272.488521 -436.489817) (xy 272.328714 -436.561994) (xy 272.165767 -436.626769)
			(xy 272.000021 -436.684006) (xy 271.831825 -436.733583) (xy 271.661533 -436.775397) (xy 271.489504 -436.809359)
			(xy 271.316098 -436.835399) (xy 271.14168 -436.853462) (xy 270.966618 -436.863509) (xy 270.79128 -436.865519)
			(xy 270.616033 -436.859489) (xy 270.441247 -436.84543) (xy 270.26729 -436.823373) (xy 270.094527 -436.793364)
			(xy 269.923321 -436.755466) (xy 269.754033 -436.709758) (xy 269.587018 -436.656338) (xy 269.422628 -436.595316)
			(xy 269.261209 -436.526822) (xy 269.103099 -436.450999) (xy 268.948632 -436.368007) (xy 268.798133 -436.278021)
			(xy 268.651917 -436.181229) (xy 268.510292 -436.077836) (xy 268.373557 -435.968059) (xy 268.241998 -435.852128)
			(xy 268.115893 -435.730287) (xy 267.995506 -435.602793) (xy 267.881091 -435.469914) (xy 267.772888 -435.331929)
			(xy 267.671126 -435.189128) (xy 267.576017 -435.041812) (xy 267.487762 -434.89029) (xy 267.406547 -434.734882)
			(xy 267.332542 -434.575914) (xy 267.265903 -434.41372) (xy 267.20677 -434.248641) (xy 267.155267 -434.081025)
			(xy 267.111504 -433.911223) (xy 267.075571 -433.739594) (xy 267.047545 -433.566498) (xy 267.027484 -433.3923)
			(xy 267.01543 -433.217364) (xy 267.01141 -433.04206) (xy 241.09426 -433.04206) (xy 241.09426 -437.31942)
			(xy 242.4811 -438.70626) (xy 278.87422 -438.70626)
		)
		(stroke
			(width 0)
			(type solid)
		)
		(fill yes)
		(layer "In6.Cu")
		(net "GND")
	)
	(gr_poly
		(pts
			(xy 372.3132 -416.6108) (xy 372.3132 -415.8488) (xy 370.2812 -413.8168) (xy 370.2812 -403.267926)
			(xy 370.280716 -403.253233) (xy 370.272359 -403.22506) (xy 370.25633 -403.200431) (xy 370.233953 -403.181383)
			(xy 370.207081 -403.169491) (xy 370.177935 -403.16574) (xy 370.148927 -403.170439) (xy 370.122456 -403.1832)
			(xy 370.111274 -403.192742) (xy 370.090081 -403.211322) (xy 370.043255 -403.242687) (xy 369.992328 -403.26683)
			(xy 369.938406 -403.283226) (xy 369.88266 -403.29152) (xy 369.85448 -403.292056) (xy 369.827226 -403.291569)
			(xy 369.773274 -403.283809) (xy 369.720975 -403.26845) (xy 369.671394 -403.245805) (xy 369.62554 -403.216334)
			(xy 369.584347 -403.180638) (xy 369.548654 -403.139444) (xy 369.519185 -403.093588) (xy 369.496543 -403.044006)
			(xy 369.481187 -402.991707) (xy 369.47343 -402.937754) (xy 369.47343 -402.883246) (xy 369.481187 -402.829293)
			(xy 369.496543 -402.776994) (xy 369.519185 -402.727412) (xy 369.548654 -402.681556) (xy 369.584347 -402.640362)
			(xy 369.62554 -402.604666) (xy 369.671394 -402.575195) (xy 369.720975 -402.55255) (xy 369.773274 -402.537191)
			(xy 369.827226 -402.529431) (xy 369.85448 -402.52904) (xy 369.882662 -402.529544) (xy 369.938413 -402.537833)
			(xy 369.992337 -402.554233) (xy 370.043263 -402.578387) (xy 370.090081 -402.609771) (xy 370.111274 -402.628354)
			(xy 370.122471 -402.637874) (xy 370.148935 -402.650632) (xy 370.177935 -402.65533) (xy 370.207073 -402.65158)
			(xy 370.233938 -402.639691) (xy 370.256308 -402.620648) (xy 370.272333 -402.596025) (xy 370.280687 -402.567859)
			(xy 370.2812 -402.55317) (xy 370.2812 -400.1262) (xy 370.84 -399.5674) (xy 419.481 -399.5674) (xy 421.9956 -402.082)
			(xy 423.6974 -402.082) (xy 424.053 -401.7264) (xy 424.053 -395.4272) (xy 423.7736 -395.1478) (xy 422.8338 -395.1478)
			(xy 421.767 -396.2146) (xy 370.765832 -396.2146) (xy 370.764054 -396.263622) (xy 370.762508 -396.291456)
			(xy 370.752344 -396.346267) (xy 370.734313 -396.399015) (xy 370.708797 -396.448578) (xy 370.67634 -396.4939)
			(xy 370.637633 -396.534015) (xy 370.593499 -396.568071) (xy 370.54488 -396.595341) (xy 370.492809 -396.615246)
			(xy 370.438397 -396.627361) (xy 370.3828 -396.631428) (xy 370.327203 -396.627361) (xy 370.272791 -396.615246)
			(xy 370.22072 -396.595341) (xy 370.172101 -396.568071) (xy 370.127967 -396.534015) (xy 370.08926 -396.4939)
			(xy 370.056803 -396.448578) (xy 370.031287 -396.399015) (xy 370.013256 -396.346267) (xy 370.003092 -396.291456)
			(xy 370.001546 -396.263622) (xy 369.999768 -396.2146) (xy 369.7478 -396.2146) (xy 369.2398 -396.7226)
			(xy 366.9538 -396.7226) (xy 366.395 -397.2814) (xy 366.395 -397.519398) (xy 370.000782 -397.519398)
			(xy 370.004853 -397.463776) (xy 370.016979 -397.409339) (xy 370.036902 -397.357248) (xy 370.064198 -397.308613)
			(xy 370.098284 -397.26447) (xy 370.138433 -397.225761) (xy 370.183791 -397.19331) (xy 370.233391 -397.167809)
			(xy 370.286175 -397.149802) (xy 370.341018 -397.139672) (xy 370.396752 -397.137635) (xy 370.452189 -397.143735)
			(xy 370.506146 -397.157841) (xy 370.557475 -397.179653) (xy 370.605081 -397.208707) (xy 370.647949 -397.244382)
			(xy 370.685166 -397.285919) (xy 370.715939 -397.332432) (xy 370.739611 -397.382929) (xy 370.755679 -397.436336)
			(xy 370.763799 -397.491512) (xy 370.764308 -397.519398) (xy 370.763799 -397.547284) (xy 370.755679 -397.60246)
			(xy 370.740931 -397.651478) (xy 422.832274 -397.651478) (xy 422.836345 -397.595856) (xy 422.848471 -397.541419)
			(xy 422.868394 -397.489328) (xy 422.89569 -397.440693) (xy 422.929776 -397.39655) (xy 422.969925 -397.357841)
			(xy 423.015283 -397.32539) (xy 423.064883 -397.299889) (xy 423.117667 -397.281882) (xy 423.17251 -397.271752)
			(xy 423.228244 -397.269715) (xy 423.283681 -397.275815) (xy 423.337638 -397.289921) (xy 423.388967 -397.311733)
			(xy 423.436573 -397.340787) (xy 423.479441 -397.376462) (xy 423.516658 -397.417999) (xy 423.547431 -397.464512)
			(xy 423.571103 -397.515009) (xy 423.587171 -397.568416) (xy 423.595291 -397.623592) (xy 423.5958 -397.651478)
			(xy 423.595291 -397.679364) (xy 423.587171 -397.73454) (xy 423.571103 -397.787947) (xy 423.547431 -397.838444)
			(xy 423.516658 -397.884957) (xy 423.479441 -397.926494) (xy 423.436573 -397.962169) (xy 423.388967 -397.991223)
			(xy 423.337638 -398.013035) (xy 423.283681 -398.027141) (xy 423.228244 -398.033241) (xy 423.17251 -398.031204)
			(xy 423.117667 -398.021074) (xy 423.064883 -398.003067) (xy 423.015283 -397.977566) (xy 422.969925 -397.945115)
			(xy 422.929776 -397.906406) (xy 422.89569 -397.862263) (xy 422.868394 -397.813628) (xy 422.848471 -397.761537)
			(xy 422.836345 -397.7071) (xy 422.832274 -397.651478) (xy 370.740931 -397.651478) (xy 370.739611 -397.655867)
			(xy 370.715939 -397.706364) (xy 370.685166 -397.752877) (xy 370.647949 -397.794414) (xy 370.605081 -397.830089)
			(xy 370.557475 -397.859143) (xy 370.506146 -397.880955) (xy 370.452189 -397.895061) (xy 370.396752 -397.901161)
			(xy 370.341018 -397.899124) (xy 370.286175 -397.888994) (xy 370.233391 -397.870987) (xy 370.183791 -397.845486)
			(xy 370.138433 -397.813035) (xy 370.098284 -397.774326) (xy 370.064198 -397.730183) (xy 370.036902 -397.681548)
			(xy 370.016979 -397.629457) (xy 370.004853 -397.57502) (xy 370.000782 -397.519398) (xy 366.395 -397.519398)
			(xy 366.395 -398.9324) (xy 367.03 -399.5674) (xy 367.0808 -399.5674) (xy 367.0808 -399.669) (xy 367.095807 -399.68979)
			(xy 367.119679 -399.735165) (xy 367.135973 -399.783778) (xy 367.144267 -399.834373) (xy 367.144808 -399.860008)
			(xy 367.144808 -404.787608) (xy 367.145339 -404.801934) (xy 367.153385 -404.829438) (xy 367.168755 -404.853623)
			(xy 367.19024 -404.872585) (xy 367.216148 -404.884831) (xy 367.244438 -404.889396) (xy 367.272882 -404.885921)
			(xy 367.286286 -404.880826) (xy 367.3101 -404.871091) (xy 367.359692 -404.857395) (xy 367.410676 -404.850505)
			(xy 367.4364 -404.850092) (xy 367.463651 -404.850578) (xy 367.517599 -404.858334) (xy 367.569894 -404.873689)
			(xy 367.619471 -404.896331) (xy 367.665321 -404.925797) (xy 367.706512 -404.961488) (xy 367.742203 -405.002679)
			(xy 367.771669 -405.048529) (xy 367.794311 -405.098106) (xy 367.809666 -405.150401) (xy 367.817422 -405.204349)
			(xy 367.817908 -405.2316) (xy 367.817402 -405.259462) (xy 367.811718 -405.298148) (xy 368.832382 -405.298148)
			(xy 368.836453 -405.242526) (xy 368.848579 -405.188089) (xy 368.868502 -405.135998) (xy 368.895798 -405.087363)
			(xy 368.929884 -405.04322) (xy 368.970033 -405.004511) (xy 369.015391 -404.97206) (xy 369.064991 -404.946559)
			(xy 369.117775 -404.928552) (xy 369.172618 -404.918422) (xy 369.228352 -404.916385) (xy 369.283789 -404.922485)
			(xy 369.337746 -404.936591) (xy 369.389075 -404.958403) (xy 369.436681 -404.987457) (xy 369.479549 -405.023132)
			(xy 369.516766 -405.064669) (xy 369.547539 -405.111182) (xy 369.571211 -405.161679) (xy 369.587279 -405.215086)
			(xy 369.595399 -405.270262) (xy 369.595908 -405.298148) (xy 369.595399 -405.326034) (xy 369.587279 -405.38121)
			(xy 369.571211 -405.434617) (xy 369.547539 -405.485114) (xy 369.516766 -405.531627) (xy 369.479549 -405.573164)
			(xy 369.436681 -405.608839) (xy 369.389075 -405.637893) (xy 369.337746 -405.659705) (xy 369.283789 -405.673811)
			(xy 369.228352 -405.679911) (xy 369.172618 -405.677874) (xy 369.117775 -405.667744) (xy 369.064991 -405.649737)
			(xy 369.015391 -405.624236) (xy 368.970033 -405.591785) (xy 368.929884 -405.553076) (xy 368.895798 -405.508933)
			(xy 368.868502 -405.460298) (xy 368.848579 -405.408207) (xy 368.836453 -405.35377) (xy 368.832382 -405.298148)
			(xy 367.811718 -405.298148) (xy 367.809302 -405.314593) (xy 367.793273 -405.367962) (xy 367.769658 -405.418433)
			(xy 367.738956 -405.464936) (xy 367.70182 -405.506482) (xy 367.680748 -405.524716) (xy 367.66924 -405.535017)
			(xy 367.652513 -405.560965) (xy 367.644286 -405.590721) (xy 367.645308 -405.621576) (xy 367.655486 -405.650722)
			(xy 367.673893 -405.675506) (xy 367.686082 -405.68499) (xy 367.706617 -405.700432) (xy 367.743749 -405.735942)
			(xy 367.775779 -405.776115) (xy 367.802128 -405.820223) (xy 367.822318 -405.867469) (xy 367.835985 -405.916997)
			(xy 367.842881 -405.967911) (xy 367.843308 -405.9936) (xy 367.842822 -406.020851) (xy 367.835066 -406.074799)
			(xy 367.819711 -406.127094) (xy 367.797069 -406.176671) (xy 367.767603 -406.222521) (xy 367.731912 -406.263712)
			(xy 367.690721 -406.299403) (xy 367.644871 -406.328869) (xy 367.595294 -406.351511) (xy 367.542999 -406.366866)
			(xy 367.489051 -406.374622) (xy 367.4618 -406.375108) (xy 367.432384 -406.374537) (xy 367.374253 -406.365465)
			(xy 367.318198 -406.347597) (xy 367.29162 -406.334976) (xy 367.278165 -406.32885) (xy 367.249044 -406.323823)
			(xy 367.219702 -406.327337) (xy 367.192592 -406.339098) (xy 367.16998 -406.358124) (xy 367.153755 -406.382824)
			(xy 367.145275 -406.411133) (xy 367.144808 -406.425908) (xy 367.144808 -408.681428) (xy 367.145313 -408.696602)
			(xy 367.154129 -408.725639) (xy 367.171091 -408.7508) (xy 367.194701 -408.769862) (xy 367.222872 -408.781141)
			(xy 367.253114 -408.783638) (xy 367.282754 -408.777134) (xy 367.296192 -408.770074) (xy 367.317717 -408.758356)
			(xy 367.363131 -408.739926) (xy 367.410532 -408.727466) (xy 367.459139 -408.721181) (xy 367.483644 -408.720798)
			(xy 367.510893 -408.721287) (xy 367.564835 -408.729048) (xy 367.617124 -408.744407) (xy 367.666694 -408.76705)
			(xy 367.712539 -408.796517) (xy 367.753723 -408.832208) (xy 367.789409 -408.873397) (xy 367.818871 -408.919244)
			(xy 367.841508 -408.968818) (xy 367.856861 -409.021108) (xy 367.864616 -409.075051) (xy 367.864616 -409.129549)
			(xy 367.856861 -409.183492) (xy 367.841508 -409.235782) (xy 367.818871 -409.285356) (xy 367.789409 -409.331203)
			(xy 367.753723 -409.372392) (xy 367.712539 -409.408083) (xy 367.666694 -409.43755) (xy 367.617124 -409.460193)
			(xy 367.564835 -409.475552) (xy 367.510893 -409.483313) (xy 367.483644 -409.483814) (xy 367.459138 -409.483438)
			(xy 367.410529 -409.47716) (xy 367.363125 -409.464702) (xy 367.317711 -409.44627) (xy 367.296192 -409.434538)
			(xy 367.282712 -409.427597) (xy 367.253103 -409.421147) (xy 367.222904 -409.423665) (xy 367.194773 -409.434929)
			(xy 367.171182 -409.45395) (xy 367.154208 -409.479054) (xy 367.145344 -409.508032) (xy 367.144808 -409.523184)
			(xy 367.144808 -413.50946) (xy 368.319302 -413.50946) (xy 368.323373 -413.453838) (xy 368.335499 -413.399401)
			(xy 368.355422 -413.34731) (xy 368.382718 -413.298675) (xy 368.416804 -413.254532) (xy 368.456953 -413.215823)
			(xy 368.502311 -413.183372) (xy 368.551911 -413.157871) (xy 368.604695 -413.139864) (xy 368.659538 -413.129734)
			(xy 368.715272 -413.127697) (xy 368.770709 -413.133797) (xy 368.824666 -413.147903) (xy 368.875995 -413.169715)
			(xy 368.923601 -413.198769) (xy 368.966469 -413.234444) (xy 369.003686 -413.275981) (xy 369.034459 -413.322494)
			(xy 369.058131 -413.372991) (xy 369.074199 -413.426398) (xy 369.082319 -413.481574) (xy 369.082828 -413.50946)
			(xy 369.082319 -413.537346) (xy 369.074199 -413.592522) (xy 369.058131 -413.645929) (xy 369.034459 -413.696426)
			(xy 369.003686 -413.742939) (xy 368.966469 -413.784476) (xy 368.923601 -413.820151) (xy 368.875995 -413.849205)
			(xy 368.824666 -413.871017) (xy 368.770709 -413.885123) (xy 368.715272 -413.891223) (xy 368.659538 -413.889186)
			(xy 368.604695 -413.879056) (xy 368.551911 -413.861049) (xy 368.502311 -413.835548) (xy 368.456953 -413.803097)
			(xy 368.416804 -413.764388) (xy 368.382718 -413.720245) (xy 368.355422 -413.67161) (xy 368.335499 -413.619519)
			(xy 368.323373 -413.565082) (xy 368.319302 -413.50946) (xy 367.144808 -413.50946) (xy 367.144808 -415.026348)
			(xy 367.144396 -415.050104) (xy 367.137333 -415.097089) (xy 367.123341 -415.142494) (xy 367.102733 -415.185305)
			(xy 367.08969 -415.205164) (xy 367.0808 -415.218118) (xy 367.0808 -415.2646) (xy 366.413288 -415.932366)
			(xy 366.413288 -417.035234) (xy 366.5982 -417.2204) (xy 371.7036 -417.2204)
		)
		(stroke
			(width 0)
			(type solid)
		)
		(fill yes)
		(layer "In6.Cu")
		(net "P3V3_AUX")
	)
	(gr_poly
		(pts
			(xy 444.88608 -26.147268) (xy 444.88608 -11.852148) (xy 443.4332 -10.399268) (xy 440.61126 -10.399268)
			(xy 436.46598 -14.544548) (xy 438.941462 -14.544548) (xy 438.945533 -14.488926) (xy 438.957659 -14.434489)
			(xy 438.977582 -14.382398) (xy 439.004878 -14.333763) (xy 439.038964 -14.28962) (xy 439.079113 -14.250911)
			(xy 439.124471 -14.21846) (xy 439.174071 -14.192959) (xy 439.226855 -14.174952) (xy 439.281698 -14.164822)
			(xy 439.337432 -14.162785) (xy 439.392869 -14.168885) (xy 439.446826 -14.182991) (xy 439.498155 -14.204803)
			(xy 439.545761 -14.233857) (xy 439.588629 -14.269532) (xy 439.625846 -14.311069) (xy 439.656619 -14.357582)
			(xy 439.680291 -14.408079) (xy 439.696359 -14.461486) (xy 439.704479 -14.516662) (xy 439.704988 -14.544548)
			(xy 439.704479 -14.572434) (xy 439.696359 -14.62761) (xy 439.680291 -14.681017) (xy 439.656619 -14.731514)
			(xy 439.625846 -14.778027) (xy 439.588629 -14.819564) (xy 439.545761 -14.855239) (xy 439.498155 -14.884293)
			(xy 439.446826 -14.906105) (xy 439.392869 -14.920211) (xy 439.337432 -14.926311) (xy 439.281698 -14.924274)
			(xy 439.226855 -14.914144) (xy 439.174071 -14.896137) (xy 439.124471 -14.870636) (xy 439.079113 -14.838185)
			(xy 439.038964 -14.799476) (xy 439.004878 -14.755333) (xy 438.977582 -14.706698) (xy 438.957659 -14.654607)
			(xy 438.945533 -14.60017) (xy 438.941462 -14.544548) (xy 436.46598 -14.544548) (xy 435.915308 -15.09522)
			(xy 435.915308 -15.687548) (xy 438.916062 -15.687548) (xy 438.920133 -15.631926) (xy 438.932259 -15.577489)
			(xy 438.952182 -15.525398) (xy 438.979478 -15.476763) (xy 439.013564 -15.43262) (xy 439.053713 -15.393911)
			(xy 439.099071 -15.36146) (xy 439.148671 -15.335959) (xy 439.201455 -15.317952) (xy 439.256298 -15.307822)
			(xy 439.312032 -15.305785) (xy 439.367469 -15.311885) (xy 439.421426 -15.325991) (xy 439.472755 -15.347803)
			(xy 439.520361 -15.376857) (xy 439.563229 -15.412532) (xy 439.600446 -15.454069) (xy 439.631219 -15.500582)
			(xy 439.654891 -15.551079) (xy 439.670959 -15.604486) (xy 439.679079 -15.659662) (xy 439.679588 -15.687548)
			(xy 439.679079 -15.715434) (xy 439.670959 -15.77061) (xy 439.654891 -15.824017) (xy 439.631219 -15.874514)
			(xy 439.600446 -15.921027) (xy 439.563229 -15.962564) (xy 439.520361 -15.998239) (xy 439.472755 -16.027293)
			(xy 439.421426 -16.049105) (xy 439.367469 -16.063211) (xy 439.312032 -16.069311) (xy 439.256298 -16.067274)
			(xy 439.201455 -16.057144) (xy 439.148671 -16.039137) (xy 439.099071 -16.013636) (xy 439.053713 -15.981185)
			(xy 439.013564 -15.942476) (xy 438.979478 -15.898333) (xy 438.952182 -15.849698) (xy 438.932259 -15.797607)
			(xy 438.920133 -15.74317) (xy 438.916062 -15.687548) (xy 435.915308 -15.687548) (xy 435.915308 -16.80972)
			(xy 435.915777 -16.82426) (xy 435.923975 -16.85216) (xy 435.939702 -16.87662) (xy 435.961682 -16.895659)
			(xy 435.988137 -16.907733) (xy 436.016921 -16.911866) (xy 436.031386 -16.910304) (xy 436.045024 -16.908415)
			(xy 436.072483 -16.906378) (xy 436.08625 -16.90624) (xy 436.113504 -16.9067) (xy 436.167458 -16.914451)
			(xy 436.219759 -16.929804) (xy 436.269342 -16.952444) (xy 436.315198 -16.981911) (xy 436.356393 -17.017606)
			(xy 436.392087 -17.0588) (xy 436.421555 -17.104656) (xy 436.444196 -17.154239) (xy 436.459548 -17.20654)
			(xy 436.4673 -17.260494) (xy 436.467758 -17.287748) (xy 436.725312 -17.287748) (xy 436.729383 -17.232126)
			(xy 436.741509 -17.177689) (xy 436.761432 -17.125598) (xy 436.788728 -17.076963) (xy 436.822814 -17.03282)
			(xy 436.862963 -16.994111) (xy 436.908321 -16.96166) (xy 436.957921 -16.936159) (xy 437.010705 -16.918152)
			(xy 437.065548 -16.908022) (xy 437.121282 -16.905985) (xy 437.176719 -16.912085) (xy 437.230676 -16.926191)
			(xy 437.282005 -16.948003) (xy 437.329611 -16.977057) (xy 437.372479 -17.012732) (xy 437.409696 -17.054269)
			(xy 437.440469 -17.100782) (xy 437.464141 -17.151279) (xy 437.480209 -17.204686) (xy 437.488329 -17.259862)
			(xy 437.488374 -17.262348) (xy 437.849262 -17.262348) (xy 437.853333 -17.206726) (xy 437.865459 -17.152289)
			(xy 437.885382 -17.100198) (xy 437.912678 -17.051563) (xy 437.946764 -17.00742) (xy 437.986913 -16.968711)
			(xy 438.032271 -16.93626) (xy 438.081871 -16.910759) (xy 438.134655 -16.892752) (xy 438.189498 -16.882622)
			(xy 438.245232 -16.880585) (xy 438.300669 -16.886685) (xy 438.354626 -16.900791) (xy 438.405955 -16.922603)
			(xy 438.453561 -16.951657) (xy 438.496429 -16.987332) (xy 438.533646 -17.028869) (xy 438.564419 -17.075382)
			(xy 438.588091 -17.125879) (xy 438.604159 -17.179286) (xy 438.612279 -17.234462) (xy 438.612788 -17.262348)
			(xy 438.612279 -17.290234) (xy 438.604159 -17.34541) (xy 438.588091 -17.398817) (xy 438.564419 -17.449314)
			(xy 438.533646 -17.495827) (xy 438.496429 -17.537364) (xy 438.453561 -17.573039) (xy 438.405955 -17.602093)
			(xy 438.354626 -17.623905) (xy 438.300669 -17.638011) (xy 438.245232 -17.644111) (xy 438.189498 -17.642074)
			(xy 438.134655 -17.631944) (xy 438.081871 -17.613937) (xy 438.032271 -17.588436) (xy 437.986913 -17.555985)
			(xy 437.946764 -17.517276) (xy 437.912678 -17.473133) (xy 437.885382 -17.424498) (xy 437.865459 -17.372407)
			(xy 437.853333 -17.31797) (xy 437.849262 -17.262348) (xy 437.488374 -17.262348) (xy 437.488838 -17.287748)
			(xy 437.488329 -17.315634) (xy 437.480209 -17.37081) (xy 437.464141 -17.424217) (xy 437.440469 -17.474714)
			(xy 437.409696 -17.521227) (xy 437.372479 -17.562764) (xy 437.329611 -17.598439) (xy 437.282005 -17.627493)
			(xy 437.230676 -17.649305) (xy 437.176719 -17.663411) (xy 437.121282 -17.669511) (xy 437.065548 -17.667474)
			(xy 437.010705 -17.657344) (xy 436.957921 -17.639337) (xy 436.908321 -17.613836) (xy 436.862963 -17.581385)
			(xy 436.822814 -17.542676) (xy 436.788728 -17.498533) (xy 436.761432 -17.449898) (xy 436.741509 -17.397807)
			(xy 436.729383 -17.34337) (xy 436.725312 -17.287748) (xy 436.467758 -17.287748) (xy 436.467234 -17.316233)
			(xy 436.458773 -17.372571) (xy 436.442032 -17.427026) (xy 436.417382 -17.478387) (xy 436.385372 -17.525514)
			(xy 436.346712 -17.567359) (xy 436.302261 -17.602992) (xy 436.253007 -17.631622) (xy 436.226712 -17.642586)
			(xy 436.213562 -17.648313) (xy 436.190882 -17.665852) (xy 436.173968 -17.689002) (xy 436.164153 -17.715939)
			(xy 436.162209 -17.744544) (xy 436.164736 -17.758664) (xy 436.168237 -17.775466) (xy 436.172053 -17.809576)
			(xy 436.172356 -17.826736) (xy 436.172356 -19.395948) (xy 439.246262 -19.395948) (xy 439.250333 -19.340326)
			(xy 439.262459 -19.285889) (xy 439.282382 -19.233798) (xy 439.309678 -19.185163) (xy 439.343764 -19.14102)
			(xy 439.383913 -19.102311) (xy 439.429271 -19.06986) (xy 439.478871 -19.044359) (xy 439.531655 -19.026352)
			(xy 439.586498 -19.016222) (xy 439.642232 -19.014185) (xy 439.697669 -19.020285) (xy 439.751626 -19.034391)
			(xy 439.802955 -19.056203) (xy 439.850561 -19.085257) (xy 439.893429 -19.120932) (xy 439.930646 -19.162469)
			(xy 439.961419 -19.208982) (xy 439.985091 -19.259479) (xy 440.001159 -19.312886) (xy 440.009279 -19.368062)
			(xy 440.009788 -19.395948) (xy 440.009279 -19.423834) (xy 440.001159 -19.47901) (xy 439.985091 -19.532417)
			(xy 439.961419 -19.582914) (xy 439.930646 -19.629427) (xy 439.893429 -19.670964) (xy 439.850561 -19.706639)
			(xy 439.802955 -19.735693) (xy 439.751626 -19.757505) (xy 439.697669 -19.771611) (xy 439.642232 -19.777711)
			(xy 439.586498 -19.775674) (xy 439.531655 -19.765544) (xy 439.478871 -19.747537) (xy 439.429271 -19.722036)
			(xy 439.383913 -19.689585) (xy 439.343764 -19.650876) (xy 439.309678 -19.606733) (xy 439.282382 -19.558098)
			(xy 439.262459 -19.506007) (xy 439.250333 -19.45157) (xy 439.246262 -19.395948) (xy 436.172356 -19.395948)
			(xy 436.172356 -21.30806) (xy 436.17184 -21.333042) (xy 436.163981 -21.382384) (xy 436.148513 -21.429894)
			(xy 436.125815 -21.474405) (xy 436.096444 -21.514825) (xy 436.079138 -21.53285) (xy 435.88178 -21.730208)
			(xy 435.88178 -23.689818) (xy 437.315354 -23.689818) (xy 437.319425 -23.634196) (xy 437.331551 -23.579759)
			(xy 437.351474 -23.527668) (xy 437.37877 -23.479033) (xy 437.412856 -23.43489) (xy 437.453005 -23.396181)
			(xy 437.498363 -23.36373) (xy 437.547963 -23.338229) (xy 437.600747 -23.320222) (xy 437.65559 -23.310092)
			(xy 437.711324 -23.308055) (xy 437.766761 -23.314155) (xy 437.820718 -23.328261) (xy 437.872047 -23.350073)
			(xy 437.919653 -23.379127) (xy 437.962521 -23.414802) (xy 437.999738 -23.456339) (xy 438.030511 -23.502852)
			(xy 438.054183 -23.553349) (xy 438.070251 -23.606756) (xy 438.078371 -23.661932) (xy 438.07888 -23.689818)
			(xy 438.078371 -23.717704) (xy 438.070251 -23.77288) (xy 438.054183 -23.826287) (xy 438.030511 -23.876784)
			(xy 437.999738 -23.923297) (xy 437.962521 -23.964834) (xy 437.919653 -24.000509) (xy 437.872047 -24.029563)
			(xy 437.820718 -24.051375) (xy 437.766761 -24.065481) (xy 437.711324 -24.071581) (xy 437.65559 -24.069544)
			(xy 437.600747 -24.059414) (xy 437.547963 -24.041407) (xy 437.498363 -24.015906) (xy 437.453005 -23.983455)
			(xy 437.412856 -23.944746) (xy 437.37877 -23.900603) (xy 437.351474 -23.851968) (xy 437.331551 -23.799877)
			(xy 437.319425 -23.74544) (xy 437.315354 -23.689818) (xy 435.88178 -23.689818) (xy 435.88178 -23.731728)
			(xy 434.32476 -25.288748) (xy 434.32476 -25.823418) (xy 437.264554 -25.823418) (xy 437.268625 -25.767796)
			(xy 437.280751 -25.713359) (xy 437.300674 -25.661268) (xy 437.32797 -25.612633) (xy 437.362056 -25.56849)
			(xy 437.402205 -25.529781) (xy 437.447563 -25.49733) (xy 437.497163 -25.471829) (xy 437.549947 -25.453822)
			(xy 437.60479 -25.443692) (xy 437.660524 -25.441655) (xy 437.715961 -25.447755) (xy 437.769918 -25.461861)
			(xy 437.821247 -25.483673) (xy 437.868853 -25.512727) (xy 437.911721 -25.548402) (xy 437.948938 -25.589939)
			(xy 437.979711 -25.636452) (xy 438.003383 -25.686949) (xy 438.019451 -25.740356) (xy 438.027571 -25.795532)
			(xy 438.02808 -25.823418) (xy 438.027571 -25.851304) (xy 438.020461 -25.899618) (xy 438.255154 -25.899618)
			(xy 438.259225 -25.843996) (xy 438.271351 -25.789559) (xy 438.291274 -25.737468) (xy 438.31857 -25.688833)
			(xy 438.352656 -25.64469) (xy 438.392805 -25.605981) (xy 438.438163 -25.57353) (xy 438.487763 -25.548029)
			(xy 438.540547 -25.530022) (xy 438.59539 -25.519892) (xy 438.651124 -25.517855) (xy 438.706561 -25.523955)
			(xy 438.760518 -25.538061) (xy 438.811847 -25.559873) (xy 438.859453 -25.588927) (xy 438.902321 -25.624602)
			(xy 438.939538 -25.666139) (xy 438.970311 -25.712652) (xy 438.993983 -25.763149) (xy 439.010051 -25.816556)
			(xy 439.018171 -25.871732) (xy 439.01868 -25.899618) (xy 439.018171 -25.927504) (xy 439.010051 -25.98268)
			(xy 438.993983 -26.036087) (xy 438.970311 -26.086584) (xy 438.939538 -26.133097) (xy 438.902321 -26.174634)
			(xy 438.859453 -26.210309) (xy 438.811847 -26.239363) (xy 438.760518 -26.261175) (xy 438.706561 -26.275281)
			(xy 438.651124 -26.281381) (xy 438.59539 -26.279344) (xy 438.540547 -26.269214) (xy 438.487763 -26.251207)
			(xy 438.438163 -26.225706) (xy 438.392805 -26.193255) (xy 438.352656 -26.154546) (xy 438.31857 -26.110403)
			(xy 438.291274 -26.061768) (xy 438.271351 -26.009677) (xy 438.259225 -25.95524) (xy 438.255154 -25.899618)
			(xy 438.020461 -25.899618) (xy 438.019451 -25.90648) (xy 438.003383 -25.959887) (xy 437.979711 -26.010384)
			(xy 437.948938 -26.056897) (xy 437.911721 -26.098434) (xy 437.868853 -26.134109) (xy 437.821247 -26.163163)
			(xy 437.769918 -26.184975) (xy 437.715961 -26.199081) (xy 437.660524 -26.205181) (xy 437.60479 -26.203144)
			(xy 437.549947 -26.193014) (xy 437.497163 -26.175007) (xy 437.447563 -26.149506) (xy 437.402205 -26.117055)
			(xy 437.362056 -26.078346) (xy 437.32797 -26.034203) (xy 437.300674 -25.985568) (xy 437.280751 -25.933477)
			(xy 437.268625 -25.87904) (xy 437.264554 -25.823418) (xy 434.32476 -25.823418) (xy 434.32476 -26.444448)
			(xy 434.75402 -26.873708) (xy 444.15964 -26.873708)
		)
		(stroke
			(width 0)
			(type solid)
		)
		(fill yes)
		(layer "In6.Cu")
		(net "P12V_OCP_SFF")
	)
	(gr_poly
		(pts
			(xy 360.991912 -364.899194) (xy 360.991912 -363.82579) (xy 360.288586 -363.122464) (xy 359.941622 -363.122464)
			(xy 359.568242 -362.749084) (xy 359.534968 -362.766864) (xy 359.50724 -362.780939) (xy 359.448342 -362.80087)
			(xy 359.386988 -362.810961) (xy 359.355898 -362.811568) (xy 359.355644 -362.811568) (xy 359.32839 -362.811108)
			(xy 359.274437 -362.803356) (xy 359.222136 -362.788003) (xy 359.172553 -362.765362) (xy 359.126697 -362.735895)
			(xy 359.085502 -362.700201) (xy 359.049807 -362.659006) (xy 359.02034 -362.613151) (xy 358.997698 -362.563568)
			(xy 358.982345 -362.511267) (xy 358.974593 -362.457314) (xy 358.974136 -362.43006) (xy 358.974624 -362.402393)
			(xy 358.982606 -362.347637) (xy 358.998412 -362.294607) (xy 359.02171 -362.244417) (xy 359.052012 -362.198116)
			(xy 359.088682 -362.156677) (xy 359.109518 -362.138468) (xy 359.109518 -362.129578) (xy 359.080553 -362.074291)
			(xy 359.029531 -361.96037) (xy 358.986624 -361.843151) (xy 358.952041 -361.723212) (xy 358.925954 -361.601144)
			(xy 358.90849 -361.477546) (xy 358.899736 -361.353029) (xy 358.899206 -361.290616) (xy 358.899206 -361.290362)
			(xy 358.899739 -361.228853) (xy 358.90826 -361.106129) (xy 358.92524 -360.984287) (xy 358.950595 -360.86391)
			(xy 358.984205 -360.745571) (xy 359.025911 -360.629837) (xy 359.075511 -360.517261) (xy 359.103676 -360.462576)
			(xy 359.109518 -360.451654) (xy 359.109518 -359.5497) (xy 360.553254 -358.105964) (xy 361.643168 -358.105964)
			(xy 362.131864 -357.617268) (xy 362.561378 -357.617268) (xy 362.69295 -357.485696) (xy 362.69295 -356.770686)
			(xy 362.669582 -356.747318) (xy 362.669582 -356.5652) (xy 362.195364 -356.2223) (xy 361.903264 -356.2223)
			(xy 361.670092 -355.989128) (xy 360.927904 -355.989128) (xy 360.26344 -355.324664) (xy 360.26344 -354.335588)
			(xy 359.84434 -353.916488) (xy 358.38892 -353.916488) (xy 358.24414 -354.061268) (xy 358.24414 -354.675948)
			(xy 358.37876 -354.810568) (xy 359.00868 -354.810568) (xy 359.2068 -354.612448) (xy 359.2068 -354.505768)
			(xy 359.3465 -354.366068) (xy 359.8164 -354.366068) (xy 359.96626 -354.515928) (xy 359.96626 -355.209348)
			(xy 359.7656 -355.410008) (xy 358.4702 -355.410008) (xy 358.383078 -355.49713) (xy 358.389936 -355.503988)
			(xy 358.389936 -355.839268) (xy 358.390372 -355.849332) (xy 358.398108 -355.867915) (xy 358.404922 -355.875336)
			(xy 358.535732 -356.006146) (xy 358.535732 -356.150926) (xy 358.863403 -356.150926) (xy 358.867371 -356.091648)
			(xy 358.879205 -356.033427) (xy 358.898693 -355.977303) (xy 358.925488 -355.924278) (xy 358.959112 -355.875297)
			(xy 358.998964 -355.831234) (xy 359.044333 -355.792877) (xy 359.094411 -355.760909) (xy 359.148302 -355.7359)
			(xy 359.205046 -355.718298) (xy 359.263629 -355.708417) (xy 359.323007 -355.706431) (xy 359.38212 -355.712378)
			(xy 359.439912 -355.726151) (xy 359.495354 -355.747504) (xy 359.547454 -355.776056) (xy 359.595284 -355.811297)
			(xy 359.637991 -355.852599) (xy 359.674811 -355.899225) (xy 359.705088 -355.950342) (xy 359.728281 -356.005039)
			(xy 359.743977 -356.062339) (xy 359.751896 -356.12122) (xy 359.752392 -356.150926) (xy 359.751896 -356.180632)
			(xy 359.743977 -356.239513) (xy 359.728281 -356.296813) (xy 359.705088 -356.35151) (xy 359.674811 -356.402627)
			(xy 359.637991 -356.449253) (xy 359.595284 -356.490555) (xy 359.547454 -356.525796) (xy 359.495354 -356.554348)
			(xy 359.459263 -356.568248) (xy 361.097078 -356.568248) (xy 361.101055 -356.511371) (xy 361.112909 -356.455601)
			(xy 361.132409 -356.402024) (xy 361.159177 -356.351682) (xy 361.19269 -356.305556) (xy 361.232296 -356.264542)
			(xy 361.277225 -356.22944) (xy 361.326602 -356.200932) (xy 361.379466 -356.179574) (xy 361.434788 -356.16578)
			(xy 361.491491 -356.15982) (xy 361.548472 -356.16181) (xy 361.604622 -356.171711) (xy 361.658847 -356.18933)
			(xy 361.710092 -356.214324) (xy 361.75736 -356.246207) (xy 361.799731 -356.284357) (xy 361.83638 -356.328034)
			(xy 361.866594 -356.376386) (xy 361.889784 -356.428472) (xy 361.9055 -356.483279) (xy 361.913435 -356.53974)
			(xy 361.913932 -356.568248) (xy 361.913435 -356.596756) (xy 361.9055 -356.653217) (xy 361.889784 -356.708024)
			(xy 361.866594 -356.76011) (xy 361.83638 -356.808462) (xy 361.799731 -356.852139) (xy 361.75736 -356.890289)
			(xy 361.710092 -356.922172) (xy 361.658847 -356.947166) (xy 361.604622 -356.964785) (xy 361.548472 -356.974686)
			(xy 361.491491 -356.976676) (xy 361.434788 -356.970716) (xy 361.379466 -356.956922) (xy 361.326602 -356.935564)
			(xy 361.277225 -356.907056) (xy 361.232296 -356.871954) (xy 361.19269 -356.83094) (xy 361.159177 -356.784814)
			(xy 361.132409 -356.734472) (xy 361.112909 -356.680895) (xy 361.101055 -356.625125) (xy 361.097078 -356.568248)
			(xy 359.459263 -356.568248) (xy 359.439912 -356.575701) (xy 359.38212 -356.589474) (xy 359.323007 -356.595421)
			(xy 359.263629 -356.593435) (xy 359.205046 -356.583554) (xy 359.148302 -356.565952) (xy 359.094411 -356.540943)
			(xy 359.044333 -356.508975) (xy 358.998964 -356.470618) (xy 358.959112 -356.426555) (xy 358.925488 -356.377574)
			(xy 358.898693 -356.324549) (xy 358.879205 -356.268425) (xy 358.867371 -356.210204) (xy 358.863403 -356.150926)
			(xy 358.535732 -356.150926) (xy 358.535732 -356.200964) (xy 358.34828 -356.388416) (xy 358.338026 -356.399421)
			(xy 358.323862 -356.42594) (xy 358.318028 -356.455434) (xy 358.321029 -356.485348) (xy 358.332606 -356.513094)
			(xy 358.351757 -356.536271) (xy 358.376823 -356.552872) (xy 358.405635 -356.561459) (xy 358.42067 -356.561898)
			(xy 358.42321 -356.561898) (xy 358.450461 -356.562384) (xy 358.504407 -356.570142) (xy 358.5567 -356.585498)
			(xy 358.606275 -356.60814) (xy 358.652124 -356.637606) (xy 358.693313 -356.673298) (xy 358.729002 -356.714488)
			(xy 358.758467 -356.760338) (xy 358.781107 -356.809914) (xy 358.796461 -356.862208) (xy 358.804217 -356.916154)
			(xy 358.804216 -356.970655) (xy 358.796459 -357.024602) (xy 358.781104 -357.076895) (xy 358.758463 -357.126471)
			(xy 358.728997 -357.17232) (xy 358.693306 -357.213509) (xy 358.652117 -357.249199) (xy 358.606267 -357.278665)
			(xy 358.556691 -357.301305) (xy 358.504398 -357.31666) (xy 358.450451 -357.324416) (xy 358.39595 -357.324416)
			(xy 358.342004 -357.31666) (xy 358.28971 -357.301306) (xy 358.240134 -357.278665) (xy 358.194285 -357.2492)
			(xy 358.153095 -357.21351) (xy 358.117404 -357.172321) (xy 358.087938 -357.126472) (xy 358.065297 -357.076896)
			(xy 358.049941 -357.024603) (xy 358.042184 -356.970657) (xy 358.041702 -356.943406) (xy 358.041702 -356.940866)
			(xy 358.041235 -356.925844) (xy 358.032632 -356.897063) (xy 358.016031 -356.872028) (xy 357.992867 -356.852903)
			(xy 357.965143 -356.841339) (xy 357.935254 -356.838338) (xy 357.905784 -356.844158) (xy 357.87928 -356.858296)
			(xy 357.86822 -356.868476) (xy 357.57612 -357.160576) (xy 357.57612 -357.561388) (xy 360.871015 -357.561388)
			(xy 360.875016 -357.504157) (xy 360.886944 -357.448041) (xy 360.906566 -357.39413) (xy 360.9335 -357.343475)
			(xy 360.967222 -357.297061) (xy 361.007074 -357.255792) (xy 361.052283 -357.220472) (xy 361.101967 -357.191786)
			(xy 361.15516 -357.170295) (xy 361.210826 -357.156416) (xy 361.267883 -357.150419) (xy 361.325218 -357.152421)
			(xy 361.381717 -357.162383) (xy 361.43628 -357.180112) (xy 361.487844 -357.205261) (xy 361.535406 -357.237343)
			(xy 361.578041 -357.275731) (xy 361.614918 -357.319679) (xy 361.645319 -357.368332) (xy 361.668654 -357.420743)
			(xy 361.684467 -357.475891) (xy 361.692452 -357.532703) (xy 361.692952 -357.561388) (xy 361.692452 -357.590073)
			(xy 361.684467 -357.646885) (xy 361.668654 -357.702033) (xy 361.645319 -357.754444) (xy 361.614918 -357.803097)
			(xy 361.578041 -357.847045) (xy 361.535406 -357.885433) (xy 361.487844 -357.917515) (xy 361.43628 -357.942664)
			(xy 361.381717 -357.960393) (xy 361.325218 -357.970355) (xy 361.267883 -357.972357) (xy 361.210826 -357.96636)
			(xy 361.15516 -357.952481) (xy 361.101967 -357.93099) (xy 361.052283 -357.902304) (xy 361.007074 -357.866984)
			(xy 360.967222 -357.825715) (xy 360.9335 -357.779301) (xy 360.906566 -357.728646) (xy 360.886944 -357.674735)
			(xy 360.875016 -357.618619) (xy 360.871015 -357.561388) (xy 357.57612 -357.561388) (xy 357.57612 -358.848406)
			(xy 358.041192 -358.848406) (xy 358.045263 -358.792784) (xy 358.057389 -358.738347) (xy 358.077312 -358.686256)
			(xy 358.104608 -358.637621) (xy 358.138694 -358.593478) (xy 358.178843 -358.554769) (xy 358.224201 -358.522318)
			(xy 358.273801 -358.496817) (xy 358.326585 -358.47881) (xy 358.381428 -358.46868) (xy 358.437162 -358.466643)
			(xy 358.492599 -358.472743) (xy 358.546556 -358.486849) (xy 358.597885 -358.508661) (xy 358.645491 -358.537715)
			(xy 358.688359 -358.57339) (xy 358.725576 -358.614927) (xy 358.756349 -358.66144) (xy 358.780021 -358.711937)
			(xy 358.796089 -358.765344) (xy 358.804209 -358.82052) (xy 358.804718 -358.848406) (xy 358.804209 -358.876292)
			(xy 358.796089 -358.931468) (xy 358.780021 -358.984875) (xy 358.756349 -359.035372) (xy 358.725576 -359.081885)
			(xy 358.688359 -359.123422) (xy 358.645491 -359.159097) (xy 358.597885 -359.188151) (xy 358.546556 -359.209963)
			(xy 358.492599 -359.224069) (xy 358.437162 -359.230169) (xy 358.381428 -359.228132) (xy 358.326585 -359.218002)
			(xy 358.273801 -359.199995) (xy 358.224201 -359.174494) (xy 358.178843 -359.142043) (xy 358.138694 -359.103334)
			(xy 358.104608 -359.059191) (xy 358.077312 -359.010556) (xy 358.057389 -358.958465) (xy 358.045263 -358.904028)
			(xy 358.041192 -358.848406) (xy 357.57612 -358.848406) (xy 357.57612 -360.753406) (xy 358.041192 -360.753406)
			(xy 358.045263 -360.697784) (xy 358.057389 -360.643347) (xy 358.077312 -360.591256) (xy 358.104608 -360.542621)
			(xy 358.138694 -360.498478) (xy 358.178843 -360.459769) (xy 358.224201 -360.427318) (xy 358.273801 -360.401817)
			(xy 358.326585 -360.38381) (xy 358.381428 -360.37368) (xy 358.437162 -360.371643) (xy 358.492599 -360.377743)
			(xy 358.546556 -360.391849) (xy 358.597885 -360.413661) (xy 358.645491 -360.442715) (xy 358.688359 -360.47839)
			(xy 358.725576 -360.519927) (xy 358.756349 -360.56644) (xy 358.780021 -360.616937) (xy 358.796089 -360.670344)
			(xy 358.804209 -360.72552) (xy 358.804718 -360.753406) (xy 358.804209 -360.781292) (xy 358.796089 -360.836468)
			(xy 358.780021 -360.889875) (xy 358.756349 -360.940372) (xy 358.725576 -360.986885) (xy 358.688359 -361.028422)
			(xy 358.645491 -361.064097) (xy 358.597885 -361.093151) (xy 358.546556 -361.114963) (xy 358.492599 -361.129069)
			(xy 358.437162 -361.135169) (xy 358.381428 -361.133132) (xy 358.326585 -361.123002) (xy 358.273801 -361.104995)
			(xy 358.224201 -361.079494) (xy 358.178843 -361.047043) (xy 358.138694 -361.008334) (xy 358.104608 -360.964191)
			(xy 358.077312 -360.915556) (xy 358.057389 -360.863465) (xy 358.045263 -360.809028) (xy 358.041192 -360.753406)
			(xy 357.57612 -360.753406) (xy 357.57612 -362.572046) (xy 357.947468 -362.94314) (xy 358.236012 -362.94314)
			(xy 358.47782 -363.184948) (xy 358.47782 -363.764068) (xy 358.80675 -364.092998) (xy 358.836347 -364.093558)
			(xy 358.89483 -364.102702) (xy 358.951201 -364.120761) (xy 359.00411 -364.147304) (xy 359.052288 -364.181695)
			(xy 359.094581 -364.223109) (xy 359.129977 -364.270554) (xy 359.144316 -364.296452) (xy 359.15854 -364.32363)
			(xy 359.35539 -364.32363) (xy 359.349219 -364.298943) (xy 359.34259 -364.248489) (xy 359.342182 -364.223046)
			(xy 359.34268 -364.195123) (xy 359.350627 -364.139847) (xy 359.366361 -364.086264) (xy 359.38956 -364.035465)
			(xy 359.419752 -363.988485) (xy 359.456323 -363.946281) (xy 359.498527 -363.90971) (xy 359.545507 -363.879518)
			(xy 359.596306 -363.856319) (xy 359.649889 -363.840585) (xy 359.705165 -363.832638) (xy 359.761011 -363.832638)
			(xy 359.816287 -363.840585) (xy 359.86987 -363.856319) (xy 359.920669 -363.879518) (xy 359.967649 -363.90971)
			(xy 360.009853 -363.946281) (xy 360.046424 -363.988485) (xy 360.076616 -364.035465) (xy 360.099815 -364.086264)
			(xy 360.115549 -364.139847) (xy 360.123496 -364.195123) (xy 360.123994 -364.223046) (xy 360.123567 -364.248488)
			(xy 360.116942 -364.29894) (xy 360.110786 -364.32363) (xy 360.220514 -364.32363) (xy 360.258106 -364.361222)
			(xy 360.258106 -364.908846) (xy 360.39806 -365.0488) (xy 360.842306 -365.0488)
		)
		(stroke
			(width 0)
			(type solid)
		)
		(fill yes)
		(layer "In6.Cu")
		(net "PVCCIN_CPU0_VREF")
	)
	(gr_poly
		(pts
			(xy 32.083502 -168.326308) (xy 32.098108 -168.325843) (xy 32.126128 -168.31759) (xy 32.150659 -168.301732)
			(xy 32.169688 -168.27957) (xy 32.181655 -168.252923) (xy 32.185576 -168.223977) (xy 32.183832 -168.209468)
			(xy 32.181803 -168.19514) (xy 32.179646 -168.16628) (xy 32.179514 -168.15181) (xy 32.179939 -168.126031)
			(xy 32.186888 -168.074944) (xy 32.200658 -168.02526) (xy 32.221 -167.977885) (xy 32.247542 -167.933684)
			(xy 32.263334 -167.913304) (xy 32.271841 -167.901911) (xy 32.28279 -167.875683) (xy 32.286094 -167.847454)
			(xy 32.281498 -167.819407) (xy 32.269357 -167.793709) (xy 32.25061 -167.772347) (xy 32.23895 -167.764206)
			(xy 32.216312 -167.749061) (xy 32.175168 -167.713371) (xy 32.139518 -167.672193) (xy 32.110087 -167.626362)
			(xy 32.087474 -167.576812) (xy 32.072138 -167.52455) (xy 32.064391 -167.470637) (xy 32.063944 -167.443404)
			(xy 32.064429 -167.416151) (xy 32.072185 -167.362201) (xy 32.08754 -167.309903) (xy 32.11018 -167.260322)
			(xy 32.139645 -167.214467) (xy 32.175336 -167.173273) (xy 32.216526 -167.137576) (xy 32.262376 -167.108105)
			(xy 32.311954 -167.085458) (xy 32.36425 -167.070096) (xy 32.418199 -167.062333) (xy 32.445452 -167.061896)
			(xy 32.472438 -167.062366) (xy 32.525871 -167.069978) (xy 32.577698 -167.085043) (xy 32.626886 -167.107261)
			(xy 32.672452 -167.136187) (xy 32.713488 -167.171245) (xy 32.749175 -167.211735) (xy 32.7788 -167.25685)
			(xy 32.801773 -167.305689) (xy 32.817636 -167.357277) (xy 32.826071 -167.410586) (xy 32.82696 -167.437562)
			(xy 32.827695 -167.452463) (xy 32.83672 -167.480886) (xy 32.85357 -167.505489) (xy 32.87681 -167.524176)
			(xy 32.904457 -167.535353) (xy 32.934154 -167.538067) (xy 32.963368 -167.532087) (xy 32.98961 -167.517922)
			(xy 33.000442 -167.507666) (xy 33.655 -166.853108) (xy 33.655 -165.157404) (xy 33.654516 -165.142824)
			(xy 33.64626 -165.114855) (xy 33.630445 -165.090353) (xy 33.608359 -165.071311) (xy 33.581797 -165.059276)
			(xy 33.552918 -165.055226) (xy 33.538414 -165.05682) (xy 33.50895 -165.06063) (xy 33.494358 -165.062728)
			(xy 33.467205 -165.074172) (xy 33.444453 -165.092898) (xy 33.428001 -165.117344) (xy 33.41922 -165.145472)
			(xy 33.418526 -165.160198) (xy 33.417628 -165.187163) (xy 33.409174 -165.240448) (xy 33.393296 -165.29201)
			(xy 33.370312 -165.340821) (xy 33.34068 -165.385906) (xy 33.304991 -165.426367) (xy 33.263958 -165.461395)
			(xy 33.218398 -165.490293) (xy 33.169221 -165.512483) (xy 33.117409 -165.527524) (xy 33.063994 -165.535114)
			(xy 33.037018 -165.53561) (xy 33.01018 -165.535154) (xy 32.957035 -165.527629) (xy 32.905471 -165.512726)
			(xy 32.856506 -165.490738) (xy 32.811108 -165.462102) (xy 32.770175 -165.427381) (xy 32.734516 -165.387264)
			(xy 32.719264 -165.365176) (xy 32.711175 -165.353781) (xy 32.689995 -165.33557) (xy 32.664668 -165.323785)
			(xy 32.637095 -165.319312) (xy 32.609342 -165.322486) (xy 32.583491 -165.333068) (xy 32.572198 -165.3413)
			(xy 32.552001 -165.356513) (xy 32.508355 -165.382043) (xy 32.461719 -165.401583) (xy 32.41291 -165.41479)
			(xy 32.362784 -165.421431) (xy 32.337502 -165.421818) (xy 32.30792 -165.421261) (xy 32.249466 -165.412129)
			(xy 32.193122 -165.394082) (xy 32.140239 -165.367553) (xy 32.092086 -165.333179) (xy 32.049815 -165.291784)
			(xy 32.031686 -165.268402) (xy 32.022566 -165.256943) (xy 31.999147 -165.239378) (xy 31.971703 -165.22919)
			(xy 31.942495 -165.227218) (xy 31.913931 -165.233625) (xy 31.888363 -165.247882) (xy 31.877762 -165.257988)
			(xy 31.856093 -165.279232) (xy 31.807273 -165.315269) (xy 31.753365 -165.343126) (xy 31.695728 -165.362101)
			(xy 31.635814 -165.371716) (xy 31.605474 -165.372288) (xy 31.589717 -165.372164) (xy 31.558307 -165.369623)
			(xy 31.542736 -165.367208) (xy 31.528349 -165.365324) (xy 31.499554 -165.368784) (xy 31.472898 -165.380209)
			(xy 31.450534 -165.398674) (xy 31.43427 -165.422686) (xy 31.425422 -165.450305) (xy 31.424705 -165.479298)
			(xy 31.427928 -165.493446) (xy 31.433869 -165.517456) (xy 31.440236 -165.566505) (xy 31.440628 -165.591236)
			(xy 31.440072 -165.62106) (xy 31.430825 -165.679987) (xy 31.412516 -165.736756) (xy 31.385592 -165.789981)
			(xy 31.350708 -165.838365) (xy 31.330138 -165.859968) (xy 31.320881 -165.869876) (xy 31.307502 -165.893449)
			(xy 31.300812 -165.919716) (xy 31.301286 -165.946817) (xy 31.308891 -165.972834) (xy 31.323087 -165.995925)
			(xy 31.332678 -166.00551) (xy 31.35132 -166.023614) (xy 31.384027 -166.063994) (xy 31.410952 -166.108439)
			(xy 31.431596 -166.156127) (xy 31.445578 -166.206175) (xy 31.452638 -166.257658) (xy 31.453074 -166.28364)
			(xy 31.452588 -166.310891) (xy 31.444832 -166.364839) (xy 31.429477 -166.417134) (xy 31.406835 -166.466711)
			(xy 31.377369 -166.512561) (xy 31.341678 -166.553752) (xy 31.300487 -166.589443) (xy 31.254637 -166.618909)
			(xy 31.20506 -166.641551) (xy 31.152765 -166.656906) (xy 31.098817 -166.664662) (xy 31.044315 -166.664662)
			(xy 30.990367 -166.656906) (xy 30.938072 -166.641551) (xy 30.888495 -166.618909) (xy 30.842645 -166.589443)
			(xy 30.801454 -166.553752) (xy 30.765763 -166.512561) (xy 30.736297 -166.466711) (xy 30.713655 -166.417134)
			(xy 30.6983 -166.364839) (xy 30.690544 -166.310891) (xy 30.690058 -166.28364) (xy 30.690616 -166.253816)
			(xy 30.699865 -166.194891) (xy 30.718177 -166.138125) (xy 30.745103 -166.084901) (xy 30.779987 -166.036519)
			(xy 30.800548 -166.014908) (xy 30.809795 -166.004997) (xy 30.823157 -165.981424) (xy 30.829835 -165.955163)
			(xy 30.829357 -165.928071) (xy 30.821756 -165.902062) (xy 30.807571 -165.878975) (xy 30.798008 -165.869366)
			(xy 30.779368 -165.851262) (xy 30.746664 -165.81088) (xy 30.719743 -165.766435) (xy 30.699103 -165.718747)
			(xy 30.685125 -165.668699) (xy 30.678068 -165.617217) (xy 30.677612 -165.591236) (xy 30.678073 -165.563982)
			(xy 30.685826 -165.510028) (xy 30.701179 -165.457727) (xy 30.72382 -165.408144) (xy 30.753287 -165.362288)
			(xy 30.788981 -165.321092) (xy 30.830175 -165.285397) (xy 30.87603 -165.255927) (xy 30.925612 -165.233285)
			(xy 30.977913 -165.217929) (xy 31.031866 -165.210174) (xy 31.05912 -165.209728) (xy 31.074877 -165.209852)
			(xy 31.106287 -165.212393) (xy 31.121858 -165.214808) (xy 31.136247 -165.216693) (xy 31.165045 -165.213233)
			(xy 31.191705 -165.201809) (xy 31.214073 -165.183344) (xy 31.23034 -165.15933) (xy 31.239192 -165.131709)
			(xy 31.239914 -165.102713) (xy 31.236666 -165.08857) (xy 31.230724 -165.064561) (xy 31.224355 -165.015511)
			(xy 31.223966 -164.99078) (xy 31.224453 -164.963529) (xy 31.232212 -164.909582) (xy 31.247568 -164.857288)
			(xy 31.27021 -164.807712) (xy 31.299677 -164.761862) (xy 31.335368 -164.720672) (xy 31.376557 -164.68498)
			(xy 31.422407 -164.655513) (xy 31.471983 -164.632871) (xy 31.524276 -164.617513) (xy 31.578223 -164.609754)
			(xy 31.605474 -164.609272) (xy 31.635057 -164.609827) (xy 31.693514 -164.618956) (xy 31.74986 -164.637)
			(xy 31.802746 -164.663526) (xy 31.850903 -164.697898) (xy 31.893177 -164.739293) (xy 31.91129 -164.762688)
			(xy 31.920409 -164.774151) (xy 31.94383 -164.791724) (xy 31.971278 -164.80192) (xy 32.000491 -164.803897)
			(xy 32.029062 -164.797493) (xy 32.054637 -164.783236) (xy 32.065214 -164.773102) (xy 32.086885 -164.751863)
			(xy 32.135707 -164.715836) (xy 32.189616 -164.687991) (xy 32.247253 -164.669028) (xy 32.307164 -164.659426)
			(xy 32.337502 -164.658802) (xy 32.36434 -164.659259) (xy 32.417485 -164.666785) (xy 32.469051 -164.681688)
			(xy 32.518017 -164.703674) (xy 32.563417 -164.732308) (xy 32.604354 -164.767024) (xy 32.64002 -164.807138)
			(xy 32.655256 -164.829236) (xy 32.663346 -164.840627) (xy 32.684526 -164.858832) (xy 32.70985 -164.87061)
			(xy 32.737419 -164.875078) (xy 32.765166 -164.871901) (xy 32.791012 -164.861318) (xy 32.802322 -164.853112)
			(xy 32.814768 -164.844222) (xy 32.822866 -164.837844) (xy 32.833562 -164.820245) (xy 32.836489 -164.79986)
			(xy 32.831175 -164.779964) (xy 32.825182 -164.771578) (xy 32.79973 -164.738041) (xy 32.755568 -164.666356)
			(xy 32.719574 -164.590241) (xy 32.692185 -164.510624) (xy 32.673734 -164.428475) (xy 32.664448 -164.344792)
			(xy 32.663892 -164.302694) (xy 32.664415 -164.26276) (xy 32.672764 -164.18333) (xy 32.68937 -164.105208)
			(xy 32.714051 -164.02925) (xy 32.746536 -163.956287) (xy 32.78647 -163.88712) (xy 32.833416 -163.822506)
			(xy 32.886858 -163.763153) (xy 32.946211 -163.709712) (xy 33.010825 -163.662767) (xy 33.079993 -163.622834)
			(xy 33.152955 -163.590349) (xy 33.228914 -163.565668) (xy 33.307036 -163.549063) (xy 33.386466 -163.540715)
			(xy 33.4264 -163.540186) (xy 33.45451 -163.540473) (xy 33.510574 -163.54467) (xy 33.538414 -163.548568)
			(xy 33.552916 -163.550252) (xy 33.58182 -163.54622) (xy 33.608405 -163.53418) (xy 33.6305 -163.515114)
			(xy 33.646302 -163.490579) (xy 33.654522 -163.462576) (xy 33.655 -163.447984) (xy 33.655 -161.892742)
			(xy 33.621226 -161.880823) (xy 33.555879 -161.851494) (xy 33.493575 -161.816157) (xy 33.463992 -161.795968)
			(xy 33.451257 -161.787767) (xy 33.422442 -161.778483) (xy 33.392171 -161.778033) (xy 33.363092 -161.786455)
			(xy 33.337747 -161.803014) (xy 33.327594 -161.814256) (xy 33.309394 -161.835375) (xy 33.267876 -161.872581)
			(xy 33.22138 -161.903341) (xy 33.1709 -161.927001) (xy 33.117511 -161.943053) (xy 33.062353 -161.951157)
			(xy 33.034478 -161.95167) (xy 33.007227 -161.951205) (xy 32.953281 -161.943445) (xy 32.900988 -161.928087)
			(xy 32.851413 -161.905443) (xy 32.805565 -161.875974) (xy 32.764378 -161.840279) (xy 32.72869 -161.799087)
			(xy 32.699228 -161.753235) (xy 32.676592 -161.703656) (xy 32.661242 -161.651361) (xy 32.653491 -161.597413)
			(xy 32.65297 -161.570162) (xy 32.653374 -161.544969) (xy 32.659998 -161.49502) (xy 32.666178 -161.470594)
			(xy 32.673798 -161.442146) (xy 32.17164 -160.939988) (xy 31.09468 -160.939988) (xy 30.5562 -161.478468)
			(xy 29.64434 -161.478468) (xy 29.590238 -161.53257) (xy 29.57957 -161.543238) (xy 29.576268 -161.557462)
			(xy 29.567608 -161.594102) (xy 29.544016 -161.665604) (xy 29.513494 -161.734434) (xy 29.476338 -161.799922)
			(xy 29.432911 -161.861429) (xy 29.408628 -161.890202) (xy 29.381733 -161.920416) (xy 29.322575 -161.97559)
			(xy 29.257913 -162.024198) (xy 29.223462 -162.045396) (xy 29.212286 -162.052254) (xy 29.203316 -162.067748)
			(xy 30.453582 -162.067748) (xy 30.457653 -162.012126) (xy 30.469779 -161.957689) (xy 30.489702 -161.905598)
			(xy 30.516998 -161.856963) (xy 30.551084 -161.81282) (xy 30.591233 -161.774111) (xy 30.636591 -161.74166)
			(xy 30.686191 -161.716159) (xy 30.738975 -161.698152) (xy 30.793818 -161.688022) (xy 30.849552 -161.685985)
			(xy 30.904989 -161.692085) (xy 30.958946 -161.706191) (xy 31.010275 -161.728003) (xy 31.057881 -161.757057)
			(xy 31.100749 -161.792732) (xy 31.137966 -161.834269) (xy 31.168739 -161.880782) (xy 31.192411 -161.931279)
			(xy 31.208479 -161.984686) (xy 31.216599 -162.039862) (xy 31.217108 -162.067748) (xy 31.216599 -162.095634)
			(xy 31.208479 -162.15081) (xy 31.192411 -162.204217) (xy 31.168739 -162.254714) (xy 31.137966 -162.301227)
			(xy 31.100749 -162.342764) (xy 31.057881 -162.378439) (xy 31.010275 -162.407493) (xy 30.958946 -162.429305)
			(xy 30.904989 -162.443411) (xy 30.849552 -162.449511) (xy 30.793818 -162.447474) (xy 30.738975 -162.437344)
			(xy 30.686191 -162.419337) (xy 30.636591 -162.393836) (xy 30.591233 -162.361385) (xy 30.551084 -162.322676)
			(xy 30.516998 -162.278533) (xy 30.489702 -162.229898) (xy 30.469779 -162.177807) (xy 30.457653 -162.12337)
			(xy 30.453582 -162.067748) (xy 29.203316 -162.067748) (xy 29.18714 -162.095688) (xy 29.18714 -162.684968)
			(xy 29.250386 -162.748468) (xy 29.59862 -163.096702) (xy 29.59862 -163.617402) (xy 31.594042 -163.617402)
			(xy 31.598113 -163.56178) (xy 31.610239 -163.507343) (xy 31.630162 -163.455252) (xy 31.657458 -163.406617)
			(xy 31.691544 -163.362474) (xy 31.731693 -163.323765) (xy 31.777051 -163.291314) (xy 31.826651 -163.265813)
			(xy 31.879435 -163.247806) (xy 31.934278 -163.237676) (xy 31.990012 -163.235639) (xy 32.045449 -163.241739)
			(xy 32.099406 -163.255845) (xy 32.150735 -163.277657) (xy 32.198341 -163.306711) (xy 32.241209 -163.342386)
			(xy 32.278426 -163.383923) (xy 32.309199 -163.430436) (xy 32.332871 -163.480933) (xy 32.348939 -163.53434)
			(xy 32.357059 -163.589516) (xy 32.357568 -163.617402) (xy 32.357059 -163.645288) (xy 32.348939 -163.700464)
			(xy 32.332871 -163.753871) (xy 32.309199 -163.804368) (xy 32.278426 -163.850881) (xy 32.241209 -163.892418)
			(xy 32.198341 -163.928093) (xy 32.150735 -163.957147) (xy 32.099406 -163.978959) (xy 32.045449 -163.993065)
			(xy 31.990012 -163.999165) (xy 31.934278 -163.997128) (xy 31.879435 -163.986998) (xy 31.826651 -163.968991)
			(xy 31.777051 -163.94349) (xy 31.731693 -163.911039) (xy 31.691544 -163.87233) (xy 31.657458 -163.828187)
			(xy 31.630162 -163.779552) (xy 31.610239 -163.727461) (xy 31.598113 -163.673024) (xy 31.594042 -163.617402)
			(xy 29.59862 -163.617402) (xy 29.59862 -166.548054) (xy 29.250386 -166.896288) (xy 29.18714 -166.959788)
			(xy 29.18714 -168.229788) (xy 29.283406 -168.326308)
		)
		(stroke
			(width 0)
			(type solid)
		)
		(fill yes)
		(layer "In6.Cu")
		(net "PVCCD_HV_CPU1_VREF")
	)
	(gr_poly
		(pts
			(xy 408.615134 -184.622948) (xy 408.62996 -184.622449) (xy 408.658368 -184.613949) (xy 408.683136 -184.597646)
			(xy 408.702177 -184.574915) (xy 408.713884 -184.547672) (xy 408.717272 -184.518214) (xy 408.712054 -184.489025)
			(xy 408.69867 -184.462565) (xy 408.688794 -184.451498) (xy 408.669207 -184.430089) (xy 408.636079 -184.382451)
			(xy 408.610544 -184.330347) (xy 408.593191 -184.274978) (xy 408.584421 -184.21762) (xy 408.583892 -184.188608)
			(xy 408.584355 -184.161355) (xy 408.592111 -184.107403) (xy 408.607466 -184.055104) (xy 408.630108 -184.005523)
			(xy 408.659576 -183.959669) (xy 408.69527 -183.918475) (xy 408.736463 -183.882781) (xy 408.782316 -183.853312)
			(xy 408.831897 -183.830669) (xy 408.884195 -183.815313) (xy 408.938147 -183.807555) (xy 408.9654 -183.8071)
			(xy 408.993166 -183.807601) (xy 409.04811 -183.815656) (xy 409.101304 -183.831596) (xy 409.151624 -183.855084)
			(xy 409.198004 -183.885623) (xy 409.239464 -183.922566) (xy 409.275127 -183.965133) (xy 409.304237 -184.012423)
			(xy 409.315666 -184.037732) (xy 409.321721 -184.050569) (xy 409.339703 -184.072516) (xy 409.363025 -184.088673)
			(xy 409.389891 -184.097796) (xy 409.41823 -184.099181) (xy 409.445857 -184.092721) (xy 409.470643 -184.078915)
			(xy 409.48102 -184.069228) (xy 409.53182 -184.018428) (xy 409.53182 -182.739284) (xy 409.507863 -182.72728)
			(xy 409.463277 -182.697559) (xy 409.42329 -182.66189) (xy 409.388688 -182.620976) (xy 409.360152 -182.575622)
			(xy 409.338244 -182.526721) (xy 409.323395 -182.475235) (xy 409.315898 -182.422178) (xy 409.3159 -182.368594)
			(xy 409.323401 -182.315538) (xy 409.338253 -182.264053) (xy 409.360165 -182.215153) (xy 409.388704 -182.169802)
			(xy 409.423309 -182.12889) (xy 409.463299 -182.093224) (xy 409.507887 -182.063506) (xy 409.53182 -182.051452)
			(xy 409.53182 -176.711864) (xy 409.507864 -176.699857) (xy 409.46328 -176.67013) (xy 409.423294 -176.634457)
			(xy 409.388692 -176.593541) (xy 409.360155 -176.548186) (xy 409.338244 -176.499285) (xy 409.32339 -176.447799)
			(xy 409.315886 -176.394741) (xy 409.315412 -176.367948) (xy 409.315929 -176.339208) (xy 409.324546 -176.282376)
			(xy 409.341591 -176.227481) (xy 409.366679 -176.175765) (xy 409.399242 -176.128397) (xy 409.418536 -176.10709)
			(xy 409.428618 -176.095557) (xy 409.441978 -176.068007) (xy 409.446577 -176.037735) (xy 409.441999 -176.00746)
			(xy 409.428658 -175.979901) (xy 409.418536 -175.968406) (xy 409.399262 -175.94708) (xy 409.36669 -175.89972)
			(xy 409.341591 -175.848008) (xy 409.324533 -175.793117) (xy 409.315903 -175.736288) (xy 409.315412 -175.707548)
			(xy 409.315863 -175.680752) (xy 409.323357 -175.627686) (xy 409.338204 -175.576192) (xy 409.360112 -175.527282)
			(xy 409.38865 -175.48192) (xy 409.423255 -175.440998) (xy 409.463247 -175.405322) (xy 409.507839 -175.375595)
			(xy 409.53182 -175.363632) (xy 409.53182 -174.103284) (xy 409.507863 -174.09128) (xy 409.463277 -174.061559)
			(xy 409.42329 -174.02589) (xy 409.388688 -173.984976) (xy 409.360152 -173.939622) (xy 409.338244 -173.890721)
			(xy 409.323395 -173.839235) (xy 409.315898 -173.786178) (xy 409.3159 -173.732594) (xy 409.323401 -173.679538)
			(xy 409.338253 -173.628053) (xy 409.360165 -173.579153) (xy 409.388704 -173.533802) (xy 409.423309 -173.49289)
			(xy 409.463299 -173.457224) (xy 409.507887 -173.427506) (xy 409.53182 -173.415452) (xy 409.53182 -168.075864)
			(xy 409.507864 -168.063857) (xy 409.46328 -168.03413) (xy 409.423294 -167.998457) (xy 409.388692 -167.957541)
			(xy 409.360155 -167.912186) (xy 409.338244 -167.863285) (xy 409.32339 -167.811799) (xy 409.315886 -167.758741)
			(xy 409.315412 -167.731948) (xy 409.315848 -167.705679) (xy 409.323055 -167.653638) (xy 409.337338 -167.603079)
			(xy 409.358428 -167.55496) (xy 409.385924 -167.510192) (xy 409.40228 -167.489632) (xy 409.407917 -167.482096)
			(xy 409.413822 -167.464245) (xy 409.412913 -167.445465) (xy 409.405309 -167.428269) (xy 409.398978 -167.421306)
			(xy 408.71394 -166.736268) (xy 398.92986 -166.736268) (xy 398.02308 -167.643048) (xy 398.02308 -168.983152)
			(xy 399.642589 -168.983152) (xy 399.646611 -168.897432) (xy 399.658642 -168.812464) (xy 399.678578 -168.728997)
			(xy 399.706241 -168.647763) (xy 399.74139 -168.569477) (xy 399.783716 -168.494826) (xy 399.832845 -168.424467)
			(xy 399.888348 -168.359017) (xy 399.949735 -168.299053) (xy 400.016468 -168.2451) (xy 400.08796 -168.197633)
			(xy 400.163582 -168.157069) (xy 400.242671 -168.123765) (xy 400.324531 -168.098013) (xy 400.408442 -168.08004)
			(xy 400.493668 -168.070004) (xy 400.57946 -168.067992) (xy 400.665062 -168.074023) (xy 400.749724 -168.088043)
			(xy 400.832701 -168.109929) (xy 400.913264 -168.13949) (xy 400.990704 -168.176464) (xy 401.064343 -168.220528)
			(xy 401.133531 -168.271294) (xy 401.197662 -168.328315) (xy 401.256171 -168.391091) (xy 401.308544 -168.459071)
			(xy 401.354322 -168.531656) (xy 401.393102 -168.608208) (xy 401.424543 -168.688056) (xy 401.448369 -168.770497)
			(xy 401.46437 -168.854807) (xy 401.472405 -168.940245) (xy 401.472908 -168.983152) (xy 401.472405 -169.026059)
			(xy 401.46437 -169.111497) (xy 401.448369 -169.195807) (xy 401.424543 -169.278248) (xy 401.393102 -169.358096)
			(xy 401.354322 -169.434648) (xy 401.308544 -169.507233) (xy 401.256171 -169.575213) (xy 401.197662 -169.637989)
			(xy 401.133531 -169.69501) (xy 401.064343 -169.745776) (xy 400.990704 -169.78984) (xy 400.913264 -169.826814)
			(xy 400.832701 -169.856375) (xy 400.749724 -169.878261) (xy 400.665062 -169.892281) (xy 400.57946 -169.898312)
			(xy 400.493668 -169.8963) (xy 400.408442 -169.886264) (xy 400.324531 -169.868291) (xy 400.242671 -169.842539)
			(xy 400.163582 -169.809235) (xy 400.08796 -169.768671) (xy 400.016468 -169.721204) (xy 399.949735 -169.667251)
			(xy 399.888348 -169.607287) (xy 399.832845 -169.541837) (xy 399.783716 -169.471478) (xy 399.74139 -169.396827)
			(xy 399.706241 -169.318541) (xy 399.678578 -169.237307) (xy 399.658642 -169.15384) (xy 399.646611 -169.068872)
			(xy 399.642589 -168.983152) (xy 398.02308 -168.983152) (xy 398.02308 -171.025496) (xy 399.668996 -171.025496)
			(xy 399.668996 -170.9408) (xy 399.677047 -170.856486) (xy 399.693076 -170.77332) (xy 399.716937 -170.692053)
			(xy 399.748416 -170.613423) (xy 399.787227 -170.538142) (xy 399.833017 -170.46689) (xy 399.885373 -170.400314)
			(xy 399.943821 -170.339016) (xy 400.007831 -170.283551) (xy 400.076823 -170.234422) (xy 400.150173 -170.192073)
			(xy 400.227216 -170.156889) (xy 400.307255 -170.129187) (xy 400.389564 -170.109219) (xy 400.473399 -170.097166)
			(xy 400.558 -170.093136) (xy 400.642601 -170.097166) (xy 400.726436 -170.109219) (xy 400.808745 -170.129187)
			(xy 400.888784 -170.156889) (xy 400.965827 -170.192073) (xy 401.039177 -170.234422) (xy 401.108169 -170.283551)
			(xy 401.172179 -170.339016) (xy 401.230627 -170.400314) (xy 401.282983 -170.46689) (xy 401.328773 -170.538142)
			(xy 401.367584 -170.613423) (xy 401.399063 -170.692053) (xy 401.422924 -170.77332) (xy 401.438953 -170.856486)
			(xy 401.447004 -170.9408) (xy 401.447508 -170.983148) (xy 401.447004 -171.025496) (xy 401.438953 -171.10981)
			(xy 401.422924 -171.192976) (xy 401.399063 -171.274243) (xy 401.367584 -171.352873) (xy 401.328773 -171.428154)
			(xy 401.282983 -171.499406) (xy 401.230627 -171.565982) (xy 401.172179 -171.62728) (xy 401.108169 -171.682745)
			(xy 401.039177 -171.731874) (xy 400.965827 -171.774223) (xy 400.888784 -171.809407) (xy 400.808745 -171.837109)
			(xy 400.726436 -171.857077) (xy 400.642601 -171.86913) (xy 400.558 -171.873161) (xy 400.473399 -171.86913)
			(xy 400.389564 -171.857077) (xy 400.307255 -171.837109) (xy 400.227216 -171.809407) (xy 400.150173 -171.774223)
			(xy 400.076823 -171.731874) (xy 400.007831 -171.682745) (xy 399.943821 -171.62728) (xy 399.885373 -171.565982)
			(xy 399.833017 -171.499406) (xy 399.787227 -171.428154) (xy 399.748416 -171.352873) (xy 399.716937 -171.274243)
			(xy 399.693076 -171.192976) (xy 399.677047 -171.10981) (xy 399.668996 -171.025496) (xy 398.02308 -171.025496)
			(xy 398.02308 -175.206152) (xy 399.642589 -175.206152) (xy 399.646611 -175.120432) (xy 399.658642 -175.035464)
			(xy 399.678578 -174.951997) (xy 399.706241 -174.870763) (xy 399.74139 -174.792477) (xy 399.783716 -174.717826)
			(xy 399.832845 -174.647467) (xy 399.888348 -174.582017) (xy 399.949735 -174.522053) (xy 400.016468 -174.4681)
			(xy 400.08796 -174.420633) (xy 400.163582 -174.380069) (xy 400.242671 -174.346765) (xy 400.324531 -174.321013)
			(xy 400.408442 -174.30304) (xy 400.493668 -174.293004) (xy 400.57946 -174.290992) (xy 400.665062 -174.297023)
			(xy 400.749724 -174.311043) (xy 400.832701 -174.332929) (xy 400.913264 -174.36249) (xy 400.990704 -174.399464)
			(xy 401.064343 -174.443528) (xy 401.133531 -174.494294) (xy 401.197662 -174.551315) (xy 401.256171 -174.614091)
			(xy 401.308544 -174.682071) (xy 401.354322 -174.754656) (xy 401.393102 -174.831208) (xy 401.424543 -174.911056)
			(xy 401.448369 -174.993497) (xy 401.46437 -175.077807) (xy 401.472405 -175.163245) (xy 401.472908 -175.206152)
			(xy 401.472405 -175.249059) (xy 401.46437 -175.334497) (xy 401.448369 -175.418807) (xy 401.424543 -175.501248)
			(xy 401.393102 -175.581096) (xy 401.354322 -175.657648) (xy 401.308544 -175.730233) (xy 401.256171 -175.798213)
			(xy 401.197662 -175.860989) (xy 401.133531 -175.91801) (xy 401.064343 -175.968776) (xy 400.990704 -176.01284)
			(xy 400.913264 -176.049814) (xy 400.832701 -176.079375) (xy 400.749724 -176.101261) (xy 400.665062 -176.115281)
			(xy 400.57946 -176.121312) (xy 400.493668 -176.1193) (xy 400.408442 -176.109264) (xy 400.324531 -176.091291)
			(xy 400.242671 -176.065539) (xy 400.163582 -176.032235) (xy 400.08796 -175.991671) (xy 400.016468 -175.944204)
			(xy 399.949735 -175.890251) (xy 399.888348 -175.830287) (xy 399.832845 -175.764837) (xy 399.783716 -175.694478)
			(xy 399.74139 -175.619827) (xy 399.706241 -175.541541) (xy 399.678578 -175.460307) (xy 399.658642 -175.37684)
			(xy 399.646611 -175.291872) (xy 399.642589 -175.206152) (xy 398.02308 -175.206152) (xy 398.02308 -177.248496)
			(xy 399.668996 -177.248496) (xy 399.668996 -177.1638) (xy 399.677047 -177.079486) (xy 399.693076 -176.99632)
			(xy 399.716937 -176.915053) (xy 399.748416 -176.836423) (xy 399.787227 -176.761142) (xy 399.833017 -176.68989)
			(xy 399.885373 -176.623314) (xy 399.943821 -176.562016) (xy 400.007831 -176.506551) (xy 400.076823 -176.457422)
			(xy 400.150173 -176.415073) (xy 400.227216 -176.379889) (xy 400.307255 -176.352187) (xy 400.389564 -176.332219)
			(xy 400.473399 -176.320166) (xy 400.558 -176.316136) (xy 400.642601 -176.320166) (xy 400.726436 -176.332219)
			(xy 400.808745 -176.352187) (xy 400.888784 -176.379889) (xy 400.965827 -176.415073) (xy 401.039177 -176.457422)
			(xy 401.108169 -176.506551) (xy 401.172179 -176.562016) (xy 401.230627 -176.623314) (xy 401.282983 -176.68989)
			(xy 401.328773 -176.761142) (xy 401.367584 -176.836423) (xy 401.399063 -176.915053) (xy 401.422924 -176.99632)
			(xy 401.438953 -177.079486) (xy 401.447004 -177.1638) (xy 401.447508 -177.206148) (xy 401.447004 -177.248496)
			(xy 401.438953 -177.33281) (xy 401.422924 -177.415976) (xy 401.399063 -177.497243) (xy 401.367584 -177.575873)
			(xy 401.328773 -177.651154) (xy 401.282983 -177.722406) (xy 401.230627 -177.788982) (xy 401.172179 -177.85028)
			(xy 401.108169 -177.905745) (xy 401.039177 -177.954874) (xy 400.965827 -177.997223) (xy 400.888784 -178.032407)
			(xy 400.808745 -178.060109) (xy 400.726436 -178.080077) (xy 400.642601 -178.09213) (xy 400.558 -178.096161)
			(xy 400.473399 -178.09213) (xy 400.389564 -178.080077) (xy 400.307255 -178.060109) (xy 400.227216 -178.032407)
			(xy 400.150173 -177.997223) (xy 400.076823 -177.954874) (xy 400.007831 -177.905745) (xy 399.943821 -177.85028)
			(xy 399.885373 -177.788982) (xy 399.833017 -177.722406) (xy 399.787227 -177.651154) (xy 399.748416 -177.575873)
			(xy 399.716937 -177.497243) (xy 399.693076 -177.415976) (xy 399.677047 -177.33281) (xy 399.668996 -177.248496)
			(xy 398.02308 -177.248496) (xy 398.02308 -181.429152) (xy 399.642589 -181.429152) (xy 399.646611 -181.343432)
			(xy 399.658642 -181.258464) (xy 399.678578 -181.174997) (xy 399.706241 -181.093763) (xy 399.74139 -181.015477)
			(xy 399.783716 -180.940826) (xy 399.832845 -180.870467) (xy 399.888348 -180.805017) (xy 399.949735 -180.745053)
			(xy 400.016468 -180.6911) (xy 400.08796 -180.643633) (xy 400.163582 -180.603069) (xy 400.242671 -180.569765)
			(xy 400.324531 -180.544013) (xy 400.408442 -180.52604) (xy 400.493668 -180.516004) (xy 400.57946 -180.513992)
			(xy 400.665062 -180.520023) (xy 400.749724 -180.534043) (xy 400.832701 -180.555929) (xy 400.913264 -180.58549)
			(xy 400.990704 -180.622464) (xy 401.064343 -180.666528) (xy 401.133531 -180.717294) (xy 401.197662 -180.774315)
			(xy 401.256171 -180.837091) (xy 401.308544 -180.905071) (xy 401.354322 -180.977656) (xy 401.393102 -181.054208)
			(xy 401.424543 -181.134056) (xy 401.448369 -181.216497) (xy 401.46437 -181.300807) (xy 401.472405 -181.386245)
			(xy 401.472908 -181.429152) (xy 401.472405 -181.472059) (xy 401.46437 -181.557497) (xy 401.448369 -181.641807)
			(xy 401.424543 -181.724248) (xy 401.393102 -181.804096) (xy 401.354322 -181.880648) (xy 401.308544 -181.953233)
			(xy 401.256171 -182.021213) (xy 401.197662 -182.083989) (xy 401.133531 -182.14101) (xy 401.064343 -182.191776)
			(xy 400.990704 -182.23584) (xy 400.913264 -182.272814) (xy 400.832701 -182.302375) (xy 400.749724 -182.324261)
			(xy 400.665062 -182.338281) (xy 400.57946 -182.344312) (xy 400.493668 -182.3423) (xy 400.408442 -182.332264)
			(xy 400.324531 -182.314291) (xy 400.242671 -182.288539) (xy 400.163582 -182.255235) (xy 400.08796 -182.214671)
			(xy 400.016468 -182.167204) (xy 399.949735 -182.113251) (xy 399.888348 -182.053287) (xy 399.832845 -181.987837)
			(xy 399.783716 -181.917478) (xy 399.74139 -181.842827) (xy 399.706241 -181.764541) (xy 399.678578 -181.683307)
			(xy 399.658642 -181.59984) (xy 399.646611 -181.514872) (xy 399.642589 -181.429152) (xy 398.02308 -181.429152)
			(xy 398.02308 -183.471496) (xy 399.668996 -183.471496) (xy 399.668996 -183.3868) (xy 399.677047 -183.302486)
			(xy 399.693076 -183.21932) (xy 399.716937 -183.138053) (xy 399.748416 -183.059423) (xy 399.787227 -182.984142)
			(xy 399.833017 -182.91289) (xy 399.885373 -182.846314) (xy 399.943821 -182.785016) (xy 400.007831 -182.729551)
			(xy 400.076823 -182.680422) (xy 400.150173 -182.638073) (xy 400.227216 -182.602889) (xy 400.307255 -182.575187)
			(xy 400.389564 -182.555219) (xy 400.473399 -182.543166) (xy 400.558 -182.539136) (xy 400.642601 -182.543166)
			(xy 400.726436 -182.555219) (xy 400.808745 -182.575187) (xy 400.888784 -182.602889) (xy 400.965827 -182.638073)
			(xy 401.039177 -182.680422) (xy 401.108169 -182.729551) (xy 401.172179 -182.785016) (xy 401.230627 -182.846314)
			(xy 401.282983 -182.91289) (xy 401.328773 -182.984142) (xy 401.367584 -183.059423) (xy 401.399063 -183.138053)
			(xy 401.422924 -183.21932) (xy 401.438953 -183.302486) (xy 401.447004 -183.3868) (xy 401.447508 -183.429148)
			(xy 401.447004 -183.471496) (xy 401.438953 -183.55581) (xy 401.422924 -183.638976) (xy 401.399063 -183.720243)
			(xy 401.367584 -183.798873) (xy 401.328773 -183.874154) (xy 401.282983 -183.945406) (xy 401.230627 -184.011982)
			(xy 401.172179 -184.07328) (xy 401.108169 -184.128745) (xy 401.039177 -184.177874) (xy 400.965827 -184.220223)
			(xy 400.888784 -184.255407) (xy 400.808745 -184.283109) (xy 400.726436 -184.303077) (xy 400.642601 -184.31513)
			(xy 400.558 -184.319161) (xy 400.473399 -184.31513) (xy 400.389564 -184.303077) (xy 400.307255 -184.283109)
			(xy 400.227216 -184.255407) (xy 400.150173 -184.220223) (xy 400.076823 -184.177874) (xy 400.007831 -184.128745)
			(xy 399.943821 -184.07328) (xy 399.885373 -184.011982) (xy 399.833017 -183.945406) (xy 399.787227 -183.874154)
			(xy 399.748416 -183.798873) (xy 399.716937 -183.720243) (xy 399.693076 -183.638976) (xy 399.677047 -183.55581)
			(xy 399.668996 -183.471496) (xy 398.02308 -183.471496) (xy 398.02308 -183.761888) (xy 398.88414 -184.622948)
		)
		(stroke
			(width 0)
			(type solid)
		)
		(fill yes)
		(layer "In6.Cu")
		(net "PVCCINFAON_CPU0")
	)
	(gr_poly
		(pts
			(xy 425.7421 -141.88694) (xy 425.742354 -141.887194) (xy 426.01896 -141.610588) (xy 426.01896 -138.748008)
			(xy 425.69384 -138.422888) (xy 423.85488 -138.422888) (xy 423.72026 -138.288268) (xy 423.72026 -132.197348)
			(xy 421.471344 -132.197348) (xy 421.4384 -132.217193) (xy 421.369272 -132.25091) (xy 421.297101 -132.277497)
			(xy 421.222619 -132.296683) (xy 421.146585 -132.308273) (xy 421.06977 -132.312149) (xy 420.992955 -132.308273)
			(xy 420.916921 -132.296683) (xy 420.842439 -132.277497) (xy 420.770268 -132.25091) (xy 420.70114 -132.217193)
			(xy 420.668196 -132.197348) (xy 419.963854 -132.197348) (xy 419.960552 -132.244592) (xy 419.958082 -132.27213)
			(xy 419.946199 -132.326127) (xy 419.926641 -132.377841) (xy 419.899818 -132.426188) (xy 419.866292 -132.470152)
			(xy 419.826767 -132.508813) (xy 419.782072 -132.541358) (xy 419.733144 -132.567106) (xy 419.68101 -132.585516)
			(xy 419.653974 -132.591302) (xy 419.61308 -132.59943) (xy 419.61308 -132.682234) (xy 419.61351 -132.691931)
			(xy 419.620706 -132.709941) (xy 419.634062 -132.724005) (xy 419.651677 -132.732121) (xy 419.66134 -132.733034)
			(xy 419.687704 -132.734751) (xy 419.739621 -132.744546) (xy 419.78969 -132.761409) (xy 419.836955 -132.785017)
			(xy 419.880511 -132.81492) (xy 419.919525 -132.850545) (xy 419.953252 -132.891212) (xy 419.981046 -132.936143)
			(xy 420.002377 -132.984478) (xy 420.016836 -133.035293) (xy 420.024147 -133.087618) (xy 420.02456 -133.114034)
			(xy 420.024051 -133.14223) (xy 420.015748 -133.198006) (xy 419.999329 -133.251954) (xy 419.97515 -133.302899)
			(xy 419.943739 -133.349731) (xy 419.905778 -133.391432) (xy 419.862094 -133.427093) (xy 419.838124 -133.441948)
			(xy 419.825563 -133.450025) (xy 419.805416 -133.472048) (xy 419.7925 -133.498958) (xy 419.78792 -133.528454)
			(xy 419.792068 -133.558013) (xy 419.804589 -133.585109) (xy 419.824412 -133.607424) (xy 419.836854 -133.615684)
			(xy 419.860225 -133.630691) (xy 419.902769 -133.666397) (xy 419.939692 -133.707888) (xy 419.970215 -133.75429)
			(xy 419.993695 -133.804624) (xy 420.009636 -133.857828) (xy 420.017703 -133.91278) (xy 420.01821 -133.94055)
			(xy 420.017739 -133.967545) (xy 420.010124 -134.020997) (xy 419.995053 -134.072842) (xy 419.972827 -134.122046)
			(xy 419.94389 -134.167627) (xy 419.908818 -134.208675) (xy 419.868311 -134.244372) (xy 419.845998 -134.259574)
			(xy 419.834682 -134.267499) (xy 419.81644 -134.288229) (xy 419.80443 -134.313094) (xy 419.799532 -134.340271)
			(xy 419.802106 -134.367764) (xy 419.811964 -134.393559) (xy 419.828381 -134.415762) (xy 419.850154 -134.432746)
			(xy 419.862762 -134.43839) (xy 419.900235 -134.454539) (xy 419.971816 -134.493723) (xy 420.038803 -134.540325)
			(xy 420.100431 -134.593814) (xy 420.155995 -134.653577) (xy 420.204861 -134.718931) (xy 420.24647 -134.78913)
			(xy 420.280345 -134.863369) (xy 420.306099 -134.940802) (xy 420.323438 -135.020541) (xy 420.332165 -135.101677)
			(xy 420.332546 -135.132976) (xy 420.938775 -135.132976) (xy 420.944107 -135.055023) (xy 420.957383 -134.978024)
			(xy 420.978463 -134.902787) (xy 421.007128 -134.8301) (xy 421.043075 -134.760725) (xy 421.085929 -134.69539)
			(xy 421.135239 -134.63478) (xy 421.190489 -134.579531) (xy 421.2511 -134.530221) (xy 421.316435 -134.487369)
			(xy 421.38581 -134.451423) (xy 421.458498 -134.42276) (xy 421.533736 -134.40168) (xy 421.610735 -134.388406)
			(xy 421.688688 -134.383075) (xy 421.766777 -134.385744) (xy 421.844184 -134.396385) (xy 421.920097 -134.414887)
			(xy 421.99372 -134.441054) (xy 422.06428 -134.474614) (xy 422.131039 -134.515213) (xy 422.193296 -134.562427)
			(xy 422.250398 -134.61576) (xy 422.301747 -134.674653) (xy 422.346804 -134.738489) (xy 422.385096 -134.806597)
			(xy 422.416222 -134.878265) (xy 422.439856 -134.95274) (xy 422.45575 -135.029241) (xy 422.463737 -135.106967)
			(xy 422.46423 -135.146034) (xy 422.463737 -135.185672) (xy 422.455523 -135.264521) (xy 422.439177 -135.342094)
			(xy 422.414875 -135.417553) (xy 422.382879 -135.490085) (xy 422.363646 -135.524748) (xy 422.384176 -135.542961)
			(xy 422.420307 -135.584269) (xy 422.45015 -135.630325) (xy 422.47309 -135.680181) (xy 422.488652 -135.732808)
			(xy 422.496517 -135.787122) (xy 422.496996 -135.814562) (xy 422.496421 -135.844475) (xy 422.487063 -135.903565)
			(xy 422.468587 -135.960466) (xy 422.441447 -136.013782) (xy 422.424352 -136.038336) (xy 422.417 -136.049244)
			(xy 422.407492 -136.073757) (xy 422.404562 -136.099886) (xy 422.408405 -136.125896) (xy 422.418765 -136.150062)
			(xy 422.434956 -136.170778) (xy 422.44518 -136.179052) (xy 422.468223 -136.197173) (xy 422.508955 -136.239328)
			(xy 422.542755 -136.287221) (xy 422.568827 -136.339723) (xy 422.586555 -136.395597) (xy 422.595522 -136.453526)
			(xy 422.596056 -136.482836) (xy 422.59557 -136.510087) (xy 422.587814 -136.564035) (xy 422.572459 -136.61633)
			(xy 422.549817 -136.665907) (xy 422.520351 -136.711757) (xy 422.48466 -136.752948) (xy 422.443469 -136.788639)
			(xy 422.397619 -136.818105) (xy 422.348042 -136.840747) (xy 422.295747 -136.856102) (xy 422.241799 -136.863858)
			(xy 422.187297 -136.863858) (xy 422.133349 -136.856102) (xy 422.081054 -136.840747) (xy 422.031477 -136.818105)
			(xy 421.985627 -136.788639) (xy 421.944436 -136.752948) (xy 421.908745 -136.711757) (xy 421.879279 -136.665907)
			(xy 421.856637 -136.61633) (xy 421.841282 -136.564035) (xy 421.833526 -136.510087) (xy 421.83304 -136.482836)
			(xy 421.833608 -136.452923) (xy 421.842966 -136.393832) (xy 421.861444 -136.33693) (xy 421.888587 -136.283615)
			(xy 421.905684 -136.259062) (xy 421.913053 -136.248163) (xy 421.922569 -136.223647) (xy 421.925501 -136.197514)
			(xy 421.921655 -136.171499) (xy 421.911287 -136.147331) (xy 421.895086 -136.126617) (xy 421.884856 -136.118346)
			(xy 421.86456 -136.102419) (xy 421.828046 -136.065973) (xy 421.79677 -136.024942) (xy 421.771304 -135.980074)
			(xy 421.752109 -135.932186) (xy 421.74541 -135.907272) (xy 421.701722 -135.908542) (xy 421.662655 -135.908036)
			(xy 421.584929 -135.900048) (xy 421.508428 -135.884153) (xy 421.433954 -135.860518) (xy 421.362287 -135.82939)
			(xy 421.294179 -135.791097) (xy 421.230344 -135.746039) (xy 421.171452 -135.69469) (xy 421.11812 -135.637587)
			(xy 421.070907 -135.575329) (xy 421.030308 -135.50857) (xy 420.99675 -135.438009) (xy 420.970583 -135.364385)
			(xy 420.952083 -135.288472) (xy 420.941443 -135.211065) (xy 420.938775 -135.132976) (xy 420.332546 -135.132976)
			(xy 420.332662 -135.142478) (xy 420.332135 -135.182853) (xy 420.323605 -135.263151) (xy 420.306637 -135.342097)
			(xy 420.281422 -135.418809) (xy 420.248243 -135.492427) (xy 420.207469 -135.562127) (xy 420.159559 -135.627128)
			(xy 420.105049 -135.686702) (xy 420.044549 -135.740183) (xy 419.978736 -135.786971) (xy 419.943788 -135.807196)
			(xy 419.931846 -135.814392) (xy 419.912132 -135.834094) (xy 419.898479 -135.858392) (xy 419.891904 -135.885477)
			(xy 419.892896 -135.91333) (xy 419.901383 -135.939878) (xy 419.908736 -135.951722) (xy 419.923681 -135.975239)
			(xy 419.947324 -136.025692) (xy 419.96337 -136.07905) (xy 419.971477 -136.134175) (xy 419.971982 -136.162034)
			(xy 419.971538 -136.188755) (xy 419.964086 -136.241676) (xy 419.949319 -136.293038) (xy 419.927526 -136.341835)
			(xy 419.899134 -136.387112) (xy 419.8647 -136.427982) (xy 419.824897 -136.463644) (xy 419.780504 -136.493401)
			(xy 419.732393 -136.516668) (xy 419.681504 -136.532991) (xy 419.655244 -136.537954) (xy 419.61308 -136.54532)
			(xy 419.61308 -136.794748) (xy 419.655244 -136.802114) (xy 419.682874 -136.807382) (xy 419.736302 -136.824967)
			(xy 419.786568 -136.850207) (xy 419.832582 -136.882556) (xy 419.873346 -136.921312) (xy 419.907976 -136.965634)
			(xy 419.935722 -137.014562) (xy 419.955982 -137.067033) (xy 419.968315 -137.121911) (xy 419.972456 -137.178006)
			(xy 419.968314 -137.2341) (xy 419.955978 -137.288978) (xy 419.935717 -137.341449) (xy 419.90797 -137.390375)
			(xy 419.873338 -137.434697) (xy 419.832573 -137.473451) (xy 419.786558 -137.505799) (xy 419.736291 -137.531037)
			(xy 419.682863 -137.54862) (xy 419.655244 -137.553954) (xy 419.61308 -137.56132) (xy 419.61308 -137.724388)
			(xy 420.811452 -137.724388) (xy 420.811941 -137.685743) (xy 420.819761 -137.608849) (xy 420.835319 -137.533141)
			(xy 420.858457 -137.459395) (xy 420.888937 -137.388368) (xy 420.926446 -137.32079) (xy 420.9706 -137.257352)
			(xy 421.020945 -137.198708) (xy 421.076964 -137.145457) (xy 421.138083 -137.098147) (xy 421.203676 -137.057263)
			(xy 421.273067 -137.023225) (xy 421.345547 -136.996382) (xy 421.42037 -136.977009) (xy 421.496769 -136.965305)
			(xy 421.57396 -136.96139) (xy 421.651151 -136.965305) (xy 421.72755 -136.977009) (xy 421.802373 -136.996382)
			(xy 421.874853 -137.023225) (xy 421.944244 -137.057263) (xy 422.009837 -137.098147) (xy 422.070956 -137.145457)
			(xy 422.126975 -137.198708) (xy 422.17732 -137.257352) (xy 422.221474 -137.32079) (xy 422.258983 -137.388368)
			(xy 422.289463 -137.459395) (xy 422.312601 -137.533141) (xy 422.328159 -137.608849) (xy 422.335979 -137.685743)
			(xy 422.336468 -137.724388) (xy 422.335878 -137.765404) (xy 422.327083 -137.846964) (xy 422.309582 -137.927108)
			(xy 422.283578 -138.004911) (xy 422.249372 -138.079471) (xy 422.207358 -138.149928) (xy 422.158023 -138.215467)
			(xy 422.101936 -138.275331) (xy 422.039747 -138.328827) (xy 422.006268 -138.35253) (xy 421.993945 -138.361614)
			(xy 421.974992 -138.385642) (xy 421.964005 -138.414205) (xy 421.961967 -138.44474) (xy 421.969062 -138.474509)
			(xy 421.984653 -138.500842) (xy 422.007343 -138.521379) (xy 422.021 -138.528298) (xy 422.045347 -138.540166)
			(xy 422.090718 -138.569745) (xy 422.13145 -138.605444) (xy 422.166725 -138.646543) (xy 422.195834 -138.692217)
			(xy 422.218192 -138.741549) (xy 422.233349 -138.793547) (xy 422.241002 -138.847165) (xy 422.241472 -138.874246)
			(xy 422.240986 -138.901497) (xy 422.23323 -138.955445) (xy 422.217875 -139.00774) (xy 422.195233 -139.057317)
			(xy 422.165767 -139.103167) (xy 422.130076 -139.144358) (xy 422.088885 -139.180049) (xy 422.043035 -139.209515)
			(xy 421.993458 -139.232157) (xy 421.941163 -139.247512) (xy 421.887215 -139.255268) (xy 421.832713 -139.255268)
			(xy 421.778765 -139.247512) (xy 421.72647 -139.232157) (xy 421.676893 -139.209515) (xy 421.631043 -139.180049)
			(xy 421.589852 -139.144358) (xy 421.554161 -139.103167) (xy 421.524695 -139.057317) (xy 421.502053 -139.00774)
			(xy 421.486698 -138.955445) (xy 421.478942 -138.901497) (xy 421.478456 -138.874246) (xy 421.479062 -138.843349)
			(xy 421.489016 -138.782362) (xy 421.50867 -138.723777) (xy 421.537512 -138.669126) (xy 421.555672 -138.644122)
			(xy 421.564435 -138.631571) (xy 421.574835 -138.602798) (xy 421.576261 -138.572237) (xy 421.568588 -138.542621)
			(xy 421.552501 -138.516597) (xy 421.529438 -138.496494) (xy 421.501463 -138.484109) (xy 421.48633 -138.481816)
			(xy 421.447004 -138.476744) (xy 421.369602 -138.45951) (xy 421.294407 -138.434335) (xy 421.222231 -138.401492)
			(xy 421.153854 -138.361335) (xy 421.090014 -138.314297) (xy 421.031401 -138.260888) (xy 420.978648 -138.201683)
			(xy 420.932325 -138.137323) (xy 420.892932 -138.068503) (xy 420.860894 -137.995966) (xy 420.836559 -137.920495)
			(xy 420.820188 -137.842906) (xy 420.811959 -137.764037) (xy 420.811452 -137.724388) (xy 419.61308 -137.724388)
			(xy 419.61308 -137.847578) (xy 419.646354 -137.85977) (xy 419.682486 -137.873615) (xy 419.751991 -137.907626)
			(xy 419.817695 -137.948501) (xy 419.878923 -137.995818) (xy 419.935046 -138.049092) (xy 419.985485 -138.107774)
			(xy 420.029724 -138.171262) (xy 420.067306 -138.238904) (xy 420.097847 -138.310002) (xy 420.121032 -138.383828)
			(xy 420.136622 -138.459622) (xy 420.144457 -138.536605) (xy 420.144458 -138.613986) (xy 420.136623 -138.690969)
			(xy 420.121034 -138.766764) (xy 420.09785 -138.84059) (xy 420.06731 -138.911689) (xy 420.029728 -138.979331)
			(xy 419.98549 -139.042819) (xy 419.935051 -139.101502) (xy 419.87893 -139.154777) (xy 419.817702 -139.202094)
			(xy 419.751998 -139.24297) (xy 419.682493 -139.276982) (xy 419.646354 -139.290806) (xy 419.61308 -139.302998)
			(xy 419.61308 -139.697968) (xy 423.5229 -139.697968) (xy 423.526971 -139.642346) (xy 423.539097 -139.587909)
			(xy 423.55902 -139.535818) (xy 423.586316 -139.487183) (xy 423.620402 -139.44304) (xy 423.660551 -139.404331)
			(xy 423.705909 -139.37188) (xy 423.755509 -139.346379) (xy 423.808293 -139.328372) (xy 423.863136 -139.318242)
			(xy 423.91887 -139.316205) (xy 423.974307 -139.322305) (xy 424.028264 -139.336411) (xy 424.079593 -139.358223)
			(xy 424.127199 -139.387277) (xy 424.170067 -139.422952) (xy 424.207284 -139.464489) (xy 424.238057 -139.511002)
			(xy 424.261729 -139.561499) (xy 424.277797 -139.614906) (xy 424.285917 -139.670082) (xy 424.286426 -139.697968)
			(xy 424.285917 -139.725854) (xy 424.277797 -139.78103) (xy 424.261729 -139.834437) (xy 424.238057 -139.884934)
			(xy 424.207284 -139.931447) (xy 424.170067 -139.972984) (xy 424.127199 -140.008659) (xy 424.079593 -140.037713)
			(xy 424.028264 -140.059525) (xy 423.974307 -140.073631) (xy 423.91887 -140.079731) (xy 423.863136 -140.077694)
			(xy 423.808293 -140.067564) (xy 423.755509 -140.049557) (xy 423.705909 -140.024056) (xy 423.660551 -139.991605)
			(xy 423.620402 -139.952896) (xy 423.586316 -139.908753) (xy 423.55902 -139.860118) (xy 423.539097 -139.808027)
			(xy 423.526971 -139.75359) (xy 423.5229 -139.697968) (xy 419.61308 -139.697968) (xy 419.61308 -141.026453)
			(xy 422.148465 -141.026453) (xy 422.148465 -140.971947) (xy 422.156222 -140.917997) (xy 422.171578 -140.8657)
			(xy 422.194221 -140.816121) (xy 422.223689 -140.770269) (xy 422.259382 -140.729077) (xy 422.300575 -140.693384)
			(xy 422.346428 -140.663917) (xy 422.396008 -140.641276) (xy 422.448305 -140.625921) (xy 422.502255 -140.618165)
			(xy 422.529508 -140.617702) (xy 422.555887 -140.618166) (xy 422.608144 -140.625419) (xy 422.658903 -140.639801)
			(xy 422.707198 -140.661037) (xy 422.752108 -140.688722) (xy 422.792777 -140.722329) (xy 422.82843 -140.761217)
			(xy 422.858387 -140.804644) (xy 422.87063 -140.828014) (xy 422.877332 -140.840373) (xy 422.896307 -140.861101)
			(xy 422.920221 -140.875863) (xy 422.947257 -140.883535) (xy 422.975359 -140.883535) (xy 423.002395 -140.875863)
			(xy 423.026309 -140.861101) (xy 423.045284 -140.840373) (xy 423.051986 -140.828014) (xy 423.064228 -140.804644)
			(xy 423.094189 -140.761219) (xy 423.129844 -140.722332) (xy 423.170513 -140.688725) (xy 423.215422 -140.661038)
			(xy 423.263715 -140.639798) (xy 423.314473 -140.62541) (xy 423.366729 -140.618147) (xy 423.393108 -140.617702)
			(xy 423.42036 -140.618168) (xy 423.474308 -140.625926) (xy 423.526603 -140.641282) (xy 423.576181 -140.663924)
			(xy 423.622031 -140.693392) (xy 423.663222 -140.729084) (xy 423.698913 -140.770275) (xy 423.728379 -140.816126)
			(xy 423.751021 -140.865704) (xy 423.766376 -140.918) (xy 423.774132 -140.971948) (xy 423.774132 -141.026452)
			(xy 423.766376 -141.0804) (xy 423.751021 -141.132696) (xy 423.728379 -141.182274) (xy 423.698913 -141.228125)
			(xy 423.663222 -141.269316) (xy 423.622031 -141.305008) (xy 423.576181 -141.334476) (xy 423.526603 -141.357118)
			(xy 423.474308 -141.372474) (xy 423.42036 -141.380232) (xy 423.393108 -141.380718) (xy 423.36673 -141.38023)
			(xy 423.314475 -141.372979) (xy 423.263716 -141.3586) (xy 423.215422 -141.337367) (xy 423.170512 -141.309686)
			(xy 423.129843 -141.276083) (xy 423.094189 -141.237198) (xy 423.06423 -141.193774) (xy 423.051986 -141.170406)
			(xy 423.045284 -141.158047) (xy 423.026309 -141.137319) (xy 423.002395 -141.122557) (xy 422.975359 -141.114885)
			(xy 422.947257 -141.114885) (xy 422.920221 -141.122557) (xy 422.896307 -141.137319) (xy 422.877332 -141.158047)
			(xy 422.87063 -141.170406) (xy 422.858385 -141.193774) (xy 422.828423 -141.237198) (xy 422.792768 -141.276084)
			(xy 422.752099 -141.30969) (xy 422.707191 -141.337377) (xy 422.658899 -141.358618) (xy 422.608141 -141.373008)
			(xy 422.555887 -141.380272) (xy 422.529508 -141.380718) (xy 422.502255 -141.380235) (xy 422.448305 -141.372479)
			(xy 422.396008 -141.357124) (xy 422.346428 -141.334483) (xy 422.300575 -141.305016) (xy 422.259382 -141.269323)
			(xy 422.223689 -141.228131) (xy 422.194221 -141.182279) (xy 422.171578 -141.1327) (xy 422.156222 -141.080403)
			(xy 422.148465 -141.026453) (xy 419.61308 -141.026453) (xy 419.61308 -141.976348) (xy 425.6532 -141.976348)
		)
		(stroke
			(width 0)
			(type solid)
		)
		(fill yes)
		(layer "In6.Cu")
		(net "PVCCINFAON_CPU0_VREF")
	)
	(gr_poly
		(pts
			(xy 198.958962 -69.070728) (xy 198.972888 -69.070302) (xy 198.999706 -69.06279) (xy 199.023499 -69.048313)
			(xy 199.042497 -69.027947) (xy 199.055288 -69.003208) (xy 199.060922 -68.975933) (xy 199.060308 -68.962016)
			(xy 199.059292 -68.9356) (xy 199.059778 -68.908349) (xy 199.067534 -68.854401) (xy 199.082889 -68.802106)
			(xy 199.105531 -68.752529) (xy 199.134997 -68.706679) (xy 199.170688 -68.665488) (xy 199.211879 -68.629797)
			(xy 199.257729 -68.600331) (xy 199.307306 -68.577689) (xy 199.359601 -68.562334) (xy 199.413549 -68.554578)
			(xy 199.468051 -68.554578) (xy 199.521999 -68.562334) (xy 199.574294 -68.577689) (xy 199.623871 -68.600331)
			(xy 199.669721 -68.629797) (xy 199.710912 -68.665488) (xy 199.746603 -68.706679) (xy 199.776069 -68.752529)
			(xy 199.798711 -68.802106) (xy 199.814066 -68.854401) (xy 199.821822 -68.908349) (xy 199.822308 -68.9356)
			(xy 199.821292 -68.962016) (xy 199.820751 -68.975928) (xy 199.826381 -69.003183) (xy 199.839163 -69.027905)
			(xy 199.858147 -69.048256) (xy 199.881923 -69.062723) (xy 199.908722 -69.07023) (xy 199.922638 -69.070728)
			(xy 202.067668 -69.070728) (xy 202.081266 -69.070288) (xy 202.107495 -69.063098) (xy 202.1309 -69.049245)
			(xy 202.149822 -69.02971) (xy 202.162922 -69.005876) (xy 202.169272 -68.979431) (xy 202.169268 -68.965826)
			(xy 202.169014 -68.953126) (xy 202.1695 -68.925875) (xy 202.177256 -68.871927) (xy 202.192611 -68.819632)
			(xy 202.215253 -68.770055) (xy 202.244719 -68.724205) (xy 202.28041 -68.683014) (xy 202.321601 -68.647323)
			(xy 202.367451 -68.617857) (xy 202.417028 -68.595215) (xy 202.469323 -68.57986) (xy 202.523271 -68.572104)
			(xy 202.577773 -68.572104) (xy 202.631721 -68.57986) (xy 202.684016 -68.595215) (xy 202.733593 -68.617857)
			(xy 202.779443 -68.647323) (xy 202.820634 -68.683014) (xy 202.856325 -68.724205) (xy 202.885791 -68.770055)
			(xy 202.908433 -68.819632) (xy 202.923788 -68.871927) (xy 202.931544 -68.925875) (xy 202.93203 -68.953126)
			(xy 202.931776 -68.965826) (xy 202.931758 -68.97944) (xy 202.938074 -69.005912) (xy 202.951162 -69.029774)
			(xy 202.970091 -69.049328) (xy 202.993515 -69.063184) (xy 203.019768 -69.070356) (xy 203.033376 -69.070728)
			(xy 210.286092 -69.070728) (xy 210.299286 -69.070311) (xy 210.324793 -69.063548) (xy 210.347714 -69.050471)
			(xy 210.366516 -69.031956) (xy 210.379943 -69.009239) (xy 210.387097 -68.983839) (xy 210.387692 -68.970652)
			(xy 210.388655 -68.9424) (xy 210.397887 -68.886631) (xy 210.415246 -68.832835) (xy 210.440353 -68.782188)
			(xy 210.472656 -68.7358) (xy 210.51145 -68.694686) (xy 210.555886 -68.659745) (xy 210.60499 -68.631742)
			(xy 210.657688 -68.611291) (xy 210.712827 -68.598838) (xy 210.7692 -68.594656) (xy 210.825573 -68.598838)
			(xy 210.880712 -68.611291) (xy 210.93341 -68.631742) (xy 210.982514 -68.659745) (xy 211.02695 -68.694686)
			(xy 211.065744 -68.7358) (xy 211.098047 -68.782188) (xy 211.123154 -68.832835) (xy 211.140513 -68.886631)
			(xy 211.149745 -68.9424) (xy 211.150708 -68.970652) (xy 211.151327 -68.983835) (xy 211.15848 -69.009229)
			(xy 211.171903 -69.031941) (xy 211.190701 -69.050452) (xy 211.213616 -69.063526) (xy 211.239117 -69.070287)
			(xy 211.252308 -69.070728) (xy 212.03793 -69.070728) (xy 212.051646 -69.041518) (xy 212.063513 -69.017201)
			(xy 212.09309 -68.971891) (xy 212.128773 -68.931215) (xy 212.169846 -68.89599) (xy 212.215484 -68.866923)
			(xy 212.264772 -68.844595) (xy 212.31672 -68.829457) (xy 212.370286 -68.821811) (xy 212.424394 -68.821811)
			(xy 212.47796 -68.829457) (xy 212.529908 -68.844595) (xy 212.579196 -68.866923) (xy 212.624834 -68.89599)
			(xy 212.665907 -68.931215) (xy 212.70159 -68.971891) (xy 212.731167 -69.017201) (xy 212.743034 -69.041518)
			(xy 212.75675 -69.070728) (xy 212.886798 -69.070728) (xy 212.900371 -69.047317) (xy 212.933107 -69.004229)
			(xy 212.971601 -68.966196) (xy 213.01508 -68.93398) (xy 213.062673 -68.908228) (xy 213.113427 -68.889456)
			(xy 213.166322 -68.87804) (xy 213.2203 -68.874209) (xy 213.274278 -68.87804) (xy 213.327173 -68.889456)
			(xy 213.377927 -68.908228) (xy 213.42552 -68.93398) (xy 213.468999 -68.966196) (xy 213.507493 -69.004229)
			(xy 213.540229 -69.047317) (xy 213.553802 -69.070728) (xy 215.466422 -69.070728) (xy 215.479711 -69.070295)
			(xy 215.505386 -69.063427) (xy 215.528418 -69.050164) (xy 215.547244 -69.031404) (xy 215.560589 -69.008419)
			(xy 215.567547 -68.982769) (xy 215.567647 -68.956191) (xy 215.56472 -68.94322) (xy 215.558874 -68.919456)
			(xy 215.55263 -68.870916) (xy 215.552274 -68.846446) (xy 215.55276 -68.819195) (xy 215.560516 -68.765247)
			(xy 215.575871 -68.712952) (xy 215.598513 -68.663375) (xy 215.627979 -68.617525) (xy 215.66367 -68.576334)
			(xy 215.704861 -68.540643) (xy 215.750711 -68.511177) (xy 215.800288 -68.488535) (xy 215.852583 -68.47318)
			(xy 215.906531 -68.465424) (xy 215.961033 -68.465424) (xy 216.014981 -68.47318) (xy 216.067276 -68.488535)
			(xy 216.116853 -68.511177) (xy 216.162703 -68.540643) (xy 216.203894 -68.576334) (xy 216.239585 -68.617525)
			(xy 216.269051 -68.663375) (xy 216.291693 -68.712952) (xy 216.307048 -68.765247) (xy 216.314804 -68.819195)
			(xy 216.31529 -68.846446) (xy 216.314894 -68.870913) (xy 216.308649 -68.919448) (xy 216.302844 -68.94322)
			(xy 216.299875 -68.956183) (xy 216.299974 -68.982767) (xy 216.306935 -69.008423) (xy 216.320287 -69.03141)
			(xy 216.339123 -69.050169) (xy 216.362165 -69.063426) (xy 216.38785 -69.070282) (xy 216.401142 -69.070728)
			(xy 220.135196 -69.070728) (xy 220.143832 -69.067426) (xy 220.17626 -69.056079) (xy 220.243851 -69.043815)
			(xy 220.278198 -69.043042) (xy 220.312551 -69.04375) (xy 220.38015 -69.056027) (xy 220.412564 -69.067426)
			(xy 220.4212 -69.070728) (xy 222.44304 -69.070728) (xy 222.9104 -68.603368) (xy 222.9104 -66.606928)
			(xy 222.54972 -66.246248) (xy 193.69024 -66.246248) (xy 192.913 -67.023488) (xy 192.913 -67.20332)
			(xy 210.356702 -67.20332) (xy 210.360773 -67.147698) (xy 210.372899 -67.093261) (xy 210.392822 -67.04117)
			(xy 210.420118 -66.992535) (xy 210.454204 -66.948392) (xy 210.494353 -66.909683) (xy 210.539711 -66.877232)
			(xy 210.589311 -66.851731) (xy 210.642095 -66.833724) (xy 210.696938 -66.823594) (xy 210.752672 -66.821557)
			(xy 210.808109 -66.827657) (xy 210.862066 -66.841763) (xy 210.913395 -66.863575) (xy 210.961001 -66.892629)
			(xy 211.003869 -66.928304) (xy 211.041086 -66.969841) (xy 211.071859 -67.016354) (xy 211.095531 -67.066851)
			(xy 211.111599 -67.120258) (xy 211.119719 -67.175434) (xy 211.120228 -67.20332) (xy 211.119719 -67.231206)
			(xy 211.111599 -67.286382) (xy 211.100137 -67.324478) (xy 216.490294 -67.324478) (xy 216.494365 -67.268856)
			(xy 216.506491 -67.214419) (xy 216.526414 -67.162328) (xy 216.55371 -67.113693) (xy 216.587796 -67.06955)
			(xy 216.627945 -67.030841) (xy 216.673303 -66.99839) (xy 216.722903 -66.972889) (xy 216.775687 -66.954882)
			(xy 216.83053 -66.944752) (xy 216.886264 -66.942715) (xy 216.941701 -66.948815) (xy 216.995658 -66.962921)
			(xy 217.046987 -66.984733) (xy 217.094593 -67.013787) (xy 217.137461 -67.049462) (xy 217.174678 -67.090999)
			(xy 217.205451 -67.137512) (xy 217.229123 -67.188009) (xy 217.245191 -67.241416) (xy 217.253311 -67.296592)
			(xy 217.25382 -67.324478) (xy 217.253311 -67.352364) (xy 217.245191 -67.40754) (xy 217.229123 -67.460947)
			(xy 217.205451 -67.511444) (xy 217.174678 -67.557957) (xy 217.137461 -67.599494) (xy 217.094593 -67.635169)
			(xy 217.046987 -67.664223) (xy 216.995658 -67.686035) (xy 216.941701 -67.700141) (xy 216.886264 -67.706241)
			(xy 216.83053 -67.704204) (xy 216.775687 -67.694074) (xy 216.722903 -67.676067) (xy 216.673303 -67.650566)
			(xy 216.627945 -67.618115) (xy 216.587796 -67.579406) (xy 216.55371 -67.535263) (xy 216.526414 -67.486628)
			(xy 216.506491 -67.434537) (xy 216.494365 -67.3801) (xy 216.490294 -67.324478) (xy 211.100137 -67.324478)
			(xy 211.095531 -67.339789) (xy 211.071859 -67.390286) (xy 211.041086 -67.436799) (xy 211.003869 -67.478336)
			(xy 210.961001 -67.514011) (xy 210.913395 -67.543065) (xy 210.862066 -67.564877) (xy 210.808109 -67.578983)
			(xy 210.752672 -67.585083) (xy 210.696938 -67.583046) (xy 210.642095 -67.572916) (xy 210.589311 -67.554909)
			(xy 210.539711 -67.529408) (xy 210.494353 -67.496957) (xy 210.454204 -67.458248) (xy 210.420118 -67.414105)
			(xy 210.392822 -67.36547) (xy 210.372899 -67.313379) (xy 210.360773 -67.258942) (xy 210.356702 -67.20332)
			(xy 192.913 -67.20332) (xy 192.913 -68.026788) (xy 199.042272 -68.026788) (xy 199.046343 -67.971166)
			(xy 199.058469 -67.916729) (xy 199.078392 -67.864638) (xy 199.105688 -67.816003) (xy 199.139774 -67.77186)
			(xy 199.179923 -67.733151) (xy 199.225281 -67.7007) (xy 199.274881 -67.675199) (xy 199.327665 -67.657192)
			(xy 199.382508 -67.647062) (xy 199.438242 -67.645025) (xy 199.493679 -67.651125) (xy 199.547636 -67.665231)
			(xy 199.598965 -67.687043) (xy 199.646571 -67.716097) (xy 199.689439 -67.751772) (xy 199.726656 -67.793309)
			(xy 199.757429 -67.839822) (xy 199.781101 -67.890319) (xy 199.797169 -67.943726) (xy 199.805289 -67.998902)
			(xy 199.805798 -68.026788) (xy 199.805436 -68.0466) (xy 205.053182 -68.0466) (xy 205.057253 -67.990978)
			(xy 205.069379 -67.936541) (xy 205.089302 -67.88445) (xy 205.116598 -67.835815) (xy 205.150684 -67.791672)
			(xy 205.190833 -67.752963) (xy 205.236191 -67.720512) (xy 205.285791 -67.695011) (xy 205.338575 -67.677004)
			(xy 205.393418 -67.666874) (xy 205.449152 -67.664837) (xy 205.504589 -67.670937) (xy 205.558546 -67.685043)
			(xy 205.609875 -67.706855) (xy 205.657481 -67.735909) (xy 205.700349 -67.771584) (xy 205.737566 -67.813121)
			(xy 205.768339 -67.859634) (xy 205.792011 -67.910131) (xy 205.808079 -67.963538) (xy 205.816199 -68.018714)
			(xy 205.816708 -68.0466) (xy 205.816199 -68.074486) (xy 205.808079 -68.129662) (xy 205.792011 -68.183069)
			(xy 205.768339 -68.233566) (xy 205.737566 -68.280079) (xy 205.700349 -68.321616) (xy 205.657481 -68.357291)
			(xy 205.609875 -68.386345) (xy 205.558546 -68.408157) (xy 205.504589 -68.422263) (xy 205.449152 -68.428363)
			(xy 205.393418 -68.426326) (xy 205.338575 -68.416196) (xy 205.285791 -68.398189) (xy 205.236191 -68.372688)
			(xy 205.190833 -68.340237) (xy 205.150684 -68.301528) (xy 205.116598 -68.257385) (xy 205.089302 -68.20875)
			(xy 205.069379 -68.156659) (xy 205.057253 -68.102222) (xy 205.053182 -68.0466) (xy 199.805436 -68.0466)
			(xy 199.805289 -68.054674) (xy 199.797169 -68.10985) (xy 199.781101 -68.163257) (xy 199.757429 -68.213754)
			(xy 199.726656 -68.260267) (xy 199.689439 -68.301804) (xy 199.646571 -68.337479) (xy 199.598965 -68.366533)
			(xy 199.547636 -68.388345) (xy 199.493679 -68.402451) (xy 199.438242 -68.408551) (xy 199.382508 -68.406514)
			(xy 199.327665 -68.396384) (xy 199.274881 -68.378377) (xy 199.225281 -68.352876) (xy 199.179923 -68.320425)
			(xy 199.139774 -68.281716) (xy 199.105688 -68.237573) (xy 199.078392 -68.188938) (xy 199.058469 -68.136847)
			(xy 199.046343 -68.08241) (xy 199.042272 -68.026788) (xy 192.913 -68.026788) (xy 192.913 -68.503292)
			(xy 206.348582 -68.503292) (xy 206.352653 -68.44767) (xy 206.364779 -68.393233) (xy 206.384702 -68.341142)
			(xy 206.411998 -68.292507) (xy 206.446084 -68.248364) (xy 206.486233 -68.209655) (xy 206.531591 -68.177204)
			(xy 206.581191 -68.151703) (xy 206.633975 -68.133696) (xy 206.688818 -68.123566) (xy 206.744552 -68.121529)
			(xy 206.799989 -68.127629) (xy 206.853946 -68.141735) (xy 206.905275 -68.163547) (xy 206.952881 -68.192601)
			(xy 206.995749 -68.228276) (xy 207.032966 -68.269813) (xy 207.03653 -68.2752) (xy 211.809582 -68.2752)
			(xy 211.813653 -68.219578) (xy 211.825779 -68.165141) (xy 211.845702 -68.11305) (xy 211.872998 -68.064415)
			(xy 211.907084 -68.020272) (xy 211.947233 -67.981563) (xy 211.992591 -67.949112) (xy 212.042191 -67.923611)
			(xy 212.094975 -67.905604) (xy 212.149818 -67.895474) (xy 212.205552 -67.893437) (xy 212.260989 -67.899537)
			(xy 212.314946 -67.913643) (xy 212.366275 -67.935455) (xy 212.413881 -67.964509) (xy 212.456749 -68.000184)
			(xy 212.493966 -68.041721) (xy 212.524739 -68.088234) (xy 212.548411 -68.138731) (xy 212.564479 -68.192138)
			(xy 212.572599 -68.247314) (xy 212.573108 -68.2752) (xy 212.572599 -68.303086) (xy 212.56762 -68.336922)
			(xy 216.490294 -68.336922) (xy 216.494365 -68.2813) (xy 216.506491 -68.226863) (xy 216.526414 -68.174772)
			(xy 216.55371 -68.126137) (xy 216.587796 -68.081994) (xy 216.627945 -68.043285) (xy 216.673303 -68.010834)
			(xy 216.722903 -67.985333) (xy 216.775687 -67.967326) (xy 216.83053 -67.957196) (xy 216.886264 -67.955159)
			(xy 216.941701 -67.961259) (xy 216.995658 -67.975365) (xy 217.046987 -67.997177) (xy 217.094593 -68.026231)
			(xy 217.137461 -68.061906) (xy 217.174678 -68.103443) (xy 217.197903 -68.138548) (xy 220.013782 -68.138548)
			(xy 220.017853 -68.082926) (xy 220.029979 -68.028489) (xy 220.049902 -67.976398) (xy 220.077198 -67.927763)
			(xy 220.111284 -67.88362) (xy 220.151433 -67.844911) (xy 220.196791 -67.81246) (xy 220.246391 -67.786959)
			(xy 220.299175 -67.768952) (xy 220.354018 -67.758822) (xy 220.409752 -67.756785) (xy 220.465189 -67.762885)
			(xy 220.519146 -67.776991) (xy 220.570475 -67.798803) (xy 220.618081 -67.827857) (xy 220.660949 -67.863532)
			(xy 220.698166 -67.905069) (xy 220.728939 -67.951582) (xy 220.752611 -68.002079) (xy 220.768679 -68.055486)
			(xy 220.776799 -68.110662) (xy 220.777308 -68.138548) (xy 220.776799 -68.166434) (xy 220.768679 -68.22161)
			(xy 220.752611 -68.275017) (xy 220.728939 -68.325514) (xy 220.698166 -68.372027) (xy 220.660949 -68.413564)
			(xy 220.618081 -68.449239) (xy 220.570475 -68.478293) (xy 220.519146 -68.500105) (xy 220.465189 -68.514211)
			(xy 220.409752 -68.520311) (xy 220.354018 -68.518274) (xy 220.299175 -68.508144) (xy 220.246391 -68.490137)
			(xy 220.196791 -68.464636) (xy 220.151433 -68.432185) (xy 220.111284 -68.393476) (xy 220.077198 -68.349333)
			(xy 220.049902 -68.300698) (xy 220.029979 -68.248607) (xy 220.017853 -68.19417) (xy 220.013782 -68.138548)
			(xy 217.197903 -68.138548) (xy 217.205451 -68.149956) (xy 217.229123 -68.200453) (xy 217.245191 -68.25386)
			(xy 217.253311 -68.309036) (xy 217.25382 -68.336922) (xy 217.253311 -68.364808) (xy 217.245191 -68.419984)
			(xy 217.229123 -68.473391) (xy 217.205451 -68.523888) (xy 217.174678 -68.570401) (xy 217.137461 -68.611938)
			(xy 217.094593 -68.647613) (xy 217.046987 -68.676667) (xy 216.995658 -68.698479) (xy 216.941701 -68.712585)
			(xy 216.886264 -68.718685) (xy 216.83053 -68.716648) (xy 216.775687 -68.706518) (xy 216.722903 -68.688511)
			(xy 216.673303 -68.66301) (xy 216.627945 -68.630559) (xy 216.587796 -68.59185) (xy 216.55371 -68.547707)
			(xy 216.526414 -68.499072) (xy 216.506491 -68.446981) (xy 216.494365 -68.392544) (xy 216.490294 -68.336922)
			(xy 212.56762 -68.336922) (xy 212.564479 -68.358262) (xy 212.548411 -68.411669) (xy 212.524739 -68.462166)
			(xy 212.493966 -68.508679) (xy 212.456749 -68.550216) (xy 212.413881 -68.585891) (xy 212.366275 -68.614945)
			(xy 212.314946 -68.636757) (xy 212.260989 -68.650863) (xy 212.205552 -68.656963) (xy 212.149818 -68.654926)
			(xy 212.094975 -68.644796) (xy 212.042191 -68.626789) (xy 211.992591 -68.601288) (xy 211.947233 -68.568837)
			(xy 211.907084 -68.530128) (xy 211.872998 -68.485985) (xy 211.845702 -68.43735) (xy 211.825779 -68.385259)
			(xy 211.813653 -68.330822) (xy 211.809582 -68.2752) (xy 207.03653 -68.2752) (xy 207.063739 -68.316326)
			(xy 207.087411 -68.366823) (xy 207.103479 -68.42023) (xy 207.111599 -68.475406) (xy 207.112108 -68.503292)
			(xy 207.111599 -68.531178) (xy 207.103479 -68.586354) (xy 207.087411 -68.639761) (xy 207.063739 -68.690258)
			(xy 207.032966 -68.736771) (xy 206.995749 -68.778308) (xy 206.952881 -68.813983) (xy 206.905275 -68.843037)
			(xy 206.853946 -68.864849) (xy 206.799989 -68.878955) (xy 206.744552 -68.885055) (xy 206.688818 -68.883018)
			(xy 206.633975 -68.872888) (xy 206.581191 -68.854881) (xy 206.531591 -68.82938) (xy 206.486233 -68.796929)
			(xy 206.446084 -68.75822) (xy 206.411998 -68.714077) (xy 206.384702 -68.665442) (xy 206.364779 -68.613351)
			(xy 206.352653 -68.558914) (xy 206.348582 -68.503292) (xy 192.913 -68.503292) (xy 192.913 -68.707508)
			(xy 193.27622 -69.070728)
		)
		(stroke
			(width 0)
			(type solid)
		)
		(fill yes)
		(layer "In6.Cu")
		(net "P3V3_E1S_0_R")
	)
	(gr_poly
		(pts
			(xy 225.6663 -399.06194) (xy 228.8032 -399.06194) (xy 230.43134 -400.69008) (xy 239.028732 -400.69008)
			(xy 239.395 -400.323812) (xy 239.395 -396.899892) (xy 239.584992 -396.7099) (xy 243.400072 -396.7099)
			(xy 243.6749 -396.435072)
			(arc
				(start 243.6749 -395.605762)
				(mid 243.180096 -394.808456)
				(end 243.6749 -394.01115)
			)
			(xy 243.6749 -392.739372) (xy 243.793772 -392.6205) (xy 245.6053 -392.6205) (xy 245.77548 -392.79068)
			(arc
				(start 245.77548 -394.032994)
				(mid 245.989778 -394.201485)
				(end 246.143018 -394.426948)
			)
			(arc
				(start 246.143018 -394.426948)
				(mid 246.383681 -394.536903)
				(end 246.482108 -394.782548)
			)
			(arc
				(start 246.482108 -394.782548)
				(mid 246.391785 -395.019553)
				(end 246.16664 -395.13637)
			)
			(arc
				(start 246.16664 -395.13637)
				(mid 246.034714 -395.36384)
				(end 245.842028 -395.54277)
			)
			(xy 245.842028 -395.724888) (xy 246.16664 -396.0495) (xy 249.34672 -396.0495) (xy 249.5931 -395.80312)
			(arc
				(start 249.5931 -395.597126)
				(mid 249.11502 -394.808456)
				(end 249.5931 -394.019786)
			)
			(xy 249.5931 -392.764772) (xy 249.711972 -392.6459) (xy 251.5489 -392.6459) (xy 251.72416 -392.82116)
			(arc
				(start 251.72416 -394.040868)
				(mid 251.930047 -394.20706)
				(end 252.077982 -394.42644)
			)
			(arc
				(start 252.086364 -394.42644)
				(mid 252.33817 -394.530742)
				(end 252.442472 -394.782548)
			)
			(arc
				(start 252.442472 -394.782548)
				(mid 252.343238 -395.029183)
				(end 252.100842 -395.138402)
			)
			(arc
				(start 252.100842 -395.138402)
				(mid 251.980942 -395.349405)
				(end 251.808488 -395.520164)
			)
			(xy 251.808488 -395.920468) (xy 251.93498 -396.04696) (xy 255.29032 -396.04696) (xy 255.41986 -395.91742)
			(arc
				(start 255.41986 -395.530578)
				(mid 255.147839 -395.214133)
				(end 255.050036 -394.808456)
			)
			(arc
				(start 255.050036 -394.808456)
				(mid 255.147809 -394.402764)
				(end 255.41986 -394.086334)
			)
			(xy 255.41986 -392.78814) (xy 255.5367 -392.6713) (xy 257.5179 -392.6713) (xy 257.63982 -392.79322)
			(arc
				(start 257.63982 -394.029692)
				(mid 257.858887 -394.200372)
				(end 258.014724 -394.43025)
			)
			(arc
				(start 258.014724 -394.43025)
				(mid 258.040435 -394.4274)
				(end 258.066286 -394.42644)
			)
			(arc
				(start 258.067048 -394.42644)
				(mid 258.423156 -394.782548)
				(end 258.067048 -395.138656)
			)
			(arc
				(start 258.03606 -395.137386)
				(mid 257.90595 -395.361998)
				(end 257.716528 -395.539468)
			)
			(xy 257.716528 -395.785848) (xy 258.02336 -396.09268) (xy 261.17804 -396.09268) (xy 261.4803 -395.79042)
			(arc
				(start 261.4803 -395.606016)
				(mid 260.984985 -394.808456)
				(end 261.4803 -394.010896)
			)
			(xy 261.4803 -392.688572) (xy 261.522972 -392.6459) (xy 263.393428 -392.6459) (xy 263.54786 -392.800332)
			(arc
				(start 263.54786 -394.015468)
				(mid 263.782481 -394.188461)
				(end 263.948672 -394.427964)
			)
			(xy 263.981438 -394.42644)
			(arc
				(start 263.981692 -394.42644)
				(mid 264.3378 -394.782548)
				(end 263.981692 -395.138656)
			)
			(arc
				(start 263.970516 -395.138402)
				(mid 263.841889 -395.360819)
				(end 263.655048 -395.537182)
			)
			(xy 263.655048 -395.976348) (xy 263.7917 -396.113) (xy 267.18768 -396.113) (xy 267.31976 -395.98092)
			(arc
				(start 267.31976 -395.551152)
				(mid 266.919971 -394.808456)
				(end 267.31976 -394.06576)
			)
			(xy 267.31976 -392.75004) (xy 267.4239 -392.6459) (xy 269.362428 -392.6459) (xy 269.49654 -392.780012)
			(arc
				(start 269.49654 -394.02258)
				(mid 269.722424 -394.193603)
				(end 269.883128 -394.426948)
			)
			(arc
				(start 269.883128 -394.426948)
				(mid 270.123634 -394.536987)
				(end 270.221964 -394.782548)
			)
			(arc
				(start 270.221964 -394.782548)
				(mid 270.131557 -395.019647)
				(end 269.906242 -395.13637)
			)
			(arc
				(start 269.906242 -395.13637)
				(mid 269.784619 -395.350744)
				(end 269.608808 -395.523466)
			)
			(xy 269.608808 -395.96949) (xy 269.835884 -396.19682) (xy 273.1389 -396.19682) (xy 273.23796 -396.09776)
			(arc
				(start 273.23796 -395.539722)
				(mid 272.854904 -394.808456)
				(end 273.23796 -394.07719)
			)
			(xy 273.23796 -392.72464) (xy 273.3167 -392.6459) (xy 275.2979 -392.6459) (xy 275.2979 -392.64844)
			(xy 275.41474 -392.76528)
			(arc
				(start 275.41474 -394.013944)
				(mid 275.650676 -394.186875)
				(end 275.817838 -394.426948)
			)
			(arc
				(start 275.817838 -394.426948)
				(mid 276.058501 -394.536903)
				(end 276.156928 -394.782548)
			)
			(arc
				(start 276.156928 -394.782548)
				(mid 276.066605 -395.019553)
				(end 275.84146 -395.13637)
			)
			(arc
				(start 275.84146 -395.13637)
				(mid 275.698945 -395.376738)
				(end 275.488908 -395.561058)
			)
			(xy 275.488908 -395.89583) (xy 275.779484 -396.18666) (xy 279.10282 -396.18666) (xy 279.2603 -396.02918)
			(arc
				(start 279.2603 -395.510766)
				(mid 278.916855 -394.808456)
				(end 279.2603 -394.106146)
			)
			(xy 279.2603 -387.64464) (xy 278.99106 -387.3754) (xy 266.95654 -387.3754) (xy 265.044936 -385.463796)
			(arc
				(start 238.995966 -387.647942)
				(mid 238.915204 -387.705538)
				(end 238.922052 -387.804406)
			)
			(arc
				(start 238.922052 -387.804406)
				(mid 238.968213 -387.904164)
				(end 238.984028 -388.01294)
			)
			(arc
				(start 238.984028 -388.01294)
				(mid 238.872287 -388.282707)
				(end 238.60252 -388.394448)
			)
			(arc
				(start 238.60252 -388.394448)
				(mid 238.468658 -388.370175)
				(end 238.351822 -388.300468)
			)
			(arc
				(start 238.351822 -388.300468)
				(mid 238.28502 -388.275458)
				(end 238.218218 -388.300468)
			)
			(arc
				(start 238.218218 -388.300468)
				(mid 237.96752 -388.394476)
				(end 237.716822 -388.300468)
			)
			(arc
				(start 237.716822 -388.300468)
				(mid 237.65002 -388.275458)
				(end 237.583218 -388.300468)
			)
			(arc
				(start 237.583218 -388.300468)
				(mid 237.33252 -388.394476)
				(end 237.081822 -388.300468)
			)
			(arc
				(start 237.081822 -388.300468)
				(mid 237.01502 -388.275458)
				(end 236.948218 -388.300468)
			)
			(arc
				(start 236.948218 -388.300468)
				(mid 236.69752 -388.394476)
				(end 236.446822 -388.300468)
			)
			(arc
				(start 236.446822 -388.300468)
				(mid 236.38002 -388.275458)
				(end 236.313218 -388.300468)
			)
			(arc
				(start 236.313218 -388.300468)
				(mid 236.06252 -388.394476)
				(end 235.811822 -388.300468)
			)
			(arc
				(start 235.811822 -388.300468)
				(mid 235.74502 -388.275458)
				(end 235.678218 -388.300468)
			)
			(arc
				(start 235.678218 -388.300468)
				(mid 235.42752 -388.394476)
				(end 235.176822 -388.300468)
			)
			(arc
				(start 235.176822 -388.300468)
				(mid 235.11002 -388.275458)
				(end 235.043218 -388.300468)
			)
			(arc
				(start 235.043218 -388.300468)
				(mid 234.79252 -388.394476)
				(end 234.541822 -388.300468)
			)
			(arc
				(start 234.541822 -388.300468)
				(mid 234.47502 -388.275458)
				(end 234.408218 -388.300468)
			)
			(arc
				(start 234.408218 -388.300468)
				(mid 234.291392 -388.370201)
				(end 234.15752 -388.394448)
			)
			(arc
				(start 234.15752 -388.394448)
				(mid 233.933147 -388.321493)
				(end 233.794554 -388.130542)
			)
			(xy 233.782108 -388.092188) (xy 185.84291 -392.15695) (xy 185.23712 -392.76274) (xy 185.23712 -397.0655)
			(xy 185.93562 -397.764) (xy 185.93562 -400.44624) (xy 186.15914 -400.66976) (xy 192.07226 -400.66976)
			(xy 194.36334 -398.37868) (xy 196.61632 -398.37868) (xy 198.92772 -400.69008) (xy 202.65898 -400.69008)
			(xy 204.37856 -398.9705) (xy 207.32242 -398.9705) (xy 209.03184 -400.67992) (xy 213.30666 -400.67992)
			(xy 215.1253 -398.86128) (xy 217.97518 -398.86128) (xy 219.83954 -400.72564) (xy 224.0026 -400.72564)
		)
		(stroke
			(width 0)
			(type solid)
		)
		(fill yes)
		(layer "In6.Cu")
		(net "P12V_AUX")
	)
	(gr_poly
		(pts
			(xy 71.86168 -160.251648) (xy 72.40905 -160.251648) (xy 72.41032 -160.210246) (xy 72.410944 -160.18309)
			(xy 72.418934 -160.129362) (xy 72.434465 -160.07731) (xy 72.457221 -160.027988) (xy 72.486743 -159.982392)
			(xy 72.522433 -159.941444) (xy 72.56357 -159.905972) (xy 72.609323 -159.876694) (xy 72.658766 -159.854201)
			(xy 72.710899 -159.838948) (xy 72.764669 -159.831244) (xy 72.818987 -159.831244) (xy 72.872757 -159.838948)
			(xy 72.92489 -159.854201) (xy 72.974333 -159.876694) (xy 73.020086 -159.905972) (xy 73.061223 -159.941444)
			(xy 73.096913 -159.982392) (xy 73.126435 -160.027988) (xy 73.149191 -160.07731) (xy 73.164722 -160.129362)
			(xy 73.172712 -160.18309) (xy 73.173336 -160.210246) (xy 73.174606 -160.251648) (xy 73.64476 -160.251648)
			(xy 75.95108 -157.945328) (xy 75.95108 -149.780752) (xy 75.950623 -149.766929) (xy 75.94321 -149.740297)
			(xy 75.928916 -149.716635) (xy 75.90879 -149.697683) (xy 75.884313 -149.684834) (xy 75.857284 -149.679033)
			(xy 75.82969 -149.680706) (xy 75.81646 -149.68474) (xy 75.81265 -149.68601) (xy 75.783334 -149.695169)
			(xy 75.722708 -149.704994) (xy 75.692 -149.705568) (xy 75.68819 -149.705568) (xy 75.661118 -149.704824)
			(xy 75.607584 -149.696629) (xy 75.555747 -149.680946) (xy 75.50665 -149.65809) (xy 75.461278 -149.62852)
			(xy 75.420544 -149.59283) (xy 75.385267 -149.551738) (xy 75.356156 -149.50607) (xy 75.333797 -149.456745)
			(xy 75.318638 -149.404752) (xy 75.310984 -149.351139) (xy 75.310492 -149.32406) (xy 75.310981 -149.296811)
			(xy 75.318742 -149.242867) (xy 75.3341 -149.190577) (xy 75.356744 -149.141005) (xy 75.386211 -149.09516)
			(xy 75.421903 -149.053974) (xy 75.463092 -149.018287) (xy 75.50894 -148.988824) (xy 75.558515 -148.966186)
			(xy 75.610806 -148.950833) (xy 75.664751 -148.943078) (xy 75.692 -148.942552) (xy 75.722704 -148.943171)
			(xy 75.78332 -148.953005) (xy 75.81265 -148.96211) (xy 75.81646 -148.96338) (xy 75.82968 -148.967437)
			(xy 75.857273 -148.969083) (xy 75.884295 -148.963266) (xy 75.908767 -148.950413) (xy 75.928892 -148.931465)
			(xy 75.943197 -148.907812) (xy 75.95063 -148.881189) (xy 75.95108 -148.867368) (xy 75.95108 -145.216118)
			(xy 75.912472 -145.17751) (xy 75.153774 -145.17751) (xy 75.123346 -145.20589) (xy 75.057346 -145.256566)
			(xy 74.986221 -145.299754) (xy 74.910815 -145.334938) (xy 74.832025 -145.361702) (xy 74.75079 -145.379725)
			(xy 74.668075 -145.388795) (xy 74.62647 -145.389346) (xy 74.586536 -145.388822) (xy 74.507107 -145.380471)
			(xy 74.428985 -145.363863) (xy 74.353027 -145.339181) (xy 74.280065 -145.306695) (xy 74.210899 -145.266761)
			(xy 74.146285 -145.219816) (xy 74.086932 -145.166374) (xy 74.033489 -145.107022) (xy 73.986544 -145.042408)
			(xy 73.946609 -144.973242) (xy 73.914122 -144.90028) (xy 73.889439 -144.824323) (xy 73.872831 -144.746201)
			(xy 73.864479 -144.666772) (xy 73.863962 -144.626838) (xy 73.864431 -144.588575) (xy 73.872097 -144.512433)
			(xy 73.887355 -144.437442) (xy 73.910052 -144.364359) (xy 73.939959 -144.293918) (xy 73.976775 -144.226828)
			(xy 73.998074 -144.195038) (xy 73.976787 -144.16324) (xy 73.939974 -144.096151) (xy 73.910069 -144.025711)
			(xy 73.887371 -143.952629) (xy 73.87211 -143.877641) (xy 73.864439 -143.801501) (xy 73.863962 -143.763238)
			(xy 73.864451 -143.724593) (xy 73.872271 -143.647699) (xy 73.887829 -143.571991) (xy 73.910967 -143.498245)
			(xy 73.941447 -143.427218) (xy 73.978956 -143.35964) (xy 74.02311 -143.296202) (xy 74.073455 -143.237558)
			(xy 74.129474 -143.184307) (xy 74.190593 -143.136997) (xy 74.256186 -143.096113) (xy 74.325577 -143.062075)
			(xy 74.398057 -143.035232) (xy 74.47288 -143.015859) (xy 74.549279 -143.004155) (xy 74.62647 -143.00024)
			(xy 74.703661 -143.004155) (xy 74.78006 -143.015859) (xy 74.854883 -143.035232) (xy 74.927363 -143.062075)
			(xy 74.996754 -143.096113) (xy 75.062347 -143.136997) (xy 75.123466 -143.184307) (xy 75.179485 -143.237558)
			(xy 75.22983 -143.296202) (xy 75.273984 -143.35964) (xy 75.311493 -143.427218) (xy 75.341973 -143.498245)
			(xy 75.365111 -143.571991) (xy 75.380669 -143.647699) (xy 75.388489 -143.724593) (xy 75.388978 -143.763238)
			(xy 75.38836 -143.806454) (xy 75.378566 -143.89233) (xy 75.359141 -143.976551) (xy 75.34529 -144.017492)
			(xy 75.341115 -144.030737) (xy 75.339272 -144.058435) (xy 75.34496 -144.085605) (xy 75.357757 -144.110239)
			(xy 75.376718 -144.130513) (xy 75.40044 -144.14493) (xy 75.427169 -144.152422) (xy 75.441048 -144.152874)
			(xy 75.912472 -144.152874) (xy 75.95108 -144.114266) (xy 75.95108 -142.514828) (xy 75.5142 -142.077948)
			(xy 63.3222 -142.077948) (xy 63.123572 -142.276576) (xy 63.123572 -144.665192) (xy 71.87641 -144.665192)
			(xy 71.880481 -144.60957) (xy 71.892607 -144.555133) (xy 71.91253 -144.503042) (xy 71.939826 -144.454407)
			(xy 71.973912 -144.410264) (xy 72.014061 -144.371555) (xy 72.059419 -144.339104) (xy 72.109019 -144.313603)
			(xy 72.161803 -144.295596) (xy 72.216646 -144.285466) (xy 72.27238 -144.283429) (xy 72.327817 -144.289529)
			(xy 72.381774 -144.303635) (xy 72.433103 -144.325447) (xy 72.480709 -144.354501) (xy 72.523577 -144.390176)
			(xy 72.560794 -144.431713) (xy 72.591567 -144.478226) (xy 72.615239 -144.528723) (xy 72.631307 -144.58213)
			(xy 72.639427 -144.637306) (xy 72.639936 -144.665192) (xy 72.639427 -144.693078) (xy 72.631307 -144.748254)
			(xy 72.615239 -144.801661) (xy 72.591567 -144.852158) (xy 72.560794 -144.898671) (xy 72.523577 -144.940208)
			(xy 72.480709 -144.975883) (xy 72.433103 -145.004937) (xy 72.381774 -145.026749) (xy 72.327817 -145.040855)
			(xy 72.27238 -145.046955) (xy 72.216646 -145.044918) (xy 72.161803 -145.034788) (xy 72.109019 -145.016781)
			(xy 72.059419 -144.99128) (xy 72.014061 -144.958829) (xy 71.973912 -144.92012) (xy 71.939826 -144.875977)
			(xy 71.91253 -144.827342) (xy 71.892607 -144.775251) (xy 71.880481 -144.720814) (xy 71.87641 -144.665192)
			(xy 63.123572 -144.665192) (xy 63.123572 -146.228308) (xy 69.007995 -146.228308) (xy 69.012017 -146.142588)
			(xy 69.024048 -146.05762) (xy 69.043984 -145.974153) (xy 69.071647 -145.892919) (xy 69.106796 -145.814633)
			(xy 69.149122 -145.739982) (xy 69.198251 -145.669623) (xy 69.253754 -145.604173) (xy 69.315141 -145.544209)
			(xy 69.381874 -145.490256) (xy 69.453366 -145.442789) (xy 69.528988 -145.402225) (xy 69.608077 -145.368921)
			(xy 69.689937 -145.343169) (xy 69.773848 -145.325196) (xy 69.859074 -145.31516) (xy 69.944866 -145.313148)
			(xy 70.030468 -145.319179) (xy 70.11513 -145.333199) (xy 70.198107 -145.355085) (xy 70.27867 -145.384646)
			(xy 70.35611 -145.42162) (xy 70.429749 -145.465684) (xy 70.498937 -145.51645) (xy 70.563068 -145.573471)
			(xy 70.621577 -145.636247) (xy 70.67395 -145.704227) (xy 70.719728 -145.776812) (xy 70.758508 -145.853364)
			(xy 70.789949 -145.933212) (xy 70.813775 -146.015653) (xy 70.829776 -146.099963) (xy 70.837811 -146.185401)
			(xy 70.838314 -146.228308) (xy 70.837811 -146.271215) (xy 70.829776 -146.356653) (xy 70.813775 -146.440963)
			(xy 70.789949 -146.523404) (xy 70.758508 -146.603252) (xy 70.719728 -146.679804) (xy 70.67395 -146.752389)
			(xy 70.621577 -146.820369) (xy 70.563068 -146.883145) (xy 70.498937 -146.940166) (xy 70.429749 -146.990932)
			(xy 70.35611 -147.034996) (xy 70.27867 -147.07197) (xy 70.198107 -147.101531) (xy 70.11513 -147.123417)
			(xy 70.030468 -147.137437) (xy 69.944866 -147.143468) (xy 69.859074 -147.141456) (xy 69.773848 -147.13142)
			(xy 69.689937 -147.113447) (xy 69.608077 -147.087695) (xy 69.528988 -147.054391) (xy 69.453366 -147.013827)
			(xy 69.381874 -146.96636) (xy 69.315141 -146.912407) (xy 69.253754 -146.852443) (xy 69.198251 -146.786993)
			(xy 69.149122 -146.716634) (xy 69.106796 -146.641983) (xy 69.071647 -146.563697) (xy 69.043984 -146.482463)
			(xy 69.024048 -146.398996) (xy 69.012017 -146.314028) (xy 69.007995 -146.228308) (xy 63.123572 -146.228308)
			(xy 63.123572 -148.270652) (xy 69.034402 -148.270652) (xy 69.034402 -148.185956) (xy 69.042453 -148.101642)
			(xy 69.058482 -148.018476) (xy 69.082343 -147.937209) (xy 69.113822 -147.858579) (xy 69.152633 -147.783298)
			(xy 69.198423 -147.712046) (xy 69.250779 -147.64547) (xy 69.309227 -147.584172) (xy 69.373237 -147.528707)
			(xy 69.442229 -147.479578) (xy 69.515579 -147.437229) (xy 69.592622 -147.402045) (xy 69.672661 -147.374343)
			(xy 69.75497 -147.354375) (xy 69.838805 -147.342322) (xy 69.923406 -147.338292) (xy 70.008007 -147.342322)
			(xy 70.091842 -147.354375) (xy 70.174151 -147.374343) (xy 70.25419 -147.402045) (xy 70.331233 -147.437229)
			(xy 70.404583 -147.479578) (xy 70.473575 -147.528707) (xy 70.537585 -147.584172) (xy 70.596033 -147.64547)
			(xy 70.648389 -147.712046) (xy 70.694179 -147.783298) (xy 70.73299 -147.858579) (xy 70.764469 -147.937209)
			(xy 70.78833 -148.018476) (xy 70.804359 -148.101642) (xy 70.81241 -148.185956) (xy 70.812914 -148.228304)
			(xy 70.81241 -148.270652) (xy 70.804359 -148.354966) (xy 70.78833 -148.438132) (xy 70.764469 -148.519399)
			(xy 70.73299 -148.598029) (xy 70.694179 -148.67331) (xy 70.648389 -148.744562) (xy 70.596033 -148.811138)
			(xy 70.537585 -148.872436) (xy 70.473575 -148.927901) (xy 70.404583 -148.97703) (xy 70.331233 -149.019379)
			(xy 70.25419 -149.054563) (xy 70.174151 -149.082265) (xy 70.091842 -149.102233) (xy 70.008007 -149.114286)
			(xy 69.923406 -149.118317) (xy 69.838805 -149.114286) (xy 69.75497 -149.102233) (xy 69.672661 -149.082265)
			(xy 69.592622 -149.054563) (xy 69.515579 -149.019379) (xy 69.442229 -148.97703) (xy 69.373237 -148.927901)
			(xy 69.309227 -148.872436) (xy 69.250779 -148.811138) (xy 69.198423 -148.744562) (xy 69.152633 -148.67331)
			(xy 69.113822 -148.598029) (xy 69.082343 -148.519399) (xy 69.058482 -148.438132) (xy 69.042453 -148.354966)
			(xy 69.034402 -148.270652) (xy 63.123572 -148.270652) (xy 63.123572 -152.364694) (xy 69.007995 -152.364694)
			(xy 69.012017 -152.278974) (xy 69.024048 -152.194006) (xy 69.043984 -152.110539) (xy 69.071647 -152.029305)
			(xy 69.106796 -151.951019) (xy 69.149122 -151.876368) (xy 69.198251 -151.806009) (xy 69.253754 -151.740559)
			(xy 69.315141 -151.680595) (xy 69.381874 -151.626642) (xy 69.453366 -151.579175) (xy 69.528988 -151.538611)
			(xy 69.608077 -151.505307) (xy 69.689937 -151.479555) (xy 69.773848 -151.461582) (xy 69.859074 -151.451546)
			(xy 69.944866 -151.449534) (xy 70.030468 -151.455565) (xy 70.11513 -151.469585) (xy 70.198107 -151.491471)
			(xy 70.27867 -151.521032) (xy 70.35611 -151.558006) (xy 70.429749 -151.60207) (xy 70.498937 -151.652836)
			(xy 70.563068 -151.709857) (xy 70.621577 -151.772633) (xy 70.67395 -151.840613) (xy 70.719728 -151.913198)
			(xy 70.758508 -151.98975) (xy 70.789949 -152.069598) (xy 70.813775 -152.152039) (xy 70.829776 -152.236349)
			(xy 70.837811 -152.321787) (xy 70.838314 -152.364694) (xy 70.837811 -152.407601) (xy 70.829776 -152.493039)
			(xy 70.813775 -152.577349) (xy 70.789949 -152.65979) (xy 70.758508 -152.739638) (xy 70.719728 -152.81619)
			(xy 70.67395 -152.888775) (xy 70.621577 -152.956755) (xy 70.563068 -153.019531) (xy 70.498937 -153.076552)
			(xy 70.429749 -153.127318) (xy 70.35611 -153.171382) (xy 70.27867 -153.208356) (xy 70.198107 -153.237917)
			(xy 70.11513 -153.259803) (xy 70.030468 -153.273823) (xy 69.944866 -153.279854) (xy 69.859074 -153.277842)
			(xy 69.773848 -153.267806) (xy 69.689937 -153.249833) (xy 69.608077 -153.224081) (xy 69.528988 -153.190777)
			(xy 69.453366 -153.150213) (xy 69.381874 -153.102746) (xy 69.315141 -153.048793) (xy 69.253754 -152.988829)
			(xy 69.198251 -152.923379) (xy 69.149122 -152.85302) (xy 69.106796 -152.778369) (xy 69.071647 -152.700083)
			(xy 69.043984 -152.618849) (xy 69.024048 -152.535382) (xy 69.012017 -152.450414) (xy 69.007995 -152.364694)
			(xy 63.123572 -152.364694) (xy 63.123572 -154.407038) (xy 69.034402 -154.407038) (xy 69.034402 -154.322342)
			(xy 69.042453 -154.238028) (xy 69.058482 -154.154862) (xy 69.082343 -154.073595) (xy 69.113822 -153.994965)
			(xy 69.152633 -153.919684) (xy 69.198423 -153.848432) (xy 69.250779 -153.781856) (xy 69.309227 -153.720558)
			(xy 69.373237 -153.665093) (xy 69.442229 -153.615964) (xy 69.515579 -153.573615) (xy 69.592622 -153.538431)
			(xy 69.672661 -153.510729) (xy 69.75497 -153.490761) (xy 69.838805 -153.478708) (xy 69.923406 -153.474678)
			(xy 70.008007 -153.478708) (xy 70.091842 -153.490761) (xy 70.174151 -153.510729) (xy 70.25419 -153.538431)
			(xy 70.331233 -153.573615) (xy 70.404583 -153.615964) (xy 70.473575 -153.665093) (xy 70.537585 -153.720558)
			(xy 70.596033 -153.781856) (xy 70.648389 -153.848432) (xy 70.694179 -153.919684) (xy 70.73299 -153.994965)
			(xy 70.764469 -154.073595) (xy 70.78833 -154.154862) (xy 70.804359 -154.238028) (xy 70.81241 -154.322342)
			(xy 70.812914 -154.36469) (xy 70.81241 -154.407038) (xy 70.804359 -154.491352) (xy 70.78833 -154.574518)
			(xy 70.764469 -154.655785) (xy 70.73299 -154.734415) (xy 70.694179 -154.809696) (xy 70.648389 -154.880948)
			(xy 70.596033 -154.947524) (xy 70.537585 -155.008822) (xy 70.473575 -155.064287) (xy 70.404583 -155.113416)
			(xy 70.331233 -155.155765) (xy 70.25419 -155.190949) (xy 70.174151 -155.218651) (xy 70.091842 -155.238619)
			(xy 70.008007 -155.250672) (xy 69.923406 -155.254703) (xy 69.838805 -155.250672) (xy 69.75497 -155.238619)
			(xy 69.672661 -155.218651) (xy 69.592622 -155.190949) (xy 69.515579 -155.155765) (xy 69.442229 -155.113416)
			(xy 69.373237 -155.064287) (xy 69.309227 -155.008822) (xy 69.250779 -154.947524) (xy 69.198423 -154.880948)
			(xy 69.152633 -154.809696) (xy 69.113822 -154.734415) (xy 69.082343 -154.655785) (xy 69.058482 -154.574518)
			(xy 69.042453 -154.491352) (xy 69.034402 -154.407038) (xy 63.123572 -154.407038) (xy 63.123572 -158.49981)
			(xy 69.007995 -158.49981) (xy 69.012017 -158.41409) (xy 69.024048 -158.329122) (xy 69.043984 -158.245655)
			(xy 69.071647 -158.164421) (xy 69.106796 -158.086135) (xy 69.149122 -158.011484) (xy 69.198251 -157.941125)
			(xy 69.253754 -157.875675) (xy 69.315141 -157.815711) (xy 69.381874 -157.761758) (xy 69.453366 -157.714291)
			(xy 69.528988 -157.673727) (xy 69.608077 -157.640423) (xy 69.689937 -157.614671) (xy 69.773848 -157.596698)
			(xy 69.859074 -157.586662) (xy 69.944866 -157.58465) (xy 70.030468 -157.590681) (xy 70.11513 -157.604701)
			(xy 70.198107 -157.626587) (xy 70.27867 -157.656148) (xy 70.35611 -157.693122) (xy 70.429749 -157.737186)
			(xy 70.498937 -157.787952) (xy 70.563068 -157.844973) (xy 70.621577 -157.907749) (xy 70.67395 -157.975729)
			(xy 70.719728 -158.048314) (xy 70.758508 -158.124866) (xy 70.789949 -158.204714) (xy 70.813775 -158.287155)
			(xy 70.829776 -158.371465) (xy 70.837811 -158.456903) (xy 70.838314 -158.49981) (xy 70.837811 -158.542717)
			(xy 70.829776 -158.628155) (xy 70.813775 -158.712465) (xy 70.789949 -158.794906) (xy 70.758508 -158.874754)
			(xy 70.719728 -158.951306) (xy 70.67395 -159.023891) (xy 70.621577 -159.091871) (xy 70.563068 -159.154647)
			(xy 70.498937 -159.211668) (xy 70.429749 -159.262434) (xy 70.35611 -159.306498) (xy 70.27867 -159.343472)
			(xy 70.198107 -159.373033) (xy 70.11513 -159.394919) (xy 70.030468 -159.408939) (xy 69.944866 -159.41497)
			(xy 69.859074 -159.412958) (xy 69.773848 -159.402922) (xy 69.689937 -159.384949) (xy 69.608077 -159.359197)
			(xy 69.528988 -159.325893) (xy 69.453366 -159.285329) (xy 69.381874 -159.237862) (xy 69.315141 -159.183909)
			(xy 69.253754 -159.123945) (xy 69.198251 -159.058495) (xy 69.149122 -158.988136) (xy 69.106796 -158.913485)
			(xy 69.071647 -158.835199) (xy 69.043984 -158.753965) (xy 69.024048 -158.670498) (xy 69.012017 -158.58553)
			(xy 69.007995 -158.49981) (xy 63.123572 -158.49981) (xy 63.123572 -160.542154) (xy 69.034402 -160.542154)
			(xy 69.034402 -160.457458) (xy 69.042453 -160.373144) (xy 69.058482 -160.289978) (xy 69.082343 -160.208711)
			(xy 69.113822 -160.130081) (xy 69.152633 -160.0548) (xy 69.198423 -159.983548) (xy 69.250779 -159.916972)
			(xy 69.309227 -159.855674) (xy 69.373237 -159.800209) (xy 69.442229 -159.75108) (xy 69.515579 -159.708731)
			(xy 69.592622 -159.673547) (xy 69.672661 -159.645845) (xy 69.75497 -159.625877) (xy 69.838805 -159.613824)
			(xy 69.923406 -159.609794) (xy 70.008007 -159.613824) (xy 70.091842 -159.625877) (xy 70.174151 -159.645845)
			(xy 70.25419 -159.673547) (xy 70.331233 -159.708731) (xy 70.404583 -159.75108) (xy 70.473575 -159.800209)
			(xy 70.537585 -159.855674) (xy 70.596033 -159.916972) (xy 70.648389 -159.983548) (xy 70.694179 -160.0548)
			(xy 70.73299 -160.130081) (xy 70.764469 -160.208711) (xy 70.78833 -160.289978) (xy 70.804359 -160.373144)
			(xy 70.81241 -160.457458) (xy 70.812914 -160.499806) (xy 70.81241 -160.542154) (xy 70.804359 -160.626468)
			(xy 70.78833 -160.709634) (xy 70.764469 -160.790901) (xy 70.73299 -160.869531) (xy 70.694179 -160.944812)
			(xy 70.648389 -161.016064) (xy 70.596033 -161.08264) (xy 70.537585 -161.143938) (xy 70.473575 -161.199403)
			(xy 70.404583 -161.248532) (xy 70.331233 -161.290881) (xy 70.25419 -161.326065) (xy 70.174151 -161.353767)
			(xy 70.091842 -161.373735) (xy 70.008007 -161.385788) (xy 69.923406 -161.389819) (xy 69.838805 -161.385788)
			(xy 69.75497 -161.373735) (xy 69.672661 -161.353767) (xy 69.592622 -161.326065) (xy 69.515579 -161.290881)
			(xy 69.442229 -161.248532) (xy 69.373237 -161.199403) (xy 69.309227 -161.143938) (xy 69.250779 -161.08264)
			(xy 69.198423 -161.016064) (xy 69.152633 -160.944812) (xy 69.113822 -160.869531) (xy 69.082343 -160.790901)
			(xy 69.058482 -160.709634) (xy 69.042453 -160.626468) (xy 69.034402 -160.542154) (xy 63.123572 -160.542154)
			(xy 63.123572 -160.549844) (xy 63.284608 -160.71088) (xy 68.465192 -160.71088) (xy 69.3674 -161.613088)
			(xy 70.50024 -161.613088)
		)
		(stroke
			(width 0)
			(type solid)
		)
		(fill yes)
		(layer "In6.Cu")
		(net "PVCCINFAON_CPU1")
	)
	(gr_poly
		(pts
			(xy 255.443482 -107.737148) (xy 255.457333 -107.736724) (xy 255.484035 -107.729357) (xy 255.507771 -107.71508)
			(xy 255.526792 -107.694944) (xy 255.539695 -107.670434) (xy 255.545531 -107.643356) (xy 255.543868 -107.615707)
			(xy 255.534829 -107.589523) (xy 255.527302 -107.57789) (xy 255.51136 -107.553875) (xy 255.486119 -107.502057)
			(xy 255.468964 -107.44703) (xy 255.460285 -107.390048) (xy 255.459738 -107.361228) (xy 255.460199 -107.333975)
			(xy 255.467953 -107.280024) (xy 255.483308 -107.227725) (xy 255.505949 -107.178144) (xy 255.535417 -107.132291)
			(xy 255.571111 -107.091099) (xy 255.612305 -107.055406) (xy 255.65816 -107.02594) (xy 255.707742 -107.003301)
			(xy 255.760041 -106.98795) (xy 255.813993 -106.980198) (xy 255.841246 -106.97972) (xy 255.851152 -106.979974)
			(xy 255.866081 -106.979858) (xy 255.894873 -106.972021) (xy 255.920178 -106.956207) (xy 255.939843 -106.933763)
			(xy 255.952193 -106.906599) (xy 255.956178 -106.877026) (xy 255.951458 -106.847561) (xy 255.945386 -106.833924)
			(xy 255.933225 -106.807758) (xy 255.91604 -106.752678) (xy 255.907326 -106.695641) (xy 255.906778 -106.666792)
			(xy 255.907241 -106.639538) (xy 255.915 -106.585585) (xy 255.930358 -106.533285) (xy 255.953002 -106.483704)
			(xy 255.982473 -106.437849) (xy 256.018169 -106.396656) (xy 256.059364 -106.360962) (xy 256.10522 -106.331494)
			(xy 256.154802 -106.308851) (xy 256.207103 -106.293496) (xy 256.261056 -106.28574) (xy 256.315564 -106.285742)
			(xy 256.369517 -106.2935) (xy 256.421816 -106.308858) (xy 256.471398 -106.331503) (xy 256.517252 -106.360974)
			(xy 256.558446 -106.39667) (xy 256.594139 -106.437865) (xy 256.623607 -106.483721) (xy 256.646249 -106.533304)
			(xy 256.661604 -106.585605) (xy 256.66936 -106.639558) (xy 256.669358 -106.694066) (xy 256.661599 -106.748019)
			(xy 256.646241 -106.800318) (xy 256.623596 -106.8499) (xy 256.594125 -106.895754) (xy 256.558429 -106.936947)
			(xy 256.517233 -106.972641) (xy 256.471377 -107.002108) (xy 256.421794 -107.02475) (xy 256.369493 -107.040105)
			(xy 256.31554 -107.04786) (xy 256.288286 -107.0483) (xy 256.27838 -107.048046) (xy 256.26345 -107.048158)
			(xy 256.234652 -107.055989) (xy 256.209341 -107.071801) (xy 256.189673 -107.094247) (xy 256.177323 -107.121415)
			(xy 256.173342 -107.150992) (xy 256.178069 -107.180459) (xy 256.184146 -107.194096) (xy 256.196304 -107.220263)
			(xy 256.213486 -107.275343) (xy 256.222196 -107.33238) (xy 256.222754 -107.361228) (xy 256.222223 -107.390048)
			(xy 256.21354 -107.44703) (xy 256.196376 -107.502055) (xy 256.171123 -107.553868) (xy 256.15519 -107.57789)
			(xy 256.147709 -107.589549) (xy 256.138683 -107.615727) (xy 256.137026 -107.643368) (xy 256.142859 -107.670437)
			(xy 256.155753 -107.694942) (xy 256.174758 -107.71508) (xy 256.198477 -107.729368) (xy 256.225164 -107.736755)
			(xy 256.23901 -107.737148) (xy 256.44348 -107.737148) (xy 257.30708 -106.873548) (xy 259.018278 -106.873548)
			(xy 259.018278 -106.82224) (xy 259.018278 -106.819192) (xy 259.018764 -106.791941) (xy 259.02652 -106.737993)
			(xy 259.041875 -106.685698) (xy 259.064517 -106.636121) (xy 259.093983 -106.590271) (xy 259.129674 -106.54908)
			(xy 259.170865 -106.513389) (xy 259.216715 -106.483923) (xy 259.266292 -106.461281) (xy 259.318587 -106.445926)
			(xy 259.372535 -106.43817) (xy 259.427037 -106.43817) (xy 259.480985 -106.445926) (xy 259.53328 -106.461281)
			(xy 259.582857 -106.483923) (xy 259.628707 -106.513389) (xy 259.669898 -106.54908) (xy 259.705589 -106.590271)
			(xy 259.735055 -106.636121) (xy 259.757697 -106.685698) (xy 259.773052 -106.737993) (xy 259.780808 -106.791941)
			(xy 259.781294 -106.819192) (xy 259.781294 -106.873548) (xy 263.30148 -106.873548) (xy 263.58088 -106.594148)
			(xy 263.58088 -103.744776) (xy 263.553956 -103.730552) (xy 263.528178 -103.716211) (xy 263.480992 -103.680813)
			(xy 263.43982 -103.638571) (xy 263.405643 -103.590493) (xy 263.379277 -103.537727) (xy 263.36135 -103.481529)
			(xy 263.35229 -103.423242) (xy 263.351772 -103.393748) (xy 263.351849 -103.382162) (xy 263.353248 -103.359031)
			(xy 263.354566 -103.34752) (xy 263.357614 -103.322882) (xy 263.09828 -103.063548) (xy 254.36068 -103.063548)
			(xy 253.462028 -102.164896) (xy 253.442724 -102.163626) (xy 253.415223 -102.161413) (xy 253.361232 -102.150064)
			(xy 253.309438 -102.131055) (xy 253.260924 -102.104784) (xy 253.2167 -102.071797) (xy 253.177689 -102.032784)
			(xy 253.144705 -101.988558) (xy 253.118436 -101.940042) (xy 253.09943 -101.888248) (xy 253.088084 -101.834256)
			(xy 253.085854 -101.806756) (xy 253.084584 -101.787452) (xy 252.10008 -100.802948) (xy 252.10008 -99.380548)
			(xy 251.89688 -99.177348) (xy 250.49988 -99.177348) (xy 250.49988 -102.63886) (xy 252.17577 -102.63886)
			(xy 252.179841 -102.583238) (xy 252.191967 -102.528801) (xy 252.21189 -102.47671) (xy 252.239186 -102.428075)
			(xy 252.273272 -102.383932) (xy 252.313421 -102.345223) (xy 252.358779 -102.312772) (xy 252.408379 -102.287271)
			(xy 252.461163 -102.269264) (xy 252.516006 -102.259134) (xy 252.57174 -102.257097) (xy 252.627177 -102.263197)
			(xy 252.681134 -102.277303) (xy 252.732463 -102.299115) (xy 252.780069 -102.328169) (xy 252.822937 -102.363844)
			(xy 252.860154 -102.405381) (xy 252.890927 -102.451894) (xy 252.914599 -102.502391) (xy 252.930667 -102.555798)
			(xy 252.938787 -102.610974) (xy 252.939296 -102.63886) (xy 252.938787 -102.666746) (xy 252.930667 -102.721922)
			(xy 252.914599 -102.775329) (xy 252.890927 -102.825826) (xy 252.860154 -102.872339) (xy 252.822937 -102.913876)
			(xy 252.780069 -102.949551) (xy 252.732463 -102.978605) (xy 252.681134 -103.000417) (xy 252.627177 -103.014523)
			(xy 252.57174 -103.020623) (xy 252.516006 -103.018586) (xy 252.461163 -103.008456) (xy 252.408379 -102.990449)
			(xy 252.358779 -102.964948) (xy 252.313421 -102.932497) (xy 252.273272 -102.893788) (xy 252.239186 -102.849645)
			(xy 252.21189 -102.80101) (xy 252.191967 -102.748919) (xy 252.179841 -102.694482) (xy 252.17577 -102.63886)
			(xy 250.49988 -102.63886) (xy 250.49988 -103.930553) (xy 250.61135 -103.930553) (xy 250.61135 -103.876047)
			(xy 250.619107 -103.822097) (xy 250.634462 -103.769799) (xy 250.657104 -103.72022) (xy 250.686571 -103.674366)
			(xy 250.722264 -103.633174) (xy 250.763455 -103.597479) (xy 250.809307 -103.568011) (xy 250.858886 -103.545367)
			(xy 250.911183 -103.53001) (xy 250.965133 -103.522251) (xy 250.992386 -103.521764) (xy 251.018067 -103.522191)
			(xy 251.068964 -103.529087) (xy 251.118474 -103.542756) (xy 251.1657 -103.562951) (xy 251.209785 -103.589305)
			(xy 251.249932 -103.621341) (xy 251.267976 -103.63962) (xy 251.277554 -103.649097) (xy 251.300604 -103.663039)
			(xy 251.326497 -103.670472) (xy 251.353432 -103.670881) (xy 251.379538 -103.664236) (xy 251.403 -103.651)
			(xy 251.422187 -103.632092) (xy 251.435767 -103.608827) (xy 251.43968 -103.595932) (xy 251.447396 -103.56935)
			(xy 251.469481 -103.518596) (xy 251.49867 -103.471567) (xy 251.534348 -103.42925) (xy 251.575767 -103.392533)
			(xy 251.622057 -103.362187) (xy 251.672247 -103.338849) (xy 251.725283 -103.323009) (xy 251.780051 -103.314999)
			(xy 251.807726 -103.3145) (xy 251.834977 -103.314972) (xy 251.888923 -103.322731) (xy 251.941215 -103.338089)
			(xy 251.99079 -103.360732) (xy 252.036638 -103.3902) (xy 252.077826 -103.425892) (xy 252.113516 -103.467082)
			(xy 252.14298 -103.512932) (xy 252.16562 -103.562509) (xy 252.180974 -103.614803) (xy 252.18873 -103.668749)
			(xy 252.18873 -103.723251) (xy 252.180974 -103.777197) (xy 252.16562 -103.829491) (xy 252.14298 -103.879068)
			(xy 252.113516 -103.924918) (xy 252.077826 -103.966108) (xy 252.036638 -104.0018) (xy 251.99079 -104.031268)
			(xy 251.941215 -104.053911) (xy 251.888923 -104.069269) (xy 251.834977 -104.077028) (xy 251.807726 -104.077516)
			(xy 251.782045 -104.077087) (xy 251.731148 -104.070192) (xy 251.681637 -104.056524) (xy 251.634412 -104.03633)
			(xy 251.590326 -104.009976) (xy 251.55018 -103.977939) (xy 251.532136 -103.95966) (xy 251.522538 -103.950205)
			(xy 251.499492 -103.936267) (xy 251.473605 -103.928834) (xy 251.446675 -103.928425) (xy 251.420574 -103.935066)
			(xy 251.397115 -103.948297) (xy 251.377928 -103.967198) (xy 251.364347 -103.990457) (xy 251.360432 -104.003348)
			(xy 251.352693 -104.029923) (xy 251.330611 -104.080676) (xy 251.301426 -104.127705) (xy 251.265751 -104.170023)
			(xy 251.224335 -104.206741) (xy 251.178047 -104.237088) (xy 251.12786 -104.260427) (xy 251.074826 -104.276269)
			(xy 251.02006 -104.28428) (xy 250.992386 -104.28478) (xy 250.965133 -104.284349) (xy 250.911183 -104.27659)
			(xy 250.858886 -104.261233) (xy 250.809307 -104.238589) (xy 250.763455 -104.209121) (xy 250.722264 -104.173426)
			(xy 250.686571 -104.132234) (xy 250.657104 -104.08638) (xy 250.634462 -104.036801) (xy 250.619107 -103.984503)
			(xy 250.61135 -103.930553) (xy 250.49988 -103.930553) (xy 250.49988 -104.358948) (xy 257.534662 -104.358948)
			(xy 257.538733 -104.303326) (xy 257.550859 -104.248889) (xy 257.570782 -104.196798) (xy 257.598078 -104.148163)
			(xy 257.632164 -104.10402) (xy 257.672313 -104.065311) (xy 257.717671 -104.03286) (xy 257.767271 -104.007359)
			(xy 257.820055 -103.989352) (xy 257.874898 -103.979222) (xy 257.930632 -103.977185) (xy 257.986069 -103.983285)
			(xy 258.040026 -103.997391) (xy 258.091355 -104.019203) (xy 258.138961 -104.048257) (xy 258.181829 -104.083932)
			(xy 258.219046 -104.125469) (xy 258.249819 -104.171982) (xy 258.273491 -104.222479) (xy 258.289559 -104.275886)
			(xy 258.297679 -104.331062) (xy 258.298188 -104.358948) (xy 258.297679 -104.386834) (xy 258.289559 -104.44201)
			(xy 258.273491 -104.495417) (xy 258.249819 -104.545914) (xy 258.219046 -104.592427) (xy 258.181829 -104.633964)
			(xy 258.138961 -104.669639) (xy 258.091355 -104.698693) (xy 258.040026 -104.720505) (xy 257.986069 -104.734611)
			(xy 257.930632 -104.740711) (xy 257.874898 -104.738674) (xy 257.820055 -104.728544) (xy 257.767271 -104.710537)
			(xy 257.717671 -104.685036) (xy 257.672313 -104.652585) (xy 257.632164 -104.613876) (xy 257.598078 -104.569733)
			(xy 257.570782 -104.521098) (xy 257.550859 -104.469007) (xy 257.538733 -104.41457) (xy 257.534662 -104.358948)
			(xy 250.49988 -104.358948) (xy 250.49988 -105.556812) (xy 252.956568 -105.556812) (xy 252.957158 -105.527621)
			(xy 252.966064 -105.469922) (xy 252.983654 -105.414254) (xy 253.00952 -105.361914) (xy 253.043055 -105.314124)
			(xy 253.083479 -105.272001) (xy 253.129847 -105.236526) (xy 253.155196 -105.22204) (xy 253.167776 -105.214685)
			(xy 253.188362 -105.194073) (xy 253.202296 -105.16849) (xy 253.208446 -105.140015) (xy 253.206311 -105.110962)
			(xy 253.196066 -105.083692) (xy 253.178543 -105.06042) (xy 253.167134 -105.051352) (xy 253.143672 -105.033254)
			(xy 253.102147 -104.990986) (xy 253.06766 -104.942804) (xy 253.041042 -104.889866) (xy 253.022933 -104.833448)
			(xy 253.01377 -104.774908) (xy 253.01321 -104.745282) (xy 253.013696 -104.718031) (xy 253.021452 -104.664083)
			(xy 253.036807 -104.611788) (xy 253.059449 -104.562211) (xy 253.088915 -104.516361) (xy 253.124606 -104.47517)
			(xy 253.165797 -104.439479) (xy 253.211647 -104.410013) (xy 253.261224 -104.387371) (xy 253.313519 -104.372016)
			(xy 253.367467 -104.36426) (xy 253.421969 -104.36426) (xy 253.475917 -104.372016) (xy 253.528212 -104.387371)
			(xy 253.577789 -104.410013) (xy 253.623639 -104.439479) (xy 253.66483 -104.47517) (xy 253.700521 -104.516361)
			(xy 253.729987 -104.562211) (xy 253.752629 -104.611788) (xy 253.767984 -104.664083) (xy 253.77574 -104.718031)
			(xy 253.776226 -104.745282) (xy 253.775635 -104.774473) (xy 253.766729 -104.832172) (xy 253.749139 -104.887841)
			(xy 253.723274 -104.940181) (xy 253.689739 -104.98797) (xy 253.649315 -105.030094) (xy 253.602947 -105.065568)
			(xy 253.577598 -105.080054) (xy 253.565024 -105.087417) (xy 253.544439 -105.108027) (xy 253.530506 -105.133609)
			(xy 253.524356 -105.162082) (xy 253.526489 -105.191133) (xy 253.536732 -105.218402) (xy 253.554253 -105.241674)
			(xy 253.56566 -105.250742) (xy 253.589118 -105.268845) (xy 253.630643 -105.311112) (xy 253.639974 -105.324148)
			(xy 254.919224 -105.324148) (xy 254.923295 -105.268526) (xy 254.935421 -105.214089) (xy 254.955344 -105.161998)
			(xy 254.98264 -105.113363) (xy 255.016726 -105.06922) (xy 255.056875 -105.030511) (xy 255.102233 -104.99806)
			(xy 255.151833 -104.972559) (xy 255.204617 -104.954552) (xy 255.25946 -104.944422) (xy 255.315194 -104.942385)
			(xy 255.370631 -104.948485) (xy 255.424588 -104.962591) (xy 255.475917 -104.984403) (xy 255.523523 -105.013457)
			(xy 255.566391 -105.049132) (xy 255.603608 -105.090669) (xy 255.634381 -105.137182) (xy 255.658053 -105.187679)
			(xy 255.674121 -105.241086) (xy 255.682241 -105.296262) (xy 255.68275 -105.324148) (xy 255.682241 -105.352034)
			(xy 255.674121 -105.40721) (xy 255.658053 -105.460617) (xy 255.634381 -105.511114) (xy 255.603608 -105.557627)
			(xy 255.566391 -105.599164) (xy 255.523523 -105.634839) (xy 255.475917 -105.663893) (xy 255.438606 -105.679748)
			(xy 256.264662 -105.679748) (xy 256.268733 -105.624126) (xy 256.280859 -105.569689) (xy 256.300782 -105.517598)
			(xy 256.328078 -105.468963) (xy 256.362164 -105.42482) (xy 256.402313 -105.386111) (xy 256.447671 -105.35366)
			(xy 256.497271 -105.328159) (xy 256.550055 -105.310152) (xy 256.604898 -105.300022) (xy 256.660632 -105.297985)
			(xy 256.716069 -105.304085) (xy 256.770026 -105.318191) (xy 256.821355 -105.340003) (xy 256.868961 -105.369057)
			(xy 256.911829 -105.404732) (xy 256.949046 -105.446269) (xy 256.979819 -105.492782) (xy 257.003491 -105.543279)
			(xy 257.019559 -105.596686) (xy 257.027679 -105.651862) (xy 257.028188 -105.679748) (xy 257.027679 -105.707634)
			(xy 257.019559 -105.76281) (xy 257.003491 -105.816217) (xy 256.979819 -105.866714) (xy 256.950257 -105.911396)
			(xy 259.012688 -105.911396) (xy 259.016759 -105.855774) (xy 259.028885 -105.801337) (xy 259.048808 -105.749246)
			(xy 259.076104 -105.700611) (xy 259.11019 -105.656468) (xy 259.150339 -105.617759) (xy 259.195697 -105.585308)
			(xy 259.245297 -105.559807) (xy 259.298081 -105.5418) (xy 259.352924 -105.53167) (xy 259.408658 -105.529633)
			(xy 259.464095 -105.535733) (xy 259.518052 -105.549839) (xy 259.569381 -105.571651) (xy 259.616987 -105.600705)
			(xy 259.659855 -105.63638) (xy 259.697072 -105.677917) (xy 259.727845 -105.72443) (xy 259.751517 -105.774927)
			(xy 259.767585 -105.828334) (xy 259.775705 -105.88351) (xy 259.776214 -105.911396) (xy 259.775705 -105.939282)
			(xy 259.767585 -105.994458) (xy 259.751517 -106.047865) (xy 259.727845 -106.098362) (xy 259.697072 -106.144875)
			(xy 259.659855 -106.186412) (xy 259.616987 -106.222087) (xy 259.569381 -106.251141) (xy 259.518052 -106.272953)
			(xy 259.464095 -106.287059) (xy 259.408658 -106.293159) (xy 259.352924 -106.291122) (xy 259.298081 -106.280992)
			(xy 259.245297 -106.262985) (xy 259.195697 -106.237484) (xy 259.150339 -106.205033) (xy 259.11019 -106.166324)
			(xy 259.076104 -106.122181) (xy 259.048808 -106.073546) (xy 259.028885 -106.021455) (xy 259.016759 -105.967018)
			(xy 259.012688 -105.911396) (xy 256.950257 -105.911396) (xy 256.949046 -105.913227) (xy 256.911829 -105.954764)
			(xy 256.868961 -105.990439) (xy 256.821355 -106.019493) (xy 256.770026 -106.041305) (xy 256.716069 -106.055411)
			(xy 256.660632 -106.061511) (xy 256.604898 -106.059474) (xy 256.550055 -106.049344) (xy 256.497271 -106.031337)
			(xy 256.447671 -106.005836) (xy 256.402313 -105.973385) (xy 256.362164 -105.934676) (xy 256.328078 -105.890533)
			(xy 256.300782 -105.841898) (xy 256.280859 -105.789807) (xy 256.268733 -105.73537) (xy 256.264662 -105.679748)
			(xy 255.438606 -105.679748) (xy 255.424588 -105.685705) (xy 255.370631 -105.699811) (xy 255.315194 -105.705911)
			(xy 255.25946 -105.703874) (xy 255.204617 -105.693744) (xy 255.151833 -105.675737) (xy 255.102233 -105.650236)
			(xy 255.056875 -105.617785) (xy 255.016726 -105.579076) (xy 254.98264 -105.534933) (xy 254.955344 -105.486298)
			(xy 254.935421 -105.434207) (xy 254.923295 -105.37977) (xy 254.919224 -105.324148) (xy 253.639974 -105.324148)
			(xy 253.665131 -105.359293) (xy 253.69175 -105.41223) (xy 253.709859 -105.468647) (xy 253.719023 -105.527186)
			(xy 253.719584 -105.556812) (xy 253.719098 -105.584063) (xy 253.711342 -105.638011) (xy 253.695987 -105.690306)
			(xy 253.673345 -105.739883) (xy 253.643879 -105.785733) (xy 253.608188 -105.826924) (xy 253.566997 -105.862615)
			(xy 253.521147 -105.892081) (xy 253.47157 -105.914723) (xy 253.419275 -105.930078) (xy 253.365327 -105.937834)
			(xy 253.310825 -105.937834) (xy 253.256877 -105.930078) (xy 253.204582 -105.914723) (xy 253.155005 -105.892081)
			(xy 253.109155 -105.862615) (xy 253.067964 -105.826924) (xy 253.032273 -105.785733) (xy 253.002807 -105.739883)
			(xy 252.980165 -105.690306) (xy 252.96481 -105.638011) (xy 252.957054 -105.584063) (xy 252.956568 -105.556812)
			(xy 250.49988 -105.556812) (xy 250.49988 -106.38409) (xy 251.528072 -106.38409) (xy 251.528558 -106.356839)
			(xy 251.536314 -106.302891) (xy 251.551669 -106.250596) (xy 251.574311 -106.201019) (xy 251.603777 -106.155169)
			(xy 251.639468 -106.113978) (xy 251.680659 -106.078287) (xy 251.726509 -106.048821) (xy 251.776086 -106.026179)
			(xy 251.828381 -106.010824) (xy 251.882329 -106.003068) (xy 251.936831 -106.003068) (xy 251.990779 -106.010824)
			(xy 252.043074 -106.026179) (xy 252.092651 -106.048821) (xy 252.138501 -106.078287) (xy 252.179692 -106.113978)
			(xy 252.215383 -106.155169) (xy 252.244849 -106.201019) (xy 252.267491 -106.250596) (xy 252.282846 -106.302891)
			(xy 252.290602 -106.356839) (xy 252.291088 -106.38409) (xy 252.29047 -106.414892) (xy 252.281942 -106.467148)
			(xy 252.913132 -106.467148) (xy 252.917203 -106.411526) (xy 252.929329 -106.357089) (xy 252.949252 -106.304998)
			(xy 252.976548 -106.256363) (xy 253.010634 -106.21222) (xy 253.050783 -106.173511) (xy 253.096141 -106.14106)
			(xy 253.145741 -106.115559) (xy 253.198525 -106.097552) (xy 253.253368 -106.087422) (xy 253.309102 -106.085385)
			(xy 253.364539 -106.091485) (xy 253.418496 -106.105591) (xy 253.469825 -106.127403) (xy 253.517431 -106.156457)
			(xy 253.560299 -106.192132) (xy 253.597516 -106.233669) (xy 253.628289 -106.280182) (xy 253.651961 -106.330679)
			(xy 253.668029 -106.384086) (xy 253.676149 -106.439262) (xy 253.676658 -106.467148) (xy 253.676149 -106.495034)
			(xy 253.668029 -106.55021) (xy 253.651961 -106.603617) (xy 253.628289 -106.654114) (xy 253.597516 -106.700627)
			(xy 253.560299 -106.742164) (xy 253.517431 -106.777839) (xy 253.469825 -106.806893) (xy 253.418496 -106.828705)
			(xy 253.364539 -106.842811) (xy 253.309102 -106.848911) (xy 253.253368 -106.846874) (xy 253.198525 -106.836744)
			(xy 253.145741 -106.818737) (xy 253.096141 -106.793236) (xy 253.050783 -106.760785) (xy 253.010634 -106.722076)
			(xy 252.976548 -106.677933) (xy 252.949252 -106.629298) (xy 252.929329 -106.577207) (xy 252.917203 -106.52277)
			(xy 252.913132 -106.467148) (xy 252.281942 -106.467148) (xy 252.280548 -106.475693) (xy 252.260978 -106.534107)
			(xy 252.247146 -106.561636) (xy 252.240403 -106.575556) (xy 252.234887 -106.60598) (xy 252.238717 -106.636661)
			(xy 252.251543 -106.664794) (xy 252.272191 -106.687808) (xy 252.298775 -106.703598) (xy 252.313694 -106.707686)
			(xy 252.341132 -106.714785) (xy 252.393698 -106.735967) (xy 252.442553 -106.764692) (xy 252.486622 -106.800327)
			(xy 252.524935 -106.842088) (xy 252.556649 -106.889057) (xy 252.581067 -106.940201) (xy 252.597651 -106.994393)
			(xy 252.606037 -107.050443) (xy 252.606556 -107.07878) (xy 252.60607 -107.106031) (xy 252.598314 -107.159979)
			(xy 252.582959 -107.212274) (xy 252.560317 -107.261851) (xy 252.530851 -107.307701) (xy 252.49516 -107.348892)
			(xy 252.453969 -107.384583) (xy 252.408119 -107.414049) (xy 252.358542 -107.436691) (xy 252.306247 -107.452046)
			(xy 252.252299 -107.459802) (xy 252.197797 -107.459802) (xy 252.143849 -107.452046) (xy 252.091554 -107.436691)
			(xy 252.041977 -107.414049) (xy 251.996127 -107.384583) (xy 251.954936 -107.348892) (xy 251.919245 -107.307701)
			(xy 251.889779 -107.261851) (xy 251.867137 -107.212274) (xy 251.851782 -107.159979) (xy 251.844026 -107.106031)
			(xy 251.84354 -107.07878) (xy 251.844144 -107.047977) (xy 251.854071 -106.987175) (xy 251.873647 -106.928762)
			(xy 251.887482 -106.901234) (xy 251.894122 -106.88727) (xy 251.899649 -106.856867) (xy 251.895836 -106.826201)
			(xy 251.883031 -106.798078) (xy 251.862404 -106.775068) (xy 251.835843 -106.759276) (xy 251.820934 -106.755184)
			(xy 251.793493 -106.748094) (xy 251.740925 -106.726913) (xy 251.692068 -106.698189) (xy 251.647998 -106.662553)
			(xy 251.609684 -106.620791) (xy 251.57797 -106.57382) (xy 251.553553 -106.522674) (xy 251.536971 -106.468479)
			(xy 251.528589 -106.412428) (xy 251.528072 -106.38409) (xy 250.49988 -106.38409) (xy 250.49988 -106.746548)
			(xy 251.49048 -107.737148)
		)
		(stroke
			(width 0)
			(type solid)
		)
		(fill yes)
		(layer "In6.Cu")
		(net "P3V3_AUX_CLK_GEN_VDDPT_CK440")
	)
	(gr_poly
		(pts
			(xy 430.358042 -129.02184) (xy 430.371883 -129.02137) (xy 430.398546 -129.013924) (xy 430.422229 -128.999589)
			(xy 430.441192 -128.979421) (xy 430.454041 -128.954901) (xy 430.459833 -128.92783) (xy 430.45814 -128.900199)
			(xy 430.454054 -128.886966) (xy 430.444226 -128.856663) (xy 430.433627 -128.793849) (xy 430.432972 -128.761998)
			(xy 430.433458 -128.734747) (xy 430.441214 -128.680799) (xy 430.456569 -128.628504) (xy 430.479211 -128.578927)
			(xy 430.508677 -128.533077) (xy 430.544368 -128.491886) (xy 430.585559 -128.456195) (xy 430.631409 -128.426729)
			(xy 430.680986 -128.404087) (xy 430.733281 -128.388732) (xy 430.787229 -128.380976) (xy 430.841731 -128.380976)
			(xy 430.895679 -128.388732) (xy 430.947974 -128.404087) (xy 430.997551 -128.426729) (xy 431.043401 -128.456195)
			(xy 431.084592 -128.491886) (xy 431.120283 -128.533077) (xy 431.149749 -128.578927) (xy 431.172391 -128.628504)
			(xy 431.187746 -128.680799) (xy 431.195502 -128.734747) (xy 431.195988 -128.761998) (xy 431.195351 -128.79385)
			(xy 431.184755 -128.856668) (xy 431.174906 -128.886966) (xy 431.170818 -128.900196) (xy 431.169123 -128.927823)
			(xy 431.174915 -128.95489) (xy 431.187765 -128.979405) (xy 431.206731 -128.999566) (xy 431.230416 -129.013889)
			(xy 431.257078 -129.021321) (xy 431.270918 -129.02184) (xy 431.41519 -129.02184) (xy 431.876962 -128.560322)
			(xy 431.893259 -128.544691) (xy 431.9303 -128.51887) (xy 431.971316 -128.499988) (xy 432.015018 -128.488638)
			(xy 432.03749 -128.486408) (xy 432.046948 -128.48529) (xy 432.064092 -128.477023) (xy 432.077047 -128.46308)
			(xy 432.084035 -128.445377) (xy 432.08448 -128.435862) (xy 432.08448 -128.077722) (xy 432.047904 -128.067054)
			(xy 432.010226 -128.05562) (xy 431.937257 -128.026024) (xy 431.867724 -127.98907) (xy 431.802367 -127.94515)
			(xy 431.741882 -127.894731) (xy 431.686913 -127.83835) (xy 431.638043 -127.776607) (xy 431.595793 -127.710159)
			(xy 431.560612 -127.639712) (xy 431.532875 -127.566016) (xy 431.522378 -127.528066) (xy 431.518017 -127.513633)
			(xy 431.502176 -127.487999) (xy 431.479541 -127.468107) (xy 431.452084 -127.455688) (xy 431.422199 -127.451826)
			(xy 431.392487 -127.456857) (xy 431.365539 -127.470342) (xy 431.35423 -127.480314) (xy 431.332821 -127.499902)
			(xy 431.285184 -127.533034) (xy 431.233081 -127.558573) (xy 431.177712 -127.57593) (xy 431.120353 -127.584705)
			(xy 431.09134 -127.585216) (xy 431.065387 -127.584781) (xy 431.013961 -127.577746) (xy 430.963964 -127.563799)
			(xy 430.916322 -127.5432) (xy 430.871914 -127.516328) (xy 430.831561 -127.483681) (xy 430.813464 -127.465074)
			(xy 430.803039 -127.454738) (xy 430.77766 -127.440006) (xy 430.74914 -127.433097) (xy 430.719833 -127.434582)
			(xy 430.692157 -127.444336) (xy 430.668397 -127.461557) (xy 430.650512 -127.484822) (xy 430.644808 -127.498348)
			(xy 430.633987 -127.524937) (xy 430.605526 -127.574788) (xy 430.569924 -127.619817) (xy 430.527982 -127.65901)
			(xy 430.480646 -127.691483) (xy 430.428983 -127.716505) (xy 430.374156 -127.733511) (xy 430.317402 -127.742118)
			(xy 430.2887 -127.742696) (xy 430.258649 -127.742132) (xy 430.19929 -127.732703) (xy 430.142145 -127.714078)
			(xy 430.088631 -127.686718) (xy 430.040071 -127.651302) (xy 430.018444 -127.630428) (xy 430.007516 -127.620243)
			(xy 429.981199 -127.606139) (xy 429.951929 -127.600242) (xy 429.922204 -127.603058) (xy 429.894561 -127.614345)
			(xy 429.871361 -127.633139) (xy 429.862488 -127.64516) (xy 429.847192 -127.666897) (xy 429.811543 -127.70632)
			(xy 429.770767 -127.740413) (xy 429.725654 -127.768517) (xy 429.677077 -127.790088) (xy 429.625977 -127.804708)
			(xy 429.573341 -127.812094) (xy 429.546766 -127.812546) (xy 429.519514 -127.812058) (xy 429.465564 -127.804297)
			(xy 429.413268 -127.788937) (xy 429.36369 -127.766292) (xy 429.31784 -127.736822) (xy 429.276649 -127.701126)
			(xy 429.240958 -127.659933) (xy 429.211492 -127.61408) (xy 429.188851 -127.5645) (xy 429.173496 -127.512203)
			(xy 429.16574 -127.458252) (xy 429.16574 -127.403748) (xy 429.173496 -127.349797) (xy 429.188851 -127.2975)
			(xy 429.211492 -127.24792) (xy 429.240958 -127.202067) (xy 429.276649 -127.160874) (xy 429.31784 -127.125178)
			(xy 429.36369 -127.095708) (xy 429.413268 -127.073063) (xy 429.465564 -127.057703) (xy 429.519514 -127.049942)
			(xy 429.546766 -127.04953) (xy 429.576819 -127.050091) (xy 429.636182 -127.059514) (xy 429.693332 -127.078132)
			(xy 429.746854 -127.105485) (xy 429.795423 -127.140894) (xy 429.817022 -127.161798) (xy 429.827952 -127.171986)
			(xy 429.854273 -127.186096) (xy 429.883548 -127.191999) (xy 429.913281 -127.189189) (xy 429.940933 -127.177908)
			(xy 429.964145 -127.159117) (xy 429.972978 -127.147066) (xy 429.981706 -127.134461) (xy 430.000908 -127.110557)
			(xy 430.011332 -127.099314) (xy 430.021103 -127.088173) (xy 430.034341 -127.061677) (xy 430.03943 -127.032497)
			(xy 430.035944 -127.003084) (xy 430.024175 -126.975902) (xy 430.00511 -126.953234) (xy 429.993044 -126.944628)
			(xy 429.970768 -126.929423) (xy 429.930325 -126.893739) (xy 429.895311 -126.852716) (xy 429.866421 -126.807172)
			(xy 429.844233 -126.758014) (xy 429.829187 -126.706221) (xy 429.821585 -126.652825) (xy 429.821086 -126.625858)
			(xy 429.821572 -126.598607) (xy 429.829328 -126.544659) (xy 429.844683 -126.492364) (xy 429.867325 -126.442787)
			(xy 429.896791 -126.396937) (xy 429.932482 -126.355746) (xy 429.973673 -126.320055) (xy 430.019523 -126.290589)
			(xy 430.0691 -126.267947) (xy 430.121395 -126.252592) (xy 430.175343 -126.244836) (xy 430.229845 -126.244836)
			(xy 430.283793 -126.252592) (xy 430.336088 -126.267947) (xy 430.385665 -126.290589) (xy 430.431515 -126.320055)
			(xy 430.472706 -126.355746) (xy 430.508397 -126.396937) (xy 430.537863 -126.442787) (xy 430.560505 -126.492364)
			(xy 430.57586 -126.544659) (xy 430.583616 -126.598607) (xy 430.584102 -126.625858) (xy 430.583565 -126.654738)
			(xy 430.574847 -126.711837) (xy 430.557619 -126.766968) (xy 430.532274 -126.818871) (xy 430.499393 -126.866359)
			(xy 430.479962 -126.887732) (xy 430.470183 -126.898874) (xy 430.456931 -126.925377) (xy 430.451829 -126.954566)
			(xy 430.455307 -126.983993) (xy 430.467071 -127.011189) (xy 430.486136 -127.033874) (xy 430.49825 -127.042418)
			(xy 430.516764 -127.054973) (xy 430.551015 -127.083751) (xy 430.566576 -127.099822) (xy 430.577 -127.110152)
			(xy 430.602373 -127.124873) (xy 430.630885 -127.131773) (xy 430.660182 -127.130283) (xy 430.687846 -127.120526)
			(xy 430.711595 -127.103307) (xy 430.729469 -127.080046) (xy 430.735232 -127.066548) (xy 430.746052 -127.039957)
			(xy 430.774512 -126.990101) (xy 430.810113 -126.945067) (xy 430.852054 -126.905868) (xy 430.899389 -126.873388)
			(xy 430.951052 -126.848359) (xy 431.00588 -126.831345) (xy 431.062637 -126.822729) (xy 431.09134 -126.8222)
			(xy 431.101839 -126.822264) (xy 431.122806 -126.82341) (xy 431.13325 -126.824486) (xy 431.148698 -126.825582)
			(xy 431.17905 -126.819503) (xy 431.206198 -126.804632) (xy 431.227662 -126.782328) (xy 431.241479 -126.754628)
			(xy 431.246387 -126.724065) (xy 431.244756 -126.708662) (xy 431.242827 -126.694709) (xy 431.240794 -126.666613)
			(xy 431.240692 -126.652528) (xy 431.241153 -126.625997) (xy 431.248512 -126.573448) (xy 431.263079 -126.522425)
			(xy 431.284573 -126.473911) (xy 431.312579 -126.428841) (xy 431.346558 -126.388085) (xy 431.385854 -126.352429)
			(xy 431.42971 -126.322559) (xy 431.45329 -126.31039) (xy 431.452782 -126.282958) (xy 431.45328 -126.24355)
			(xy 431.461416 -126.165155) (xy 431.477598 -126.088019) (xy 431.501653 -126.012963) (xy 431.533324 -125.94079)
			(xy 431.55235 -125.906276) (xy 431.5714 -125.872748) (xy 431.119026 -125.420374) (xy 430.656492 -125.420374)
			(xy 430.165256 -124.929138) (xy 430.165256 -121.199148) (xy 431.34915 -120.015254) (xy 431.34915 -119.190516)
			(xy 431.147982 -118.989348) (xy 427.990508 -118.989348) (xy 427.976921 -118.989777) (xy 427.950708 -118.996941)
			(xy 427.927313 -119.010764) (xy 427.90839 -119.030267) (xy 427.895281 -119.05407) (xy 427.888913 -119.080487)
			(xy 427.889736 -119.107648) (xy 427.897693 -119.133631) (xy 427.904656 -119.145304) (xy 427.91862 -119.16827)
			(xy 427.940661 -119.217291) (xy 427.955602 -119.268921) (xy 427.963146 -119.322138) (xy 427.963584 -119.349012)
			(xy 427.963098 -119.376263) (xy 427.955342 -119.430211) (xy 427.939987 -119.482506) (xy 427.917345 -119.532083)
			(xy 427.887879 -119.577933) (xy 427.852188 -119.619124) (xy 427.810997 -119.654815) (xy 427.765147 -119.684281)
			(xy 427.71557 -119.706923) (xy 427.663275 -119.722278) (xy 427.609327 -119.730034) (xy 427.554825 -119.730034)
			(xy 427.500877 -119.722278) (xy 427.448582 -119.706923) (xy 427.399005 -119.684281) (xy 427.353155 -119.654815)
			(xy 427.311964 -119.619124) (xy 427.276273 -119.577933) (xy 427.246807 -119.532083) (xy 427.224165 -119.482506)
			(xy 427.20881 -119.430211) (xy 427.201054 -119.376263) (xy 427.200568 -119.349012) (xy 427.201026 -119.322138)
			(xy 427.208565 -119.268922) (xy 427.223497 -119.217291) (xy 427.245525 -119.168265) (xy 427.259496 -119.145304)
			(xy 427.266409 -119.133597) (xy 427.27439 -119.107618) (xy 427.275233 -119.080454) (xy 427.268877 -119.05403)
			(xy 427.255773 -119.03022) (xy 427.236851 -119.010713) (xy 427.213451 -118.99689) (xy 427.187233 -118.989733)
			(xy 427.173644 -118.989348) (xy 425.6532 -118.989348) (xy 425.6532 -120.238012) (xy 427.221396 -120.238012)
			(xy 427.221882 -120.210761) (xy 427.229638 -120.156813) (xy 427.244993 -120.104518) (xy 427.267635 -120.054941)
			(xy 427.297101 -120.009091) (xy 427.332792 -119.9679) (xy 427.373983 -119.932209) (xy 427.419833 -119.902743)
			(xy 427.46941 -119.880101) (xy 427.521705 -119.864746) (xy 427.575653 -119.85699) (xy 427.630155 -119.85699)
			(xy 427.684103 -119.864746) (xy 427.736398 -119.880101) (xy 427.785975 -119.902743) (xy 427.831825 -119.932209)
			(xy 427.873016 -119.9679) (xy 427.908707 -120.009091) (xy 427.938173 -120.054941) (xy 427.960815 -120.104518)
			(xy 427.97617 -120.156813) (xy 427.983926 -120.210761) (xy 427.984412 -120.238012) (xy 427.983871 -120.268234)
			(xy 427.974372 -120.327925) (xy 427.955565 -120.385367) (xy 427.927923 -120.439119) (xy 427.910498 -120.463818)
			(xy 427.902886 -120.474932) (xy 427.893193 -120.500054) (xy 427.890409 -120.526838) (xy 427.89473 -120.553416)
			(xy 427.905852 -120.577939) (xy 427.923003 -120.598698) (xy 427.944987 -120.614248) (xy 427.957488 -120.619266)
			(xy 427.98463 -120.629809) (xy 428.035637 -120.657889) (xy 428.081785 -120.693392) (xy 428.122002 -120.735495)
			(xy 428.155356 -120.78322) (xy 428.181071 -120.835458) (xy 428.19855 -120.890997) (xy 428.207387 -120.948548)
			(xy 428.207932 -120.97766) (xy 428.207446 -121.004911) (xy 428.19969 -121.058859) (xy 428.184335 -121.111154)
			(xy 428.161693 -121.160731) (xy 428.132227 -121.206581) (xy 428.096536 -121.247772) (xy 428.055345 -121.283463)
			(xy 428.009495 -121.312929) (xy 427.959918 -121.335571) (xy 427.907623 -121.350926) (xy 427.853675 -121.358682)
			(xy 427.799173 -121.358682) (xy 427.745225 -121.350926) (xy 427.69293 -121.335571) (xy 427.643353 -121.312929)
			(xy 427.597503 -121.283463) (xy 427.556312 -121.247772) (xy 427.520621 -121.206581) (xy 427.491155 -121.160731)
			(xy 427.468513 -121.111154) (xy 427.453158 -121.058859) (xy 427.445402 -121.004911) (xy 427.444916 -120.97766)
			(xy 427.445488 -120.947439) (xy 427.454977 -120.887749) (xy 427.473775 -120.830307) (xy 427.501409 -120.776554)
			(xy 427.51883 -120.751854) (xy 427.526463 -120.740755) (xy 427.536149 -120.715628) (xy 427.538926 -120.688842)
			(xy 427.534602 -120.662263) (xy 427.523476 -120.637739) (xy 427.506325 -120.616978) (xy 427.484341 -120.601426)
			(xy 427.47184 -120.596406) (xy 427.444672 -120.585926) (xy 427.393667 -120.557834) (xy 427.347521 -120.52232)
			(xy 427.307307 -120.480207) (xy 427.273957 -120.432474) (xy 427.248246 -120.380228) (xy 427.230772 -120.324683)
			(xy 427.221938 -120.267127) (xy 427.221396 -120.238012) (xy 425.6532 -120.238012) (xy 425.6532 -121.743216)
			(xy 428.864014 -121.743216) (xy 428.8645 -121.715965) (xy 428.872256 -121.662017) (xy 428.887611 -121.609722)
			(xy 428.910253 -121.560145) (xy 428.939719 -121.514295) (xy 428.97541 -121.473104) (xy 429.016601 -121.437413)
			(xy 429.062451 -121.407947) (xy 429.112028 -121.385305) (xy 429.164323 -121.36995) (xy 429.218271 -121.362194)
			(xy 429.272773 -121.362194) (xy 429.326721 -121.36995) (xy 429.379016 -121.385305) (xy 429.428593 -121.407947)
			(xy 429.474443 -121.437413) (xy 429.515634 -121.473104) (xy 429.551325 -121.514295) (xy 429.580791 -121.560145)
			(xy 429.603433 -121.609722) (xy 429.618788 -121.662017) (xy 429.626544 -121.715965) (xy 429.62703 -121.743216)
			(xy 429.626439 -121.773043) (xy 429.617165 -121.831972) (xy 429.598829 -121.888738) (xy 429.57188 -121.941957)
			(xy 429.554894 -121.966482) (xy 429.546539 -121.97895) (xy 429.536807 -122.007326) (xy 429.535742 -122.037306)
			(xy 429.543437 -122.066301) (xy 429.559226 -122.091808) (xy 429.570134 -122.102118) (xy 429.590087 -122.120342)
			(xy 429.625216 -122.161399) (xy 429.654204 -122.207001) (xy 429.67647 -122.256236) (xy 429.691569 -122.308119)
			(xy 429.6992 -122.361612) (xy 429.699674 -122.38863) (xy 429.699188 -122.415881) (xy 429.691432 -122.469829)
			(xy 429.676077 -122.522124) (xy 429.653435 -122.571701) (xy 429.623969 -122.617551) (xy 429.588278 -122.658742)
			(xy 429.547087 -122.694433) (xy 429.501237 -122.723899) (xy 429.45166 -122.746541) (xy 429.399365 -122.761896)
			(xy 429.345417 -122.769652) (xy 429.290915 -122.769652) (xy 429.236967 -122.761896) (xy 429.184672 -122.746541)
			(xy 429.135095 -122.723899) (xy 429.089245 -122.694433) (xy 429.048054 -122.658742) (xy 429.012363 -122.617551)
			(xy 428.982897 -122.571701) (xy 428.960255 -122.522124) (xy 428.9449 -122.469829) (xy 428.937144 -122.415881)
			(xy 428.936658 -122.38863) (xy 428.937205 -122.358801) (xy 428.94649 -122.29987) (xy 428.964838 -122.243103)
			(xy 428.991801 -122.189886) (xy 429.008794 -122.165364) (xy 429.017104 -122.152868) (xy 429.026844 -122.124503)
			(xy 429.027919 -122.094532) (xy 429.020235 -122.065542) (xy 429.004456 -122.040038) (xy 428.993554 -122.029728)
			(xy 428.973573 -122.011534) (xy 428.938446 -121.97047) (xy 428.909463 -121.924862) (xy 428.887201 -121.875621)
			(xy 428.872108 -121.823733) (xy 428.864484 -121.770235) (xy 428.864014 -121.743216) (xy 425.6532 -121.743216)
			(xy 425.6532 -123.262952) (xy 426.745875 -123.262952) (xy 426.745875 -123.208448) (xy 426.753632 -123.154499)
			(xy 426.768988 -123.102204) (xy 426.79163 -123.052626) (xy 426.821097 -123.006775) (xy 426.856789 -122.965584)
			(xy 426.897981 -122.929892) (xy 426.943833 -122.900426) (xy 426.993411 -122.877785) (xy 427.045707 -122.86243)
			(xy 427.099656 -122.854675) (xy 427.126908 -122.854212) (xy 427.153746 -122.854659) (xy 427.206889 -122.862196)
			(xy 427.258453 -122.877105) (xy 427.307418 -122.899093) (xy 427.352819 -122.927725) (xy 427.393759 -122.962437)
			(xy 427.429432 -123.002544) (xy 427.444662 -123.024646) (xy 427.4527 -123.036082) (xy 427.473895 -123.054296)
			(xy 427.499235 -123.066079) (xy 427.526821 -123.070549) (xy 427.554586 -123.067369) (xy 427.580447 -123.056779)
			(xy 427.591728 -123.048522) (xy 427.611934 -123.033322) (xy 427.655579 -123.007796) (xy 427.702213 -122.988257)
			(xy 427.75102 -122.975048) (xy 427.801143 -122.9684) (xy 427.826424 -122.968004) (xy 427.852345 -122.968454)
			(xy 427.903707 -122.975487) (xy 427.953644 -122.989408) (xy 428.001238 -123.00996) (xy 428.045613 -123.036764)
			(xy 428.08595 -123.069328) (xy 428.104046 -123.087892) (xy 428.114451 -123.098157) (xy 428.139677 -123.112888)
			(xy 428.168043 -123.11987) (xy 428.197225 -123.11853) (xy 428.224831 -123.108977) (xy 428.248601 -123.091996)
			(xy 428.25797 -123.08078) (xy 428.276143 -123.058376) (xy 428.318151 -123.01884) (xy 428.365631 -122.986075)
			(xy 428.4175 -122.960828) (xy 428.472577 -122.943673) (xy 428.529608 -122.935) (xy 428.558452 -122.934476)
			(xy 428.585706 -122.934968) (xy 428.63966 -122.942719) (xy 428.691961 -122.95807) (xy 428.741545 -122.980709)
			(xy 428.787403 -123.010175) (xy 428.828599 -123.045867) (xy 428.864297 -123.087059) (xy 428.893768 -123.132913)
			(xy 428.916413 -123.182494) (xy 428.931771 -123.234793) (xy 428.939529 -123.288746) (xy 428.939529 -123.343254)
			(xy 428.931771 -123.397207) (xy 428.916413 -123.449506) (xy 428.893768 -123.499087) (xy 428.864297 -123.544941)
			(xy 428.828599 -123.586133) (xy 428.787403 -123.621825) (xy 428.741545 -123.651291) (xy 428.691961 -123.67393)
			(xy 428.63966 -123.689281) (xy 428.585706 -123.697032) (xy 428.558452 -123.697492) (xy 428.532531 -123.697059)
			(xy 428.481168 -123.690022) (xy 428.43123 -123.676099) (xy 428.383636 -123.655544) (xy 428.339262 -123.628736)
			(xy 428.298925 -123.59617) (xy 428.28083 -123.577604) (xy 428.270448 -123.567314) (xy 428.245215 -123.552585)
			(xy 428.216843 -123.545607) (xy 428.187656 -123.546952) (xy 428.160046 -123.556509) (xy 428.136275 -123.573497)
			(xy 428.126906 -123.584716) (xy 428.108689 -123.607083) (xy 428.06669 -123.646621) (xy 428.01922 -123.67939)
			(xy 427.96736 -123.704644) (xy 427.91229 -123.721808) (xy 427.855265 -123.73049) (xy 427.826424 -123.73102)
			(xy 427.799588 -123.730534) (xy 427.746446 -123.723003) (xy 427.694885 -123.708099) (xy 427.64592 -123.686117)
			(xy 427.600519 -123.657491) (xy 427.559577 -123.622786) (xy 427.523902 -123.582685) (xy 427.50867 -123.560586)
			(xy 427.500594 -123.549179) (xy 427.47941 -123.530961) (xy 427.454079 -123.519172) (xy 427.4265 -123.514697)
			(xy 427.39874 -123.51787) (xy 427.372883 -123.528455) (xy 427.361604 -123.53671) (xy 427.341391 -123.5519)
			(xy 427.297747 -123.577427) (xy 427.251115 -123.596967) (xy 427.20231 -123.610179) (xy 427.152189 -123.61683)
			(xy 427.126908 -123.617228) (xy 427.099656 -123.616725) (xy 427.045707 -123.60897) (xy 426.993411 -123.593615)
			(xy 426.943833 -123.570974) (xy 426.897981 -123.541508) (xy 426.856789 -123.505816) (xy 426.821097 -123.464625)
			(xy 426.79163 -123.418774) (xy 426.768988 -123.369196) (xy 426.753632 -123.316901) (xy 426.745875 -123.262952)
			(xy 425.6532 -123.262952) (xy 425.6532 -124.553726) (xy 425.653681 -124.568347) (xy 425.661971 -124.596388)
			(xy 425.677864 -124.620934) (xy 425.700059 -124.639972) (xy 425.726737 -124.651945) (xy 425.755714 -124.65587)
			(xy 425.784615 -124.651427) (xy 425.811075 -124.63898) (xy 425.822364 -124.629672) (xy 425.843429 -124.611615)
			(xy 425.889794 -124.581145) (xy 425.940079 -124.5577) (xy 425.993225 -124.541774) (xy 426.048116 -124.533701)
			(xy 426.075856 -124.533152) (xy 426.103114 -124.533612) (xy 426.157075 -124.541365) (xy 426.209384 -124.556718)
			(xy 426.258975 -124.579361) (xy 426.304838 -124.608831) (xy 426.346041 -124.644528) (xy 426.381743 -124.685726)
			(xy 426.411218 -124.731587) (xy 426.429867 -124.77242) (xy 427.805848 -124.77242) (xy 427.809919 -124.716798)
			(xy 427.822045 -124.662361) (xy 427.841968 -124.61027) (xy 427.869264 -124.561635) (xy 427.90335 -124.517492)
			(xy 427.943499 -124.478783) (xy 427.988857 -124.446332) (xy 428.038457 -124.420831) (xy 428.091241 -124.402824)
			(xy 428.146084 -124.392694) (xy 428.201818 -124.390657) (xy 428.257255 -124.396757) (xy 428.311212 -124.410863)
			(xy 428.362541 -124.432675) (xy 428.410147 -124.461729) (xy 428.453015 -124.497404) (xy 428.490232 -124.538941)
			(xy 428.521005 -124.585454) (xy 428.544677 -124.635951) (xy 428.560745 -124.689358) (xy 428.568865 -124.744534)
			(xy 428.569374 -124.77242) (xy 428.568865 -124.800306) (xy 428.560745 -124.855482) (xy 428.544677 -124.908889)
			(xy 428.521005 -124.959386) (xy 428.490232 -125.005899) (xy 428.453015 -125.047436) (xy 428.410147 -125.083111)
			(xy 428.362541 -125.112165) (xy 428.311212 -125.133977) (xy 428.257255 -125.148083) (xy 428.201818 -125.154183)
			(xy 428.146084 -125.152146) (xy 428.091241 -125.142016) (xy 428.038457 -125.124009) (xy 427.988857 -125.098508)
			(xy 427.943499 -125.066057) (xy 427.90335 -125.027348) (xy 427.869264 -124.983205) (xy 427.841968 -124.93457)
			(xy 427.822045 -124.882479) (xy 427.809919 -124.828042) (xy 427.805848 -124.77242) (xy 426.429867 -124.77242)
			(xy 426.433866 -124.781175) (xy 426.449226 -124.833482) (xy 426.456985 -124.887442) (xy 426.456985 -124.941958)
			(xy 426.449226 -124.995918) (xy 426.433866 -125.048225) (xy 426.411218 -125.097813) (xy 426.381743 -125.143674)
			(xy 426.346041 -125.184872) (xy 426.304838 -125.220569) (xy 426.258975 -125.250039) (xy 426.209384 -125.272682)
			(xy 426.157075 -125.288035) (xy 426.103114 -125.295788) (xy 426.075856 -125.296168) (xy 426.048109 -125.295677)
			(xy 425.993201 -125.287645) (xy 425.94004 -125.271726) (xy 425.889753 -125.24826) (xy 425.843404 -125.217742)
			(xy 425.822364 -125.199648) (xy 425.81112 -125.190275) (xy 425.78465 -125.177805) (xy 425.755731 -125.173351)
			(xy 425.726735 -125.177278) (xy 425.700042 -125.189263) (xy 425.677842 -125.208324) (xy 425.661955 -125.232896)
			(xy 425.653686 -125.260963) (xy 425.6532 -125.275594) (xy 425.6532 -125.394212) (xy 429.170336 -125.394212)
			(xy 429.174407 -125.33859) (xy 429.186533 -125.284153) (xy 429.206456 -125.232062) (xy 429.233752 -125.183427)
			(xy 429.267838 -125.139284) (xy 429.307987 -125.100575) (xy 429.353345 -125.068124) (xy 429.402945 -125.042623)
			(xy 429.455729 -125.024616) (xy 429.510572 -125.014486) (xy 429.566306 -125.012449) (xy 429.621743 -125.018549)
			(xy 429.6757 -125.032655) (xy 429.727029 -125.054467) (xy 429.774635 -125.083521) (xy 429.817503 -125.119196)
			(xy 429.85472 -125.160733) (xy 429.885493 -125.207246) (xy 429.909165 -125.257743) (xy 429.925233 -125.31115)
			(xy 429.933353 -125.366326) (xy 429.933862 -125.394212) (xy 429.933353 -125.422098) (xy 429.925233 -125.477274)
			(xy 429.909165 -125.530681) (xy 429.885493 -125.581178) (xy 429.85472 -125.627691) (xy 429.817503 -125.669228)
			(xy 429.774635 -125.704903) (xy 429.727029 -125.733957) (xy 429.6757 -125.755769) (xy 429.621743 -125.769875)
			(xy 429.566306 -125.775975) (xy 429.510572 -125.773938) (xy 429.455729 -125.763808) (xy 429.402945 -125.745801)
			(xy 429.353345 -125.7203) (xy 429.307987 -125.687849) (xy 429.267838 -125.64914) (xy 429.233752 -125.604997)
			(xy 429.206456 -125.556362) (xy 429.186533 -125.504271) (xy 429.174407 -125.449834) (xy 429.170336 -125.394212)
			(xy 425.6532 -125.394212) (xy 425.6532 -126.81966) (xy 426.74743 -126.81966) (xy 426.751501 -126.764038)
			(xy 426.763627 -126.709601) (xy 426.78355 -126.65751) (xy 426.810846 -126.608875) (xy 426.844932 -126.564732)
			(xy 426.885081 -126.526023) (xy 426.930439 -126.493572) (xy 426.980039 -126.468071) (xy 427.032823 -126.450064)
			(xy 427.087666 -126.439934) (xy 427.1434 -126.437897) (xy 427.198837 -126.443997) (xy 427.252794 -126.458103)
			(xy 427.304123 -126.479915) (xy 427.351729 -126.508969) (xy 427.394597 -126.544644) (xy 427.431814 -126.586181)
			(xy 427.462587 -126.632694) (xy 427.486259 -126.683191) (xy 427.502327 -126.736598) (xy 427.510447 -126.791774)
			(xy 427.510956 -126.81966) (xy 427.510447 -126.847546) (xy 427.502327 -126.902722) (xy 427.486259 -126.956129)
			(xy 427.462587 -127.006626) (xy 427.431814 -127.053139) (xy 427.394597 -127.094676) (xy 427.351729 -127.130351)
			(xy 427.304123 -127.159405) (xy 427.252794 -127.181217) (xy 427.198837 -127.195323) (xy 427.1434 -127.201423)
			(xy 427.087666 -127.199386) (xy 427.032823 -127.189256) (xy 426.980039 -127.171249) (xy 426.930439 -127.145748)
			(xy 426.885081 -127.113297) (xy 426.844932 -127.074588) (xy 426.810846 -127.030445) (xy 426.78355 -126.98181)
			(xy 426.763627 -126.929719) (xy 426.751501 -126.875282) (xy 426.74743 -126.81966) (xy 425.6532 -126.81966)
			(xy 425.6532 -129.02184)
		)
		(stroke
			(width 0)
			(type solid)
		)
		(fill yes)
		(layer "In6.Cu")
		(net "PVCCD_HV_CPU0_VREF")
	)
	(gr_poly
		(pts
			(xy 228.12248 -53.177948) (xy 228.12248 -50.434748) (xy 229.69728 -48.859948) (xy 234.425236 -48.859948)
			(xy 234.447362 -48.843916) (xy 234.495285 -48.817672) (xy 234.546462 -48.798533) (xy 234.599845 -48.786891)
			(xy 234.654344 -48.782984) (xy 234.708843 -48.786891) (xy 234.762226 -48.798533) (xy 234.813403 -48.817672)
			(xy 234.861326 -48.843916) (xy 234.883452 -48.859948) (xy 237.74908 -48.859948) (xy 238.506 -48.103028)
			(xy 238.497618 -48.074326) (xy 238.490607 -48.04841) (xy 238.483082 -47.995252) (xy 238.482632 -47.968408)
			(xy 238.483095 -47.941156) (xy 238.490851 -47.887206) (xy 238.506207 -47.83491) (xy 238.528849 -47.785331)
			(xy 238.558318 -47.73948) (xy 238.594012 -47.698289) (xy 238.635205 -47.662599) (xy 238.681059 -47.633134)
			(xy 238.73064 -47.610496) (xy 238.782937 -47.595144) (xy 238.836888 -47.587393) (xy 238.86414 -47.5869)
			(xy 238.890983 -47.587359) (xy 238.94414 -47.594885) (xy 238.970058 -47.601886) (xy 238.99876 -47.610268)
			(xy 239.12068 -47.488348) (xy 239.12068 -47.242984) (xy 239.120228 -47.229258) (xy 239.112907 -47.202801)
			(xy 239.098799 -47.179253) (xy 239.078925 -47.160316) (xy 239.054723 -47.147361) (xy 239.027943 -47.141326)
			(xy 239.000524 -47.142647) (xy 238.98733 -47.146464) (xy 238.958244 -47.155471) (xy 238.898138 -47.165177)
			(xy 238.867696 -47.165768) (xy 238.840448 -47.165282) (xy 238.786506 -47.157525) (xy 238.734218 -47.142172)
			(xy 238.684646 -47.119533) (xy 238.638801 -47.090069) (xy 238.597616 -47.054382) (xy 238.561928 -47.013196)
			(xy 238.532466 -46.96735) (xy 238.509827 -46.917779) (xy 238.494474 -46.86549) (xy 238.486718 -46.811548)
			(xy 238.486718 -46.757052) (xy 238.494474 -46.70311) (xy 238.509827 -46.650821) (xy 238.532466 -46.60125)
			(xy 238.561928 -46.555404) (xy 238.597616 -46.514218) (xy 238.638801 -46.478531) (xy 238.684646 -46.449067)
			(xy 238.734218 -46.426428) (xy 238.786506 -46.411075) (xy 238.840448 -46.403318) (xy 238.867696 -46.402752)
			(xy 238.898137 -46.403365) (xy 238.958243 -46.41306) (xy 238.98733 -46.422056) (xy 239.000516 -46.425921)
			(xy 239.02795 -46.427242) (xy 239.054744 -46.421204) (xy 239.07896 -46.408244) (xy 239.098847 -46.389299)
			(xy 239.112965 -46.365739) (xy 239.120294 -46.339269) (xy 239.12068 -46.325536) (xy 239.12068 -46.043088)
			(xy 238.83874 -45.761148) (xy 234.582208 -45.761148) (xy 234.567754 -45.761652) (xy 234.540002 -45.769746)
			(xy 234.515629 -45.785289) (xy 234.496584 -45.807037) (xy 234.484392 -45.833248) (xy 234.48003 -45.861825)
			(xy 234.483846 -45.89048) (xy 234.495535 -45.916919) (xy 234.504484 -45.92828) (xy 234.521483 -45.949044)
			(xy 234.550099 -45.994439) (xy 234.572069 -46.043397) (xy 234.586961 -46.094951) (xy 234.59448 -46.148083)
			(xy 234.594908 -46.174914) (xy 234.59444 -46.202212) (xy 234.586656 -46.256251) (xy 234.571247 -46.308628)
			(xy 234.548529 -46.358274) (xy 234.518967 -46.404175) (xy 234.483163 -46.445392) (xy 234.441849 -46.481084)
			(xy 234.395869 -46.510523) (xy 234.346162 -46.533107) (xy 234.293743 -46.548374) (xy 234.239684 -46.556013)
			(xy 234.212384 -46.556422) (xy 234.19702 -46.556921) (xy 234.167662 -46.565991) (xy 234.142322 -46.583369)
			(xy 234.123284 -46.607488) (xy 234.112266 -46.636171) (xy 234.110262 -46.666833) (xy 234.113324 -46.681898)
			(xy 234.118297 -46.703851) (xy 234.123651 -46.748545) (xy 234.123992 -46.771052) (xy 234.123769 -46.78426)
			(xy 237.469678 -46.78426) (xy 237.473749 -46.728638) (xy 237.485875 -46.674201) (xy 237.505798 -46.62211)
			(xy 237.533094 -46.573475) (xy 237.56718 -46.529332) (xy 237.607329 -46.490623) (xy 237.652687 -46.458172)
			(xy 237.702287 -46.432671) (xy 237.755071 -46.414664) (xy 237.809914 -46.404534) (xy 237.865648 -46.402497)
			(xy 237.921085 -46.408597) (xy 237.975042 -46.422703) (xy 238.026371 -46.444515) (xy 238.073977 -46.473569)
			(xy 238.116845 -46.509244) (xy 238.154062 -46.550781) (xy 238.184835 -46.597294) (xy 238.208507 -46.647791)
			(xy 238.224575 -46.701198) (xy 238.232695 -46.756374) (xy 238.233204 -46.78426) (xy 238.232695 -46.812146)
			(xy 238.224575 -46.867322) (xy 238.208507 -46.920729) (xy 238.184835 -46.971226) (xy 238.154062 -47.017739)
			(xy 238.116845 -47.059276) (xy 238.073977 -47.094951) (xy 238.026371 -47.124005) (xy 237.975042 -47.145817)
			(xy 237.921085 -47.159923) (xy 237.865648 -47.166023) (xy 237.809914 -47.163986) (xy 237.755071 -47.153856)
			(xy 237.702287 -47.135849) (xy 237.652687 -47.110348) (xy 237.607329 -47.077897) (xy 237.56718 -47.039188)
			(xy 237.533094 -46.995045) (xy 237.505798 -46.94641) (xy 237.485875 -46.894319) (xy 237.473749 -46.839882)
			(xy 237.469678 -46.78426) (xy 234.123769 -46.78426) (xy 234.123532 -46.798307) (xy 234.11578 -46.852262)
			(xy 234.100428 -46.904565) (xy 234.077788 -46.95415) (xy 234.048321 -47.000008) (xy 234.012628 -47.041205)
			(xy 233.971433 -47.076902) (xy 233.925578 -47.106373) (xy 233.875995 -47.129017) (xy 233.823693 -47.144374)
			(xy 233.769739 -47.15213) (xy 233.742484 -47.15256) (xy 233.715147 -47.152092) (xy 233.661031 -47.144293)
			(xy 233.608579 -47.128859) (xy 233.558865 -47.106103) (xy 233.512903 -47.076491) (xy 233.471633 -47.040628)
			(xy 233.453432 -47.020226) (xy 233.443643 -47.009605) (xy 233.419448 -46.993856) (xy 233.391807 -46.985523)
			(xy 233.362938 -46.985273) (xy 233.335157 -46.993128) (xy 233.310692 -47.008456) (xy 233.300778 -47.018956)
			(xy 233.282595 -47.038643) (xy 233.241664 -47.073236) (xy 233.196299 -47.101767) (xy 233.147392 -47.123676)
			(xy 233.095901 -47.138532) (xy 233.042839 -47.146044) (xy 233.016044 -47.146464) (xy 232.988792 -47.146004)
			(xy 232.934843 -47.138253) (xy 232.882546 -47.122902) (xy 232.832966 -47.100265) (xy 232.787112 -47.070802)
			(xy 232.745919 -47.035112) (xy 232.710225 -46.993923) (xy 232.680756 -46.948073) (xy 232.658113 -46.898496)
			(xy 232.642757 -46.8462) (xy 232.634999 -46.792252) (xy 232.634999 -46.737748) (xy 232.642757 -46.6838)
			(xy 232.658113 -46.631504) (xy 232.680756 -46.581927) (xy 232.710225 -46.536077) (xy 232.745919 -46.494888)
			(xy 232.787112 -46.459198) (xy 232.832966 -46.429735) (xy 232.882546 -46.407098) (xy 232.934843 -46.391747)
			(xy 232.988792 -46.383996) (xy 233.016044 -46.383448) (xy 233.043381 -46.383918) (xy 233.097494 -46.39172)
			(xy 233.149943 -46.407158) (xy 233.199654 -46.429917) (xy 233.245612 -46.459531) (xy 233.286879 -46.495395)
			(xy 233.305096 -46.515782) (xy 233.314885 -46.526398) (xy 233.339079 -46.542138) (xy 233.366715 -46.550464)
			(xy 233.395577 -46.550709) (xy 233.423351 -46.542851) (xy 233.447808 -46.527523) (xy 233.45775 -46.517052)
			(xy 233.475985 -46.497296) (xy 233.517049 -46.462595) (xy 233.562581 -46.434007) (xy 233.611677 -46.4121)
			(xy 233.663365 -46.397306) (xy 233.716617 -46.389921) (xy 233.7435 -46.389544) (xy 233.758864 -46.389047)
			(xy 233.788221 -46.37998) (xy 233.81356 -46.362602) (xy 233.832594 -46.338482) (xy 233.843606 -46.309798)
			(xy 233.845602 -46.279138) (xy 233.84256 -46.264068) (xy 233.837589 -46.242115) (xy 233.832239 -46.19742)
			(xy 233.831892 -46.174914) (xy 233.832347 -46.148084) (xy 233.839862 -46.094953) (xy 233.854746 -46.043398)
			(xy 233.876706 -45.994437) (xy 233.905308 -45.949035) (xy 233.922316 -45.92828) (xy 233.931247 -45.91691)
			(xy 233.942943 -45.890484) (xy 233.946765 -45.861839) (xy 233.942405 -45.833272) (xy 233.930213 -45.807071)
			(xy 233.911166 -45.785337) (xy 233.886791 -45.769813) (xy 233.859042 -45.761743) (xy 233.844592 -45.761148)
			(xy 230.371396 -45.761148) (xy 230.331991 -45.814092) (xy 230.247562 -45.915551) (xy 230.157023 -46.011598)
			(xy 230.06072 -46.101865) (xy 229.959022 -46.186006) (xy 229.852318 -46.263701) (xy 229.741015 -46.334651)
			(xy 229.62554 -46.398586) (xy 229.506333 -46.455261) (xy 229.383851 -46.50446) (xy 229.32136 -46.525688)
			(xy 229.30993 -46.529498) (xy 229.11308 -46.726348) (xy 228.07168 -46.726348) (xy 227.805234 -46.459902)
			(xy 227.796598 -46.456092) (xy 227.735817 -46.429024) (xy 227.617399 -46.368327) (xy 227.502992 -46.30037)
			(xy 227.393043 -46.225416) (xy 227.287977 -46.143757) (xy 227.188203 -46.05571) (xy 227.09411 -45.961618)
			(xy 227.006061 -45.861845) (xy 226.924401 -45.756781) (xy 226.849446 -45.646832) (xy 226.781487 -45.532427)
			(xy 226.720788 -45.414009) (xy 226.69373 -45.353224) (xy 226.68992 -45.344588) (xy 226.11588 -44.770548)
			(xy 226.11588 -41.773348) (xy 225.30308 -40.960548) (xy 220.93428 -40.960548) (xy 220.80728 -41.087548)
			(xy 220.80728 -41.620948) (xy 221.688912 -41.620948) (xy 221.692983 -41.565326) (xy 221.705109 -41.510889)
			(xy 221.725032 -41.458798) (xy 221.752328 -41.410163) (xy 221.786414 -41.36602) (xy 221.826563 -41.327311)
			(xy 221.871921 -41.29486) (xy 221.921521 -41.269359) (xy 221.974305 -41.251352) (xy 222.029148 -41.241222)
			(xy 222.084882 -41.239185) (xy 222.140319 -41.245285) (xy 222.194276 -41.259391) (xy 222.245605 -41.281203)
			(xy 222.293211 -41.310257) (xy 222.336079 -41.345932) (xy 222.373296 -41.387469) (xy 222.404069 -41.433982)
			(xy 222.427741 -41.484479) (xy 222.443809 -41.537886) (xy 222.451929 -41.593062) (xy 222.452438 -41.620948)
			(xy 222.451929 -41.648834) (xy 222.443809 -41.70401) (xy 222.427741 -41.757417) (xy 222.404069 -41.807914)
			(xy 222.373296 -41.854427) (xy 222.336079 -41.895964) (xy 222.293211 -41.931639) (xy 222.245605 -41.960693)
			(xy 222.194276 -41.982505) (xy 222.140319 -41.996611) (xy 222.084882 -42.002711) (xy 222.029148 -42.000674)
			(xy 221.974305 -41.990544) (xy 221.921521 -41.972537) (xy 221.871921 -41.947036) (xy 221.826563 -41.914585)
			(xy 221.786414 -41.875876) (xy 221.752328 -41.831733) (xy 221.725032 -41.783098) (xy 221.705109 -41.731007)
			(xy 221.692983 -41.67657) (xy 221.688912 -41.620948) (xy 220.80728 -41.620948) (xy 220.80728 -44.21759)
			(xy 224.733612 -44.21759) (xy 224.734127 -44.18932) (xy 224.742446 -44.133397) (xy 224.758931 -44.079315)
			(xy 224.783219 -44.028259) (xy 224.814779 -43.981349) (xy 224.852919 -43.939612) (xy 224.896803 -43.903963)
			(xy 224.945469 -43.875184) (xy 224.99785 -43.853905) (xy 225.025204 -43.84675) (xy 225.039993 -43.842626)
			(xy 225.066305 -43.826829) (xy 225.086732 -43.803925) (xy 225.09943 -43.775986) (xy 225.103249 -43.745535)
			(xy 225.097845 -43.715324) (xy 225.091244 -43.701462) (xy 225.077771 -43.674191) (xy 225.058745 -43.61642)
			(xy 225.049138 -43.55636) (xy 225.048572 -43.525948) (xy 225.049058 -43.498697) (xy 225.056814 -43.444749)
			(xy 225.072169 -43.392454) (xy 225.094811 -43.342877) (xy 225.124277 -43.297027) (xy 225.159968 -43.255836)
			(xy 225.201159 -43.220145) (xy 225.247009 -43.190679) (xy 225.296586 -43.168037) (xy 225.348881 -43.152682)
			(xy 225.402829 -43.144926) (xy 225.457331 -43.144926) (xy 225.511279 -43.152682) (xy 225.563574 -43.168037)
			(xy 225.613151 -43.190679) (xy 225.659001 -43.220145) (xy 225.700192 -43.255836) (xy 225.735883 -43.297027)
			(xy 225.765349 -43.342877) (xy 225.787991 -43.392454) (xy 225.803346 -43.444749) (xy 225.811102 -43.498697)
			(xy 225.811588 -43.525948) (xy 225.811107 -43.554219) (xy 225.802782 -43.610143) (xy 225.786293 -43.664226)
			(xy 225.762 -43.715282) (xy 225.730435 -43.762193) (xy 225.692292 -43.803929) (xy 225.648404 -43.839577)
			(xy 225.599735 -43.868355) (xy 225.547351 -43.889633) (xy 225.519996 -43.896788) (xy 225.50519 -43.900862)
			(xy 225.478872 -43.916668) (xy 225.458442 -43.939581) (xy 225.445747 -43.967532) (xy 225.441934 -43.997994)
			(xy 225.447348 -44.028211) (xy 225.453956 -44.042076) (xy 225.467407 -44.069357) (xy 225.486441 -44.127123)
			(xy 225.496058 -44.187179) (xy 225.496628 -44.21759) (xy 225.495935 -44.249833) (xy 225.485064 -44.313398)
			(xy 225.463682 -44.374237) (xy 225.448622 -44.402756) (xy 225.442499 -44.414758) (xy 225.436071 -44.440911)
			(xy 225.436702 -44.467835) (xy 225.444349 -44.493659) (xy 225.45848 -44.516585) (xy 225.478113 -44.535021)
			(xy 225.501882 -44.547684) (xy 225.514916 -44.551092) (xy 225.542637 -44.557949) (xy 225.595804 -44.578782)
			(xy 225.64527 -44.607311) (xy 225.689929 -44.642897) (xy 225.728781 -44.684746) (xy 225.760959 -44.73192)
			(xy 225.785741 -44.783365) (xy 225.802575 -44.837931) (xy 225.811084 -44.894396) (xy 225.811588 -44.922948)
			(xy 225.811102 -44.950199) (xy 225.803346 -45.004147) (xy 225.787991 -45.056442) (xy 225.765349 -45.106019)
			(xy 225.735883 -45.151869) (xy 225.700192 -45.19306) (xy 225.659001 -45.228751) (xy 225.613151 -45.258217)
			(xy 225.563574 -45.280859) (xy 225.511279 -45.296214) (xy 225.457331 -45.30397) (xy 225.402829 -45.30397)
			(xy 225.348881 -45.296214) (xy 225.296586 -45.280859) (xy 225.247009 -45.258217) (xy 225.201159 -45.228751)
			(xy 225.159968 -45.19306) (xy 225.124277 -45.151869) (xy 225.094811 -45.106019) (xy 225.072169 -45.056442)
			(xy 225.056814 -45.004147) (xy 225.049058 -44.950199) (xy 225.048572 -44.922948) (xy 225.049281 -44.890705)
			(xy 225.060144 -44.827141) (xy 225.081521 -44.766301) (xy 225.096578 -44.737782) (xy 225.102655 -44.725758)
			(xy 225.109089 -44.699613) (xy 225.108465 -44.672695) (xy 225.100825 -44.646876) (xy 225.086702 -44.623952)
			(xy 225.067076 -44.605518) (xy 225.043315 -44.592855) (xy 225.030284 -44.589446) (xy 225.002547 -44.582646)
			(xy 224.949376 -44.561808) (xy 224.899907 -44.533274) (xy 224.855247 -44.49768) (xy 224.816395 -44.455825)
			(xy 224.78422 -44.408643) (xy 224.759441 -44.35719) (xy 224.742613 -44.302617) (xy 224.734112 -44.246144)
			(xy 224.733612 -44.21759) (xy 220.80728 -44.21759) (xy 220.80728 -46.57598) (xy 220.999302 -46.57598)
			(xy 221.003373 -46.520358) (xy 221.015499 -46.465921) (xy 221.035422 -46.41383) (xy 221.062718 -46.365195)
			(xy 221.096804 -46.321052) (xy 221.136953 -46.282343) (xy 221.182311 -46.249892) (xy 221.231911 -46.224391)
			(xy 221.284695 -46.206384) (xy 221.339538 -46.196254) (xy 221.395272 -46.194217) (xy 221.450709 -46.200317)
			(xy 221.504666 -46.214423) (xy 221.555995 -46.236235) (xy 221.603601 -46.265289) (xy 221.646469 -46.300964)
			(xy 221.683686 -46.342501) (xy 221.714459 -46.389014) (xy 221.738131 -46.439511) (xy 221.754199 -46.492918)
			(xy 221.762319 -46.548094) (xy 221.762828 -46.57598) (xy 221.762319 -46.603866) (xy 221.754199 -46.659042)
			(xy 221.738131 -46.712449) (xy 221.714459 -46.762946) (xy 221.683686 -46.809459) (xy 221.646469 -46.850996)
			(xy 221.603601 -46.886671) (xy 221.555995 -46.915725) (xy 221.504666 -46.937537) (xy 221.450709 -46.951643)
			(xy 221.395272 -46.957743) (xy 221.339538 -46.955706) (xy 221.284695 -46.945576) (xy 221.231911 -46.927569)
			(xy 221.182311 -46.902068) (xy 221.136953 -46.869617) (xy 221.096804 -46.830908) (xy 221.062718 -46.786765)
			(xy 221.035422 -46.73813) (xy 221.015499 -46.686039) (xy 221.003373 -46.631602) (xy 220.999302 -46.57598)
			(xy 220.80728 -46.57598) (xy 220.80728 -47.018702) (xy 221.910908 -47.018702) (xy 221.914979 -46.96308)
			(xy 221.927105 -46.908643) (xy 221.947028 -46.856552) (xy 221.974324 -46.807917) (xy 222.00841 -46.763774)
			(xy 222.048559 -46.725065) (xy 222.093917 -46.692614) (xy 222.143517 -46.667113) (xy 222.196301 -46.649106)
			(xy 222.251144 -46.638976) (xy 222.306878 -46.636939) (xy 222.362315 -46.643039) (xy 222.416272 -46.657145)
			(xy 222.467601 -46.678957) (xy 222.515207 -46.708011) (xy 222.558075 -46.743686) (xy 222.595292 -46.785223)
			(xy 222.626065 -46.831736) (xy 222.649737 -46.882233) (xy 222.665805 -46.93564) (xy 222.673925 -46.990816)
			(xy 222.674434 -47.018702) (xy 222.673925 -47.046588) (xy 222.665805 -47.101764) (xy 222.649737 -47.155171)
			(xy 222.626065 -47.205668) (xy 222.595292 -47.252181) (xy 222.558075 -47.293718) (xy 222.515207 -47.329393)
			(xy 222.467601 -47.358447) (xy 222.416272 -47.380259) (xy 222.362315 -47.394365) (xy 222.306878 -47.400465)
			(xy 222.251144 -47.398428) (xy 222.196301 -47.388298) (xy 222.143517 -47.370291) (xy 222.093917 -47.34479)
			(xy 222.048559 -47.312339) (xy 222.00841 -47.27363) (xy 221.974324 -47.229487) (xy 221.947028 -47.180852)
			(xy 221.927105 -47.128761) (xy 221.914979 -47.074324) (xy 221.910908 -47.018702) (xy 220.80728 -47.018702)
			(xy 220.80728 -47.980346) (xy 230.407462 -47.980346) (xy 230.411533 -47.924724) (xy 230.423659 -47.870287)
			(xy 230.443582 -47.818196) (xy 230.470878 -47.769561) (xy 230.504964 -47.725418) (xy 230.545113 -47.686709)
			(xy 230.590471 -47.654258) (xy 230.640071 -47.628757) (xy 230.692855 -47.61075) (xy 230.747698 -47.60062)
			(xy 230.803432 -47.598583) (xy 230.858869 -47.604683) (xy 230.912826 -47.618789) (xy 230.964155 -47.640601)
			(xy 231.011761 -47.669655) (xy 231.054629 -47.70533) (xy 231.091846 -47.746867) (xy 231.122619 -47.79338)
			(xy 231.146291 -47.843877) (xy 231.162359 -47.897284) (xy 231.170479 -47.95246) (xy 231.170988 -47.980346)
			(xy 231.170479 -48.008232) (xy 231.162359 -48.063408) (xy 231.150133 -48.104044) (xy 235.109764 -48.104044)
			(xy 235.113835 -48.048422) (xy 235.125961 -47.993985) (xy 235.145884 -47.941894) (xy 235.17318 -47.893259)
			(xy 235.207266 -47.849116) (xy 235.247415 -47.810407) (xy 235.292773 -47.777956) (xy 235.342373 -47.752455)
			(xy 235.395157 -47.734448) (xy 235.45 -47.724318) (xy 235.505734 -47.722281) (xy 235.561171 -47.728381)
			(xy 235.615128 -47.742487) (xy 235.666457 -47.764299) (xy 235.714063 -47.793353) (xy 235.756931 -47.829028)
			(xy 235.794148 -47.870565) (xy 235.824921 -47.917078) (xy 235.848593 -47.967575) (xy 235.864661 -48.020982)
			(xy 235.872781 -48.076158) (xy 235.87329 -48.104044) (xy 235.872781 -48.13193) (xy 235.864661 -48.187106)
			(xy 235.848593 -48.240513) (xy 235.824921 -48.29101) (xy 235.794148 -48.337523) (xy 235.756931 -48.37906)
			(xy 235.714063 -48.414735) (xy 235.666457 -48.443789) (xy 235.615128 -48.465601) (xy 235.561171 -48.479707)
			(xy 235.505734 -48.485807) (xy 235.45 -48.48377) (xy 235.395157 -48.47364) (xy 235.342373 -48.455633)
			(xy 235.292773 -48.430132) (xy 235.247415 -48.397681) (xy 235.207266 -48.358972) (xy 235.17318 -48.314829)
			(xy 235.145884 -48.266194) (xy 235.125961 -48.214103) (xy 235.113835 -48.159666) (xy 235.109764 -48.104044)
			(xy 231.150133 -48.104044) (xy 231.146291 -48.116815) (xy 231.122619 -48.167312) (xy 231.091846 -48.213825)
			(xy 231.054629 -48.255362) (xy 231.011761 -48.291037) (xy 230.964155 -48.320091) (xy 230.912826 -48.341903)
			(xy 230.858869 -48.356009) (xy 230.803432 -48.362109) (xy 230.747698 -48.360072) (xy 230.692855 -48.349942)
			(xy 230.640071 -48.331935) (xy 230.590471 -48.306434) (xy 230.545113 -48.273983) (xy 230.504964 -48.235274)
			(xy 230.470878 -48.191131) (xy 230.443582 -48.142496) (xy 230.423659 -48.090405) (xy 230.411533 -48.035968)
			(xy 230.407462 -47.980346) (xy 220.80728 -47.980346) (xy 220.80728 -48.78197) (xy 222.685862 -48.78197)
			(xy 222.689933 -48.726348) (xy 222.702059 -48.671911) (xy 222.721982 -48.61982) (xy 222.749278 -48.571185)
			(xy 222.783364 -48.527042) (xy 222.823513 -48.488333) (xy 222.868871 -48.455882) (xy 222.918471 -48.430381)
			(xy 222.971255 -48.412374) (xy 223.026098 -48.402244) (xy 223.081832 -48.400207) (xy 223.137269 -48.406307)
			(xy 223.191226 -48.420413) (xy 223.242555 -48.442225) (xy 223.290161 -48.471279) (xy 223.333029 -48.506954)
			(xy 223.370246 -48.548491) (xy 223.401019 -48.595004) (xy 223.424691 -48.645501) (xy 223.440759 -48.698908)
			(xy 223.448879 -48.754084) (xy 223.449388 -48.78197) (xy 223.448879 -48.809856) (xy 223.440759 -48.865032)
			(xy 223.424691 -48.918439) (xy 223.401019 -48.968936) (xy 223.370246 -49.015449) (xy 223.333029 -49.056986)
			(xy 223.290161 -49.092661) (xy 223.242555 -49.121715) (xy 223.191226 -49.143527) (xy 223.137269 -49.157633)
			(xy 223.081832 -49.163733) (xy 223.026098 -49.161696) (xy 222.971255 -49.151566) (xy 222.918471 -49.133559)
			(xy 222.868871 -49.108058) (xy 222.823513 -49.075607) (xy 222.783364 -49.036898) (xy 222.749278 -48.992755)
			(xy 222.721982 -48.94412) (xy 222.702059 -48.892029) (xy 222.689933 -48.837592) (xy 222.685862 -48.78197)
			(xy 220.80728 -48.78197) (xy 220.80728 -49.342548) (xy 221.410782 -49.342548) (xy 221.414853 -49.286926)
			(xy 221.426979 -49.232489) (xy 221.446902 -49.180398) (xy 221.474198 -49.131763) (xy 221.508284 -49.08762)
			(xy 221.548433 -49.048911) (xy 221.593791 -49.01646) (xy 221.643391 -48.990959) (xy 221.696175 -48.972952)
			(xy 221.751018 -48.962822) (xy 221.806752 -48.960785) (xy 221.862189 -48.966885) (xy 221.916146 -48.980991)
			(xy 221.967475 -49.002803) (xy 222.015081 -49.031857) (xy 222.057949 -49.067532) (xy 222.095166 -49.109069)
			(xy 222.125939 -49.155582) (xy 222.149611 -49.206079) (xy 222.165679 -49.259486) (xy 222.173799 -49.314662)
			(xy 222.174308 -49.342548) (xy 222.173799 -49.370434) (xy 222.165679 -49.42561) (xy 222.149611 -49.479017)
			(xy 222.125939 -49.529514) (xy 222.095166 -49.576027) (xy 222.057949 -49.617564) (xy 222.015081 -49.653239)
			(xy 221.967475 -49.682293) (xy 221.916146 -49.704105) (xy 221.862189 -49.718211) (xy 221.806752 -49.724311)
			(xy 221.751018 -49.722274) (xy 221.696175 -49.712144) (xy 221.643391 -49.694137) (xy 221.593791 -49.668636)
			(xy 221.548433 -49.636185) (xy 221.508284 -49.597476) (xy 221.474198 -49.553333) (xy 221.446902 -49.504698)
			(xy 221.426979 -49.452607) (xy 221.414853 -49.39817) (xy 221.410782 -49.342548) (xy 220.80728 -49.342548)
			(xy 220.80728 -49.89068) (xy 220.866208 -49.949608) (xy 222.622616 -49.949608) (xy 222.626687 -49.893986)
			(xy 222.638813 -49.839549) (xy 222.658736 -49.787458) (xy 222.686032 -49.738823) (xy 222.720118 -49.69468)
			(xy 222.760267 -49.655971) (xy 222.805625 -49.62352) (xy 222.855225 -49.598019) (xy 222.908009 -49.580012)
			(xy 222.962852 -49.569882) (xy 223.018586 -49.567845) (xy 223.074023 -49.573945) (xy 223.12798 -49.588051)
			(xy 223.179309 -49.609863) (xy 223.226915 -49.638917) (xy 223.269783 -49.674592) (xy 223.307 -49.716129)
			(xy 223.337773 -49.762642) (xy 223.361445 -49.813139) (xy 223.377513 -49.866546) (xy 223.385633 -49.921722)
			(xy 223.386142 -49.949608) (xy 223.385633 -49.977494) (xy 223.377513 -50.03267) (xy 223.361445 -50.086077)
			(xy 223.337773 -50.136574) (xy 223.307 -50.183087) (xy 223.269783 -50.224624) (xy 223.226915 -50.260299)
			(xy 223.179309 -50.289353) (xy 223.12798 -50.311165) (xy 223.074023 -50.325271) (xy 223.018586 -50.331371)
			(xy 222.962852 -50.329334) (xy 222.908009 -50.319204) (xy 222.855225 -50.301197) (xy 222.805625 -50.275696)
			(xy 222.760267 -50.243245) (xy 222.720118 -50.204536) (xy 222.686032 -50.160393) (xy 222.658736 -50.111758)
			(xy 222.638813 -50.059667) (xy 222.626687 -50.00523) (xy 222.622616 -49.949608) (xy 220.866208 -49.949608)
			(xy 221.270576 -50.353976) (xy 221.303596 -50.336196) (xy 221.331363 -50.322103) (xy 221.390345 -50.302155)
			(xy 221.451787 -50.292072) (xy 221.48292 -50.291492) (xy 221.51017 -50.291979) (xy 221.564116 -50.299738)
			(xy 221.616408 -50.315095) (xy 221.665983 -50.337737) (xy 221.711831 -50.367204) (xy 221.753019 -50.402895)
			(xy 221.788708 -50.444085) (xy 221.818172 -50.489935) (xy 221.840812 -50.539511) (xy 221.856166 -50.591804)
			(xy 221.863922 -50.64575) (xy 221.864428 -50.673) (xy 221.863809 -50.704129) (xy 221.853711 -50.765563)
			(xy 221.833797 -50.824551) (xy 221.819724 -50.852324) (xy 221.801944 -50.885344) (xy 221.929198 -51.012598)
			(xy 222.559878 -51.012598) (xy 222.563949 -50.956976) (xy 222.576075 -50.902539) (xy 222.595998 -50.850448)
			(xy 222.623294 -50.801813) (xy 222.65738 -50.75767) (xy 222.697529 -50.718961) (xy 222.742887 -50.68651)
			(xy 222.792487 -50.661009) (xy 222.845271 -50.643002) (xy 222.900114 -50.632872) (xy 222.955848 -50.630835)
			(xy 223.011285 -50.636935) (xy 223.065242 -50.651041) (xy 223.116571 -50.672853) (xy 223.164177 -50.701907)
			(xy 223.207045 -50.737582) (xy 223.244262 -50.779119) (xy 223.275035 -50.825632) (xy 223.298707 -50.876129)
			(xy 223.314775 -50.929536) (xy 223.322895 -50.984712) (xy 223.323404 -51.012598) (xy 223.322895 -51.040484)
			(xy 223.314775 -51.09566) (xy 223.298707 -51.149067) (xy 223.275035 -51.199564) (xy 223.244262 -51.246077)
			(xy 223.207045 -51.287614) (xy 223.164177 -51.323289) (xy 223.116571 -51.352343) (xy 223.065242 -51.374155)
			(xy 223.011285 -51.388261) (xy 222.955848 -51.394361) (xy 222.900114 -51.392324) (xy 222.845271 -51.382194)
			(xy 222.792487 -51.364187) (xy 222.742887 -51.338686) (xy 222.697529 -51.306235) (xy 222.65738 -51.267526)
			(xy 222.623294 -51.223383) (xy 222.595998 -51.174748) (xy 222.576075 -51.122657) (xy 222.563949 -51.06822)
			(xy 222.559878 -51.012598) (xy 221.929198 -51.012598) (xy 224.500948 -53.584348) (xy 227.71608 -53.584348)
		)
		(stroke
			(width 0)
			(type solid)
		)
		(fill yes)
		(layer "In6.Cu")
		(net "P3V3_E1S_0")
	)
	(gr_poly
		(pts
			(xy 286.42437 -19.609308) (xy 298.515786 -19.609308) (xy 298.534074 -19.601688) (xy 301.991776 -16.143986)
			(xy 310.252364 -16.143986) (xy 312.009536 -14.386814) (xy 320.023236 -14.386814) (xy 320.189606 -14.353794)
			(xy 320.702432 -13.840968) (xy 320.702432 -12.899136) (xy 320.655696 -12.8524) (xy 319.911984 -12.8524)
			(xy 319.8901 -12.867866) (xy 319.84286 -12.893165) (xy 319.792544 -12.911601) (xy 319.740141 -12.92281)
			(xy 319.686686 -12.926571) (xy 319.633231 -12.92281) (xy 319.580828 -12.911601) (xy 319.530512 -12.893165)
			(xy 319.483272 -12.867866) (xy 319.461388 -12.8524) (xy 314.831984 -12.8524) (xy 314.8101 -12.867866)
			(xy 314.76286 -12.893165) (xy 314.712544 -12.911601) (xy 314.660141 -12.92281) (xy 314.606686 -12.926571)
			(xy 314.553231 -12.92281) (xy 314.500828 -12.911601) (xy 314.450512 -12.893165) (xy 314.403272 -12.867866)
			(xy 314.381388 -12.8524) (xy 309.751984 -12.8524) (xy 309.7301 -12.867866) (xy 309.68286 -12.893165)
			(xy 309.632544 -12.911601) (xy 309.580141 -12.92281) (xy 309.526686 -12.926571) (xy 309.473231 -12.92281)
			(xy 309.420828 -12.911601) (xy 309.370512 -12.893165) (xy 309.323272 -12.867866) (xy 309.301388 -12.8524)
			(xy 304.671984 -12.8524) (xy 304.6501 -12.867866) (xy 304.60286 -12.893165) (xy 304.552544 -12.911601)
			(xy 304.500141 -12.92281) (xy 304.446686 -12.926571) (xy 304.393231 -12.92281) (xy 304.340828 -12.911601)
			(xy 304.290512 -12.893165) (xy 304.243272 -12.867866) (xy 304.221388 -12.8524) (xy 294.511984 -12.8524)
			(xy 294.4901 -12.867866) (xy 294.44286 -12.893165) (xy 294.392544 -12.911601) (xy 294.340141 -12.92281)
			(xy 294.286686 -12.926571) (xy 294.233231 -12.92281) (xy 294.180828 -12.911601) (xy 294.130512 -12.893165)
			(xy 294.083272 -12.867866) (xy 294.061388 -12.8524) (xy 289.431984 -12.8524) (xy 289.4101 -12.867866)
			(xy 289.36286 -12.893165) (xy 289.312544 -12.911601) (xy 289.260141 -12.92281) (xy 289.206686 -12.926571)
			(xy 289.153231 -12.92281) (xy 289.100828 -12.911601) (xy 289.050512 -12.893165) (xy 289.003272 -12.867866)
			(xy 288.981388 -12.8524) (xy 284.351984 -12.8524) (xy 284.3301 -12.867866) (xy 284.28286 -12.893165)
			(xy 284.232544 -12.911601) (xy 284.180141 -12.92281) (xy 284.126686 -12.926571) (xy 284.073231 -12.92281)
			(xy 284.020828 -12.911601) (xy 283.970512 -12.893165) (xy 283.923272 -12.867866) (xy 283.901388 -12.8524)
			(xy 279.271984 -12.8524) (xy 279.2501 -12.867866) (xy 279.20286 -12.893165) (xy 279.152544 -12.911601)
			(xy 279.100141 -12.92281) (xy 279.046686 -12.926571) (xy 278.993231 -12.92281) (xy 278.940828 -12.911601)
			(xy 278.890512 -12.893165) (xy 278.843272 -12.867866) (xy 278.821388 -12.8524) (xy 274.401026 -12.8524)
			(xy 273.810222 -13.443204) (xy 287.363406 -13.443204) (xy 287.367477 -13.387582) (xy 287.379603 -13.333145)
			(xy 287.399526 -13.281054) (xy 287.426822 -13.232419) (xy 287.460908 -13.188276) (xy 287.501057 -13.149567)
			(xy 287.546415 -13.117116) (xy 287.596015 -13.091615) (xy 287.648799 -13.073608) (xy 287.703642 -13.063478)
			(xy 287.759376 -13.061441) (xy 287.814813 -13.067541) (xy 287.86877 -13.081647) (xy 287.920099 -13.103459)
			(xy 287.967705 -13.132513) (xy 288.010573 -13.168188) (xy 288.04779 -13.209725) (xy 288.078563 -13.256238)
			(xy 288.102235 -13.306735) (xy 288.118303 -13.360142) (xy 288.126423 -13.415318) (xy 288.126932 -13.443204)
			(xy 288.126423 -13.47109) (xy 288.118303 -13.526266) (xy 288.102235 -13.579673) (xy 288.078563 -13.63017)
			(xy 288.04779 -13.676683) (xy 288.010573 -13.71822) (xy 287.967705 -13.753895) (xy 287.920099 -13.782949)
			(xy 287.86877 -13.804761) (xy 287.814813 -13.818867) (xy 287.759376 -13.824967) (xy 287.703642 -13.82293)
			(xy 287.648799 -13.8128) (xy 287.596015 -13.794793) (xy 287.546415 -13.769292) (xy 287.501057 -13.736841)
			(xy 287.460908 -13.698132) (xy 287.426822 -13.653989) (xy 287.399526 -13.605354) (xy 287.379603 -13.553263)
			(xy 287.367477 -13.498826) (xy 287.363406 -13.443204) (xy 273.810222 -13.443204) (xy 273.55673 -13.696696)
			(xy 273.55673 -14.09827) (xy 281.80614 -14.09827) (xy 281.810211 -14.042648) (xy 281.822337 -13.988211)
			(xy 281.84226 -13.93612) (xy 281.869556 -13.887485) (xy 281.903642 -13.843342) (xy 281.943791 -13.804633)
			(xy 281.989149 -13.772182) (xy 282.038749 -13.746681) (xy 282.091533 -13.728674) (xy 282.146376 -13.718544)
			(xy 282.20211 -13.716507) (xy 282.257547 -13.722607) (xy 282.311504 -13.736713) (xy 282.362833 -13.758525)
			(xy 282.410439 -13.787579) (xy 282.453307 -13.823254) (xy 282.490524 -13.864791) (xy 282.521297 -13.911304)
			(xy 282.544969 -13.961801) (xy 282.561037 -14.015208) (xy 282.569157 -14.070384) (xy 282.569666 -14.09827)
			(xy 282.569157 -14.126156) (xy 282.561037 -14.181332) (xy 282.544969 -14.234739) (xy 282.521297 -14.285236)
			(xy 282.490524 -14.331749) (xy 282.453307 -14.373286) (xy 282.410439 -14.408961) (xy 282.362833 -14.438015)
			(xy 282.35098 -14.443052) (xy 301.553848 -14.443052) (xy 301.553848 -14.388548) (xy 301.561604 -14.334597)
			(xy 301.57696 -14.2823) (xy 301.599601 -14.23272) (xy 301.629068 -14.186867) (xy 301.66476 -14.145674)
			(xy 301.705951 -14.10998) (xy 301.751803 -14.080511) (xy 301.801381 -14.057867) (xy 301.853678 -14.042509)
			(xy 301.907628 -14.034749) (xy 301.93488 -14.034262) (xy 301.964249 -14.034826) (xy 302.022294 -14.043825)
			(xy 302.078274 -14.061616) (xy 302.130866 -14.087775) (xy 302.178827 -14.121687) (xy 302.221024 -14.162549)
			(xy 302.239172 -14.185646) (xy 302.248873 -14.197414) (xy 302.273677 -14.215128) (xy 302.302597 -14.224753)
			(xy 302.33307 -14.225435) (xy 302.362392 -14.217115) (xy 302.387964 -14.200529) (xy 302.398176 -14.189202)
			(xy 302.416386 -14.168011) (xy 302.457952 -14.130672) (xy 302.504519 -14.099796) (xy 302.555091 -14.076041)
			(xy 302.608587 -14.059917) (xy 302.663863 -14.051768) (xy 302.6918 -14.05128) (xy 302.719777 -14.051797)
			(xy 302.77513 -14.059987) (xy 302.828691 -14.076177) (xy 302.879312 -14.100019) (xy 302.925907 -14.131001)
			(xy 302.967475 -14.168459) (xy 302.985678 -14.18971) (xy 302.994919 -14.20012) (xy 303.017806 -14.215942)
			(xy 303.044115 -14.225) (xy 303.071892 -14.226621) (xy 303.099075 -14.220686) (xy 303.123648 -14.207635)
			(xy 303.134014 -14.198346) (xy 303.155428 -14.17866) (xy 303.203139 -14.145388) (xy 303.255344 -14.119737)
			(xy 303.310835 -14.1023) (xy 303.368329 -14.093481) (xy 303.397412 -14.092936) (xy 303.426642 -14.093513)
			(xy 303.484415 -14.102445) (xy 303.540151 -14.120083) (xy 303.592545 -14.146015) (xy 303.640371 -14.179634)
			(xy 303.682511 -14.220153) (xy 303.700688 -14.24305) (xy 303.709206 -14.253507) (xy 303.730599 -14.269915)
			(xy 303.755541 -14.280152) (xy 303.782292 -14.283504) (xy 303.808989 -14.279737) (xy 303.833769 -14.269114)
			(xy 303.854904 -14.252376) (xy 303.863248 -14.24178) (xy 303.881374 -14.218207) (xy 303.92367 -14.176413)
			(xy 303.97194 -14.141693) (xy 304.025016 -14.114887) (xy 304.08161 -14.096645) (xy 304.14035 -14.087411)
			(xy 304.17008 -14.08684) (xy 304.197337 -14.087206) (xy 304.251297 -14.094961) (xy 304.303604 -14.110317)
			(xy 304.353193 -14.132962) (xy 304.399054 -14.162433) (xy 304.440255 -14.198131) (xy 304.475955 -14.23933)
			(xy 304.505429 -14.285189) (xy 304.528076 -14.334777) (xy 304.543435 -14.387083) (xy 304.547085 -14.412468)
			(xy 307.726586 -14.412468) (xy 307.730657 -14.356846) (xy 307.742783 -14.302409) (xy 307.762706 -14.250318)
			(xy 307.790002 -14.201683) (xy 307.824088 -14.15754) (xy 307.864237 -14.118831) (xy 307.909595 -14.08638)
			(xy 307.959195 -14.060879) (xy 308.011979 -14.042872) (xy 308.066822 -14.032742) (xy 308.122556 -14.030705)
			(xy 308.177993 -14.036805) (xy 308.23195 -14.050911) (xy 308.283279 -14.072723) (xy 308.330885 -14.101777)
			(xy 308.373753 -14.137452) (xy 308.41097 -14.178989) (xy 308.441743 -14.225502) (xy 308.465415 -14.275999)
			(xy 308.481483 -14.329406) (xy 308.489603 -14.384582) (xy 308.490112 -14.412468) (xy 308.489603 -14.440354)
			(xy 308.481483 -14.49553) (xy 308.465415 -14.548937) (xy 308.441743 -14.599434) (xy 308.41097 -14.645947)
			(xy 308.373753 -14.687484) (xy 308.330885 -14.723159) (xy 308.283279 -14.752213) (xy 308.23195 -14.774025)
			(xy 308.177993 -14.788131) (xy 308.122556 -14.794231) (xy 308.066822 -14.792194) (xy 308.011979 -14.782064)
			(xy 307.959195 -14.764057) (xy 307.909595 -14.738556) (xy 307.864237 -14.706105) (xy 307.824088 -14.667396)
			(xy 307.790002 -14.623253) (xy 307.762706 -14.574618) (xy 307.742783 -14.522527) (xy 307.730657 -14.46809)
			(xy 307.726586 -14.412468) (xy 304.547085 -14.412468) (xy 304.551193 -14.441043) (xy 304.551193 -14.495557)
			(xy 304.543435 -14.549517) (xy 304.528076 -14.601823) (xy 304.505429 -14.651411) (xy 304.475955 -14.69727)
			(xy 304.440255 -14.738469) (xy 304.399054 -14.774167) (xy 304.353193 -14.803638) (xy 304.303604 -14.826283)
			(xy 304.251297 -14.841639) (xy 304.197337 -14.849394) (xy 304.17008 -14.849856) (xy 304.14085 -14.849288)
			(xy 304.083076 -14.840355) (xy 304.02734 -14.822715) (xy 303.974946 -14.796781) (xy 303.92712 -14.763161)
			(xy 303.884981 -14.72264) (xy 303.866804 -14.699742) (xy 303.858295 -14.689278) (xy 303.836899 -14.672871)
			(xy 303.811956 -14.662635) (xy 303.785203 -14.659285) (xy 303.758505 -14.663053) (xy 303.733725 -14.673676)
			(xy 303.712588 -14.690415) (xy 303.704244 -14.701012) (xy 303.686147 -14.724608) (xy 303.643843 -14.766396)
			(xy 303.595565 -14.801112) (xy 303.542484 -14.827913) (xy 303.485886 -14.84615) (xy 303.427144 -14.855382)
			(xy 303.397412 -14.855952) (xy 303.369436 -14.855415) (xy 303.314085 -14.847227) (xy 303.260524 -14.831041)
			(xy 303.209903 -14.807203) (xy 303.163308 -14.776225) (xy 303.121738 -14.738771) (xy 303.103534 -14.717522)
			(xy 303.094281 -14.707123) (xy 303.071398 -14.691296) (xy 303.045092 -14.682234) (xy 303.017317 -14.68061)
			(xy 302.990134 -14.686544) (xy 302.965562 -14.699596) (xy 302.955198 -14.708886) (xy 302.933769 -14.728555)
			(xy 302.886063 -14.761832) (xy 302.833863 -14.787487) (xy 302.778374 -14.804928) (xy 302.720882 -14.81375)
			(xy 302.6918 -14.814296) (xy 302.662429 -14.813763) (xy 302.604382 -14.804759) (xy 302.548401 -14.786964)
			(xy 302.495809 -14.760799) (xy 302.447849 -14.726881) (xy 302.405655 -14.686012) (xy 302.387508 -14.662912)
			(xy 302.377831 -14.651121) (xy 302.353023 -14.633397) (xy 302.324095 -14.623769) (xy 302.293614 -14.62309)
			(xy 302.264286 -14.63142) (xy 302.238713 -14.648021) (xy 302.228504 -14.659356) (xy 302.210295 -14.680549)
			(xy 302.16873 -14.717888) (xy 302.122163 -14.748766) (xy 302.07159 -14.772521) (xy 302.018094 -14.788644)
			(xy 301.962817 -14.796792) (xy 301.93488 -14.797278) (xy 301.907628 -14.796851) (xy 301.853678 -14.789091)
			(xy 301.801381 -14.773733) (xy 301.751803 -14.751089) (xy 301.705951 -14.72162) (xy 301.66476 -14.685926)
			(xy 301.629068 -14.644733) (xy 301.599601 -14.59888) (xy 301.57696 -14.5493) (xy 301.561604 -14.497003)
			(xy 301.553848 -14.443052) (xy 282.35098 -14.443052) (xy 282.311504 -14.459827) (xy 282.257547 -14.473933)
			(xy 282.20211 -14.480033) (xy 282.146376 -14.477996) (xy 282.091533 -14.467866) (xy 282.038749 -14.449859)
			(xy 281.989149 -14.424358) (xy 281.943791 -14.391907) (xy 281.903642 -14.353198) (xy 281.869556 -14.309055)
			(xy 281.84226 -14.26042) (xy 281.822337 -14.208329) (xy 281.810211 -14.153892) (xy 281.80614 -14.09827)
			(xy 273.55673 -14.09827) (xy 273.55673 -15.286482) (xy 301.723804 -15.286482) (xy 301.727875 -15.23086)
			(xy 301.740001 -15.176423) (xy 301.759924 -15.124332) (xy 301.78722 -15.075697) (xy 301.821306 -15.031554)
			(xy 301.861455 -14.992845) (xy 301.906813 -14.960394) (xy 301.956413 -14.934893) (xy 302.009197 -14.916886)
			(xy 302.06404 -14.906756) (xy 302.119774 -14.904719) (xy 302.175211 -14.910819) (xy 302.229168 -14.924925)
			(xy 302.280497 -14.946737) (xy 302.328103 -14.975791) (xy 302.370971 -15.011466) (xy 302.408188 -15.053003)
			(xy 302.438961 -15.099516) (xy 302.462633 -15.150013) (xy 302.478701 -15.20342) (xy 302.486821 -15.258596)
			(xy 302.48733 -15.286482) (xy 302.486821 -15.314368) (xy 302.478701 -15.369544) (xy 302.462633 -15.422951)
			(xy 302.438961 -15.473448) (xy 302.408188 -15.519961) (xy 302.370971 -15.561498) (xy 302.328103 -15.597173)
			(xy 302.280497 -15.626227) (xy 302.229168 -15.648039) (xy 302.175211 -15.662145) (xy 302.119774 -15.668245)
			(xy 302.06404 -15.666208) (xy 302.009197 -15.656078) (xy 301.956413 -15.638071) (xy 301.906813 -15.61257)
			(xy 301.861455 -15.580119) (xy 301.821306 -15.54141) (xy 301.78722 -15.497267) (xy 301.759924 -15.448632)
			(xy 301.740001 -15.396541) (xy 301.727875 -15.342104) (xy 301.723804 -15.286482) (xy 273.55673 -15.286482)
			(xy 273.55673 -17.043908) (xy 274.991066 -17.043908) (xy 274.995137 -16.988286) (xy 275.007263 -16.933849)
			(xy 275.027186 -16.881758) (xy 275.054482 -16.833123) (xy 275.088568 -16.78898) (xy 275.128717 -16.750271)
			(xy 275.174075 -16.71782) (xy 275.223675 -16.692319) (xy 275.276459 -16.674312) (xy 275.331302 -16.664182)
			(xy 275.387036 -16.662145) (xy 275.442473 -16.668245) (xy 275.49643 -16.682351) (xy 275.547759 -16.704163)
			(xy 275.595365 -16.733217) (xy 275.638233 -16.768892) (xy 275.67545 -16.810429) (xy 275.706223 -16.856942)
			(xy 275.729895 -16.907439) (xy 275.745963 -16.960846) (xy 275.754083 -17.016022) (xy 275.754592 -17.043908)
			(xy 275.754083 -17.071794) (xy 275.745963 -17.12697) (xy 275.729895 -17.180377) (xy 275.706223 -17.230874)
			(xy 275.699012 -17.241774) (xy 278.457658 -17.241774) (xy 278.461729 -17.186152) (xy 278.473855 -17.131715)
			(xy 278.493778 -17.079624) (xy 278.521074 -17.030989) (xy 278.55516 -16.986846) (xy 278.595309 -16.948137)
			(xy 278.640667 -16.915686) (xy 278.690267 -16.890185) (xy 278.743051 -16.872178) (xy 278.797894 -16.862048)
			(xy 278.853628 -16.860011) (xy 278.909065 -16.866111) (xy 278.963022 -16.880217) (xy 279.014351 -16.902029)
			(xy 279.061957 -16.931083) (xy 279.101083 -16.963644) (xy 286.625284 -16.963644) (xy 286.625796 -16.936393)
			(xy 286.633547 -16.882444) (xy 286.648897 -16.830147) (xy 286.671534 -16.780568) (xy 286.700996 -16.734715)
			(xy 286.736685 -16.693522) (xy 286.777873 -16.657828) (xy 286.823722 -16.628359) (xy 286.873299 -16.605715)
			(xy 286.925593 -16.590358) (xy 286.979541 -16.5826) (xy 287.006792 -16.582136) (xy 287.007046 -16.582136)
			(xy 287.031074 -16.582522) (xy 287.07875 -16.588566) (xy 287.125292 -16.600539) (xy 287.147762 -16.60906)
			(xy 287.161681 -16.614083) (xy 287.191133 -16.616776) (xy 287.220121 -16.610908) (xy 287.246208 -16.596973)
			(xy 287.267201 -16.576142) (xy 287.281338 -16.550164) (xy 287.28743 -16.521222) (xy 287.2867 -16.506444)
			(xy 287.28543 -16.475456) (xy 287.285925 -16.448209) (xy 287.293686 -16.394271) (xy 287.309044 -16.341986)
			(xy 287.331687 -16.292419) (xy 287.361152 -16.246579) (xy 287.396841 -16.205398) (xy 287.438028 -16.169716)
			(xy 287.483873 -16.140257) (xy 287.533443 -16.117623) (xy 287.58573 -16.102273) (xy 287.63967 -16.094521)
			(xy 287.694163 -16.094523) (xy 287.748102 -16.102281) (xy 287.800388 -16.117635) (xy 287.849957 -16.140273)
			(xy 287.895799 -16.169736) (xy 287.936982 -16.205422) (xy 287.972668 -16.246606) (xy 288.002129 -16.292449)
			(xy 288.024767 -16.342018) (xy 288.040121 -16.394304) (xy 288.047877 -16.448243) (xy 288.047879 -16.502736)
			(xy 288.040125 -16.556675) (xy 288.024775 -16.608962) (xy 288.00214 -16.658533) (xy 287.972681 -16.704377)
			(xy 287.936997 -16.745563) (xy 287.895816 -16.781251) (xy 287.849975 -16.810716) (xy 287.800408 -16.833358)
			(xy 287.748123 -16.848715) (xy 287.694185 -16.856475) (xy 287.666938 -16.856964) (xy 287.666684 -16.856964)
			(xy 287.642655 -16.856599) (xy 287.594979 -16.850547) (xy 287.548437 -16.838565) (xy 287.525968 -16.83004)
			(xy 287.512037 -16.825053) (xy 287.48259 -16.822353) (xy 287.453605 -16.828214) (xy 287.42752 -16.842143)
			(xy 287.406528 -16.86297) (xy 287.392391 -16.888943) (xy 287.3863 -16.91788) (xy 287.38703 -16.932656)
			(xy 287.3883 -16.963644) (xy 287.387786 -16.993121) (xy 287.378711 -17.051373) (xy 287.360784 -17.107536)
			(xy 287.334431 -17.160273) (xy 287.300279 -17.208329) (xy 287.259142 -17.250559) (xy 287.2359 -17.268698)
			(xy 287.225195 -17.277305) (xy 287.208375 -17.299004) (xy 287.19795 -17.324402) (xy 287.194673 -17.35166)
			(xy 287.198781 -17.378805) (xy 287.209979 -17.403872) (xy 287.227454 -17.425047) (xy 287.23844 -17.43329)
			(xy 287.259585 -17.448651) (xy 287.297863 -17.484235) (xy 287.330924 -17.524713) (xy 287.358149 -17.569326)
			(xy 287.379029 -17.617237) (xy 287.393172 -17.667551) (xy 287.400313 -17.719324) (xy 287.400746 -17.745456)
			(xy 287.40026 -17.772707) (xy 287.392504 -17.826655) (xy 287.377149 -17.87895) (xy 287.354507 -17.928527)
			(xy 287.325041 -17.974377) (xy 287.28935 -18.015568) (xy 287.248159 -18.051259) (xy 287.202309 -18.080725)
			(xy 287.152732 -18.103367) (xy 287.100437 -18.118722) (xy 287.046489 -18.126478) (xy 286.991987 -18.126478)
			(xy 286.938039 -18.118722) (xy 286.885744 -18.103367) (xy 286.836167 -18.080725) (xy 286.790317 -18.051259)
			(xy 286.749126 -18.015568) (xy 286.713435 -17.974377) (xy 286.683969 -17.928527) (xy 286.661327 -17.87895)
			(xy 286.645972 -17.826655) (xy 286.638216 -17.772707) (xy 286.63773 -17.745456) (xy 286.638232 -17.715978)
			(xy 286.647308 -17.657725) (xy 286.665237 -17.601561) (xy 286.691592 -17.548824) (xy 286.725746 -17.500769)
			(xy 286.766886 -17.45854) (xy 286.79013 -17.440402) (xy 286.800842 -17.4318) (xy 286.817673 -17.410103)
			(xy 286.828107 -17.384703) (xy 286.831387 -17.35744) (xy 286.827275 -17.33029) (xy 286.816069 -17.305221)
			(xy 286.798582 -17.284049) (xy 286.78759 -17.27581) (xy 286.766452 -17.26044) (xy 286.728172 -17.224858)
			(xy 286.69511 -17.184382) (xy 286.667883 -17.139772) (xy 286.647002 -17.091861) (xy 286.632858 -17.041548)
			(xy 286.625717 -16.989775) (xy 286.625284 -16.963644) (xy 279.101083 -16.963644) (xy 279.104825 -16.966758)
			(xy 279.142042 -17.008295) (xy 279.172815 -17.054808) (xy 279.196487 -17.105305) (xy 279.212555 -17.158712)
			(xy 279.220675 -17.213888) (xy 279.221184 -17.241774) (xy 279.220675 -17.26966) (xy 279.212555 -17.324836)
			(xy 279.196487 -17.378243) (xy 279.172815 -17.42874) (xy 279.142042 -17.475253) (xy 279.104825 -17.51679)
			(xy 279.061957 -17.552465) (xy 279.014351 -17.581519) (xy 278.963022 -17.603331) (xy 278.909065 -17.617437)
			(xy 278.853628 -17.623537) (xy 278.797894 -17.6215) (xy 278.743051 -17.61137) (xy 278.690267 -17.593363)
			(xy 278.640667 -17.567862) (xy 278.595309 -17.535411) (xy 278.55516 -17.496702) (xy 278.521074 -17.452559)
			(xy 278.493778 -17.403924) (xy 278.473855 -17.351833) (xy 278.461729 -17.297396) (xy 278.457658 -17.241774)
			(xy 275.699012 -17.241774) (xy 275.67545 -17.277387) (xy 275.638233 -17.318924) (xy 275.595365 -17.354599)
			(xy 275.547759 -17.383653) (xy 275.49643 -17.405465) (xy 275.442473 -17.419571) (xy 275.387036 -17.425671)
			(xy 275.331302 -17.423634) (xy 275.276459 -17.413504) (xy 275.223675 -17.395497) (xy 275.174075 -17.369996)
			(xy 275.128717 -17.337545) (xy 275.088568 -17.298836) (xy 275.054482 -17.254693) (xy 275.027186 -17.206058)
			(xy 275.007263 -17.153967) (xy 274.995137 -17.09953) (xy 274.991066 -17.043908) (xy 273.55673 -17.043908)
			(xy 273.55673 -17.744948) (xy 282.470858 -17.744948) (xy 282.474929 -17.689326) (xy 282.487055 -17.634889)
			(xy 282.506978 -17.582798) (xy 282.534274 -17.534163) (xy 282.56836 -17.49002) (xy 282.608509 -17.451311)
			(xy 282.653867 -17.41886) (xy 282.703467 -17.393359) (xy 282.756251 -17.375352) (xy 282.811094 -17.365222)
			(xy 282.866828 -17.363185) (xy 282.922265 -17.369285) (xy 282.976222 -17.383391) (xy 283.027551 -17.405203)
			(xy 283.075157 -17.434257) (xy 283.118025 -17.469932) (xy 283.155242 -17.511469) (xy 283.186015 -17.557982)
			(xy 283.209687 -17.608479) (xy 283.225755 -17.661886) (xy 283.233875 -17.717062) (xy 283.234384 -17.744948)
			(xy 283.233875 -17.772834) (xy 283.225755 -17.82801) (xy 283.209687 -17.881417) (xy 283.186015 -17.931914)
			(xy 283.155242 -17.978427) (xy 283.118025 -18.019964) (xy 283.075157 -18.055639) (xy 283.027551 -18.084693)
			(xy 282.976222 -18.106505) (xy 282.922265 -18.120611) (xy 282.866828 -18.126711) (xy 282.811094 -18.124674)
			(xy 282.756251 -18.114544) (xy 282.703467 -18.096537) (xy 282.653867 -18.071036) (xy 282.608509 -18.038585)
			(xy 282.56836 -17.999876) (xy 282.534274 -17.955733) (xy 282.506978 -17.907098) (xy 282.487055 -17.855007)
			(xy 282.474929 -17.80057) (xy 282.470858 -17.744948) (xy 273.55673 -17.744948) (xy 273.55673 -18.714466)
			(xy 290.601144 -18.714466) (xy 290.605215 -18.658844) (xy 290.617341 -18.604407) (xy 290.637264 -18.552316)
			(xy 290.66456 -18.503681) (xy 290.698646 -18.459538) (xy 290.738795 -18.420829) (xy 290.784153 -18.388378)
			(xy 290.833753 -18.362877) (xy 290.886537 -18.34487) (xy 290.94138 -18.33474) (xy 290.997114 -18.332703)
			(xy 291.052551 -18.338803) (xy 291.106508 -18.352909) (xy 291.157837 -18.374721) (xy 291.205443 -18.403775)
			(xy 291.248311 -18.43945) (xy 291.285528 -18.480987) (xy 291.316301 -18.5275) (xy 291.339973 -18.577997)
			(xy 291.356041 -18.631404) (xy 291.364161 -18.68658) (xy 291.36467 -18.714466) (xy 291.364161 -18.742352)
			(xy 291.356041 -18.797528) (xy 291.339973 -18.850935) (xy 291.316301 -18.901432) (xy 291.285528 -18.947945)
			(xy 291.248311 -18.989482) (xy 291.205443 -19.025157) (xy 291.157837 -19.054211) (xy 291.106508 -19.076023)
			(xy 291.052551 -19.090129) (xy 290.997114 -19.096229) (xy 290.94138 -19.094192) (xy 290.886537 -19.084062)
			(xy 290.833753 -19.066055) (xy 290.784153 -19.040554) (xy 290.738795 -19.008103) (xy 290.698646 -18.969394)
			(xy 290.66456 -18.925251) (xy 290.637264 -18.876616) (xy 290.617341 -18.824525) (xy 290.605215 -18.770088)
			(xy 290.601144 -18.714466) (xy 273.55673 -18.714466) (xy 273.55673 -19.929094) (xy 279.668476 -19.929094)
			(xy 279.672547 -19.873472) (xy 279.684673 -19.819035) (xy 279.704596 -19.766944) (xy 279.731892 -19.718309)
			(xy 279.765978 -19.674166) (xy 279.806127 -19.635457) (xy 279.851485 -19.603006) (xy 279.901085 -19.577505)
			(xy 279.953869 -19.559498) (xy 280.008712 -19.549368) (xy 280.064446 -19.547331) (xy 280.119883 -19.553431)
			(xy 280.17384 -19.567537) (xy 280.225169 -19.589349) (xy 280.272775 -19.618403) (xy 280.315643 -19.654078)
			(xy 280.35286 -19.695615) (xy 280.383633 -19.742128) (xy 280.407305 -19.792625) (xy 280.423373 -19.846032)
			(xy 280.431493 -19.901208) (xy 280.432002 -19.929094) (xy 280.431493 -19.95698) (xy 280.423373 -20.012156)
			(xy 280.407305 -20.065563) (xy 280.383633 -20.11606) (xy 280.35286 -20.162573) (xy 280.315643 -20.20411)
			(xy 280.272775 -20.239785) (xy 280.225169 -20.268839) (xy 280.17384 -20.290651) (xy 280.119883 -20.304757)
			(xy 280.064446 -20.310857) (xy 280.008712 -20.30882) (xy 279.953869 -20.29869) (xy 279.901085 -20.280683)
			(xy 279.851485 -20.255182) (xy 279.806127 -20.222731) (xy 279.765978 -20.184022) (xy 279.731892 -20.139879)
			(xy 279.704596 -20.091244) (xy 279.684673 -20.039153) (xy 279.672547 -19.984716) (xy 279.668476 -19.929094)
			(xy 273.55673 -19.929094) (xy 273.55673 -20.470368) (xy 281.309062 -20.470368) (xy 281.313133 -20.414746)
			(xy 281.325259 -20.360309) (xy 281.345182 -20.308218) (xy 281.372478 -20.259583) (xy 281.406564 -20.21544)
			(xy 281.446713 -20.176731) (xy 281.492071 -20.14428) (xy 281.541671 -20.118779) (xy 281.594455 -20.100772)
			(xy 281.649298 -20.090642) (xy 281.705032 -20.088605) (xy 281.760469 -20.094705) (xy 281.814426 -20.108811)
			(xy 281.865755 -20.130623) (xy 281.913361 -20.159677) (xy 281.956229 -20.195352) (xy 281.993446 -20.236889)
			(xy 282.024219 -20.283402) (xy 282.047891 -20.333899) (xy 282.063959 -20.387306) (xy 282.072079 -20.442482)
			(xy 282.072588 -20.470368) (xy 282.072079 -20.498254) (xy 282.063959 -20.55343) (xy 282.047891 -20.606837)
			(xy 282.024219 -20.657334) (xy 281.993446 -20.703847) (xy 281.956229 -20.745384) (xy 281.913361 -20.781059)
			(xy 281.865755 -20.810113) (xy 281.814426 -20.831925) (xy 281.760469 -20.846031) (xy 281.705032 -20.852131)
			(xy 281.649298 -20.850094) (xy 281.594455 -20.839964) (xy 281.541671 -20.821957) (xy 281.492071 -20.796456)
			(xy 281.446713 -20.764005) (xy 281.406564 -20.725296) (xy 281.372478 -20.681153) (xy 281.345182 -20.632518)
			(xy 281.325259 -20.580427) (xy 281.313133 -20.52599) (xy 281.309062 -20.470368) (xy 273.55673 -20.470368)
			(xy 273.55673 -21.705316) (xy 274.134326 -22.282912) (xy 283.750766 -22.282912)
		)
		(stroke
			(width 0)
			(type solid)
		)
		(fill yes)
		(layer "In6.Cu")
		(net "P3V3_AUX")
	)
	(gr_poly
		(pts
			(arc
				(start 194.443604 -441.479432)
				(mid 194.479525 -441.464553)
				(end 194.494404 -441.428632)
			)
			(arc
				(start 194.494404 -441.17006)
				(mid 194.790421 -440.455411)
				(end 195.50507 -440.159394)
			)
			(arc
				(start 276.314916 -440.159394)
				(mid 277.029565 -440.455411)
				(end 277.325582 -441.17006)
			)
			(arc
				(start 277.325582 -441.428632)
				(mid 277.340461 -441.464553)
				(end 277.376382 -441.479432)
			)
			(arc
				(start 463.300064 -441.479432)
				(mid 464.353268 -441.04318)
				(end 464.78952 -439.989976)
			)
			(arc
				(start 464.78952 -409.528264)
				(mid 464.980687 -408.567674)
				(end 465.52485 -407.753312)
			)
			(arc
				(start 467.353396 -405.924766)
				(mid 467.676179 -405.441593)
				(end 467.789514 -404.871682)
			)
			(xy 467.789514 -334.500982) (xy 467.75624 -334.467708) (xy 467.41588 -334.467708) (xy 467.282276 -334.601312)
			(arc
				(start 467.282276 -358.935274)
				(mid 467.28295 -358.943778)
				(end 467.28507 -358.952038)
			)
			(arc
				(start 467.28507 -358.952038)
				(mid 467.514132 -359.845086)
				(end 467.59114 -360.76382)
			)
			(arc
				(start 467.59114 -360.76382)
				(mid 467.514124 -361.682553)
				(end 467.28507 -362.575602)
			)
			(arc
				(start 467.28507 -362.575602)
				(mid 467.282984 -362.583868)
				(end 467.282276 -362.592366)
			)
			(arc
				(start 467.282276 -404.871936)
				(mid 467.207495 -405.247595)
				(end 466.994748 -405.566118)
			)
			(arc
				(start 465.166202 -407.394664)
				(mid 464.5119 -408.373524)
				(end 464.282028 -409.528264)
			)
			(arc
				(start 464.282028 -439.989976)
				(mid 463.994417 -440.684329)
				(end 463.300064 -440.97194)
			)
			(xy 410.917898 -440.97194)
			(arc
				(start 410.910024 -440.974734)
				(mid 410.831038 -440.993945)
				(end 410.750004 -441.000388)
			)
			(arc
				(start 410.750004 -441.000388)
				(mid 410.668968 -440.993957)
				(end 410.589984 -440.974734)
			)
			(xy 410.58211 -440.97194) (xy 406.917906 -440.97194)
			(arc
				(start 406.910032 -440.974734)
				(mid 406.831046 -440.993945)
				(end 406.750012 -441.000388)
			)
			(arc
				(start 406.750012 -441.000388)
				(mid 406.668976 -440.993957)
				(end 406.589992 -440.974734)
			)
			(xy 406.582118 -440.97194) (xy 402.917914 -440.97194)
			(arc
				(start 402.91004 -440.974734)
				(mid 402.831054 -440.993945)
				(end 402.75002 -441.000388)
			)
			(arc
				(start 402.75002 -441.000388)
				(mid 402.668984 -440.993957)
				(end 402.59 -440.974734)
			)
			(xy 402.582126 -440.97194) (xy 398.917922 -440.97194)
			(arc
				(start 398.910048 -440.974734)
				(mid 398.831062 -440.993945)
				(end 398.750028 -441.000388)
			)
			(arc
				(start 398.750028 -441.000388)
				(mid 398.668992 -440.993957)
				(end 398.590008 -440.974734)
			)
			(xy 398.582134 -440.97194) (xy 393.917932 -440.97194)
			(arc
				(start 393.910058 -440.974734)
				(mid 393.831072 -440.993945)
				(end 393.750038 -441.000388)
			)
			(arc
				(start 393.750038 -441.000388)
				(mid 393.669002 -440.993957)
				(end 393.590018 -440.974734)
			)
			(xy 393.582144 -440.97194) (xy 389.91794 -440.97194)
			(arc
				(start 389.910066 -440.974734)
				(mid 389.83108 -440.993945)
				(end 389.750046 -441.000388)
			)
			(arc
				(start 389.750046 -441.000388)
				(mid 389.66901 -440.993957)
				(end 389.590026 -440.974734)
			)
			(xy 389.582152 -440.97194) (xy 385.917948 -440.97194)
			(arc
				(start 385.910074 -440.974734)
				(mid 385.831088 -440.993945)
				(end 385.750054 -441.000388)
			)
			(arc
				(start 385.750054 -441.000388)
				(mid 385.669018 -440.993957)
				(end 385.590034 -440.974734)
			)
			(xy 385.58216 -440.97194) (xy 381.917956 -440.97194)
			(arc
				(start 381.910082 -440.974734)
				(mid 381.831096 -440.993945)
				(end 381.750062 -441.000388)
			)
			(arc
				(start 381.750062 -441.000388)
				(mid 381.669026 -440.993957)
				(end 381.590042 -440.974734)
			)
			(xy 381.582168 -440.97194) (xy 343.817956 -440.97194)
			(arc
				(start 343.810082 -440.974734)
				(mid 343.731096 -440.993945)
				(end 343.650062 -441.000388)
			)
			(arc
				(start 343.650062 -441.000388)
				(mid 343.569026 -440.993957)
				(end 343.490042 -440.974734)
			)
			(xy 343.482168 -440.97194) (xy 339.817964 -440.97194)
			(arc
				(start 339.81009 -440.974734)
				(mid 339.731104 -440.993945)
				(end 339.65007 -441.000388)
			)
			(arc
				(start 339.65007 -441.000388)
				(mid 339.569034 -440.993957)
				(end 339.49005 -440.974734)
			)
			(xy 339.482176 -440.97194) (xy 335.817972 -440.97194)
			(arc
				(start 335.810098 -440.974734)
				(mid 335.731112 -440.993945)
				(end 335.650078 -441.000388)
			)
			(arc
				(start 335.650078 -441.000388)
				(mid 335.569042 -440.993957)
				(end 335.490058 -440.974734)
			)
			(xy 335.482184 -440.97194) (xy 331.81798 -440.97194)
			(arc
				(start 331.810106 -440.974734)
				(mid 331.73112 -440.993945)
				(end 331.650086 -441.000388)
			)
			(arc
				(start 331.650086 -441.000388)
				(mid 331.56905 -440.993957)
				(end 331.490066 -440.974734)
			)
			(xy 331.482192 -440.97194) (xy 326.81799 -440.97194)
			(arc
				(start 326.810116 -440.974734)
				(mid 326.73113 -440.993945)
				(end 326.650096 -441.000388)
			)
			(arc
				(start 326.650096 -441.000388)
				(mid 326.56906 -440.993957)
				(end 326.490076 -440.974734)
			)
			(xy 326.482202 -440.97194) (xy 322.817998 -440.97194)
			(arc
				(start 322.810124 -440.974734)
				(mid 322.731138 -440.993945)
				(end 322.650104 -441.000388)
			)
			(arc
				(start 322.650104 -441.000388)
				(mid 322.569068 -440.993957)
				(end 322.490084 -440.974734)
			)
			(xy 322.48221 -440.97194) (xy 318.818006 -440.97194)
			(arc
				(start 318.810132 -440.974734)
				(mid 318.731146 -440.993945)
				(end 318.650112 -441.000388)
			)
			(arc
				(start 318.650112 -441.000388)
				(mid 318.569076 -440.993957)
				(end 318.490092 -440.974734)
			)
			(xy 318.482218 -440.97194) (xy 314.818014 -440.97194)
			(arc
				(start 314.81014 -440.974734)
				(mid 314.731154 -440.993945)
				(end 314.65012 -441.000388)
			)
			(arc
				(start 314.65012 -441.000388)
				(mid 314.569084 -440.993957)
				(end 314.4901 -440.974734)
			)
			(xy 314.482226 -440.97194)
			(arc
				(start 277.82012 -440.97194)
				(mid 277.31587 -440.028787)
				(end 276.314916 -439.652156)
			)
			(arc
				(start 195.50507 -439.652156)
				(mid 194.504157 -440.028834)
				(end 193.999866 -440.97194)
			)
			(xy 154.917902 -440.97194)
			(arc
				(start 154.910028 -440.974734)
				(mid 154.831042 -440.993945)
				(end 154.750008 -441.000388)
			)
			(arc
				(start 154.750008 -441.000388)
				(mid 154.668972 -440.993957)
				(end 154.589988 -440.974734)
			)
			(xy 154.582114 -440.97194) (xy 150.91791 -440.97194)
			(arc
				(start 150.910036 -440.974734)
				(mid 150.83105 -440.993945)
				(end 150.750016 -441.000388)
			)
			(arc
				(start 150.750016 -441.000388)
				(mid 150.66898 -440.993957)
				(end 150.589996 -440.974734)
			)
			(xy 150.582122 -440.97194) (xy 146.917918 -440.97194)
			(arc
				(start 146.910044 -440.974734)
				(mid 146.831058 -440.993945)
				(end 146.750024 -441.000388)
			)
			(arc
				(start 146.750024 -441.000388)
				(mid 146.668988 -440.993957)
				(end 146.590004 -440.974734)
			)
			(xy 146.58213 -440.97194) (xy 142.917926 -440.97194)
			(arc
				(start 142.910052 -440.974734)
				(mid 142.831066 -440.993945)
				(end 142.750032 -441.000388)
			)
			(arc
				(start 142.750032 -441.000388)
				(mid 142.668996 -440.993957)
				(end 142.590012 -440.974734)
			)
			(xy 142.582138 -440.97194) (xy 137.917936 -440.97194)
			(arc
				(start 137.910062 -440.974734)
				(mid 137.831076 -440.993945)
				(end 137.750042 -441.000388)
			)
			(arc
				(start 137.750042 -441.000388)
				(mid 137.669006 -440.993957)
				(end 137.590022 -440.974734)
			)
			(xy 137.582148 -440.97194) (xy 133.917944 -440.97194)
			(arc
				(start 133.91007 -440.974734)
				(mid 133.831084 -440.993945)
				(end 133.75005 -441.000388)
			)
			(arc
				(start 133.75005 -441.000388)
				(mid 133.669014 -440.993957)
				(end 133.59003 -440.974734)
			)
			(xy 133.582156 -440.97194) (xy 129.917952 -440.97194)
			(arc
				(start 129.910078 -440.974734)
				(mid 129.831092 -440.993945)
				(end 129.750058 -441.000388)
			)
			(arc
				(start 129.750058 -441.000388)
				(mid 129.669022 -440.993957)
				(end 129.590038 -440.974734)
			)
			(xy 129.582164 -440.97194) (xy 125.91796 -440.97194)
			(arc
				(start 125.910086 -440.974734)
				(mid 125.8311 -440.993945)
				(end 125.750066 -441.000388)
			)
			(arc
				(start 125.750066 -441.000388)
				(mid 125.66903 -440.993957)
				(end 125.590046 -440.974734)
			)
			(xy 125.582172 -440.97194) (xy 87.81796 -440.97194)
			(arc
				(start 87.810086 -440.974734)
				(mid 87.7311 -440.993945)
				(end 87.650066 -441.000388)
			)
			(arc
				(start 87.650066 -441.000388)
				(mid 87.56903 -440.993957)
				(end 87.490046 -440.974734)
			)
			(xy 87.482172 -440.97194) (xy 83.817968 -440.97194)
			(arc
				(start 83.810094 -440.974734)
				(mid 83.731108 -440.993945)
				(end 83.650074 -441.000388)
			)
			(arc
				(start 83.650074 -441.000388)
				(mid 83.569038 -440.993957)
				(end 83.490054 -440.974734)
			)
			(xy 83.48218 -440.97194) (xy 79.817976 -440.97194)
			(arc
				(start 79.810102 -440.974734)
				(mid 79.731116 -440.993945)
				(end 79.650082 -441.000388)
			)
			(arc
				(start 79.650082 -441.000388)
				(mid 79.569046 -440.993957)
				(end 79.490062 -440.974734)
			)
			(xy 79.482188 -440.97194) (xy 75.817984 -440.97194)
			(arc
				(start 75.81011 -440.974734)
				(mid 75.731124 -440.993945)
				(end 75.65009 -441.000388)
			)
			(arc
				(start 75.65009 -441.000388)
				(mid 75.569054 -440.993957)
				(end 75.49007 -440.974734)
			)
			(xy 75.482196 -440.97194) (xy 70.817994 -440.97194)
			(arc
				(start 70.81012 -440.974734)
				(mid 70.731134 -440.993945)
				(end 70.6501 -441.000388)
			)
			(arc
				(start 70.6501 -441.000388)
				(mid 70.569064 -440.993957)
				(end 70.49008 -440.974734)
			)
			(xy 70.482206 -440.97194) (xy 66.818002 -440.97194)
			(arc
				(start 66.810128 -440.974734)
				(mid 66.731142 -440.993945)
				(end 66.650108 -441.000388)
			)
			(arc
				(start 66.650108 -441.000388)
				(mid 66.569072 -440.993957)
				(end 66.490088 -440.974734)
			)
			(xy 66.482214 -440.97194) (xy 62.81801 -440.97194)
			(arc
				(start 62.810136 -440.974734)
				(mid 62.73115 -440.993945)
				(end 62.650116 -441.000388)
			)
			(arc
				(start 62.650116 -441.000388)
				(mid 62.56908 -440.993957)
				(end 62.490096 -440.974734)
			)
			(xy 62.482222 -440.97194) (xy 58.818018 -440.97194)
			(arc
				(start 58.810144 -440.974734)
				(mid 58.731158 -440.993945)
				(end 58.650124 -441.000388)
			)
			(arc
				(start 58.650124 -441.000388)
				(mid 58.569088 -440.993957)
				(end 58.490104 -440.974734)
			)
			(xy 58.48223 -440.97194)
			(arc
				(start 8.50011 -440.97194)
				(mid 7.805667 -440.684345)
				(end 7.517892 -439.989976)
			)
			(arc
				(start 7.517892 -409.528264)
				(mid 7.287997 -408.373534)
				(end 6.633718 -407.394664)
			)
			(arc
				(start 3.305302 -404.066248)
				(mid 3.092701 -403.747829)
				(end 3.018028 -403.37232)
			)
			(arc
				(start 3.018028 -81.32826)
				(mid 2.788133 -80.17353)
				(end 2.133854 -79.19466)
			)
			(arc
				(start 1.305306 -78.366112)
				(mid 1.092705 -78.047693)
				(end 1.018032 -77.672184)
			)
			(arc
				(start 1.018032 -42.244772)
				(mid 1.013298 -42.223357)
				(end 0.999998 -42.20591)
			)
			(arc
				(start 0.999998 -42.20591)
				(mid 0.873253 -41.933622)
				(end 0.999998 -41.661334)
			)
			(arc
				(start 0.999998 -41.661334)
				(mid 1.013327 -41.6439)
				(end 1.018032 -41.622472)
			)
			(arc
				(start 1.018032 -41.222422)
				(mid 1.013298 -41.201007)
				(end 0.999998 -41.18356)
			)
			(arc
				(start 0.999998 -41.18356)
				(mid 0.873253 -40.911272)
				(end 0.999998 -40.638984)
			)
			(arc
				(start 0.999998 -40.638984)
				(mid 1.013327 -40.62155)
				(end 1.018032 -40.600122)
			)
			(arc
				(start 1.018032 -40.167814)
				(mid 1.012748 -40.145255)
				(end 0.997966 -40.127428)
			)
			(arc
				(start 0.997966 -40.127428)
				(mid 0.84779 -39.824152)
				(end 0.997966 -39.520876)
			)
			(arc
				(start 0.997966 -39.520876)
				(mid 1.012704 -39.503027)
				(end 1.018032 -39.48049)
			)
			(arc
				(start 1.018032 -39.099998)
				(mid 1.013298 -39.078583)
				(end 0.999998 -39.061136)
			)
			(arc
				(start 0.999998 -39.061136)
				(mid 0.873253 -38.788848)
				(end 0.999998 -38.51656)
			)
			(arc
				(start 0.999998 -38.51656)
				(mid 1.013327 -38.499126)
				(end 1.018032 -38.477698)
			)
			(arc
				(start 1.018032 -38.110414)
				(mid 1.011311 -38.085415)
				(end 0.99314 -38.06698)
			)
			(arc
				(start 0.99314 -38.06698)
				(mid 0.807128 -37.73932)
				(end 0.99314 -37.41166)
			)
			(arc
				(start 0.99314 -37.41166)
				(mid 1.011304 -37.393221)
				(end 1.018032 -37.368226)
			)
			(arc
				(start 1.018032 -37.067236)
				(mid 1.011311 -37.042237)
				(end 0.99314 -37.023802)
			)
			(arc
				(start 0.99314 -37.023802)
				(mid 0.807128 -36.696142)
				(end 0.99314 -36.368482)
			)
			(arc
				(start 0.99314 -36.368482)
				(mid 1.011304 -36.350043)
				(end 1.018032 -36.325048)
			)
			(arc
				(start 1.018032 -35.987228)
				(mid 1.011311 -35.962229)
				(end 0.99314 -35.943794)
			)
			(arc
				(start 0.99314 -35.943794)
				(mid 0.807128 -35.616134)
				(end 0.99314 -35.288474)
			)
			(arc
				(start 0.99314 -35.288474)
				(mid 1.011304 -35.270035)
				(end 1.018032 -35.24504)
			)
			(arc
				(start 1.018032 -26.980642)
				(mid 1.010858 -26.954615)
				(end 0.991362 -26.935938)
			)
			(arc
				(start 0.991362 -26.935938)
				(mid 0.827352 -26.84333)
				(end 0.66675 -26.74493)
			)
			(xy 0.654812 -26.73731) (xy 0.62738 -26.736294)
			(arc
				(start 0.536956 -26.786078)
				(mid 0.517713 -26.8047)
				(end 0.51054 -26.830528)
			)
			(arc
				(start 0.51054 -77.671676)
				(mid 0.623884 -78.241583)
				(end 0.946658 -78.72476)
			)
			(arc
				(start 1.775206 -79.553308)
				(mid 2.319424 -80.367648)
				(end 2.510536 -81.32826)
			)
			(arc
				(start 2.510536 -403.371812)
				(mid 2.62388 -403.941719)
				(end 2.946654 -404.424896)
			)
			(arc
				(start 6.27507 -407.753312)
				(mid 6.819424 -408.567623)
				(end 7.010654 -409.528264)
			)
			(arc
				(start 7.010654 -439.989976)
				(mid 7.446906 -441.04318)
				(end 8.50011 -441.479432)
			)
		)
		(stroke
			(width 0)
			(type solid)
		)
		(fill yes)
		(layer "In6.Cu")
		(net "GND")
	)
	(gr_poly
		(pts
			(xy 94.107 -189.829948) (xy 94.107 -173.787054) (xy 94.105984 -173.782228) (xy 94.102635 -173.763998)
			(xy 94.099077 -173.727102) (xy 94.098872 -173.708568) (xy 94.099081 -173.690034) (xy 94.102644 -173.653139)
			(xy 94.105984 -173.634908) (xy 94.107 -173.630082) (xy 94.107 -158.587948) (xy 92.71 -157.190948)
			(xy 77.089 -157.190948) (xy 76.708 -157.571948) (xy 76.708 -160.746948) (xy 77.343 -161.381948) (xy 77.343 -175.288956)
			(xy 90.966798 -175.288956) (xy 90.967181 -175.262774) (xy 90.974324 -175.2109) (xy 90.988497 -175.160492)
			(xy 91.009435 -175.112497) (xy 91.036742 -175.067817) (xy 91.069906 -175.027295) (xy 91.108302 -174.991691)
			(xy 91.151208 -174.961675) (xy 91.174316 -174.949358) (xy 91.186494 -174.942722) (xy 91.206898 -174.923945)
			(xy 91.221497 -174.900372) (xy 91.229215 -174.873739) (xy 91.229483 -174.846013) (xy 91.22228 -174.819236)
			(xy 91.208139 -174.795385) (xy 91.188101 -174.776219) (xy 91.176094 -174.769272) (xy 91.150385 -174.754926)
			(xy 91.103329 -174.719546) (xy 91.062272 -174.677353) (xy 91.028191 -174.629349) (xy 91.001895 -174.576675)
			(xy 90.984011 -174.520585) (xy 90.974963 -174.462412) (xy 90.974418 -174.432976) (xy 90.974904 -174.405725)
			(xy 90.98266 -174.351777) (xy 90.998015 -174.299482) (xy 91.020657 -174.249905) (xy 91.050123 -174.204055)
			(xy 91.085814 -174.162864) (xy 91.127005 -174.127173) (xy 91.172855 -174.097707) (xy 91.222432 -174.075065)
			(xy 91.274727 -174.05971) (xy 91.328675 -174.051954) (xy 91.383177 -174.051954) (xy 91.437125 -174.05971)
			(xy 91.48942 -174.075065) (xy 91.538997 -174.097707) (xy 91.584847 -174.127173) (xy 91.626038 -174.162864)
			(xy 91.661729 -174.204055) (xy 91.691195 -174.249905) (xy 91.713837 -174.299482) (xy 91.729192 -174.351777)
			(xy 91.736948 -174.405725) (xy 91.737434 -174.432976) (xy 91.73706 -174.459158) (xy 91.729914 -174.511031)
			(xy 91.715737 -174.561439) (xy 91.694798 -174.609434) (xy 91.667489 -174.654112) (xy 91.634325 -174.694635)
			(xy 91.595929 -174.730239) (xy 91.553023 -174.760256) (xy 91.529916 -174.772574) (xy 91.517795 -174.779308)
			(xy 91.497391 -174.798065) (xy 91.482788 -174.82162) (xy 91.475064 -174.848237) (xy 91.474788 -174.87595)
			(xy 91.481981 -174.902715) (xy 91.496111 -174.926557) (xy 91.516137 -174.945716) (xy 91.528138 -174.95266)
			(xy 91.553868 -174.96697) (xy 91.600923 -175.002357) (xy 91.641978 -175.044557) (xy 91.676056 -175.092567)
			(xy 91.702348 -175.145246) (xy 91.720228 -175.201341) (xy 91.729271 -175.259518) (xy 91.729814 -175.288956)
			(xy 91.729328 -175.316207) (xy 91.721572 -175.370155) (xy 91.706217 -175.42245) (xy 91.683575 -175.472027)
			(xy 91.654109 -175.517877) (xy 91.618418 -175.559068) (xy 91.577227 -175.594759) (xy 91.531377 -175.624225)
			(xy 91.4818 -175.646867) (xy 91.429505 -175.662222) (xy 91.375557 -175.669978) (xy 91.321055 -175.669978)
			(xy 91.267107 -175.662222) (xy 91.214812 -175.646867) (xy 91.165235 -175.624225) (xy 91.119385 -175.594759)
			(xy 91.078194 -175.559068) (xy 91.042503 -175.517877) (xy 91.013037 -175.472027) (xy 90.990395 -175.42245)
			(xy 90.97504 -175.370155) (xy 90.967284 -175.316207) (xy 90.966798 -175.288956) (xy 77.343 -175.288956)
			(xy 77.343 -177.126392) (xy 91.846146 -177.126392) (xy 91.84664 -177.100014) (xy 91.853893 -177.04776)
			(xy 91.868272 -176.997003) (xy 91.889505 -176.94871) (xy 91.917185 -176.9038) (xy 91.950787 -176.863131)
			(xy 91.989669 -176.827476) (xy 92.033091 -176.797516) (xy 92.056458 -176.78527) (xy 92.068824 -176.778581)
			(xy 92.089556 -176.759604) (xy 92.104318 -176.735687) (xy 92.11199 -176.708649) (xy 92.111989 -176.680544)
			(xy 92.104315 -176.653506) (xy 92.089551 -176.629591) (xy 92.068818 -176.610615) (xy 92.056458 -176.603914)
			(xy 92.033075 -176.591696) (xy 91.989652 -176.561729) (xy 91.950768 -176.52607) (xy 91.917164 -176.485397)
			(xy 91.889479 -176.440485) (xy 91.86824 -176.392189) (xy 91.853853 -176.341429) (xy 91.846591 -176.289172)
			(xy 91.846146 -176.262792) (xy 91.846632 -176.235541) (xy 91.854388 -176.181593) (xy 91.869743 -176.129298)
			(xy 91.892385 -176.079721) (xy 91.921851 -176.033871) (xy 91.957542 -175.99268) (xy 91.998733 -175.956989)
			(xy 92.044583 -175.927523) (xy 92.09416 -175.904881) (xy 92.146455 -175.889526) (xy 92.200403 -175.88177)
			(xy 92.254905 -175.88177) (xy 92.308853 -175.889526) (xy 92.361148 -175.904881) (xy 92.410725 -175.927523)
			(xy 92.456575 -175.956989) (xy 92.497766 -175.99268) (xy 92.533457 -176.033871) (xy 92.562923 -176.079721)
			(xy 92.585565 -176.129298) (xy 92.60092 -176.181593) (xy 92.608676 -176.235541) (xy 92.609162 -176.262792)
			(xy 92.608705 -176.289171) (xy 92.601452 -176.341429) (xy 92.587071 -176.39219) (xy 92.565835 -176.440486)
			(xy 92.538149 -176.485396) (xy 92.504541 -176.526065) (xy 92.465651 -176.561717) (xy 92.422221 -176.591672)
			(xy 92.39885 -176.603914) (xy 92.386497 -176.610626) (xy 92.365766 -176.629599) (xy 92.351002 -176.653511)
			(xy 92.343328 -176.680545) (xy 92.343327 -176.708648) (xy 92.350999 -176.735683) (xy 92.365761 -176.759596)
			(xy 92.386491 -176.77857) (xy 92.39885 -176.78527) (xy 92.422229 -176.797496) (xy 92.465651 -176.827463)
			(xy 92.504534 -176.863121) (xy 92.538139 -176.903793) (xy 92.565824 -176.948704) (xy 92.587064 -176.996998)
			(xy 92.601452 -177.047757) (xy 92.608716 -177.100013) (xy 92.609162 -177.126392) (xy 92.608676 -177.153643)
			(xy 92.60092 -177.207591) (xy 92.585565 -177.259886) (xy 92.562923 -177.309463) (xy 92.533457 -177.355313)
			(xy 92.497766 -177.396504) (xy 92.456575 -177.432195) (xy 92.410725 -177.461661) (xy 92.361148 -177.484303)
			(xy 92.308853 -177.499658) (xy 92.254905 -177.507414) (xy 92.200403 -177.507414) (xy 92.146455 -177.499658)
			(xy 92.09416 -177.484303) (xy 92.044583 -177.461661) (xy 91.998733 -177.432195) (xy 91.957542 -177.396504)
			(xy 91.921851 -177.355313) (xy 91.892385 -177.309463) (xy 91.869743 -177.259886) (xy 91.854388 -177.207591)
			(xy 91.846632 -177.153643) (xy 91.846146 -177.126392) (xy 77.343 -177.126392) (xy 77.343 -178.674268)
			(xy 88.233502 -178.674268) (xy 88.237573 -178.618646) (xy 88.249699 -178.564209) (xy 88.269622 -178.512118)
			(xy 88.296918 -178.463483) (xy 88.331004 -178.41934) (xy 88.371153 -178.380631) (xy 88.416511 -178.34818)
			(xy 88.466111 -178.322679) (xy 88.518895 -178.304672) (xy 88.573738 -178.294542) (xy 88.629472 -178.292505)
			(xy 88.684909 -178.298605) (xy 88.738866 -178.312711) (xy 88.790195 -178.334523) (xy 88.837801 -178.363577)
			(xy 88.880669 -178.399252) (xy 88.917886 -178.440789) (xy 88.948659 -178.487302) (xy 88.972331 -178.537799)
			(xy 88.988399 -178.591206) (xy 88.996519 -178.646382) (xy 88.997028 -178.674268) (xy 88.996519 -178.702154)
			(xy 88.988399 -178.75733) (xy 88.972331 -178.810737) (xy 88.948659 -178.861234) (xy 88.917886 -178.907747)
			(xy 88.880669 -178.949284) (xy 88.837801 -178.984959) (xy 88.790195 -179.014013) (xy 88.738866 -179.035825)
			(xy 88.684909 -179.049931) (xy 88.629472 -179.056031) (xy 88.573738 -179.053994) (xy 88.518895 -179.043864)
			(xy 88.466111 -179.025857) (xy 88.416511 -179.000356) (xy 88.371153 -178.967905) (xy 88.331004 -178.929196)
			(xy 88.296918 -178.885053) (xy 88.269622 -178.836418) (xy 88.249699 -178.784327) (xy 88.237573 -178.72989)
			(xy 88.233502 -178.674268) (xy 77.343 -178.674268) (xy 77.343 -178.907948) (xy 77.72908 -179.294028)
			(xy 83.885022 -179.294028) (xy 83.889093 -179.238406) (xy 83.901219 -179.183969) (xy 83.921142 -179.131878)
			(xy 83.948438 -179.083243) (xy 83.982524 -179.0391) (xy 84.022673 -179.000391) (xy 84.068031 -178.96794)
			(xy 84.117631 -178.942439) (xy 84.170415 -178.924432) (xy 84.225258 -178.914302) (xy 84.280992 -178.912265)
			(xy 84.336429 -178.918365) (xy 84.390386 -178.932471) (xy 84.441715 -178.954283) (xy 84.489321 -178.983337)
			(xy 84.532189 -179.019012) (xy 84.569406 -179.060549) (xy 84.600179 -179.107062) (xy 84.623851 -179.157559)
			(xy 84.639919 -179.210966) (xy 84.648039 -179.266142) (xy 84.648548 -179.294028) (xy 84.648163 -179.31511)
			(xy 91.177362 -179.31511) (xy 91.181433 -179.259488) (xy 91.193559 -179.205051) (xy 91.213482 -179.15296)
			(xy 91.240778 -179.104325) (xy 91.274864 -179.060182) (xy 91.315013 -179.021473) (xy 91.360371 -178.989022)
			(xy 91.409971 -178.963521) (xy 91.462755 -178.945514) (xy 91.517598 -178.935384) (xy 91.573332 -178.933347)
			(xy 91.628769 -178.939447) (xy 91.682726 -178.953553) (xy 91.734055 -178.975365) (xy 91.781661 -179.004419)
			(xy 91.824529 -179.040094) (xy 91.861746 -179.081631) (xy 91.892519 -179.128144) (xy 91.916191 -179.178641)
			(xy 91.932259 -179.232048) (xy 91.940379 -179.287224) (xy 91.940888 -179.31511) (xy 91.940379 -179.342996)
			(xy 91.932259 -179.398172) (xy 91.916191 -179.451579) (xy 91.892519 -179.502076) (xy 91.861746 -179.548589)
			(xy 91.824529 -179.590126) (xy 91.781661 -179.625801) (xy 91.734055 -179.654855) (xy 91.682726 -179.676667)
			(xy 91.628769 -179.690773) (xy 91.573332 -179.696873) (xy 91.517598 -179.694836) (xy 91.462755 -179.684706)
			(xy 91.409971 -179.666699) (xy 91.360371 -179.641198) (xy 91.315013 -179.608747) (xy 91.274864 -179.570038)
			(xy 91.240778 -179.525895) (xy 91.213482 -179.47726) (xy 91.193559 -179.425169) (xy 91.181433 -179.370732)
			(xy 91.177362 -179.31511) (xy 84.648163 -179.31511) (xy 84.648039 -179.321914) (xy 84.639919 -179.37709)
			(xy 84.623851 -179.430497) (xy 84.600179 -179.480994) (xy 84.569406 -179.527507) (xy 84.532189 -179.569044)
			(xy 84.489321 -179.604719) (xy 84.441715 -179.633773) (xy 84.390386 -179.655585) (xy 84.336429 -179.669691)
			(xy 84.280992 -179.675791) (xy 84.225258 -179.673754) (xy 84.170415 -179.663624) (xy 84.117631 -179.645617)
			(xy 84.068031 -179.620116) (xy 84.022673 -179.587665) (xy 83.982524 -179.548956) (xy 83.948438 -179.504813)
			(xy 83.921142 -179.456178) (xy 83.901219 -179.404087) (xy 83.889093 -179.34965) (xy 83.885022 -179.294028)
			(xy 77.72908 -179.294028) (xy 78.600554 -180.165502) (xy 83.778088 -180.165502) (xy 83.782159 -180.10988)
			(xy 83.794285 -180.055443) (xy 83.814208 -180.003352) (xy 83.841504 -179.954717) (xy 83.87559 -179.910574)
			(xy 83.915739 -179.871865) (xy 83.961097 -179.839414) (xy 84.010697 -179.813913) (xy 84.063481 -179.795906)
			(xy 84.118324 -179.785776) (xy 84.174058 -179.783739) (xy 84.229495 -179.789839) (xy 84.283452 -179.803945)
			(xy 84.334781 -179.825757) (xy 84.382387 -179.854811) (xy 84.425255 -179.890486) (xy 84.462472 -179.932023)
			(xy 84.493245 -179.978536) (xy 84.516917 -180.029033) (xy 84.532985 -180.08244) (xy 84.541105 -180.137616)
			(xy 84.541614 -180.165502) (xy 84.541105 -180.193388) (xy 84.532985 -180.248564) (xy 84.516917 -180.301971)
			(xy 84.493245 -180.352468) (xy 84.462472 -180.398981) (xy 84.425255 -180.440518) (xy 84.382387 -180.476193)
			(xy 84.334781 -180.505247) (xy 84.283452 -180.527059) (xy 84.229495 -180.541165) (xy 84.174058 -180.547265)
			(xy 84.118324 -180.545228) (xy 84.063481 -180.535098) (xy 84.010697 -180.517091) (xy 83.961097 -180.49159)
			(xy 83.915739 -180.459139) (xy 83.87559 -180.42043) (xy 83.841504 -180.376287) (xy 83.814208 -180.327652)
			(xy 83.794285 -180.275561) (xy 83.782159 -180.221124) (xy 83.778088 -180.165502) (xy 78.600554 -180.165502)
			(xy 78.994 -180.558948) (xy 82.960462 -180.558948) (xy 82.964533 -180.503326) (xy 82.976659 -180.448889)
			(xy 82.996582 -180.396798) (xy 83.023878 -180.348163) (xy 83.057964 -180.30402) (xy 83.098113 -180.265311)
			(xy 83.143471 -180.23286) (xy 83.193071 -180.207359) (xy 83.245855 -180.189352) (xy 83.300698 -180.179222)
			(xy 83.356432 -180.177185) (xy 83.411869 -180.183285) (xy 83.465826 -180.197391) (xy 83.517155 -180.219203)
			(xy 83.564761 -180.248257) (xy 83.607629 -180.283932) (xy 83.644846 -180.325469) (xy 83.675619 -180.371982)
			(xy 83.699291 -180.422479) (xy 83.715359 -180.475886) (xy 83.723479 -180.531062) (xy 83.723988 -180.558948)
			(xy 83.723479 -180.586834) (xy 83.715359 -180.64201) (xy 83.699291 -180.695417) (xy 83.675619 -180.745914)
			(xy 83.644846 -180.792427) (xy 83.607629 -180.833964) (xy 83.564761 -180.869639) (xy 83.517155 -180.898693)
			(xy 83.465826 -180.920505) (xy 83.411869 -180.934611) (xy 83.356432 -180.940711) (xy 83.300698 -180.938674)
			(xy 83.245855 -180.928544) (xy 83.193071 -180.910537) (xy 83.143471 -180.885036) (xy 83.098113 -180.852585)
			(xy 83.057964 -180.813876) (xy 83.023878 -180.769733) (xy 82.996582 -180.721098) (xy 82.976659 -180.669007)
			(xy 82.964533 -180.61457) (xy 82.960462 -180.558948) (xy 78.994 -180.558948) (xy 80.099662 -181.66461)
			(xy 84.87994 -181.66461) (xy 84.884011 -181.608988) (xy 84.896137 -181.554551) (xy 84.91606 -181.50246)
			(xy 84.943356 -181.453825) (xy 84.977442 -181.409682) (xy 85.017591 -181.370973) (xy 85.062949 -181.338522)
			(xy 85.112549 -181.313021) (xy 85.165333 -181.295014) (xy 85.220176 -181.284884) (xy 85.27591 -181.282847)
			(xy 85.331347 -181.288947) (xy 85.385304 -181.303053) (xy 85.436633 -181.324865) (xy 85.484239 -181.353919)
			(xy 85.527107 -181.389594) (xy 85.564324 -181.431131) (xy 85.595097 -181.477644) (xy 85.618769 -181.528141)
			(xy 85.634837 -181.581548) (xy 85.642957 -181.636724) (xy 85.643466 -181.66461) (xy 85.642957 -181.692496)
			(xy 85.636968 -181.73319) (xy 88.31148 -181.73319) (xy 88.315551 -181.677568) (xy 88.327677 -181.623131)
			(xy 88.3476 -181.57104) (xy 88.374896 -181.522405) (xy 88.408982 -181.478262) (xy 88.449131 -181.439553)
			(xy 88.494489 -181.407102) (xy 88.544089 -181.381601) (xy 88.596873 -181.363594) (xy 88.651716 -181.353464)
			(xy 88.70745 -181.351427) (xy 88.762887 -181.357527) (xy 88.816844 -181.371633) (xy 88.868173 -181.393445)
			(xy 88.915779 -181.422499) (xy 88.958647 -181.458174) (xy 88.995864 -181.499711) (xy 89.026637 -181.546224)
			(xy 89.050309 -181.596721) (xy 89.066377 -181.650128) (xy 89.074497 -181.705304) (xy 89.075006 -181.73319)
			(xy 89.074497 -181.761076) (xy 89.066377 -181.816252) (xy 89.050309 -181.869659) (xy 89.026637 -181.920156)
			(xy 88.995864 -181.966669) (xy 88.958647 -182.008206) (xy 88.915779 -182.043881) (xy 88.868173 -182.072935)
			(xy 88.816844 -182.094747) (xy 88.762887 -182.108853) (xy 88.70745 -182.114953) (xy 88.651716 -182.112916)
			(xy 88.596873 -182.102786) (xy 88.544089 -182.084779) (xy 88.494489 -182.059278) (xy 88.449131 -182.026827)
			(xy 88.408982 -181.988118) (xy 88.374896 -181.943975) (xy 88.3476 -181.89534) (xy 88.327677 -181.843249)
			(xy 88.315551 -181.788812) (xy 88.31148 -181.73319) (xy 85.636968 -181.73319) (xy 85.634837 -181.747672)
			(xy 85.618769 -181.801079) (xy 85.595097 -181.851576) (xy 85.564324 -181.898089) (xy 85.527107 -181.939626)
			(xy 85.484239 -181.975301) (xy 85.436633 -182.004355) (xy 85.385304 -182.026167) (xy 85.331347 -182.040273)
			(xy 85.27591 -182.046373) (xy 85.220176 -182.044336) (xy 85.165333 -182.034206) (xy 85.112549 -182.016199)
			(xy 85.062949 -181.990698) (xy 85.017591 -181.958247) (xy 84.977442 -181.919538) (xy 84.943356 -181.875395)
			(xy 84.91606 -181.82676) (xy 84.896137 -181.774669) (xy 84.884011 -181.720232) (xy 84.87994 -181.66461)
			(xy 80.099662 -181.66461) (xy 81.503774 -183.068722) (xy 89.559382 -183.068722) (xy 89.563453 -183.0131)
			(xy 89.575579 -182.958663) (xy 89.595502 -182.906572) (xy 89.622798 -182.857937) (xy 89.656884 -182.813794)
			(xy 89.697033 -182.775085) (xy 89.742391 -182.742634) (xy 89.791991 -182.717133) (xy 89.844775 -182.699126)
			(xy 89.899618 -182.688996) (xy 89.955352 -182.686959) (xy 90.010789 -182.693059) (xy 90.064746 -182.707165)
			(xy 90.116075 -182.728977) (xy 90.163681 -182.758031) (xy 90.206549 -182.793706) (xy 90.243766 -182.835243)
			(xy 90.274539 -182.881756) (xy 90.298211 -182.932253) (xy 90.314279 -182.98566) (xy 90.322399 -183.040836)
			(xy 90.322908 -183.068722) (xy 90.322399 -183.096608) (xy 90.314279 -183.151784) (xy 90.298211 -183.205191)
			(xy 90.274539 -183.255688) (xy 90.243766 -183.302201) (xy 90.206549 -183.343738) (xy 90.163681 -183.379413)
			(xy 90.116075 -183.408467) (xy 90.064746 -183.430279) (xy 90.010789 -183.444385) (xy 89.955352 -183.450485)
			(xy 89.899618 -183.448448) (xy 89.844775 -183.438318) (xy 89.791991 -183.420311) (xy 89.742391 -183.39481)
			(xy 89.697033 -183.362359) (xy 89.656884 -183.32365) (xy 89.622798 -183.279507) (xy 89.595502 -183.230872)
			(xy 89.575579 -183.178781) (xy 89.563453 -183.124344) (xy 89.559382 -183.068722) (xy 81.503774 -183.068722)
			(xy 82.670142 -184.23509) (xy 84.8266 -184.23509) (xy 84.830671 -184.179468) (xy 84.842797 -184.125031)
			(xy 84.86272 -184.07294) (xy 84.890016 -184.024305) (xy 84.924102 -183.980162) (xy 84.964251 -183.941453)
			(xy 85.009609 -183.909002) (xy 85.059209 -183.883501) (xy 85.111993 -183.865494) (xy 85.166836 -183.855364)
			(xy 85.22257 -183.853327) (xy 85.278007 -183.859427) (xy 85.331964 -183.873533) (xy 85.383293 -183.895345)
			(xy 85.430899 -183.924399) (xy 85.473767 -183.960074) (xy 85.510984 -184.001611) (xy 85.541757 -184.048124)
			(xy 85.565429 -184.098621) (xy 85.581497 -184.152028) (xy 85.589617 -184.207204) (xy 85.590126 -184.23509)
			(xy 85.589617 -184.262976) (xy 85.581497 -184.318152) (xy 85.565429 -184.371559) (xy 85.541757 -184.422056)
			(xy 85.510984 -184.468569) (xy 85.473767 -184.510106) (xy 85.430899 -184.545781) (xy 85.383293 -184.574835)
			(xy 85.331964 -184.596647) (xy 85.278007 -184.610753) (xy 85.22257 -184.616853) (xy 85.166836 -184.614816)
			(xy 85.111993 -184.604686) (xy 85.059209 -184.586679) (xy 85.009609 -184.561178) (xy 84.964251 -184.528727)
			(xy 84.924102 -184.490018) (xy 84.890016 -184.445875) (xy 84.86272 -184.39724) (xy 84.842797 -184.345149)
			(xy 84.830671 -184.290712) (xy 84.8266 -184.23509) (xy 82.670142 -184.23509) (xy 83.058 -184.622948)
			(xy 91.309442 -184.622948) (xy 91.313513 -184.567326) (xy 91.325639 -184.512889) (xy 91.345562 -184.460798)
			(xy 91.372858 -184.412163) (xy 91.406944 -184.36802) (xy 91.447093 -184.329311) (xy 91.492451 -184.29686)
			(xy 91.542051 -184.271359) (xy 91.594835 -184.253352) (xy 91.649678 -184.243222) (xy 91.705412 -184.241185)
			(xy 91.760849 -184.247285) (xy 91.814806 -184.261391) (xy 91.866135 -184.283203) (xy 91.913741 -184.312257)
			(xy 91.956609 -184.347932) (xy 91.993826 -184.389469) (xy 92.024599 -184.435982) (xy 92.048271 -184.486479)
			(xy 92.064339 -184.539886) (xy 92.072459 -184.595062) (xy 92.072968 -184.622948) (xy 92.072459 -184.650834)
			(xy 92.064339 -184.70601) (xy 92.048271 -184.759417) (xy 92.024599 -184.809914) (xy 91.993826 -184.856427)
			(xy 91.956609 -184.897964) (xy 91.913741 -184.933639) (xy 91.866135 -184.962693) (xy 91.814806 -184.984505)
			(xy 91.760849 -184.998611) (xy 91.705412 -185.004711) (xy 91.649678 -185.002674) (xy 91.594835 -184.992544)
			(xy 91.542051 -184.974537) (xy 91.492451 -184.949036) (xy 91.447093 -184.916585) (xy 91.406944 -184.877876)
			(xy 91.372858 -184.833733) (xy 91.345562 -184.785098) (xy 91.325639 -184.733007) (xy 91.313513 -184.67857)
			(xy 91.309442 -184.622948) (xy 83.058 -184.622948) (xy 83.533742 -185.09869) (xy 88.01989 -185.09869)
			(xy 88.020376 -185.071439) (xy 88.028132 -185.017491) (xy 88.043487 -184.965196) (xy 88.066129 -184.915619)
			(xy 88.095595 -184.869769) (xy 88.131286 -184.828578) (xy 88.172477 -184.792887) (xy 88.218327 -184.763421)
			(xy 88.267904 -184.740779) (xy 88.320199 -184.725424) (xy 88.374147 -184.717668) (xy 88.428649 -184.717668)
			(xy 88.482597 -184.725424) (xy 88.534892 -184.740779) (xy 88.584469 -184.763421) (xy 88.630319 -184.792887)
			(xy 88.67151 -184.828578) (xy 88.707201 -184.869769) (xy 88.736667 -184.915619) (xy 88.759309 -184.965196)
			(xy 88.774664 -185.017491) (xy 88.78242 -185.071439) (xy 88.782553 -185.078878) (xy 89.249248 -185.078878)
			(xy 89.253319 -185.023256) (xy 89.265445 -184.968819) (xy 89.285368 -184.916728) (xy 89.312664 -184.868093)
			(xy 89.34675 -184.82395) (xy 89.386899 -184.785241) (xy 89.432257 -184.75279) (xy 89.481857 -184.727289)
			(xy 89.534641 -184.709282) (xy 89.589484 -184.699152) (xy 89.645218 -184.697115) (xy 89.700655 -184.703215)
			(xy 89.754612 -184.717321) (xy 89.805941 -184.739133) (xy 89.853547 -184.768187) (xy 89.896415 -184.803862)
			(xy 89.933632 -184.845399) (xy 89.964405 -184.891912) (xy 89.988077 -184.942409) (xy 90.004145 -184.995816)
			(xy 90.012265 -185.050992) (xy 90.012774 -185.078878) (xy 90.012265 -185.106764) (xy 90.004145 -185.16194)
			(xy 89.988077 -185.215347) (xy 89.964405 -185.265844) (xy 89.933632 -185.312357) (xy 89.896415 -185.353894)
			(xy 89.853547 -185.389569) (xy 89.805941 -185.418623) (xy 89.754612 -185.440435) (xy 89.700655 -185.454541)
			(xy 89.645218 -185.460641) (xy 89.589484 -185.458604) (xy 89.534641 -185.448474) (xy 89.481857 -185.430467)
			(xy 89.432257 -185.404966) (xy 89.386899 -185.372515) (xy 89.34675 -185.333806) (xy 89.312664 -185.289663)
			(xy 89.285368 -185.241028) (xy 89.265445 -185.188937) (xy 89.253319 -185.1345) (xy 89.249248 -185.078878)
			(xy 88.782553 -185.078878) (xy 88.782906 -185.09869) (xy 88.782439 -185.125319) (xy 88.775033 -185.178061)
			(xy 88.760362 -185.229259) (xy 88.738713 -185.27792) (xy 88.710505 -185.323096) (xy 88.693752 -185.3438)
			(xy 88.685499 -185.354452) (xy 88.674248 -185.378923) (xy 88.669782 -185.405482) (xy 88.67241 -185.432287)
			(xy 88.681951 -185.457473) (xy 88.697741 -185.479292) (xy 88.718683 -185.496227) (xy 88.730836 -185.502042)
			(xy 88.755922 -185.513559) (xy 88.80274 -185.542797) (xy 88.844853 -185.57848) (xy 88.881381 -185.619862)
			(xy 88.911561 -185.666078) (xy 88.934763 -185.716163) (xy 88.950501 -185.76907) (xy 88.958446 -185.823693)
			(xy 88.958928 -185.851292) (xy 88.958435 -185.87767) (xy 88.951184 -185.929924) (xy 88.936805 -185.980683)
			(xy 88.915573 -186.028977) (xy 88.887892 -186.073886) (xy 88.85429 -186.114556) (xy 88.815407 -186.15021)
			(xy 88.771984 -186.180169) (xy 88.748616 -186.192414) (xy 88.736266 -186.199129) (xy 88.715542 -186.218104)
			(xy 88.700784 -186.242015) (xy 88.693113 -186.269047) (xy 88.693112 -186.297146) (xy 88.700781 -186.324178)
			(xy 88.715537 -186.348091) (xy 88.73626 -186.367067) (xy 88.748616 -186.37377) (xy 88.771987 -186.386011)
			(xy 88.81541 -186.415974) (xy 88.854295 -186.451629) (xy 88.887901 -186.492299) (xy 88.915588 -186.537208)
			(xy 88.936828 -186.585501) (xy 88.951218 -186.636258) (xy 88.958482 -186.688513) (xy 88.958928 -186.714892)
			(xy 88.958442 -186.742143) (xy 88.950686 -186.796091) (xy 88.935331 -186.848386) (xy 88.912689 -186.897963)
			(xy 88.883223 -186.943813) (xy 88.847532 -186.985004) (xy 88.828898 -187.00115) (xy 90.7796 -187.00115)
			(xy 90.780142 -186.974203) (xy 90.787733 -186.920846) (xy 90.802758 -186.869088) (xy 90.824918 -186.819959)
			(xy 90.85377 -186.774438) (xy 90.888741 -186.733431) (xy 90.929136 -186.697753) (xy 90.974149 -186.668114)
			(xy 91.022885 -186.645106) (xy 91.074375 -186.629185) (xy 91.10091 -186.624468) (xy 91.114738 -186.621771)
			(xy 91.140288 -186.609933) (xy 91.161632 -186.591565) (xy 91.177147 -186.568065) (xy 91.185652 -186.541221)
			(xy 91.186501 -186.513075) (xy 91.179628 -186.485767) (xy 91.165558 -186.461375) (xy 91.155774 -186.45124)
			(xy 91.137909 -186.433224) (xy 91.106612 -186.393289) (xy 91.080886 -186.349558) (xy 91.061183 -186.302803)
			(xy 91.047852 -186.253848) (xy 91.041128 -186.203559) (xy 91.040712 -186.17819) (xy 91.041198 -186.150939)
			(xy 91.048954 -186.096991) (xy 91.064309 -186.044696) (xy 91.086951 -185.995119) (xy 91.116417 -185.949269)
			(xy 91.152108 -185.908078) (xy 91.193299 -185.872387) (xy 91.239149 -185.842921) (xy 91.288726 -185.820279)
			(xy 91.341021 -185.804924) (xy 91.394969 -185.797168) (xy 91.449471 -185.797168) (xy 91.503419 -185.804924)
			(xy 91.555714 -185.820279) (xy 91.605291 -185.842921) (xy 91.651141 -185.872387) (xy 91.692332 -185.908078)
			(xy 91.728023 -185.949269) (xy 91.757489 -185.995119) (xy 91.780131 -186.044696) (xy 91.795486 -186.096991)
			(xy 91.803242 -186.150939) (xy 91.803728 -186.17819) (xy 91.803283 -186.205141) (xy 91.795684 -186.258505)
			(xy 91.780651 -186.310268) (xy 91.758482 -186.359401) (xy 91.729619 -186.404924) (xy 91.694636 -186.445932)
			(xy 91.65423 -186.481609) (xy 91.609205 -186.511244) (xy 91.560458 -186.534247) (xy 91.508958 -186.55016)
			(xy 91.482418 -186.554872) (xy 91.468576 -186.557515) (xy 91.443014 -186.569355) (xy 91.421661 -186.587729)
			(xy 91.406141 -186.611239) (xy 91.397636 -186.638095) (xy 91.396793 -186.666253) (xy 91.403676 -186.693569)
			(xy 91.417762 -186.717965) (xy 91.427554 -186.7281) (xy 91.445396 -186.746138) (xy 91.476693 -186.786069)
			(xy 91.502422 -186.829795) (xy 91.522129 -186.876546) (xy 91.535465 -186.925497) (xy 91.542196 -186.975783)
			(xy 91.542616 -187.00115) (xy 91.54213 -187.028401) (xy 91.534374 -187.082349) (xy 91.519019 -187.134644)
			(xy 91.496377 -187.184221) (xy 91.466911 -187.230071) (xy 91.43122 -187.271262) (xy 91.390029 -187.306953)
			(xy 91.344179 -187.336419) (xy 91.294602 -187.359061) (xy 91.242307 -187.374416) (xy 91.188359 -187.382172)
			(xy 91.133857 -187.382172) (xy 91.079909 -187.374416) (xy 91.027614 -187.359061) (xy 90.978037 -187.336419)
			(xy 90.932187 -187.306953) (xy 90.890996 -187.271262) (xy 90.855305 -187.230071) (xy 90.825839 -187.184221)
			(xy 90.803197 -187.134644) (xy 90.787842 -187.082349) (xy 90.780086 -187.028401) (xy 90.7796 -187.00115)
			(xy 88.828898 -187.00115) (xy 88.806341 -187.020695) (xy 88.760491 -187.050161) (xy 88.710914 -187.072803)
			(xy 88.658619 -187.088158) (xy 88.604671 -187.095914) (xy 88.550169 -187.095914) (xy 88.496221 -187.088158)
			(xy 88.443926 -187.072803) (xy 88.394349 -187.050161) (xy 88.348499 -187.020695) (xy 88.307308 -186.985004)
			(xy 88.271617 -186.943813) (xy 88.242151 -186.897963) (xy 88.219509 -186.848386) (xy 88.204154 -186.796091)
			(xy 88.196398 -186.742143) (xy 88.195912 -186.714892) (xy 88.19637 -186.688513) (xy 88.203624 -186.636256)
			(xy 88.218006 -186.585496) (xy 88.239243 -186.5372) (xy 88.266929 -186.49229) (xy 88.300536 -186.451622)
			(xy 88.339425 -186.415969) (xy 88.382854 -186.386013) (xy 88.406224 -186.37377) (xy 88.418594 -186.367084)
			(xy 88.439332 -186.348109) (xy 88.4541 -186.324192) (xy 88.461775 -186.297151) (xy 88.461774 -186.269042)
			(xy 88.454097 -186.242002) (xy 88.439327 -186.218086) (xy 88.418588 -186.199112) (xy 88.406224 -186.192414)
			(xy 88.382856 -186.180168) (xy 88.33943 -186.150208) (xy 88.300544 -186.114554) (xy 88.266937 -186.073885)
			(xy 88.239249 -186.028977) (xy 88.218009 -185.980684) (xy 88.20362 -185.929926) (xy 88.196357 -185.877671)
			(xy 88.195912 -185.851292) (xy 88.196364 -185.824662) (xy 88.203774 -185.77192) (xy 88.218448 -185.720721)
			(xy 88.2401 -185.672061) (xy 88.268311 -185.626886) (xy 88.285066 -185.606182) (xy 88.293333 -185.595541)
			(xy 88.30458 -185.571067) (xy 88.309042 -185.544505) (xy 88.306411 -185.5177) (xy 88.296869 -185.492513)
			(xy 88.281078 -185.470693) (xy 88.260135 -185.453757) (xy 88.247982 -185.44794) (xy 88.22291 -185.436398)
			(xy 88.176097 -185.407158) (xy 88.133987 -185.371476) (xy 88.097461 -185.330097) (xy 88.06728 -185.283886)
			(xy 88.044076 -185.233806) (xy 88.028332 -185.180905) (xy 88.020378 -185.126287) (xy 88.01989 -185.09869)
			(xy 83.533742 -185.09869) (xy 86.251288 -187.816236) (xy 87.107266 -187.816236) (xy 87.111337 -187.760614)
			(xy 87.123463 -187.706177) (xy 87.143386 -187.654086) (xy 87.170682 -187.605451) (xy 87.204768 -187.561308)
			(xy 87.244917 -187.522599) (xy 87.290275 -187.490148) (xy 87.339875 -187.464647) (xy 87.392659 -187.44664)
			(xy 87.447502 -187.43651) (xy 87.503236 -187.434473) (xy 87.558673 -187.440573) (xy 87.61263 -187.454679)
			(xy 87.663959 -187.476491) (xy 87.711565 -187.505545) (xy 87.754433 -187.54122) (xy 87.79165 -187.582757)
			(xy 87.822423 -187.62927) (xy 87.846095 -187.679767) (xy 87.862163 -187.733174) (xy 87.870283 -187.78835)
			(xy 87.870792 -187.816236) (xy 87.870283 -187.844122) (xy 87.862163 -187.899298) (xy 87.846095 -187.952705)
			(xy 87.822423 -188.003202) (xy 87.79165 -188.049715) (xy 87.754433 -188.091252) (xy 87.711565 -188.126927)
			(xy 87.663959 -188.155981) (xy 87.61263 -188.177793) (xy 87.558673 -188.191899) (xy 87.503236 -188.197999)
			(xy 87.447502 -188.195962) (xy 87.392659 -188.185832) (xy 87.339875 -188.167825) (xy 87.290275 -188.142324)
			(xy 87.244917 -188.109873) (xy 87.204768 -188.071164) (xy 87.170682 -188.027021) (xy 87.143386 -187.978386)
			(xy 87.123463 -187.926295) (xy 87.111337 -187.871858) (xy 87.107266 -187.816236) (xy 86.251288 -187.816236)
			(xy 87.165942 -188.73089) (xy 90.77909 -188.73089) (xy 90.783161 -188.675268) (xy 90.795287 -188.620831)
			(xy 90.81521 -188.56874) (xy 90.842506 -188.520105) (xy 90.876592 -188.475962) (xy 90.916741 -188.437253)
			(xy 90.962099 -188.404802) (xy 91.011699 -188.379301) (xy 91.064483 -188.361294) (xy 91.119326 -188.351164)
			(xy 91.17506 -188.349127) (xy 91.230497 -188.355227) (xy 91.284454 -188.369333) (xy 91.335783 -188.391145)
			(xy 91.383389 -188.420199) (xy 91.426257 -188.455874) (xy 91.463474 -188.497411) (xy 91.494247 -188.543924)
			(xy 91.517919 -188.594421) (xy 91.533987 -188.647828) (xy 91.542107 -188.703004) (xy 91.542616 -188.73089)
			(xy 91.542107 -188.758776) (xy 91.533987 -188.813952) (xy 91.517919 -188.867359) (xy 91.494247 -188.917856)
			(xy 91.463474 -188.964369) (xy 91.426257 -189.005906) (xy 91.383389 -189.041581) (xy 91.335783 -189.070635)
			(xy 91.284454 -189.092447) (xy 91.230497 -189.106553) (xy 91.17506 -189.112653) (xy 91.119326 -189.110616)
			(xy 91.064483 -189.100486) (xy 91.011699 -189.082479) (xy 90.962099 -189.056978) (xy 90.916741 -189.024527)
			(xy 90.876592 -188.985818) (xy 90.842506 -188.941675) (xy 90.81521 -188.89304) (xy 90.795287 -188.840949)
			(xy 90.783161 -188.786512) (xy 90.77909 -188.73089) (xy 87.165942 -188.73089) (xy 88.9 -190.464948)
			(xy 93.472 -190.464948)
		)
		(stroke
			(width 0)
			(type solid)
		)
		(fill yes)
		(layer "In6.Cu")
		(net "PVNN_TERM_CPU1")
	)
	(gr_poly
		(pts
			(xy 465.316316 -395.996414) (xy 466.954616 -394.358114) (xy 466.954616 -379.012704) (xy 465.741258 -377.799346)
			(xy 433.923694 -377.799346) (xy 433.908708 -377.814332) (xy 433.196492 -378.526548) (xy 438.052462 -378.526548)
			(xy 438.056533 -378.470926) (xy 438.068659 -378.416489) (xy 438.088582 -378.364398) (xy 438.115878 -378.315763)
			(xy 438.149964 -378.27162) (xy 438.190113 -378.232911) (xy 438.235471 -378.20046) (xy 438.285071 -378.174959)
			(xy 438.337855 -378.156952) (xy 438.392698 -378.146822) (xy 438.448432 -378.144785) (xy 438.503869 -378.150885)
			(xy 438.557826 -378.164991) (xy 438.609155 -378.186803) (xy 438.656761 -378.215857) (xy 438.699629 -378.251532)
			(xy 438.736846 -378.293069) (xy 438.767619 -378.339582) (xy 438.791291 -378.390079) (xy 438.807359 -378.443486)
			(xy 438.815479 -378.498662) (xy 438.815988 -378.526548) (xy 438.815479 -378.554434) (xy 438.807359 -378.60961)
			(xy 438.791291 -378.663017) (xy 438.767619 -378.713514) (xy 438.736846 -378.760027) (xy 438.699629 -378.801564)
			(xy 438.656761 -378.837239) (xy 438.609155 -378.866293) (xy 438.557826 -378.888105) (xy 438.503869 -378.902211)
			(xy 438.448432 -378.908311) (xy 438.392698 -378.906274) (xy 438.337855 -378.896144) (xy 438.285071 -378.878137)
			(xy 438.235471 -378.852636) (xy 438.190113 -378.820185) (xy 438.149964 -378.781476) (xy 438.115878 -378.737333)
			(xy 438.088582 -378.688698) (xy 438.068659 -378.636607) (xy 438.056533 -378.58217) (xy 438.052462 -378.526548)
			(xy 433.196492 -378.526548) (xy 432.645058 -379.077982) (xy 432.645058 -379.669548) (xy 460.297782 -379.669548)
			(xy 460.301853 -379.613926) (xy 460.313979 -379.559489) (xy 460.333902 -379.507398) (xy 460.361198 -379.458763)
			(xy 460.395284 -379.41462) (xy 460.435433 -379.375911) (xy 460.480791 -379.34346) (xy 460.530391 -379.317959)
			(xy 460.583175 -379.299952) (xy 460.638018 -379.289822) (xy 460.693752 -379.287785) (xy 460.749189 -379.293885)
			(xy 460.803146 -379.307991) (xy 460.854475 -379.329803) (xy 460.902081 -379.358857) (xy 460.944949 -379.394532)
			(xy 460.982166 -379.436069) (xy 461.012939 -379.482582) (xy 461.036611 -379.533079) (xy 461.052679 -379.586486)
			(xy 461.060799 -379.641662) (xy 461.061308 -379.669548) (xy 461.060799 -379.697434) (xy 461.052679 -379.75261)
			(xy 461.036611 -379.806017) (xy 461.012939 -379.856514) (xy 460.982166 -379.903027) (xy 460.944949 -379.944564)
			(xy 460.902081 -379.980239) (xy 460.854475 -380.009293) (xy 460.803146 -380.031105) (xy 460.749189 -380.045211)
			(xy 460.693752 -380.051311) (xy 460.638018 -380.049274) (xy 460.583175 -380.039144) (xy 460.530391 -380.021137)
			(xy 460.480791 -379.995636) (xy 460.435433 -379.963185) (xy 460.395284 -379.924476) (xy 460.361198 -379.880333)
			(xy 460.333902 -379.831698) (xy 460.313979 -379.779607) (xy 460.301853 -379.72517) (xy 460.297782 -379.669548)
			(xy 432.645058 -379.669548) (xy 432.645058 -380.05258) (xy 438.059828 -380.05258) (xy 438.063899 -379.996958)
			(xy 438.076025 -379.942521) (xy 438.095948 -379.89043) (xy 438.123244 -379.841795) (xy 438.15733 -379.797652)
			(xy 438.197479 -379.758943) (xy 438.242837 -379.726492) (xy 438.292437 -379.700991) (xy 438.345221 -379.682984)
			(xy 438.400064 -379.672854) (xy 438.455798 -379.670817) (xy 438.511235 -379.676917) (xy 438.565192 -379.691023)
			(xy 438.616521 -379.712835) (xy 438.664127 -379.741889) (xy 438.706995 -379.777564) (xy 438.744212 -379.819101)
			(xy 438.774985 -379.865614) (xy 438.798657 -379.916111) (xy 438.814725 -379.969518) (xy 438.822845 -380.024694)
			(xy 438.823354 -380.05258) (xy 438.822845 -380.080466) (xy 438.814725 -380.135642) (xy 438.798657 -380.189049)
			(xy 438.774985 -380.239546) (xy 438.744212 -380.286059) (xy 438.706995 -380.327596) (xy 438.664127 -380.363271)
			(xy 438.616521 -380.392325) (xy 438.565192 -380.414137) (xy 438.511235 -380.428243) (xy 438.455798 -380.434343)
			(xy 438.400064 -380.432306) (xy 438.345221 -380.422176) (xy 438.292437 -380.404169) (xy 438.242837 -380.378668)
			(xy 438.197479 -380.346217) (xy 438.15733 -380.307508) (xy 438.123244 -380.263365) (xy 438.095948 -380.21473)
			(xy 438.076025 -380.162639) (xy 438.063899 -380.108202) (xy 438.059828 -380.05258) (xy 432.645058 -380.05258)
			(xy 432.645058 -380.807468) (xy 432.645509 -380.820935) (xy 432.652627 -380.846914) (xy 432.666297 -380.870124)
			(xy 432.685564 -380.888948) (xy 432.709086 -380.902072) (xy 432.735224 -380.908584) (xy 432.762155 -380.908027)
			(xy 432.788001 -380.900442) (xy 432.799744 -380.893828) (xy 432.822391 -380.880439) (xy 432.870583 -380.859333)
			(xy 432.921218 -380.845052) (xy 432.973336 -380.837866) (xy 432.999642 -380.83744) (xy 433.026888 -380.837929)
			(xy 433.080824 -380.845689) (xy 433.133107 -380.861046) (xy 433.182673 -380.883687) (xy 433.228512 -380.913151)
			(xy 433.269692 -380.948838) (xy 433.305375 -380.990021) (xy 433.334833 -381.035864) (xy 433.357468 -381.085432)
			(xy 433.37282 -381.137717) (xy 433.380574 -381.191654) (xy 433.380574 -381.246146) (xy 433.37282 -381.300083)
			(xy 433.357468 -381.352368) (xy 433.334833 -381.401936) (xy 433.333433 -381.404114) (xy 461.463388 -381.404114)
			(xy 461.467459 -381.348492) (xy 461.479585 -381.294055) (xy 461.499508 -381.241964) (xy 461.526804 -381.193329)
			(xy 461.56089 -381.149186) (xy 461.601039 -381.110477) (xy 461.646397 -381.078026) (xy 461.695997 -381.052525)
			(xy 461.748781 -381.034518) (xy 461.803624 -381.024388) (xy 461.859358 -381.022351) (xy 461.914795 -381.028451)
			(xy 461.968752 -381.042557) (xy 462.020081 -381.064369) (xy 462.067687 -381.093423) (xy 462.110555 -381.129098)
			(xy 462.147772 -381.170635) (xy 462.178545 -381.217148) (xy 462.202217 -381.267645) (xy 462.218285 -381.321052)
			(xy 462.226405 -381.376228) (xy 462.226914 -381.404114) (xy 462.226405 -381.432) (xy 462.218285 -381.487176)
			(xy 462.202217 -381.540583) (xy 462.193558 -381.559054) (xy 463.166712 -381.559054) (xy 463.170783 -381.503432)
			(xy 463.182909 -381.448995) (xy 463.202832 -381.396904) (xy 463.230128 -381.348269) (xy 463.264214 -381.304126)
			(xy 463.304363 -381.265417) (xy 463.349721 -381.232966) (xy 463.399321 -381.207465) (xy 463.452105 -381.189458)
			(xy 463.506948 -381.179328) (xy 463.562682 -381.177291) (xy 463.618119 -381.183391) (xy 463.672076 -381.197497)
			(xy 463.689681 -381.204978) (xy 464.315048 -381.204978) (xy 464.315541 -381.17613) (xy 464.324227 -381.119091)
			(xy 464.341412 -381.064014) (xy 464.366703 -381.012157) (xy 464.399522 -380.964704) (xy 464.418934 -380.943358)
			(xy 464.429105 -380.931769) (xy 464.442652 -380.904088) (xy 464.447314 -380.873626) (xy 464.442667 -380.843161)
			(xy 464.429135 -380.815473) (xy 464.418934 -380.803912) (xy 464.399513 -380.782577) (xy 464.366716 -380.735113)
			(xy 464.341441 -380.683251) (xy 464.324264 -380.628174) (xy 464.315577 -380.571139) (xy 464.315048 -380.542292)
			(xy 464.31557 -380.515043) (xy 464.323327 -380.461098) (xy 464.338681 -380.408807) (xy 464.361319 -380.359233)
			(xy 464.390782 -380.313384) (xy 464.42647 -380.272195) (xy 464.467656 -380.236504) (xy 464.513501 -380.207037)
			(xy 464.563073 -380.184393) (xy 464.615363 -380.169034) (xy 464.669307 -380.161273) (xy 464.696556 -380.160784)
			(xy 464.725296 -380.161278) (xy 464.782124 -380.169908) (xy 464.837015 -380.186966) (xy 464.888727 -380.212064)
			(xy 464.936088 -380.244635) (xy 464.957414 -380.263908) (xy 464.968948 -380.27398) (xy 464.996494 -380.287322)
			(xy 465.026756 -380.291907) (xy 465.057018 -380.287322) (xy 465.084564 -380.27398) (xy 465.096098 -380.263908)
			(xy 465.117398 -380.244606) (xy 465.164768 -380.212045) (xy 465.216486 -380.186959) (xy 465.271383 -380.169916)
			(xy 465.328215 -380.161301) (xy 465.356956 -380.160784) (xy 465.384207 -380.161296) (xy 465.438156 -380.169047)
			(xy 465.490453 -380.184397) (xy 465.540032 -380.207034) (xy 465.585885 -380.236496) (xy 465.627078 -380.272185)
			(xy 465.662772 -380.313373) (xy 465.692241 -380.359222) (xy 465.714885 -380.408799) (xy 465.730242 -380.461093)
			(xy 465.738 -380.515041) (xy 465.738464 -380.542292) (xy 465.737949 -380.571139) (xy 465.729268 -380.628177)
			(xy 465.712088 -380.683254) (xy 465.686802 -380.735112) (xy 465.653988 -380.782565) (xy 465.634578 -380.803912)
			(xy 465.624387 -380.815468) (xy 465.610927 -380.843173) (xy 465.606307 -380.873626) (xy 465.610943 -380.904076)
			(xy 465.624416 -380.931774) (xy 465.634578 -380.943358) (xy 465.653987 -380.964704) (xy 465.686785 -381.012165)
			(xy 465.712063 -381.064025) (xy 465.729243 -381.119099) (xy 465.737933 -381.176132) (xy 465.738464 -381.204978)
			(xy 465.738024 -381.232232) (xy 465.730269 -381.286186) (xy 465.714913 -381.338487) (xy 465.69227 -381.38807)
			(xy 465.662801 -381.433926) (xy 465.627104 -381.47512) (xy 465.585908 -381.510814) (xy 465.540051 -381.540281)
			(xy 465.490467 -381.562921) (xy 465.438165 -381.578274) (xy 465.38421 -381.586026) (xy 465.356956 -381.586486)
			(xy 465.328217 -381.585966) (xy 465.271391 -381.577339) (xy 465.216501 -381.560287) (xy 465.164789 -381.535195)
			(xy 465.117426 -381.502631) (xy 465.096098 -381.483362) (xy 465.084564 -381.47329) (xy 465.057018 -381.459948)
			(xy 465.026756 -381.455363) (xy 464.996494 -381.459948) (xy 464.968948 -381.47329) (xy 464.957414 -381.483362)
			(xy 464.936105 -381.502654) (xy 464.888738 -381.535217) (xy 464.837022 -381.560305) (xy 464.782127 -381.577351)
			(xy 464.725296 -381.585968) (xy 464.696556 -381.586486) (xy 464.669303 -381.586063) (xy 464.615352 -381.5783)
			(xy 464.563054 -381.562938) (xy 464.513475 -381.54029) (xy 464.467624 -381.510817) (xy 464.426434 -381.475119)
			(xy 464.390743 -381.433923) (xy 464.361278 -381.388067) (xy 464.338639 -381.338484) (xy 464.323286 -381.286184)
			(xy 464.315532 -381.232231) (xy 464.315048 -381.204978) (xy 463.689681 -381.204978) (xy 463.723405 -381.219309)
			(xy 463.771011 -381.248363) (xy 463.813879 -381.284038) (xy 463.851096 -381.325575) (xy 463.881869 -381.372088)
			(xy 463.905541 -381.422585) (xy 463.921609 -381.475992) (xy 463.929729 -381.531168) (xy 463.930238 -381.559054)
			(xy 463.929729 -381.58694) (xy 463.921609 -381.642116) (xy 463.905541 -381.695523) (xy 463.881869 -381.74602)
			(xy 463.851096 -381.792533) (xy 463.813879 -381.83407) (xy 463.771011 -381.869745) (xy 463.723405 -381.898799)
			(xy 463.672076 -381.920611) (xy 463.618119 -381.934717) (xy 463.562682 -381.940817) (xy 463.506948 -381.93878)
			(xy 463.452105 -381.92865) (xy 463.399321 -381.910643) (xy 463.349721 -381.885142) (xy 463.304363 -381.852691)
			(xy 463.264214 -381.813982) (xy 463.230128 -381.769839) (xy 463.202832 -381.721204) (xy 463.182909 -381.669113)
			(xy 463.170783 -381.614676) (xy 463.166712 -381.559054) (xy 462.193558 -381.559054) (xy 462.178545 -381.59108)
			(xy 462.147772 -381.637593) (xy 462.110555 -381.67913) (xy 462.067687 -381.714805) (xy 462.020081 -381.743859)
			(xy 461.968752 -381.765671) (xy 461.914795 -381.779777) (xy 461.859358 -381.785877) (xy 461.803624 -381.78384)
			(xy 461.748781 -381.77371) (xy 461.695997 -381.755703) (xy 461.646397 -381.730202) (xy 461.601039 -381.697751)
			(xy 461.56089 -381.659042) (xy 461.526804 -381.614899) (xy 461.499508 -381.566264) (xy 461.479585 -381.514173)
			(xy 461.467459 -381.459736) (xy 461.463388 -381.404114) (xy 433.333433 -381.404114) (xy 433.305375 -381.447779)
			(xy 433.269692 -381.488962) (xy 433.228512 -381.524649) (xy 433.182673 -381.554113) (xy 433.133107 -381.576754)
			(xy 433.080824 -381.592111) (xy 433.026888 -381.599871) (xy 432.999642 -381.600456) (xy 432.973336 -381.600032)
			(xy 432.921219 -381.592841) (xy 432.870583 -381.578561) (xy 432.822388 -381.557463) (xy 432.799744 -381.544068)
			(xy 432.788042 -381.537389) (xy 432.762191 -381.529824) (xy 432.735261 -381.529284) (xy 432.709128 -381.535809)
			(xy 432.685612 -381.548943) (xy 432.666351 -381.567772) (xy 432.652686 -381.590983) (xy 432.64557 -381.616962)
			(xy 432.645058 -381.630428) (xy 432.645058 -382.524553) (xy 437.679785 -382.524553) (xy 437.679785 -382.470047)
			(xy 437.687543 -382.416096) (xy 437.7029 -382.363799) (xy 437.725544 -382.31422) (xy 437.755014 -382.268368)
			(xy 437.79071 -382.227177) (xy 437.831905 -382.191487) (xy 437.87776 -382.162022) (xy 437.927342 -382.139384)
			(xy 437.979641 -382.124033) (xy 438.033593 -382.116282) (xy 438.060846 -382.115822) (xy 438.090076 -382.11638)
			(xy 438.147851 -382.125317) (xy 438.203586 -382.142959) (xy 438.25598 -382.168894) (xy 438.303805 -382.202516)
			(xy 438.345945 -382.243038) (xy 438.364122 -382.265936) (xy 438.37256 -382.276333) (xy 438.393764 -382.29267)
			(xy 438.418483 -382.302943) (xy 438.445021 -382.306448) (xy 438.471559 -382.302943) (xy 438.496278 -382.29267)
			(xy 438.517482 -382.276333) (xy 438.52592 -382.265936) (xy 438.544107 -382.243043) (xy 438.586231 -382.2025)
			(xy 438.634051 -382.168863) (xy 438.686444 -382.14292) (xy 438.742184 -382.125279) (xy 438.799964 -382.116353)
			(xy 438.829196 -382.115822) (xy 438.856451 -382.116225) (xy 438.910407 -382.123982) (xy 438.962709 -382.139339)
			(xy 439.012294 -382.161983) (xy 439.058151 -382.191453) (xy 439.099348 -382.227149) (xy 439.135045 -382.268346)
			(xy 439.164515 -382.314203) (xy 439.171008 -382.32842) (xy 456.932282 -382.32842) (xy 456.936353 -382.272798)
			(xy 456.948479 -382.218361) (xy 456.968402 -382.16627) (xy 456.995698 -382.117635) (xy 457.029784 -382.073492)
			(xy 457.069933 -382.034783) (xy 457.115291 -382.002332) (xy 457.164891 -381.976831) (xy 457.217675 -381.958824)
			(xy 457.272518 -381.948694) (xy 457.328252 -381.946657) (xy 457.383689 -381.952757) (xy 457.437646 -381.966863)
			(xy 457.488975 -381.988675) (xy 457.536581 -382.017729) (xy 457.579449 -382.053404) (xy 457.616666 -382.094941)
			(xy 457.647439 -382.141454) (xy 457.671111 -382.191951) (xy 457.687179 -382.245358) (xy 457.695299 -382.300534)
			(xy 457.695808 -382.32842) (xy 457.695299 -382.356306) (xy 457.687179 -382.411482) (xy 457.678163 -382.44145)
			(xy 458.634082 -382.44145) (xy 458.638153 -382.385828) (xy 458.650279 -382.331391) (xy 458.670202 -382.2793)
			(xy 458.697498 -382.230665) (xy 458.731584 -382.186522) (xy 458.771733 -382.147813) (xy 458.817091 -382.115362)
			(xy 458.866691 -382.089861) (xy 458.919475 -382.071854) (xy 458.974318 -382.061724) (xy 459.030052 -382.059687)
			(xy 459.085489 -382.065787) (xy 459.139446 -382.079893) (xy 459.190775 -382.101705) (xy 459.238381 -382.130759)
			(xy 459.281249 -382.166434) (xy 459.318466 -382.207971) (xy 459.349239 -382.254484) (xy 459.372911 -382.304981)
			(xy 459.388979 -382.358388) (xy 459.389017 -382.358646) (xy 459.737458 -382.358646) (xy 459.741529 -382.303024)
			(xy 459.753655 -382.248587) (xy 459.773578 -382.196496) (xy 459.800874 -382.147861) (xy 459.83496 -382.103718)
			(xy 459.875109 -382.065009) (xy 459.920467 -382.032558) (xy 459.970067 -382.007057) (xy 460.022851 -381.98905)
			(xy 460.077694 -381.97892) (xy 460.133428 -381.976883) (xy 460.188865 -381.982983) (xy 460.242822 -381.997089)
			(xy 460.294151 -382.018901) (xy 460.341757 -382.047955) (xy 460.384625 -382.08363) (xy 460.421842 -382.125167)
			(xy 460.452615 -382.17168) (xy 460.476287 -382.222177) (xy 460.492355 -382.275584) (xy 460.500475 -382.33076)
			(xy 460.500984 -382.358646) (xy 460.500475 -382.386532) (xy 460.492355 -382.441708) (xy 460.476287 -382.495115)
			(xy 460.452615 -382.545612) (xy 460.421842 -382.592125) (xy 460.384625 -382.633662) (xy 460.341757 -382.669337)
			(xy 460.294151 -382.698391) (xy 460.242822 -382.720203) (xy 460.188865 -382.734309) (xy 460.133428 -382.740409)
			(xy 460.077694 -382.738372) (xy 460.022851 -382.728242) (xy 459.970067 -382.710235) (xy 459.920467 -382.684734)
			(xy 459.875109 -382.652283) (xy 459.83496 -382.613574) (xy 459.800874 -382.569431) (xy 459.773578 -382.520796)
			(xy 459.753655 -382.468705) (xy 459.741529 -382.414268) (xy 459.737458 -382.358646) (xy 459.389017 -382.358646)
			(xy 459.397099 -382.413564) (xy 459.397608 -382.44145) (xy 459.397099 -382.469336) (xy 459.388979 -382.524512)
			(xy 459.372911 -382.577919) (xy 459.349239 -382.628416) (xy 459.318466 -382.674929) (xy 459.281249 -382.716466)
			(xy 459.238381 -382.752141) (xy 459.190775 -382.781195) (xy 459.139446 -382.803007) (xy 459.085489 -382.817113)
			(xy 459.030052 -382.823213) (xy 458.974318 -382.821176) (xy 458.919475 -382.811046) (xy 458.866691 -382.793039)
			(xy 458.817091 -382.767538) (xy 458.771733 -382.735087) (xy 458.731584 -382.696378) (xy 458.697498 -382.652235)
			(xy 458.670202 -382.6036) (xy 458.650279 -382.551509) (xy 458.638153 -382.497072) (xy 458.634082 -382.44145)
			(xy 457.678163 -382.44145) (xy 457.671111 -382.464889) (xy 457.647439 -382.515386) (xy 457.616666 -382.561899)
			(xy 457.579449 -382.603436) (xy 457.536581 -382.639111) (xy 457.488975 -382.668165) (xy 457.437646 -382.689977)
			(xy 457.383689 -382.704083) (xy 457.328252 -382.710183) (xy 457.272518 -382.708146) (xy 457.217675 -382.698016)
			(xy 457.164891 -382.680009) (xy 457.115291 -382.654508) (xy 457.069933 -382.622057) (xy 457.029784 -382.583348)
			(xy 456.995698 -382.539205) (xy 456.968402 -382.49057) (xy 456.948479 -382.438479) (xy 456.936353 -382.384042)
			(xy 456.932282 -382.32842) (xy 439.171008 -382.32842) (xy 439.18716 -382.363787) (xy 439.202517 -382.416089)
			(xy 439.210275 -382.470045) (xy 439.210275 -382.524555) (xy 439.202517 -382.578511) (xy 439.18716 -382.630813)
			(xy 439.164515 -382.680397) (xy 439.135045 -382.726254) (xy 439.099348 -382.767451) (xy 439.058151 -382.803147)
			(xy 439.012294 -382.832617) (xy 438.962709 -382.855261) (xy 438.910407 -382.870618) (xy 438.856451 -382.878375)
			(xy 438.829196 -382.878838) (xy 438.799966 -382.878266) (xy 438.742192 -382.869334) (xy 438.686456 -382.851696)
			(xy 438.634062 -382.825763) (xy 438.586236 -382.792143) (xy 438.544097 -382.751622) (xy 438.52592 -382.728724)
			(xy 438.517509 -382.718283) (xy 438.496323 -382.701865) (xy 438.471591 -382.691536) (xy 438.445021 -382.688012)
			(xy 438.418451 -382.691536) (xy 438.393719 -382.701865) (xy 438.372533 -382.718283) (xy 438.364122 -382.728724)
			(xy 438.345962 -382.751639) (xy 438.303829 -382.792173) (xy 438.256003 -382.825801) (xy 438.203604 -382.851735)
			(xy 438.14786 -382.869367) (xy 438.090079 -382.878283) (xy 438.060846 -382.878838) (xy 438.033593 -382.878318)
			(xy 437.979641 -382.870567) (xy 437.927342 -382.855216) (xy 437.87776 -382.832578) (xy 437.831905 -382.803113)
			(xy 437.79071 -382.767423) (xy 437.755014 -382.726232) (xy 437.725544 -382.68038) (xy 437.7029 -382.630801)
			(xy 437.687543 -382.578504) (xy 437.679785 -382.524553) (xy 432.645058 -382.524553) (xy 432.645058 -382.903853)
			(xy 442.76693 -382.903853) (xy 442.76693 -382.849347) (xy 442.774686 -382.795396) (xy 442.790041 -382.743098)
			(xy 442.812682 -382.693518) (xy 442.842148 -382.647664) (xy 442.87784 -382.606469) (xy 442.91903 -382.570773)
			(xy 442.964881 -382.541302) (xy 443.014459 -382.518656) (xy 443.066755 -382.503295) (xy 443.120705 -382.495533)
			(xy 443.147958 -382.495044) (xy 443.176875 -382.495576) (xy 443.234046 -382.5043) (xy 443.289245 -382.521554)
			(xy 443.341207 -382.546943) (xy 443.388742 -382.579885) (xy 443.430758 -382.619625) (xy 443.448948 -382.64211)
			(xy 443.458845 -382.653915) (xy 443.484169 -382.671434) (xy 443.513562 -382.68061) (xy 443.544354 -382.68061)
			(xy 443.573747 -382.671434) (xy 443.599071 -382.653915) (xy 443.608968 -382.64211) (xy 443.62718 -382.619644)
			(xy 443.669195 -382.579907) (xy 443.716725 -382.546966) (xy 443.768683 -382.521574) (xy 443.823877 -382.504314)
			(xy 443.881043 -382.495581) (xy 443.909958 -382.495044) (xy 443.937209 -382.4956) (xy 443.991158 -382.503351)
			(xy 444.043454 -382.518702) (xy 444.093034 -382.541339) (xy 444.138886 -382.570802) (xy 444.180079 -382.606492)
			(xy 444.215772 -382.64768) (xy 444.245241 -382.69353) (xy 444.267883 -382.743106) (xy 444.28324 -382.795401)
			(xy 444.290997 -382.849349) (xy 444.290997 -382.903851) (xy 444.28324 -382.957799) (xy 444.26958 -383.004314)
			(xy 460.372458 -383.004314) (xy 460.376529 -382.948692) (xy 460.388655 -382.894255) (xy 460.408578 -382.842164)
			(xy 460.435874 -382.793529) (xy 460.46996 -382.749386) (xy 460.510109 -382.710677) (xy 460.555467 -382.678226)
			(xy 460.605067 -382.652725) (xy 460.657851 -382.634718) (xy 460.712694 -382.624588) (xy 460.768428 -382.622551)
			(xy 460.823865 -382.628651) (xy 460.877822 -382.642757) (xy 460.929151 -382.664569) (xy 460.976757 -382.693623)
			(xy 461.019625 -382.729298) (xy 461.056842 -382.770835) (xy 461.087615 -382.817348) (xy 461.111287 -382.867845)
			(xy 461.127355 -382.921252) (xy 461.135475 -382.976428) (xy 461.135984 -383.004314) (xy 461.135475 -383.0322)
			(xy 461.127355 -383.087376) (xy 461.111287 -383.140783) (xy 461.087615 -383.19128) (xy 461.056842 -383.237793)
			(xy 461.019625 -383.27933) (xy 460.976757 -383.315005) (xy 460.929151 -383.344059) (xy 460.877822 -383.365871)
			(xy 460.823865 -383.379977) (xy 460.768428 -383.386077) (xy 460.712694 -383.38404) (xy 460.657851 -383.37391)
			(xy 460.605067 -383.355903) (xy 460.555467 -383.330402) (xy 460.510109 -383.297951) (xy 460.46996 -383.259242)
			(xy 460.435874 -383.215099) (xy 460.408578 -383.166464) (xy 460.388655 -383.114373) (xy 460.376529 -383.059936)
			(xy 460.372458 -383.004314) (xy 444.26958 -383.004314) (xy 444.267883 -383.010094) (xy 444.245241 -383.05967)
			(xy 444.215772 -383.10552) (xy 444.180079 -383.146708) (xy 444.138886 -383.182398) (xy 444.093034 -383.211861)
			(xy 444.043454 -383.234498) (xy 443.991158 -383.249849) (xy 443.937209 -383.2576) (xy 443.909958 -383.25806)
			(xy 443.881042 -383.257515) (xy 443.823871 -383.248794) (xy 443.768672 -383.231542) (xy 443.71671 -383.206156)
			(xy 443.669176 -383.173216) (xy 443.627158 -383.133478) (xy 443.608968 -383.110994) (xy 443.599071 -383.099189)
			(xy 443.573747 -383.08167) (xy 443.544354 -383.072494) (xy 443.513562 -383.072494) (xy 443.484169 -383.08167)
			(xy 443.458845 -383.099189) (xy 443.448948 -383.110994) (xy 443.430728 -383.133453) (xy 443.388715 -383.17319)
			(xy 443.341186 -383.206132) (xy 443.28923 -383.231525) (xy 443.234038 -383.248786) (xy 443.176872 -383.257522)
			(xy 443.147958 -383.25806) (xy 443.120705 -383.257667) (xy 443.066755 -383.249905) (xy 443.014459 -383.234544)
			(xy 442.964881 -383.211898) (xy 442.91903 -383.182427) (xy 442.87784 -383.146731) (xy 442.842148 -383.105536)
			(xy 442.812682 -383.059682) (xy 442.790041 -383.010102) (xy 442.774686 -382.957804) (xy 442.76693 -382.903853)
			(xy 432.645058 -382.903853) (xy 432.645058 -384.569253) (xy 437.679785 -384.569253) (xy 437.679785 -384.514747)
			(xy 437.687543 -384.460796) (xy 437.7029 -384.408499) (xy 437.725544 -384.35892) (xy 437.755014 -384.313068)
			(xy 437.79071 -384.271877) (xy 437.831905 -384.236187) (xy 437.87776 -384.206722) (xy 437.927342 -384.184084)
			(xy 437.979641 -384.168733) (xy 438.033593 -384.160982) (xy 438.060846 -384.160522) (xy 438.090076 -384.16108)
			(xy 438.147851 -384.170017) (xy 438.203586 -384.187659) (xy 438.25598 -384.213594) (xy 438.303805 -384.247216)
			(xy 438.345945 -384.287738) (xy 438.364122 -384.310636) (xy 438.37256 -384.321033) (xy 438.393764 -384.33737)
			(xy 438.418483 -384.347643) (xy 438.445021 -384.351148) (xy 438.471559 -384.347643) (xy 438.496278 -384.33737)
			(xy 438.517482 -384.321033) (xy 438.52592 -384.310636) (xy 438.544107 -384.287743) (xy 438.586231 -384.2472)
			(xy 438.634051 -384.213563) (xy 438.686444 -384.18762) (xy 438.742184 -384.169979) (xy 438.799964 -384.161053)
			(xy 438.829196 -384.160522) (xy 438.856451 -384.160925) (xy 438.910407 -384.168682) (xy 438.962709 -384.184039)
			(xy 439.012294 -384.206683) (xy 439.058151 -384.236153) (xy 439.099348 -384.271849) (xy 439.135045 -384.313046)
			(xy 439.164515 -384.358903) (xy 439.18716 -384.408487) (xy 439.202517 -384.460789) (xy 439.210275 -384.514745)
			(xy 439.210275 -384.569255) (xy 439.202517 -384.623211) (xy 439.18716 -384.675513) (xy 439.164515 -384.725097)
			(xy 439.135045 -384.770954) (xy 439.099348 -384.812151) (xy 439.058151 -384.847847) (xy 439.012294 -384.877317)
			(xy 438.962709 -384.899961) (xy 438.910407 -384.915318) (xy 438.856451 -384.923075) (xy 438.829196 -384.923538)
			(xy 438.799966 -384.922966) (xy 438.742192 -384.914034) (xy 438.686456 -384.896396) (xy 438.634062 -384.870463)
			(xy 438.586236 -384.836843) (xy 438.544097 -384.796322) (xy 438.52592 -384.773424) (xy 438.517509 -384.762983)
			(xy 438.496323 -384.746565) (xy 438.471591 -384.736236) (xy 438.445021 -384.732712) (xy 438.418451 -384.736236)
			(xy 438.393719 -384.746565) (xy 438.372533 -384.762983) (xy 438.364122 -384.773424) (xy 438.345962 -384.796339)
			(xy 438.303829 -384.836873) (xy 438.256003 -384.870501) (xy 438.203604 -384.896435) (xy 438.14786 -384.914067)
			(xy 438.090079 -384.922983) (xy 438.060846 -384.923538) (xy 438.033593 -384.923018) (xy 437.979641 -384.915267)
			(xy 437.927342 -384.899916) (xy 437.87776 -384.877278) (xy 437.831905 -384.847813) (xy 437.79071 -384.812123)
			(xy 437.755014 -384.770932) (xy 437.725544 -384.72508) (xy 437.7029 -384.675501) (xy 437.687543 -384.623204)
			(xy 437.679785 -384.569253) (xy 432.645058 -384.569253) (xy 432.645058 -385.760468) (xy 432.645509 -385.773935)
			(xy 432.652627 -385.799914) (xy 432.666297 -385.823124) (xy 432.685564 -385.841948) (xy 432.709086 -385.855072)
			(xy 432.735224 -385.861584) (xy 432.762155 -385.861027) (xy 432.788001 -385.853442) (xy 432.799744 -385.846828)
			(xy 432.822391 -385.833439) (xy 432.870583 -385.812333) (xy 432.921218 -385.798052) (xy 432.973336 -385.790866)
			(xy 432.999642 -385.79044) (xy 433.026888 -385.790929) (xy 433.080824 -385.798689) (xy 433.133107 -385.814046)
			(xy 433.182673 -385.836687) (xy 433.228512 -385.866151) (xy 433.269692 -385.901838) (xy 433.305375 -385.943021)
			(xy 433.334833 -385.988864) (xy 433.357468 -386.038432) (xy 433.37282 -386.090717) (xy 433.380574 -386.144654)
			(xy 433.380574 -386.199146) (xy 433.37282 -386.253083) (xy 433.357468 -386.305368) (xy 433.337608 -386.348858)
			(xy 438.101609 -386.348858) (xy 438.101609 -386.294342) (xy 438.109368 -386.240381) (xy 438.124728 -386.188074)
			(xy 438.147376 -386.138485) (xy 438.176851 -386.092624) (xy 438.212554 -386.051425) (xy 438.253756 -386.015727)
			(xy 438.29962 -385.986257) (xy 438.349211 -385.963614) (xy 438.40152 -385.94826) (xy 438.455482 -385.940506)
			(xy 438.48274 -385.940046) (xy 438.511656 -385.94059) (xy 438.568827 -385.949311) (xy 438.624026 -385.966563)
			(xy 438.675988 -385.991949) (xy 438.723523 -386.024889) (xy 438.76554 -386.064628) (xy 438.78373 -386.087112)
			(xy 438.793627 -386.098917) (xy 438.818951 -386.116436) (xy 438.848344 -386.125612) (xy 438.879136 -386.125612)
			(xy 438.908529 -386.116436) (xy 438.933853 -386.098917) (xy 438.94375 -386.087112) (xy 438.960503 -386.066329)
			(xy 438.998857 -386.029199) (xy 439.042011 -385.997777) (xy 439.089125 -385.972678) (xy 439.139277 -385.954392)
			(xy 439.191488 -385.943275) (xy 439.24474 -385.939545) (xy 439.297992 -385.943275) (xy 439.350203 -385.954392)
			(xy 439.400355 -385.972678) (xy 439.447469 -385.997777) (xy 439.490623 -386.029199) (xy 439.528977 -386.066329)
			(xy 439.54573 -386.087112) (xy 439.555627 -386.098917) (xy 439.580951 -386.116436) (xy 439.610344 -386.125612)
			(xy 439.641136 -386.125612) (xy 439.670529 -386.116436) (xy 439.695853 -386.098917) (xy 439.70575 -386.087112)
			(xy 439.722503 -386.066329) (xy 439.760857 -386.029199) (xy 439.804011 -385.997777) (xy 439.851125 -385.972678)
			(xy 439.901277 -385.954392) (xy 439.953488 -385.943275) (xy 440.00674 -385.939545) (xy 440.059992 -385.943275)
			(xy 440.112203 -385.954392) (xy 440.162355 -385.972678) (xy 440.209469 -385.997777) (xy 440.252623 -386.029199)
			(xy 440.290977 -386.066329) (xy 440.30773 -386.087112) (xy 440.317627 -386.098917) (xy 440.342951 -386.116436)
			(xy 440.372344 -386.125612) (xy 440.403136 -386.125612) (xy 440.432529 -386.116436) (xy 440.457853 -386.098917)
			(xy 440.46775 -386.087112) (xy 440.485972 -386.064655) (xy 440.527985 -386.024918) (xy 440.575513 -385.991975)
			(xy 440.627469 -385.966582) (xy 440.682661 -385.94932) (xy 440.739826 -385.940585) (xy 440.76874 -385.940046)
			(xy 440.795986 -385.940627) (xy 440.849923 -385.948387) (xy 440.902206 -385.963744) (xy 440.951773 -385.986384)
			(xy 440.997612 -386.015848) (xy 441.038793 -386.051535) (xy 441.074476 -386.09272) (xy 441.103935 -386.138563)
			(xy 441.12657 -386.188131) (xy 441.141921 -386.240416) (xy 441.149676 -386.294354) (xy 441.149676 -386.348846)
			(xy 441.141921 -386.402784) (xy 441.12657 -386.455069) (xy 441.103935 -386.504637) (xy 441.074476 -386.55048)
			(xy 441.038793 -386.591665) (xy 440.997612 -386.627352) (xy 440.951773 -386.656816) (xy 440.902206 -386.679456)
			(xy 440.849923 -386.694813) (xy 440.795986 -386.702573) (xy 440.76874 -386.703062) (xy 440.739823 -386.702529)
			(xy 440.682652 -386.693805) (xy 440.627453 -386.676551) (xy 440.575491 -386.651162) (xy 440.527957 -386.618221)
			(xy 440.48594 -386.578481) (xy 440.46775 -386.555996) (xy 440.457853 -386.544191) (xy 440.432529 -386.526672)
			(xy 440.403136 -386.517496) (xy 440.372344 -386.517496) (xy 440.342951 -386.526672) (xy 440.317627 -386.544191)
			(xy 440.30773 -386.555996) (xy 440.290977 -386.576779) (xy 440.252623 -386.613909) (xy 440.209469 -386.645331)
			(xy 440.162355 -386.67043) (xy 440.112203 -386.688716) (xy 440.059992 -386.699833) (xy 440.00674 -386.703563)
			(xy 439.953488 -386.699833) (xy 439.901277 -386.688716) (xy 439.851125 -386.67043) (xy 439.804011 -386.645331)
			(xy 439.760857 -386.613909) (xy 439.722503 -386.576779) (xy 439.70575 -386.555996) (xy 439.695853 -386.544191)
			(xy 439.670529 -386.526672) (xy 439.641136 -386.517496) (xy 439.610344 -386.517496) (xy 439.580951 -386.526672)
			(xy 439.555627 -386.544191) (xy 439.54573 -386.555996) (xy 439.528977 -386.576779) (xy 439.490623 -386.613909)
			(xy 439.447469 -386.645331) (xy 439.400355 -386.67043) (xy 439.350203 -386.688716) (xy 439.297992 -386.699833)
			(xy 439.24474 -386.703563) (xy 439.191488 -386.699833) (xy 439.139277 -386.688716) (xy 439.089125 -386.67043)
			(xy 439.042011 -386.645331) (xy 438.998857 -386.613909) (xy 438.960503 -386.576779) (xy 438.94375 -386.555996)
			(xy 438.933853 -386.544191) (xy 438.908529 -386.526672) (xy 438.879136 -386.517496) (xy 438.848344 -386.517496)
			(xy 438.818951 -386.526672) (xy 438.793627 -386.544191) (xy 438.78373 -386.555996) (xy 438.765521 -386.578464)
			(xy 438.723505 -386.618201) (xy 438.675974 -386.651142) (xy 438.624016 -386.676533) (xy 438.568822 -386.693792)
			(xy 438.511655 -386.702525) (xy 438.48274 -386.703062) (xy 438.455482 -386.702694) (xy 438.40152 -386.69494)
			(xy 438.349211 -386.679586) (xy 438.29962 -386.656943) (xy 438.253756 -386.627473) (xy 438.212554 -386.591775)
			(xy 438.176851 -386.550576) (xy 438.147376 -386.504715) (xy 438.124728 -386.455126) (xy 438.109368 -386.402819)
			(xy 438.101609 -386.348858) (xy 433.337608 -386.348858) (xy 433.334833 -386.354936) (xy 433.305375 -386.400779)
			(xy 433.269692 -386.441962) (xy 433.228512 -386.477649) (xy 433.182673 -386.507113) (xy 433.133107 -386.529754)
			(xy 433.080824 -386.545111) (xy 433.026888 -386.552871) (xy 432.999642 -386.553456) (xy 432.973336 -386.553032)
			(xy 432.921219 -386.545841) (xy 432.870583 -386.531561) (xy 432.822388 -386.510463) (xy 432.799744 -386.497068)
			(xy 432.788042 -386.490389) (xy 432.762191 -386.482824) (xy 432.735261 -386.482284) (xy 432.709128 -386.488809)
			(xy 432.685612 -386.501943) (xy 432.666351 -386.520772) (xy 432.652686 -386.543983) (xy 432.64557 -386.569962)
			(xy 432.645058 -386.583428) (xy 432.645058 -387.371153) (xy 442.672159 -387.371153) (xy 442.672159 -387.316647)
			(xy 442.679917 -387.262695) (xy 442.695273 -387.210396) (xy 442.717917 -387.160816) (xy 442.747386 -387.114962)
			(xy 442.783081 -387.07377) (xy 442.824275 -387.038076) (xy 442.87013 -387.008609) (xy 442.919711 -386.985968)
			(xy 442.972011 -386.970613) (xy 443.025963 -386.962858) (xy 443.053216 -386.962396) (xy 443.082132 -386.962938)
			(xy 443.139304 -386.971657) (xy 443.194504 -386.988908) (xy 443.246467 -387.014295) (xy 443.294001 -387.047236)
			(xy 443.336017 -387.086977) (xy 443.354206 -387.109462) (xy 443.364103 -387.121267) (xy 443.389427 -387.138786)
			(xy 443.41882 -387.147962) (xy 443.449612 -387.147962) (xy 443.479005 -387.138786) (xy 443.504329 -387.121267)
			(xy 443.514226 -387.109462) (xy 443.532393 -387.086958) (xy 443.574419 -387.047226) (xy 443.621959 -387.01429)
			(xy 443.673925 -386.988906) (xy 443.729126 -386.971654) (xy 443.786299 -386.962929) (xy 443.815216 -386.962396)
			(xy 443.842467 -386.962875) (xy 443.896413 -386.970633) (xy 443.948707 -386.98599) (xy 443.998282 -387.008632)
			(xy 444.044131 -387.038099) (xy 444.08532 -387.073791) (xy 444.12101 -387.114981) (xy 444.150475 -387.160832)
			(xy 444.173116 -387.210408) (xy 444.18847 -387.262702) (xy 444.191125 -387.281166) (xy 455.690476 -387.281166)
			(xy 455.694547 -387.225544) (xy 455.706673 -387.171107) (xy 455.726596 -387.119016) (xy 455.753892 -387.070381)
			(xy 455.787978 -387.026238) (xy 455.828127 -386.987529) (xy 455.873485 -386.955078) (xy 455.923085 -386.929577)
			(xy 455.975869 -386.91157) (xy 456.030712 -386.90144) (xy 456.086446 -386.899403) (xy 456.141883 -386.905503)
			(xy 456.19584 -386.919609) (xy 456.247169 -386.941421) (xy 456.294775 -386.970475) (xy 456.337643 -387.00615)
			(xy 456.37486 -387.047687) (xy 456.405633 -387.0942) (xy 456.429305 -387.144697) (xy 456.445373 -387.198104)
			(xy 456.453493 -387.25328) (xy 456.454002 -387.281166) (xy 456.453493 -387.309052) (xy 456.445373 -387.364228)
			(xy 456.429305 -387.417635) (xy 456.405633 -387.468132) (xy 456.37486 -387.514645) (xy 456.337643 -387.556182)
			(xy 456.294775 -387.591857) (xy 456.247169 -387.620911) (xy 456.19584 -387.642723) (xy 456.141883 -387.656829)
			(xy 456.086446 -387.662929) (xy 456.030712 -387.660892) (xy 455.975869 -387.650762) (xy 455.923085 -387.632755)
			(xy 455.873485 -387.607254) (xy 455.828127 -387.574803) (xy 455.787978 -387.536094) (xy 455.753892 -387.491951)
			(xy 455.726596 -387.443316) (xy 455.706673 -387.391225) (xy 455.694547 -387.336788) (xy 455.690476 -387.281166)
			(xy 444.191125 -387.281166) (xy 444.196226 -387.316649) (xy 444.196226 -387.371151) (xy 444.18847 -387.425098)
			(xy 444.173116 -387.477392) (xy 444.150475 -387.526968) (xy 444.12101 -387.572819) (xy 444.08532 -387.614009)
			(xy 444.044131 -387.649701) (xy 443.998282 -387.679168) (xy 443.948707 -387.70181) (xy 443.896413 -387.717167)
			(xy 443.842467 -387.724925) (xy 443.815216 -387.725412) (xy 443.786298 -387.724916) (xy 443.729124 -387.716187)
			(xy 443.673923 -387.698927) (xy 443.621961 -387.673531) (xy 443.574428 -387.640582) (xy 443.532414 -387.600835)
			(xy 443.514226 -387.578346) (xy 443.504329 -387.566541) (xy 443.479005 -387.549022) (xy 443.449612 -387.539846)
			(xy 443.41882 -387.539846) (xy 443.389427 -387.549022) (xy 443.364103 -387.566541) (xy 443.354206 -387.578346)
			(xy 443.336023 -387.600836) (xy 443.294 -387.640569) (xy 443.246463 -387.673506) (xy 443.194501 -387.698893)
			(xy 443.139302 -387.716148) (xy 443.082132 -387.724877) (xy 443.053216 -387.725412) (xy 443.025963 -387.724942)
			(xy 442.972011 -387.717187) (xy 442.919711 -387.701832) (xy 442.87013 -387.679191) (xy 442.824275 -387.649724)
			(xy 442.783081 -387.61403) (xy 442.747386 -387.572838) (xy 442.717917 -387.526984) (xy 442.695273 -387.477404)
			(xy 442.679917 -387.425105) (xy 442.672159 -387.371153) (xy 432.645058 -387.371153) (xy 432.645058 -388.760253)
			(xy 438.101685 -388.760253) (xy 438.101685 -388.705747) (xy 438.109443 -388.651797) (xy 438.1248 -388.5995)
			(xy 438.147443 -388.549921) (xy 438.176913 -388.50407) (xy 438.212608 -388.46288) (xy 438.253802 -388.427189)
			(xy 438.299657 -388.397724) (xy 438.349238 -388.375086) (xy 438.401536 -388.359734) (xy 438.455487 -388.351983)
			(xy 438.48274 -388.351522) (xy 438.511656 -388.352075) (xy 438.568826 -388.360796) (xy 438.624024 -388.378046)
			(xy 438.675986 -388.403431) (xy 438.723521 -388.436369) (xy 438.765539 -388.476105) (xy 438.78373 -388.498588)
			(xy 438.793627 -388.510393) (xy 438.818951 -388.527912) (xy 438.848344 -388.537088) (xy 438.879136 -388.537088)
			(xy 438.908529 -388.527912) (xy 438.933853 -388.510393) (xy 438.94375 -388.498588) (xy 438.960503 -388.477805)
			(xy 438.998857 -388.440675) (xy 439.042011 -388.409253) (xy 439.089125 -388.384154) (xy 439.139277 -388.365868)
			(xy 439.191488 -388.354751) (xy 439.24474 -388.351021) (xy 439.297992 -388.354751) (xy 439.350203 -388.365868)
			(xy 439.400355 -388.384154) (xy 439.447469 -388.409253) (xy 439.490623 -388.440675) (xy 439.528977 -388.477805)
			(xy 439.54573 -388.498588) (xy 439.555627 -388.510393) (xy 439.580951 -388.527912) (xy 439.610344 -388.537088)
			(xy 439.641136 -388.537088) (xy 439.670529 -388.527912) (xy 439.695853 -388.510393) (xy 439.70575 -388.498588)
			(xy 439.722503 -388.477805) (xy 439.760857 -388.440675) (xy 439.804011 -388.409253) (xy 439.851125 -388.384154)
			(xy 439.901277 -388.365868) (xy 439.953488 -388.354751) (xy 440.00674 -388.351021) (xy 440.059992 -388.354751)
			(xy 440.112203 -388.365868) (xy 440.162355 -388.384154) (xy 440.209469 -388.409253) (xy 440.252623 -388.440675)
			(xy 440.290977 -388.477805) (xy 440.30773 -388.498588) (xy 440.317627 -388.510393) (xy 440.342951 -388.527912)
			(xy 440.372344 -388.537088) (xy 440.403136 -388.537088) (xy 440.432529 -388.527912) (xy 440.457853 -388.510393)
			(xy 440.46775 -388.498588) (xy 440.485966 -388.476126) (xy 440.527981 -388.43639) (xy 440.575511 -388.403449)
			(xy 440.627467 -388.378057) (xy 440.68266 -388.360796) (xy 440.739826 -388.352061) (xy 440.76874 -388.351522)
			(xy 440.795992 -388.351951) (xy 440.849939 -388.359712) (xy 440.902233 -388.375072) (xy 440.951809 -388.397717)
			(xy 440.997658 -388.427187) (xy 441.038847 -388.462881) (xy 441.074537 -388.504074) (xy 441.104002 -388.549926)
			(xy 441.126642 -388.599504) (xy 441.141996 -388.6518) (xy 441.149752 -388.705748) (xy 441.149752 -388.760252)
			(xy 441.141996 -388.8142) (xy 441.126642 -388.866496) (xy 441.104002 -388.916074) (xy 441.074537 -388.961926)
			(xy 441.038847 -389.003119) (xy 440.997658 -389.038813) (xy 440.951809 -389.068283) (xy 440.902233 -389.090928)
			(xy 440.849939 -389.106288) (xy 440.795992 -389.114049) (xy 440.76874 -389.114538) (xy 440.739823 -389.114015)
			(xy 440.682651 -389.10529) (xy 440.627451 -389.088035) (xy 440.575489 -389.062644) (xy 440.527955 -389.0297)
			(xy 440.485939 -388.989958) (xy 440.46775 -388.967472) (xy 440.457853 -388.955667) (xy 440.432529 -388.938148)
			(xy 440.403136 -388.928972) (xy 440.372344 -388.928972) (xy 440.342951 -388.938148) (xy 440.317627 -388.955667)
			(xy 440.30773 -388.967472) (xy 440.290977 -388.988255) (xy 440.252623 -389.025385) (xy 440.209469 -389.056807)
			(xy 440.162355 -389.081906) (xy 440.112203 -389.100192) (xy 440.059992 -389.111309) (xy 440.00674 -389.115039)
			(xy 439.953488 -389.111309) (xy 439.901277 -389.100192) (xy 439.851125 -389.081906) (xy 439.804011 -389.056807)
			(xy 439.760857 -389.025385) (xy 439.722503 -388.988255) (xy 439.70575 -388.967472) (xy 439.695853 -388.955667)
			(xy 439.670529 -388.938148) (xy 439.641136 -388.928972) (xy 439.610344 -388.928972) (xy 439.580951 -388.938148)
			(xy 439.555627 -388.955667) (xy 439.54573 -388.967472) (xy 439.528977 -388.988255) (xy 439.490623 -389.025385)
			(xy 439.447469 -389.056807) (xy 439.400355 -389.081906) (xy 439.350203 -389.100192) (xy 439.297992 -389.111309)
			(xy 439.24474 -389.115039) (xy 439.191488 -389.111309) (xy 439.139277 -389.100192) (xy 439.089125 -389.081906)
			(xy 439.042011 -389.056807) (xy 438.998857 -389.025385) (xy 438.960503 -388.988255) (xy 438.94375 -388.967472)
			(xy 438.933853 -388.955667) (xy 438.908529 -388.938148) (xy 438.879136 -388.928972) (xy 438.848344 -388.928972)
			(xy 438.818951 -388.938148) (xy 438.793627 -388.955667) (xy 438.78373 -388.967472) (xy 438.765515 -388.989935)
			(xy 438.723501 -389.029673) (xy 438.675971 -389.062615) (xy 438.624015 -389.088007) (xy 438.568821 -389.105268)
			(xy 438.511655 -389.114001) (xy 438.48274 -389.114538) (xy 438.455487 -389.114017) (xy 438.401536 -389.106266)
			(xy 438.349238 -389.090914) (xy 438.299657 -389.068276) (xy 438.253802 -389.038811) (xy 438.212608 -389.00312)
			(xy 438.176913 -388.96193) (xy 438.147443 -388.916079) (xy 438.1248 -388.8665) (xy 438.109443 -388.814203)
			(xy 438.101685 -388.760253) (xy 432.645058 -388.760253) (xy 432.645058 -391.094468) (xy 432.645509 -391.107935)
			(xy 432.652627 -391.133914) (xy 432.666297 -391.157124) (xy 432.685564 -391.175948) (xy 432.709086 -391.189072)
			(xy 432.735224 -391.195584) (xy 432.762155 -391.195027) (xy 432.788001 -391.187442) (xy 432.799744 -391.180828)
			(xy 432.822391 -391.167439) (xy 432.870583 -391.146333) (xy 432.921218 -391.132052) (xy 432.973336 -391.124866)
			(xy 432.999642 -391.12444) (xy 433.026888 -391.124929) (xy 433.080824 -391.132689) (xy 433.133107 -391.148046)
			(xy 433.182673 -391.170687) (xy 433.228512 -391.200151) (xy 433.269692 -391.235838) (xy 433.305375 -391.277021)
			(xy 433.334833 -391.322864) (xy 433.357468 -391.372432) (xy 433.37282 -391.424717) (xy 433.380574 -391.478654)
			(xy 433.380574 -391.533146) (xy 433.37282 -391.587083) (xy 433.357468 -391.639368) (xy 433.334833 -391.688936)
			(xy 433.305375 -391.734779) (xy 433.269692 -391.775962) (xy 433.228512 -391.811649) (xy 433.182673 -391.841113)
			(xy 433.133107 -391.863754) (xy 433.080824 -391.879111) (xy 433.026888 -391.886871) (xy 432.999642 -391.887456)
			(xy 432.973336 -391.887032) (xy 432.921219 -391.879841) (xy 432.870583 -391.865561) (xy 432.822388 -391.844463)
			(xy 432.799744 -391.831068) (xy 432.788042 -391.824389) (xy 432.762191 -391.816824) (xy 432.735261 -391.816284)
			(xy 432.709128 -391.822809) (xy 432.685612 -391.835943) (xy 432.666351 -391.854772) (xy 432.652686 -391.877983)
			(xy 432.64557 -391.903962) (xy 432.645058 -391.917428) (xy 432.645058 -393.67079) (xy 432.65979 -393.685776)
			(xy 434.970428 -395.996414) (xy 434.985414 -396.011146) (xy 465.30133 -396.011146)
		)
		(stroke
			(width 0)
			(type solid)
		)
		(fill yes)
		(layer "In6.Cu")
		(net "GND")
	)
	(gr_poly
		(pts
			(xy 437.1594 -108.720128) (xy 437.1594 -97.254568) (xy 436.72252 -96.817688) (xy 436.71233 -96.808166)
			(xy 436.687982 -96.794587) (xy 436.660868 -96.788102) (xy 436.63301 -96.789194) (xy 436.606487 -96.797782)
			(xy 436.583276 -96.813225) (xy 436.565109 -96.834371) (xy 436.553339 -96.859644) (xy 436.550562 -96.873314)
			(xy 436.54582 -96.899826) (xy 436.529856 -96.951265) (xy 436.506817 -96.999947) (xy 436.477161 -97.044905)
			(xy 436.441477 -97.085245) (xy 436.400474 -97.120166) (xy 436.354967 -97.148974) (xy 436.305861 -97.171095)
			(xy 436.254133 -97.186091) (xy 436.200809 -97.193662) (xy 436.17388 -97.194116) (xy 436.146629 -97.193629)
			(xy 436.092683 -97.18587) (xy 436.040391 -97.170513) (xy 435.990815 -97.147871) (xy 435.944967 -97.118404)
			(xy 435.903778 -97.082713) (xy 435.868088 -97.041523) (xy 435.838623 -96.995674) (xy 435.815982 -96.946098)
			(xy 435.800627 -96.893805) (xy 435.79287 -96.839859) (xy 435.792372 -96.812608) (xy 435.792834 -96.785677)
			(xy 435.800406 -96.732351) (xy 435.815401 -96.68062) (xy 435.83752 -96.63151) (xy 435.866325 -96.585999)
			(xy 435.901242 -96.544989) (xy 435.941579 -96.509297) (xy 435.986534 -96.479631) (xy 436.035213 -96.45658)
			(xy 436.08665 -96.440602) (xy 436.113174 -96.435926) (xy 436.126886 -96.43327) (xy 436.152212 -96.421518)
			(xy 436.173405 -96.403342) (xy 436.188878 -96.380102) (xy 436.197474 -96.353538) (xy 436.198547 -96.325638)
			(xy 436.192019 -96.298492) (xy 436.178378 -96.274132) (xy 436.1688 -96.263968) (xy 435.82336 -95.918528)
			(xy 418.1094 -95.918528) (xy 417.21532 -96.812608) (xy 434.902862 -96.812608) (xy 434.906933 -96.756986)
			(xy 434.919059 -96.702549) (xy 434.938982 -96.650458) (xy 434.966278 -96.601823) (xy 435.000364 -96.55768)
			(xy 435.040513 -96.518971) (xy 435.085871 -96.48652) (xy 435.135471 -96.461019) (xy 435.188255 -96.443012)
			(xy 435.243098 -96.432882) (xy 435.298832 -96.430845) (xy 435.354269 -96.436945) (xy 435.408226 -96.451051)
			(xy 435.459555 -96.472863) (xy 435.507161 -96.501917) (xy 435.550029 -96.537592) (xy 435.587246 -96.579129)
			(xy 435.618019 -96.625642) (xy 435.641691 -96.676139) (xy 435.657759 -96.729546) (xy 435.665879 -96.784722)
			(xy 435.666388 -96.812608) (xy 435.665879 -96.840494) (xy 435.657759 -96.89567) (xy 435.641691 -96.949077)
			(xy 435.618019 -96.999574) (xy 435.587246 -97.046087) (xy 435.550029 -97.087624) (xy 435.507161 -97.123299)
			(xy 435.459555 -97.152353) (xy 435.408226 -97.174165) (xy 435.354269 -97.188271) (xy 435.298832 -97.194371)
			(xy 435.243098 -97.192334) (xy 435.188255 -97.182204) (xy 435.135471 -97.164197) (xy 435.085871 -97.138696)
			(xy 435.040513 -97.106245) (xy 435.000364 -97.067536) (xy 434.966278 -97.023393) (xy 434.938982 -96.974758)
			(xy 434.919059 -96.922667) (xy 434.906933 -96.86823) (xy 434.902862 -96.812608) (xy 417.21532 -96.812608)
			(xy 416.32632 -97.701608) (xy 434.902862 -97.701608) (xy 434.906933 -97.645986) (xy 434.919059 -97.591549)
			(xy 434.938982 -97.539458) (xy 434.966278 -97.490823) (xy 435.000364 -97.44668) (xy 435.040513 -97.407971)
			(xy 435.085871 -97.37552) (xy 435.135471 -97.350019) (xy 435.188255 -97.332012) (xy 435.243098 -97.321882)
			(xy 435.298832 -97.319845) (xy 435.354269 -97.325945) (xy 435.408226 -97.340051) (xy 435.459555 -97.361863)
			(xy 435.507161 -97.390917) (xy 435.550029 -97.426592) (xy 435.587246 -97.468129) (xy 435.618019 -97.514642)
			(xy 435.641691 -97.565139) (xy 435.657759 -97.618546) (xy 435.665879 -97.673722) (xy 435.666388 -97.701608)
			(xy 435.791862 -97.701608) (xy 435.795933 -97.645986) (xy 435.808059 -97.591549) (xy 435.827982 -97.539458)
			(xy 435.855278 -97.490823) (xy 435.889364 -97.44668) (xy 435.929513 -97.407971) (xy 435.974871 -97.37552)
			(xy 436.024471 -97.350019) (xy 436.077255 -97.332012) (xy 436.132098 -97.321882) (xy 436.187832 -97.319845)
			(xy 436.243269 -97.325945) (xy 436.297226 -97.340051) (xy 436.348555 -97.361863) (xy 436.396161 -97.390917)
			(xy 436.439029 -97.426592) (xy 436.476246 -97.468129) (xy 436.507019 -97.514642) (xy 436.530691 -97.565139)
			(xy 436.546759 -97.618546) (xy 436.554879 -97.673722) (xy 436.555388 -97.701608) (xy 436.554879 -97.729494)
			(xy 436.546759 -97.78467) (xy 436.530691 -97.838077) (xy 436.507019 -97.888574) (xy 436.476246 -97.935087)
			(xy 436.439029 -97.976624) (xy 436.396161 -98.012299) (xy 436.348555 -98.041353) (xy 436.297226 -98.063165)
			(xy 436.243269 -98.077271) (xy 436.187832 -98.083371) (xy 436.132098 -98.081334) (xy 436.077255 -98.071204)
			(xy 436.024471 -98.053197) (xy 435.974871 -98.027696) (xy 435.929513 -97.995245) (xy 435.889364 -97.956536)
			(xy 435.855278 -97.912393) (xy 435.827982 -97.863758) (xy 435.808059 -97.811667) (xy 435.795933 -97.75723)
			(xy 435.791862 -97.701608) (xy 435.666388 -97.701608) (xy 435.665879 -97.729494) (xy 435.657759 -97.78467)
			(xy 435.641691 -97.838077) (xy 435.618019 -97.888574) (xy 435.587246 -97.935087) (xy 435.550029 -97.976624)
			(xy 435.507161 -98.012299) (xy 435.459555 -98.041353) (xy 435.408226 -98.063165) (xy 435.354269 -98.077271)
			(xy 435.298832 -98.083371) (xy 435.243098 -98.081334) (xy 435.188255 -98.071204) (xy 435.135471 -98.053197)
			(xy 435.085871 -98.027696) (xy 435.040513 -97.995245) (xy 435.000364 -97.956536) (xy 434.966278 -97.912393)
			(xy 434.938982 -97.863758) (xy 434.919059 -97.811667) (xy 434.906933 -97.75723) (xy 434.902862 -97.701608)
			(xy 416.32632 -97.701608) (xy 415.43732 -98.590608) (xy 434.902862 -98.590608) (xy 434.906933 -98.534986)
			(xy 434.919059 -98.480549) (xy 434.938982 -98.428458) (xy 434.966278 -98.379823) (xy 435.000364 -98.33568)
			(xy 435.040513 -98.296971) (xy 435.085871 -98.26452) (xy 435.135471 -98.239019) (xy 435.188255 -98.221012)
			(xy 435.243098 -98.210882) (xy 435.298832 -98.208845) (xy 435.354269 -98.214945) (xy 435.408226 -98.229051)
			(xy 435.459555 -98.250863) (xy 435.507161 -98.279917) (xy 435.550029 -98.315592) (xy 435.587246 -98.357129)
			(xy 435.618019 -98.403642) (xy 435.641691 -98.454139) (xy 435.657759 -98.507546) (xy 435.665879 -98.562722)
			(xy 435.666388 -98.590608) (xy 435.791862 -98.590608) (xy 435.795933 -98.534986) (xy 435.808059 -98.480549)
			(xy 435.827982 -98.428458) (xy 435.855278 -98.379823) (xy 435.889364 -98.33568) (xy 435.929513 -98.296971)
			(xy 435.974871 -98.26452) (xy 436.024471 -98.239019) (xy 436.077255 -98.221012) (xy 436.132098 -98.210882)
			(xy 436.187832 -98.208845) (xy 436.243269 -98.214945) (xy 436.297226 -98.229051) (xy 436.348555 -98.250863)
			(xy 436.396161 -98.279917) (xy 436.439029 -98.315592) (xy 436.476246 -98.357129) (xy 436.507019 -98.403642)
			(xy 436.530691 -98.454139) (xy 436.546759 -98.507546) (xy 436.554879 -98.562722) (xy 436.555388 -98.590608)
			(xy 436.554879 -98.618494) (xy 436.546759 -98.67367) (xy 436.530691 -98.727077) (xy 436.507019 -98.777574)
			(xy 436.476246 -98.824087) (xy 436.439029 -98.865624) (xy 436.396161 -98.901299) (xy 436.348555 -98.930353)
			(xy 436.297226 -98.952165) (xy 436.243269 -98.966271) (xy 436.187832 -98.972371) (xy 436.132098 -98.970334)
			(xy 436.077255 -98.960204) (xy 436.024471 -98.942197) (xy 435.974871 -98.916696) (xy 435.929513 -98.884245)
			(xy 435.889364 -98.845536) (xy 435.855278 -98.801393) (xy 435.827982 -98.752758) (xy 435.808059 -98.700667)
			(xy 435.795933 -98.64623) (xy 435.791862 -98.590608) (xy 435.666388 -98.590608) (xy 435.665879 -98.618494)
			(xy 435.657759 -98.67367) (xy 435.641691 -98.727077) (xy 435.618019 -98.777574) (xy 435.587246 -98.824087)
			(xy 435.550029 -98.865624) (xy 435.507161 -98.901299) (xy 435.459555 -98.930353) (xy 435.408226 -98.952165)
			(xy 435.354269 -98.966271) (xy 435.298832 -98.972371) (xy 435.243098 -98.970334) (xy 435.188255 -98.960204)
			(xy 435.135471 -98.942197) (xy 435.085871 -98.916696) (xy 435.040513 -98.884245) (xy 435.000364 -98.845536)
			(xy 434.966278 -98.801393) (xy 434.938982 -98.752758) (xy 434.919059 -98.700667) (xy 434.906933 -98.64623)
			(xy 434.902862 -98.590608) (xy 415.43732 -98.590608) (xy 414.8328 -99.195128) (xy 414.8328 -99.479608)
			(xy 434.902862 -99.479608) (xy 434.906933 -99.423986) (xy 434.919059 -99.369549) (xy 434.938982 -99.317458)
			(xy 434.966278 -99.268823) (xy 435.000364 -99.22468) (xy 435.040513 -99.185971) (xy 435.085871 -99.15352)
			(xy 435.135471 -99.128019) (xy 435.188255 -99.110012) (xy 435.243098 -99.099882) (xy 435.298832 -99.097845)
			(xy 435.354269 -99.103945) (xy 435.408226 -99.118051) (xy 435.459555 -99.139863) (xy 435.507161 -99.168917)
			(xy 435.550029 -99.204592) (xy 435.587246 -99.246129) (xy 435.618019 -99.292642) (xy 435.641691 -99.343139)
			(xy 435.657759 -99.396546) (xy 435.665879 -99.451722) (xy 435.666388 -99.479608) (xy 435.791862 -99.479608)
			(xy 435.795933 -99.423986) (xy 435.808059 -99.369549) (xy 435.827982 -99.317458) (xy 435.855278 -99.268823)
			(xy 435.889364 -99.22468) (xy 435.929513 -99.185971) (xy 435.974871 -99.15352) (xy 436.024471 -99.128019)
			(xy 436.077255 -99.110012) (xy 436.132098 -99.099882) (xy 436.187832 -99.097845) (xy 436.243269 -99.103945)
			(xy 436.297226 -99.118051) (xy 436.348555 -99.139863) (xy 436.396161 -99.168917) (xy 436.439029 -99.204592)
			(xy 436.476246 -99.246129) (xy 436.507019 -99.292642) (xy 436.530691 -99.343139) (xy 436.546759 -99.396546)
			(xy 436.554879 -99.451722) (xy 436.555388 -99.479608) (xy 436.554879 -99.507494) (xy 436.546759 -99.56267)
			(xy 436.530691 -99.616077) (xy 436.507019 -99.666574) (xy 436.476246 -99.713087) (xy 436.439029 -99.754624)
			(xy 436.396161 -99.790299) (xy 436.348555 -99.819353) (xy 436.297226 -99.841165) (xy 436.243269 -99.855271)
			(xy 436.187832 -99.861371) (xy 436.132098 -99.859334) (xy 436.077255 -99.849204) (xy 436.024471 -99.831197)
			(xy 435.974871 -99.805696) (xy 435.929513 -99.773245) (xy 435.889364 -99.734536) (xy 435.855278 -99.690393)
			(xy 435.827982 -99.641758) (xy 435.808059 -99.589667) (xy 435.795933 -99.53523) (xy 435.791862 -99.479608)
			(xy 435.666388 -99.479608) (xy 435.665879 -99.507494) (xy 435.657759 -99.56267) (xy 435.641691 -99.616077)
			(xy 435.618019 -99.666574) (xy 435.587246 -99.713087) (xy 435.550029 -99.754624) (xy 435.507161 -99.790299)
			(xy 435.459555 -99.819353) (xy 435.408226 -99.841165) (xy 435.354269 -99.855271) (xy 435.298832 -99.861371)
			(xy 435.243098 -99.859334) (xy 435.188255 -99.849204) (xy 435.135471 -99.831197) (xy 435.085871 -99.805696)
			(xy 435.040513 -99.773245) (xy 435.000364 -99.734536) (xy 434.966278 -99.690393) (xy 434.938982 -99.641758)
			(xy 434.919059 -99.589667) (xy 434.906933 -99.53523) (xy 434.902862 -99.479608) (xy 414.8328 -99.479608)
			(xy 414.8328 -102.63945) (xy 429.495968 -102.63945) (xy 429.495968 -102.58495) (xy 429.503724 -102.531003)
			(xy 429.519077 -102.47871) (xy 429.541717 -102.429134) (xy 429.57118 -102.383284) (xy 429.606869 -102.342093)
			(xy 429.648057 -102.306401) (xy 429.693904 -102.276933) (xy 429.743478 -102.254289) (xy 429.79577 -102.238931)
			(xy 429.849716 -102.23117) (xy 429.876966 -102.230682) (xy 429.903569 -102.231164) (xy 429.95626 -102.238541)
			(xy 430.007415 -102.25317) (xy 430.056039 -102.274767) (xy 430.10119 -102.302914) (xy 430.14199 -102.337062)
			(xy 430.177648 -102.376551) (xy 430.192942 -102.398322) (xy 430.201276 -102.409802) (xy 430.22302 -102.428006)
			(xy 430.248933 -102.439524) (xy 430.277016 -102.443464) (xy 430.305099 -102.439524) (xy 430.331012 -102.428006)
			(xy 430.352756 -102.409802) (xy 430.36109 -102.398322) (xy 430.376374 -102.376544) (xy 430.412042 -102.337065)
			(xy 430.452848 -102.302923) (xy 430.498 -102.274779) (xy 430.546623 -102.253178) (xy 430.597775 -102.238539)
			(xy 430.650463 -102.231145) (xy 430.677066 -102.230682) (xy 430.704318 -102.231187) (xy 430.758266 -102.238939)
			(xy 430.810563 -102.25429) (xy 430.860142 -102.276928) (xy 430.905995 -102.306392) (xy 430.947188 -102.342081)
			(xy 430.982882 -102.38327) (xy 431.012351 -102.429119) (xy 431.034994 -102.478696) (xy 431.050352 -102.53099)
			(xy 431.05811 -102.584938) (xy 431.058574 -102.61219) (xy 431.058169 -102.636998) (xy 431.057848 -102.639451)
			(xy 431.370468 -102.639451) (xy 431.370468 -102.584949) (xy 431.378224 -102.531001) (xy 431.393579 -102.478706)
			(xy 431.41622 -102.429128) (xy 431.445685 -102.383277) (xy 431.481376 -102.342086) (xy 431.522566 -102.306394)
			(xy 431.568416 -102.276926) (xy 431.617993 -102.254284) (xy 431.670287 -102.238927) (xy 431.724235 -102.231169)
			(xy 431.751486 -102.230682) (xy 431.780451 -102.231233) (xy 431.837715 -102.240002) (xy 431.892995 -102.257325)
			(xy 431.945022 -102.282805) (xy 431.9926 -102.315856) (xy 432.034635 -102.355719) (xy 432.070163 -102.401477)
			(xy 432.084734 -102.426516) (xy 432.092088 -102.438728) (xy 432.112316 -102.458797) (xy 432.137304 -102.472494)
			(xy 432.165104 -102.47875) (xy 432.19355 -102.47708) (xy 432.220426 -102.467612) (xy 432.243639 -102.451085)
			(xy 432.252882 -102.440232) (xy 432.271098 -102.418176) (xy 432.313 -102.379236) (xy 432.360242 -102.346983)
			(xy 432.411768 -102.322139) (xy 432.466423 -102.30526) (xy 432.522985 -102.296724) (xy 432.551586 -102.296214)
			(xy 432.578841 -102.296632) (xy 432.632797 -102.304388) (xy 432.685099 -102.319743) (xy 432.734684 -102.342386)
			(xy 432.780542 -102.371856) (xy 432.821738 -102.407552) (xy 432.857436 -102.448747) (xy 432.886907 -102.494604)
			(xy 432.909552 -102.544188) (xy 432.924909 -102.59649) (xy 432.932667 -102.650445) (xy 432.932667 -102.704955)
			(xy 432.924909 -102.75891) (xy 432.909552 -102.811212) (xy 432.886907 -102.860796) (xy 432.857436 -102.906653)
			(xy 432.821738 -102.947848) (xy 432.780542 -102.983544) (xy 432.734684 -103.013014) (xy 432.685099 -103.035657)
			(xy 432.632797 -103.051012) (xy 432.578841 -103.058768) (xy 432.551586 -103.05923) (xy 432.522618 -103.058746)
			(xy 432.465349 -103.049971) (xy 432.410065 -103.032639) (xy 432.358036 -103.007149) (xy 432.310459 -102.974086)
			(xy 432.268427 -102.934212) (xy 432.232905 -102.888441) (xy 432.218338 -102.863396) (xy 432.211021 -102.851159)
			(xy 432.190786 -102.831086) (xy 432.16579 -102.817388) (xy 432.137982 -102.811133) (xy 432.109529 -102.812809)
			(xy 432.082648 -102.822285) (xy 432.059433 -102.838822) (xy 432.05019 -102.84968) (xy 432.031993 -102.871752)
			(xy 431.990086 -102.91069) (xy 431.94284 -102.942941) (xy 431.891311 -102.967782) (xy 431.836652 -102.984658)
			(xy 431.780088 -102.99319) (xy 431.751486 -102.993698) (xy 431.724235 -102.993231) (xy 431.670287 -102.985473)
			(xy 431.617993 -102.970116) (xy 431.568416 -102.947474) (xy 431.522566 -102.918006) (xy 431.481376 -102.882314)
			(xy 431.445685 -102.841123) (xy 431.41622 -102.795272) (xy 431.393579 -102.745694) (xy 431.378224 -102.693399)
			(xy 431.370468 -102.639451) (xy 431.057848 -102.639451) (xy 431.051732 -102.686194) (xy 431.038953 -102.734135)
			(xy 431.029872 -102.757224) (xy 431.025139 -102.769969) (xy 431.0218 -102.796937) (xy 431.025686 -102.823832)
			(xy 431.036521 -102.848752) (xy 431.053541 -102.869936) (xy 431.075541 -102.885887) (xy 431.100967 -102.895476)
			(xy 431.114454 -102.897178) (xy 431.142478 -102.90029) (xy 431.197232 -102.913751) (xy 431.249408 -102.935124)
			(xy 431.29787 -102.963943) (xy 431.341562 -102.999582) (xy 431.379534 -103.041264) (xy 431.410956 -103.08808)
			(xy 431.435146 -103.139011) (xy 431.451576 -103.192948) (xy 431.459889 -103.248716) (xy 431.460402 -103.276908)
			(xy 431.459916 -103.304159) (xy 431.45216 -103.358107) (xy 431.436805 -103.410402) (xy 431.414163 -103.459979)
			(xy 431.384697 -103.505829) (xy 431.349006 -103.54702) (xy 431.307815 -103.582711) (xy 431.261965 -103.612177)
			(xy 431.212388 -103.634819) (xy 431.160093 -103.650174) (xy 431.106145 -103.65793) (xy 431.051643 -103.65793)
			(xy 430.997695 -103.650174) (xy 430.9454 -103.634819) (xy 430.895823 -103.612177) (xy 430.849973 -103.582711)
			(xy 430.808782 -103.54702) (xy 430.773091 -103.505829) (xy 430.743625 -103.459979) (xy 430.720983 -103.410402)
			(xy 430.705628 -103.358107) (xy 430.697872 -103.304159) (xy 430.697386 -103.276908) (xy 430.697793 -103.2521)
			(xy 430.704229 -103.202905) (xy 430.717007 -103.154963) (xy 430.726088 -103.131874) (xy 430.730856 -103.11914)
			(xy 430.734198 -103.092165) (xy 430.730311 -103.065263) (xy 430.71947 -103.040337) (xy 430.702443 -103.019151)
			(xy 430.680433 -103.003201) (xy 430.654997 -102.993618) (xy 430.641506 -102.99192) (xy 430.613609 -102.988818)
			(xy 430.559087 -102.975477) (xy 430.50711 -102.95429) (xy 430.458798 -102.925714) (xy 430.415195 -102.890368)
			(xy 430.377243 -102.849014) (xy 430.36109 -102.826058) (xy 430.352756 -102.814578) (xy 430.331012 -102.796374)
			(xy 430.305099 -102.784856) (xy 430.277016 -102.780916) (xy 430.248933 -102.784856) (xy 430.22302 -102.796374)
			(xy 430.201276 -102.814578) (xy 430.192942 -102.826058) (xy 430.177632 -102.847817) (xy 430.141968 -102.887297)
			(xy 430.101167 -102.921441) (xy 430.05602 -102.949588) (xy 430.007401 -102.971192) (xy 429.956253 -102.985835)
			(xy 429.903567 -102.993232) (xy 429.876966 -102.993698) (xy 429.849716 -102.99323) (xy 429.79577 -102.985469)
			(xy 429.743478 -102.970111) (xy 429.693904 -102.947467) (xy 429.648057 -102.917999) (xy 429.606869 -102.882307)
			(xy 429.57118 -102.841116) (xy 429.541717 -102.795266) (xy 429.519077 -102.74569) (xy 429.503724 -102.693397)
			(xy 429.495968 -102.63945) (xy 414.8328 -102.63945) (xy 414.8328 -104.501188) (xy 418.035232 -104.501188)
			(xy 418.035683 -104.473817) (xy 418.043503 -104.419637) (xy 418.058996 -104.367134) (xy 418.081841 -104.317387)
			(xy 418.111569 -104.271421) (xy 418.129212 -104.25049) (xy 418.138459 -104.239171) (xy 418.150634 -104.21261)
			(xy 418.154804 -104.183691) (xy 418.150629 -104.154773) (xy 418.13845 -104.128214) (xy 418.129212 -104.116886)
			(xy 418.111602 -104.095931) (xy 418.081885 -104.049965) (xy 418.059043 -104.000223) (xy 418.043546 -103.947727)
			(xy 418.03571 -103.893556) (xy 418.035232 -103.866188) (xy 418.035644 -103.838933) (xy 418.043403 -103.784978)
			(xy 418.058763 -103.732677) (xy 418.08141 -103.683094) (xy 418.110883 -103.637239) (xy 418.146582 -103.596045)
			(xy 418.187781 -103.560352) (xy 418.23364 -103.530885) (xy 418.283226 -103.508245) (xy 418.335529 -103.492892)
			(xy 418.389485 -103.48514) (xy 418.41674 -103.48468) (xy 418.442319 -103.485084) (xy 418.493018 -103.491932)
			(xy 418.542348 -103.505486) (xy 418.589428 -103.525504) (xy 418.633414 -103.551628) (xy 418.673519 -103.583389)
			(xy 418.691568 -103.60152) (xy 418.701199 -103.61092) (xy 418.724293 -103.624724) (xy 418.750189 -103.632019)
			(xy 418.777092 -103.6323) (xy 418.803136 -103.625548) (xy 418.826513 -103.612231) (xy 418.836348 -103.603044)
			(xy 418.857913 -103.582417) (xy 418.906289 -103.547481) (xy 418.959517 -103.520507) (xy 419.016298 -103.502155)
			(xy 419.075244 -103.492872) (xy 419.10508 -103.4923) (xy 419.132333 -103.492774) (xy 419.186284 -103.500528)
			(xy 419.238582 -103.515882) (xy 419.288162 -103.538523) (xy 419.334016 -103.56799) (xy 419.375209 -103.603682)
			(xy 419.410903 -103.644874) (xy 419.440371 -103.690727) (xy 419.463013 -103.740307) (xy 419.478369 -103.792605)
			(xy 419.486125 -103.846555) (xy 419.486588 -103.873808) (xy 419.48613 -103.901179) (xy 419.47831 -103.955358)
			(xy 419.46282 -104.007861) (xy 419.439976 -104.057608) (xy 419.41025 -104.103575) (xy 419.392608 -104.124506)
			(xy 419.383363 -104.135827) (xy 419.371185 -104.162387) (xy 419.367014 -104.191306) (xy 419.371189 -104.220225)
			(xy 419.383369 -104.246783) (xy 419.392608 -104.25811) (xy 419.410266 -104.279026) (xy 419.439975 -104.325004)
			(xy 419.462807 -104.374755) (xy 419.478294 -104.427259) (xy 419.486117 -104.481438) (xy 419.486588 -104.508808)
			(xy 419.486152 -104.536062) (xy 419.478393 -104.590015) (xy 419.463035 -104.642314) (xy 419.440391 -104.691896)
			(xy 419.41092 -104.73775) (xy 419.375223 -104.778943) (xy 419.334028 -104.814637) (xy 419.288171 -104.844104)
			(xy 419.238588 -104.866745) (xy 419.186287 -104.882099) (xy 419.132334 -104.889854) (xy 419.10508 -104.890316)
			(xy 419.079501 -104.8899) (xy 419.028803 -104.883055) (xy 418.979473 -104.869503) (xy 418.932393 -104.849487)
			(xy 418.888407 -104.823365) (xy 418.848301 -104.791606) (xy 418.830252 -104.773476) (xy 418.820603 -104.764096)
			(xy 418.797514 -104.750292) (xy 418.771623 -104.742994) (xy 418.744724 -104.742709) (xy 418.718683 -104.749456)
			(xy 418.695307 -104.762768) (xy 418.685472 -104.771952) (xy 418.663898 -104.792569) (xy 418.615524 -104.827506)
			(xy 418.562298 -104.854482) (xy 418.50552 -104.872837) (xy 418.446576 -104.882123) (xy 418.41674 -104.882696)
			(xy 418.389488 -104.882207) (xy 418.335537 -104.874456) (xy 418.283239 -104.859104) (xy 418.233658 -104.836465)
			(xy 418.187804 -104.807) (xy 418.146611 -104.771309) (xy 418.110916 -104.730118) (xy 418.081448 -104.684267)
			(xy 418.058806 -104.634687) (xy 418.04345 -104.58239) (xy 418.035695 -104.52844) (xy 418.035232 -104.501188)
			(xy 414.8328 -104.501188) (xy 414.8328 -105.827322) (xy 429.906682 -105.827322) (xy 429.910753 -105.7717)
			(xy 429.922879 -105.717263) (xy 429.942802 -105.665172) (xy 429.970098 -105.616537) (xy 430.004184 -105.572394)
			(xy 430.044333 -105.533685) (xy 430.089691 -105.501234) (xy 430.139291 -105.475733) (xy 430.192075 -105.457726)
			(xy 430.246918 -105.447596) (xy 430.302652 -105.445559) (xy 430.358089 -105.451659) (xy 430.412046 -105.465765)
			(xy 430.463375 -105.487577) (xy 430.510981 -105.516631) (xy 430.553849 -105.552306) (xy 430.591066 -105.593843)
			(xy 430.614291 -105.628948) (xy 433.069492 -105.628948) (xy 433.069988 -105.601579) (xy 433.077799 -105.547401)
			(xy 433.093281 -105.494898) (xy 433.116116 -105.445151) (xy 433.145834 -105.399183) (xy 433.163472 -105.37825)
			(xy 433.172664 -105.366889) (xy 433.184851 -105.340344) (xy 433.189034 -105.311436) (xy 433.184871 -105.282526)
			(xy 433.172704 -105.255972) (xy 433.163472 -105.244646) (xy 433.145837 -105.223711) (xy 433.116125 -105.177739)
			(xy 433.093289 -105.127992) (xy 433.077797 -105.075492) (xy 433.069967 -105.021317) (xy 433.069492 -104.993948)
			(xy 433.069991 -104.965775) (xy 433.078298 -104.910045) (xy 433.094709 -104.856142) (xy 433.118868 -104.805238)
			(xy 433.150249 -104.75844) (xy 433.188171 -104.716765) (xy 433.231808 -104.681118) (xy 433.280212 -104.652276)
			(xy 433.332331 -104.630864) (xy 433.35956 -104.623616) (xy 433.373871 -104.619591) (xy 433.399467 -104.604497)
			(xy 433.419628 -104.582668) (xy 433.432644 -104.555955) (xy 433.437411 -104.526624) (xy 433.433523 -104.497164)
			(xy 433.427886 -104.483408) (xy 433.417375 -104.458766) (xy 433.402561 -104.407283) (xy 433.395071 -104.354238)
			(xy 433.394612 -104.327452) (xy 433.395098 -104.300201) (xy 433.402854 -104.246253) (xy 433.418209 -104.193958)
			(xy 433.440851 -104.144381) (xy 433.470317 -104.098531) (xy 433.506008 -104.05734) (xy 433.547199 -104.021649)
			(xy 433.593049 -103.992183) (xy 433.642626 -103.969541) (xy 433.694921 -103.954186) (xy 433.748869 -103.94643)
			(xy 433.803371 -103.94643) (xy 433.857319 -103.954186) (xy 433.909614 -103.969541) (xy 433.959191 -103.992183)
			(xy 434.005041 -104.021649) (xy 434.046232 -104.05734) (xy 434.081923 -104.098531) (xy 434.111389 -104.144381)
			(xy 434.134031 -104.193958) (xy 434.149386 -104.246253) (xy 434.157142 -104.300201) (xy 434.157628 -104.327452)
			(xy 434.157175 -104.354753) (xy 434.149421 -104.4088) (xy 434.134021 -104.461184) (xy 434.123084 -104.486202)
			(xy 434.117403 -104.499723) (xy 434.113306 -104.528754) (xy 434.117603 -104.557756) (xy 434.129943 -104.584351)
			(xy 434.149314 -104.606359) (xy 434.174127 -104.621976) (xy 434.188108 -104.62641) (xy 434.214542 -104.634228)
			(xy 434.264983 -104.656465) (xy 434.311697 -104.685732) (xy 434.353711 -104.721419) (xy 434.390149 -104.762783)
			(xy 434.420254 -104.808961) (xy 434.443397 -104.858992) (xy 434.459097 -104.911834) (xy 434.467026 -104.966386)
			(xy 434.467508 -104.993948) (xy 434.467009 -105.021317) (xy 434.459199 -105.075495) (xy 434.443718 -105.127997)
			(xy 434.420883 -105.177745) (xy 434.391166 -105.223713) (xy 434.373528 -105.244646) (xy 434.364243 -105.255938)
			(xy 434.352068 -105.282508) (xy 434.347903 -105.311436) (xy 434.352088 -105.340362) (xy 434.364282 -105.366923)
			(xy 434.373528 -105.37825) (xy 434.391161 -105.399187) (xy 434.420873 -105.445159) (xy 434.44371 -105.494905)
			(xy 434.459202 -105.547404) (xy 434.467033 -105.601579) (xy 434.467508 -105.628948) (xy 434.467067 -105.6562)
			(xy 434.459304 -105.71015) (xy 434.443943 -105.762445) (xy 434.421296 -105.812023) (xy 434.391825 -105.857873)
			(xy 434.356129 -105.899063) (xy 434.314934 -105.934753) (xy 434.269081 -105.964219) (xy 434.2195 -105.986859)
			(xy 434.167203 -106.002214) (xy 434.113252 -106.00997) (xy 434.086 -106.010456) (xy 434.058629 -106.010001)
			(xy 434.004449 -106.002182) (xy 433.951946 -105.986691) (xy 433.902199 -105.963847) (xy 433.856233 -105.934119)
			(xy 433.835302 -105.916476) (xy 433.823974 -105.90724) (xy 433.797417 -105.895064) (xy 433.7685 -105.890891)
			(xy 433.739583 -105.895064) (xy 433.713026 -105.90724) (xy 433.701698 -105.916476) (xy 433.680774 -105.934126)
			(xy 433.6348 -105.963837) (xy 433.58505 -105.986671) (xy 433.532547 -106.00216) (xy 433.47837 -106.009984)
			(xy 433.451 -106.010456) (xy 433.423751 -106.009922) (xy 433.369807 -106.002167) (xy 433.317516 -105.986814)
			(xy 433.267942 -105.964177) (xy 433.222094 -105.934715) (xy 433.180905 -105.899029) (xy 433.145214 -105.857844)
			(xy 433.115746 -105.812) (xy 433.093102 -105.762429) (xy 433.077743 -105.71014) (xy 433.069981 -105.656197)
			(xy 433.069492 -105.628948) (xy 430.614291 -105.628948) (xy 430.621839 -105.640356) (xy 430.645511 -105.690853)
			(xy 430.661579 -105.74426) (xy 430.669699 -105.799436) (xy 430.670208 -105.827322) (xy 430.669699 -105.855208)
			(xy 430.661579 -105.910384) (xy 430.645511 -105.963791) (xy 430.621839 -106.014288) (xy 430.591066 -106.060801)
			(xy 430.553849 -106.102338) (xy 430.510981 -106.138013) (xy 430.463375 -106.167067) (xy 430.412046 -106.188879)
			(xy 430.358089 -106.202985) (xy 430.302652 -106.209085) (xy 430.246918 -106.207048) (xy 430.192075 -106.196918)
			(xy 430.139291 -106.178911) (xy 430.089691 -106.15341) (xy 430.044333 -106.120959) (xy 430.004184 -106.08225)
			(xy 429.970098 -106.038107) (xy 429.942802 -105.989472) (xy 429.922879 -105.937381) (xy 429.910753 -105.882944)
			(xy 429.906682 -105.827322) (xy 414.8328 -105.827322) (xy 414.8328 -107.15117) (xy 428.930814 -107.15117)
			(xy 428.934885 -107.095548) (xy 428.947011 -107.041111) (xy 428.966934 -106.98902) (xy 428.99423 -106.940385)
			(xy 429.028316 -106.896242) (xy 429.068465 -106.857533) (xy 429.113823 -106.825082) (xy 429.163423 -106.799581)
			(xy 429.216207 -106.781574) (xy 429.27105 -106.771444) (xy 429.326784 -106.769407) (xy 429.368344 -106.77398)
			(xy 433.340254 -106.77398) (xy 433.344325 -106.718358) (xy 433.356451 -106.663921) (xy 433.376374 -106.61183)
			(xy 433.40367 -106.563195) (xy 433.437756 -106.519052) (xy 433.477905 -106.480343) (xy 433.523263 -106.447892)
			(xy 433.572863 -106.422391) (xy 433.625647 -106.404384) (xy 433.68049 -106.394254) (xy 433.736224 -106.392217)
			(xy 433.791661 -106.398317) (xy 433.845618 -106.412423) (xy 433.896947 -106.434235) (xy 433.944553 -106.463289)
			(xy 433.987421 -106.498964) (xy 434.024638 -106.540501) (xy 434.055411 -106.587014) (xy 434.079083 -106.637511)
			(xy 434.095151 -106.690918) (xy 434.103271 -106.746094) (xy 434.10378 -106.77398) (xy 434.103271 -106.801866)
			(xy 434.095151 -106.857042) (xy 434.079083 -106.910449) (xy 434.055411 -106.960946) (xy 434.024638 -107.007459)
			(xy 433.987421 -107.048996) (xy 433.944553 -107.084671) (xy 433.896947 -107.113725) (xy 433.845618 -107.135537)
			(xy 433.791661 -107.149643) (xy 433.736224 -107.155743) (xy 433.68049 -107.153706) (xy 433.625647 -107.143576)
			(xy 433.572863 -107.125569) (xy 433.523263 -107.100068) (xy 433.477905 -107.067617) (xy 433.437756 -107.028908)
			(xy 433.40367 -106.984765) (xy 433.376374 -106.93613) (xy 433.356451 -106.884039) (xy 433.344325 -106.829602)
			(xy 433.340254 -106.77398) (xy 429.368344 -106.77398) (xy 429.382221 -106.775507) (xy 429.436178 -106.789613)
			(xy 429.487507 -106.811425) (xy 429.535113 -106.840479) (xy 429.577981 -106.876154) (xy 429.615198 -106.917691)
			(xy 429.645971 -106.964204) (xy 429.669643 -107.014701) (xy 429.685711 -107.068108) (xy 429.693831 -107.123284)
			(xy 429.69434 -107.15117) (xy 429.693831 -107.179056) (xy 429.685711 -107.234232) (xy 429.677688 -107.260898)
			(xy 430.263552 -107.260898) (xy 430.267623 -107.205276) (xy 430.279749 -107.150839) (xy 430.299672 -107.098748)
			(xy 430.326968 -107.050113) (xy 430.361054 -107.00597) (xy 430.401203 -106.967261) (xy 430.446561 -106.93481)
			(xy 430.496161 -106.909309) (xy 430.548945 -106.891302) (xy 430.603788 -106.881172) (xy 430.659522 -106.879135)
			(xy 430.714959 -106.885235) (xy 430.768916 -106.899341) (xy 430.820245 -106.921153) (xy 430.867851 -106.950207)
			(xy 430.910719 -106.985882) (xy 430.947936 -107.027419) (xy 430.978709 -107.073932) (xy 431.002381 -107.124429)
			(xy 431.018449 -107.177836) (xy 431.026569 -107.233012) (xy 431.027078 -107.260898) (xy 431.026569 -107.288784)
			(xy 431.018449 -107.34396) (xy 431.002381 -107.397367) (xy 430.978709 -107.447864) (xy 430.947936 -107.494377)
			(xy 430.910719 -107.535914) (xy 430.867851 -107.571589) (xy 430.820245 -107.600643) (xy 430.768916 -107.622455)
			(xy 430.714959 -107.636561) (xy 430.659522 -107.642661) (xy 430.603788 -107.640624) (xy 430.548945 -107.630494)
			(xy 430.496161 -107.612487) (xy 430.446561 -107.586986) (xy 430.401203 -107.554535) (xy 430.361054 -107.515826)
			(xy 430.326968 -107.471683) (xy 430.299672 -107.423048) (xy 430.279749 -107.370957) (xy 430.267623 -107.31652)
			(xy 430.263552 -107.260898) (xy 429.677688 -107.260898) (xy 429.669643 -107.287639) (xy 429.645971 -107.338136)
			(xy 429.615198 -107.384649) (xy 429.577981 -107.426186) (xy 429.535113 -107.461861) (xy 429.487507 -107.490915)
			(xy 429.436178 -107.512727) (xy 429.382221 -107.526833) (xy 429.326784 -107.532933) (xy 429.27105 -107.530896)
			(xy 429.216207 -107.520766) (xy 429.163423 -107.502759) (xy 429.113823 -107.477258) (xy 429.068465 -107.444807)
			(xy 429.028316 -107.406098) (xy 428.99423 -107.361955) (xy 428.966934 -107.31332) (xy 428.947011 -107.261229)
			(xy 428.934885 -107.206792) (xy 428.930814 -107.15117) (xy 414.8328 -107.15117) (xy 414.8328 -107.645708)
			(xy 431.703478 -107.645708) (xy 431.707549 -107.590086) (xy 431.719675 -107.535649) (xy 431.739598 -107.483558)
			(xy 431.766894 -107.434923) (xy 431.80098 -107.39078) (xy 431.841129 -107.352071) (xy 431.886487 -107.31962)
			(xy 431.936087 -107.294119) (xy 431.988871 -107.276112) (xy 432.043714 -107.265982) (xy 432.099448 -107.263945)
			(xy 432.154885 -107.270045) (xy 432.208842 -107.284151) (xy 432.260171 -107.305963) (xy 432.307777 -107.335017)
			(xy 432.350645 -107.370692) (xy 432.387862 -107.412229) (xy 432.418635 -107.458742) (xy 432.442307 -107.509239)
			(xy 432.458375 -107.562646) (xy 432.466495 -107.617822) (xy 432.467004 -107.645708) (xy 432.466495 -107.673594)
			(xy 432.458375 -107.72877) (xy 432.442307 -107.782177) (xy 432.418635 -107.832674) (xy 432.387862 -107.879187)
			(xy 432.350645 -107.920724) (xy 432.307777 -107.956399) (xy 432.260171 -107.985453) (xy 432.208842 -108.007265)
			(xy 432.154885 -108.021371) (xy 432.099448 -108.027471) (xy 432.043714 -108.025434) (xy 431.988871 -108.015304)
			(xy 431.936087 -107.997297) (xy 431.886487 -107.971796) (xy 431.841129 -107.939345) (xy 431.80098 -107.900636)
			(xy 431.766894 -107.856493) (xy 431.739598 -107.807858) (xy 431.719675 -107.755767) (xy 431.707549 -107.70133)
			(xy 431.703478 -107.645708) (xy 414.8328 -107.645708) (xy 414.8328 -110.739417) (xy 415.365214 -110.739417)
			(xy 415.368942 -110.686169) (xy 415.380055 -110.63396) (xy 415.398338 -110.58381) (xy 415.423433 -110.536698)
			(xy 415.454851 -110.493544) (xy 415.491977 -110.455192) (xy 415.512758 -110.438438) (xy 415.524538 -110.428512)
			(xy 415.542061 -110.403197) (xy 415.551243 -110.373811) (xy 415.551248 -110.343023) (xy 415.542076 -110.313634)
			(xy 415.524562 -110.288314) (xy 415.512758 -110.278418) (xy 415.492003 -110.261631) (xy 415.454873 -110.223282)
			(xy 415.423452 -110.180131) (xy 415.398352 -110.133022) (xy 415.380065 -110.082873) (xy 415.368946 -110.030665)
			(xy 415.365214 -109.977417) (xy 415.368942 -109.924169) (xy 415.380055 -109.87196) (xy 415.398338 -109.82181)
			(xy 415.423433 -109.774698) (xy 415.454851 -109.731544) (xy 415.491977 -109.693192) (xy 415.512758 -109.676438)
			(xy 415.524538 -109.666512) (xy 415.542061 -109.641197) (xy 415.551243 -109.611811) (xy 415.551248 -109.581023)
			(xy 415.542076 -109.551634) (xy 415.524562 -109.526314) (xy 415.512758 -109.516418) (xy 415.492003 -109.499631)
			(xy 415.454873 -109.461282) (xy 415.423452 -109.418131) (xy 415.398352 -109.371022) (xy 415.380065 -109.320873)
			(xy 415.368946 -109.268665) (xy 415.365214 -109.215417) (xy 415.368942 -109.162169) (xy 415.380055 -109.10996)
			(xy 415.398338 -109.05981) (xy 415.423433 -109.012698) (xy 415.454851 -108.969544) (xy 415.491977 -108.931192)
			(xy 415.512758 -108.914438) (xy 415.524538 -108.904512) (xy 415.542061 -108.879197) (xy 415.551243 -108.849811)
			(xy 415.551248 -108.819023) (xy 415.542076 -108.789634) (xy 415.524562 -108.764314) (xy 415.512758 -108.754418)
			(xy 415.490274 -108.736227) (xy 415.450541 -108.694206) (xy 415.417603 -108.646671) (xy 415.392215 -108.59471)
			(xy 415.374959 -108.539513) (xy 415.366228 -108.482344) (xy 415.365692 -108.453428) (xy 415.366181 -108.426176)
			(xy 415.373935 -108.372226) (xy 415.389287 -108.319928) (xy 415.411926 -108.270348) (xy 415.441391 -108.224495)
			(xy 415.477082 -108.183302) (xy 415.518273 -108.147608) (xy 415.564124 -108.11814) (xy 415.613702 -108.095497)
			(xy 415.665998 -108.08014) (xy 415.719948 -108.072383) (xy 415.7472 -108.07192) (xy 415.776117 -108.072431)
			(xy 415.833289 -108.08116) (xy 415.888488 -108.098419) (xy 415.94045 -108.123812) (xy 415.987984 -108.156758)
			(xy 416.03 -108.1965) (xy 416.04819 -108.218986) (xy 416.058087 -108.230791) (xy 416.083411 -108.24831)
			(xy 416.112804 -108.257486) (xy 416.143596 -108.257486) (xy 416.172989 -108.24831) (xy 416.198313 -108.230791)
			(xy 416.20821 -108.218986) (xy 416.226392 -108.196495) (xy 416.268414 -108.156761) (xy 416.315951 -108.123823)
			(xy 416.367914 -108.098436) (xy 416.423113 -108.081181) (xy 416.480284 -108.072454) (xy 416.5092 -108.07192)
			(xy 416.536454 -108.072355) (xy 416.590408 -108.080113) (xy 416.642708 -108.095471) (xy 416.69229 -108.118115)
			(xy 416.738144 -108.147586) (xy 416.779337 -108.183282) (xy 416.815031 -108.224478) (xy 416.844498 -108.270335)
			(xy 416.867139 -108.319919) (xy 416.882493 -108.37222) (xy 416.890247 -108.426174) (xy 416.890708 -108.453428)
			(xy 416.890173 -108.482345) (xy 416.881452 -108.539517) (xy 416.8642 -108.594717) (xy 416.838812 -108.646679)
			(xy 416.805869 -108.694213) (xy 416.766128 -108.736229) (xy 416.743642 -108.754418) (xy 416.731806 -108.764283)
			(xy 416.714284 -108.789614) (xy 416.705109 -108.819017) (xy 416.705114 -108.849818) (xy 416.714299 -108.879217)
			(xy 416.73183 -108.904542) (xy 416.743642 -108.914438) (xy 416.764453 -108.931158) (xy 416.801583 -108.969516)
			(xy 416.833005 -109.012674) (xy 416.858103 -109.059791) (xy 416.876388 -109.109947) (xy 416.887503 -109.162163)
			(xy 416.89123 -109.215417) (xy 416.887498 -109.268672) (xy 416.876378 -109.320886) (xy 416.858089 -109.37104)
			(xy 416.832986 -109.418155) (xy 416.801561 -109.461311) (xy 416.764427 -109.499665) (xy 416.743642 -109.516418)
			(xy 416.731806 -109.526283) (xy 416.714284 -109.551614) (xy 416.705109 -109.581017) (xy 416.705114 -109.611818)
			(xy 416.714299 -109.641217) (xy 416.729537 -109.66323) (xy 433.334158 -109.66323) (xy 433.338229 -109.607608)
			(xy 433.350355 -109.553171) (xy 433.370278 -109.50108) (xy 433.397574 -109.452445) (xy 433.43166 -109.408302)
			(xy 433.471809 -109.369593) (xy 433.517167 -109.337142) (xy 433.566767 -109.311641) (xy 433.619551 -109.293634)
			(xy 433.674394 -109.283504) (xy 433.730128 -109.281467) (xy 433.785565 -109.287567) (xy 433.839522 -109.301673)
			(xy 433.890851 -109.323485) (xy 433.938457 -109.352539) (xy 433.981325 -109.388214) (xy 434.018542 -109.429751)
			(xy 434.049315 -109.476264) (xy 434.072987 -109.526761) (xy 434.089055 -109.580168) (xy 434.097175 -109.635344)
			(xy 434.097684 -109.66323) (xy 434.097175 -109.691116) (xy 434.089055 -109.746292) (xy 434.072987 -109.799699)
			(xy 434.049315 -109.850196) (xy 434.018542 -109.896709) (xy 433.981325 -109.938246) (xy 433.938457 -109.973921)
			(xy 433.890851 -110.002975) (xy 433.839522 -110.024787) (xy 433.785565 -110.038893) (xy 433.730128 -110.044993)
			(xy 433.674394 -110.042956) (xy 433.619551 -110.032826) (xy 433.566767 -110.014819) (xy 433.517167 -109.989318)
			(xy 433.471809 -109.956867) (xy 433.43166 -109.918158) (xy 433.397574 -109.874015) (xy 433.370278 -109.82538)
			(xy 433.350355 -109.773289) (xy 433.338229 -109.718852) (xy 433.334158 -109.66323) (xy 416.729537 -109.66323)
			(xy 416.73183 -109.666542) (xy 416.743642 -109.676438) (xy 416.764453 -109.693158) (xy 416.801583 -109.731516)
			(xy 416.833005 -109.774674) (xy 416.858103 -109.821791) (xy 416.876388 -109.871947) (xy 416.887503 -109.924163)
			(xy 416.89123 -109.977417) (xy 416.887498 -110.030672) (xy 416.876378 -110.082886) (xy 416.858089 -110.13304)
			(xy 416.832986 -110.180155) (xy 416.801561 -110.223311) (xy 416.764427 -110.261665) (xy 416.743642 -110.278418)
			(xy 416.740595 -110.280958) (xy 419.761922 -110.280958) (xy 419.765993 -110.225336) (xy 419.778119 -110.170899)
			(xy 419.798042 -110.118808) (xy 419.825338 -110.070173) (xy 419.859424 -110.02603) (xy 419.899573 -109.987321)
			(xy 419.944931 -109.95487) (xy 419.994531 -109.929369) (xy 420.047315 -109.911362) (xy 420.102158 -109.901232)
			(xy 420.157892 -109.899195) (xy 420.213329 -109.905295) (xy 420.267286 -109.919401) (xy 420.318615 -109.941213)
			(xy 420.366221 -109.970267) (xy 420.409089 -110.005942) (xy 420.446306 -110.047479) (xy 420.477079 -110.093992)
			(xy 420.500751 -110.144489) (xy 420.516819 -110.197896) (xy 420.524939 -110.253072) (xy 420.525369 -110.27664)
			(xy 428.913542 -110.27664) (xy 428.917613 -110.221018) (xy 428.929739 -110.166581) (xy 428.949662 -110.11449)
			(xy 428.976958 -110.065855) (xy 429.011044 -110.021712) (xy 429.051193 -109.983003) (xy 429.096551 -109.950552)
			(xy 429.146151 -109.925051) (xy 429.198935 -109.907044) (xy 429.253778 -109.896914) (xy 429.309512 -109.894877)
			(xy 429.364949 -109.900977) (xy 429.418906 -109.915083) (xy 429.470235 -109.936895) (xy 429.517841 -109.965949)
			(xy 429.560709 -110.001624) (xy 429.597926 -110.043161) (xy 429.628699 -110.089674) (xy 429.652371 -110.140171)
			(xy 429.668439 -110.193578) (xy 429.676559 -110.248754) (xy 429.677068 -110.27664) (xy 429.676559 -110.304526)
			(xy 429.668439 -110.359702) (xy 429.652371 -110.413109) (xy 429.628699 -110.463606) (xy 429.597926 -110.510119)
			(xy 429.560709 -110.551656) (xy 429.517841 -110.587331) (xy 429.470235 -110.616385) (xy 429.418906 -110.638197)
			(xy 429.364949 -110.652303) (xy 429.309512 -110.658403) (xy 429.253778 -110.656366) (xy 429.198935 -110.646236)
			(xy 429.146151 -110.628229) (xy 429.096551 -110.602728) (xy 429.051193 -110.570277) (xy 429.011044 -110.531568)
			(xy 428.976958 -110.487425) (xy 428.949662 -110.43879) (xy 428.929739 -110.386699) (xy 428.917613 -110.332262)
			(xy 428.913542 -110.27664) (xy 420.525369 -110.27664) (xy 420.525448 -110.280958) (xy 420.524939 -110.308844)
			(xy 420.516819 -110.36402) (xy 420.500751 -110.417427) (xy 420.477079 -110.467924) (xy 420.446306 -110.514437)
			(xy 420.409089 -110.555974) (xy 420.366221 -110.591649) (xy 420.318615 -110.620703) (xy 420.267286 -110.642515)
			(xy 420.213329 -110.656621) (xy 420.157892 -110.662721) (xy 420.102158 -110.660684) (xy 420.047315 -110.650554)
			(xy 419.994531 -110.632547) (xy 419.944931 -110.607046) (xy 419.899573 -110.574595) (xy 419.859424 -110.535886)
			(xy 419.825338 -110.491743) (xy 419.798042 -110.443108) (xy 419.778119 -110.391017) (xy 419.765993 -110.33658)
			(xy 419.761922 -110.280958) (xy 416.740595 -110.280958) (xy 416.731806 -110.288283) (xy 416.714284 -110.313614)
			(xy 416.705109 -110.343017) (xy 416.705114 -110.373818) (xy 416.714299 -110.403217) (xy 416.73183 -110.428542)
			(xy 416.743642 -110.438438) (xy 416.764453 -110.455158) (xy 416.801583 -110.493516) (xy 416.833005 -110.536674)
			(xy 416.858103 -110.583791) (xy 416.876388 -110.633947) (xy 416.887503 -110.686163) (xy 416.89123 -110.739417)
			(xy 416.887498 -110.792672) (xy 416.876378 -110.844886) (xy 416.858089 -110.89504) (xy 416.832986 -110.942155)
			(xy 416.801561 -110.985311) (xy 416.764427 -111.023665) (xy 416.743642 -111.040418) (xy 416.731806 -111.050283)
			(xy 416.714284 -111.075614) (xy 416.705109 -111.105017) (xy 416.705114 -111.135818) (xy 416.714299 -111.165217)
			(xy 416.73183 -111.190542) (xy 416.743642 -111.200438) (xy 416.766152 -111.218597) (xy 416.805884 -111.260625)
			(xy 416.838819 -111.308167) (xy 416.864202 -111.360134) (xy 416.881453 -111.415337) (xy 416.890176 -111.47251)
			(xy 416.890708 -111.501428) (xy 416.890248 -111.52868) (xy 416.882488 -111.582629) (xy 416.867129 -111.634924)
			(xy 416.844485 -111.684501) (xy 416.815016 -111.730351) (xy 416.779321 -111.771541) (xy 416.738129 -111.807232)
			(xy 416.692277 -111.836698) (xy 416.642698 -111.859339) (xy 416.590401 -111.874694) (xy 416.536452 -111.88245)
			(xy 416.5092 -111.882936) (xy 416.480282 -111.882442) (xy 416.423108 -111.873711) (xy 416.367908 -111.85645)
			(xy 416.315946 -111.831054) (xy 416.268413 -111.798105) (xy 416.226398 -111.758358) (xy 416.20821 -111.73587)
			(xy 416.198313 -111.724065) (xy 416.172989 -111.706546) (xy 416.143596 -111.69737) (xy 416.112804 -111.69737)
			(xy 416.083411 -111.706546) (xy 416.058087 -111.724065) (xy 416.04819 -111.73587) (xy 416.029997 -111.758352)
			(xy 415.987979 -111.798089) (xy 415.940444 -111.831029) (xy 415.888483 -111.856418) (xy 415.833286 -111.873674)
			(xy 415.776116 -111.882402) (xy 415.7472 -111.882936) (xy 415.71995 -111.882422) (xy 415.666005 -111.874667)
			(xy 415.613712 -111.859313) (xy 415.564137 -111.836674) (xy 415.518288 -111.80721) (xy 415.477098 -111.771522)
			(xy 415.441407 -111.730335) (xy 415.41194 -111.684488) (xy 415.389297 -111.634914) (xy 415.373939 -111.582623)
			(xy 415.36618 -111.528678) (xy 415.365692 -111.501428) (xy 415.366195 -111.47251) (xy 415.374923 -111.415337)
			(xy 415.392181 -111.360136) (xy 415.417575 -111.308173) (xy 415.450523 -111.26064) (xy 415.49027 -111.218626)
			(xy 415.512758 -111.200438) (xy 415.524538 -111.190512) (xy 415.542061 -111.165197) (xy 415.551243 -111.135811)
			(xy 415.551248 -111.105023) (xy 415.542076 -111.075634) (xy 415.524562 -111.050314) (xy 415.512758 -111.040418)
			(xy 415.492003 -111.023631) (xy 415.454873 -110.985282) (xy 415.423452 -110.942131) (xy 415.398352 -110.895022)
			(xy 415.380065 -110.844873) (xy 415.368946 -110.792665) (xy 415.365214 -110.739417) (xy 414.8328 -110.739417)
			(xy 414.8328 -111.521748) (xy 415.4805 -112.169448) (xy 433.71008 -112.169448)
		)
		(stroke
			(width 0)
			(type solid)
		)
		(fill yes)
		(layer "In6.Cu")
		(net "GND")
	)
	(gr_poly
		(pts
			(xy 353.869498 -222.285814) (xy 353.889892 -222.243631) (xy 353.936745 -222.162481) (xy 353.990217 -222.085532)
			(xy 354.049935 -222.013323) (xy 354.08235 -221.97949) (xy 354.080826 -221.94774) (xy 354.081361 -221.92073)
			(xy 354.090143 -221.867429) (xy 354.107479 -221.816267) (xy 354.132907 -221.768607) (xy 354.165751 -221.725718)
			(xy 354.205134 -221.688744) (xy 354.250008 -221.65867) (xy 354.274374 -221.647004) (xy 354.287443 -221.601961)
			(xy 354.320137 -221.514047) (xy 354.360081 -221.429181) (xy 354.406994 -221.34796) (xy 354.433378 -221.309184)
			(xy 354.442522 -221.29623) (xy 354.442522 -220.971872) (xy 354.433378 -220.958664) (xy 354.406947 -220.919834)
			(xy 354.359948 -220.838495) (xy 354.319937 -220.753502) (xy 354.287193 -220.665453) (xy 354.27412 -220.620336)
			(xy 354.249821 -220.608634) (xy 354.205071 -220.578534) (xy 354.165802 -220.541568) (xy 354.133057 -220.498717)
			(xy 354.107703 -220.451117) (xy 354.090415 -220.400033) (xy 354.081649 -220.346819) (xy 354.08108 -220.319854)
			(xy 354.08162 -220.292874) (xy 354.0904 -220.239634) (xy 354.107719 -220.18853) (xy 354.133117 -220.140921)
			(xy 354.165916 -220.098075) (xy 354.205245 -220.061132) (xy 354.250058 -220.031074) (xy 354.274374 -220.019372)
			(xy 354.287421 -219.97436) (xy 354.320067 -219.886505) (xy 354.359959 -219.801694) (xy 354.406817 -219.720523)
			(xy 354.460311 -219.643564) (xy 354.520065 -219.571357) (xy 354.552504 -219.537534) (xy 354.55098 -219.506038)
			(xy 354.551513 -219.479042) (xy 354.560282 -219.425768) (xy 354.577593 -219.374627) (xy 354.602986 -219.32698)
			(xy 354.635786 -219.284093) (xy 354.67512 -219.247107) (xy 354.719942 -219.217007) (xy 354.744274 -219.205302)
			(xy 354.757207 -219.160743) (xy 354.789484 -219.073748) (xy 354.828859 -218.989727) (xy 354.875061 -218.909257)
			(xy 354.927772 -218.832893) (xy 354.98663 -218.761159) (xy 355.018594 -218.727528) (xy 355.021896 -218.723718)
			(xy 355.020372 -218.692222) (xy 355.021896 -218.660726) (xy 355.018594 -218.656916) (xy 354.98663 -218.623285)
			(xy 354.927767 -218.551554) (xy 354.875053 -218.475191) (xy 354.82885 -218.394722) (xy 354.789475 -218.310699)
			(xy 354.757201 -218.223702) (xy 354.744274 -218.179142) (xy 354.719943 -218.167436) (xy 354.675132 -218.13732)
			(xy 354.635805 -218.100329) (xy 354.603005 -218.057444) (xy 354.577603 -218.009803) (xy 354.560273 -217.95867)
			(xy 354.551474 -217.905401) (xy 354.55098 -217.878406) (xy 354.551514 -217.851439) (xy 354.560275 -217.798221)
			(xy 354.577565 -217.747134) (xy 354.602925 -217.699534) (xy 354.635681 -217.656686) (xy 354.674963 -217.619729)
			(xy 354.719727 -217.589645) (xy 354.74402 -217.577924) (xy 354.757063 -217.532891) (xy 354.789703 -217.444995)
			(xy 354.829592 -217.360141) (xy 354.876449 -217.278927) (xy 354.929944 -217.201924) (xy 354.989702 -217.129673)
			(xy 355.02215 -217.095832) (xy 355.020626 -217.064336) (xy 355.021161 -217.037326) (xy 355.029943 -216.984026)
			(xy 355.04728 -216.932864) (xy 355.072709 -216.885204) (xy 355.105552 -216.842316) (xy 355.144936 -216.805343)
			(xy 355.189809 -216.775269) (xy 355.214174 -216.7636) (xy 355.227229 -216.71861) (xy 355.259887 -216.630799)
			(xy 355.299784 -216.546031) (xy 355.346639 -216.464902) (xy 355.400124 -216.387982) (xy 355.459862 -216.315811)
			(xy 355.492304 -216.282016) (xy 355.49078 -216.25052) (xy 355.491336 -216.222968) (xy 355.500483 -216.168627)
			(xy 355.518509 -216.116554) (xy 355.544918 -216.068189) (xy 355.578977 -216.02487) (xy 355.598984 -216.005918)
			(xy 355.598984 -215.741504) (xy 355.59492 -215.732106) (xy 355.580534 -215.696995) (xy 355.55806 -215.624518)
			(xy 355.542973 -215.550151) (xy 355.535427 -215.474645) (xy 355.534976 -215.436704) (xy 355.534976 -215.412574)
			(xy 355.471984 -215.349582) (xy 355.461478 -215.339825) (xy 355.436341 -215.326059) (xy 355.408371 -215.319812)
			(xy 355.379766 -215.321577) (xy 355.352776 -215.331214) (xy 355.329522 -215.347966) (xy 355.320346 -215.35898)
			(xy 355.286818 -215.398858) (xy 355.274126 -215.43646) (xy 355.241931 -215.509003) (xy 355.222556 -215.543638)
			(xy 355.066092 -215.814656) (xy 355.047804 -215.844628) (xy 355.039923 -215.857937) (xy 355.031783 -215.887762)
			(xy 355.032916 -215.918657) (xy 355.043219 -215.947806) (xy 355.061752 -215.972551) (xy 355.073966 -215.982042)
			(xy 355.094927 -215.997664) (xy 355.132101 -216.034418) (xy 355.163016 -216.076573) (xy 355.186901 -216.123073)
			(xy 355.203157 -216.172757) (xy 355.211378 -216.224382) (xy 355.211888 -216.25052) (xy 355.211377 -216.276487)
			(xy 355.203251 -216.327782) (xy 355.187201 -216.377174) (xy 355.163622 -216.423447) (xy 355.133096 -216.465463)
			(xy 355.096374 -216.502187) (xy 355.054359 -216.532715) (xy 355.008087 -216.556295) (xy 354.958695 -216.572347)
			(xy 354.907401 -216.580476) (xy 354.881434 -216.580974) (xy 354.854401 -216.58043) (xy 354.801056 -216.571624)
			(xy 354.749854 -216.554257) (xy 354.70216 -216.528791) (xy 354.659243 -216.495906) (xy 354.622249 -216.456477)
			(xy 354.592161 -216.411555) (xy 354.569782 -216.362337) (xy 354.555708 -216.310134) (xy 354.552504 -216.283286)
			(xy 354.550465 -216.267957) (xy 354.538397 -216.239501) (xy 354.51836 -216.215967) (xy 354.492195 -216.199513)
			(xy 354.462302 -216.191651) (xy 354.44684 -216.191846) (xy 354.41128 -216.192608) (xy 354.376228 -216.191846)
			(xy 354.36077 -216.191683) (xy 354.330894 -216.199565) (xy 354.304739 -216.216015) (xy 354.284696 -216.239531)
			(xy 354.272598 -216.267963) (xy 354.270564 -216.283286) (xy 354.267351 -216.310138) (xy 354.25331 -216.362359)
			(xy 354.230952 -216.411596) (xy 354.200873 -216.456535) (xy 354.163878 -216.495976) (xy 354.120954 -216.528866)
			(xy 354.073247 -216.554327) (xy 354.022031 -216.571679) (xy 353.968672 -216.580458) (xy 353.941634 -216.580974)
			(xy 353.915662 -216.580494) (xy 353.864358 -216.572373) (xy 353.814956 -216.556326) (xy 353.768672 -216.532749)
			(xy 353.726646 -216.502221) (xy 353.689914 -216.465495) (xy 353.659379 -216.423474) (xy 353.635794 -216.377194)
			(xy 353.61974 -216.327795) (xy 353.611611 -216.276492) (xy 353.61118 -216.25052) (xy 353.611671 -216.224426)
			(xy 353.619869 -216.172885) (xy 353.636066 -216.123273) (xy 353.659857 -216.076823) (xy 353.690653 -216.034689)
			(xy 353.727687 -215.997918) (xy 353.748594 -215.982296) (xy 353.760842 -215.972834) (xy 353.779437 -215.94811)
			(xy 353.789803 -215.918963) (xy 353.790996 -215.88805) (xy 353.782908 -215.858191) (xy 353.77501 -215.844882)
			(xy 353.75597 -215.8144) (xy 353.72309 -215.750488) (xy 353.696423 -215.683744) (xy 353.676209 -215.614771)
			(xy 353.662631 -215.544191) (xy 353.655811 -215.472641) (xy 353.655376 -215.436704) (xy 353.655376 -215.435942)
			(xy 353.655631 -215.40828) (xy 353.659696 -215.353106) (xy 353.663504 -215.325706) (xy 353.643576 -215.317727)
			(xy 353.604563 -215.299811) (xy 353.585526 -215.289892) (xy 353.57435 -215.283796) (xy 353.49307 -215.283796)
			(xy 353.478084 -215.30691) (xy 353.461928 -215.331059) (xy 353.426454 -215.377082) (xy 353.407218 -215.398858)
			(xy 353.394526 -215.43646) (xy 353.362331 -215.509003) (xy 353.342956 -215.543638) (xy 353.186492 -215.814656)
			(xy 353.168204 -215.844628) (xy 353.160323 -215.857937) (xy 353.152183 -215.887762) (xy 353.153316 -215.918657)
			(xy 353.163619 -215.947806) (xy 353.182152 -215.972551) (xy 353.194366 -215.982042) (xy 353.215327 -215.997664)
			(xy 353.252501 -216.034418) (xy 353.283416 -216.076573) (xy 353.307301 -216.123073) (xy 353.323557 -216.172757)
			(xy 353.331778 -216.224382) (xy 353.332288 -216.25052) (xy 353.331777 -216.276487) (xy 353.323651 -216.327782)
			(xy 353.307601 -216.377174) (xy 353.284022 -216.423447) (xy 353.253496 -216.465463) (xy 353.216774 -216.502187)
			(xy 353.174759 -216.532715) (xy 353.128487 -216.556295) (xy 353.079095 -216.572347) (xy 353.027801 -216.580476)
			(xy 353.001834 -216.580974) (xy 352.974801 -216.58043) (xy 352.921456 -216.571624) (xy 352.870254 -216.554257)
			(xy 352.82256 -216.528791) (xy 352.779643 -216.495906) (xy 352.742649 -216.456477) (xy 352.712561 -216.411555)
			(xy 352.690182 -216.362337) (xy 352.676108 -216.310134) (xy 352.672904 -216.283286) (xy 352.670865 -216.267957)
			(xy 352.658797 -216.239501) (xy 352.63876 -216.215967) (xy 352.612595 -216.199513) (xy 352.582702 -216.191651)
			(xy 352.56724 -216.191846) (xy 352.53168 -216.192608) (xy 352.496628 -216.191846) (xy 352.48117 -216.191683)
			(xy 352.451294 -216.199565) (xy 352.425139 -216.216015) (xy 352.405096 -216.239531) (xy 352.392998 -216.267963)
			(xy 352.390964 -216.283286) (xy 352.387751 -216.310138) (xy 352.37371 -216.362359) (xy 352.351352 -216.411596)
			(xy 352.321273 -216.456535) (xy 352.284278 -216.495976) (xy 352.241354 -216.528866) (xy 352.193647 -216.554327)
			(xy 352.142431 -216.571679) (xy 352.089072 -216.580458) (xy 352.062034 -216.580974) (xy 352.036062 -216.580494)
			(xy 351.984758 -216.572373) (xy 351.935356 -216.556326) (xy 351.889072 -216.532749) (xy 351.847046 -216.502221)
			(xy 351.810314 -216.465495) (xy 351.779779 -216.423474) (xy 351.756194 -216.377194) (xy 351.74014 -216.327795)
			(xy 351.732011 -216.276492) (xy 351.73158 -216.25052) (xy 351.732071 -216.224426) (xy 351.740269 -216.172885)
			(xy 351.756466 -216.123273) (xy 351.780257 -216.076823) (xy 351.811053 -216.034689) (xy 351.848087 -215.997918)
			(xy 351.868994 -215.982296) (xy 351.881242 -215.972834) (xy 351.899837 -215.94811) (xy 351.910203 -215.918963)
			(xy 351.911396 -215.88805) (xy 351.903308 -215.858191) (xy 351.89541 -215.844882) (xy 351.87637 -215.8144)
			(xy 351.84349 -215.750488) (xy 351.816823 -215.683744) (xy 351.796609 -215.614771) (xy 351.783031 -215.544191)
			(xy 351.776211 -215.472641) (xy 351.775776 -215.436704) (xy 351.775776 -215.435942) (xy 351.776031 -215.40828)
			(xy 351.780096 -215.353106) (xy 351.783904 -215.325706) (xy 351.763976 -215.317727) (xy 351.724963 -215.299811)
			(xy 351.705926 -215.289892) (xy 351.69475 -215.283796) (xy 351.61347 -215.283796) (xy 351.598484 -215.30691)
			(xy 351.582328 -215.331059) (xy 351.546854 -215.377082) (xy 351.527618 -215.398858) (xy 351.514926 -215.43646)
			(xy 351.482731 -215.509003) (xy 351.463356 -215.543638) (xy 351.306892 -215.814656) (xy 351.288604 -215.844628)
			(xy 351.280723 -215.857937) (xy 351.272583 -215.887762) (xy 351.273716 -215.918657) (xy 351.284019 -215.947806)
			(xy 351.302552 -215.972551) (xy 351.314766 -215.982042) (xy 351.335727 -215.997664) (xy 351.372901 -216.034418)
			(xy 351.403816 -216.076573) (xy 351.427701 -216.123073) (xy 351.443957 -216.172757) (xy 351.452178 -216.224382)
			(xy 351.452688 -216.25052) (xy 351.452177 -216.276487) (xy 351.444051 -216.327782) (xy 351.428001 -216.377174)
			(xy 351.404422 -216.423447) (xy 351.373896 -216.465463) (xy 351.337174 -216.502187) (xy 351.295159 -216.532715)
			(xy 351.248887 -216.556295) (xy 351.199495 -216.572347) (xy 351.148201 -216.580476) (xy 351.122234 -216.580974)
			(xy 351.095201 -216.58043) (xy 351.041856 -216.571624) (xy 350.990654 -216.554257) (xy 350.94296 -216.528791)
			(xy 350.900043 -216.495906) (xy 350.863049 -216.456477) (xy 350.832961 -216.411555) (xy 350.810582 -216.362337)
			(xy 350.796508 -216.310134) (xy 350.793304 -216.283286) (xy 350.791265 -216.267957) (xy 350.779197 -216.239501)
			(xy 350.75916 -216.215967) (xy 350.732995 -216.199513) (xy 350.703102 -216.191651) (xy 350.68764 -216.191846)
			(xy 350.65208 -216.192608) (xy 350.617028 -216.191846) (xy 350.60157 -216.191683) (xy 350.571694 -216.199565)
			(xy 350.545539 -216.216015) (xy 350.525496 -216.239531) (xy 350.513398 -216.267963) (xy 350.511364 -216.283286)
			(xy 350.508151 -216.310138) (xy 350.49411 -216.362359) (xy 350.471752 -216.411596) (xy 350.441673 -216.456535)
			(xy 350.404678 -216.495976) (xy 350.361754 -216.528866) (xy 350.314047 -216.554327) (xy 350.262831 -216.571679)
			(xy 350.209472 -216.580458) (xy 350.182434 -216.580974) (xy 350.156462 -216.580494) (xy 350.105158 -216.572373)
			(xy 350.055756 -216.556326) (xy 350.009472 -216.532749) (xy 349.967446 -216.502221) (xy 349.930714 -216.465495)
			(xy 349.900179 -216.423474) (xy 349.876594 -216.377194) (xy 349.86054 -216.327795) (xy 349.852411 -216.276492)
			(xy 349.85198 -216.25052) (xy 349.852471 -216.224426) (xy 349.860669 -216.172885) (xy 349.876866 -216.123273)
			(xy 349.900657 -216.076823) (xy 349.931453 -216.034689) (xy 349.968487 -215.997918) (xy 349.989394 -215.982296)
			(xy 350.001642 -215.972834) (xy 350.020237 -215.94811) (xy 350.030603 -215.918963) (xy 350.031796 -215.88805)
			(xy 350.023708 -215.858191) (xy 350.01581 -215.844882) (xy 349.99677 -215.8144) (xy 349.96389 -215.750488)
			(xy 349.937223 -215.683744) (xy 349.917009 -215.614771) (xy 349.903431 -215.544191) (xy 349.896611 -215.472641)
			(xy 349.896176 -215.436704) (xy 349.896176 -215.435942) (xy 349.896431 -215.40828) (xy 349.900496 -215.353106)
			(xy 349.904304 -215.325706) (xy 349.884376 -215.317727) (xy 349.845363 -215.299811) (xy 349.826326 -215.289892)
			(xy 349.81515 -215.283796) (xy 349.73387 -215.283796) (xy 349.718884 -215.30691) (xy 349.702728 -215.331059)
			(xy 349.667254 -215.377082) (xy 349.648018 -215.398858) (xy 349.635326 -215.43646) (xy 349.603131 -215.509003)
			(xy 349.583756 -215.543638) (xy 349.427292 -215.814656) (xy 349.409004 -215.844628) (xy 349.401123 -215.857937)
			(xy 349.392983 -215.887762) (xy 349.394116 -215.918657) (xy 349.404419 -215.947806) (xy 349.422952 -215.972551)
			(xy 349.435166 -215.982042) (xy 349.456127 -215.997664) (xy 349.493301 -216.034418) (xy 349.524216 -216.076573)
			(xy 349.548101 -216.123073) (xy 349.564357 -216.172757) (xy 349.572578 -216.224382) (xy 349.573088 -216.25052)
			(xy 349.572577 -216.276487) (xy 349.564451 -216.327782) (xy 349.548401 -216.377174) (xy 349.524822 -216.423447)
			(xy 349.494296 -216.465463) (xy 349.457574 -216.502187) (xy 349.415559 -216.532715) (xy 349.369287 -216.556295)
			(xy 349.319895 -216.572347) (xy 349.268601 -216.580476) (xy 349.242634 -216.580974) (xy 349.214855 -216.580378)
			(xy 349.160083 -216.571051) (xy 349.133668 -216.562432) (xy 349.120437 -216.558294) (xy 349.092786 -216.55651)
			(xy 349.065673 -216.56223) (xy 349.041099 -216.575032) (xy 349.020874 -216.593973) (xy 349.00649 -216.617656)
			(xy 348.999007 -216.644336) (xy 348.99854 -216.65819) (xy 348.99854 -216.823036) (xy 349.016191 -216.840178)
			(xy 349.04673 -216.878757) (xy 349.071211 -216.921437) (xy 349.089093 -216.967275) (xy 349.099982 -217.015258)
			(xy 349.103636 -217.064325) (xy 349.099975 -217.113391) (xy 349.089079 -217.161372) (xy 349.07119 -217.207207)
			(xy 349.046702 -217.249884) (xy 349.016158 -217.288458) (xy 348.99854 -217.305636) (xy 348.99854 -217.470736)
			(xy 348.999049 -217.48458) (xy 349.006568 -217.51123) (xy 349.020962 -217.534885) (xy 349.041176 -217.553809)
			(xy 349.065726 -217.566616) (xy 349.092813 -217.572365) (xy 349.120449 -217.570634) (xy 349.133668 -217.566494)
			(xy 349.145445 -217.562475) (xy 349.169474 -217.555992) (xy 349.181674 -217.55354) (xy 349.204534 -217.549222)
			(xy 349.408242 -217.196162) (xy 349.400622 -217.174064) (xy 349.391825 -217.14749) (xy 349.382368 -217.092322)
			(xy 349.381826 -217.064336) (xy 349.382335 -217.038369) (xy 349.39046 -216.987074) (xy 349.406508 -216.937681)
			(xy 349.430086 -216.891407) (xy 349.460612 -216.849391) (xy 349.497335 -216.812668) (xy 349.539351 -216.782142)
			(xy 349.585625 -216.758564) (xy 349.635018 -216.742516) (xy 349.686313 -216.734391) (xy 349.738247 -216.734391)
			(xy 349.789542 -216.742516) (xy 349.838935 -216.758564) (xy 349.885209 -216.782142) (xy 349.927225 -216.812668)
			(xy 349.963948 -216.849391) (xy 349.994474 -216.891407) (xy 350.018052 -216.937681) (xy 350.0341 -216.987074)
			(xy 350.042225 -217.038369) (xy 350.042734 -217.064336) (xy 350.042263 -217.089785) (xy 350.042183 -217.090303)
			(xy 350.322389 -217.090303) (xy 350.322389 -217.038369) (xy 350.330514 -216.987074) (xy 350.346562 -216.937681)
			(xy 350.37014 -216.891407) (xy 350.400666 -216.849391) (xy 350.437389 -216.812668) (xy 350.479405 -216.782142)
			(xy 350.525679 -216.758564) (xy 350.575072 -216.742516) (xy 350.626367 -216.734391) (xy 350.678301 -216.734391)
			(xy 350.729596 -216.742516) (xy 350.778989 -216.758564) (xy 350.825263 -216.782142) (xy 350.867279 -216.812668)
			(xy 350.904002 -216.849391) (xy 350.934528 -216.891407) (xy 350.958106 -216.937681) (xy 350.974154 -216.987074)
			(xy 350.982279 -217.038369) (xy 350.982788 -217.064336) (xy 350.982279 -217.090303) (xy 350.974154 -217.141598)
			(xy 350.958106 -217.190991) (xy 350.934528 -217.237265) (xy 350.904002 -217.279281) (xy 350.867279 -217.316004)
			(xy 350.825263 -217.34653) (xy 350.778989 -217.370108) (xy 350.729596 -217.386156) (xy 350.678301 -217.394281)
			(xy 350.626367 -217.394281) (xy 350.575072 -217.386156) (xy 350.525679 -217.370108) (xy 350.479405 -217.34653)
			(xy 350.437389 -217.316004) (xy 350.400666 -217.279281) (xy 350.37014 -217.237265) (xy 350.346562 -217.190991)
			(xy 350.330514 -217.141598) (xy 350.322389 -217.090303) (xy 350.042183 -217.090303) (xy 350.034457 -217.14008)
			(xy 350.019037 -217.188586) (xy 349.996365 -217.234155) (xy 349.966977 -217.275711) (xy 349.931568 -217.312273)
			(xy 349.890974 -217.342977) (xy 349.846155 -217.367097) (xy 349.798169 -217.384064) (xy 349.77324 -217.389202)
			(xy 349.75038 -217.39352) (xy 349.546672 -217.74658) (xy 349.554292 -217.768678) (xy 349.563085 -217.795252)
			(xy 349.572534 -217.85042) (xy 349.573088 -217.878406) (xy 349.85198 -217.878406) (xy 349.852489 -217.852439)
			(xy 349.860614 -217.801144) (xy 349.876662 -217.751751) (xy 349.90024 -217.705477) (xy 349.930766 -217.663461)
			(xy 349.967489 -217.626738) (xy 350.009505 -217.596212) (xy 350.055779 -217.572634) (xy 350.105172 -217.556586)
			(xy 350.156467 -217.548461) (xy 350.208401 -217.548461) (xy 350.259696 -217.556586) (xy 350.309089 -217.572634)
			(xy 350.355363 -217.596212) (xy 350.397379 -217.626738) (xy 350.434102 -217.663461) (xy 350.464628 -217.705477)
			(xy 350.488206 -217.751751) (xy 350.504254 -217.801144) (xy 350.512379 -217.852439) (xy 350.512888 -217.878406)
			(xy 350.79178 -217.878406) (xy 350.792245 -217.852954) (xy 350.800023 -217.802648) (xy 350.815427 -217.754131)
			(xy 350.838092 -217.708551) (xy 350.867481 -217.666988) (xy 350.902898 -217.630426) (xy 350.943505 -217.59973)
			(xy 350.988341 -217.575628) (xy 351.036344 -217.558689) (xy 351.061274 -217.55354) (xy 351.084134 -217.549222)
			(xy 351.287842 -217.196162) (xy 351.280222 -217.174064) (xy 351.271476 -217.147478) (xy 351.262034 -217.092317)
			(xy 351.261426 -217.064336) (xy 351.261935 -217.038369) (xy 351.27006 -216.987074) (xy 351.286108 -216.937681)
			(xy 351.309686 -216.891407) (xy 351.340212 -216.849391) (xy 351.376935 -216.812668) (xy 351.418951 -216.782142)
			(xy 351.465225 -216.758564) (xy 351.514618 -216.742516) (xy 351.565913 -216.734391) (xy 351.617847 -216.734391)
			(xy 351.669142 -216.742516) (xy 351.718535 -216.758564) (xy 351.764809 -216.782142) (xy 351.806825 -216.812668)
			(xy 351.843548 -216.849391) (xy 351.874074 -216.891407) (xy 351.897652 -216.937681) (xy 351.9137 -216.987074)
			(xy 351.921825 -217.038369) (xy 351.922334 -217.064336) (xy 351.921896 -217.089789) (xy 351.921816 -217.090303)
			(xy 352.201989 -217.090303) (xy 352.201989 -217.038369) (xy 352.210114 -216.987074) (xy 352.226162 -216.937681)
			(xy 352.24974 -216.891407) (xy 352.280266 -216.849391) (xy 352.316989 -216.812668) (xy 352.359005 -216.782142)
			(xy 352.405279 -216.758564) (xy 352.454672 -216.742516) (xy 352.505967 -216.734391) (xy 352.557901 -216.734391)
			(xy 352.609196 -216.742516) (xy 352.658589 -216.758564) (xy 352.704863 -216.782142) (xy 352.746879 -216.812668)
			(xy 352.783602 -216.849391) (xy 352.814128 -216.891407) (xy 352.837706 -216.937681) (xy 352.853754 -216.987074)
			(xy 352.861879 -217.038369) (xy 352.862388 -217.064336) (xy 352.861879 -217.090303) (xy 352.853754 -217.141598)
			(xy 352.837706 -217.190991) (xy 352.814128 -217.237265) (xy 352.783602 -217.279281) (xy 352.746879 -217.316004)
			(xy 352.704863 -217.34653) (xy 352.658589 -217.370108) (xy 352.609196 -217.386156) (xy 352.557901 -217.394281)
			(xy 352.505967 -217.394281) (xy 352.454672 -217.386156) (xy 352.405279 -217.370108) (xy 352.359005 -217.34653)
			(xy 352.316989 -217.316004) (xy 352.280266 -217.279281) (xy 352.24974 -217.237265) (xy 352.226162 -217.190991)
			(xy 352.210114 -217.141598) (xy 352.201989 -217.090303) (xy 351.921816 -217.090303) (xy 351.914112 -217.140095)
			(xy 351.898703 -217.188612) (xy 351.876034 -217.234192) (xy 351.846642 -217.275754) (xy 351.811222 -217.312316)
			(xy 351.770612 -217.343011) (xy 351.725775 -217.367114) (xy 351.677771 -217.384053) (xy 351.65284 -217.389202)
			(xy 351.62998 -217.39352) (xy 351.426272 -217.74658) (xy 351.433892 -217.768678) (xy 351.442624 -217.795268)
			(xy 351.452075 -217.850426) (xy 351.452688 -217.878406) (xy 351.73158 -217.878406) (xy 351.732089 -217.852439)
			(xy 351.740214 -217.801144) (xy 351.756262 -217.751751) (xy 351.77984 -217.705477) (xy 351.810366 -217.663461)
			(xy 351.847089 -217.626738) (xy 351.889105 -217.596212) (xy 351.935379 -217.572634) (xy 351.984772 -217.556586)
			(xy 352.036067 -217.548461) (xy 352.088001 -217.548461) (xy 352.139296 -217.556586) (xy 352.188689 -217.572634)
			(xy 352.234963 -217.596212) (xy 352.276979 -217.626738) (xy 352.313702 -217.663461) (xy 352.344228 -217.705477)
			(xy 352.367806 -217.751751) (xy 352.383854 -217.801144) (xy 352.391979 -217.852439) (xy 352.392488 -217.878406)
			(xy 352.67138 -217.878406) (xy 352.671845 -217.852954) (xy 352.679623 -217.802648) (xy 352.695027 -217.754131)
			(xy 352.717692 -217.708551) (xy 352.747081 -217.666988) (xy 352.782498 -217.630426) (xy 352.823105 -217.59973)
			(xy 352.867941 -217.575628) (xy 352.915944 -217.558689) (xy 352.940874 -217.55354) (xy 352.963734 -217.549222)
			(xy 353.167442 -217.196162) (xy 353.159822 -217.174064) (xy 353.151076 -217.147478) (xy 353.141634 -217.092317)
			(xy 353.141026 -217.064336) (xy 353.141535 -217.038369) (xy 353.14966 -216.987074) (xy 353.165708 -216.937681)
			(xy 353.189286 -216.891407) (xy 353.219812 -216.849391) (xy 353.256535 -216.812668) (xy 353.298551 -216.782142)
			(xy 353.344825 -216.758564) (xy 353.394218 -216.742516) (xy 353.445513 -216.734391) (xy 353.497447 -216.734391)
			(xy 353.548742 -216.742516) (xy 353.598135 -216.758564) (xy 353.644409 -216.782142) (xy 353.686425 -216.812668)
			(xy 353.723148 -216.849391) (xy 353.753674 -216.891407) (xy 353.777252 -216.937681) (xy 353.7933 -216.987074)
			(xy 353.801425 -217.038369) (xy 353.801934 -217.064336) (xy 353.801496 -217.089789) (xy 353.801416 -217.090303)
			(xy 354.081589 -217.090303) (xy 354.081589 -217.038369) (xy 354.089714 -216.987074) (xy 354.105762 -216.937681)
			(xy 354.12934 -216.891407) (xy 354.159866 -216.849391) (xy 354.196589 -216.812668) (xy 354.238605 -216.782142)
			(xy 354.284879 -216.758564) (xy 354.334272 -216.742516) (xy 354.385567 -216.734391) (xy 354.437501 -216.734391)
			(xy 354.488796 -216.742516) (xy 354.538189 -216.758564) (xy 354.584463 -216.782142) (xy 354.626479 -216.812668)
			(xy 354.663202 -216.849391) (xy 354.693728 -216.891407) (xy 354.717306 -216.937681) (xy 354.733354 -216.987074)
			(xy 354.741479 -217.038369) (xy 354.741988 -217.064336) (xy 354.741479 -217.090303) (xy 354.733354 -217.141598)
			(xy 354.717306 -217.190991) (xy 354.693728 -217.237265) (xy 354.663202 -217.279281) (xy 354.626479 -217.316004)
			(xy 354.584463 -217.34653) (xy 354.538189 -217.370108) (xy 354.488796 -217.386156) (xy 354.437501 -217.394281)
			(xy 354.385567 -217.394281) (xy 354.334272 -217.386156) (xy 354.284879 -217.370108) (xy 354.238605 -217.34653)
			(xy 354.196589 -217.316004) (xy 354.159866 -217.279281) (xy 354.12934 -217.237265) (xy 354.105762 -217.190991)
			(xy 354.089714 -217.141598) (xy 354.081589 -217.090303) (xy 353.801416 -217.090303) (xy 353.793712 -217.140095)
			(xy 353.778303 -217.188612) (xy 353.755634 -217.234192) (xy 353.726242 -217.275754) (xy 353.690822 -217.312316)
			(xy 353.650212 -217.343011) (xy 353.605375 -217.367114) (xy 353.557371 -217.384053) (xy 353.53244 -217.389202)
			(xy 353.50958 -217.39352) (xy 353.305872 -217.74658) (xy 353.313492 -217.768678) (xy 353.322224 -217.795268)
			(xy 353.331675 -217.850426) (xy 353.332288 -217.878406) (xy 353.61118 -217.878406) (xy 353.611689 -217.852439)
			(xy 353.619814 -217.801144) (xy 353.635862 -217.751751) (xy 353.65944 -217.705477) (xy 353.689966 -217.663461)
			(xy 353.726689 -217.626738) (xy 353.768705 -217.596212) (xy 353.814979 -217.572634) (xy 353.864372 -217.556586)
			(xy 353.915667 -217.548461) (xy 353.967601 -217.548461) (xy 354.018896 -217.556586) (xy 354.068289 -217.572634)
			(xy 354.114563 -217.596212) (xy 354.156579 -217.626738) (xy 354.193302 -217.663461) (xy 354.223828 -217.705477)
			(xy 354.247406 -217.751751) (xy 354.263454 -217.801144) (xy 354.271579 -217.852439) (xy 354.272088 -217.878406)
			(xy 354.271537 -217.906392) (xy 354.262086 -217.96156) (xy 354.253292 -217.988134) (xy 354.245672 -218.010232)
			(xy 354.44938 -218.363038) (xy 354.47224 -218.367356) (xy 354.497159 -218.372533) (xy 354.545143 -218.389497)
			(xy 354.58996 -218.413614) (xy 354.630552 -218.444313) (xy 354.665961 -218.48087) (xy 354.69535 -218.522421)
			(xy 354.718024 -218.567984) (xy 354.733449 -218.616484) (xy 354.74126 -218.666775) (xy 354.741734 -218.692222)
			(xy 354.741225 -218.718189) (xy 354.7331 -218.769484) (xy 354.717052 -218.818877) (xy 354.693474 -218.865151)
			(xy 354.662948 -218.907167) (xy 354.626225 -218.94389) (xy 354.584209 -218.974416) (xy 354.537935 -218.997994)
			(xy 354.488542 -219.014042) (xy 354.437247 -219.022167) (xy 354.385313 -219.022167) (xy 354.334018 -219.014042)
			(xy 354.284625 -218.997994) (xy 354.238351 -218.974416) (xy 354.196335 -218.94389) (xy 354.159612 -218.907167)
			(xy 354.129086 -218.865151) (xy 354.105508 -218.818877) (xy 354.08946 -218.769484) (xy 354.081335 -218.718189)
			(xy 354.080826 -218.692222) (xy 354.081383 -218.664236) (xy 354.09083 -218.609068) (xy 354.099622 -218.582494)
			(xy 354.107242 -218.560396) (xy 353.903534 -218.20759) (xy 353.880674 -218.203272) (xy 353.855763 -218.198058)
			(xy 353.807782 -218.181098) (xy 353.762966 -218.156986) (xy 353.722374 -218.126292) (xy 353.686965 -218.08974)
			(xy 353.657575 -218.048193) (xy 353.634898 -218.002634) (xy 353.619471 -217.954138) (xy 353.611656 -217.903851)
			(xy 353.61118 -217.878406) (xy 353.332288 -217.878406) (xy 353.331779 -217.904373) (xy 353.323654 -217.955668)
			(xy 353.307606 -218.005061) (xy 353.284028 -218.051335) (xy 353.253502 -218.093351) (xy 353.216779 -218.130074)
			(xy 353.174763 -218.1606) (xy 353.128489 -218.184178) (xy 353.079096 -218.200226) (xy 353.027801 -218.208351)
			(xy 352.975867 -218.208351) (xy 352.924572 -218.200226) (xy 352.875179 -218.184178) (xy 352.828905 -218.1606)
			(xy 352.786889 -218.130074) (xy 352.750166 -218.093351) (xy 352.71964 -218.051335) (xy 352.696062 -218.005061)
			(xy 352.680014 -217.955668) (xy 352.671889 -217.904373) (xy 352.67138 -217.878406) (xy 352.392488 -217.878406)
			(xy 352.391937 -217.906392) (xy 352.382486 -217.96156) (xy 352.373692 -217.988134) (xy 352.366072 -218.010232)
			(xy 352.56978 -218.363038) (xy 352.59264 -218.367356) (xy 352.617559 -218.372533) (xy 352.665543 -218.389497)
			(xy 352.71036 -218.413614) (xy 352.750952 -218.444313) (xy 352.786361 -218.48087) (xy 352.81575 -218.522421)
			(xy 352.838424 -218.567984) (xy 352.853849 -218.616484) (xy 352.86166 -218.666775) (xy 352.862134 -218.692222)
			(xy 352.861625 -218.718189) (xy 352.8535 -218.769484) (xy 352.837452 -218.818877) (xy 352.813874 -218.865151)
			(xy 352.783348 -218.907167) (xy 352.746625 -218.94389) (xy 352.704609 -218.974416) (xy 352.658335 -218.997994)
			(xy 352.608942 -219.014042) (xy 352.557647 -219.022167) (xy 352.505713 -219.022167) (xy 352.454418 -219.014042)
			(xy 352.405025 -218.997994) (xy 352.358751 -218.974416) (xy 352.316735 -218.94389) (xy 352.280012 -218.907167)
			(xy 352.249486 -218.865151) (xy 352.225908 -218.818877) (xy 352.20986 -218.769484) (xy 352.201735 -218.718189)
			(xy 352.201226 -218.692222) (xy 352.201783 -218.664236) (xy 352.21123 -218.609068) (xy 352.220022 -218.582494)
			(xy 352.227642 -218.560396) (xy 352.023934 -218.20759) (xy 352.001074 -218.203272) (xy 351.976163 -218.198058)
			(xy 351.928182 -218.181098) (xy 351.883366 -218.156986) (xy 351.842774 -218.126292) (xy 351.807365 -218.08974)
			(xy 351.777975 -218.048193) (xy 351.755298 -218.002634) (xy 351.739871 -217.954138) (xy 351.732056 -217.903851)
			(xy 351.73158 -217.878406) (xy 351.452688 -217.878406) (xy 351.452179 -217.904373) (xy 351.444054 -217.955668)
			(xy 351.428006 -218.005061) (xy 351.404428 -218.051335) (xy 351.373902 -218.093351) (xy 351.337179 -218.130074)
			(xy 351.295163 -218.1606) (xy 351.248889 -218.184178) (xy 351.199496 -218.200226) (xy 351.148201 -218.208351)
			(xy 351.096267 -218.208351) (xy 351.044972 -218.200226) (xy 350.995579 -218.184178) (xy 350.949305 -218.1606)
			(xy 350.907289 -218.130074) (xy 350.870566 -218.093351) (xy 350.84004 -218.051335) (xy 350.816462 -218.005061)
			(xy 350.800414 -217.955668) (xy 350.792289 -217.904373) (xy 350.79178 -217.878406) (xy 350.512888 -217.878406)
			(xy 350.512337 -217.906392) (xy 350.502886 -217.96156) (xy 350.494092 -217.988134) (xy 350.486472 -218.010232)
			(xy 350.69018 -218.363038) (xy 350.71304 -218.367356) (xy 350.737959 -218.372533) (xy 350.785943 -218.389497)
			(xy 350.83076 -218.413614) (xy 350.871352 -218.444313) (xy 350.906761 -218.48087) (xy 350.93615 -218.522421)
			(xy 350.958824 -218.567984) (xy 350.974249 -218.616484) (xy 350.98206 -218.666775) (xy 350.982534 -218.692222)
			(xy 350.982025 -218.718189) (xy 350.9739 -218.769484) (xy 350.957852 -218.818877) (xy 350.934274 -218.865151)
			(xy 350.903748 -218.907167) (xy 350.867025 -218.94389) (xy 350.825009 -218.974416) (xy 350.778735 -218.997994)
			(xy 350.729342 -219.014042) (xy 350.678047 -219.022167) (xy 350.626113 -219.022167) (xy 350.574818 -219.014042)
			(xy 350.525425 -218.997994) (xy 350.479151 -218.974416) (xy 350.437135 -218.94389) (xy 350.400412 -218.907167)
			(xy 350.369886 -218.865151) (xy 350.346308 -218.818877) (xy 350.33026 -218.769484) (xy 350.322135 -218.718189)
			(xy 350.321626 -218.692222) (xy 350.322183 -218.664236) (xy 350.33163 -218.609068) (xy 350.340422 -218.582494)
			(xy 350.348042 -218.560396) (xy 350.144334 -218.20759) (xy 350.121474 -218.203272) (xy 350.096563 -218.198058)
			(xy 350.048582 -218.181098) (xy 350.003766 -218.156986) (xy 349.963174 -218.126292) (xy 349.927765 -218.08974)
			(xy 349.898375 -218.048193) (xy 349.875698 -218.002634) (xy 349.860271 -217.954138) (xy 349.852456 -217.903851)
			(xy 349.85198 -217.878406) (xy 349.573088 -217.878406) (xy 349.572578 -217.904374) (xy 349.564453 -217.95567)
			(xy 349.548405 -218.005064) (xy 349.524827 -218.05134) (xy 349.494301 -218.093358) (xy 349.457579 -218.130083)
			(xy 349.415564 -218.160613) (xy 349.36929 -218.184194) (xy 349.319897 -218.200247) (xy 349.268602 -218.208376)
			(xy 349.242634 -218.20886) (xy 349.214855 -218.208264) (xy 349.160082 -218.19894) (xy 349.133668 -218.190318)
			(xy 349.120437 -218.186181) (xy 349.092784 -218.184397) (xy 349.065671 -218.190116) (xy 349.041095 -218.202918)
			(xy 349.020869 -218.221859) (xy 349.006482 -218.245542) (xy 348.998996 -218.272221) (xy 348.99854 -218.286076)
			(xy 348.99854 -218.451176) (xy 349.017887 -218.47006) (xy 349.050774 -218.512967) (xy 349.076238 -218.560655)
			(xy 349.0936 -218.611852) (xy 349.102396 -218.665192) (xy 349.102934 -218.692222) (xy 349.102734 -218.708071)
			(xy 349.099681 -218.739621) (xy 349.096838 -218.755214) (xy 349.091758 -218.781884) (xy 349.71482 -219.404946)
			(xy 349.725154 -219.414571) (xy 349.749858 -219.428231) (xy 349.777356 -219.434614) (xy 349.805551 -219.433233)
			(xy 349.832294 -219.424193) (xy 349.855544 -219.408183) (xy 349.873529 -219.386425) (xy 349.879666 -219.373704)
			(xy 349.891119 -219.348843) (xy 349.921006 -219.30299) (xy 349.958039 -219.262688) (xy 350.001205 -219.229036)
			(xy 350.049325 -219.202955) (xy 350.101084 -219.185158) (xy 350.155067 -219.17613) (xy 350.182434 -219.175584)
			(xy 350.2084 -219.176069) (xy 350.259693 -219.184199) (xy 350.309083 -219.200252) (xy 350.355353 -219.223834)
			(xy 350.397364 -219.254364) (xy 350.434083 -219.29109) (xy 350.464603 -219.333109) (xy 350.488175 -219.379384)
			(xy 350.504218 -219.428777) (xy 350.512336 -219.480071) (xy 350.512888 -219.506038) (xy 350.512384 -219.532005)
			(xy 350.792289 -219.532005) (xy 350.792289 -219.480071) (xy 350.800414 -219.428776) (xy 350.816462 -219.379383)
			(xy 350.84004 -219.333109) (xy 350.870566 -219.291093) (xy 350.907289 -219.25437) (xy 350.949305 -219.223844)
			(xy 350.995579 -219.200266) (xy 351.044972 -219.184218) (xy 351.096267 -219.176093) (xy 351.148201 -219.176093)
			(xy 351.199496 -219.184218) (xy 351.248889 -219.200266) (xy 351.295163 -219.223844) (xy 351.337179 -219.25437)
			(xy 351.373902 -219.291093) (xy 351.404428 -219.333109) (xy 351.428006 -219.379383) (xy 351.444054 -219.428776)
			(xy 351.452179 -219.480071) (xy 351.452688 -219.506038) (xy 351.452179 -219.532005) (xy 351.732089 -219.532005)
			(xy 351.732089 -219.480071) (xy 351.740214 -219.428776) (xy 351.756262 -219.379383) (xy 351.77984 -219.333109)
			(xy 351.810366 -219.291093) (xy 351.847089 -219.25437) (xy 351.889105 -219.223844) (xy 351.935379 -219.200266)
			(xy 351.984772 -219.184218) (xy 352.036067 -219.176093) (xy 352.088001 -219.176093) (xy 352.139296 -219.184218)
			(xy 352.188689 -219.200266) (xy 352.234963 -219.223844) (xy 352.276979 -219.25437) (xy 352.313702 -219.291093)
			(xy 352.344228 -219.333109) (xy 352.367806 -219.379383) (xy 352.383854 -219.428776) (xy 352.391979 -219.480071)
			(xy 352.392488 -219.506038) (xy 352.391979 -219.532005) (xy 352.671889 -219.532005) (xy 352.671889 -219.480071)
			(xy 352.680014 -219.428776) (xy 352.696062 -219.379383) (xy 352.71964 -219.333109) (xy 352.750166 -219.291093)
			(xy 352.786889 -219.25437) (xy 352.828905 -219.223844) (xy 352.875179 -219.200266) (xy 352.924572 -219.184218)
			(xy 352.975867 -219.176093) (xy 353.027801 -219.176093) (xy 353.079096 -219.184218) (xy 353.128489 -219.200266)
			(xy 353.174763 -219.223844) (xy 353.216779 -219.25437) (xy 353.253502 -219.291093) (xy 353.284028 -219.333109)
			(xy 353.307606 -219.379383) (xy 353.323654 -219.428776) (xy 353.331779 -219.480071) (xy 353.332288 -219.506038)
			(xy 353.331779 -219.532005) (xy 353.611689 -219.532005) (xy 353.611689 -219.480071) (xy 353.619814 -219.428776)
			(xy 353.635862 -219.379383) (xy 353.65944 -219.333109) (xy 353.689966 -219.291093) (xy 353.726689 -219.25437)
			(xy 353.768705 -219.223844) (xy 353.814979 -219.200266) (xy 353.864372 -219.184218) (xy 353.915667 -219.176093)
			(xy 353.967601 -219.176093) (xy 354.018896 -219.184218) (xy 354.068289 -219.200266) (xy 354.114563 -219.223844)
			(xy 354.156579 -219.25437) (xy 354.193302 -219.291093) (xy 354.223828 -219.333109) (xy 354.247406 -219.379383)
			(xy 354.263454 -219.428776) (xy 354.271579 -219.480071) (xy 354.272088 -219.506038) (xy 354.271579 -219.532005)
			(xy 354.263454 -219.5833) (xy 354.247406 -219.632693) (xy 354.223828 -219.678967) (xy 354.193302 -219.720983)
			(xy 354.156579 -219.757706) (xy 354.114563 -219.788232) (xy 354.068289 -219.81181) (xy 354.018896 -219.827858)
			(xy 353.967601 -219.835983) (xy 353.915667 -219.835983) (xy 353.864372 -219.827858) (xy 353.814979 -219.81181)
			(xy 353.768705 -219.788232) (xy 353.726689 -219.757706) (xy 353.689966 -219.720983) (xy 353.65944 -219.678967)
			(xy 353.635862 -219.632693) (xy 353.619814 -219.5833) (xy 353.611689 -219.532005) (xy 353.331779 -219.532005)
			(xy 353.323654 -219.5833) (xy 353.307606 -219.632693) (xy 353.284028 -219.678967) (xy 353.253502 -219.720983)
			(xy 353.216779 -219.757706) (xy 353.174763 -219.788232) (xy 353.128489 -219.81181) (xy 353.079096 -219.827858)
			(xy 353.027801 -219.835983) (xy 352.975867 -219.835983) (xy 352.924572 -219.827858) (xy 352.875179 -219.81181)
			(xy 352.828905 -219.788232) (xy 352.786889 -219.757706) (xy 352.750166 -219.720983) (xy 352.71964 -219.678967)
			(xy 352.696062 -219.632693) (xy 352.680014 -219.5833) (xy 352.671889 -219.532005) (xy 352.391979 -219.532005)
			(xy 352.383854 -219.5833) (xy 352.367806 -219.632693) (xy 352.344228 -219.678967) (xy 352.313702 -219.720983)
			(xy 352.276979 -219.757706) (xy 352.234963 -219.788232) (xy 352.188689 -219.81181) (xy 352.139296 -219.827858)
			(xy 352.088001 -219.835983) (xy 352.036067 -219.835983) (xy 351.984772 -219.827858) (xy 351.935379 -219.81181)
			(xy 351.889105 -219.788232) (xy 351.847089 -219.757706) (xy 351.810366 -219.720983) (xy 351.77984 -219.678967)
			(xy 351.756262 -219.632693) (xy 351.740214 -219.5833) (xy 351.732089 -219.532005) (xy 351.452179 -219.532005)
			(xy 351.444054 -219.5833) (xy 351.428006 -219.632693) (xy 351.404428 -219.678967) (xy 351.373902 -219.720983)
			(xy 351.337179 -219.757706) (xy 351.295163 -219.788232) (xy 351.248889 -219.81181) (xy 351.199496 -219.827858)
			(xy 351.148201 -219.835983) (xy 351.096267 -219.835983) (xy 351.044972 -219.827858) (xy 350.995579 -219.81181)
			(xy 350.949305 -219.788232) (xy 350.907289 -219.757706) (xy 350.870566 -219.720983) (xy 350.84004 -219.678967)
			(xy 350.816462 -219.632693) (xy 350.800414 -219.5833) (xy 350.792289 -219.532005) (xy 350.512384 -219.532005)
			(xy 350.512357 -219.533408) (xy 350.503345 -219.587402) (xy 350.485556 -219.639172) (xy 350.459479 -219.687302)
			(xy 350.425825 -219.730476) (xy 350.385515 -219.767512) (xy 350.339652 -219.797398) (xy 350.314768 -219.808806)
			(xy 350.301981 -219.814864) (xy 350.280129 -219.832822) (xy 350.264047 -219.856089) (xy 350.254972 -219.882878)
			(xy 350.253601 -219.911128) (xy 350.26004 -219.93867) (xy 350.273793 -219.963385) (xy 350.283526 -219.973652)
			(xy 350.405446 -220.095572) (xy 350.441006 -220.065854) (xy 350.463439 -220.04797) (xy 350.5132 -220.019427)
			(xy 350.567145 -219.999916) (xy 350.623651 -219.990022) (xy 350.652334 -219.9894) (xy 350.678301 -219.989912)
			(xy 350.729594 -219.99804) (xy 350.778985 -220.014091) (xy 350.825258 -220.03767) (xy 350.867273 -220.068196)
			(xy 350.903996 -220.104918) (xy 350.934524 -220.146932) (xy 350.958104 -220.193204) (xy 350.974157 -220.242594)
			(xy 350.982287 -220.293887) (xy 350.982788 -220.319854) (xy 350.982169 -220.348535) (xy 350.972257 -220.405036)
			(xy 350.952739 -220.458976) (xy 350.924202 -220.508737) (xy 350.906334 -220.531182) (xy 350.876616 -220.566742)
			(xy 351.001838 -220.691964) (xy 351.011532 -220.701121) (xy 351.034607 -220.714473) (xy 351.060353 -220.721388)
			(xy 351.087013 -220.721393) (xy 351.112762 -220.714487) (xy 351.135841 -220.701142) (xy 351.154672 -220.682272)
			(xy 351.161604 -220.670882) (xy 351.287842 -220.45168) (xy 351.280222 -220.429582) (xy 351.271432 -220.403007)
			(xy 351.261989 -220.347839) (xy 351.261426 -220.319854) (xy 351.261935 -220.293887) (xy 351.27006 -220.242592)
			(xy 351.286108 -220.193199) (xy 351.309686 -220.146925) (xy 351.340212 -220.104909) (xy 351.376935 -220.068186)
			(xy 351.418951 -220.03766) (xy 351.465225 -220.014082) (xy 351.514618 -219.998034) (xy 351.565913 -219.989909)
			(xy 351.617847 -219.989909) (xy 351.669142 -219.998034) (xy 351.718535 -220.014082) (xy 351.764809 -220.03766)
			(xy 351.806825 -220.068186) (xy 351.843548 -220.104909) (xy 351.874074 -220.146925) (xy 351.897652 -220.193199)
			(xy 351.9137 -220.242592) (xy 351.921825 -220.293887) (xy 351.922334 -220.319854) (xy 351.921862 -220.345302)
			(xy 351.921781 -220.345821) (xy 352.201989 -220.345821) (xy 352.201989 -220.293887) (xy 352.210114 -220.242592)
			(xy 352.226162 -220.193199) (xy 352.24974 -220.146925) (xy 352.280266 -220.104909) (xy 352.316989 -220.068186)
			(xy 352.359005 -220.03766) (xy 352.405279 -220.014082) (xy 352.454672 -219.998034) (xy 352.505967 -219.989909)
			(xy 352.557901 -219.989909) (xy 352.609196 -219.998034) (xy 352.658589 -220.014082) (xy 352.704863 -220.03766)
			(xy 352.746879 -220.068186) (xy 352.783602 -220.104909) (xy 352.814128 -220.146925) (xy 352.837706 -220.193199)
			(xy 352.853754 -220.242592) (xy 352.861879 -220.293887) (xy 352.862388 -220.319854) (xy 353.141026 -220.319854)
			(xy 353.141535 -220.293887) (xy 353.14966 -220.242592) (xy 353.165708 -220.193199) (xy 353.189286 -220.146925)
			(xy 353.219812 -220.104909) (xy 353.256535 -220.068186) (xy 353.298551 -220.03766) (xy 353.344825 -220.014082)
			(xy 353.394218 -219.998034) (xy 353.445513 -219.989909) (xy 353.497447 -219.989909) (xy 353.548742 -219.998034)
			(xy 353.598135 -220.014082) (xy 353.644409 -220.03766) (xy 353.686425 -220.068186) (xy 353.723148 -220.104909)
			(xy 353.753674 -220.146925) (xy 353.777252 -220.193199) (xy 353.7933 -220.242592) (xy 353.801425 -220.293887)
			(xy 353.801934 -220.319854) (xy 353.801934 -220.320616) (xy 353.801353 -220.348334) (xy 353.792024 -220.402981)
			(xy 353.783392 -220.429328) (xy 353.775518 -220.451172) (xy 353.979734 -220.80474) (xy 354.002594 -220.809058)
			(xy 354.027507 -220.814267) (xy 354.07549 -220.831224) (xy 354.120308 -220.855335) (xy 354.160902 -220.886029)
			(xy 354.196312 -220.922582) (xy 354.225702 -220.96413) (xy 354.248378 -221.009691) (xy 354.263803 -221.058189)
			(xy 354.271614 -221.108478) (xy 354.272088 -221.133924) (xy 354.271579 -221.159891) (xy 354.263454 -221.211186)
			(xy 354.247406 -221.260579) (xy 354.223828 -221.306853) (xy 354.193302 -221.348869) (xy 354.156579 -221.385592)
			(xy 354.114563 -221.416118) (xy 354.068289 -221.439696) (xy 354.018896 -221.455744) (xy 353.967601 -221.463869)
			(xy 353.915667 -221.463869) (xy 353.864372 -221.455744) (xy 353.814979 -221.439696) (xy 353.768705 -221.416118)
			(xy 353.726689 -221.385592) (xy 353.689966 -221.348869) (xy 353.65944 -221.306853) (xy 353.635862 -221.260579)
			(xy 353.619814 -221.211186) (xy 353.611689 -221.159891) (xy 353.61118 -221.133924) (xy 353.61174 -221.105938)
			(xy 353.621185 -221.050771) (xy 353.629976 -221.024196) (xy 353.637596 -221.002098) (xy 353.433888 -220.649038)
			(xy 353.410774 -220.64472) (xy 353.385833 -220.639583) (xy 353.33781 -220.622649) (xy 353.292952 -220.598551)
			(xy 353.25232 -220.567859) (xy 353.216875 -220.5313) (xy 353.187455 -220.489738) (xy 353.164756 -220.444156)
			(xy 353.149316 -220.395632) (xy 353.1415 -220.345314) (xy 353.141026 -220.319854) (xy 352.862388 -220.319854)
			(xy 352.861879 -220.345821) (xy 352.853754 -220.397116) (xy 352.837706 -220.446509) (xy 352.814128 -220.492783)
			(xy 352.783602 -220.534799) (xy 352.746879 -220.571522) (xy 352.704863 -220.602048) (xy 352.658589 -220.625626)
			(xy 352.609196 -220.641674) (xy 352.557901 -220.649799) (xy 352.505967 -220.649799) (xy 352.454672 -220.641674)
			(xy 352.405279 -220.625626) (xy 352.359005 -220.602048) (xy 352.316989 -220.571522) (xy 352.280266 -220.534799)
			(xy 352.24974 -220.492783) (xy 352.226162 -220.446509) (xy 352.210114 -220.397116) (xy 352.201989 -220.345821)
			(xy 351.921781 -220.345821) (xy 351.914054 -220.395596) (xy 351.898631 -220.444099) (xy 351.875958 -220.489665)
			(xy 351.84657 -220.531219) (xy 351.811161 -220.567779) (xy 351.770568 -220.598481) (xy 351.72575 -220.6226)
			(xy 351.677765 -220.639565) (xy 351.65284 -220.64472) (xy 351.62998 -220.649038) (xy 351.426272 -221.002098)
			(xy 351.433892 -221.024196) (xy 351.441867 -221.04822) (xy 351.451179 -221.097974) (xy 351.452434 -221.123256)
			(xy 351.453196 -221.143322) (xy 351.469765 -221.159891) (xy 351.732089 -221.159891) (xy 351.732089 -221.107957)
			(xy 351.740214 -221.056662) (xy 351.756262 -221.007269) (xy 351.77984 -220.960995) (xy 351.810366 -220.918979)
			(xy 351.847089 -220.882256) (xy 351.889105 -220.85173) (xy 351.935379 -220.828152) (xy 351.984772 -220.812104)
			(xy 352.036067 -220.803979) (xy 352.088001 -220.803979) (xy 352.139296 -220.812104) (xy 352.188689 -220.828152)
			(xy 352.234963 -220.85173) (xy 352.276979 -220.882256) (xy 352.313702 -220.918979) (xy 352.344228 -220.960995)
			(xy 352.367806 -221.007269) (xy 352.383854 -221.056662) (xy 352.391979 -221.107957) (xy 352.392488 -221.133924)
			(xy 352.391979 -221.159891) (xy 352.383854 -221.211186) (xy 352.367806 -221.260579) (xy 352.344228 -221.306853)
			(xy 352.313702 -221.348869) (xy 352.276979 -221.385592) (xy 352.234963 -221.416118) (xy 352.188689 -221.439696)
			(xy 352.139296 -221.455744) (xy 352.088001 -221.463869) (xy 352.036067 -221.463869) (xy 351.984772 -221.455744)
			(xy 351.935379 -221.439696) (xy 351.889105 -221.416118) (xy 351.847089 -221.385592) (xy 351.810366 -221.348869)
			(xy 351.77984 -221.306853) (xy 351.756262 -221.260579) (xy 351.740214 -221.211186) (xy 351.732089 -221.159891)
			(xy 351.469765 -221.159891) (xy 352.096324 -221.78645) (xy 352.107437 -221.796716) (xy 352.134183 -221.810823)
			(xy 352.163884 -221.816493) (xy 352.193946 -221.81323) (xy 352.221739 -221.801319) (xy 352.244835 -221.781802)
			(xy 352.25355 -221.769432) (xy 352.268536 -221.74702) (xy 352.304593 -221.706941) (xy 352.346676 -221.673246)
			(xy 352.39367 -221.646826) (xy 352.444328 -221.628382) (xy 352.47072 -221.622874) (xy 352.49358 -221.618556)
			(xy 352.697542 -221.264988) (xy 352.689922 -221.243144) (xy 352.68128 -221.216735) (xy 352.671965 -221.161959)
			(xy 352.67138 -221.134178) (xy 352.67138 -221.133924) (xy 352.671889 -221.107957) (xy 352.680014 -221.056662)
			(xy 352.696062 -221.007269) (xy 352.71964 -220.960995) (xy 352.750166 -220.918979) (xy 352.786889 -220.882256)
			(xy 352.828905 -220.85173) (xy 352.875179 -220.828152) (xy 352.924572 -220.812104) (xy 352.975867 -220.803979)
			(xy 353.027801 -220.803979) (xy 353.079096 -220.812104) (xy 353.128489 -220.828152) (xy 353.174763 -220.85173)
			(xy 353.216779 -220.882256) (xy 353.253502 -220.918979) (xy 353.284028 -220.960995) (xy 353.307606 -221.007269)
			(xy 353.323654 -221.056662) (xy 353.331779 -221.107957) (xy 353.332288 -221.133924) (xy 353.331815 -221.159396)
			(xy 353.323992 -221.209734) (xy 353.308535 -221.258276) (xy 353.28581 -221.303869) (xy 353.256355 -221.345434)
			(xy 353.22087 -221.381985) (xy 353.180195 -221.412657) (xy 353.135293 -221.436721) (xy 353.087231 -221.453607)
			(xy 353.062286 -221.45879) (xy 353.039172 -221.463108) (xy 352.835718 -221.815914) (xy 352.843338 -221.838012)
			(xy 352.85213 -221.864586) (xy 352.861575 -221.919754) (xy 352.862134 -221.94774) (xy 352.861714 -221.971671)
			(xy 352.854819 -222.019035) (xy 352.841165 -222.064908) (xy 352.821038 -222.108333) (xy 352.808286 -222.128588)
			(xy 352.801176 -222.140264) (xy 352.79282 -222.166281) (xy 352.791667 -222.193583) (xy 352.797799 -222.220213)
			(xy 352.810777 -222.244261) (xy 352.829671 -222.264004) (xy 352.853125 -222.278026) (xy 352.87946 -222.285323)
			(xy 352.893122 -222.285814)
		)
		(stroke
			(width 0)
			(type solid)
		)
		(fill yes)
		(layer "In6.Cu")
		(net "PVCCD_HV_CPU0")
	)
	(gr_poly
		(pts
			(xy 349.54845 -261.05993) (xy 349.562723 -261.039595) (xy 349.596377 -261.003052) (xy 349.635122 -260.971958)
			(xy 349.678086 -260.947016) (xy 349.724301 -260.928788) (xy 349.772723 -260.917683) (xy 349.822262 -260.913954)
			(xy 349.871801 -260.917683) (xy 349.920223 -260.928788) (xy 349.966438 -260.947016) (xy 350.009402 -260.971958)
			(xy 350.048147 -261.003052) (xy 350.081801 -261.039595) (xy 350.096074 -261.05993) (xy 350.402906 -261.05993)
			(xy 350.416832 -261.059509) (xy 350.443652 -261.051996) (xy 350.467438 -261.037506) (xy 350.486414 -261.017119)
			(xy 350.499166 -260.992357) (xy 350.50474 -260.965068) (xy 350.502721 -260.93729) (xy 350.49841 -260.92404)
			(xy 350.489393 -260.89705) (xy 350.479692 -260.840984) (xy 350.479106 -260.812534) (xy 350.479613 -260.786564)
			(xy 350.487733 -260.735262) (xy 350.503778 -260.685863) (xy 350.527353 -260.639581) (xy 350.557878 -260.597557)
			(xy 350.594601 -260.560826) (xy 350.636618 -260.530292) (xy 350.682894 -260.506706) (xy 350.73229 -260.49065)
			(xy 350.78359 -260.482518) (xy 350.80956 -260.48208) (xy 350.83617 -260.482618) (xy 350.888702 -260.491153)
			(xy 350.939188 -260.507992) (xy 350.986324 -260.532702) (xy 351.028894 -260.564643) (xy 351.065797 -260.602991)
			(xy 351.09608 -260.646756) (xy 351.10801 -260.670548) (xy 351.114415 -260.68289) (xy 351.132693 -260.703828)
			(xy 351.155938 -260.719065) (xy 351.18243 -260.727473) (xy 351.210207 -260.728429) (xy 351.237214 -260.721863)
			(xy 351.261452 -260.70826) (xy 351.271586 -260.698742) (xy 351.489518 -260.48081) (xy 351.489518 -258.122166)
			(xy 351.489044 -258.107889) (xy 351.481143 -258.08045) (xy 351.465941 -258.056279) (xy 351.444633 -258.037272)
			(xy 351.418889 -258.024921) (xy 351.390729 -258.020194) (xy 351.376488 -258.021328) (xy 351.367247 -258.022292)
			(xy 351.348695 -258.023311) (xy 351.339404 -258.02336) (xy 351.313434 -258.022877) (xy 351.262133 -258.014753)
			(xy 351.212736 -257.998703) (xy 351.166457 -257.975123) (xy 351.124436 -257.944594) (xy 351.087709 -257.907867)
			(xy 351.057179 -257.865847) (xy 351.033599 -257.819568) (xy 351.017548 -257.77017) (xy 351.009423 -257.71887)
			(xy 351.009423 -257.66693) (xy 351.017548 -257.61563) (xy 351.033599 -257.566232) (xy 351.057179 -257.519953)
			(xy 351.087709 -257.477933) (xy 351.124436 -257.441206) (xy 351.166457 -257.410677) (xy 351.212736 -257.387097)
			(xy 351.262133 -257.371047) (xy 351.313434 -257.362923) (xy 351.339404 -257.362452) (xy 351.348695 -257.362503)
			(xy 351.367247 -257.36352) (xy 351.376488 -257.364484) (xy 351.390722 -257.36561) (xy 351.418861 -257.360844)
			(xy 351.444584 -257.348479) (xy 351.465882 -257.32948) (xy 351.481092 -257.30533) (xy 351.489027 -257.277915)
			(xy 351.489518 -257.263646) (xy 351.489518 -249.79249) (xy 352.795078 -248.48693) (xy 352.795078 -245.06555)
			(xy 351.225358 -243.49583) (xy 351.225358 -241.26063) (xy 351.224862 -241.246217) (xy 351.216811 -241.218538)
			(xy 351.201344 -241.194213) (xy 351.179694 -241.175182) (xy 351.153586 -241.162962) (xy 351.125103 -241.158528)
			(xy 351.096516 -241.162234) (xy 351.070105 -241.173783) (xy 351.058734 -241.182652) (xy 351.036248 -241.200584)
			(xy 350.986369 -241.229207) (xy 350.932295 -241.248781) (xy 350.875652 -241.258718) (xy 350.846898 -241.25936)
			(xy 350.820931 -241.258851) (xy 350.769636 -241.250726) (xy 350.720243 -241.234677) (xy 350.673969 -241.2111)
			(xy 350.631953 -241.180573) (xy 350.595229 -241.14385) (xy 350.564703 -241.101835) (xy 350.541124 -241.055561)
			(xy 350.525075 -241.006168) (xy 350.51695 -240.954873) (xy 350.516444 -240.928906) (xy 350.516871 -240.904352)
			(xy 350.524098 -240.855779) (xy 350.538437 -240.808812) (xy 350.559573 -240.764486) (xy 350.58704 -240.723779)
			(xy 350.603312 -240.705386) (xy 350.613114 -240.693896) (xy 350.626124 -240.666658) (xy 350.630593 -240.636804)
			(xy 350.626127 -240.606951) (xy 350.613119 -240.579712) (xy 350.603312 -240.568226) (xy 350.587059 -240.549821)
			(xy 350.559612 -240.509108) (xy 350.538487 -240.464783) (xy 350.524151 -240.417822) (xy 350.516917 -240.369257)
			(xy 350.516444 -240.344706) (xy 350.516926 -240.318736) (xy 350.525051 -240.267436) (xy 350.5411 -240.218039)
			(xy 350.564679 -240.17176) (xy 350.595208 -240.12974) (xy 350.631934 -240.093013) (xy 350.673953 -240.062483)
			(xy 350.720231 -240.038903) (xy 350.769629 -240.022852) (xy 350.820928 -240.014727) (xy 350.846898 -240.014252)
			(xy 350.871319 -240.014692) (xy 350.919627 -240.021885) (xy 350.966349 -240.036115) (xy 351.010466 -240.05707)
			(xy 351.051016 -240.084295) (xy 351.087113 -240.117196) (xy 351.117972 -240.155054) (xy 351.13087 -240.175796)
			(xy 351.145602 -240.200688) (xy 351.225358 -240.200688) (xy 351.225358 -240.05921) (xy 351.060258 -239.89411)
			(xy 349.10268 -239.89411) (xy 349.093282 -239.932718) (xy 349.086993 -239.956291) (xy 349.068429 -240.001407)
			(xy 349.043431 -240.043302) (xy 349.012544 -240.081066) (xy 348.976439 -240.113876) (xy 348.935902 -240.14102)
			(xy 348.891813 -240.161908) (xy 348.845132 -240.176084) (xy 348.796873 -240.183241) (xy 348.77248 -240.18367)
			(xy 348.747951 -240.183228) (xy 348.699431 -240.175983) (xy 348.652516 -240.16164) (xy 348.608239 -240.140516)
			(xy 348.567574 -240.113074) (xy 348.549214 -240.096802) (xy 348.537373 -240.086636) (xy 348.509137 -240.073381)
			(xy 348.478217 -240.069275) (xy 348.4475 -240.0747) (xy 348.419857 -240.089151) (xy 348.408498 -240.09985)
			(xy 348.332806 -240.175542) (xy 348.323568 -240.185374) (xy 348.31016 -240.208774) (xy 348.303346 -240.234867)
			(xy 348.303599 -240.261835) (xy 348.310903 -240.287796) (xy 348.324748 -240.31094) (xy 348.344168 -240.329653)
			(xy 348.367809 -240.34263) (xy 348.380812 -240.34623) (xy 348.404483 -240.352442) (xy 348.44981 -240.370892)
			(xy 348.491921 -240.395824) (xy 348.529896 -240.426692) (xy 348.562904 -240.462822) (xy 348.590225 -240.503425)
			(xy 348.611259 -240.547611) (xy 348.625549 -240.594417) (xy 348.632782 -240.642817) (xy 348.633288 -240.667286)
			(xy 348.63278 -240.693253) (xy 348.912689 -240.693253) (xy 348.912689 -240.641319) (xy 348.920814 -240.590024)
			(xy 348.936862 -240.540631) (xy 348.96044 -240.494357) (xy 348.990966 -240.452341) (xy 349.027689 -240.415618)
			(xy 349.069705 -240.385092) (xy 349.115979 -240.361514) (xy 349.165372 -240.345466) (xy 349.216667 -240.337341)
			(xy 349.268601 -240.337341) (xy 349.319896 -240.345466) (xy 349.369289 -240.361514) (xy 349.415563 -240.385092)
			(xy 349.457579 -240.415618) (xy 349.494302 -240.452341) (xy 349.524828 -240.494357) (xy 349.548406 -240.540631)
			(xy 349.564454 -240.590024) (xy 349.572579 -240.641319) (xy 349.573088 -240.667286) (xy 349.572579 -240.693253)
			(xy 349.564454 -240.744548) (xy 349.548406 -240.793941) (xy 349.524828 -240.840215) (xy 349.494302 -240.882231)
			(xy 349.457579 -240.918954) (xy 349.415563 -240.94948) (xy 349.369289 -240.973058) (xy 349.319896 -240.989106)
			(xy 349.268601 -240.997231) (xy 349.216667 -240.997231) (xy 349.165372 -240.989106) (xy 349.115979 -240.973058)
			(xy 349.069705 -240.94948) (xy 349.027689 -240.918954) (xy 348.990966 -240.882231) (xy 348.96044 -240.840215)
			(xy 348.936862 -240.793941) (xy 348.920814 -240.744548) (xy 348.912689 -240.693253) (xy 348.63278 -240.693253)
			(xy 348.63278 -240.693255) (xy 348.624657 -240.744554) (xy 348.60861 -240.79395) (xy 348.585034 -240.840229)
			(xy 348.554509 -240.882249) (xy 348.517786 -240.918977) (xy 348.47577 -240.949509) (xy 348.429495 -240.973092)
			(xy 348.3801 -240.989146) (xy 348.328803 -240.997276) (xy 348.302834 -240.99774) (xy 348.290388 -240.997486)
			(xy 348.276729 -240.997403) (xy 348.250144 -241.003629) (xy 348.226161 -241.01668) (xy 348.206496 -241.035622)
			(xy 348.192556 -241.0591) (xy 348.18534 -241.085434) (xy 348.184978 -241.099086) (xy 348.184978 -241.507069)
			(xy 348.442789 -241.507069) (xy 348.442789 -241.455135) (xy 348.450914 -241.40384) (xy 348.466962 -241.354447)
			(xy 348.49054 -241.308173) (xy 348.521066 -241.266157) (xy 348.557789 -241.229434) (xy 348.599805 -241.198908)
			(xy 348.646079 -241.17533) (xy 348.695472 -241.159282) (xy 348.746767 -241.151157) (xy 348.798701 -241.151157)
			(xy 348.849996 -241.159282) (xy 348.899389 -241.17533) (xy 348.945663 -241.198908) (xy 348.987679 -241.229434)
			(xy 349.024402 -241.266157) (xy 349.054928 -241.308173) (xy 349.078506 -241.354447) (xy 349.094554 -241.40384)
			(xy 349.102679 -241.455135) (xy 349.103188 -241.481102) (xy 349.102679 -241.507069) (xy 349.094554 -241.558364)
			(xy 349.078506 -241.607757) (xy 349.054928 -241.654031) (xy 349.024402 -241.696047) (xy 348.987679 -241.73277)
			(xy 348.945663 -241.763296) (xy 348.899389 -241.786874) (xy 348.849996 -241.802922) (xy 348.798701 -241.811047)
			(xy 348.746767 -241.811047) (xy 348.695472 -241.802922) (xy 348.646079 -241.786874) (xy 348.599805 -241.763296)
			(xy 348.557789 -241.73277) (xy 348.521066 -241.696047) (xy 348.49054 -241.654031) (xy 348.466962 -241.607757)
			(xy 348.450914 -241.558364) (xy 348.442789 -241.507069) (xy 348.184978 -241.507069) (xy 348.184978 -241.863118)
			(xy 348.185417 -241.876762) (xy 348.192643 -241.903077) (xy 348.206575 -241.926542) (xy 348.22622 -241.945483)
			(xy 348.250177 -241.958551) (xy 348.276738 -241.964813) (xy 348.290388 -241.964718) (xy 348.302834 -241.964464)
			(xy 348.328798 -241.964976) (xy 348.380086 -241.973104) (xy 348.429472 -241.989155) (xy 348.475738 -242.012733)
			(xy 348.517747 -242.043258) (xy 348.554464 -242.079979) (xy 348.584985 -242.121991) (xy 348.608558 -242.16826)
			(xy 348.624604 -242.217647) (xy 348.632727 -242.268936) (xy 348.632727 -242.320864) (xy 348.624604 -242.372153)
			(xy 348.608558 -242.42154) (xy 348.584985 -242.467809) (xy 348.554464 -242.509821) (xy 348.517747 -242.546542)
			(xy 348.475738 -242.577067) (xy 348.429472 -242.600645) (xy 348.380086 -242.616696) (xy 348.328798 -242.624824)
			(xy 348.302834 -242.625372) (xy 348.290388 -242.625118) (xy 348.276731 -242.625035) (xy 348.250149 -242.631261)
			(xy 348.226169 -242.644313) (xy 348.206509 -242.663256) (xy 348.192576 -242.686735) (xy 348.185368 -242.713067)
			(xy 348.184978 -242.726718) (xy 348.184978 -243.134955) (xy 348.442535 -243.134955) (xy 348.442535 -243.083021)
			(xy 348.45066 -243.031726) (xy 348.466708 -242.982333) (xy 348.490286 -242.936059) (xy 348.520812 -242.894043)
			(xy 348.557535 -242.85732) (xy 348.599551 -242.826794) (xy 348.645825 -242.803216) (xy 348.695218 -242.787168)
			(xy 348.746513 -242.779043) (xy 348.798447 -242.779043) (xy 348.849742 -242.787168) (xy 348.899135 -242.803216)
			(xy 348.945409 -242.826794) (xy 348.987425 -242.85732) (xy 349.024148 -242.894043) (xy 349.054674 -242.936059)
			(xy 349.078252 -242.982333) (xy 349.0943 -243.031726) (xy 349.102425 -243.083021) (xy 349.102934 -243.108988)
			(xy 349.102425 -243.134955) (xy 349.382335 -243.134955) (xy 349.382335 -243.083021) (xy 349.39046 -243.031726)
			(xy 349.406508 -242.982333) (xy 349.430086 -242.936059) (xy 349.460612 -242.894043) (xy 349.497335 -242.85732)
			(xy 349.539351 -242.826794) (xy 349.585625 -242.803216) (xy 349.635018 -242.787168) (xy 349.686313 -242.779043)
			(xy 349.738247 -242.779043) (xy 349.789542 -242.787168) (xy 349.838935 -242.803216) (xy 349.885209 -242.826794)
			(xy 349.927225 -242.85732) (xy 349.963948 -242.894043) (xy 349.994474 -242.936059) (xy 350.018052 -242.982333)
			(xy 350.0341 -243.031726) (xy 350.042225 -243.083021) (xy 350.042734 -243.108988) (xy 350.042225 -243.134955)
			(xy 350.0341 -243.18625) (xy 350.018052 -243.235643) (xy 349.994474 -243.281917) (xy 349.963948 -243.323933)
			(xy 349.927225 -243.360656) (xy 349.885209 -243.391182) (xy 349.838935 -243.41476) (xy 349.789542 -243.430808)
			(xy 349.738247 -243.438933) (xy 349.686313 -243.438933) (xy 349.635018 -243.430808) (xy 349.585625 -243.41476)
			(xy 349.539351 -243.391182) (xy 349.497335 -243.360656) (xy 349.460612 -243.323933) (xy 349.430086 -243.281917)
			(xy 349.406508 -243.235643) (xy 349.39046 -243.18625) (xy 349.382335 -243.134955) (xy 349.102425 -243.134955)
			(xy 349.0943 -243.18625) (xy 349.078252 -243.235643) (xy 349.054674 -243.281917) (xy 349.024148 -243.323933)
			(xy 348.987425 -243.360656) (xy 348.945409 -243.391182) (xy 348.899135 -243.41476) (xy 348.849742 -243.430808)
			(xy 348.798447 -243.438933) (xy 348.746513 -243.438933) (xy 348.695218 -243.430808) (xy 348.645825 -243.41476)
			(xy 348.599551 -243.391182) (xy 348.557535 -243.360656) (xy 348.520812 -243.323933) (xy 348.490286 -243.281917)
			(xy 348.466708 -243.235643) (xy 348.45066 -243.18625) (xy 348.442535 -243.134955) (xy 348.184978 -243.134955)
			(xy 348.184978 -243.491004) (xy 348.185416 -243.50465) (xy 348.192639 -243.530968) (xy 348.206571 -243.554436)
			(xy 348.226216 -243.57338) (xy 348.250174 -243.58645) (xy 348.276737 -243.592713) (xy 348.290388 -243.592604)
			(xy 348.302834 -243.59235) (xy 348.328799 -243.592862) (xy 348.380089 -243.60099) (xy 348.429477 -243.617042)
			(xy 348.475746 -243.640621) (xy 348.517756 -243.671147) (xy 348.554475 -243.70787) (xy 348.584997 -243.749884)
			(xy 348.608571 -243.796155) (xy 348.624618 -243.845544) (xy 348.632741 -243.896835) (xy 348.632741 -243.948765)
			(xy 348.63274 -243.948771) (xy 348.912435 -243.948771) (xy 348.912435 -243.896837) (xy 348.92056 -243.845542)
			(xy 348.936608 -243.796149) (xy 348.960186 -243.749875) (xy 348.990712 -243.707859) (xy 349.027435 -243.671136)
			(xy 349.069451 -243.64061) (xy 349.115725 -243.617032) (xy 349.165118 -243.600984) (xy 349.216413 -243.592859)
			(xy 349.268347 -243.592859) (xy 349.319642 -243.600984) (xy 349.369035 -243.617032) (xy 349.415309 -243.64061)
			(xy 349.457325 -243.671136) (xy 349.494048 -243.707859) (xy 349.524574 -243.749875) (xy 349.548152 -243.796149)
			(xy 349.5642 -243.845542) (xy 349.572325 -243.896837) (xy 349.572834 -243.922804) (xy 349.572325 -243.948771)
			(xy 349.852489 -243.948771) (xy 349.852489 -243.896837) (xy 349.860614 -243.845542) (xy 349.876662 -243.796149)
			(xy 349.90024 -243.749875) (xy 349.930766 -243.707859) (xy 349.967489 -243.671136) (xy 350.009505 -243.64061)
			(xy 350.055779 -243.617032) (xy 350.105172 -243.600984) (xy 350.156467 -243.592859) (xy 350.208401 -243.592859)
			(xy 350.259696 -243.600984) (xy 350.309089 -243.617032) (xy 350.355363 -243.64061) (xy 350.397379 -243.671136)
			(xy 350.434102 -243.707859) (xy 350.464628 -243.749875) (xy 350.488206 -243.796149) (xy 350.504254 -243.845542)
			(xy 350.512379 -243.896837) (xy 350.512888 -243.922804) (xy 350.512379 -243.948771) (xy 350.504254 -244.000066)
			(xy 350.488206 -244.049459) (xy 350.464628 -244.095733) (xy 350.434102 -244.137749) (xy 350.397379 -244.174472)
			(xy 350.355363 -244.204998) (xy 350.309089 -244.228576) (xy 350.259696 -244.244624) (xy 350.208401 -244.252749)
			(xy 350.156467 -244.252749) (xy 350.105172 -244.244624) (xy 350.055779 -244.228576) (xy 350.009505 -244.204998)
			(xy 349.967489 -244.174472) (xy 349.930766 -244.137749) (xy 349.90024 -244.095733) (xy 349.876662 -244.049459)
			(xy 349.860614 -244.000066) (xy 349.852489 -243.948771) (xy 349.572325 -243.948771) (xy 349.5642 -244.000066)
			(xy 349.548152 -244.049459) (xy 349.524574 -244.095733) (xy 349.494048 -244.137749) (xy 349.457325 -244.174472)
			(xy 349.415309 -244.204998) (xy 349.369035 -244.228576) (xy 349.319642 -244.244624) (xy 349.268347 -244.252749)
			(xy 349.216413 -244.252749) (xy 349.165118 -244.244624) (xy 349.115725 -244.228576) (xy 349.069451 -244.204998)
			(xy 349.027435 -244.174472) (xy 348.990712 -244.137749) (xy 348.960186 -244.095733) (xy 348.936608 -244.049459)
			(xy 348.92056 -244.000066) (xy 348.912435 -243.948771) (xy 348.63274 -243.948771) (xy 348.624618 -244.000056)
			(xy 348.608571 -244.049445) (xy 348.584997 -244.095716) (xy 348.554475 -244.13773) (xy 348.517756 -244.174453)
			(xy 348.475746 -244.204979) (xy 348.429477 -244.228558) (xy 348.380089 -244.24461) (xy 348.328799 -244.252738)
			(xy 348.302834 -244.253258) (xy 348.288215 -244.253123) (xy 348.259089 -244.250576) (xy 348.244668 -244.248178)
			(xy 348.24035 -244.247416) (xy 348.184978 -244.247416) (xy 348.184978 -244.33657) (xy 348.373954 -244.525546)
			(xy 348.384119 -244.535122) (xy 348.408447 -244.548813) (xy 348.435574 -244.555405) (xy 348.463473 -244.554405)
			(xy 348.490058 -244.545888) (xy 348.513344 -244.530491) (xy 348.522798 -244.520212) (xy 348.538574 -244.502657)
			(xy 348.574249 -244.471757) (xy 348.613955 -244.446244) (xy 348.656885 -244.426637) (xy 348.702168 -244.413334)
			(xy 348.748882 -244.406605) (xy 348.77248 -244.406166) (xy 348.79845 -244.406647) (xy 348.84975 -244.41477)
			(xy 348.899148 -244.430818) (xy 348.945427 -244.454397) (xy 348.987447 -244.484926) (xy 349.024174 -244.521653)
			(xy 349.054703 -244.563673) (xy 349.078282 -244.609952) (xy 349.09433 -244.65935) (xy 349.102453 -244.71065)
			(xy 349.102934 -244.73662) (xy 349.102538 -244.760223) (xy 349.102199 -244.762587) (xy 349.382335 -244.762587)
			(xy 349.382335 -244.710653) (xy 349.39046 -244.659358) (xy 349.406508 -244.609965) (xy 349.430086 -244.563691)
			(xy 349.460612 -244.521675) (xy 349.497335 -244.484952) (xy 349.539351 -244.454426) (xy 349.585625 -244.430848)
			(xy 349.635018 -244.4148) (xy 349.686313 -244.406675) (xy 349.738247 -244.406675) (xy 349.789542 -244.4148)
			(xy 349.838935 -244.430848) (xy 349.885209 -244.454426) (xy 349.927225 -244.484952) (xy 349.963948 -244.521675)
			(xy 349.994474 -244.563691) (xy 350.018052 -244.609965) (xy 350.0341 -244.659358) (xy 350.042225 -244.710653)
			(xy 350.042734 -244.73662) (xy 350.042225 -244.762587) (xy 350.0341 -244.813882) (xy 350.018052 -244.863275)
			(xy 349.994474 -244.909549) (xy 349.963948 -244.951565) (xy 349.927225 -244.988288) (xy 349.885209 -245.018814)
			(xy 349.838935 -245.042392) (xy 349.789542 -245.05844) (xy 349.738247 -245.066565) (xy 349.686313 -245.066565)
			(xy 349.635018 -245.05844) (xy 349.585625 -245.042392) (xy 349.539351 -245.018814) (xy 349.497335 -244.988288)
			(xy 349.460612 -244.951565) (xy 349.430086 -244.909549) (xy 349.406508 -244.863275) (xy 349.39046 -244.813882)
			(xy 349.382335 -244.762587) (xy 349.102199 -244.762587) (xy 349.095828 -244.806949) (xy 349.082532 -244.852243)
			(xy 349.062923 -244.895183) (xy 349.0374 -244.934893) (xy 349.006482 -244.970564) (xy 348.988888 -244.986302)
			(xy 348.978583 -244.995742) (xy 348.96314 -245.01902) (xy 348.954596 -245.045617) (xy 348.953593 -245.073535)
			(xy 348.960207 -245.100677) (xy 348.973941 -245.125003) (xy 348.983554 -245.135146) (xy 349.099378 -245.25097)
			(xy 349.129858 -245.240048) (xy 349.157122 -245.230772) (xy 349.21384 -245.220808) (xy 349.242634 -245.220236)
			(xy 349.2686 -245.220748) (xy 349.319891 -245.228876) (xy 349.36928 -245.244928) (xy 349.41555 -245.268507)
			(xy 349.457562 -245.299034) (xy 349.494282 -245.335756) (xy 349.524805 -245.377771) (xy 349.548381 -245.424042)
			(xy 349.564429 -245.473432) (xy 349.572554 -245.524724) (xy 349.573088 -245.55069) (xy 349.572523 -245.576672)
			(xy 349.852419 -245.576672) (xy 349.852419 -245.524728) (xy 349.860545 -245.473424) (xy 349.876598 -245.424023)
			(xy 349.900181 -245.377742) (xy 349.930714 -245.33572) (xy 349.967446 -245.298992) (xy 350.009471 -245.268463)
			(xy 350.055755 -245.244885) (xy 350.105157 -245.228837) (xy 350.156462 -245.220716) (xy 350.182434 -245.220236)
			(xy 350.207904 -245.220693) (xy 350.258244 -245.22847) (xy 350.30679 -245.243896) (xy 350.352387 -245.266604)
			(xy 350.373442 -245.280942) (xy 350.3847 -245.288444) (xy 350.410078 -245.297789) (xy 350.43702 -245.300131)
			(xy 350.46363 -245.295306) (xy 350.488035 -245.283655) (xy 350.508517 -245.265996) (xy 350.523636 -245.243573)
			(xy 350.528382 -245.230904) (xy 350.536056 -245.209436) (xy 350.556509 -245.168691) (xy 350.582366 -245.131142)
			(xy 350.59747 -245.114064) (xy 350.60729 -245.102587) (xy 350.620302 -245.075346) (xy 350.624768 -245.045488)
			(xy 350.620295 -245.015631) (xy 350.607276 -244.988393) (xy 350.59747 -244.976904) (xy 350.581186 -244.958521)
			(xy 350.553723 -244.91781) (xy 350.53259 -244.873482) (xy 350.518253 -244.826513) (xy 350.511028 -244.777939)
			(xy 350.510602 -244.753384) (xy 350.511111 -244.727417) (xy 350.519236 -244.676122) (xy 350.535284 -244.626729)
			(xy 350.558862 -244.580455) (xy 350.589388 -244.538439) (xy 350.626111 -244.501716) (xy 350.668127 -244.47119)
			(xy 350.714401 -244.447612) (xy 350.763794 -244.431564) (xy 350.815089 -244.423439) (xy 350.867023 -244.423439)
			(xy 350.918318 -244.431564) (xy 350.967711 -244.447612) (xy 351.013985 -244.47119) (xy 351.056001 -244.501716)
			(xy 351.092724 -244.538439) (xy 351.12325 -244.580455) (xy 351.146828 -244.626729) (xy 351.162876 -244.676122)
			(xy 351.171001 -244.727417) (xy 351.17151 -244.753384) (xy 351.171095 -244.777937) (xy 351.16385 -244.826505)
			(xy 351.1495 -244.873468) (xy 351.128362 -244.917791) (xy 351.100902 -244.958501) (xy 351.084642 -244.976904)
			(xy 351.074853 -244.988405) (xy 351.061835 -245.015637) (xy 351.057363 -245.045488) (xy 351.061828 -245.07534)
			(xy 351.074839 -245.102576) (xy 351.084642 -245.114064) (xy 351.100896 -245.132472) (xy 351.128367 -245.173175)
			(xy 351.149507 -245.217497) (xy 351.163851 -245.264461) (xy 351.171081 -245.313031) (xy 351.17151 -245.337584)
			(xy 351.171056 -245.363555) (xy 351.162932 -245.414858) (xy 351.146882 -245.464258) (xy 351.1233 -245.510538)
			(xy 351.092769 -245.55256) (xy 351.056038 -245.589287) (xy 351.014015 -245.619815) (xy 350.967732 -245.643393)
			(xy 350.918331 -245.659439) (xy 350.867027 -245.667558) (xy 350.841056 -245.668038) (xy 350.815586 -245.667591)
			(xy 350.765245 -245.659811) (xy 350.716698 -245.644383) (xy 350.671102 -245.621672) (xy 350.650048 -245.607332)
			(xy 350.638818 -245.599781) (xy 350.613431 -245.590428) (xy 350.586477 -245.588084) (xy 350.559856 -245.592913)
			(xy 350.535444 -245.604576) (xy 350.51496 -245.622251) (xy 350.499848 -245.644693) (xy 350.495108 -245.65737)
			(xy 350.486375 -245.681508) (xy 350.462509 -245.72695) (xy 350.431899 -245.768152) (xy 350.395284 -245.804123)
			(xy 350.353543 -245.833995) (xy 350.307684 -245.857049) (xy 350.25881 -245.872731) (xy 350.208098 -245.880662)
			(xy 350.182434 -245.881144) (xy 350.156462 -245.880684) (xy 350.105157 -245.872563) (xy 350.055755 -245.856515)
			(xy 350.009471 -245.832937) (xy 349.967446 -245.802408) (xy 349.930714 -245.76568) (xy 349.900181 -245.723658)
			(xy 349.876598 -245.677377) (xy 349.860545 -245.627976) (xy 349.852419 -245.576672) (xy 349.572523 -245.576672)
			(xy 349.572462 -245.579478) (xy 349.562496 -245.636187) (xy 349.553276 -245.663466) (xy 349.542354 -245.693946)
			(xy 350.465898 -246.61749) (xy 350.465898 -247.007888) (xy 350.472248 -247.019318) (xy 350.485042 -247.043846)
			(xy 350.503166 -247.096111) (xy 350.512337 -247.150663) (xy 350.512888 -247.178322) (xy 350.51235 -247.205982)
			(xy 350.50318 -247.260536) (xy 350.485049 -247.3128) (xy 350.472248 -247.337326) (xy 350.465898 -247.348756)
			(xy 350.465898 -248.279158) (xy 350.466476 -248.2942) (xy 350.475312 -248.322961) (xy 350.492141 -248.347901)
			(xy 350.515505 -248.366858) (xy 350.543378 -248.378188) (xy 350.573341 -248.380909) (xy 350.602799 -248.374785)
			(xy 350.616266 -248.368058) (xy 350.640729 -248.355345) (xy 350.692832 -248.337337) (xy 350.747198 -248.328213)
			(xy 350.774762 -248.327672) (xy 350.800733 -248.328152) (xy 350.852035 -248.336272) (xy 350.901435 -248.352319)
			(xy 350.947716 -248.375897) (xy 350.989738 -248.406426) (xy 351.026466 -248.443153) (xy 351.056996 -248.485174)
			(xy 351.080576 -248.531454) (xy 351.096625 -248.580854) (xy 351.104747 -248.632156) (xy 351.105216 -248.658126)
			(xy 351.104787 -248.682679) (xy 351.097555 -248.731249) (xy 351.083211 -248.778212) (xy 351.06207 -248.822533)
			(xy 351.034598 -248.863235) (xy 351.018348 -248.881646) (xy 351.008546 -248.893134) (xy 350.995537 -248.920369)
			(xy 350.991074 -248.950219) (xy 350.995548 -248.980068) (xy 351.008568 -249.007298) (xy 351.018348 -249.018806)
			(xy 351.034607 -249.037209) (xy 351.062066 -249.077919) (xy 351.083202 -249.122243) (xy 351.09755 -249.169205)
			(xy 351.104794 -249.217773) (xy 351.105216 -249.242326) (xy 351.104731 -249.268293) (xy 351.096603 -249.319587)
			(xy 351.08055 -249.368977) (xy 351.056968 -249.415249) (xy 351.026439 -249.457261) (xy 350.989712 -249.49398)
			(xy 350.947694 -249.524502) (xy 350.901418 -249.548075) (xy 350.852024 -249.564118) (xy 350.800729 -249.572236)
			(xy 350.774762 -249.57278) (xy 350.747503 -249.572219) (xy 350.693727 -249.563266) (xy 350.642148 -249.545607)
			(xy 350.594168 -249.519723) (xy 350.551086 -249.486316) (xy 350.514071 -249.446291) (xy 350.484127 -249.400733)
			(xy 350.462066 -249.350879) (xy 350.454722 -249.324622) (xy 350.450414 -249.30993) (xy 350.43437 -249.283869)
			(xy 350.411333 -249.263723) (xy 350.383365 -249.251297) (xy 350.352973 -249.247704) (xy 350.322879 -249.253266)
			(xy 350.295779 -249.267485) (xy 350.284542 -249.277886) (xy 350.031558 -249.53087) (xy 350.036638 -249.557286)
			(xy 350.039477 -249.572815) (xy 350.042525 -249.604239) (xy 350.042734 -249.620024) (xy 350.04229 -249.644813)
			(xy 350.034884 -249.693834) (xy 350.020242 -249.741199) (xy 349.998692 -249.785848) (xy 349.970718 -249.826779)
			(xy 349.936946 -249.863074) (xy 349.898133 -249.893921) (xy 349.85515 -249.918626) (xy 349.80896 -249.936637)
			(xy 349.760599 -249.947549) (xy 349.735902 -249.949716) (xy 349.726413 -249.950802) (xy 349.709194 -249.959036)
			(xy 349.696165 -249.972983) (xy 349.689121 -249.990721) (xy 349.688658 -250.000262) (xy 349.688658 -251.135134)
			(xy 350.444308 -251.135134) (xy 350.444729 -251.110581) (xy 350.451972 -251.062013) (xy 350.46632 -251.01505)
			(xy 350.487457 -250.970727) (xy 350.514917 -250.930017) (xy 350.531176 -250.911614) (xy 350.540946 -250.900099)
			(xy 350.553964 -250.872871) (xy 350.558438 -250.843025) (xy 350.553978 -250.813177) (xy 350.540974 -250.785943)
			(xy 350.531176 -250.774454) (xy 350.514917 -250.75605) (xy 350.48745 -250.715345) (xy 350.466312 -250.671022)
			(xy 350.451969 -250.624057) (xy 350.444738 -250.575487) (xy 350.444308 -250.550934) (xy 350.444817 -250.524967)
			(xy 350.452942 -250.473672) (xy 350.46899 -250.424279) (xy 350.492568 -250.378005) (xy 350.523094 -250.335989)
			(xy 350.559817 -250.299266) (xy 350.601833 -250.26874) (xy 350.648107 -250.245162) (xy 350.6975 -250.229114)
			(xy 350.748795 -250.220989) (xy 350.800729 -250.220989) (xy 350.852024 -250.229114) (xy 350.901417 -250.245162)
			(xy 350.947691 -250.26874) (xy 350.989707 -250.299266) (xy 351.02643 -250.335989) (xy 351.056956 -250.378005)
			(xy 351.080534 -250.424279) (xy 351.096582 -250.473672) (xy 351.104707 -250.524967) (xy 351.105216 -250.550934)
			(xy 351.10477 -250.575486) (xy 351.097531 -250.624053) (xy 351.083189 -250.671015) (xy 351.062059 -250.715339)
			(xy 351.034604 -250.75605) (xy 351.018348 -250.774454) (xy 351.008509 -250.785916) (xy 350.995496 -250.813163)
			(xy 350.991033 -250.843025) (xy 350.995511 -250.872886) (xy 351.008538 -250.900126) (xy 351.018348 -250.911614)
			(xy 351.034627 -250.930001) (xy 351.062094 -250.97071) (xy 351.08323 -251.015037) (xy 351.097567 -251.062005)
			(xy 351.104791 -251.110579) (xy 351.105216 -251.135134) (xy 351.104707 -251.161101) (xy 351.096582 -251.212396)
			(xy 351.080534 -251.261789) (xy 351.056956 -251.308063) (xy 351.02643 -251.350079) (xy 350.989707 -251.386802)
			(xy 350.947691 -251.417328) (xy 350.901417 -251.440906) (xy 350.852024 -251.456954) (xy 350.800729 -251.465079)
			(xy 350.748795 -251.465079) (xy 350.6975 -251.456954) (xy 350.648107 -251.440906) (xy 350.601833 -251.417328)
			(xy 350.559817 -251.386802) (xy 350.523094 -251.350079) (xy 350.492568 -251.308063) (xy 350.46899 -251.261789)
			(xy 350.452942 -251.212396) (xy 350.444817 -251.161101) (xy 350.444308 -251.135134) (xy 349.688658 -251.135134)
			(xy 349.688658 -252.798834) (xy 350.505268 -252.798834) (xy 350.505699 -252.774282) (xy 350.512942 -252.725714)
			(xy 350.527288 -252.678752) (xy 350.548422 -252.634429) (xy 350.575878 -252.593718) (xy 350.592136 -252.575314)
			(xy 350.60191 -252.5638) (xy 350.614932 -252.536573) (xy 350.619409 -252.506725) (xy 350.614947 -252.476875)
			(xy 350.601938 -252.449641) (xy 350.592136 -252.438154) (xy 350.575887 -252.419742) (xy 350.548416 -252.37904)
			(xy 350.527275 -252.334719) (xy 350.51293 -252.287756) (xy 350.505698 -252.239187) (xy 350.505268 -252.214634)
			(xy 350.505777 -252.188667) (xy 350.513902 -252.137372) (xy 350.52995 -252.087979) (xy 350.553528 -252.041705)
			(xy 350.584054 -251.999689) (xy 350.620777 -251.962966) (xy 350.662793 -251.93244) (xy 350.709067 -251.908862)
			(xy 350.75846 -251.892814) (xy 350.809755 -251.884689) (xy 350.861689 -251.884689) (xy 350.912984 -251.892814)
			(xy 350.962377 -251.908862) (xy 351.008651 -251.93244) (xy 351.050667 -251.962966) (xy 351.08739 -251.999689)
			(xy 351.117916 -252.041705) (xy 351.141494 -252.087979) (xy 351.157542 -252.137372) (xy 351.165667 -252.188667)
			(xy 351.166176 -252.214634) (xy 351.165714 -252.239185) (xy 351.158477 -252.287751) (xy 351.144138 -252.334712)
			(xy 351.123011 -252.379036) (xy 351.095562 -252.419749) (xy 351.079308 -252.438154) (xy 351.069472 -252.449617)
			(xy 351.056465 -252.476864) (xy 351.052003 -252.506725) (xy 351.056479 -252.536584) (xy 351.069501 -252.563824)
			(xy 351.079308 -252.575314) (xy 351.095597 -252.593693) (xy 351.12306 -252.634404) (xy 351.144193 -252.678734)
			(xy 351.158528 -252.725704) (xy 351.165751 -252.774279) (xy 351.166176 -252.798834) (xy 351.165667 -252.824801)
			(xy 351.157542 -252.876096) (xy 351.141494 -252.925489) (xy 351.117916 -252.971763) (xy 351.08739 -253.013779)
			(xy 351.050667 -253.050502) (xy 351.008651 -253.081028) (xy 350.962377 -253.104606) (xy 350.912984 -253.120654)
			(xy 350.861689 -253.128779) (xy 350.809755 -253.128779) (xy 350.75846 -253.120654) (xy 350.709067 -253.104606)
			(xy 350.662793 -253.081028) (xy 350.620777 -253.050502) (xy 350.584054 -253.013779) (xy 350.553528 -252.971763)
			(xy 350.52995 -252.925489) (xy 350.513902 -252.876096) (xy 350.505777 -252.824801) (xy 350.505268 -252.798834)
			(xy 349.688658 -252.798834) (xy 349.688658 -253.801626) (xy 349.691198 -253.809246) (xy 349.699392 -253.83613)
			(xy 349.708197 -253.891636) (xy 349.708724 -253.919736) (xy 349.708256 -253.945703) (xy 349.962471 -253.945703)
			(xy 349.962471 -253.893769) (xy 349.970596 -253.842474) (xy 349.986644 -253.793081) (xy 350.010222 -253.746807)
			(xy 350.040748 -253.704791) (xy 350.077471 -253.668068) (xy 350.119487 -253.637542) (xy 350.165761 -253.613964)
			(xy 350.215154 -253.597916) (xy 350.266449 -253.589791) (xy 350.318383 -253.589791) (xy 350.369678 -253.597916)
			(xy 350.419071 -253.613964) (xy 350.465345 -253.637542) (xy 350.507361 -253.668068) (xy 350.544084 -253.704791)
			(xy 350.57461 -253.746807) (xy 350.598188 -253.793081) (xy 350.614236 -253.842474) (xy 350.622361 -253.893769)
			(xy 350.62287 -253.919736) (xy 350.622361 -253.945703) (xy 350.614236 -253.996998) (xy 350.598188 -254.046391)
			(xy 350.57461 -254.092665) (xy 350.544084 -254.134681) (xy 350.507361 -254.171404) (xy 350.465345 -254.20193)
			(xy 350.419071 -254.225508) (xy 350.369678 -254.241556) (xy 350.318383 -254.249681) (xy 350.266449 -254.249681)
			(xy 350.215154 -254.241556) (xy 350.165761 -254.225508) (xy 350.119487 -254.20193) (xy 350.077471 -254.171404)
			(xy 350.040748 -254.134681) (xy 350.010222 -254.092665) (xy 349.986644 -254.046391) (xy 349.970596 -253.996998)
			(xy 349.962471 -253.945703) (xy 349.708256 -253.945703) (xy 349.708217 -253.947838) (xy 349.699414 -254.003347)
			(xy 349.691198 -254.030226) (xy 349.688658 -254.037846) (xy 349.688658 -254.302768) (xy 349.689103 -254.316727)
			(xy 349.696678 -254.343597) (xy 349.711244 -254.367413) (xy 349.731714 -254.386397) (xy 349.756558 -254.399132)
			(xy 349.783921 -254.404665) (xy 349.797878 -254.404114) (xy 349.822262 -254.403098) (xy 349.848237 -254.403578)
			(xy 349.899548 -254.4117) (xy 349.948957 -254.427748) (xy 349.995247 -254.451329) (xy 350.037277 -254.481862)
			(xy 350.074013 -254.518594) (xy 350.104551 -254.560621) (xy 350.128137 -254.606908) (xy 350.144192 -254.656315)
			(xy 350.152319 -254.707625) (xy 350.152319 -254.759575) (xy 350.144192 -254.810885) (xy 350.128137 -254.860292)
			(xy 350.104551 -254.906579) (xy 350.074013 -254.948606) (xy 350.037277 -254.985338) (xy 349.995247 -255.015871)
			(xy 349.948957 -255.039452) (xy 349.899548 -255.0555) (xy 349.848237 -255.063622) (xy 349.822262 -255.064006)
			(xy 349.794935 -255.06344) (xy 349.741027 -255.054445) (xy 349.689332 -255.036706) (xy 349.641259 -255.010707)
			(xy 349.598116 -254.977156) (xy 349.561079 -254.936965) (xy 349.545656 -254.9144) (xy 349.536947 -254.902073)
			(xy 349.513789 -254.882743) (xy 349.485996 -254.871016) (xy 349.45599 -254.867914) (xy 349.426386 -254.873707)
			(xy 349.399763 -254.887892) (xy 349.388684 -254.898144) (xy 348.797118 -255.48971) (xy 348.797118 -255.573589)
			(xy 349.022671 -255.573589) (xy 349.022671 -255.521655) (xy 349.030796 -255.47036) (xy 349.046844 -255.420967)
			(xy 349.070422 -255.374693) (xy 349.100948 -255.332677) (xy 349.137671 -255.295954) (xy 349.179687 -255.265428)
			(xy 349.225961 -255.24185) (xy 349.275354 -255.225802) (xy 349.326649 -255.217677) (xy 349.378583 -255.217677)
			(xy 349.429878 -255.225802) (xy 349.479271 -255.24185) (xy 349.525545 -255.265428) (xy 349.567561 -255.295954)
			(xy 349.604284 -255.332677) (xy 349.63481 -255.374693) (xy 349.658388 -255.420967) (xy 349.674436 -255.47036)
			(xy 349.682561 -255.521655) (xy 349.68307 -255.547622) (xy 349.682561 -255.573568) (xy 349.962451 -255.573568)
			(xy 349.962451 -255.521632) (xy 349.970576 -255.470334) (xy 349.986626 -255.42094) (xy 350.010205 -255.374664)
			(xy 350.040734 -255.332647) (xy 350.077459 -255.295923) (xy 350.119478 -255.265397) (xy 350.165755 -255.241819)
			(xy 350.21515 -255.225772) (xy 350.266448 -255.21765) (xy 350.292416 -255.217168) (xy 350.322434 -255.217823)
			(xy 350.381478 -255.228686) (xy 350.409764 -255.238758) (xy 350.42366 -255.243467) (xy 350.452903 -255.245652)
			(xy 350.481558 -255.239426) (xy 350.507259 -255.225304) (xy 350.527879 -255.204454) (xy 350.541715 -255.1786)
			(xy 350.545146 -255.164336) (xy 350.550761 -255.13987) (xy 350.568261 -255.092826) (xy 350.592674 -255.048969)
			(xy 350.623439 -255.009309) (xy 350.659847 -254.974758) (xy 350.701062 -254.94611) (xy 350.746136 -254.924024)
			(xy 350.79403 -254.909009) (xy 350.843645 -254.901409) (xy 350.868742 -254.900938) (xy 350.89471 -254.901416)
			(xy 350.946006 -254.909547) (xy 350.995398 -254.925601) (xy 351.041672 -254.949183) (xy 351.083687 -254.979713)
			(xy 351.120409 -255.016439) (xy 351.150935 -255.058457) (xy 351.174512 -255.104733) (xy 351.190561 -255.154127)
			(xy 351.198686 -255.205424) (xy 351.199196 -255.231392) (xy 351.198774 -255.256099) (xy 351.191407 -255.304962)
			(xy 351.176838 -255.352181) (xy 351.155391 -255.396699) (xy 351.127546 -255.437522) (xy 351.111058 -255.455928)
			(xy 351.10111 -255.467423) (xy 351.087909 -255.494791) (xy 351.08334 -255.524831) (xy 351.087809 -255.554886)
			(xy 351.100921 -255.582298) (xy 351.110804 -255.59385) (xy 351.127158 -255.612231) (xy 351.154754 -255.652962)
			(xy 351.176003 -255.697335) (xy 351.190434 -255.74437) (xy 351.197729 -255.793025) (xy 351.19818 -255.817624)
			(xy 351.197667 -255.843591) (xy 351.18954 -255.894884) (xy 351.17349 -255.944275) (xy 351.149911 -255.990547)
			(xy 351.119385 -256.032561) (xy 351.082663 -256.069284) (xy 351.040649 -256.09981) (xy 350.994376 -256.123389)
			(xy 350.944986 -256.139439) (xy 350.893693 -256.147567) (xy 350.867726 -256.148078) (xy 350.841571 -256.147558)
			(xy 350.789911 -256.139334) (xy 350.740193 -256.123071) (xy 350.69366 -256.099176) (xy 350.651473 -256.068246)
			(xy 350.614689 -256.031054) (xy 350.584225 -255.988529) (xy 350.560844 -255.941735) (xy 350.552512 -255.916938)
			(xy 350.547793 -255.903761) (xy 350.5324 -255.880402) (xy 350.511241 -255.862102) (xy 350.485907 -255.850235)
			(xy 350.458303 -255.845695) (xy 350.430503 -255.848821) (xy 350.417384 -255.853692) (xy 350.387398 -255.865052)
			(xy 350.324473 -255.877338) (xy 350.292416 -255.878076) (xy 350.266448 -255.87755) (xy 350.21515 -255.869428)
			(xy 350.165755 -255.853381) (xy 350.119478 -255.829803) (xy 350.077459 -255.799277) (xy 350.040734 -255.762553)
			(xy 350.010205 -255.720536) (xy 349.986626 -255.67426) (xy 349.970576 -255.624866) (xy 349.962451 -255.573568)
			(xy 349.682561 -255.573568) (xy 349.682561 -255.573589) (xy 349.674436 -255.624884) (xy 349.658388 -255.674277)
			(xy 349.63481 -255.720551) (xy 349.604284 -255.762567) (xy 349.567561 -255.79929) (xy 349.525545 -255.829816)
			(xy 349.479271 -255.853394) (xy 349.429878 -255.869442) (xy 349.378583 -255.877567) (xy 349.326649 -255.877567)
			(xy 349.275354 -255.869442) (xy 349.225961 -255.853394) (xy 349.179687 -255.829816) (xy 349.137671 -255.79929)
			(xy 349.100948 -255.762567) (xy 349.070422 -255.720551) (xy 349.046844 -255.674277) (xy 349.030796 -255.624884)
			(xy 349.022671 -255.573589) (xy 348.797118 -255.573589) (xy 348.797118 -255.929638) (xy 348.797689 -255.945253)
			(xy 348.807121 -255.975024) (xy 348.825094 -256.000564) (xy 348.849934 -256.019492) (xy 348.879327 -256.030045)
			(xy 348.894908 -256.031238) (xy 348.920226 -256.032636) (xy 348.970015 -256.042229) (xy 349.017754 -256.059317)
			(xy 349.062322 -256.083497) (xy 349.102672 -256.114203) (xy 349.137857 -256.150713) (xy 349.167051 -256.192171)
			(xy 349.189568 -256.237602) (xy 349.204879 -256.285939) (xy 349.212626 -256.336049) (xy 349.212626 -256.386754)
			(xy 349.212525 -256.387405) (xy 349.492317 -256.387405) (xy 349.492317 -256.335471) (xy 349.500442 -256.284176)
			(xy 349.51649 -256.234783) (xy 349.540068 -256.188509) (xy 349.570594 -256.146493) (xy 349.607317 -256.10977)
			(xy 349.649333 -256.079244) (xy 349.695607 -256.055666) (xy 349.745 -256.039618) (xy 349.796295 -256.031493)
			(xy 349.848229 -256.031493) (xy 349.899524 -256.039618) (xy 349.948917 -256.055666) (xy 349.995191 -256.079244)
			(xy 350.037207 -256.10977) (xy 350.07393 -256.146493) (xy 350.104456 -256.188509) (xy 350.128034 -256.234783)
			(xy 350.144082 -256.284176) (xy 350.152207 -256.335471) (xy 350.152716 -256.361438) (xy 350.152207 -256.387405)
			(xy 350.144082 -256.4387) (xy 350.128034 -256.488093) (xy 350.104456 -256.534367) (xy 350.07393 -256.576383)
			(xy 350.037207 -256.613106) (xy 349.995191 -256.643632) (xy 349.948917 -256.66721) (xy 349.899524 -256.683258)
			(xy 349.848229 -256.691383) (xy 349.796295 -256.691383) (xy 349.745 -256.683258) (xy 349.695607 -256.66721)
			(xy 349.649333 -256.643632) (xy 349.607317 -256.613106) (xy 349.570594 -256.576383) (xy 349.540068 -256.534367)
			(xy 349.51649 -256.488093) (xy 349.500442 -256.4387) (xy 349.492317 -256.387405) (xy 349.212525 -256.387405)
			(xy 349.204879 -256.436863) (xy 349.189567 -256.485201) (xy 349.167049 -256.530632) (xy 349.137855 -256.572089)
			(xy 349.10267 -256.608599) (xy 349.062319 -256.639304) (xy 349.017751 -256.663484) (xy 348.970012 -256.680571)
			(xy 348.920223 -256.690164) (xy 348.894908 -256.691638) (xy 348.879321 -256.692789) (xy 348.849917 -256.703333)
			(xy 348.825073 -256.72227) (xy 348.807112 -256.747828) (xy 348.797714 -256.777618) (xy 348.797118 -256.793238)
			(xy 348.797118 -257.201221) (xy 349.022671 -257.201221) (xy 349.022671 -257.149287) (xy 349.030796 -257.097992)
			(xy 349.046844 -257.048599) (xy 349.070422 -257.002325) (xy 349.100948 -256.960309) (xy 349.137671 -256.923586)
			(xy 349.179687 -256.89306) (xy 349.225961 -256.869482) (xy 349.275354 -256.853434) (xy 349.326649 -256.845309)
			(xy 349.378583 -256.845309) (xy 349.429878 -256.853434) (xy 349.479271 -256.869482) (xy 349.525545 -256.89306)
			(xy 349.567561 -256.923586) (xy 349.604284 -256.960309) (xy 349.63481 -257.002325) (xy 349.658388 -257.048599)
			(xy 349.674436 -257.097992) (xy 349.682561 -257.149287) (xy 349.68307 -257.175254) (xy 349.682561 -257.201221)
			(xy 349.962471 -257.201221) (xy 349.962471 -257.149287) (xy 349.970596 -257.097992) (xy 349.986644 -257.048599)
			(xy 350.010222 -257.002325) (xy 350.040748 -256.960309) (xy 350.077471 -256.923586) (xy 350.119487 -256.89306)
			(xy 350.165761 -256.869482) (xy 350.215154 -256.853434) (xy 350.266449 -256.845309) (xy 350.318383 -256.845309)
			(xy 350.369678 -256.853434) (xy 350.419071 -256.869482) (xy 350.465345 -256.89306) (xy 350.507361 -256.923586)
			(xy 350.544084 -256.960309) (xy 350.57461 -257.002325) (xy 350.598188 -257.048599) (xy 350.614236 -257.097992)
			(xy 350.622361 -257.149287) (xy 350.62287 -257.175254) (xy 350.622361 -257.201221) (xy 350.614236 -257.252516)
			(xy 350.598188 -257.301909) (xy 350.57461 -257.348183) (xy 350.544084 -257.390199) (xy 350.507361 -257.426922)
			(xy 350.465345 -257.457448) (xy 350.419071 -257.481026) (xy 350.369678 -257.497074) (xy 350.318383 -257.505199)
			(xy 350.266449 -257.505199) (xy 350.215154 -257.497074) (xy 350.165761 -257.481026) (xy 350.119487 -257.457448)
			(xy 350.077471 -257.426922) (xy 350.040748 -257.390199) (xy 350.010222 -257.348183) (xy 349.986644 -257.301909)
			(xy 349.970596 -257.252516) (xy 349.962471 -257.201221) (xy 349.682561 -257.201221) (xy 349.674436 -257.252516)
			(xy 349.658388 -257.301909) (xy 349.63481 -257.348183) (xy 349.604284 -257.390199) (xy 349.567561 -257.426922)
			(xy 349.525545 -257.457448) (xy 349.479271 -257.481026) (xy 349.429878 -257.497074) (xy 349.378583 -257.505199)
			(xy 349.326649 -257.505199) (xy 349.275354 -257.497074) (xy 349.225961 -257.481026) (xy 349.179687 -257.457448)
			(xy 349.137671 -257.426922) (xy 349.100948 -257.390199) (xy 349.070422 -257.348183) (xy 349.046844 -257.301909)
			(xy 349.030796 -257.252516) (xy 349.022671 -257.201221) (xy 348.797118 -257.201221) (xy 348.797118 -257.55727)
			(xy 348.797693 -257.572882) (xy 348.807131 -257.602645) (xy 348.825106 -257.628176) (xy 348.849944 -257.647097)
			(xy 348.879331 -257.657646) (xy 348.894908 -257.65887) (xy 348.920221 -257.660283) (xy 348.969997 -257.669901)
			(xy 349.01772 -257.687008) (xy 349.06227 -257.711203) (xy 349.102602 -257.741918) (xy 349.137771 -257.778433)
			(xy 349.16695 -257.81989) (xy 349.189456 -257.865317) (xy 349.204759 -257.913649) (xy 349.212502 -257.963751)
			(xy 349.212502 -258.014447) (xy 349.212411 -258.015037) (xy 349.492317 -258.015037) (xy 349.492317 -257.963103)
			(xy 349.500442 -257.911808) (xy 349.51649 -257.862415) (xy 349.540068 -257.816141) (xy 349.570594 -257.774125)
			(xy 349.607317 -257.737402) (xy 349.649333 -257.706876) (xy 349.695607 -257.683298) (xy 349.745 -257.66725)
			(xy 349.796295 -257.659125) (xy 349.848229 -257.659125) (xy 349.899524 -257.66725) (xy 349.948917 -257.683298)
			(xy 349.995191 -257.706876) (xy 350.037207 -257.737402) (xy 350.07393 -257.774125) (xy 350.104456 -257.816141)
			(xy 350.128034 -257.862415) (xy 350.144082 -257.911808) (xy 350.152207 -257.963103) (xy 350.152716 -257.98907)
			(xy 350.152207 -258.015037) (xy 350.144082 -258.066332) (xy 350.128034 -258.115725) (xy 350.104456 -258.161999)
			(xy 350.07393 -258.204015) (xy 350.037207 -258.240738) (xy 349.995191 -258.271264) (xy 349.948917 -258.294842)
			(xy 349.899524 -258.31089) (xy 349.848229 -258.319015) (xy 349.796295 -258.319015) (xy 349.745 -258.31089)
			(xy 349.695607 -258.294842) (xy 349.649333 -258.271264) (xy 349.607317 -258.240738) (xy 349.570594 -258.204015)
			(xy 349.540068 -258.161999) (xy 349.51649 -258.115725) (xy 349.500442 -258.066332) (xy 349.492317 -258.015037)
			(xy 349.212411 -258.015037) (xy 349.20476 -258.064549) (xy 349.189456 -258.11288) (xy 349.166951 -258.158308)
			(xy 349.137772 -258.199765) (xy 349.102604 -258.23628) (xy 349.062272 -258.266996) (xy 349.017722 -258.291191)
			(xy 348.969999 -258.308299) (xy 348.920223 -258.317917) (xy 348.894908 -258.31927) (xy 348.879323 -258.320422)
			(xy 348.849923 -258.330967) (xy 348.825085 -258.349904) (xy 348.807131 -258.375463) (xy 348.797742 -258.405252)
			(xy 348.797118 -258.42087) (xy 348.797118 -258.829107) (xy 349.022417 -258.829107) (xy 349.022417 -258.777173)
			(xy 349.030542 -258.725878) (xy 349.04659 -258.676485) (xy 349.070168 -258.630211) (xy 349.100694 -258.588195)
			(xy 349.137417 -258.551472) (xy 349.179433 -258.520946) (xy 349.225707 -258.497368) (xy 349.2751 -258.48132)
			(xy 349.326395 -258.473195) (xy 349.378329 -258.473195) (xy 349.429624 -258.48132) (xy 349.479017 -258.497368)
			(xy 349.525291 -258.520946) (xy 349.567307 -258.551472) (xy 349.60403 -258.588195) (xy 349.634556 -258.630211)
			(xy 349.658134 -258.676485) (xy 349.674182 -258.725878) (xy 349.682307 -258.777173) (xy 349.682816 -258.80314)
			(xy 349.682307 -258.829107) (xy 349.674182 -258.880402) (xy 349.658134 -258.929795) (xy 349.634556 -258.976069)
			(xy 349.60403 -259.018085) (xy 349.567307 -259.054808) (xy 349.525291 -259.085334) (xy 349.479017 -259.108912)
			(xy 349.429624 -259.12496) (xy 349.378329 -259.133085) (xy 349.326395 -259.133085) (xy 349.2751 -259.12496)
			(xy 349.225707 -259.108912) (xy 349.179433 -259.085334) (xy 349.137417 -259.054808) (xy 349.100694 -259.018085)
			(xy 349.070168 -258.976069) (xy 349.04659 -258.929795) (xy 349.030542 -258.880402) (xy 349.022417 -258.829107)
			(xy 348.797118 -258.829107) (xy 348.797118 -259.185156) (xy 348.797691 -259.200769) (xy 348.807126 -259.230536)
			(xy 348.825101 -259.256071) (xy 348.84994 -259.274995) (xy 348.87933 -259.285546) (xy 348.894908 -259.286756)
			(xy 348.920222 -259.288169) (xy 348.97 -259.297787) (xy 349.017725 -259.314895) (xy 349.062277 -259.339091)
			(xy 349.102611 -259.369808) (xy 349.137781 -259.406324) (xy 349.166962 -259.447783) (xy 349.189468 -259.493212)
			(xy 349.204773 -259.541545) (xy 349.212516 -259.591649) (xy 349.212516 -259.642348) (xy 349.204773 -259.692452)
			(xy 349.195283 -259.722425) (xy 350.476567 -259.722425) (xy 350.476567 -259.670491) (xy 350.484692 -259.619196)
			(xy 350.50074 -259.569803) (xy 350.524318 -259.523529) (xy 350.554844 -259.481513) (xy 350.591567 -259.44479)
			(xy 350.633583 -259.414264) (xy 350.679857 -259.390686) (xy 350.72925 -259.374638) (xy 350.780545 -259.366513)
			(xy 350.832479 -259.366513) (xy 350.883774 -259.374638) (xy 350.933167 -259.390686) (xy 350.979441 -259.414264)
			(xy 351.021457 -259.44479) (xy 351.05818 -259.481513) (xy 351.088706 -259.523529) (xy 351.112284 -259.569803)
			(xy 351.128332 -259.619196) (xy 351.136457 -259.670491) (xy 351.136966 -259.696458) (xy 351.136457 -259.722425)
			(xy 351.128332 -259.77372) (xy 351.112284 -259.823113) (xy 351.088706 -259.869387) (xy 351.05818 -259.911403)
			(xy 351.021457 -259.948126) (xy 350.979441 -259.978652) (xy 350.933167 -260.00223) (xy 350.883774 -260.018278)
			(xy 350.832479 -260.026403) (xy 350.780545 -260.026403) (xy 350.72925 -260.018278) (xy 350.679857 -260.00223)
			(xy 350.633583 -259.978652) (xy 350.591567 -259.948126) (xy 350.554844 -259.911403) (xy 350.524318 -259.869387)
			(xy 350.50074 -259.823113) (xy 350.484692 -259.77372) (xy 350.476567 -259.722425) (xy 349.195283 -259.722425)
			(xy 349.18947 -259.740785) (xy 349.166964 -259.786215) (xy 349.137783 -259.827674) (xy 349.102614 -259.86419)
			(xy 349.06228 -259.894907) (xy 349.017728 -259.919103) (xy 348.970003 -259.936212) (xy 348.920225 -259.945831)
			(xy 348.894908 -259.947156) (xy 348.879322 -259.948307) (xy 348.84992 -259.958852) (xy 348.82508 -259.977789)
			(xy 348.807123 -260.003348) (xy 348.79773 -260.033137) (xy 348.797118 -260.048756) (xy 348.797118 -260.48335)
			(xy 349.373698 -261.05993)
		)
		(stroke
			(width 0)
			(type solid)
		)
		(fill yes)
		(layer "In6.Cu")
		(net "PVCCD_HV_CPU0")
	)
	(gr_poly
		(pts
			(xy 101.557074 -261.185914) (xy 101.562102 -261.160852) (xy 101.578854 -261.112561) (xy 101.602843 -261.067426)
			(xy 101.633496 -261.026524) (xy 101.670083 -260.99083) (xy 101.71173 -260.961195) (xy 101.757443 -260.938328)
			(xy 101.806133 -260.922773) (xy 101.856637 -260.914902) (xy 101.907751 -260.914902) (xy 101.958255 -260.922773)
			(xy 102.006945 -260.938328) (xy 102.052658 -260.961195) (xy 102.094305 -260.99083) (xy 102.130892 -261.026524)
			(xy 102.161545 -261.067426) (xy 102.185534 -261.112561) (xy 102.202286 -261.160852) (xy 102.207314 -261.185914)
			(xy 102.214934 -261.22757) (xy 102.572058 -261.22757) (xy 102.587207 -261.227007) (xy 102.61617 -261.218111)
			(xy 102.641255 -261.201117) (xy 102.660258 -261.177518) (xy 102.67151 -261.149386) (xy 102.674024 -261.119192)
			(xy 102.667578 -261.089587) (xy 102.652739 -261.06317) (xy 102.642162 -261.05231) (xy 102.623031 -261.033465)
			(xy 102.590536 -260.990715) (xy 102.565391 -260.943269) (xy 102.548259 -260.892377) (xy 102.539592 -260.839383)
			(xy 102.539038 -260.812534) (xy 102.539547 -260.786567) (xy 102.547672 -260.735272) (xy 102.56372 -260.685879)
			(xy 102.587298 -260.639605) (xy 102.617824 -260.597589) (xy 102.654547 -260.560866) (xy 102.696563 -260.53034)
			(xy 102.742837 -260.506762) (xy 102.79223 -260.490714) (xy 102.843525 -260.482589) (xy 102.895459 -260.482589)
			(xy 102.946754 -260.490714) (xy 102.996147 -260.506762) (xy 103.042421 -260.53034) (xy 103.084437 -260.560866)
			(xy 103.12116 -260.597589) (xy 103.151686 -260.639605) (xy 103.175264 -260.685879) (xy 103.191312 -260.735272)
			(xy 103.199437 -260.786567) (xy 103.199946 -260.812534) (xy 103.199946 -260.815836) (xy 103.200372 -260.830885)
			(xy 103.208916 -260.859738) (xy 103.22549 -260.884853) (xy 103.248659 -260.904055) (xy 103.276414 -260.91568)
			(xy 103.306351 -260.91872) (xy 103.335877 -260.912913) (xy 103.362432 -260.898762) (xy 103.373428 -260.88848)
			(xy 103.532178 -260.72973) (xy 103.532178 -258.124198) (xy 103.531744 -258.110258) (xy 103.524202 -258.083417)
			(xy 103.50968 -258.059617) (xy 103.489261 -258.040633) (xy 103.464468 -258.02788) (xy 103.43715 -258.02231)
			(xy 103.423212 -258.022852) (xy 103.39959 -258.023614) (xy 103.373626 -258.023104) (xy 103.322339 -258.01498)
			(xy 103.272954 -257.998932) (xy 103.226687 -257.975357) (xy 103.184677 -257.944834) (xy 103.14796 -257.908115)
			(xy 103.117438 -257.866105) (xy 103.093864 -257.819837) (xy 103.077818 -257.770451) (xy 103.069695 -257.719164)
			(xy 103.069695 -257.667236) (xy 103.077818 -257.615949) (xy 103.093864 -257.566563) (xy 103.117438 -257.520295)
			(xy 103.14796 -257.478285) (xy 103.184677 -257.441566) (xy 103.226687 -257.411043) (xy 103.272954 -257.387468)
			(xy 103.322339 -257.37142) (xy 103.373626 -257.363296) (xy 103.39959 -257.362706) (xy 103.423212 -257.363468)
			(xy 103.437153 -257.364049) (xy 103.464484 -257.358476) (xy 103.489288 -257.345719) (xy 103.509718 -257.326729)
			(xy 103.52425 -257.30292) (xy 103.5318 -257.276068) (xy 103.532178 -257.262122) (xy 103.532178 -250.26239)
			(xy 104.893618 -248.90095) (xy 104.893618 -245.01729) (xy 103.290878 -243.41455) (xy 103.290878 -241.255804)
			(xy 103.290364 -241.241291) (xy 103.282197 -241.213437) (xy 103.266521 -241.189007) (xy 103.244605 -241.169975)
			(xy 103.218218 -241.15788) (xy 103.189494 -241.1537) (xy 103.160754 -241.157771) (xy 103.134321 -241.169766)
			(xy 103.122984 -241.178842) (xy 103.104879 -241.193942) (xy 103.065198 -241.219395) (xy 103.022304 -241.238953)
			(xy 102.977065 -241.252217) (xy 102.930401 -241.258919) (xy 102.90683 -241.25936) (xy 102.880859 -241.258879)
			(xy 102.829556 -241.250758) (xy 102.780155 -241.234711) (xy 102.733873 -241.211133) (xy 102.691849 -241.180605)
			(xy 102.655118 -241.143878) (xy 102.624586 -241.101858) (xy 102.601003 -241.055578) (xy 102.58495 -241.006179)
			(xy 102.576823 -240.954877) (xy 102.576376 -240.928906) (xy 102.576803 -240.904352) (xy 102.58403 -240.85578)
			(xy 102.598371 -240.808814) (xy 102.619508 -240.764489) (xy 102.646977 -240.723783) (xy 102.663244 -240.705386)
			(xy 102.673051 -240.693898) (xy 102.686071 -240.666661) (xy 102.690542 -240.636804) (xy 102.686073 -240.606948)
			(xy 102.673056 -240.579709) (xy 102.663244 -240.568226) (xy 102.646989 -240.549821) (xy 102.61954 -240.509109)
			(xy 102.598413 -240.464785) (xy 102.584075 -240.417823) (xy 102.576841 -240.369257) (xy 102.576376 -240.344706)
			(xy 102.576858 -240.318737) (xy 102.584983 -240.267439) (xy 102.601033 -240.218044) (xy 102.624612 -240.171767)
			(xy 102.655142 -240.12975) (xy 102.691868 -240.093026) (xy 102.733888 -240.0625) (xy 102.780166 -240.038923)
			(xy 102.829563 -240.022877) (xy 102.880861 -240.014757) (xy 102.90683 -240.014252) (xy 102.930404 -240.014666)
			(xy 102.977075 -240.02136) (xy 103.022319 -240.034621) (xy 103.065219 -240.05418) (xy 103.104902 -240.07964)
			(xy 103.122984 -240.09477) (xy 103.134316 -240.103855) (xy 103.160752 -240.115849) (xy 103.189495 -240.119921)
			(xy 103.218223 -240.115739) (xy 103.244613 -240.103644) (xy 103.266533 -240.084611) (xy 103.282212 -240.060179)
			(xy 103.290383 -240.032323) (xy 103.290878 -240.017808) (xy 103.290878 -239.91189) (xy 103.059738 -239.68075)
			(xy 102.198678 -239.68075) (xy 102.183948 -239.681259) (xy 102.155719 -239.689687) (xy 102.13106 -239.705808)
			(xy 102.112017 -239.728287) (xy 102.100168 -239.755259) (xy 102.096495 -239.78449) (xy 102.098348 -239.799114)
			(xy 102.100472 -239.812539) (xy 102.102759 -239.839625) (xy 102.10292 -239.853216) (xy 102.102411 -239.879183)
			(xy 102.094286 -239.930478) (xy 102.078238 -239.979871) (xy 102.05466 -240.026145) (xy 102.024134 -240.068161)
			(xy 101.987411 -240.104884) (xy 101.945395 -240.13541) (xy 101.899121 -240.158988) (xy 101.849728 -240.175036)
			(xy 101.798433 -240.183161) (xy 101.746499 -240.183161) (xy 101.695204 -240.175036) (xy 101.645811 -240.158988)
			(xy 101.599537 -240.13541) (xy 101.557521 -240.104884) (xy 101.520798 -240.068161) (xy 101.490272 -240.026145)
			(xy 101.466694 -239.979871) (xy 101.450646 -239.930478) (xy 101.442521 -239.879183) (xy 101.442012 -239.853216)
			(xy 101.442184 -239.839626) (xy 101.444474 -239.812541) (xy 101.446584 -239.799114) (xy 101.448535 -239.784487)
			(xy 101.444902 -239.755214) (xy 101.433057 -239.728199) (xy 101.413988 -239.705695) (xy 101.389283 -239.689578)
			(xy 101.361003 -239.68119) (xy 101.346254 -239.68075) (xy 101.258624 -239.68075) (xy 101.24389 -239.681253)
			(xy 101.215649 -239.689673) (xy 101.190978 -239.705792) (xy 101.171925 -239.728274) (xy 101.16007 -239.755254)
			(xy 101.156395 -239.784493) (xy 101.158294 -239.799114) (xy 101.160417 -239.812539) (xy 101.162704 -239.839625)
			(xy 101.162866 -239.853216) (xy 101.162356 -239.879183) (xy 101.154229 -239.930477) (xy 101.138179 -239.979868)
			(xy 101.114601 -240.02614) (xy 101.084075 -240.068155) (xy 101.047352 -240.104877) (xy 101.005337 -240.135403)
			(xy 100.959064 -240.158981) (xy 100.909673 -240.17503) (xy 100.858379 -240.183156) (xy 100.832412 -240.18367)
			(xy 100.808227 -240.183249) (xy 100.760373 -240.176197) (xy 100.71406 -240.162243) (xy 100.670276 -240.141685)
			(xy 100.629957 -240.114963) (xy 100.593966 -240.082647) (xy 100.563072 -240.045428) (xy 100.537936 -240.004102)
			(xy 100.52812 -239.981994) (xy 100.52217 -239.969026) (xy 100.504302 -239.946798) (xy 100.48098 -239.930383)
			(xy 100.454026 -239.921066) (xy 100.425545 -239.919574) (xy 100.397765 -239.926023) (xy 100.372855 -239.939911)
			(xy 100.362512 -239.949736) (xy 100.202238 -240.11001) (xy 100.202238 -240.239296) (xy 100.202749 -240.253787)
			(xy 100.210893 -240.281602) (xy 100.226526 -240.306007) (xy 100.248387 -240.325035) (xy 100.274714 -240.337153)
			(xy 100.303386 -240.341383) (xy 100.317808 -240.33988) (xy 100.328993 -240.338452) (xy 100.351491 -240.336929)
			(xy 100.362766 -240.336832) (xy 100.388738 -240.337312) (xy 100.440044 -240.345433) (xy 100.489447 -240.361481)
			(xy 100.535731 -240.38506) (xy 100.577757 -240.415589) (xy 100.614489 -240.452317) (xy 100.645022 -240.49434)
			(xy 100.668606 -240.540622) (xy 100.684659 -240.590023) (xy 100.692785 -240.641328) (xy 100.692785 -240.693253)
			(xy 100.972621 -240.693253) (xy 100.972621 -240.641319) (xy 100.980746 -240.590024) (xy 100.996794 -240.540631)
			(xy 101.020372 -240.494357) (xy 101.050898 -240.452341) (xy 101.087621 -240.415618) (xy 101.129637 -240.385092)
			(xy 101.175911 -240.361514) (xy 101.225304 -240.345466) (xy 101.276599 -240.337341) (xy 101.328533 -240.337341)
			(xy 101.379828 -240.345466) (xy 101.429221 -240.361514) (xy 101.475495 -240.385092) (xy 101.517511 -240.415618)
			(xy 101.554234 -240.452341) (xy 101.58476 -240.494357) (xy 101.608338 -240.540631) (xy 101.624386 -240.590024)
			(xy 101.632511 -240.641319) (xy 101.63302 -240.667286) (xy 101.632511 -240.693253) (xy 101.624386 -240.744548)
			(xy 101.608338 -240.793941) (xy 101.58476 -240.840215) (xy 101.554234 -240.882231) (xy 101.517511 -240.918954)
			(xy 101.475495 -240.94948) (xy 101.429221 -240.973058) (xy 101.379828 -240.989106) (xy 101.328533 -240.997231)
			(xy 101.276599 -240.997231) (xy 101.225304 -240.989106) (xy 101.175911 -240.973058) (xy 101.129637 -240.94948)
			(xy 101.087621 -240.918954) (xy 101.050898 -240.882231) (xy 101.020372 -240.840215) (xy 100.996794 -240.793941)
			(xy 100.980746 -240.744548) (xy 100.972621 -240.693253) (xy 100.692785 -240.693253) (xy 100.692785 -240.693272)
			(xy 100.684659 -240.744577) (xy 100.668606 -240.793978) (xy 100.645022 -240.84026) (xy 100.614489 -240.882283)
			(xy 100.577757 -240.919011) (xy 100.535731 -240.94954) (xy 100.489447 -240.973119) (xy 100.440044 -240.989167)
			(xy 100.388738 -240.997288) (xy 100.362766 -240.99774) (xy 100.35149 -240.997657) (xy 100.328991 -240.996135)
			(xy 100.317808 -240.994692) (xy 100.303389 -240.993215) (xy 100.274732 -240.997465) (xy 100.248419 -241.009587)
			(xy 100.226565 -241.028606) (xy 100.210928 -241.052995) (xy 100.202763 -241.080791) (xy 100.202238 -241.095276)
			(xy 100.202238 -241.365278) (xy 100.205032 -241.373406) (xy 100.213456 -241.399529) (xy 100.222516 -241.45366)
			(xy 100.222515 -241.507069) (xy 100.502721 -241.507069) (xy 100.502721 -241.455135) (xy 100.510846 -241.40384)
			(xy 100.526894 -241.354447) (xy 100.550472 -241.308173) (xy 100.580998 -241.266157) (xy 100.617721 -241.229434)
			(xy 100.659737 -241.198908) (xy 100.706011 -241.17533) (xy 100.755404 -241.159282) (xy 100.806699 -241.151157)
			(xy 100.858633 -241.151157) (xy 100.909928 -241.159282) (xy 100.959321 -241.17533) (xy 101.005595 -241.198908)
			(xy 101.047611 -241.229434) (xy 101.084334 -241.266157) (xy 101.11486 -241.308173) (xy 101.138438 -241.354447)
			(xy 101.154486 -241.40384) (xy 101.162611 -241.455135) (xy 101.16312 -241.481102) (xy 101.162611 -241.507069)
			(xy 101.154486 -241.558364) (xy 101.138438 -241.607757) (xy 101.11486 -241.654031) (xy 101.084334 -241.696047)
			(xy 101.047611 -241.73277) (xy 101.005595 -241.763296) (xy 100.959321 -241.786874) (xy 100.909928 -241.802922)
			(xy 100.858633 -241.811047) (xy 100.806699 -241.811047) (xy 100.755404 -241.802922) (xy 100.706011 -241.786874)
			(xy 100.659737 -241.763296) (xy 100.617721 -241.73277) (xy 100.580998 -241.696047) (xy 100.550472 -241.654031)
			(xy 100.526894 -241.607757) (xy 100.510846 -241.558364) (xy 100.502721 -241.507069) (xy 100.222515 -241.507069)
			(xy 100.222515 -241.508544) (xy 100.213455 -241.562675) (xy 100.205032 -241.588798) (xy 100.202238 -241.596926)
			(xy 100.202238 -241.866928) (xy 100.20274 -241.881426) (xy 100.210873 -241.909257) (xy 100.226502 -241.93368)
			(xy 100.248367 -241.952723) (xy 100.274705 -241.96485) (xy 100.303389 -241.969083) (xy 100.317808 -241.967512)
			(xy 100.328993 -241.966084) (xy 100.351491 -241.964561) (xy 100.362766 -241.964464) (xy 100.388736 -241.964944)
			(xy 100.440036 -241.973065) (xy 100.489434 -241.989111) (xy 100.535714 -242.012687) (xy 100.577736 -242.043214)
			(xy 100.614464 -242.079938) (xy 100.644995 -242.121957) (xy 100.668576 -242.168234) (xy 100.684627 -242.217631)
			(xy 100.692753 -242.26893) (xy 100.692753 -242.32087) (xy 100.684627 -242.372169) (xy 100.668576 -242.421566)
			(xy 100.644995 -242.467843) (xy 100.614464 -242.509862) (xy 100.577736 -242.546586) (xy 100.535714 -242.577113)
			(xy 100.489434 -242.600689) (xy 100.440036 -242.616735) (xy 100.388736 -242.624856) (xy 100.362766 -242.625372)
			(xy 100.35149 -242.625289) (xy 100.328991 -242.623767) (xy 100.317808 -242.622324) (xy 100.303391 -242.620847)
			(xy 100.274736 -242.625097) (xy 100.248427 -242.637219) (xy 100.226578 -242.65624) (xy 100.210947 -242.680629)
			(xy 100.202791 -242.708425) (xy 100.202238 -242.722908) (xy 100.202238 -242.993164) (xy 100.205032 -243.001292)
			(xy 100.213457 -243.027415) (xy 100.222519 -243.081546) (xy 100.222521 -243.134955) (xy 100.502467 -243.134955)
			(xy 100.502467 -243.083021) (xy 100.510592 -243.031726) (xy 100.52664 -242.982333) (xy 100.550218 -242.936059)
			(xy 100.580744 -242.894043) (xy 100.617467 -242.85732) (xy 100.659483 -242.826794) (xy 100.705757 -242.803216)
			(xy 100.75515 -242.787168) (xy 100.806445 -242.779043) (xy 100.858379 -242.779043) (xy 100.909674 -242.787168)
			(xy 100.959067 -242.803216) (xy 101.005341 -242.826794) (xy 101.047357 -242.85732) (xy 101.08408 -242.894043)
			(xy 101.114606 -242.936059) (xy 101.138184 -242.982333) (xy 101.154232 -243.031726) (xy 101.162357 -243.083021)
			(xy 101.162866 -243.108988) (xy 101.162357 -243.134955) (xy 101.442267 -243.134955) (xy 101.442267 -243.083021)
			(xy 101.450392 -243.031726) (xy 101.46644 -242.982333) (xy 101.490018 -242.936059) (xy 101.520544 -242.894043)
			(xy 101.557267 -242.85732) (xy 101.599283 -242.826794) (xy 101.645557 -242.803216) (xy 101.69495 -242.787168)
			(xy 101.746245 -242.779043) (xy 101.798179 -242.779043) (xy 101.849474 -242.787168) (xy 101.898867 -242.803216)
			(xy 101.945141 -242.826794) (xy 101.987157 -242.85732) (xy 102.02388 -242.894043) (xy 102.054406 -242.936059)
			(xy 102.077984 -242.982333) (xy 102.094032 -243.031726) (xy 102.102157 -243.083021) (xy 102.102666 -243.108988)
			(xy 102.102157 -243.134955) (xy 102.094032 -243.18625) (xy 102.077984 -243.235643) (xy 102.054406 -243.281917)
			(xy 102.02388 -243.323933) (xy 101.987157 -243.360656) (xy 101.945141 -243.391182) (xy 101.898867 -243.41476)
			(xy 101.849474 -243.430808) (xy 101.798179 -243.438933) (xy 101.746245 -243.438933) (xy 101.69495 -243.430808)
			(xy 101.645557 -243.41476) (xy 101.599283 -243.391182) (xy 101.557267 -243.360656) (xy 101.520544 -243.323933)
			(xy 101.490018 -243.281917) (xy 101.46644 -243.235643) (xy 101.450392 -243.18625) (xy 101.442267 -243.134955)
			(xy 101.162357 -243.134955) (xy 101.154232 -243.18625) (xy 101.138184 -243.235643) (xy 101.114606 -243.281917)
			(xy 101.08408 -243.323933) (xy 101.047357 -243.360656) (xy 101.005341 -243.391182) (xy 100.959067 -243.41476)
			(xy 100.909674 -243.430808) (xy 100.858379 -243.438933) (xy 100.806445 -243.438933) (xy 100.75515 -243.430808)
			(xy 100.705757 -243.41476) (xy 100.659483 -243.391182) (xy 100.617467 -243.360656) (xy 100.580744 -243.323933)
			(xy 100.550218 -243.281917) (xy 100.52664 -243.235643) (xy 100.510592 -243.18625) (xy 100.502467 -243.134955)
			(xy 100.222521 -243.134955) (xy 100.222521 -243.136431) (xy 100.213463 -243.190563) (xy 100.205032 -243.216684)
			(xy 100.202238 -243.224812) (xy 100.202238 -243.494814) (xy 100.202752 -243.509303) (xy 100.210898 -243.537114)
			(xy 100.226532 -243.561514) (xy 100.248392 -243.580538) (xy 100.274717 -243.592654) (xy 100.303386 -243.596883)
			(xy 100.317808 -243.595398) (xy 100.328993 -243.59397) (xy 100.351491 -243.592447) (xy 100.362766 -243.59235)
			(xy 100.388737 -243.59283) (xy 100.440039 -243.600951) (xy 100.48944 -243.616998) (xy 100.535722 -243.640575)
			(xy 100.577745 -243.671103) (xy 100.614475 -243.707829) (xy 100.645007 -243.749849) (xy 100.668589 -243.796129)
			(xy 100.684641 -243.845528) (xy 100.692767 -243.896829) (xy 100.692767 -243.948771) (xy 100.972367 -243.948771)
			(xy 100.972367 -243.896837) (xy 100.980492 -243.845542) (xy 100.99654 -243.796149) (xy 101.020118 -243.749875)
			(xy 101.050644 -243.707859) (xy 101.087367 -243.671136) (xy 101.129383 -243.64061) (xy 101.175657 -243.617032)
			(xy 101.22505 -243.600984) (xy 101.276345 -243.592859) (xy 101.328279 -243.592859) (xy 101.379574 -243.600984)
			(xy 101.428967 -243.617032) (xy 101.475241 -243.64061) (xy 101.517257 -243.671136) (xy 101.55398 -243.707859)
			(xy 101.584506 -243.749875) (xy 101.608084 -243.796149) (xy 101.624132 -243.845542) (xy 101.632257 -243.896837)
			(xy 101.632766 -243.922804) (xy 101.632257 -243.948771) (xy 101.912421 -243.948771) (xy 101.912421 -243.896837)
			(xy 101.920546 -243.845542) (xy 101.936594 -243.796149) (xy 101.960172 -243.749875) (xy 101.990698 -243.707859)
			(xy 102.027421 -243.671136) (xy 102.069437 -243.64061) (xy 102.115711 -243.617032) (xy 102.165104 -243.600984)
			(xy 102.216399 -243.592859) (xy 102.268333 -243.592859) (xy 102.319628 -243.600984) (xy 102.369021 -243.617032)
			(xy 102.415295 -243.64061) (xy 102.457311 -243.671136) (xy 102.494034 -243.707859) (xy 102.52456 -243.749875)
			(xy 102.548138 -243.796149) (xy 102.564186 -243.845542) (xy 102.572311 -243.896837) (xy 102.57282 -243.922804)
			(xy 102.572311 -243.948771) (xy 102.564186 -244.000066) (xy 102.548138 -244.049459) (xy 102.52456 -244.095733)
			(xy 102.494034 -244.137749) (xy 102.457311 -244.174472) (xy 102.415295 -244.204998) (xy 102.369021 -244.228576)
			(xy 102.319628 -244.244624) (xy 102.268333 -244.252749) (xy 102.216399 -244.252749) (xy 102.165104 -244.244624)
			(xy 102.115711 -244.228576) (xy 102.069437 -244.204998) (xy 102.027421 -244.174472) (xy 101.990698 -244.137749)
			(xy 101.960172 -244.095733) (xy 101.936594 -244.049459) (xy 101.920546 -244.000066) (xy 101.912421 -243.948771)
			(xy 101.632257 -243.948771) (xy 101.624132 -244.000066) (xy 101.608084 -244.049459) (xy 101.584506 -244.095733)
			(xy 101.55398 -244.137749) (xy 101.517257 -244.174472) (xy 101.475241 -244.204998) (xy 101.428967 -244.228576)
			(xy 101.379574 -244.244624) (xy 101.328279 -244.252749) (xy 101.276345 -244.252749) (xy 101.22505 -244.244624)
			(xy 101.175657 -244.228576) (xy 101.129383 -244.204998) (xy 101.087367 -244.174472) (xy 101.050644 -244.137749)
			(xy 101.020118 -244.095733) (xy 100.99654 -244.049459) (xy 100.980492 -244.000066) (xy 100.972367 -243.948771)
			(xy 100.692767 -243.948771) (xy 100.684641 -244.000072) (xy 100.668589 -244.049471) (xy 100.645007 -244.095751)
			(xy 100.614475 -244.137771) (xy 100.577745 -244.174497) (xy 100.535722 -244.205025) (xy 100.48944 -244.228602)
			(xy 100.440039 -244.244649) (xy 100.388737 -244.25277) (xy 100.362766 -244.253258) (xy 100.35149 -244.253175)
			(xy 100.328991 -244.251653) (xy 100.317808 -244.25021) (xy 100.30339 -244.248733) (xy 100.274734 -244.252983)
			(xy 100.248423 -244.265105) (xy 100.226573 -244.284125) (xy 100.210939 -244.308514) (xy 100.202779 -244.33631)
			(xy 100.202238 -244.350794) (xy 100.202238 -244.56263) (xy 100.341684 -244.702076) (xy 100.351447 -244.711281)
			(xy 100.374688 -244.724676) (xy 100.400616 -244.731554) (xy 100.42744 -244.731441) (xy 100.453309 -244.724343)
			(xy 100.476436 -244.710753) (xy 100.495224 -244.691607) (xy 100.508376 -244.668228) (xy 100.512118 -244.65534)
			(xy 100.519384 -244.628993) (xy 100.541357 -244.578955) (xy 100.571263 -244.533214) (xy 100.608288 -244.493018)
			(xy 100.651423 -244.459462) (xy 100.699491 -244.433461) (xy 100.751182 -244.415723) (xy 100.805087 -244.406733)
			(xy 100.832412 -244.406166) (xy 100.85838 -244.40665) (xy 100.909677 -244.414776) (xy 100.95907 -244.430828)
			(xy 101.005345 -244.454408) (xy 101.047361 -244.484937) (xy 101.084083 -244.521664) (xy 101.114609 -244.563683)
			(xy 101.138185 -244.609959) (xy 101.154231 -244.659355) (xy 101.162353 -244.710652) (xy 101.162866 -244.73662)
			(xy 101.162329 -244.762587) (xy 101.442267 -244.762587) (xy 101.442267 -244.710653) (xy 101.450392 -244.659358)
			(xy 101.46644 -244.609965) (xy 101.490018 -244.563691) (xy 101.520544 -244.521675) (xy 101.557267 -244.484952)
			(xy 101.599283 -244.454426) (xy 101.645557 -244.430848) (xy 101.69495 -244.4148) (xy 101.746245 -244.406675)
			(xy 101.798179 -244.406675) (xy 101.849474 -244.4148) (xy 101.898867 -244.430848) (xy 101.945141 -244.454426)
			(xy 101.987157 -244.484952) (xy 102.02388 -244.521675) (xy 102.054406 -244.563691) (xy 102.077984 -244.609965)
			(xy 102.094032 -244.659358) (xy 102.102157 -244.710653) (xy 102.102666 -244.73662) (xy 102.102157 -244.762587)
			(xy 102.094032 -244.813882) (xy 102.077984 -244.863275) (xy 102.054406 -244.909549) (xy 102.02388 -244.951565)
			(xy 101.987157 -244.988288) (xy 101.945141 -245.018814) (xy 101.898867 -245.042392) (xy 101.849474 -245.05844)
			(xy 101.798179 -245.066565) (xy 101.746245 -245.066565) (xy 101.69495 -245.05844) (xy 101.645557 -245.042392)
			(xy 101.599283 -245.018814) (xy 101.557267 -244.988288) (xy 101.520544 -244.951565) (xy 101.490018 -244.909549)
			(xy 101.46644 -244.863275) (xy 101.450392 -244.813882) (xy 101.442267 -244.762587) (xy 101.162329 -244.762587)
			(xy 101.162301 -244.763944) (xy 101.153307 -244.817848) (xy 101.135567 -244.869538) (xy 101.109564 -244.917604)
			(xy 101.076008 -244.960737) (xy 101.035813 -244.997762) (xy 100.990074 -245.02767) (xy 100.940038 -245.049644)
			(xy 100.913692 -245.056914) (xy 100.900768 -245.060584) (xy 100.877332 -245.073704) (xy 100.858137 -245.09249)
			(xy 100.844516 -245.115638) (xy 100.837415 -245.14154) (xy 100.837327 -245.168398) (xy 100.844258 -245.194346)
			(xy 100.857727 -245.217583) (xy 100.866956 -245.227348) (xy 100.941378 -245.30177) (xy 100.952707 -245.312334)
			(xy 100.980147 -245.326674) (xy 101.010622 -245.332135) (xy 101.041334 -245.328218) (xy 101.069463 -245.315281)
			(xy 101.081332 -245.305326) (xy 101.099626 -245.289392) (xy 101.140007 -245.262508) (xy 101.183887 -245.241821)
			(xy 101.230321 -245.227775) (xy 101.27831 -245.220673) (xy 101.302566 -245.220236) (xy 101.328537 -245.220716)
			(xy 101.379841 -245.228837) (xy 101.429243 -245.244884) (xy 101.475526 -245.268461) (xy 101.517551 -245.298989)
			(xy 101.554282 -245.335716) (xy 101.584816 -245.377736) (xy 101.608399 -245.424016) (xy 101.624453 -245.473416)
			(xy 101.63258 -245.524719) (xy 101.63302 -245.55069) (xy 101.632593 -245.574947) (xy 101.632339 -245.576666)
			(xy 101.912445 -245.576666) (xy 101.912445 -245.524734) (xy 101.920569 -245.47344) (xy 101.936616 -245.424049)
			(xy 101.960191 -245.377776) (xy 101.990715 -245.335761) (xy 102.027435 -245.299037) (xy 102.069447 -245.268509)
			(xy 102.115718 -245.244929) (xy 102.165107 -245.228877) (xy 102.2164 -245.220748) (xy 102.242366 -245.220236)
			(xy 102.267836 -245.220677) (xy 102.318178 -245.228459) (xy 102.366724 -245.24389) (xy 102.41232 -245.266602)
			(xy 102.433374 -245.280942) (xy 102.444608 -245.288483) (xy 102.469993 -245.297823) (xy 102.496942 -245.30016)
			(xy 102.523557 -245.29533) (xy 102.547965 -245.283671) (xy 102.568449 -245.266006) (xy 102.583568 -245.243576)
			(xy 102.588314 -245.230904) (xy 102.596 -245.209441) (xy 102.616448 -245.168694) (xy 102.642301 -245.131143)
			(xy 102.657402 -245.114064) (xy 102.667219 -245.102586) (xy 102.680228 -245.075345) (xy 102.684692 -245.045488)
			(xy 102.680221 -245.015633) (xy 102.667206 -244.988394) (xy 102.657402 -244.976904) (xy 102.641123 -244.958517)
			(xy 102.613658 -244.917807) (xy 102.592523 -244.87348) (xy 102.578185 -244.826512) (xy 102.57096 -244.777938)
			(xy 102.570534 -244.753384) (xy 102.571043 -244.727417) (xy 102.579168 -244.676122) (xy 102.595216 -244.626729)
			(xy 102.618794 -244.580455) (xy 102.64932 -244.538439) (xy 102.686043 -244.501716) (xy 102.728059 -244.47119)
			(xy 102.774333 -244.447612) (xy 102.823726 -244.431564) (xy 102.875021 -244.423439) (xy 102.926955 -244.423439)
			(xy 102.97825 -244.431564) (xy 103.027643 -244.447612) (xy 103.073917 -244.47119) (xy 103.115933 -244.501716)
			(xy 103.152656 -244.538439) (xy 103.183182 -244.580455) (xy 103.20676 -244.626729) (xy 103.222808 -244.676122)
			(xy 103.230933 -244.727417) (xy 103.231442 -244.753384) (xy 103.231019 -244.777937) (xy 103.223774 -244.826504)
			(xy 103.209426 -244.873466) (xy 103.18829 -244.91779) (xy 103.160832 -244.9585) (xy 103.144574 -244.976904)
			(xy 103.134782 -244.988403) (xy 103.12176 -245.015636) (xy 103.117286 -245.045488) (xy 103.121753 -245.075341)
			(xy 103.134769 -245.102577) (xy 103.144574 -245.114064) (xy 103.160833 -245.132467) (xy 103.188302 -245.173172)
			(xy 103.209441 -245.217495) (xy 103.223784 -245.26446) (xy 103.231013 -245.313031) (xy 103.231442 -245.337584)
			(xy 103.230956 -245.363553) (xy 103.222833 -245.414853) (xy 103.206785 -245.464251) (xy 103.183206 -245.510529)
			(xy 103.152678 -245.552549) (xy 103.115952 -245.589275) (xy 103.073932 -245.619804) (xy 103.027654 -245.643383)
			(xy 102.978257 -245.659432) (xy 102.926957 -245.667556) (xy 102.900988 -245.668038) (xy 102.875519 -245.667575)
			(xy 102.825178 -245.6598) (xy 102.776632 -245.644376) (xy 102.731035 -245.62167) (xy 102.70998 -245.607332)
			(xy 102.698726 -245.59982) (xy 102.673346 -245.590463) (xy 102.646399 -245.588113) (xy 102.619783 -245.592937)
			(xy 102.595374 -245.604593) (xy 102.574892 -245.622262) (xy 102.559781 -245.644696) (xy 102.55504 -245.65737)
			(xy 102.54628 -245.681497) (xy 102.522417 -245.726938) (xy 102.491811 -245.768139) (xy 102.455199 -245.80411)
			(xy 102.413463 -245.833983) (xy 102.367607 -245.85704) (xy 102.318737 -245.872725) (xy 102.268029 -245.88066)
			(xy 102.242366 -245.881144) (xy 102.2164 -245.880652) (xy 102.165107 -245.872523) (xy 102.115718 -245.856471)
			(xy 102.069447 -245.832891) (xy 102.027435 -245.802363) (xy 101.990715 -245.765639) (xy 101.960191 -245.723624)
			(xy 101.936616 -245.677351) (xy 101.920569 -245.62796) (xy 101.912445 -245.576666) (xy 101.632339 -245.576666)
			(xy 101.625494 -245.622938) (xy 101.611448 -245.669373) (xy 101.590757 -245.713253) (xy 101.563867 -245.753632)
			(xy 101.54793 -245.771924) (xy 101.537976 -245.783784) (xy 101.525083 -245.811917) (xy 101.521188 -245.842619)
			(xy 101.526648 -245.87308) (xy 101.540964 -245.900518) (xy 101.551486 -245.911878) (xy 101.684328 -246.04472)
			(xy 101.710744 -246.039894) (xy 101.725964 -246.037164) (xy 101.75675 -246.034237) (xy 101.772212 -246.034052)
			(xy 101.798178 -246.034562) (xy 101.849472 -246.042688) (xy 101.898862 -246.058738) (xy 101.945134 -246.082316)
			(xy 101.987148 -246.112843) (xy 102.023869 -246.149566) (xy 102.054393 -246.191581) (xy 102.077969 -246.237854)
			(xy 102.094016 -246.287246) (xy 102.102139 -246.33854) (xy 102.102666 -246.364506) (xy 102.102462 -246.379967)
			(xy 102.099539 -246.410752) (xy 102.096824 -246.425974) (xy 102.091998 -246.45239) (xy 102.589838 -246.95023)
			(xy 102.589838 -248.250456) (xy 102.590234 -248.26436) (xy 102.597673 -248.291153) (xy 102.612067 -248.314945)
			(xy 102.632346 -248.33397) (xy 102.657008 -248.346816) (xy 102.684221 -248.352532) (xy 102.711967 -248.350691)
			(xy 102.72522 -248.346468) (xy 102.751748 -248.337751) (xy 102.806778 -248.328308) (xy 102.834694 -248.327672)
			(xy 102.860663 -248.328154) (xy 102.911961 -248.336279) (xy 102.961357 -248.352329) (xy 103.007633 -248.375908)
			(xy 103.049651 -248.406437) (xy 103.086376 -248.443164) (xy 103.116902 -248.485184) (xy 103.140479 -248.531462)
			(xy 103.156526 -248.580858) (xy 103.164647 -248.632157) (xy 103.165148 -248.658126) (xy 103.164719 -248.682679)
			(xy 103.157488 -248.731249) (xy 103.143144 -248.778213) (xy 103.122005 -248.822536) (xy 103.094536 -248.863239)
			(xy 103.07828 -248.881646) (xy 103.068484 -248.893137) (xy 103.055484 -248.920372) (xy 103.051024 -248.950219)
			(xy 103.055495 -248.980065) (xy 103.068506 -249.007295) (xy 103.07828 -249.018806) (xy 103.094537 -249.03721)
			(xy 103.121994 -249.077921) (xy 103.143128 -249.122245) (xy 103.157474 -249.169207) (xy 103.164718 -249.217774)
			(xy 103.165148 -249.242326) (xy 103.164637 -249.268292) (xy 103.156509 -249.319583) (xy 103.140458 -249.368972)
			(xy 103.116879 -249.415242) (xy 103.086352 -249.457254) (xy 103.049629 -249.493973) (xy 103.007615 -249.524496)
			(xy 102.961342 -249.54807) (xy 102.911952 -249.564117) (xy 102.86066 -249.572239) (xy 102.834694 -249.57278)
			(xy 102.809566 -249.572317) (xy 102.759889 -249.564718) (xy 102.711936 -249.54968) (xy 102.666815 -249.527551)
			(xy 102.625567 -249.498842) (xy 102.589145 -249.464216) (xy 102.558388 -249.424471) (xy 102.534008 -249.380525)
			(xy 102.516568 -249.333393) (xy 102.506468 -249.284163) (xy 102.504748 -249.25909) (xy 102.503546 -249.244434)
			(xy 102.493814 -249.216699) (xy 102.47658 -249.192889) (xy 102.453273 -249.174979) (xy 102.425828 -249.164456)
			(xy 102.396522 -249.162192) (xy 102.367787 -249.168376) (xy 102.342007 -249.182495) (xy 102.331266 -249.192542)
			(xy 102.06355 -249.460258) (xy 102.076758 -249.491754) (xy 102.084952 -249.512135) (xy 102.096489 -249.55452)
			(xy 102.102307 -249.59806) (xy 102.102666 -249.620024) (xy 102.102221 -249.644899) (xy 102.094773 -249.694089)
			(xy 102.080033 -249.741605) (xy 102.058335 -249.786374) (xy 102.030169 -249.827384) (xy 101.996173 -249.863706)
			(xy 101.957115 -249.89452) (xy 101.913878 -249.91913) (xy 101.867439 -249.936978) (xy 101.81885 -249.947661)
			(xy 101.794056 -249.949716) (xy 101.784492 -249.950744) (xy 101.767117 -249.958962) (xy 101.753998 -249.973009)
			(xy 101.746985 -249.990904) (xy 101.746558 -250.000516) (xy 101.746558 -251.135134) (xy 102.50424 -251.135134)
			(xy 102.504678 -251.110582) (xy 102.51192 -251.062015) (xy 102.526265 -251.015054) (xy 102.547397 -250.97073)
			(xy 102.574852 -250.930018) (xy 102.591108 -250.911614) (xy 102.600876 -250.900098) (xy 102.613889 -250.87287)
			(xy 102.618362 -250.843025) (xy 102.613904 -250.813178) (xy 102.600904 -250.785944) (xy 102.591108 -250.774454)
			(xy 102.574854 -250.756046) (xy 102.547385 -250.715342) (xy 102.526245 -250.67102) (xy 102.511902 -250.624057)
			(xy 102.50467 -250.575487) (xy 102.50424 -250.550934) (xy 102.504749 -250.524967) (xy 102.512874 -250.473672)
			(xy 102.528922 -250.424279) (xy 102.5525 -250.378005) (xy 102.583026 -250.335989) (xy 102.619749 -250.299266)
			(xy 102.661765 -250.26874) (xy 102.708039 -250.245162) (xy 102.757432 -250.229114) (xy 102.808727 -250.220989)
			(xy 102.860661 -250.220989) (xy 102.911956 -250.229114) (xy 102.961349 -250.245162) (xy 103.007623 -250.26874)
			(xy 103.049639 -250.299266) (xy 103.086362 -250.335989) (xy 103.116888 -250.378005) (xy 103.140466 -250.424279)
			(xy 103.156514 -250.473672) (xy 103.164639 -250.524967) (xy 103.165148 -250.550934) (xy 103.164694 -250.575485)
			(xy 103.157456 -250.624052) (xy 103.143115 -250.671013) (xy 103.121987 -250.715337) (xy 103.094535 -250.756049)
			(xy 103.07828 -250.774454) (xy 103.068447 -250.785919) (xy 103.055443 -250.813165) (xy 103.050983 -250.843025)
			(xy 103.055457 -250.872883) (xy 103.068475 -250.900123) (xy 103.07828 -250.911614) (xy 103.094564 -250.929997)
			(xy 103.122029 -250.970707) (xy 103.143163 -251.015035) (xy 103.1575 -251.062005) (xy 103.164723 -251.110579)
			(xy 103.165148 -251.135134) (xy 103.164639 -251.161101) (xy 103.156514 -251.212396) (xy 103.140466 -251.261789)
			(xy 103.116888 -251.308063) (xy 103.086362 -251.350079) (xy 103.049639 -251.386802) (xy 103.007623 -251.417328)
			(xy 102.961349 -251.440906) (xy 102.911956 -251.456954) (xy 102.860661 -251.465079) (xy 102.808727 -251.465079)
			(xy 102.757432 -251.456954) (xy 102.708039 -251.440906) (xy 102.661765 -251.417328) (xy 102.619749 -251.386802)
			(xy 102.583026 -251.350079) (xy 102.5525 -251.308063) (xy 102.528922 -251.261789) (xy 102.512874 -251.212396)
			(xy 102.504749 -251.161101) (xy 102.50424 -251.135134) (xy 101.746558 -251.135134) (xy 101.746558 -252.798834)
			(xy 102.5652 -252.798834) (xy 102.565623 -252.774281) (xy 102.572866 -252.725713) (xy 102.587214 -252.678751)
			(xy 102.60835 -252.634427) (xy 102.635809 -252.593717) (xy 102.652068 -252.575314) (xy 102.661839 -252.563799)
			(xy 102.674857 -252.536571) (xy 102.679333 -252.506725) (xy 102.674872 -252.476877) (xy 102.661867 -252.449643)
			(xy 102.652068 -252.438154) (xy 102.635824 -252.419737) (xy 102.608351 -252.379037) (xy 102.587209 -252.334718)
			(xy 102.572863 -252.287755) (xy 102.56563 -252.239187) (xy 102.5652 -252.214634) (xy 102.565709 -252.188667)
			(xy 102.573834 -252.137372) (xy 102.589882 -252.087979) (xy 102.61346 -252.041705) (xy 102.643986 -251.999689)
			(xy 102.680709 -251.962966) (xy 102.722725 -251.93244) (xy 102.768999 -251.908862) (xy 102.818392 -251.892814)
			(xy 102.869687 -251.884689) (xy 102.921621 -251.884689) (xy 102.972916 -251.892814) (xy 103.022309 -251.908862)
			(xy 103.068583 -251.93244) (xy 103.110599 -251.962966) (xy 103.147322 -251.999689) (xy 103.177848 -252.041705)
			(xy 103.201426 -252.087979) (xy 103.217474 -252.137372) (xy 103.225599 -252.188667) (xy 103.226108 -252.214634)
			(xy 103.225664 -252.239186) (xy 103.218425 -252.287753) (xy 103.204083 -252.334715) (xy 103.182952 -252.379039)
			(xy 103.155497 -252.41975) (xy 103.13924 -252.438154) (xy 103.129402 -252.449617) (xy 103.11639 -252.476863)
			(xy 103.111927 -252.506725) (xy 103.116405 -252.536585) (xy 103.12943 -252.563825) (xy 103.13924 -252.575314)
			(xy 103.155518 -252.593702) (xy 103.182985 -252.63441) (xy 103.204121 -252.678737) (xy 103.218459 -252.725706)
			(xy 103.225683 -252.774279) (xy 103.226108 -252.798834) (xy 103.225599 -252.824801) (xy 103.217474 -252.876096)
			(xy 103.201426 -252.925489) (xy 103.177848 -252.971763) (xy 103.147322 -253.013779) (xy 103.110599 -253.050502)
			(xy 103.068583 -253.081028) (xy 103.022309 -253.104606) (xy 102.972916 -253.120654) (xy 102.921621 -253.128779)
			(xy 102.869687 -253.128779) (xy 102.818392 -253.120654) (xy 102.768999 -253.104606) (xy 102.722725 -253.081028)
			(xy 102.680709 -253.050502) (xy 102.643986 -253.013779) (xy 102.61346 -252.971763) (xy 102.589882 -252.925489)
			(xy 102.573834 -252.876096) (xy 102.565709 -252.824801) (xy 102.5652 -252.798834) (xy 101.746558 -252.798834)
			(xy 101.746558 -253.796038) (xy 101.749352 -253.803912) (xy 101.758346 -253.83202) (xy 101.768044 -253.89023)
			(xy 101.768656 -253.919736) (xy 101.768169 -253.945703) (xy 102.022403 -253.945703) (xy 102.022403 -253.893769)
			(xy 102.030528 -253.842474) (xy 102.046576 -253.793081) (xy 102.070154 -253.746807) (xy 102.10068 -253.704791)
			(xy 102.137403 -253.668068) (xy 102.179419 -253.637542) (xy 102.225693 -253.613964) (xy 102.275086 -253.597916)
			(xy 102.326381 -253.589791) (xy 102.378315 -253.589791) (xy 102.42961 -253.597916) (xy 102.479003 -253.613964)
			(xy 102.525277 -253.637542) (xy 102.567293 -253.668068) (xy 102.604016 -253.704791) (xy 102.634542 -253.746807)
			(xy 102.65812 -253.793081) (xy 102.674168 -253.842474) (xy 102.682293 -253.893769) (xy 102.682802 -253.919736)
			(xy 102.682293 -253.945703) (xy 102.674168 -253.996998) (xy 102.65812 -254.046391) (xy 102.634542 -254.092665)
			(xy 102.604016 -254.134681) (xy 102.567293 -254.171404) (xy 102.525277 -254.20193) (xy 102.479003 -254.225508)
			(xy 102.42961 -254.241556) (xy 102.378315 -254.249681) (xy 102.326381 -254.249681) (xy 102.275086 -254.241556)
			(xy 102.225693 -254.225508) (xy 102.179419 -254.20193) (xy 102.137403 -254.171404) (xy 102.10068 -254.134681)
			(xy 102.070154 -254.092665) (xy 102.046576 -254.046391) (xy 102.030528 -253.996998) (xy 102.022403 -253.945703)
			(xy 101.768169 -253.945703) (xy 101.768102 -253.949247) (xy 101.758405 -254.007466) (xy 101.749352 -254.03556)
			(xy 101.746558 -254.043434) (xy 101.746558 -254.23749) (xy 101.272848 -254.7112) (xy 101.272848 -254.732536)
			(xy 101.272427 -254.758422) (xy 101.272257 -254.759519) (xy 101.552249 -254.759519) (xy 101.552249 -254.707585)
			(xy 101.560374 -254.65629) (xy 101.576422 -254.606897) (xy 101.6 -254.560623) (xy 101.630526 -254.518607)
			(xy 101.667249 -254.481884) (xy 101.709265 -254.451358) (xy 101.755539 -254.42778) (xy 101.804932 -254.411732)
			(xy 101.856227 -254.403607) (xy 101.908161 -254.403607) (xy 101.959456 -254.411732) (xy 102.008849 -254.42778)
			(xy 102.055123 -254.451358) (xy 102.097139 -254.481884) (xy 102.133862 -254.518607) (xy 102.164388 -254.560623)
			(xy 102.187966 -254.606897) (xy 102.204014 -254.65629) (xy 102.212139 -254.707585) (xy 102.212648 -254.733552)
			(xy 102.212139 -254.759519) (xy 102.204014 -254.810814) (xy 102.187966 -254.860207) (xy 102.164388 -254.906481)
			(xy 102.133862 -254.948497) (xy 102.097139 -254.98522) (xy 102.055123 -255.015746) (xy 102.008849 -255.039324)
			(xy 101.959456 -255.055372) (xy 101.908161 -255.063497) (xy 101.856227 -255.063497) (xy 101.804932 -255.055372)
			(xy 101.755539 -255.039324) (xy 101.709265 -255.015746) (xy 101.667249 -254.98522) (xy 101.630526 -254.948497)
			(xy 101.6 -254.906481) (xy 101.576422 -254.860207) (xy 101.560374 -254.810814) (xy 101.552249 -254.759519)
			(xy 101.272257 -254.759519) (xy 101.264514 -254.809583) (xy 101.248715 -254.858883) (xy 101.225417 -254.905114)
			(xy 101.19519 -254.947143) (xy 101.158776 -254.983941) (xy 101.117065 -255.014606) (xy 101.071081 -255.038387)
			(xy 101.02195 -255.054701) (xy 100.996496 -255.059434) (xy 100.954078 -255.066546) (xy 100.954078 -255.573589)
			(xy 101.082603 -255.573589) (xy 101.082603 -255.521655) (xy 101.090728 -255.47036) (xy 101.106776 -255.420967)
			(xy 101.130354 -255.374693) (xy 101.16088 -255.332677) (xy 101.197603 -255.295954) (xy 101.239619 -255.265428)
			(xy 101.285893 -255.24185) (xy 101.335286 -255.225802) (xy 101.386581 -255.217677) (xy 101.438515 -255.217677)
			(xy 101.48981 -255.225802) (xy 101.539203 -255.24185) (xy 101.585477 -255.265428) (xy 101.627493 -255.295954)
			(xy 101.664216 -255.332677) (xy 101.694742 -255.374693) (xy 101.71832 -255.420967) (xy 101.734368 -255.47036)
			(xy 101.742493 -255.521655) (xy 101.743002 -255.547622) (xy 101.742493 -255.57357) (xy 102.022351 -255.57357)
			(xy 102.022351 -255.52163) (xy 102.030477 -255.47033) (xy 102.046529 -255.420932) (xy 102.070111 -255.374655)
			(xy 102.100643 -255.332636) (xy 102.137373 -255.295912) (xy 102.179396 -255.265386) (xy 102.225677 -255.24181)
			(xy 102.275076 -255.225766) (xy 102.326378 -255.217647) (xy 102.352348 -255.217168) (xy 102.382366 -255.217814)
			(xy 102.441411 -255.228683) (xy 102.469696 -255.238758) (xy 102.48358 -255.243504) (xy 102.512829 -255.245681)
			(xy 102.541488 -255.239448) (xy 102.567191 -255.225319) (xy 102.587812 -255.204463) (xy 102.601648 -255.178602)
			(xy 102.605078 -255.164336) (xy 102.610663 -255.139862) (xy 102.628165 -255.092816) (xy 102.652581 -255.048958)
			(xy 102.68335 -255.009297) (xy 102.719762 -254.974745) (xy 102.760981 -254.946098) (xy 102.806059 -254.924015)
			(xy 102.853958 -254.909003) (xy 102.903576 -254.901407) (xy 102.928674 -254.900938) (xy 102.954642 -254.901453)
			(xy 103.00594 -254.909574) (xy 103.055335 -254.92562) (xy 103.101612 -254.949195) (xy 103.143631 -254.97972)
			(xy 103.180358 -255.016443) (xy 103.210887 -255.058459) (xy 103.234467 -255.104733) (xy 103.250518 -255.154127)
			(xy 103.258645 -255.205424) (xy 103.259128 -255.231392) (xy 103.258697 -255.256099) (xy 103.251331 -255.304961)
			(xy 103.236763 -255.352179) (xy 103.215319 -255.396697) (xy 103.187477 -255.437521) (xy 103.17099 -255.455928)
			(xy 103.16104 -255.467422) (xy 103.147834 -255.49479) (xy 103.143264 -255.524831) (xy 103.147734 -255.554888)
			(xy 103.16085 -255.582299) (xy 103.170736 -255.59385) (xy 103.187095 -255.612227) (xy 103.214689 -255.652959)
			(xy 103.235936 -255.697334) (xy 103.250367 -255.744369) (xy 103.257661 -255.793024) (xy 103.258112 -255.817624)
			(xy 103.257693 -255.843596) (xy 103.249563 -255.8949) (xy 103.233508 -255.944301) (xy 103.209921 -255.990581)
			(xy 103.179385 -256.032602) (xy 103.142652 -256.069328) (xy 103.100625 -256.099856) (xy 103.054339 -256.123433)
			(xy 103.004936 -256.139479) (xy 102.95363 -256.147598) (xy 102.927658 -256.148078) (xy 102.901501 -256.147618)
			(xy 102.849838 -256.139383) (xy 102.800119 -256.123111) (xy 102.753585 -256.099206) (xy 102.7114 -256.068268)
			(xy 102.674616 -256.031069) (xy 102.644154 -255.988538) (xy 102.620775 -255.941738) (xy 102.612444 -255.916938)
			(xy 102.607806 -255.903728) (xy 102.592398 -255.880361) (xy 102.571223 -255.862059) (xy 102.545871 -255.850197)
			(xy 102.518251 -255.845668) (xy 102.490439 -255.848811) (xy 102.477316 -255.853692) (xy 102.447336 -255.86507)
			(xy 102.384406 -255.877345) (xy 102.352348 -255.878076) (xy 102.326378 -255.877553) (xy 102.275076 -255.869434)
			(xy 102.225677 -255.85339) (xy 102.179396 -255.829814) (xy 102.137373 -255.799288) (xy 102.100643 -255.762564)
			(xy 102.070111 -255.720545) (xy 102.046529 -255.674268) (xy 102.030477 -255.62487) (xy 102.022351 -255.57357)
			(xy 101.742493 -255.57357) (xy 101.742493 -255.573589) (xy 101.734368 -255.624884) (xy 101.71832 -255.674277)
			(xy 101.694742 -255.720551) (xy 101.664216 -255.762567) (xy 101.627493 -255.79929) (xy 101.585477 -255.829816)
			(xy 101.539203 -255.853394) (xy 101.48981 -255.869442) (xy 101.438515 -255.877567) (xy 101.386581 -255.877567)
			(xy 101.335286 -255.869442) (xy 101.285893 -255.853394) (xy 101.239619 -255.829816) (xy 101.197603 -255.79929)
			(xy 101.16088 -255.762567) (xy 101.130354 -255.720551) (xy 101.106776 -255.674277) (xy 101.090728 -255.624884)
			(xy 101.082603 -255.573589) (xy 100.954078 -255.573589) (xy 100.954078 -256.028444) (xy 100.996496 -256.035302)
			(xy 101.021918 -256.04001) (xy 101.070991 -256.05628) (xy 101.116932 -256.079991) (xy 101.158622 -256.110567)
			(xy 101.195042 -256.14726) (xy 101.225305 -256.189177) (xy 101.248672 -256.235294) (xy 101.264574 -256.284487)
			(xy 101.272622 -256.335556) (xy 101.272622 -256.387256) (xy 101.272599 -256.387405) (xy 101.552249 -256.387405)
			(xy 101.552249 -256.335471) (xy 101.560374 -256.284176) (xy 101.576422 -256.234783) (xy 101.6 -256.188509)
			(xy 101.630526 -256.146493) (xy 101.667249 -256.10977) (xy 101.709265 -256.079244) (xy 101.755539 -256.055666)
			(xy 101.804932 -256.039618) (xy 101.856227 -256.031493) (xy 101.908161 -256.031493) (xy 101.959456 -256.039618)
			(xy 102.008849 -256.055666) (xy 102.055123 -256.079244) (xy 102.097139 -256.10977) (xy 102.133862 -256.146493)
			(xy 102.164388 -256.188509) (xy 102.187966 -256.234783) (xy 102.204014 -256.284176) (xy 102.212139 -256.335471)
			(xy 102.212648 -256.361438) (xy 102.212139 -256.387405) (xy 102.204014 -256.4387) (xy 102.187966 -256.488093)
			(xy 102.164388 -256.534367) (xy 102.133862 -256.576383) (xy 102.097139 -256.613106) (xy 102.055123 -256.643632)
			(xy 102.008849 -256.66721) (xy 101.959456 -256.683258) (xy 101.908161 -256.691383) (xy 101.856227 -256.691383)
			(xy 101.804932 -256.683258) (xy 101.755539 -256.66721) (xy 101.709265 -256.643632) (xy 101.667249 -256.613106)
			(xy 101.630526 -256.576383) (xy 101.6 -256.534367) (xy 101.576422 -256.488093) (xy 101.560374 -256.4387)
			(xy 101.552249 -256.387405) (xy 101.272599 -256.387405) (xy 101.264571 -256.438325) (xy 101.248667 -256.487517)
			(xy 101.225298 -256.533634) (xy 101.195034 -256.575549) (xy 101.158612 -256.612242) (xy 101.116922 -256.642815)
			(xy 101.07098 -256.666525) (xy 101.021906 -256.682793) (xy 100.996496 -256.687574) (xy 100.954078 -256.694432)
			(xy 100.954078 -257.201221) (xy 101.082603 -257.201221) (xy 101.082603 -257.149287) (xy 101.090728 -257.097992)
			(xy 101.106776 -257.048599) (xy 101.130354 -257.002325) (xy 101.16088 -256.960309) (xy 101.197603 -256.923586)
			(xy 101.239619 -256.89306) (xy 101.285893 -256.869482) (xy 101.335286 -256.853434) (xy 101.386581 -256.845309)
			(xy 101.438515 -256.845309) (xy 101.48981 -256.853434) (xy 101.539203 -256.869482) (xy 101.585477 -256.89306)
			(xy 101.627493 -256.923586) (xy 101.664216 -256.960309) (xy 101.694742 -257.002325) (xy 101.71832 -257.048599)
			(xy 101.734368 -257.097992) (xy 101.742493 -257.149287) (xy 101.743002 -257.175254) (xy 101.742493 -257.201221)
			(xy 102.022403 -257.201221) (xy 102.022403 -257.149287) (xy 102.030528 -257.097992) (xy 102.046576 -257.048599)
			(xy 102.070154 -257.002325) (xy 102.10068 -256.960309) (xy 102.137403 -256.923586) (xy 102.179419 -256.89306)
			(xy 102.225693 -256.869482) (xy 102.275086 -256.853434) (xy 102.326381 -256.845309) (xy 102.378315 -256.845309)
			(xy 102.42961 -256.853434) (xy 102.479003 -256.869482) (xy 102.525277 -256.89306) (xy 102.567293 -256.923586)
			(xy 102.604016 -256.960309) (xy 102.634542 -257.002325) (xy 102.65812 -257.048599) (xy 102.674168 -257.097992)
			(xy 102.682293 -257.149287) (xy 102.682802 -257.175254) (xy 102.682293 -257.201221) (xy 102.674168 -257.252516)
			(xy 102.65812 -257.301909) (xy 102.634542 -257.348183) (xy 102.604016 -257.390199) (xy 102.567293 -257.426922)
			(xy 102.525277 -257.457448) (xy 102.479003 -257.481026) (xy 102.42961 -257.497074) (xy 102.378315 -257.505199)
			(xy 102.326381 -257.505199) (xy 102.275086 -257.497074) (xy 102.225693 -257.481026) (xy 102.179419 -257.457448)
			(xy 102.137403 -257.426922) (xy 102.10068 -257.390199) (xy 102.070154 -257.348183) (xy 102.046576 -257.301909)
			(xy 102.030528 -257.252516) (xy 102.022403 -257.201221) (xy 101.742493 -257.201221) (xy 101.734368 -257.252516)
			(xy 101.71832 -257.301909) (xy 101.694742 -257.348183) (xy 101.664216 -257.390199) (xy 101.627493 -257.426922)
			(xy 101.585477 -257.457448) (xy 101.539203 -257.481026) (xy 101.48981 -257.497074) (xy 101.438515 -257.505199)
			(xy 101.386581 -257.505199) (xy 101.335286 -257.497074) (xy 101.285893 -257.481026) (xy 101.239619 -257.457448)
			(xy 101.197603 -257.426922) (xy 101.16088 -257.390199) (xy 101.130354 -257.348183) (xy 101.106776 -257.301909)
			(xy 101.090728 -257.252516) (xy 101.082603 -257.201221) (xy 100.954078 -257.201221) (xy 100.954078 -257.656076)
			(xy 100.996496 -257.663188) (xy 101.021901 -257.667896) (xy 101.070941 -257.684158) (xy 101.116852 -257.707858)
			(xy 101.158512 -257.738415) (xy 101.194908 -257.775086) (xy 101.22515 -257.816977) (xy 101.248502 -257.863065)
			(xy 101.264394 -257.912226) (xy 101.272438 -257.963262) (xy 101.272439 -258.014928) (xy 101.272422 -258.015037)
			(xy 101.552249 -258.015037) (xy 101.552249 -257.963103) (xy 101.560374 -257.911808) (xy 101.576422 -257.862415)
			(xy 101.6 -257.816141) (xy 101.630526 -257.774125) (xy 101.667249 -257.737402) (xy 101.709265 -257.706876)
			(xy 101.755539 -257.683298) (xy 101.804932 -257.66725) (xy 101.856227 -257.659125) (xy 101.908161 -257.659125)
			(xy 101.959456 -257.66725) (xy 102.008849 -257.683298) (xy 102.055123 -257.706876) (xy 102.097139 -257.737402)
			(xy 102.133862 -257.774125) (xy 102.164388 -257.816141) (xy 102.187966 -257.862415) (xy 102.204014 -257.911808)
			(xy 102.212139 -257.963103) (xy 102.212648 -257.98907) (xy 102.212139 -258.015037) (xy 102.204014 -258.066332)
			(xy 102.187966 -258.115725) (xy 102.164388 -258.161999) (xy 102.133862 -258.204015) (xy 102.097139 -258.240738)
			(xy 102.055123 -258.271264) (xy 102.008849 -258.294842) (xy 101.959456 -258.31089) (xy 101.908161 -258.319015)
			(xy 101.856227 -258.319015) (xy 101.804932 -258.31089) (xy 101.755539 -258.294842) (xy 101.709265 -258.271264)
			(xy 101.667249 -258.240738) (xy 101.630526 -258.204015) (xy 101.6 -258.161999) (xy 101.576422 -258.115725)
			(xy 101.560374 -258.066332) (xy 101.552249 -258.015037) (xy 101.272422 -258.015037) (xy 101.264396 -258.065965)
			(xy 101.248506 -258.115126) (xy 101.225155 -258.161215) (xy 101.194914 -258.203106) (xy 101.15852 -258.239778)
			(xy 101.11686 -258.270337) (xy 101.07095 -258.294038) (xy 101.021911 -258.310302) (xy 100.996496 -258.314952)
			(xy 100.954078 -258.322064) (xy 100.954078 -258.829107) (xy 101.082349 -258.829107) (xy 101.082349 -258.777173)
			(xy 101.090474 -258.725878) (xy 101.106522 -258.676485) (xy 101.1301 -258.630211) (xy 101.160626 -258.588195)
			(xy 101.197349 -258.551472) (xy 101.239365 -258.520946) (xy 101.285639 -258.497368) (xy 101.335032 -258.48132)
			(xy 101.386327 -258.473195) (xy 101.438261 -258.473195) (xy 101.489556 -258.48132) (xy 101.538949 -258.497368)
			(xy 101.585223 -258.520946) (xy 101.627239 -258.551472) (xy 101.663962 -258.588195) (xy 101.694488 -258.630211)
			(xy 101.718066 -258.676485) (xy 101.734114 -258.725878) (xy 101.742239 -258.777173) (xy 101.742748 -258.80314)
			(xy 101.742239 -258.829107) (xy 101.734114 -258.880402) (xy 101.718066 -258.929795) (xy 101.694488 -258.976069)
			(xy 101.663962 -259.018085) (xy 101.627239 -259.054808) (xy 101.585223 -259.085334) (xy 101.538949 -259.108912)
			(xy 101.489556 -259.12496) (xy 101.438261 -259.133085) (xy 101.386327 -259.133085) (xy 101.335032 -259.12496)
			(xy 101.285639 -259.108912) (xy 101.239365 -259.085334) (xy 101.197349 -259.054808) (xy 101.160626 -259.018085)
			(xy 101.1301 -258.976069) (xy 101.106522 -258.929795) (xy 101.090474 -258.880402) (xy 101.082349 -258.829107)
			(xy 100.954078 -258.829107) (xy 100.954078 -259.283962) (xy 100.996496 -259.291074) (xy 101.021903 -259.295781)
			(xy 101.070945 -259.312044) (xy 101.116857 -259.335744) (xy 101.15852 -259.366303) (xy 101.194917 -259.402975)
			(xy 101.225161 -259.444867) (xy 101.248514 -259.490957) (xy 101.264407 -259.54012) (xy 101.272452 -259.591159)
			(xy 101.272454 -259.642827) (xy 101.264411 -259.693866) (xy 101.25518 -259.722425) (xy 102.536499 -259.722425)
			(xy 102.536499 -259.670491) (xy 102.544624 -259.619196) (xy 102.560672 -259.569803) (xy 102.58425 -259.523529)
			(xy 102.614776 -259.481513) (xy 102.651499 -259.44479) (xy 102.693515 -259.414264) (xy 102.739789 -259.390686)
			(xy 102.789182 -259.374638) (xy 102.840477 -259.366513) (xy 102.892411 -259.366513) (xy 102.943706 -259.374638)
			(xy 102.993099 -259.390686) (xy 103.039373 -259.414264) (xy 103.081389 -259.44479) (xy 103.118112 -259.481513)
			(xy 103.148638 -259.523529) (xy 103.172216 -259.569803) (xy 103.188264 -259.619196) (xy 103.196389 -259.670491)
			(xy 103.196898 -259.696458) (xy 103.196389 -259.722425) (xy 103.188264 -259.77372) (xy 103.172216 -259.823113)
			(xy 103.148638 -259.869387) (xy 103.118112 -259.911403) (xy 103.081389 -259.948126) (xy 103.039373 -259.978652)
			(xy 102.993099 -260.00223) (xy 102.943706 -260.018278) (xy 102.892411 -260.026403) (xy 102.840477 -260.026403)
			(xy 102.789182 -260.018278) (xy 102.739789 -260.00223) (xy 102.693515 -259.978652) (xy 102.651499 -259.948126)
			(xy 102.614776 -259.911403) (xy 102.58425 -259.869387) (xy 102.560672 -259.823113) (xy 102.544624 -259.77372)
			(xy 102.536499 -259.722425) (xy 101.25518 -259.722425) (xy 101.24852 -259.74303) (xy 101.225169 -259.78912)
			(xy 101.194926 -259.831014) (xy 101.158531 -259.867688) (xy 101.116869 -259.898248) (xy 101.070958 -259.92195)
			(xy 101.021917 -259.938215) (xy 100.996496 -259.942838) (xy 100.954078 -259.94995) (xy 100.954078 -260.81609)
			(xy 101.08438 -260.946392) (xy 101.091492 -260.949948) (xy 101.114669 -260.962231) (xy 101.157149 -260.992997)
			(xy 101.194234 -261.030088) (xy 101.224994 -261.072573) (xy 101.237288 -261.095744) (xy 101.240844 -261.102856)
			(xy 101.365558 -261.22757) (xy 101.549454 -261.22757)
		)
		(stroke
			(width 0)
			(type solid)
		)
		(fill yes)
		(layer "In6.Cu")
		(net "PVCCD_HV_CPU1")
	)
	(gr_poly
		(pts
			(xy 371.62867 -270.37792) (xy 371.61216 -270.345408) (xy 371.601174 -270.322331) (xy 371.585656 -270.273636)
			(xy 371.577812 -270.223134) (xy 371.577362 -270.19758) (xy 371.577792 -270.173608) (xy 371.58473 -270.126169)
			(xy 371.598457 -270.080232) (xy 371.618684 -270.036764) (xy 371.631464 -270.016478) (xy 371.631464 -269.805658)
			(xy 371.630904 -269.790517) (xy 371.622022 -269.761566) (xy 371.605048 -269.736488) (xy 371.581473 -269.717481)
			(xy 371.553364 -269.706215) (xy 371.523189 -269.703676) (xy 371.508274 -269.706344) (xy 371.49084 -269.709918)
			(xy 371.455457 -269.713741) (xy 371.437662 -269.713964) (xy 371.411696 -269.713452) (xy 371.360404 -269.705323)
			(xy 371.311015 -269.68927) (xy 371.264745 -269.66569) (xy 371.222733 -269.635162) (xy 371.186014 -269.598438)
			(xy 371.15549 -269.556423) (xy 371.131915 -269.51015) (xy 371.115869 -269.460759) (xy 371.107745 -269.409466)
			(xy 371.107745 -269.357534) (xy 371.115869 -269.306241) (xy 371.131915 -269.25685) (xy 371.15549 -269.210577)
			(xy 371.186014 -269.168562) (xy 371.222733 -269.131838) (xy 371.264745 -269.10131) (xy 371.311015 -269.07773)
			(xy 371.360404 -269.061677) (xy 371.411696 -269.053548) (xy 371.437662 -269.053056) (xy 371.455456 -269.053293)
			(xy 371.490839 -269.057113) (xy 371.508274 -269.060676) (xy 371.523194 -269.063358) (xy 371.553386 -269.060842)
			(xy 371.581514 -269.049584) (xy 371.605103 -269.030572) (xy 371.622081 -269.005479) (xy 371.630955 -268.976511)
			(xy 371.631464 -268.961362) (xy 371.631464 -268.750796) (xy 371.616888 -268.727586) (xy 371.594812 -268.677426)
			(xy 371.581319 -268.62431) (xy 371.576781 -268.569695) (xy 371.581321 -268.51508) (xy 371.594815 -268.461964)
			(xy 371.616893 -268.411805) (xy 371.631464 -268.388592) (xy 371.631464 -268.178026) (xy 371.630913 -268.162878)
			(xy 371.622042 -268.133909) (xy 371.605071 -268.108813) (xy 371.58149 -268.089792) (xy 371.553371 -268.078516)
			(xy 371.523181 -268.075976) (xy 371.508274 -268.078712) (xy 371.49084 -268.082287) (xy 371.455457 -268.086109)
			(xy 371.437662 -268.086332) (xy 371.411698 -268.08582) (xy 371.360411 -268.077691) (xy 371.311027 -268.061641)
			(xy 371.264762 -268.038062) (xy 371.222754 -268.007537) (xy 371.186038 -267.970817) (xy 371.155518 -267.928806)
			(xy 371.131945 -267.882538) (xy 371.1159 -267.833152) (xy 371.107777 -267.781864) (xy 371.107777 -267.729936)
			(xy 371.1159 -267.678648) (xy 371.131945 -267.629262) (xy 371.155518 -267.582994) (xy 371.186038 -267.540983)
			(xy 371.222754 -267.504263) (xy 371.264762 -267.473738) (xy 371.311027 -267.450159) (xy 371.360411 -267.434109)
			(xy 371.411698 -267.42598) (xy 371.437662 -267.425424) (xy 371.455456 -267.425662) (xy 371.490838 -267.429482)
			(xy 371.508274 -267.433044) (xy 371.523192 -267.435726) (xy 371.553382 -267.433211) (xy 371.581506 -267.421952)
			(xy 371.605091 -267.402939) (xy 371.622062 -267.377845) (xy 371.630928 -267.348877) (xy 371.631464 -267.33373)
			(xy 371.631464 -267.12291) (xy 371.616887 -267.0997) (xy 371.594808 -267.04954) (xy 371.581313 -266.996423)
			(xy 371.576773 -266.941807) (xy 371.581311 -266.88719) (xy 371.594804 -266.834073) (xy 371.616881 -266.783911)
			(xy 371.631464 -266.760706) (xy 371.631464 -266.550394) (xy 371.630909 -266.535249) (xy 371.622033 -266.506289)
			(xy 371.60506 -266.481201) (xy 371.581482 -266.462187) (xy 371.553368 -266.450915) (xy 371.523185 -266.448376)
			(xy 371.508274 -266.45108) (xy 371.49084 -266.454655) (xy 371.455457 -266.458478) (xy 371.437662 -266.4587)
			(xy 371.411693 -266.458188) (xy 371.360396 -266.450058) (xy 371.311001 -266.434003) (xy 371.264726 -266.41042)
			(xy 371.22271 -266.379889) (xy 371.185986 -266.343161) (xy 371.15546 -266.301141) (xy 371.131882 -266.254864)
			(xy 371.115834 -266.205467) (xy 371.107709 -266.154169) (xy 371.107709 -266.102231) (xy 371.115834 -266.050933)
			(xy 371.131882 -266.001536) (xy 371.15546 -265.955259) (xy 371.185986 -265.913239) (xy 371.22271 -265.876511)
			(xy 371.264726 -265.84598) (xy 371.311001 -265.822397) (xy 371.360396 -265.806342) (xy 371.411693 -265.798212)
			(xy 371.437662 -265.797792) (xy 371.455456 -265.79803) (xy 371.490839 -265.801849) (xy 371.508274 -265.805412)
			(xy 371.523195 -265.808093) (xy 371.553391 -265.805577) (xy 371.581522 -265.79432) (xy 371.605117 -265.775309)
			(xy 371.622102 -265.750217) (xy 371.630985 -265.721248) (xy 371.631464 -265.706098) (xy 371.631464 -265.495278)
			(xy 371.61689 -265.472068) (xy 371.594816 -265.421909) (xy 371.581326 -265.368793) (xy 371.57679 -265.31418)
			(xy 371.581333 -265.259567) (xy 371.594829 -265.206453) (xy 371.616909 -265.156296) (xy 371.631464 -265.133074)
			(xy 371.631464 -264.922508) (xy 371.630911 -264.907362) (xy 371.622037 -264.878398) (xy 371.605065 -264.853306)
			(xy 371.581486 -264.834289) (xy 371.553369 -264.823016) (xy 371.523183 -264.820476) (xy 371.508274 -264.823194)
			(xy 371.49084 -264.826769) (xy 371.455457 -264.830592) (xy 371.437662 -264.830814) (xy 371.4117 -264.830302)
			(xy 371.360416 -264.822174) (xy 371.311034 -264.806124) (xy 371.264771 -264.782547) (xy 371.222765 -264.752024)
			(xy 371.186052 -264.715306) (xy 371.155533 -264.673296) (xy 371.131962 -264.627031) (xy 371.115917 -264.577647)
			(xy 371.107795 -264.526362) (xy 371.107795 -264.474438) (xy 371.115917 -264.423153) (xy 371.131962 -264.373769)
			(xy 371.155533 -264.327504) (xy 371.186052 -264.285494) (xy 371.222765 -264.248776) (xy 371.264771 -264.218253)
			(xy 371.311034 -264.194676) (xy 371.360416 -264.178626) (xy 371.4117 -264.170498) (xy 371.437662 -264.169906)
			(xy 371.455456 -264.170144) (xy 371.490839 -264.173964) (xy 371.508274 -264.177526) (xy 371.523191 -264.180208)
			(xy 371.553379 -264.177693) (xy 371.581501 -264.166434) (xy 371.605084 -264.147421) (xy 371.622052 -264.122326)
			(xy 371.630913 -264.093359) (xy 371.631464 -264.078212) (xy 371.631464 -263.867646) (xy 371.616884 -263.844436)
			(xy 371.594799 -263.794275) (xy 371.581299 -263.741156) (xy 371.576753 -263.686537) (xy 371.581287 -263.631917)
			(xy 371.594775 -263.578795) (xy 371.616849 -263.528628) (xy 371.631464 -263.505442) (xy 371.631464 -263.294622)
			(xy 371.630913 -263.279474) (xy 371.622041 -263.250507) (xy 371.60507 -263.225411) (xy 371.581489 -263.206391)
			(xy 371.55337 -263.195116) (xy 371.523181 -263.192576) (xy 371.508274 -263.195308) (xy 371.49084 -263.198883)
			(xy 371.455457 -263.202705) (xy 371.437662 -263.202928) (xy 371.411699 -263.202416) (xy 371.360412 -263.194288)
			(xy 371.311029 -263.178237) (xy 371.264764 -263.154659) (xy 371.222756 -263.124134) (xy 371.186041 -263.087415)
			(xy 371.155521 -263.045404) (xy 371.131949 -262.999136) (xy 371.115904 -262.949751) (xy 371.107781 -262.898463)
			(xy 371.107781 -262.846537) (xy 371.115904 -262.795249) (xy 371.131949 -262.745864) (xy 371.155521 -262.699596)
			(xy 371.186041 -262.657585) (xy 371.222756 -262.620866) (xy 371.264764 -262.590341) (xy 371.311029 -262.566763)
			(xy 371.360412 -262.550712) (xy 371.411699 -262.542584) (xy 371.437662 -262.54202) (xy 371.455456 -262.542258)
			(xy 371.490839 -262.546078) (xy 371.508274 -262.54964) (xy 371.523192 -262.552322) (xy 371.553381 -262.549807)
			(xy 371.581505 -262.538548) (xy 371.605089 -262.519535) (xy 371.62206 -262.494441) (xy 371.630924 -262.465473)
			(xy 371.631464 -262.450326) (xy 371.631464 -262.23976) (xy 371.621374 -262.223942) (xy 371.604444 -262.190459)
			(xy 371.597682 -262.172958) (xy 371.593872 -262.162544) (xy 371.464078 -262.03275) (xy 371.300502 -262.03275)
			(xy 371.297454 -262.080248) (xy 371.295243 -262.106353) (xy 371.283613 -262.157432) (xy 371.264069 -262.206036)
			(xy 371.237101 -262.250947) (xy 371.203383 -262.29104) (xy 371.16376 -262.32531) (xy 371.119227 -262.352897)
			(xy 371.070898 -262.373112) (xy 371.019984 -262.385447) (xy 370.967762 -262.389594) (xy 370.91554 -262.385447)
			(xy 370.864626 -262.373112) (xy 370.816297 -262.352897) (xy 370.771764 -262.32531) (xy 370.732141 -262.29104)
			(xy 370.698423 -262.250947) (xy 370.671455 -262.206036) (xy 370.651911 -262.157432) (xy 370.640281 -262.106353)
			(xy 370.63807 -262.080248) (xy 370.635022 -262.03275) (xy 370.360956 -262.03275) (xy 370.357908 -262.080248)
			(xy 370.355697 -262.106353) (xy 370.344067 -262.157432) (xy 370.324523 -262.206036) (xy 370.297555 -262.250947)
			(xy 370.263837 -262.29104) (xy 370.224214 -262.32531) (xy 370.179681 -262.352897) (xy 370.131352 -262.373112)
			(xy 370.080438 -262.385447) (xy 370.028216 -262.389594) (xy 369.975994 -262.385447) (xy 369.92508 -262.373112)
			(xy 369.876751 -262.352897) (xy 369.832218 -262.32531) (xy 369.792595 -262.29104) (xy 369.758877 -262.250947)
			(xy 369.731909 -262.206036) (xy 369.712365 -262.157432) (xy 369.700735 -262.106353) (xy 369.698524 -262.080248)
			(xy 369.695476 -262.03275) (xy 369.508278 -262.03275) (xy 369.165378 -261.68985) (xy 369.165378 -260.301486)
			(xy 369.079018 -260.215126) (xy 366.913922 -260.215126) (xy 366.28324 -260.845808) (xy 366.273091 -260.856691)
			(xy 366.259011 -260.882892) (xy 366.253064 -260.912037) (xy 366.255752 -260.941659) (xy 366.266849 -260.969257)
			(xy 366.285417 -260.992494) (xy 366.309884 -261.009408) (xy 366.32388 -261.014464) (xy 366.348489 -261.022911)
			(xy 366.394892 -261.04644) (xy 366.437036 -261.076947) (xy 366.473882 -261.113678) (xy 366.50452 -261.155727)
			(xy 366.528194 -261.202057) (xy 366.544319 -261.251522) (xy 366.552497 -261.302903) (xy 366.552988 -261.328916)
			(xy 366.552478 -261.354883) (xy 366.544351 -261.406178) (xy 366.528302 -261.455571) (xy 366.504724 -261.501845)
			(xy 366.474198 -261.543862) (xy 366.437475 -261.580586) (xy 366.395461 -261.611114) (xy 366.349188 -261.634695)
			(xy 366.299796 -261.650747) (xy 366.248501 -261.658876) (xy 366.222534 -261.65937) (xy 366.195235 -261.658811)
			(xy 366.141381 -261.649837) (xy 366.089735 -261.632128) (xy 366.041705 -261.606166) (xy 365.998599 -261.572659)
			(xy 365.97971 -261.552944) (xy 365.969877 -261.542964) (xy 365.945993 -261.528338) (xy 365.919037 -261.520739)
			(xy 365.891031 -261.520739) (xy 365.864075 -261.528338) (xy 365.840191 -261.542964) (xy 365.830358 -261.552944)
			(xy 365.814396 -261.569676) (xy 365.778609 -261.598962) (xy 365.739091 -261.622974) (xy 365.696611 -261.641244)
			(xy 365.674402 -261.647686) (xy 365.637064 -261.657846) (xy 365.637064 -263.083548) (xy 365.677704 -263.09193)
			(xy 365.702199 -263.097465) (xy 365.749275 -263.114944) (xy 365.793165 -263.139346) (xy 365.832856 -263.170108)
			(xy 365.867435 -263.206522) (xy 365.896105 -263.24775) (xy 365.918205 -263.292842) (xy 365.933228 -263.340759)
			(xy 365.940827 -263.390397) (xy 365.940827 -263.402123) (xy 366.329469 -263.402123) (xy 366.329469 -263.350189)
			(xy 366.337594 -263.298894) (xy 366.353642 -263.249501) (xy 366.37722 -263.203227) (xy 366.407746 -263.161211)
			(xy 366.444469 -263.124488) (xy 366.486485 -263.093962) (xy 366.532759 -263.070384) (xy 366.582152 -263.054336)
			(xy 366.633447 -263.046211) (xy 366.685381 -263.046211) (xy 366.736676 -263.054336) (xy 366.786069 -263.070384)
			(xy 366.832343 -263.093962) (xy 366.874359 -263.124488) (xy 366.911082 -263.161211) (xy 366.941608 -263.203227)
			(xy 366.965186 -263.249501) (xy 366.981234 -263.298894) (xy 366.981974 -263.303567) (xy 367.315759 -263.303567)
			(xy 367.315759 -263.251633) (xy 367.323883 -263.200339) (xy 367.339932 -263.150948) (xy 367.363509 -263.104675)
			(xy 367.394034 -263.062659) (xy 367.430756 -263.025937) (xy 367.472771 -262.995411) (xy 367.519044 -262.971833)
			(xy 367.568435 -262.955784) (xy 367.619729 -262.94766) (xy 367.645696 -262.94715) (xy 367.672209 -262.947689)
			(xy 367.724554 -262.956172) (xy 367.774866 -262.97292) (xy 367.798604 -262.984742) (xy 367.812288 -262.99133)
			(xy 367.842135 -262.996881) (xy 367.872296 -262.993424) (xy 367.900112 -262.981263) (xy 367.923131 -262.96147)
			(xy 367.9317 -262.948928) (xy 367.946989 -262.92579) (xy 367.984057 -262.884544) (xy 368.027492 -262.850066)
			(xy 368.076075 -262.823326) (xy 368.12844 -262.805073) (xy 368.183118 -262.795821) (xy 368.210846 -262.795258)
			(xy 368.236812 -262.795747) (xy 368.288103 -262.803877) (xy 368.337491 -262.81993) (xy 368.383761 -262.843511)
			(xy 368.425772 -262.87404) (xy 368.45017 -262.898441) (xy 369.228117 -262.898441) (xy 369.228117 -262.846507)
			(xy 369.236242 -262.795212) (xy 369.25229 -262.745819) (xy 369.275868 -262.699545) (xy 369.306394 -262.657529)
			(xy 369.343117 -262.620806) (xy 369.385133 -262.59028) (xy 369.431407 -262.566702) (xy 369.4808 -262.550654)
			(xy 369.532095 -262.542529) (xy 369.584029 -262.542529) (xy 369.635324 -262.550654) (xy 369.684717 -262.566702)
			(xy 369.730991 -262.59028) (xy 369.773007 -262.620806) (xy 369.80973 -262.657529) (xy 369.840256 -262.699545)
			(xy 369.863834 -262.745819) (xy 369.879882 -262.795212) (xy 369.888007 -262.846507) (xy 369.888516 -262.872474)
			(xy 369.888007 -262.898441) (xy 370.168171 -262.898441) (xy 370.168171 -262.846507) (xy 370.176296 -262.795212)
			(xy 370.192344 -262.745819) (xy 370.215922 -262.699545) (xy 370.246448 -262.657529) (xy 370.283171 -262.620806)
			(xy 370.325187 -262.59028) (xy 370.371461 -262.566702) (xy 370.420854 -262.550654) (xy 370.472149 -262.542529)
			(xy 370.524083 -262.542529) (xy 370.575378 -262.550654) (xy 370.624771 -262.566702) (xy 370.671045 -262.59028)
			(xy 370.713061 -262.620806) (xy 370.749784 -262.657529) (xy 370.78031 -262.699545) (xy 370.803888 -262.745819)
			(xy 370.819936 -262.795212) (xy 370.828061 -262.846507) (xy 370.82857 -262.872474) (xy 370.828061 -262.898441)
			(xy 370.819936 -262.949736) (xy 370.803888 -262.999129) (xy 370.78031 -263.045403) (xy 370.749784 -263.087419)
			(xy 370.713061 -263.124142) (xy 370.671045 -263.154668) (xy 370.624771 -263.178246) (xy 370.575378 -263.194294)
			(xy 370.524083 -263.202419) (xy 370.472149 -263.202419) (xy 370.420854 -263.194294) (xy 370.371461 -263.178246)
			(xy 370.325187 -263.154668) (xy 370.283171 -263.124142) (xy 370.246448 -263.087419) (xy 370.215922 -263.045403)
			(xy 370.192344 -262.999129) (xy 370.176296 -262.949736) (xy 370.168171 -262.898441) (xy 369.888007 -262.898441)
			(xy 369.879882 -262.949736) (xy 369.863834 -262.999129) (xy 369.840256 -263.045403) (xy 369.80973 -263.087419)
			(xy 369.773007 -263.124142) (xy 369.730991 -263.154668) (xy 369.684717 -263.178246) (xy 369.635324 -263.194294)
			(xy 369.584029 -263.202419) (xy 369.532095 -263.202419) (xy 369.4808 -263.194294) (xy 369.431407 -263.178246)
			(xy 369.385133 -263.154668) (xy 369.343117 -263.124142) (xy 369.306394 -263.087419) (xy 369.275868 -263.045403)
			(xy 369.25229 -262.999129) (xy 369.236242 -262.949736) (xy 369.228117 -262.898441) (xy 368.45017 -262.898441)
			(xy 368.46249 -262.910763) (xy 368.493013 -262.952779) (xy 368.516587 -262.999051) (xy 368.532634 -263.048442)
			(xy 368.540757 -263.099734) (xy 368.540757 -263.151666) (xy 368.532634 -263.202958) (xy 368.516587 -263.252349)
			(xy 368.493013 -263.298621) (xy 368.46249 -263.340637) (xy 368.425772 -263.37736) (xy 368.383761 -263.407889)
			(xy 368.337491 -263.43147) (xy 368.288103 -263.447523) (xy 368.236812 -263.455653) (xy 368.210846 -263.456166)
			(xy 368.184331 -263.455659) (xy 368.131986 -263.447164) (xy 368.081674 -263.430403) (xy 368.057938 -263.418574)
			(xy 368.044236 -263.412025) (xy 368.014398 -263.406464) (xy 367.984242 -263.409912) (xy 367.956428 -263.422064)
			(xy 367.933411 -263.44185) (xy 367.924842 -263.454388) (xy 367.909498 -263.477488) (xy 367.872444 -263.51874)
			(xy 367.829021 -263.553224) (xy 367.780449 -263.579972) (xy 367.728092 -263.598232) (xy 367.673421 -263.607492)
			(xy 367.645696 -263.608058) (xy 367.619729 -263.60754) (xy 367.568435 -263.599416) (xy 367.519044 -263.583367)
			(xy 367.472771 -263.559789) (xy 367.430756 -263.529263) (xy 367.394034 -263.492541) (xy 367.363509 -263.450525)
			(xy 367.339932 -263.404252) (xy 367.323883 -263.354861) (xy 367.315759 -263.303567) (xy 366.981974 -263.303567)
			(xy 366.989359 -263.350189) (xy 366.989868 -263.376156) (xy 366.989359 -263.402123) (xy 366.981234 -263.453418)
			(xy 366.965186 -263.502811) (xy 366.941608 -263.549085) (xy 366.911082 -263.591101) (xy 366.874359 -263.627824)
			(xy 366.832343 -263.65835) (xy 366.786069 -263.681928) (xy 366.736676 -263.697976) (xy 366.685381 -263.706101)
			(xy 366.633447 -263.706101) (xy 366.582152 -263.697976) (xy 366.532759 -263.681928) (xy 366.486485 -263.65835)
			(xy 366.444469 -263.627824) (xy 366.407746 -263.591101) (xy 366.37722 -263.549085) (xy 366.353642 -263.502811)
			(xy 366.337594 -263.453418) (xy 366.329469 -263.402123) (xy 365.940827 -263.402123) (xy 365.940826 -263.440614)
			(xy 365.933226 -263.490252) (xy 365.918202 -263.538168) (xy 365.896099 -263.583259) (xy 365.867428 -263.624486)
			(xy 365.832848 -263.660899) (xy 365.793156 -263.69166) (xy 365.75565 -263.712511) (xy 369.698271 -263.712511)
			(xy 369.698271 -263.660577) (xy 369.706396 -263.609282) (xy 369.722444 -263.559889) (xy 369.746022 -263.513615)
			(xy 369.776548 -263.471599) (xy 369.813271 -263.434876) (xy 369.855287 -263.40435) (xy 369.901561 -263.380772)
			(xy 369.950954 -263.364724) (xy 370.002249 -263.356599) (xy 370.054183 -263.356599) (xy 370.105478 -263.364724)
			(xy 370.154871 -263.380772) (xy 370.201145 -263.40435) (xy 370.243161 -263.434876) (xy 370.279884 -263.471599)
			(xy 370.31041 -263.513615) (xy 370.333988 -263.559889) (xy 370.350036 -263.609282) (xy 370.358161 -263.660577)
			(xy 370.35867 -263.686544) (xy 370.358161 -263.712511) (xy 370.637817 -263.712511) (xy 370.637817 -263.660577)
			(xy 370.645942 -263.609282) (xy 370.66199 -263.559889) (xy 370.685568 -263.513615) (xy 370.716094 -263.471599)
			(xy 370.752817 -263.434876) (xy 370.794833 -263.40435) (xy 370.841107 -263.380772) (xy 370.8905 -263.364724)
			(xy 370.941795 -263.356599) (xy 370.993729 -263.356599) (xy 371.045024 -263.364724) (xy 371.094417 -263.380772)
			(xy 371.140691 -263.40435) (xy 371.182707 -263.434876) (xy 371.21943 -263.471599) (xy 371.249956 -263.513615)
			(xy 371.273534 -263.559889) (xy 371.289582 -263.609282) (xy 371.297707 -263.660577) (xy 371.298216 -263.686544)
			(xy 371.297707 -263.712511) (xy 371.289582 -263.763806) (xy 371.273534 -263.813199) (xy 371.249956 -263.859473)
			(xy 371.21943 -263.901489) (xy 371.182707 -263.938212) (xy 371.140691 -263.968738) (xy 371.094417 -263.992316)
			(xy 371.045024 -264.008364) (xy 370.993729 -264.016489) (xy 370.941795 -264.016489) (xy 370.8905 -264.008364)
			(xy 370.841107 -263.992316) (xy 370.794833 -263.968738) (xy 370.752817 -263.938212) (xy 370.716094 -263.901489)
			(xy 370.685568 -263.859473) (xy 370.66199 -263.813199) (xy 370.645942 -263.763806) (xy 370.637817 -263.712511)
			(xy 370.358161 -263.712511) (xy 370.350036 -263.763806) (xy 370.333988 -263.813199) (xy 370.31041 -263.859473)
			(xy 370.279884 -263.901489) (xy 370.243161 -263.938212) (xy 370.201145 -263.968738) (xy 370.154871 -263.992316)
			(xy 370.105478 -264.008364) (xy 370.054183 -264.016489) (xy 370.002249 -264.016489) (xy 369.950954 -264.008364)
			(xy 369.901561 -263.992316) (xy 369.855287 -263.968738) (xy 369.813271 -263.938212) (xy 369.776548 -263.901489)
			(xy 369.746022 -263.859473) (xy 369.722444 -263.813199) (xy 369.706396 -263.763806) (xy 369.698271 -263.712511)
			(xy 365.75565 -263.712511) (xy 365.749266 -263.71606) (xy 365.702189 -263.733538) (xy 365.677704 -263.739122)
			(xy 365.637064 -263.747504) (xy 365.637064 -264.072624) (xy 365.637582 -264.087132) (xy 365.645754 -264.114973)
			(xy 365.661431 -264.139389) (xy 365.683345 -264.158406) (xy 365.709726 -264.170488) (xy 365.73844 -264.174658)
			(xy 365.752888 -264.173208) (xy 365.764321 -264.171688) (xy 365.787329 -264.170038) (xy 365.798862 -264.169906)
			(xy 365.824836 -264.170386) (xy 365.876146 -264.178507) (xy 365.925554 -264.194556) (xy 365.971842 -264.218136)
			(xy 366.013872 -264.248668) (xy 366.050607 -264.285399) (xy 366.081144 -264.327425) (xy 366.10473 -264.373711)
			(xy 366.120784 -264.423117) (xy 366.128911 -264.474426) (xy 366.128911 -264.526327) (xy 366.408717 -264.526327)
			(xy 366.408717 -264.474393) (xy 366.416842 -264.423098) (xy 366.43289 -264.373705) (xy 366.456468 -264.327431)
			(xy 366.486994 -264.285415) (xy 366.523717 -264.248692) (xy 366.565733 -264.218166) (xy 366.612007 -264.194588)
			(xy 366.6614 -264.17854) (xy 366.712695 -264.170415) (xy 366.764629 -264.170415) (xy 366.815924 -264.17854)
			(xy 366.865317 -264.194588) (xy 366.911591 -264.218166) (xy 366.953607 -264.248692) (xy 366.99033 -264.285415)
			(xy 367.020856 -264.327431) (xy 367.044434 -264.373705) (xy 367.060482 -264.423098) (xy 367.068607 -264.474393)
			(xy 367.069116 -264.50036) (xy 367.068607 -264.526327) (xy 367.348517 -264.526327) (xy 367.348517 -264.474393)
			(xy 367.356642 -264.423098) (xy 367.37269 -264.373705) (xy 367.396268 -264.327431) (xy 367.426794 -264.285415)
			(xy 367.463517 -264.248692) (xy 367.505533 -264.218166) (xy 367.551807 -264.194588) (xy 367.6012 -264.17854)
			(xy 367.652495 -264.170415) (xy 367.704429 -264.170415) (xy 367.755724 -264.17854) (xy 367.805117 -264.194588)
			(xy 367.851391 -264.218166) (xy 367.893407 -264.248692) (xy 367.93013 -264.285415) (xy 367.960656 -264.327431)
			(xy 367.984234 -264.373705) (xy 368.000282 -264.423098) (xy 368.008407 -264.474393) (xy 368.008916 -264.50036)
			(xy 368.008407 -264.526327) (xy 368.288317 -264.526327) (xy 368.288317 -264.474393) (xy 368.296442 -264.423098)
			(xy 368.31249 -264.373705) (xy 368.336068 -264.327431) (xy 368.366594 -264.285415) (xy 368.403317 -264.248692)
			(xy 368.445333 -264.218166) (xy 368.491607 -264.194588) (xy 368.541 -264.17854) (xy 368.592295 -264.170415)
			(xy 368.644229 -264.170415) (xy 368.695524 -264.17854) (xy 368.744917 -264.194588) (xy 368.791191 -264.218166)
			(xy 368.833207 -264.248692) (xy 368.86993 -264.285415) (xy 368.900456 -264.327431) (xy 368.924034 -264.373705)
			(xy 368.940082 -264.423098) (xy 368.948207 -264.474393) (xy 368.948716 -264.50036) (xy 368.948207 -264.526327)
			(xy 369.228117 -264.526327) (xy 369.228117 -264.474393) (xy 369.236242 -264.423098) (xy 369.25229 -264.373705)
			(xy 369.275868 -264.327431) (xy 369.306394 -264.285415) (xy 369.343117 -264.248692) (xy 369.385133 -264.218166)
			(xy 369.431407 -264.194588) (xy 369.4808 -264.17854) (xy 369.532095 -264.170415) (xy 369.584029 -264.170415)
			(xy 369.635324 -264.17854) (xy 369.684717 -264.194588) (xy 369.730991 -264.218166) (xy 369.773007 -264.248692)
			(xy 369.80973 -264.285415) (xy 369.840256 -264.327431) (xy 369.863834 -264.373705) (xy 369.879882 -264.423098)
			(xy 369.888007 -264.474393) (xy 369.888516 -264.50036) (xy 369.888007 -264.526327) (xy 370.167917 -264.526327)
			(xy 370.167917 -264.474393) (xy 370.176042 -264.423098) (xy 370.19209 -264.373705) (xy 370.215668 -264.327431)
			(xy 370.246194 -264.285415) (xy 370.282917 -264.248692) (xy 370.324933 -264.218166) (xy 370.371207 -264.194588)
			(xy 370.4206 -264.17854) (xy 370.471895 -264.170415) (xy 370.523829 -264.170415) (xy 370.575124 -264.17854)
			(xy 370.624517 -264.194588) (xy 370.670791 -264.218166) (xy 370.712807 -264.248692) (xy 370.74953 -264.285415)
			(xy 370.780056 -264.327431) (xy 370.803634 -264.373705) (xy 370.819682 -264.423098) (xy 370.827807 -264.474393)
			(xy 370.828316 -264.50036) (xy 370.827807 -264.526327) (xy 370.819682 -264.577622) (xy 370.803634 -264.627015)
			(xy 370.780056 -264.673289) (xy 370.74953 -264.715305) (xy 370.712807 -264.752028) (xy 370.670791 -264.782554)
			(xy 370.624517 -264.806132) (xy 370.575124 -264.82218) (xy 370.523829 -264.830305) (xy 370.471895 -264.830305)
			(xy 370.4206 -264.82218) (xy 370.371207 -264.806132) (xy 370.324933 -264.782554) (xy 370.282917 -264.752028)
			(xy 370.246194 -264.715305) (xy 370.215668 -264.673289) (xy 370.19209 -264.627015) (xy 370.176042 -264.577622)
			(xy 370.167917 -264.526327) (xy 369.888007 -264.526327) (xy 369.879882 -264.577622) (xy 369.863834 -264.627015)
			(xy 369.840256 -264.673289) (xy 369.80973 -264.715305) (xy 369.773007 -264.752028) (xy 369.730991 -264.782554)
			(xy 369.684717 -264.806132) (xy 369.635324 -264.82218) (xy 369.584029 -264.830305) (xy 369.532095 -264.830305)
			(xy 369.4808 -264.82218) (xy 369.431407 -264.806132) (xy 369.385133 -264.782554) (xy 369.343117 -264.752028)
			(xy 369.306394 -264.715305) (xy 369.275868 -264.673289) (xy 369.25229 -264.627015) (xy 369.236242 -264.577622)
			(xy 369.228117 -264.526327) (xy 368.948207 -264.526327) (xy 368.940082 -264.577622) (xy 368.924034 -264.627015)
			(xy 368.900456 -264.673289) (xy 368.86993 -264.715305) (xy 368.833207 -264.752028) (xy 368.791191 -264.782554)
			(xy 368.744917 -264.806132) (xy 368.695524 -264.82218) (xy 368.644229 -264.830305) (xy 368.592295 -264.830305)
			(xy 368.541 -264.82218) (xy 368.491607 -264.806132) (xy 368.445333 -264.782554) (xy 368.403317 -264.752028)
			(xy 368.366594 -264.715305) (xy 368.336068 -264.673289) (xy 368.31249 -264.627015) (xy 368.296442 -264.577622)
			(xy 368.288317 -264.526327) (xy 368.008407 -264.526327) (xy 368.000282 -264.577622) (xy 367.984234 -264.627015)
			(xy 367.960656 -264.673289) (xy 367.93013 -264.715305) (xy 367.893407 -264.752028) (xy 367.851391 -264.782554)
			(xy 367.805117 -264.806132) (xy 367.755724 -264.82218) (xy 367.704429 -264.830305) (xy 367.652495 -264.830305)
			(xy 367.6012 -264.82218) (xy 367.551807 -264.806132) (xy 367.505533 -264.782554) (xy 367.463517 -264.752028)
			(xy 367.426794 -264.715305) (xy 367.396268 -264.673289) (xy 367.37269 -264.627015) (xy 367.356642 -264.577622)
			(xy 367.348517 -264.526327) (xy 367.068607 -264.526327) (xy 367.060482 -264.577622) (xy 367.044434 -264.627015)
			(xy 367.020856 -264.673289) (xy 366.99033 -264.715305) (xy 366.953607 -264.752028) (xy 366.911591 -264.782554)
			(xy 366.865317 -264.806132) (xy 366.815924 -264.82218) (xy 366.764629 -264.830305) (xy 366.712695 -264.830305)
			(xy 366.6614 -264.82218) (xy 366.612007 -264.806132) (xy 366.565733 -264.782554) (xy 366.523717 -264.752028)
			(xy 366.486994 -264.715305) (xy 366.456468 -264.673289) (xy 366.43289 -264.627015) (xy 366.416842 -264.577622)
			(xy 366.408717 -264.526327) (xy 366.128911 -264.526327) (xy 366.128911 -264.526374) (xy 366.120784 -264.577683)
			(xy 366.10473 -264.627089) (xy 366.081144 -264.673375) (xy 366.050607 -264.715401) (xy 366.013872 -264.752132)
			(xy 365.971842 -264.782664) (xy 365.925554 -264.806244) (xy 365.876146 -264.822293) (xy 365.824836 -264.830414)
			(xy 365.798862 -264.830814) (xy 365.787328 -264.830701) (xy 365.764319 -264.829051) (xy 365.752888 -264.827512)
			(xy 365.73845 -264.825994) (xy 365.709738 -264.830187) (xy 365.683365 -264.842288) (xy 365.66146 -264.861319)
			(xy 365.645794 -264.885743) (xy 365.63763 -264.913588) (xy 365.637064 -264.928096) (xy 365.637064 -265.19378)
			(xy 365.640112 -265.202162) (xy 365.649234 -265.229263) (xy 365.659075 -265.285588) (xy 365.659079 -265.340143)
			(xy 365.938817 -265.340143) (xy 365.938817 -265.288209) (xy 365.946942 -265.236914) (xy 365.96299 -265.187521)
			(xy 365.986568 -265.141247) (xy 366.017094 -265.099231) (xy 366.053817 -265.062508) (xy 366.095833 -265.031982)
			(xy 366.142107 -265.008404) (xy 366.1915 -264.992356) (xy 366.242795 -264.984231) (xy 366.294729 -264.984231)
			(xy 366.346024 -264.992356) (xy 366.395417 -265.008404) (xy 366.441691 -265.031982) (xy 366.483707 -265.062508)
			(xy 366.52043 -265.099231) (xy 366.550956 -265.141247) (xy 366.574534 -265.187521) (xy 366.590582 -265.236914)
			(xy 366.598707 -265.288209) (xy 366.599216 -265.314176) (xy 366.598707 -265.340143) (xy 366.878871 -265.340143)
			(xy 366.878871 -265.288209) (xy 366.886996 -265.236914) (xy 366.903044 -265.187521) (xy 366.926622 -265.141247)
			(xy 366.957148 -265.099231) (xy 366.993871 -265.062508) (xy 367.035887 -265.031982) (xy 367.082161 -265.008404)
			(xy 367.131554 -264.992356) (xy 367.182849 -264.984231) (xy 367.234783 -264.984231) (xy 367.286078 -264.992356)
			(xy 367.335471 -265.008404) (xy 367.381745 -265.031982) (xy 367.423761 -265.062508) (xy 367.460484 -265.099231)
			(xy 367.49101 -265.141247) (xy 367.514588 -265.187521) (xy 367.530636 -265.236914) (xy 367.538761 -265.288209)
			(xy 367.53927 -265.314176) (xy 367.538761 -265.340143) (xy 367.818671 -265.340143) (xy 367.818671 -265.288209)
			(xy 367.826796 -265.236914) (xy 367.842844 -265.187521) (xy 367.866422 -265.141247) (xy 367.896948 -265.099231)
			(xy 367.933671 -265.062508) (xy 367.975687 -265.031982) (xy 368.021961 -265.008404) (xy 368.071354 -264.992356)
			(xy 368.122649 -264.984231) (xy 368.174583 -264.984231) (xy 368.225878 -264.992356) (xy 368.275271 -265.008404)
			(xy 368.321545 -265.031982) (xy 368.363561 -265.062508) (xy 368.400284 -265.099231) (xy 368.43081 -265.141247)
			(xy 368.454388 -265.187521) (xy 368.470436 -265.236914) (xy 368.478561 -265.288209) (xy 368.47907 -265.314176)
			(xy 368.478561 -265.340143) (xy 369.698271 -265.340143) (xy 369.698271 -265.288209) (xy 369.706396 -265.236914)
			(xy 369.722444 -265.187521) (xy 369.746022 -265.141247) (xy 369.776548 -265.099231) (xy 369.813271 -265.062508)
			(xy 369.855287 -265.031982) (xy 369.901561 -265.008404) (xy 369.950954 -264.992356) (xy 370.002249 -264.984231)
			(xy 370.054183 -264.984231) (xy 370.105478 -264.992356) (xy 370.154871 -265.008404) (xy 370.201145 -265.031982)
			(xy 370.243161 -265.062508) (xy 370.279884 -265.099231) (xy 370.31041 -265.141247) (xy 370.333988 -265.187521)
			(xy 370.350036 -265.236914) (xy 370.358161 -265.288209) (xy 370.35867 -265.314176) (xy 370.358161 -265.340143)
			(xy 370.638071 -265.340143) (xy 370.638071 -265.288209) (xy 370.646196 -265.236914) (xy 370.662244 -265.187521)
			(xy 370.685822 -265.141247) (xy 370.716348 -265.099231) (xy 370.753071 -265.062508) (xy 370.795087 -265.031982)
			(xy 370.841361 -265.008404) (xy 370.890754 -264.992356) (xy 370.942049 -264.984231) (xy 370.993983 -264.984231)
			(xy 371.045278 -264.992356) (xy 371.094671 -265.008404) (xy 371.140945 -265.031982) (xy 371.182961 -265.062508)
			(xy 371.219684 -265.099231) (xy 371.25021 -265.141247) (xy 371.273788 -265.187521) (xy 371.289836 -265.236914)
			(xy 371.297961 -265.288209) (xy 371.29847 -265.314176) (xy 371.297961 -265.340143) (xy 371.289836 -265.391438)
			(xy 371.273788 -265.440831) (xy 371.25021 -265.487105) (xy 371.219684 -265.529121) (xy 371.182961 -265.565844)
			(xy 371.140945 -265.59637) (xy 371.094671 -265.619948) (xy 371.045278 -265.635996) (xy 370.993983 -265.644121)
			(xy 370.942049 -265.644121) (xy 370.890754 -265.635996) (xy 370.841361 -265.619948) (xy 370.795087 -265.59637)
			(xy 370.753071 -265.565844) (xy 370.716348 -265.529121) (xy 370.685822 -265.487105) (xy 370.662244 -265.440831)
			(xy 370.646196 -265.391438) (xy 370.638071 -265.340143) (xy 370.358161 -265.340143) (xy 370.350036 -265.391438)
			(xy 370.333988 -265.440831) (xy 370.31041 -265.487105) (xy 370.279884 -265.529121) (xy 370.243161 -265.565844)
			(xy 370.201145 -265.59637) (xy 370.154871 -265.619948) (xy 370.105478 -265.635996) (xy 370.054183 -265.644121)
			(xy 370.002249 -265.644121) (xy 369.950954 -265.635996) (xy 369.901561 -265.619948) (xy 369.855287 -265.59637)
			(xy 369.813271 -265.565844) (xy 369.776548 -265.529121) (xy 369.746022 -265.487105) (xy 369.722444 -265.440831)
			(xy 369.706396 -265.391438) (xy 369.698271 -265.340143) (xy 368.478561 -265.340143) (xy 368.470436 -265.391438)
			(xy 368.454388 -265.440831) (xy 368.43081 -265.487105) (xy 368.400284 -265.529121) (xy 368.363561 -265.565844)
			(xy 368.321545 -265.59637) (xy 368.275271 -265.619948) (xy 368.225878 -265.635996) (xy 368.174583 -265.644121)
			(xy 368.122649 -265.644121) (xy 368.071354 -265.635996) (xy 368.021961 -265.619948) (xy 367.975687 -265.59637)
			(xy 367.933671 -265.565844) (xy 367.896948 -265.529121) (xy 367.866422 -265.487105) (xy 367.842844 -265.440831)
			(xy 367.826796 -265.391438) (xy 367.818671 -265.340143) (xy 367.538761 -265.340143) (xy 367.530636 -265.391438)
			(xy 367.514588 -265.440831) (xy 367.49101 -265.487105) (xy 367.460484 -265.529121) (xy 367.423761 -265.565844)
			(xy 367.381745 -265.59637) (xy 367.335471 -265.619948) (xy 367.286078 -265.635996) (xy 367.234783 -265.644121)
			(xy 367.182849 -265.644121) (xy 367.131554 -265.635996) (xy 367.082161 -265.619948) (xy 367.035887 -265.59637)
			(xy 366.993871 -265.565844) (xy 366.957148 -265.529121) (xy 366.926622 -265.487105) (xy 366.903044 -265.440831)
			(xy 366.886996 -265.391438) (xy 366.878871 -265.340143) (xy 366.598707 -265.340143) (xy 366.590582 -265.391438)
			(xy 366.574534 -265.440831) (xy 366.550956 -265.487105) (xy 366.52043 -265.529121) (xy 366.483707 -265.565844)
			(xy 366.441691 -265.59637) (xy 366.395417 -265.619948) (xy 366.346024 -265.635996) (xy 366.294729 -265.644121)
			(xy 366.242795 -265.644121) (xy 366.1915 -265.635996) (xy 366.142107 -265.619948) (xy 366.095833 -265.59637)
			(xy 366.053817 -265.565844) (xy 366.017094 -265.529121) (xy 365.986568 -265.487105) (xy 365.96299 -265.440831)
			(xy 365.946942 -265.391438) (xy 365.938817 -265.340143) (xy 365.659079 -265.340143) (xy 365.659079 -265.342767)
			(xy 365.649246 -265.399093) (xy 365.640112 -265.42619) (xy 365.637064 -265.434572) (xy 365.637064 -265.70051)
			(xy 365.63758 -265.715019) (xy 365.64575 -265.742864) (xy 365.661426 -265.767283) (xy 365.683341 -265.786304)
			(xy 365.709724 -265.798388) (xy 365.738441 -265.802558) (xy 365.752888 -265.801094) (xy 365.764321 -265.799574)
			(xy 365.787329 -265.797924) (xy 365.798862 -265.797792) (xy 365.82483 -265.798272) (xy 365.876126 -265.806391)
			(xy 365.925521 -265.822435) (xy 365.971797 -265.84601) (xy 366.013816 -265.876533) (xy 366.050542 -265.913255)
			(xy 366.08107 -265.95527) (xy 366.10465 -266.001544) (xy 366.1207 -266.050937) (xy 366.128825 -266.102232)
			(xy 366.128825 -266.154168) (xy 366.128778 -266.154467) (xy 366.408717 -266.154467) (xy 366.408717 -266.102533)
			(xy 366.416842 -266.051238) (xy 366.43289 -266.001845) (xy 366.456468 -265.955571) (xy 366.486994 -265.913555)
			(xy 366.523717 -265.876832) (xy 366.565733 -265.846306) (xy 366.612007 -265.822728) (xy 366.6614 -265.80668)
			(xy 366.712695 -265.798555) (xy 366.764629 -265.798555) (xy 366.815924 -265.80668) (xy 366.865317 -265.822728)
			(xy 366.911591 -265.846306) (xy 366.953607 -265.876832) (xy 366.99033 -265.913555) (xy 367.020856 -265.955571)
			(xy 367.044434 -266.001845) (xy 367.060482 -266.051238) (xy 367.068607 -266.102533) (xy 367.069116 -266.1285)
			(xy 367.068612 -266.154213) (xy 367.348517 -266.154213) (xy 367.348517 -266.102279) (xy 367.356642 -266.050984)
			(xy 367.37269 -266.001591) (xy 367.396268 -265.955317) (xy 367.426794 -265.913301) (xy 367.463517 -265.876578)
			(xy 367.505533 -265.846052) (xy 367.551807 -265.822474) (xy 367.6012 -265.806426) (xy 367.652495 -265.798301)
			(xy 367.704429 -265.798301) (xy 367.755724 -265.806426) (xy 367.805117 -265.822474) (xy 367.851391 -265.846052)
			(xy 367.893407 -265.876578) (xy 367.93013 -265.913301) (xy 367.960656 -265.955317) (xy 367.984234 -266.001591)
			(xy 368.000282 -266.050984) (xy 368.008407 -266.102279) (xy 368.008916 -266.128246) (xy 368.008407 -266.154213)
			(xy 368.288317 -266.154213) (xy 368.288317 -266.102279) (xy 368.296442 -266.050984) (xy 368.31249 -266.001591)
			(xy 368.336068 -265.955317) (xy 368.366594 -265.913301) (xy 368.403317 -265.876578) (xy 368.445333 -265.846052)
			(xy 368.491607 -265.822474) (xy 368.541 -265.806426) (xy 368.592295 -265.798301) (xy 368.644229 -265.798301)
			(xy 368.695524 -265.806426) (xy 368.744917 -265.822474) (xy 368.791191 -265.846052) (xy 368.833207 -265.876578)
			(xy 368.86993 -265.913301) (xy 368.900456 -265.955317) (xy 368.924034 -266.001591) (xy 368.940082 -266.050984)
			(xy 368.948207 -266.102279) (xy 368.948716 -266.128246) (xy 368.948207 -266.154213) (xy 370.167917 -266.154213)
			(xy 370.167917 -266.102279) (xy 370.176042 -266.050984) (xy 370.19209 -266.001591) (xy 370.215668 -265.955317)
			(xy 370.246194 -265.913301) (xy 370.282917 -265.876578) (xy 370.324933 -265.846052) (xy 370.371207 -265.822474)
			(xy 370.4206 -265.806426) (xy 370.471895 -265.798301) (xy 370.523829 -265.798301) (xy 370.575124 -265.806426)
			(xy 370.624517 -265.822474) (xy 370.670791 -265.846052) (xy 370.712807 -265.876578) (xy 370.74953 -265.913301)
			(xy 370.780056 -265.955317) (xy 370.803634 -266.001591) (xy 370.819682 -266.050984) (xy 370.827807 -266.102279)
			(xy 370.828316 -266.128246) (xy 370.827807 -266.154213) (xy 370.819682 -266.205508) (xy 370.803634 -266.254901)
			(xy 370.780056 -266.301175) (xy 370.74953 -266.343191) (xy 370.712807 -266.379914) (xy 370.670791 -266.41044)
			(xy 370.624517 -266.434018) (xy 370.575124 -266.450066) (xy 370.523829 -266.458191) (xy 370.471895 -266.458191)
			(xy 370.4206 -266.450066) (xy 370.371207 -266.434018) (xy 370.324933 -266.41044) (xy 370.282917 -266.379914)
			(xy 370.246194 -266.343191) (xy 370.215668 -266.301175) (xy 370.19209 -266.254901) (xy 370.176042 -266.205508)
			(xy 370.167917 -266.154213) (xy 368.948207 -266.154213) (xy 368.940082 -266.205508) (xy 368.924034 -266.254901)
			(xy 368.900456 -266.301175) (xy 368.86993 -266.343191) (xy 368.833207 -266.379914) (xy 368.791191 -266.41044)
			(xy 368.744917 -266.434018) (xy 368.695524 -266.450066) (xy 368.644229 -266.458191) (xy 368.592295 -266.458191)
			(xy 368.541 -266.450066) (xy 368.491607 -266.434018) (xy 368.445333 -266.41044) (xy 368.403317 -266.379914)
			(xy 368.366594 -266.343191) (xy 368.336068 -266.301175) (xy 368.31249 -266.254901) (xy 368.296442 -266.205508)
			(xy 368.288317 -266.154213) (xy 368.008407 -266.154213) (xy 368.000282 -266.205508) (xy 367.984234 -266.254901)
			(xy 367.960656 -266.301175) (xy 367.93013 -266.343191) (xy 367.893407 -266.379914) (xy 367.851391 -266.41044)
			(xy 367.805117 -266.434018) (xy 367.755724 -266.450066) (xy 367.704429 -266.458191) (xy 367.652495 -266.458191)
			(xy 367.6012 -266.450066) (xy 367.551807 -266.434018) (xy 367.505533 -266.41044) (xy 367.463517 -266.379914)
			(xy 367.426794 -266.343191) (xy 367.396268 -266.301175) (xy 367.37269 -266.254901) (xy 367.356642 -266.205508)
			(xy 367.348517 -266.154213) (xy 367.068612 -266.154213) (xy 367.068607 -266.154467) (xy 367.060482 -266.205762)
			(xy 367.044434 -266.255155) (xy 367.020856 -266.301429) (xy 366.99033 -266.343445) (xy 366.953607 -266.380168)
			(xy 366.911591 -266.410694) (xy 366.865317 -266.434272) (xy 366.815924 -266.45032) (xy 366.764629 -266.458445)
			(xy 366.712695 -266.458445) (xy 366.6614 -266.45032) (xy 366.612007 -266.434272) (xy 366.565733 -266.410694)
			(xy 366.523717 -266.380168) (xy 366.486994 -266.343445) (xy 366.456468 -266.301429) (xy 366.43289 -266.255155)
			(xy 366.416842 -266.205762) (xy 366.408717 -266.154467) (xy 366.128778 -266.154467) (xy 366.1207 -266.205463)
			(xy 366.10465 -266.254856) (xy 366.08107 -266.30113) (xy 366.050542 -266.343145) (xy 366.013816 -266.379867)
			(xy 365.971797 -266.41039) (xy 365.925521 -266.433965) (xy 365.876126 -266.450009) (xy 365.82483 -266.458128)
			(xy 365.798862 -266.4587) (xy 365.787328 -266.458587) (xy 365.764319 -266.456937) (xy 365.752888 -266.455398)
			(xy 365.738449 -266.45388) (xy 365.709736 -266.458074) (xy 365.683361 -266.470174) (xy 365.661455 -266.489204)
			(xy 365.645785 -266.513628) (xy 365.637618 -266.541473) (xy 365.637064 -266.555982) (xy 365.637064 -266.821412)
			(xy 365.640112 -266.829794) (xy 365.649232 -266.856895) (xy 365.659067 -266.913219) (xy 365.659066 -266.967775)
			(xy 365.938563 -266.967775) (xy 365.938563 -266.915841) (xy 365.946688 -266.864546) (xy 365.962736 -266.815153)
			(xy 365.986314 -266.768879) (xy 366.01684 -266.726863) (xy 366.053563 -266.69014) (xy 366.095579 -266.659614)
			(xy 366.141853 -266.636036) (xy 366.191246 -266.619988) (xy 366.242541 -266.611863) (xy 366.294475 -266.611863)
			(xy 366.34577 -266.619988) (xy 366.395163 -266.636036) (xy 366.441437 -266.659614) (xy 366.483453 -266.69014)
			(xy 366.520176 -266.726863) (xy 366.550702 -266.768879) (xy 366.57428 -266.815153) (xy 366.590328 -266.864546)
			(xy 366.598453 -266.915841) (xy 366.598962 -266.941808) (xy 366.598453 -266.967775) (xy 369.698271 -266.967775)
			(xy 369.698271 -266.915841) (xy 369.706396 -266.864546) (xy 369.722444 -266.815153) (xy 369.746022 -266.768879)
			(xy 369.776548 -266.726863) (xy 369.813271 -266.69014) (xy 369.855287 -266.659614) (xy 369.901561 -266.636036)
			(xy 369.950954 -266.619988) (xy 370.002249 -266.611863) (xy 370.054183 -266.611863) (xy 370.105478 -266.619988)
			(xy 370.154871 -266.636036) (xy 370.201145 -266.659614) (xy 370.243161 -266.69014) (xy 370.279884 -266.726863)
			(xy 370.31041 -266.768879) (xy 370.333988 -266.815153) (xy 370.350036 -266.864546) (xy 370.358161 -266.915841)
			(xy 370.35867 -266.941808) (xy 370.358161 -266.967775) (xy 370.638071 -266.967775) (xy 370.638071 -266.915841)
			(xy 370.646196 -266.864546) (xy 370.662244 -266.815153) (xy 370.685822 -266.768879) (xy 370.716348 -266.726863)
			(xy 370.753071 -266.69014) (xy 370.795087 -266.659614) (xy 370.841361 -266.636036) (xy 370.890754 -266.619988)
			(xy 370.942049 -266.611863) (xy 370.993983 -266.611863) (xy 371.045278 -266.619988) (xy 371.094671 -266.636036)
			(xy 371.140945 -266.659614) (xy 371.182961 -266.69014) (xy 371.219684 -266.726863) (xy 371.25021 -266.768879)
			(xy 371.273788 -266.815153) (xy 371.289836 -266.864546) (xy 371.297961 -266.915841) (xy 371.29847 -266.941808)
			(xy 371.297961 -266.967775) (xy 371.289836 -267.01907) (xy 371.273788 -267.068463) (xy 371.25021 -267.114737)
			(xy 371.219684 -267.156753) (xy 371.182961 -267.193476) (xy 371.140945 -267.224002) (xy 371.094671 -267.24758)
			(xy 371.045278 -267.263628) (xy 370.993983 -267.271753) (xy 370.942049 -267.271753) (xy 370.890754 -267.263628)
			(xy 370.841361 -267.24758) (xy 370.795087 -267.224002) (xy 370.753071 -267.193476) (xy 370.716348 -267.156753)
			(xy 370.685822 -267.114737) (xy 370.662244 -267.068463) (xy 370.646196 -267.01907) (xy 370.638071 -266.967775)
			(xy 370.358161 -266.967775) (xy 370.350036 -267.01907) (xy 370.333988 -267.068463) (xy 370.31041 -267.114737)
			(xy 370.279884 -267.156753) (xy 370.243161 -267.193476) (xy 370.201145 -267.224002) (xy 370.154871 -267.24758)
			(xy 370.105478 -267.263628) (xy 370.054183 -267.271753) (xy 370.002249 -267.271753) (xy 369.950954 -267.263628)
			(xy 369.901561 -267.24758) (xy 369.855287 -267.224002) (xy 369.813271 -267.193476) (xy 369.776548 -267.156753)
			(xy 369.746022 -267.114737) (xy 369.722444 -267.068463) (xy 369.706396 -267.01907) (xy 369.698271 -266.967775)
			(xy 366.598453 -266.967775) (xy 366.590328 -267.01907) (xy 366.57428 -267.068463) (xy 366.550702 -267.114737)
			(xy 366.520176 -267.156753) (xy 366.483453 -267.193476) (xy 366.441437 -267.224002) (xy 366.395163 -267.24758)
			(xy 366.34577 -267.263628) (xy 366.294475 -267.271753) (xy 366.242541 -267.271753) (xy 366.191246 -267.263628)
			(xy 366.141853 -267.24758) (xy 366.095579 -267.224002) (xy 366.053563 -267.193476) (xy 366.01684 -267.156753)
			(xy 365.986314 -267.114737) (xy 365.962736 -267.068463) (xy 365.946688 -267.01907) (xy 365.938563 -266.967775)
			(xy 365.659066 -266.967775) (xy 365.659066 -266.970396) (xy 365.649228 -267.026719) (xy 365.640112 -267.053822)
			(xy 365.637064 -267.062204) (xy 365.637064 -267.328142) (xy 365.637571 -267.342658) (xy 365.64573 -267.370519)
			(xy 365.661403 -267.394956) (xy 365.683322 -267.413992) (xy 365.709715 -267.426085) (xy 365.738444 -267.430258)
			(xy 365.752888 -267.428726) (xy 365.764321 -267.427206) (xy 365.787329 -267.425556) (xy 365.798862 -267.425424)
			(xy 365.824835 -267.425904) (xy 365.876142 -267.434025) (xy 365.925547 -267.450072) (xy 365.971833 -267.473652)
			(xy 366.01386 -267.504182) (xy 366.050594 -267.540911) (xy 366.081128 -267.582935) (xy 366.104713 -267.629218)
			(xy 366.120766 -267.678621) (xy 366.128893 -267.729927) (xy 366.128893 -267.781845) (xy 367.348517 -267.781845)
			(xy 367.348517 -267.729911) (xy 367.356642 -267.678616) (xy 367.37269 -267.629223) (xy 367.396268 -267.582949)
			(xy 367.426794 -267.540933) (xy 367.463517 -267.50421) (xy 367.505533 -267.473684) (xy 367.551807 -267.450106)
			(xy 367.6012 -267.434058) (xy 367.652495 -267.425933) (xy 367.704429 -267.425933) (xy 367.755724 -267.434058)
			(xy 367.805117 -267.450106) (xy 367.851391 -267.473684) (xy 367.893407 -267.50421) (xy 367.93013 -267.540933)
			(xy 367.960656 -267.582949) (xy 367.984234 -267.629223) (xy 368.000282 -267.678616) (xy 368.008407 -267.729911)
			(xy 368.008916 -267.755878) (xy 368.008407 -267.781845) (xy 368.000282 -267.83314) (xy 367.984234 -267.882533)
			(xy 367.960656 -267.928807) (xy 367.93013 -267.970823) (xy 367.893407 -268.007546) (xy 367.851391 -268.038072)
			(xy 367.805117 -268.06165) (xy 367.755724 -268.077698) (xy 367.704429 -268.085823) (xy 367.652495 -268.085823)
			(xy 367.6012 -268.077698) (xy 367.551807 -268.06165) (xy 367.505533 -268.038072) (xy 367.463517 -268.007546)
			(xy 367.426794 -267.970823) (xy 367.396268 -267.928807) (xy 367.37269 -267.882533) (xy 367.356642 -267.83314)
			(xy 367.348517 -267.781845) (xy 366.128893 -267.781845) (xy 366.128893 -267.781873) (xy 366.120766 -267.833179)
			(xy 366.104713 -267.882582) (xy 366.081128 -267.928865) (xy 366.050594 -267.970889) (xy 366.01386 -268.007618)
			(xy 365.971833 -268.038148) (xy 365.925547 -268.061728) (xy 365.876142 -268.077775) (xy 365.824835 -268.085896)
			(xy 365.798862 -268.086332) (xy 365.787328 -268.086219) (xy 365.764319 -268.084569) (xy 365.752888 -268.08303)
			(xy 365.738451 -268.081512) (xy 365.709741 -268.085706) (xy 365.68337 -268.097807) (xy 365.661468 -268.116838)
			(xy 365.645805 -268.141262) (xy 365.637646 -268.169106) (xy 365.637064 -268.183614) (xy 365.637064 -268.449806)
			(xy 365.640112 -268.458188) (xy 365.649134 -268.485177) (xy 365.658847 -268.541243) (xy 365.659416 -268.569694)
			(xy 365.658897 -268.595661) (xy 365.939071 -268.595661) (xy 365.939071 -268.543727) (xy 365.947196 -268.492432)
			(xy 365.963244 -268.443039) (xy 365.986822 -268.396765) (xy 366.017348 -268.354749) (xy 366.054071 -268.318026)
			(xy 366.096087 -268.2875) (xy 366.142361 -268.263922) (xy 366.191754 -268.247874) (xy 366.243049 -268.239749)
			(xy 366.294983 -268.239749) (xy 366.346278 -268.247874) (xy 366.395671 -268.263922) (xy 366.441945 -268.2875)
			(xy 366.483961 -268.318026) (xy 366.520684 -268.354749) (xy 366.55121 -268.396765) (xy 366.574788 -268.443039)
			(xy 366.590836 -268.492432) (xy 366.598961 -268.543727) (xy 366.59947 -268.569694) (xy 366.598961 -268.595661)
			(xy 370.637817 -268.595661) (xy 370.637817 -268.543727) (xy 370.645942 -268.492432) (xy 370.66199 -268.443039)
			(xy 370.685568 -268.396765) (xy 370.716094 -268.354749) (xy 370.752817 -268.318026) (xy 370.794833 -268.2875)
			(xy 370.841107 -268.263922) (xy 370.8905 -268.247874) (xy 370.941795 -268.239749) (xy 370.993729 -268.239749)
			(xy 371.045024 -268.247874) (xy 371.094417 -268.263922) (xy 371.140691 -268.2875) (xy 371.182707 -268.318026)
			(xy 371.21943 -268.354749) (xy 371.249956 -268.396765) (xy 371.273534 -268.443039) (xy 371.289582 -268.492432)
			(xy 371.297707 -268.543727) (xy 371.298216 -268.569694) (xy 371.297707 -268.595661) (xy 371.289582 -268.646956)
			(xy 371.273534 -268.696349) (xy 371.249956 -268.742623) (xy 371.21943 -268.784639) (xy 371.182707 -268.821362)
			(xy 371.140691 -268.851888) (xy 371.094417 -268.875466) (xy 371.045024 -268.891514) (xy 370.993729 -268.899639)
			(xy 370.941795 -268.899639) (xy 370.8905 -268.891514) (xy 370.841107 -268.875466) (xy 370.794833 -268.851888)
			(xy 370.752817 -268.821362) (xy 370.716094 -268.784639) (xy 370.685568 -268.742623) (xy 370.66199 -268.696349)
			(xy 370.645942 -268.646956) (xy 370.637817 -268.595661) (xy 366.598961 -268.595661) (xy 366.590836 -268.646956)
			(xy 366.574788 -268.696349) (xy 366.55121 -268.742623) (xy 366.520684 -268.784639) (xy 366.483961 -268.821362)
			(xy 366.441945 -268.851888) (xy 366.395671 -268.875466) (xy 366.346278 -268.891514) (xy 366.294983 -268.899639)
			(xy 366.243049 -268.899639) (xy 366.191754 -268.891514) (xy 366.142361 -268.875466) (xy 366.096087 -268.851888)
			(xy 366.054071 -268.821362) (xy 366.017348 -268.784639) (xy 365.986822 -268.742623) (xy 365.963244 -268.696349)
			(xy 365.947196 -268.646956) (xy 365.939071 -268.595661) (xy 365.658897 -268.595661) (xy 365.658847 -268.598145)
			(xy 365.649142 -268.654214) (xy 365.640112 -268.6812) (xy 365.637064 -268.689582) (xy 365.637064 -268.955774)
			(xy 365.637575 -268.970287) (xy 365.645739 -268.99814) (xy 365.661414 -269.022569) (xy 365.683331 -269.041597)
			(xy 365.709719 -269.053686) (xy 365.738443 -269.057858) (xy 365.752888 -269.056358) (xy 365.764384 -269.054831)
			(xy 365.787519 -269.05318) (xy 365.799116 -269.053056) (xy 365.825082 -269.053566) (xy 365.876373 -269.061692)
			(xy 365.925762 -269.077742) (xy 365.972032 -269.10132) (xy 366.014045 -269.131846) (xy 366.050765 -269.168567)
			(xy 366.081288 -269.210581) (xy 366.104864 -269.256853) (xy 366.120911 -269.306242) (xy 366.129035 -269.357534)
			(xy 366.129035 -269.409466) (xy 366.129033 -269.409477) (xy 368.288317 -269.409477) (xy 368.288317 -269.357543)
			(xy 368.296442 -269.306248) (xy 368.31249 -269.256855) (xy 368.336068 -269.210581) (xy 368.366594 -269.168565)
			(xy 368.403317 -269.131842) (xy 368.445333 -269.101316) (xy 368.491607 -269.077738) (xy 368.541 -269.06169)
			(xy 368.592295 -269.053565) (xy 368.644229 -269.053565) (xy 368.695524 -269.06169) (xy 368.744917 -269.077738)
			(xy 368.791191 -269.101316) (xy 368.833207 -269.131842) (xy 368.86993 -269.168565) (xy 368.900456 -269.210581)
			(xy 368.924034 -269.256855) (xy 368.940082 -269.306248) (xy 368.948207 -269.357543) (xy 368.948716 -269.38351)
			(xy 368.948207 -269.409477) (xy 370.167917 -269.409477) (xy 370.167917 -269.357543) (xy 370.176042 -269.306248)
			(xy 370.19209 -269.256855) (xy 370.215668 -269.210581) (xy 370.246194 -269.168565) (xy 370.282917 -269.131842)
			(xy 370.324933 -269.101316) (xy 370.371207 -269.077738) (xy 370.4206 -269.06169) (xy 370.471895 -269.053565)
			(xy 370.523829 -269.053565) (xy 370.575124 -269.06169) (xy 370.624517 -269.077738) (xy 370.670791 -269.101316)
			(xy 370.712807 -269.131842) (xy 370.74953 -269.168565) (xy 370.780056 -269.210581) (xy 370.803634 -269.256855)
			(xy 370.819682 -269.306248) (xy 370.827807 -269.357543) (xy 370.828316 -269.38351) (xy 370.827807 -269.409477)
			(xy 370.819682 -269.460772) (xy 370.803634 -269.510165) (xy 370.780056 -269.556439) (xy 370.74953 -269.598455)
			(xy 370.712807 -269.635178) (xy 370.670791 -269.665704) (xy 370.624517 -269.689282) (xy 370.575124 -269.70533)
			(xy 370.523829 -269.713455) (xy 370.471895 -269.713455) (xy 370.4206 -269.70533) (xy 370.371207 -269.689282)
			(xy 370.324933 -269.665704) (xy 370.282917 -269.635178) (xy 370.246194 -269.598455) (xy 370.215668 -269.556439)
			(xy 370.19209 -269.510165) (xy 370.176042 -269.460772) (xy 370.167917 -269.409477) (xy 368.948207 -269.409477)
			(xy 368.940082 -269.460772) (xy 368.924034 -269.510165) (xy 368.900456 -269.556439) (xy 368.86993 -269.598455)
			(xy 368.833207 -269.635178) (xy 368.791191 -269.665704) (xy 368.744917 -269.689282) (xy 368.695524 -269.70533)
			(xy 368.644229 -269.713455) (xy 368.592295 -269.713455) (xy 368.541 -269.70533) (xy 368.491607 -269.689282)
			(xy 368.445333 -269.665704) (xy 368.403317 -269.635178) (xy 368.366594 -269.598455) (xy 368.336068 -269.556439)
			(xy 368.31249 -269.510165) (xy 368.296442 -269.460772) (xy 368.288317 -269.409477) (xy 366.129033 -269.409477)
			(xy 366.120911 -269.460758) (xy 366.104864 -269.510147) (xy 366.081288 -269.556419) (xy 366.050765 -269.598433)
			(xy 366.014045 -269.635154) (xy 365.972032 -269.66568) (xy 365.925762 -269.689258) (xy 365.876373 -269.705308)
			(xy 365.825082 -269.713434) (xy 365.799116 -269.713964) (xy 365.787519 -269.713859) (xy 365.764382 -269.712209)
			(xy 365.752888 -269.710662) (xy 365.738448 -269.709145) (xy 365.709731 -269.713338) (xy 365.683352 -269.725437)
			(xy 365.66144 -269.744467) (xy 365.645764 -269.76889) (xy 365.637588 -269.796736) (xy 365.637064 -269.811246)
			(xy 365.637064 -270.077692) (xy 365.640112 -270.086074) (xy 365.643411 -270.095444) (xy 365.649002 -270.114507)
			(xy 365.651288 -270.124174) (xy 365.654336 -270.138398) (xy 365.765588 -270.24965) (xy 365.776324 -270.259713)
			(xy 365.802175 -270.273742) (xy 365.830954 -270.279812) (xy 365.860269 -270.27742) (xy 365.887683 -270.266763)
			(xy 365.910917 -270.248728) (xy 365.92804 -270.224814) (xy 365.937629 -270.197009) (xy 365.938816 -270.18234)
			(xy 365.940448 -270.157179) (xy 365.950389 -270.10775) (xy 365.967726 -270.060406) (xy 365.992056 -270.016246)
			(xy 366.022814 -269.976296) (xy 366.059285 -269.941484) (xy 366.100624 -269.912619) (xy 366.145868 -269.890371)
			(xy 366.193968 -269.875257) (xy 366.243806 -269.867627) (xy 366.269016 -269.867126) (xy 366.294984 -269.867637)
			(xy 366.34628 -269.875763) (xy 366.395674 -269.891814) (xy 366.441948 -269.915394) (xy 366.483964 -269.945923)
			(xy 366.520688 -269.982648) (xy 366.551214 -270.024666) (xy 366.574792 -270.070941) (xy 366.59084 -270.120335)
			(xy 366.598965 -270.171632) (xy 366.598965 -270.223547) (xy 370.638071 -270.223547) (xy 370.638071 -270.171613)
			(xy 370.646196 -270.120318) (xy 370.662244 -270.070925) (xy 370.685822 -270.024651) (xy 370.716348 -269.982635)
			(xy 370.753071 -269.945912) (xy 370.795087 -269.915386) (xy 370.841361 -269.891808) (xy 370.890754 -269.87576)
			(xy 370.942049 -269.867635) (xy 370.993983 -269.867635) (xy 371.045278 -269.87576) (xy 371.094671 -269.891808)
			(xy 371.140945 -269.915386) (xy 371.182961 -269.945912) (xy 371.219684 -269.982635) (xy 371.25021 -270.024651)
			(xy 371.273788 -270.070925) (xy 371.289836 -270.120318) (xy 371.297961 -270.171613) (xy 371.29847 -270.19758)
			(xy 371.297961 -270.223547) (xy 371.289836 -270.274842) (xy 371.273788 -270.324235) (xy 371.25021 -270.370509)
			(xy 371.219684 -270.412525) (xy 371.182961 -270.449248) (xy 371.140945 -270.479774) (xy 371.094671 -270.503352)
			(xy 371.045278 -270.5194) (xy 370.993983 -270.527525) (xy 370.942049 -270.527525) (xy 370.890754 -270.5194)
			(xy 370.841361 -270.503352) (xy 370.795087 -270.479774) (xy 370.753071 -270.449248) (xy 370.716348 -270.412525)
			(xy 370.685822 -270.370509) (xy 370.662244 -270.324235) (xy 370.646196 -270.274842) (xy 370.638071 -270.223547)
			(xy 366.598965 -270.223547) (xy 366.598965 -270.223568) (xy 366.59084 -270.274865) (xy 366.574792 -270.324259)
			(xy 366.551214 -270.370534) (xy 366.520688 -270.412552) (xy 366.483964 -270.449277) (xy 366.441948 -270.479806)
			(xy 366.395674 -270.503386) (xy 366.34628 -270.519437) (xy 366.294984 -270.527563) (xy 366.269016 -270.528034)
			(xy 366.241913 -270.527514) (xy 366.188427 -270.518713) (xy 366.16259 -270.510508) (xy 366.132872 -270.500348)
			(xy 366.074452 -270.558514) (xy 366.195864 -270.679926) (xy 371.326664 -270.679926)
		)
		(stroke
			(width 0)
			(type solid)
		)
		(fill yes)
		(layer "In6.Cu")
		(net "PVCCINFAON_CPU0")
	)
	(gr_poly
		(pts
			(xy 279.4 -78.10246) (xy 279.4 -73.8124) (xy 278.42464 -72.83704) (xy 278.42464 -62.987428) (xy 277.93696 -62.499748)
			(xy 277.24608 -62.499748) (xy 275.67128 -64.074548) (xy 275.61286 -64.074548) (xy 275.48967 -64.197738)
			(xy 275.471687 -64.215095) (xy 275.431276 -64.244502) (xy 275.386758 -64.267217) (xy 275.339231 -64.282677)
			(xy 275.289869 -64.290502) (xy 275.26488 -64.290956) (xy 265.178032 -64.290956) (xy 264.386314 -65.082674)
			(xy 264.363681 -65.104193) (xy 264.311741 -65.138852) (xy 264.28319 -65.151508) (xy 263.023604 -65.673224)
			(xy 262.352028 -66.3448) (xy 263.172954 -66.3448) (xy 263.177025 -66.289178) (xy 263.189151 -66.234741)
			(xy 263.209074 -66.18265) (xy 263.23637 -66.134015) (xy 263.270456 -66.089872) (xy 263.310605 -66.051163)
			(xy 263.355963 -66.018712) (xy 263.405563 -65.993211) (xy 263.458347 -65.975204) (xy 263.51319 -65.965074)
			(xy 263.568924 -65.963037) (xy 263.624361 -65.969137) (xy 263.678318 -65.983243) (xy 263.729647 -66.005055)
			(xy 263.777253 -66.034109) (xy 263.820121 -66.069784) (xy 263.857338 -66.111321) (xy 263.888111 -66.157834)
			(xy 263.911783 -66.208331) (xy 263.927851 -66.261738) (xy 263.930708 -66.281153) (xy 273.401246 -66.281153)
			(xy 273.401246 -66.226647) (xy 273.409003 -66.172697) (xy 273.424358 -66.120399) (xy 273.447 -66.070819)
			(xy 273.476467 -66.024965) (xy 273.512159 -65.983772) (xy 273.553351 -65.948078) (xy 273.599203 -65.918608)
			(xy 273.648782 -65.895964) (xy 273.701079 -65.880606) (xy 273.755029 -65.872847) (xy 273.782282 -65.87236)
			(xy 273.8112 -65.872868) (xy 273.868372 -65.881596) (xy 273.923572 -65.898855) (xy 273.975534 -65.924248)
			(xy 274.023068 -65.957194) (xy 274.065083 -65.996939) (xy 274.083272 -66.019426) (xy 274.093169 -66.031231)
			(xy 274.118493 -66.04875) (xy 274.147886 -66.057926) (xy 274.178678 -66.057926) (xy 274.208071 -66.04875)
			(xy 274.233395 -66.031231) (xy 274.243292 -66.019426) (xy 274.260045 -65.998643) (xy 274.298399 -65.961513)
			(xy 274.341553 -65.930091) (xy 274.388667 -65.904992) (xy 274.438819 -65.886706) (xy 274.49103 -65.875589)
			(xy 274.544282 -65.871859) (xy 274.597534 -65.875589) (xy 274.649745 -65.886706) (xy 274.699897 -65.904992)
			(xy 274.747011 -65.930091) (xy 274.790165 -65.961513) (xy 274.828519 -65.998643) (xy 274.845272 -66.019426)
			(xy 274.855169 -66.031231) (xy 274.880493 -66.04875) (xy 274.909886 -66.057926) (xy 274.940678 -66.057926)
			(xy 274.970071 -66.04875) (xy 274.995395 -66.031231) (xy 275.005292 -66.019426) (xy 275.023494 -65.996952)
			(xy 275.065511 -65.957215) (xy 275.113043 -65.924274) (xy 275.165002 -65.898884) (xy 275.220198 -65.881626)
			(xy 275.277367 -65.872896) (xy 275.306282 -65.87236) (xy 275.333533 -65.872886) (xy 275.387482 -65.88064)
			(xy 275.439777 -65.895993) (xy 275.489356 -65.918633) (xy 275.535207 -65.948098) (xy 275.576399 -65.983789)
			(xy 275.612091 -66.024978) (xy 275.641558 -66.070829) (xy 275.6642 -66.120406) (xy 275.679556 -66.172701)
			(xy 275.687313 -66.226649) (xy 275.687313 -66.281151) (xy 275.679556 -66.335099) (xy 275.6642 -66.387394)
			(xy 275.641558 -66.436971) (xy 275.612091 -66.482822) (xy 275.576399 -66.524011) (xy 275.535207 -66.559702)
			(xy 275.489356 -66.589167) (xy 275.439777 -66.611807) (xy 275.387482 -66.62716) (xy 275.333533 -66.634914)
			(xy 275.306282 -66.635376) (xy 275.277367 -66.634808) (xy 275.220197 -66.626091) (xy 275.164999 -66.608843)
			(xy 275.113037 -66.583461) (xy 275.065502 -66.550526) (xy 275.023483 -66.510792) (xy 275.005292 -66.48831)
			(xy 274.995395 -66.476505) (xy 274.970071 -66.458986) (xy 274.940678 -66.44981) (xy 274.909886 -66.44981)
			(xy 274.880493 -66.458986) (xy 274.855169 -66.476505) (xy 274.845272 -66.48831) (xy 274.828519 -66.509093)
			(xy 274.790165 -66.546223) (xy 274.747011 -66.577645) (xy 274.699897 -66.602744) (xy 274.649745 -66.62103)
			(xy 274.597534 -66.632147) (xy 274.544282 -66.635877) (xy 274.49103 -66.632147) (xy 274.438819 -66.62103)
			(xy 274.388667 -66.602744) (xy 274.341553 -66.577645) (xy 274.298399 -66.546223) (xy 274.260045 -66.509093)
			(xy 274.243292 -66.48831) (xy 274.233395 -66.476505) (xy 274.208071 -66.458986) (xy 274.178678 -66.44981)
			(xy 274.147886 -66.44981) (xy 274.118493 -66.458986) (xy 274.093169 -66.476505) (xy 274.083272 -66.48831)
			(xy 274.065099 -66.510809) (xy 274.023075 -66.550543) (xy 273.975537 -66.58348) (xy 273.923572 -66.608865)
			(xy 273.868371 -66.626118) (xy 273.811199 -66.634843) (xy 273.782282 -66.635376) (xy 273.755029 -66.634953)
			(xy 273.701079 -66.627194) (xy 273.648782 -66.611836) (xy 273.599203 -66.589192) (xy 273.553351 -66.559722)
			(xy 273.512159 -66.524028) (xy 273.476467 -66.482835) (xy 273.447 -66.436981) (xy 273.424358 -66.387401)
			(xy 273.409003 -66.335103) (xy 273.401246 -66.281153) (xy 263.930708 -66.281153) (xy 263.935971 -66.316914)
			(xy 263.93648 -66.3448) (xy 263.935971 -66.372686) (xy 263.927851 -66.427862) (xy 263.911783 -66.481269)
			(xy 263.888111 -66.531766) (xy 263.857338 -66.578279) (xy 263.820121 -66.619816) (xy 263.777253 -66.655491)
			(xy 263.729647 -66.684545) (xy 263.678318 -66.706357) (xy 263.624361 -66.720463) (xy 263.568924 -66.726563)
			(xy 263.51319 -66.724526) (xy 263.458347 -66.714396) (xy 263.405563 -66.696389) (xy 263.355963 -66.670888)
			(xy 263.310605 -66.638437) (xy 263.270456 -66.599728) (xy 263.23637 -66.555585) (xy 263.209074 -66.50695)
			(xy 263.189151 -66.454859) (xy 263.177025 -66.400422) (xy 263.172954 -66.3448) (xy 262.352028 -66.3448)
			(xy 262.13689 -66.559938) (xy 262.126805 -66.570714) (xy 262.112755 -66.596656) (xy 262.106691 -66.625527)
			(xy 262.109118 -66.654929) (xy 262.119834 -66.682416) (xy 262.137948 -66.705702) (xy 262.161953 -66.722852)
			(xy 262.175752 -66.728086) (xy 262.200507 -66.737024) (xy 262.247487 -66.760748) (xy 262.290761 -66.790703)
			(xy 262.329507 -66.826321) (xy 262.362991 -66.866927) (xy 262.390576 -66.911749) (xy 262.41174 -66.959936)
			(xy 262.42608 -67.010576) (xy 262.433324 -67.062705) (xy 262.433816 -67.08902) (xy 262.433329 -67.116271)
			(xy 262.42557 -67.170217) (xy 262.410213 -67.222509) (xy 262.387571 -67.272085) (xy 262.358104 -67.317933)
			(xy 262.322413 -67.359122) (xy 262.281223 -67.394812) (xy 262.240081 -67.421252) (xy 273.131024 -67.421252)
			(xy 273.135095 -67.36563) (xy 273.147221 -67.311193) (xy 273.167144 -67.259102) (xy 273.19444 -67.210467)
			(xy 273.228526 -67.166324) (xy 273.268675 -67.127615) (xy 273.314033 -67.095164) (xy 273.363633 -67.069663)
			(xy 273.416417 -67.051656) (xy 273.47126 -67.041526) (xy 273.526994 -67.039489) (xy 273.582431 -67.045589)
			(xy 273.636388 -67.059695) (xy 273.687717 -67.081507) (xy 273.735323 -67.110561) (xy 273.778191 -67.146236)
			(xy 273.815408 -67.187773) (xy 273.846181 -67.234286) (xy 273.869853 -67.284783) (xy 273.885921 -67.33819)
			(xy 273.894041 -67.393366) (xy 273.89455 -67.421252) (xy 274.020024 -67.421252) (xy 274.024095 -67.36563)
			(xy 274.036221 -67.311193) (xy 274.056144 -67.259102) (xy 274.08344 -67.210467) (xy 274.117526 -67.166324)
			(xy 274.157675 -67.127615) (xy 274.203033 -67.095164) (xy 274.252633 -67.069663) (xy 274.305417 -67.051656)
			(xy 274.36026 -67.041526) (xy 274.415994 -67.039489) (xy 274.471431 -67.045589) (xy 274.525388 -67.059695)
			(xy 274.576717 -67.081507) (xy 274.624323 -67.110561) (xy 274.667191 -67.146236) (xy 274.704408 -67.187773)
			(xy 274.735181 -67.234286) (xy 274.758853 -67.284783) (xy 274.774921 -67.33819) (xy 274.783041 -67.393366)
			(xy 274.78355 -67.421252) (xy 274.909024 -67.421252) (xy 274.913095 -67.36563) (xy 274.925221 -67.311193)
			(xy 274.945144 -67.259102) (xy 274.97244 -67.210467) (xy 275.006526 -67.166324) (xy 275.046675 -67.127615)
			(xy 275.092033 -67.095164) (xy 275.141633 -67.069663) (xy 275.194417 -67.051656) (xy 275.24926 -67.041526)
			(xy 275.304994 -67.039489) (xy 275.360431 -67.045589) (xy 275.414388 -67.059695) (xy 275.465717 -67.081507)
			(xy 275.513323 -67.110561) (xy 275.556191 -67.146236) (xy 275.593408 -67.187773) (xy 275.624181 -67.234286)
			(xy 275.647853 -67.284783) (xy 275.663921 -67.33819) (xy 275.672041 -67.393366) (xy 275.67255 -67.421252)
			(xy 275.672041 -67.449138) (xy 275.663921 -67.504314) (xy 275.647853 -67.557721) (xy 275.624181 -67.608218)
			(xy 275.593408 -67.654731) (xy 275.556191 -67.696268) (xy 275.513323 -67.731943) (xy 275.465717 -67.760997)
			(xy 275.414388 -67.782809) (xy 275.360431 -67.796915) (xy 275.304994 -67.803015) (xy 275.24926 -67.800978)
			(xy 275.194417 -67.790848) (xy 275.141633 -67.772841) (xy 275.092033 -67.74734) (xy 275.046675 -67.714889)
			(xy 275.006526 -67.67618) (xy 274.97244 -67.632037) (xy 274.945144 -67.583402) (xy 274.925221 -67.531311)
			(xy 274.913095 -67.476874) (xy 274.909024 -67.421252) (xy 274.78355 -67.421252) (xy 274.783041 -67.449138)
			(xy 274.774921 -67.504314) (xy 274.758853 -67.557721) (xy 274.735181 -67.608218) (xy 274.704408 -67.654731)
			(xy 274.667191 -67.696268) (xy 274.624323 -67.731943) (xy 274.576717 -67.760997) (xy 274.525388 -67.782809)
			(xy 274.471431 -67.796915) (xy 274.415994 -67.803015) (xy 274.36026 -67.800978) (xy 274.305417 -67.790848)
			(xy 274.252633 -67.772841) (xy 274.203033 -67.74734) (xy 274.157675 -67.714889) (xy 274.117526 -67.67618)
			(xy 274.08344 -67.632037) (xy 274.056144 -67.583402) (xy 274.036221 -67.531311) (xy 274.024095 -67.476874)
			(xy 274.020024 -67.421252) (xy 273.89455 -67.421252) (xy 273.894041 -67.449138) (xy 273.885921 -67.504314)
			(xy 273.869853 -67.557721) (xy 273.846181 -67.608218) (xy 273.815408 -67.654731) (xy 273.778191 -67.696268)
			(xy 273.735323 -67.731943) (xy 273.687717 -67.760997) (xy 273.636388 -67.782809) (xy 273.582431 -67.796915)
			(xy 273.526994 -67.803015) (xy 273.47126 -67.800978) (xy 273.416417 -67.790848) (xy 273.363633 -67.772841)
			(xy 273.314033 -67.74734) (xy 273.268675 -67.714889) (xy 273.228526 -67.67618) (xy 273.19444 -67.632037)
			(xy 273.167144 -67.583402) (xy 273.147221 -67.531311) (xy 273.135095 -67.476874) (xy 273.131024 -67.421252)
			(xy 262.240081 -67.421252) (xy 262.235374 -67.424277) (xy 262.185798 -67.446918) (xy 262.133505 -67.462273)
			(xy 262.079559 -67.47003) (xy 262.052308 -67.470528) (xy 262.02599 -67.470086) (xy 261.973852 -67.462849)
			(xy 261.923206 -67.448512) (xy 261.875011 -67.427347) (xy 261.830185 -67.399757) (xy 261.789578 -67.366264)
			(xy 261.753963 -67.327506) (xy 261.724015 -67.284219) (xy 261.700303 -67.237225) (xy 261.691374 -67.212464)
			(xy 261.686161 -67.198635) (xy 261.669064 -67.174543) (xy 261.645782 -67.15636) (xy 261.618265 -67.145612)
			(xy 261.588822 -67.143199) (xy 261.559923 -67.149324) (xy 261.53399 -67.163474) (xy 261.523226 -67.173602)
			(xy 261.26948 -67.427348) (xy 260.570726 -67.427348) (xy 260.549664 -67.443384) (xy 260.503735 -67.469704)
			(xy 260.454414 -67.48893) (xy 260.402789 -67.500638) (xy 260.35 -67.50457) (xy 260.297211 -67.500638)
			(xy 260.245586 -67.48893) (xy 260.196265 -67.469704) (xy 260.150336 -67.443384) (xy 260.129274 -67.427348)
			(xy 259.808726 -67.427348) (xy 259.787664 -67.443384) (xy 259.741735 -67.469704) (xy 259.692414 -67.48893)
			(xy 259.640789 -67.500638) (xy 259.588 -67.50457) (xy 259.535211 -67.500638) (xy 259.483586 -67.48893)
			(xy 259.434265 -67.469704) (xy 259.388336 -67.443384) (xy 259.367274 -67.427348) (xy 252.63348 -67.427348)
			(xy 251.582576 -68.478252) (xy 273.901646 -68.478252) (xy 273.901646 -68.423748) (xy 273.909402 -68.369799)
			(xy 273.924756 -68.317503) (xy 273.947397 -68.267924) (xy 273.976862 -68.222072) (xy 274.012552 -68.180879)
			(xy 274.053741 -68.145185) (xy 274.099591 -68.115715) (xy 274.149168 -68.09307) (xy 274.201462 -68.07771)
			(xy 274.25541 -68.069948) (xy 274.282662 -68.06946) (xy 274.311579 -68.069983) (xy 274.368751 -68.078708)
			(xy 274.423951 -68.095963) (xy 274.475913 -68.121354) (xy 274.523447 -68.154298) (xy 274.565463 -68.19404)
			(xy 274.583652 -68.216526) (xy 274.593549 -68.228331) (xy 274.618873 -68.24585) (xy 274.648266 -68.255026)
			(xy 274.679058 -68.255026) (xy 274.708451 -68.24585) (xy 274.733775 -68.228331) (xy 274.743672 -68.216526)
			(xy 274.761885 -68.194061) (xy 274.8039 -68.154324) (xy 274.85143 -68.121382) (xy 274.903387 -68.09599)
			(xy 274.958581 -68.07873) (xy 275.015747 -68.069997) (xy 275.044662 -68.06946) (xy 275.071914 -68.069985)
			(xy 275.125865 -68.077737) (xy 275.178163 -68.093088) (xy 275.227744 -68.115726) (xy 275.273598 -68.145191)
			(xy 275.314791 -68.180882) (xy 275.350486 -68.222072) (xy 275.379955 -68.267923) (xy 275.402599 -68.317501)
			(xy 275.417955 -68.369798) (xy 275.425713 -68.423748) (xy 275.425713 -68.478252) (xy 275.417955 -68.532202)
			(xy 275.402599 -68.584499) (xy 275.379955 -68.634077) (xy 275.350486 -68.679928) (xy 275.314791 -68.721118)
			(xy 275.273598 -68.756809) (xy 275.227744 -68.786274) (xy 275.178163 -68.808912) (xy 275.125865 -68.824263)
			(xy 275.071914 -68.832015) (xy 275.044662 -68.832476) (xy 275.015746 -68.831922) (xy 274.958576 -68.823202)
			(xy 274.903378 -68.805952) (xy 274.851416 -68.780567) (xy 274.803881 -68.747629) (xy 274.761863 -68.707893)
			(xy 274.743672 -68.68541) (xy 274.733775 -68.673605) (xy 274.708451 -68.656086) (xy 274.679058 -68.64691)
			(xy 274.648266 -68.64691) (xy 274.618873 -68.656086) (xy 274.593549 -68.673605) (xy 274.583652 -68.68541)
			(xy 274.565434 -68.707871) (xy 274.52342 -68.747607) (xy 274.47589 -68.780548) (xy 274.423934 -68.80594)
			(xy 274.368742 -68.823202) (xy 274.311576 -68.831937) (xy 274.282662 -68.832476) (xy 274.25541 -68.832052)
			(xy 274.201462 -68.82429) (xy 274.149168 -68.80893) (xy 274.099591 -68.786285) (xy 274.053741 -68.756815)
			(xy 274.012552 -68.721121) (xy 273.976862 -68.679928) (xy 273.947397 -68.634076) (xy 273.924756 -68.584497)
			(xy 273.909402 -68.532201) (xy 273.901646 -68.478252) (xy 251.582576 -68.478252) (xy 251.38888 -68.671948)
			(xy 246.96928 -68.671948) (xy 246.61368 -69.027548) (xy 246.61368 -69.562748) (xy 272.770626 -69.562748)
			(xy 272.770626 -69.508252) (xy 272.778382 -69.454311) (xy 272.793735 -69.402023) (xy 272.816373 -69.352452)
			(xy 272.845836 -69.306608) (xy 272.881523 -69.265423) (xy 272.922708 -69.229736) (xy 272.968552 -69.200273)
			(xy 273.018123 -69.177635) (xy 273.070411 -69.162282) (xy 273.124352 -69.154526) (xy 273.1516 -69.15404)
			(xy 273.180518 -69.154543) (xy 273.23769 -69.163273) (xy 273.29289 -69.180533) (xy 273.344852 -69.205928)
			(xy 273.392385 -69.238875) (xy 273.434401 -69.278619) (xy 273.45259 -69.301106) (xy 273.462487 -69.312911)
			(xy 273.487811 -69.33043) (xy 273.517204 -69.339606) (xy 273.547996 -69.339606) (xy 273.577389 -69.33043)
			(xy 273.602713 -69.312911) (xy 273.61261 -69.301106) (xy 273.629363 -69.280323) (xy 273.667717 -69.243193)
			(xy 273.710871 -69.211771) (xy 273.757985 -69.186672) (xy 273.808137 -69.168386) (xy 273.860348 -69.157269)
			(xy 273.9136 -69.153539) (xy 273.966852 -69.157269) (xy 274.019063 -69.168386) (xy 274.069215 -69.186672)
			(xy 274.116329 -69.211771) (xy 274.159483 -69.243193) (xy 274.197837 -69.280323) (xy 274.21459 -69.301106)
			(xy 274.224487 -69.312911) (xy 274.249811 -69.33043) (xy 274.279204 -69.339606) (xy 274.309996 -69.339606)
			(xy 274.339389 -69.33043) (xy 274.364713 -69.312911) (xy 274.37461 -69.301106) (xy 274.391363 -69.280323)
			(xy 274.429717 -69.243193) (xy 274.472871 -69.211771) (xy 274.519985 -69.186672) (xy 274.570137 -69.168386)
			(xy 274.622348 -69.157269) (xy 274.6756 -69.153539) (xy 274.728852 -69.157269) (xy 274.781063 -69.168386)
			(xy 274.831215 -69.186672) (xy 274.878329 -69.211771) (xy 274.921483 -69.243193) (xy 274.959837 -69.280323)
			(xy 274.97659 -69.301106) (xy 274.986487 -69.312911) (xy 275.011811 -69.33043) (xy 275.041204 -69.339606)
			(xy 275.071996 -69.339606) (xy 275.101389 -69.33043) (xy 275.126713 -69.312911) (xy 275.13661 -69.301106)
			(xy 275.153363 -69.280323) (xy 275.191717 -69.243193) (xy 275.234871 -69.211771) (xy 275.281985 -69.186672)
			(xy 275.332137 -69.168386) (xy 275.384348 -69.157269) (xy 275.4376 -69.153539) (xy 275.490852 -69.157269)
			(xy 275.543063 -69.168386) (xy 275.593215 -69.186672) (xy 275.640329 -69.211771) (xy 275.683483 -69.243193)
			(xy 275.721837 -69.280323) (xy 275.73859 -69.301106) (xy 275.748487 -69.312911) (xy 275.773811 -69.33043)
			(xy 275.803204 -69.339606) (xy 275.833996 -69.339606) (xy 275.863389 -69.33043) (xy 275.888713 -69.312911)
			(xy 275.89861 -69.301106) (xy 275.916797 -69.278619) (xy 275.958817 -69.238884) (xy 276.006353 -69.205945)
			(xy 276.058315 -69.180557) (xy 276.113514 -69.163302) (xy 276.170684 -69.154574) (xy 276.1996 -69.15404)
			(xy 276.226855 -69.15443) (xy 276.280809 -69.162187) (xy 276.333111 -69.177544) (xy 276.382694 -69.200188)
			(xy 276.42855 -69.229658) (xy 276.469746 -69.265354) (xy 276.505442 -69.30655) (xy 276.534912 -69.352406)
			(xy 276.557556 -69.401989) (xy 276.572913 -69.454291) (xy 276.58067 -69.508245) (xy 276.58067 -69.562755)
			(xy 276.572913 -69.616709) (xy 276.557556 -69.669011) (xy 276.534912 -69.718594) (xy 276.505442 -69.76445)
			(xy 276.469746 -69.805646) (xy 276.42855 -69.841342) (xy 276.382694 -69.870812) (xy 276.333111 -69.893456)
			(xy 276.280809 -69.908813) (xy 276.226855 -69.91657) (xy 276.1996 -69.917056) (xy 276.170682 -69.916554)
			(xy 276.11351 -69.907824) (xy 276.05831 -69.890564) (xy 276.006348 -69.865169) (xy 275.958814 -69.832222)
			(xy 275.916799 -69.792477) (xy 275.89861 -69.76999) (xy 275.888713 -69.758185) (xy 275.863389 -69.740666)
			(xy 275.833996 -69.73149) (xy 275.803204 -69.73149) (xy 275.773811 -69.740666) (xy 275.748487 -69.758185)
			(xy 275.73859 -69.76999) (xy 275.721837 -69.790773) (xy 275.683483 -69.827903) (xy 275.640329 -69.859325)
			(xy 275.593215 -69.884424) (xy 275.543063 -69.90271) (xy 275.490852 -69.913827) (xy 275.4376 -69.917557)
			(xy 275.384348 -69.913827) (xy 275.332137 -69.90271) (xy 275.281985 -69.884424) (xy 275.234871 -69.859325)
			(xy 275.191717 -69.827903) (xy 275.153363 -69.790773) (xy 275.13661 -69.76999) (xy 275.126713 -69.758185)
			(xy 275.101389 -69.740666) (xy 275.071996 -69.73149) (xy 275.041204 -69.73149) (xy 275.011811 -69.740666)
			(xy 274.986487 -69.758185) (xy 274.97659 -69.76999) (xy 274.959837 -69.790773) (xy 274.921483 -69.827903)
			(xy 274.878329 -69.859325) (xy 274.831215 -69.884424) (xy 274.781063 -69.90271) (xy 274.728852 -69.913827)
			(xy 274.6756 -69.917557) (xy 274.622348 -69.913827) (xy 274.570137 -69.90271) (xy 274.519985 -69.884424)
			(xy 274.472871 -69.859325) (xy 274.429717 -69.827903) (xy 274.391363 -69.790773) (xy 274.37461 -69.76999)
			(xy 274.364713 -69.758185) (xy 274.339389 -69.740666) (xy 274.309996 -69.73149) (xy 274.279204 -69.73149)
			(xy 274.249811 -69.740666) (xy 274.224487 -69.758185) (xy 274.21459 -69.76999) (xy 274.197837 -69.790773)
			(xy 274.159483 -69.827903) (xy 274.116329 -69.859325) (xy 274.069215 -69.884424) (xy 274.019063 -69.90271)
			(xy 273.966852 -69.913827) (xy 273.9136 -69.917557) (xy 273.860348 -69.913827) (xy 273.808137 -69.90271)
			(xy 273.757985 -69.884424) (xy 273.710871 -69.859325) (xy 273.667717 -69.827903) (xy 273.629363 -69.790773)
			(xy 273.61261 -69.76999) (xy 273.602713 -69.758185) (xy 273.577389 -69.740666) (xy 273.547996 -69.73149)
			(xy 273.517204 -69.73149) (xy 273.487811 -69.740666) (xy 273.462487 -69.758185) (xy 273.45259 -69.76999)
			(xy 273.434402 -69.792476) (xy 273.392382 -69.832212) (xy 273.344847 -69.865151) (xy 273.292885 -69.890539)
			(xy 273.237686 -69.907794) (xy 273.180516 -69.916522) (xy 273.1516 -69.917056) (xy 273.124352 -69.916474)
			(xy 273.070411 -69.908718) (xy 273.018123 -69.893365) (xy 272.968552 -69.870727) (xy 272.922708 -69.841264)
			(xy 272.881523 -69.805577) (xy 272.845836 -69.764392) (xy 272.816373 -69.718548) (xy 272.793735 -69.668977)
			(xy 272.778382 -69.616689) (xy 272.770626 -69.562748) (xy 246.61368 -69.562748) (xy 246.61368 -71.652384)
			(xy 247.39854 -71.652384) (xy 247.398982 -71.625711) (xy 247.406426 -71.572887) (xy 247.421154 -71.521615)
			(xy 247.442878 -71.472893) (xy 247.471175 -71.42767) (xy 247.505494 -71.386829) (xy 247.525032 -71.368666)
			(xy 247.535357 -71.35882) (xy 247.550505 -71.334654) (xy 247.558383 -71.307243) (xy 247.558378 -71.278722)
			(xy 247.550491 -71.251314) (xy 247.535335 -71.227153) (xy 247.525032 -71.217282) (xy 247.505486 -71.199126)
			(xy 247.471158 -71.15829) (xy 247.442856 -71.113068) (xy 247.421133 -71.064343) (xy 247.406413 -71.013066)
			(xy 247.398983 -70.960238) (xy 247.39854 -70.933564) (xy 247.398922 -70.906308) (xy 247.406685 -70.852352)
			(xy 247.422048 -70.800049) (xy 247.444698 -70.750466) (xy 247.474174 -70.70461) (xy 247.509876 -70.663417)
			(xy 247.551078 -70.627724) (xy 247.59694 -70.598258) (xy 247.646528 -70.575618) (xy 247.698834 -70.560267)
			(xy 247.752792 -70.552516) (xy 247.780048 -70.552056) (xy 247.806286 -70.552464) (xy 247.858265 -70.559667)
			(xy 247.908765 -70.57393) (xy 247.956831 -70.594984) (xy 248.001557 -70.622431) (xy 248.042096 -70.655752)
			(xy 248.06021 -70.674738) (xy 248.067739 -70.68211) (xy 248.087024 -70.690541) (xy 248.108072 -70.690541)
			(xy 248.127357 -70.68211) (xy 248.134886 -70.674738) (xy 248.160032 -70.649846) (xy 248.170378 -70.64002)
			(xy 248.185524 -70.615848) (xy 248.1934 -70.588432) (xy 248.193392 -70.559907) (xy 248.185499 -70.532495)
			(xy 248.170338 -70.508333) (xy 248.160032 -70.498462) (xy 248.140476 -70.480316) (xy 248.106149 -70.439478)
			(xy 248.077849 -70.394254) (xy 248.056128 -70.345527) (xy 248.04141 -70.294248) (xy 248.033982 -70.241419)
			(xy 248.03354 -70.214744) (xy 248.034026 -70.187493) (xy 248.041782 -70.133545) (xy 248.057137 -70.08125)
			(xy 248.079779 -70.031673) (xy 248.109245 -69.985823) (xy 248.144936 -69.944632) (xy 248.186127 -69.908941)
			(xy 248.231977 -69.879475) (xy 248.281554 -69.856833) (xy 248.333849 -69.841478) (xy 248.387797 -69.833722)
			(xy 248.442299 -69.833722) (xy 248.496247 -69.841478) (xy 248.548542 -69.856833) (xy 248.598119 -69.879475)
			(xy 248.643969 -69.908941) (xy 248.68516 -69.944632) (xy 248.720851 -69.985823) (xy 248.750317 -70.031673)
			(xy 248.772959 -70.08125) (xy 248.788314 -70.133545) (xy 248.79607 -70.187493) (xy 248.796556 -70.214744)
			(xy 248.796067 -70.241415) (xy 248.788632 -70.294237) (xy 248.773914 -70.345509) (xy 248.752199 -70.394231)
			(xy 248.72391 -70.439455) (xy 248.689599 -70.480298) (xy 248.670064 -70.498462) (xy 248.659811 -70.508377)
			(xy 248.644661 -70.532524) (xy 248.636774 -70.559917) (xy 248.636765 -70.588422) (xy 248.644635 -70.61582)
			(xy 248.659771 -70.639975) (xy 248.670064 -70.649846) (xy 248.689565 -70.668046) (xy 248.72388 -70.708882)
			(xy 248.752172 -70.7541) (xy 248.773889 -70.802819) (xy 248.788608 -70.854087) (xy 248.796041 -70.906906)
			(xy 248.796045 -70.960246) (xy 248.788618 -71.013066) (xy 248.773905 -71.064336) (xy 248.752194 -71.113057)
			(xy 248.723908 -71.158279) (xy 248.689599 -71.199119) (xy 248.670064 -71.217282) (xy 248.659791 -71.227178)
			(xy 248.644642 -71.25133) (xy 248.636757 -71.278728) (xy 248.636752 -71.307238) (xy 248.644627 -71.334638)
			(xy 248.659769 -71.358795) (xy 248.670064 -71.368666) (xy 248.689584 -71.386849) (xy 248.723915 -71.427679)
			(xy 248.75222 -71.472895) (xy 248.773947 -71.521615) (xy 248.788673 -71.572887) (xy 248.796109 -71.625712)
			(xy 248.796556 -71.652384) (xy 248.796094 -71.679035) (xy 248.788674 -71.731818) (xy 248.773975 -71.783053)
			(xy 248.763536 -71.807578) (xy 248.757906 -71.821707) (xy 248.754301 -71.85189) (xy 248.759721 -71.8818)
			(xy 248.773687 -71.9088) (xy 248.794967 -71.930506) (xy 248.821683 -71.945005) (xy 248.85148 -71.951017)
			(xy 248.86666 -71.950072) (xy 248.90476 -71.94804) (xy 248.932014 -71.948493) (xy 248.985968 -71.956245)
			(xy 249.038269 -71.971599) (xy 249.087852 -71.99424) (xy 249.133708 -72.023708) (xy 249.174902 -72.059404)
			(xy 249.210596 -72.100599) (xy 249.240064 -72.146455) (xy 249.262704 -72.196039) (xy 249.278056 -72.24834)
			(xy 249.285808 -72.302294) (xy 249.286268 -72.329548) (xy 249.285779 -72.356918) (xy 249.277968 -72.411096)
			(xy 249.262485 -72.463599) (xy 249.239648 -72.513346) (xy 249.209927 -72.559314) (xy 249.192288 -72.580246)
			(xy 249.183006 -72.591539) (xy 249.170836 -72.61811) (xy 249.166673 -72.647036) (xy 249.170856 -72.67596)
			(xy 249.183045 -72.702522) (xy 249.192288 -72.71385) (xy 249.209975 -72.734745) (xy 249.239697 -72.78072)
			(xy 249.262538 -72.830472) (xy 249.27803 -72.88298) (xy 249.285854 -72.937163) (xy 249.285849 -72.991909)
			(xy 249.278015 -73.046091) (xy 249.262513 -73.098596) (xy 249.239662 -73.148344) (xy 249.209931 -73.194313)
			(xy 249.192288 -73.215246) (xy 249.183006 -73.226539) (xy 249.170836 -73.25311) (xy 249.166673 -73.282036)
			(xy 249.170856 -73.31096) (xy 249.183045 -73.337522) (xy 249.192288 -73.34885) (xy 249.209975 -73.369745)
			(xy 249.239697 -73.41572) (xy 249.262538 -73.465472) (xy 249.27803 -73.51798) (xy 249.285854 -73.572163)
			(xy 249.28585 -73.620122) (xy 252.28245 -73.620122) (xy 252.286523 -73.564463) (xy 252.298658 -73.50999)
			(xy 252.318594 -73.457864) (xy 252.345908 -73.409196) (xy 252.380016 -73.365024) (xy 252.420193 -73.326289)
			(xy 252.465581 -73.293817) (xy 252.515213 -73.268299) (xy 252.568033 -73.25028) (xy 252.622912 -73.240143)
			(xy 252.678683 -73.238105) (xy 252.734157 -73.244208) (xy 252.78815 -73.258324) (xy 252.839513 -73.280151)
			(xy 252.887151 -73.309224) (xy 252.930047 -73.344923) (xy 252.967289 -73.386487) (xy 252.998083 -73.433031)
			(xy 253.021771 -73.483562) (xy 253.037201 -73.53485) (xy 272.927578 -73.53485) (xy 272.927578 -73.48035)
			(xy 272.935333 -73.426405) (xy 272.950687 -73.374112) (xy 272.973326 -73.324537) (xy 273.00279 -73.278688)
			(xy 273.038478 -73.237498) (xy 273.079665 -73.201807) (xy 273.125512 -73.17234) (xy 273.175086 -73.149697)
			(xy 273.227377 -73.134339) (xy 273.281322 -73.12658) (xy 273.308572 -73.126092) (xy 273.33749 -73.126595)
			(xy 273.394663 -73.135323) (xy 273.449864 -73.152581) (xy 273.501827 -73.177975) (xy 273.54936 -73.210923)
			(xy 273.591374 -73.25067) (xy 273.609562 -73.273158) (xy 273.619459 -73.284963) (xy 273.644783 -73.302482)
			(xy 273.674176 -73.311658) (xy 273.704968 -73.311658) (xy 273.734361 -73.302482) (xy 273.759685 -73.284963)
			(xy 273.769582 -73.273158) (xy 273.786335 -73.252375) (xy 273.824689 -73.215245) (xy 273.867843 -73.183823)
			(xy 273.914957 -73.158724) (xy 273.965109 -73.140438) (xy 274.01732 -73.129321) (xy 274.070572 -73.125591)
			(xy 274.123824 -73.129321) (xy 274.176035 -73.140438) (xy 274.226187 -73.158724) (xy 274.273301 -73.183823)
			(xy 274.316455 -73.215245) (xy 274.354809 -73.252375) (xy 274.371562 -73.273158) (xy 274.381459 -73.284963)
			(xy 274.406783 -73.302482) (xy 274.436176 -73.311658) (xy 274.466968 -73.311658) (xy 274.496361 -73.302482)
			(xy 274.521685 -73.284963) (xy 274.531582 -73.273158) (xy 274.548335 -73.252375) (xy 274.586689 -73.215245)
			(xy 274.629843 -73.183823) (xy 274.676957 -73.158724) (xy 274.727109 -73.140438) (xy 274.77932 -73.129321)
			(xy 274.832572 -73.125591) (xy 274.885824 -73.129321) (xy 274.938035 -73.140438) (xy 274.988187 -73.158724)
			(xy 275.035301 -73.183823) (xy 275.078455 -73.215245) (xy 275.116809 -73.252375) (xy 275.133562 -73.273158)
			(xy 275.143459 -73.284963) (xy 275.168783 -73.302482) (xy 275.198176 -73.311658) (xy 275.228968 -73.311658)
			(xy 275.258361 -73.302482) (xy 275.283685 -73.284963) (xy 275.293582 -73.273158) (xy 275.310335 -73.252375)
			(xy 275.348689 -73.215245) (xy 275.391843 -73.183823) (xy 275.438957 -73.158724) (xy 275.489109 -73.140438)
			(xy 275.54132 -73.129321) (xy 275.594572 -73.125591) (xy 275.647824 -73.129321) (xy 275.700035 -73.140438)
			(xy 275.750187 -73.158724) (xy 275.797301 -73.183823) (xy 275.840455 -73.215245) (xy 275.878809 -73.252375)
			(xy 275.895562 -73.273158) (xy 275.905459 -73.284963) (xy 275.930783 -73.302482) (xy 275.960176 -73.311658)
			(xy 275.990968 -73.311658) (xy 276.020361 -73.302482) (xy 276.045685 -73.284963) (xy 276.055582 -73.273158)
			(xy 276.073773 -73.250674) (xy 276.115794 -73.210941) (xy 276.163329 -73.178003) (xy 276.21529 -73.152615)
			(xy 276.270487 -73.135359) (xy 276.327656 -73.126628) (xy 276.356572 -73.126092) (xy 276.383826 -73.126553)
			(xy 276.43778 -73.134307) (xy 276.490081 -73.149661) (xy 276.539665 -73.172302) (xy 276.585522 -73.201769)
			(xy 276.626718 -73.237463) (xy 276.662414 -73.278656) (xy 276.691885 -73.32451) (xy 276.714529 -73.374092)
			(xy 276.729887 -73.426392) (xy 276.737645 -73.480346) (xy 276.737645 -73.534854) (xy 276.729887 -73.588808)
			(xy 276.714529 -73.641108) (xy 276.691885 -73.69069) (xy 276.662414 -73.736544) (xy 276.626718 -73.777737)
			(xy 276.585522 -73.813431) (xy 276.539665 -73.842898) (xy 276.490081 -73.865539) (xy 276.43778 -73.880893)
			(xy 276.383826 -73.888647) (xy 276.356572 -73.889108) (xy 276.327655 -73.888573) (xy 276.270483 -73.879852)
			(xy 276.215283 -73.8626) (xy 276.163321 -73.837212) (xy 276.115787 -73.804269) (xy 276.073771 -73.764528)
			(xy 276.055582 -73.742042) (xy 276.045685 -73.730237) (xy 276.020361 -73.712718) (xy 275.990968 -73.703542)
			(xy 275.960176 -73.703542) (xy 275.930783 -73.712718) (xy 275.905459 -73.730237) (xy 275.895562 -73.742042)
			(xy 275.878809 -73.762825) (xy 275.840455 -73.799955) (xy 275.797301 -73.831377) (xy 275.750187 -73.856476)
			(xy 275.700035 -73.874762) (xy 275.647824 -73.885879) (xy 275.594572 -73.889609) (xy 275.54132 -73.885879)
			(xy 275.489109 -73.874762) (xy 275.438957 -73.856476) (xy 275.391843 -73.831377) (xy 275.348689 -73.799955)
			(xy 275.310335 -73.762825) (xy 275.293582 -73.742042) (xy 275.283685 -73.730237) (xy 275.258361 -73.712718)
			(xy 275.228968 -73.703542) (xy 275.198176 -73.703542) (xy 275.168783 -73.712718) (xy 275.143459 -73.730237)
			(xy 275.133562 -73.742042) (xy 275.116809 -73.762825) (xy 275.078455 -73.799955) (xy 275.035301 -73.831377)
			(xy 274.988187 -73.856476) (xy 274.938035 -73.874762) (xy 274.885824 -73.885879) (xy 274.832572 -73.889609)
			(xy 274.77932 -73.885879) (xy 274.727109 -73.874762) (xy 274.676957 -73.856476) (xy 274.629843 -73.831377)
			(xy 274.586689 -73.799955) (xy 274.548335 -73.762825) (xy 274.531582 -73.742042) (xy 274.521685 -73.730237)
			(xy 274.496361 -73.712718) (xy 274.466968 -73.703542) (xy 274.436176 -73.703542) (xy 274.406783 -73.712718)
			(xy 274.381459 -73.730237) (xy 274.371562 -73.742042) (xy 274.354809 -73.762825) (xy 274.316455 -73.799955)
			(xy 274.273301 -73.831377) (xy 274.226187 -73.856476) (xy 274.176035 -73.874762) (xy 274.123824 -73.885879)
			(xy 274.070572 -73.889609) (xy 274.01732 -73.885879) (xy 273.965109 -73.874762) (xy 273.914957 -73.856476)
			(xy 273.867843 -73.831377) (xy 273.824689 -73.799955) (xy 273.786335 -73.762825) (xy 273.769582 -73.742042)
			(xy 273.759685 -73.730237) (xy 273.734361 -73.712718) (xy 273.704968 -73.703542) (xy 273.674176 -73.703542)
			(xy 273.644783 -73.712718) (xy 273.619459 -73.730237) (xy 273.609562 -73.742042) (xy 273.591403 -73.764552)
			(xy 273.549375 -73.804284) (xy 273.501833 -73.837219) (xy 273.449866 -73.862602) (xy 273.394663 -73.879853)
			(xy 273.33749 -73.888576) (xy 273.308572 -73.889108) (xy 273.281322 -73.88862) (xy 273.227377 -73.880861)
			(xy 273.175086 -73.865503) (xy 273.125512 -73.84286) (xy 273.079665 -73.813393) (xy 273.038478 -73.777702)
			(xy 273.00279 -73.736512) (xy 272.973326 -73.690663) (xy 272.950687 -73.641088) (xy 272.935333 -73.588795)
			(xy 272.927578 -73.53485) (xy 253.037201 -73.53485) (xy 253.037849 -73.537004) (xy 253.045975 -73.592218)
			(xy 253.046484 -73.620122) (xy 253.045975 -73.648026) (xy 253.037849 -73.70324) (xy 253.021771 -73.756682)
			(xy 252.998083 -73.807213) (xy 252.967289 -73.853757) (xy 252.930047 -73.895321) (xy 252.887151 -73.93102)
			(xy 252.839513 -73.960093) (xy 252.78815 -73.98192) (xy 252.734157 -73.996036) (xy 252.678683 -74.002139)
			(xy 252.622912 -74.000101) (xy 252.568033 -73.989964) (xy 252.515213 -73.971945) (xy 252.465581 -73.946427)
			(xy 252.420193 -73.913955) (xy 252.380016 -73.87522) (xy 252.345908 -73.831048) (xy 252.318594 -73.78238)
			(xy 252.298658 -73.730254) (xy 252.286523 -73.675781) (xy 252.28245 -73.620122) (xy 249.28585 -73.620122)
			(xy 249.285849 -73.626909) (xy 249.278015 -73.681091) (xy 249.262513 -73.733596) (xy 249.239662 -73.783344)
			(xy 249.209931 -73.829313) (xy 249.192288 -73.850246) (xy 249.183006 -73.861539) (xy 249.170836 -73.88811)
			(xy 249.166673 -73.917036) (xy 249.170856 -73.94596) (xy 249.183045 -73.972522) (xy 249.192288 -73.98385)
			(xy 249.209915 -74.004792) (xy 249.239629 -74.050762) (xy 249.261619 -74.098658) (xy 260.18693 -74.098658)
			(xy 260.191001 -74.043036) (xy 260.203127 -73.988599) (xy 260.22305 -73.936508) (xy 260.250346 -73.887873)
			(xy 260.284432 -73.84373) (xy 260.324581 -73.805021) (xy 260.369939 -73.77257) (xy 260.419539 -73.747069)
			(xy 260.472323 -73.729062) (xy 260.527166 -73.718932) (xy 260.5829 -73.716895) (xy 260.638337 -73.722995)
			(xy 260.692294 -73.737101) (xy 260.743623 -73.758913) (xy 260.791229 -73.787967) (xy 260.834097 -73.823642)
			(xy 260.871314 -73.865179) (xy 260.902087 -73.911692) (xy 260.925759 -73.962189) (xy 260.932964 -73.986136)
			(xy 261.8265 -73.986136) (xy 261.830571 -73.930514) (xy 261.842697 -73.876077) (xy 261.86262 -73.823986)
			(xy 261.889916 -73.775351) (xy 261.924002 -73.731208) (xy 261.964151 -73.692499) (xy 262.009509 -73.660048)
			(xy 262.059109 -73.634547) (xy 262.111893 -73.61654) (xy 262.166736 -73.60641) (xy 262.22247 -73.604373)
			(xy 262.277907 -73.610473) (xy 262.331864 -73.624579) (xy 262.383193 -73.646391) (xy 262.430799 -73.675445)
			(xy 262.473667 -73.71112) (xy 262.510884 -73.752657) (xy 262.541657 -73.79917) (xy 262.565329 -73.849667)
			(xy 262.581397 -73.903074) (xy 262.589517 -73.95825) (xy 262.590026 -73.986136) (xy 262.589517 -74.014022)
			(xy 262.581397 -74.069198) (xy 262.565329 -74.122605) (xy 262.541657 -74.173102) (xy 262.510884 -74.219615)
			(xy 262.473667 -74.261152) (xy 262.430799 -74.296827) (xy 262.383193 -74.325881) (xy 262.331864 -74.347693)
			(xy 262.277907 -74.361799) (xy 262.22247 -74.367899) (xy 262.166736 -74.365862) (xy 262.111893 -74.355732)
			(xy 262.059109 -74.337725) (xy 262.009509 -74.312224) (xy 261.964151 -74.279773) (xy 261.924002 -74.241064)
			(xy 261.889916 -74.196921) (xy 261.86262 -74.148286) (xy 261.842697 -74.096195) (xy 261.830571 -74.041758)
			(xy 261.8265 -73.986136) (xy 260.932964 -73.986136) (xy 260.941827 -74.015596) (xy 260.949947 -74.070772)
			(xy 260.950456 -74.098658) (xy 260.949947 -74.126544) (xy 260.941827 -74.18172) (xy 260.925759 -74.235127)
			(xy 260.902087 -74.285624) (xy 260.871314 -74.332137) (xy 260.834097 -74.373674) (xy 260.791229 -74.409349)
			(xy 260.743623 -74.438403) (xy 260.692294 -74.460215) (xy 260.638337 -74.474321) (xy 260.5829 -74.480421)
			(xy 260.527166 -74.478384) (xy 260.472323 -74.468254) (xy 260.419539 -74.450247) (xy 260.369939 -74.424746)
			(xy 260.324581 -74.392295) (xy 260.284432 -74.353586) (xy 260.250346 -74.309443) (xy 260.22305 -74.260808)
			(xy 260.203127 -74.208717) (xy 260.191001 -74.15428) (xy 260.18693 -74.098658) (xy 249.261619 -74.098658)
			(xy 249.262468 -74.100507) (xy 249.277961 -74.153005) (xy 249.285793 -74.207179) (xy 249.286268 -74.234548)
			(xy 249.285867 -74.261802) (xy 249.278103 -74.315755) (xy 249.262739 -74.368054) (xy 249.24009 -74.417634)
			(xy 249.210615 -74.463486) (xy 249.174914 -74.504677) (xy 249.133715 -74.540368) (xy 249.087857 -74.569832)
			(xy 249.038271 -74.59247) (xy 248.985969 -74.607821) (xy 248.932014 -74.615573) (xy 248.90476 -74.616056)
			(xy 248.893495 -74.616003) (xy 248.871001 -74.614732) (xy 248.859802 -74.613516) (xy 248.846201 -74.612398)
			(xy 248.819238 -74.616521) (xy 248.79433 -74.627641) (xy 248.773259 -74.644963) (xy 248.757532 -74.667249)
			(xy 248.748272 -74.692906) (xy 248.746141 -74.7201) (xy 248.751293 -74.746886) (xy 248.752552 -74.74966)
			(xy 258.981954 -74.74966) (xy 258.986025 -74.694038) (xy 258.998151 -74.639601) (xy 259.018074 -74.58751)
			(xy 259.04537 -74.538875) (xy 259.079456 -74.494732) (xy 259.119605 -74.456023) (xy 259.164963 -74.423572)
			(xy 259.214563 -74.398071) (xy 259.267347 -74.380064) (xy 259.32219 -74.369934) (xy 259.377924 -74.367897)
			(xy 259.433361 -74.373997) (xy 259.487318 -74.388103) (xy 259.538647 -74.409915) (xy 259.586253 -74.438969)
			(xy 259.629121 -74.474644) (xy 259.666338 -74.516181) (xy 259.697111 -74.562694) (xy 259.720783 -74.613191)
			(xy 259.736851 -74.666598) (xy 259.744971 -74.721774) (xy 259.74548 -74.74966) (xy 259.744971 -74.777546)
			(xy 259.736851 -74.832722) (xy 259.720783 -74.886129) (xy 259.697111 -74.936626) (xy 259.666338 -74.983139)
			(xy 259.629121 -75.024676) (xy 259.586253 -75.060351) (xy 259.538647 -75.089405) (xy 259.487318 -75.111217)
			(xy 259.433361 -75.125323) (xy 259.377924 -75.131423) (xy 259.32219 -75.129386) (xy 259.267347 -75.119256)
			(xy 259.214563 -75.101249) (xy 259.164963 -75.075748) (xy 259.119605 -75.043297) (xy 259.079456 -75.004588)
			(xy 259.04537 -74.960445) (xy 259.018074 -74.91181) (xy 258.998151 -74.859719) (xy 258.986025 -74.805282)
			(xy 258.981954 -74.74966) (xy 248.752552 -74.74966) (xy 248.756932 -74.759312) (xy 248.769388 -74.785711)
			(xy 248.787005 -74.841359) (xy 248.795961 -74.899038) (xy 248.796556 -74.928222) (xy 248.796556 -74.928984)
			(xy 248.796007 -74.956233) (xy 248.788254 -75.010176) (xy 248.772903 -75.062466) (xy 248.750268 -75.11204)
			(xy 248.720807 -75.157888) (xy 248.685123 -75.199077) (xy 248.643939 -75.234769) (xy 248.598096 -75.264237)
			(xy 248.548526 -75.286881) (xy 248.496238 -75.30224) (xy 248.442297 -75.310002) (xy 248.415048 -75.310492)
			(xy 248.387679 -75.31) (xy 248.333501 -75.302189) (xy 248.280998 -75.286706) (xy 248.23125 -75.26387)
			(xy 248.185283 -75.234151) (xy 248.16435 -75.216512) (xy 248.153022 -75.207276) (xy 248.126465 -75.1951)
			(xy 248.097548 -75.190927) (xy 248.068631 -75.1951) (xy 248.042074 -75.207276) (xy 248.030746 -75.216512)
			(xy 248.009809 -75.234145) (xy 247.963837 -75.263857) (xy 247.914091 -75.286694) (xy 247.861592 -75.302187)
			(xy 247.807417 -75.310017) (xy 247.780048 -75.310492) (xy 247.752792 -75.310064) (xy 247.698833 -75.302313)
			(xy 247.646527 -75.28696) (xy 247.596939 -75.264319) (xy 247.551078 -75.234851) (xy 247.509878 -75.199156)
			(xy 247.474177 -75.15796) (xy 247.444704 -75.112103) (xy 247.422057 -75.062518) (xy 247.406698 -75.010214)
			(xy 247.398939 -74.956256) (xy 247.398939 -74.901744) (xy 247.406698 -74.847786) (xy 247.422057 -74.795482)
			(xy 247.444704 -74.745897) (xy 247.474177 -74.70004) (xy 247.509878 -74.658844) (xy 247.551078 -74.623149)
			(xy 247.596939 -74.593681) (xy 247.646527 -74.57104) (xy 247.698833 -74.555687) (xy 247.752792 -74.547936)
			(xy 247.780048 -74.547476) (xy 247.807418 -74.547954) (xy 247.861597 -74.555766) (xy 247.914101 -74.571251)
			(xy 247.963848 -74.594091) (xy 248.009815 -74.623815) (xy 248.030746 -74.641456) (xy 248.042074 -74.650692)
			(xy 248.068631 -74.662868) (xy 248.097548 -74.667041) (xy 248.126465 -74.662868) (xy 248.153022 -74.650692)
			(xy 248.16435 -74.641456) (xy 248.185284 -74.62382) (xy 248.231257 -74.594109) (xy 248.281004 -74.571273)
			(xy 248.333504 -74.555781) (xy 248.387679 -74.547951) (xy 248.415048 -74.547476) (xy 248.426313 -74.547528)
			(xy 248.448807 -74.5488) (xy 248.460006 -74.550016) (xy 248.473603 -74.551239) (xy 248.500583 -74.547112)
			(xy 248.525505 -74.535982) (xy 248.546585 -74.518644) (xy 248.562316 -74.496339) (xy 248.571573 -74.470663)
			(xy 248.573693 -74.443451) (xy 248.568525 -74.416651) (xy 248.562876 -74.40422) (xy 248.550432 -74.377816)
			(xy 248.532811 -74.32217) (xy 248.52385 -74.264494) (xy 248.523252 -74.23531) (xy 248.523252 -74.234548)
			(xy 248.523734 -74.207178) (xy 248.531546 -74.152999) (xy 248.54703 -74.100496) (xy 248.569869 -74.050749)
			(xy 248.599591 -74.004782) (xy 248.617232 -73.98385) (xy 248.62642 -73.972487) (xy 248.638599 -73.945942)
			(xy 248.642779 -73.917036) (xy 248.63862 -73.888128) (xy 248.62646 -73.861574) (xy 248.617232 -73.850246)
			(xy 248.599638 -73.829275) (xy 248.569911 -73.783314) (xy 248.547063 -73.733574) (xy 248.531562 -73.681078)
			(xy 248.523729 -73.626905) (xy 248.523724 -73.572168) (xy 248.531547 -73.517993) (xy 248.547037 -73.465494)
			(xy 248.569876 -73.415749) (xy 248.599595 -73.369783) (xy 248.617232 -73.34885) (xy 248.62642 -73.337487)
			(xy 248.638599 -73.310942) (xy 248.642779 -73.282036) (xy 248.63862 -73.253128) (xy 248.62646 -73.226574)
			(xy 248.617232 -73.215246) (xy 248.599638 -73.194275) (xy 248.569911 -73.148314) (xy 248.547063 -73.098574)
			(xy 248.531562 -73.046078) (xy 248.523729 -72.991905) (xy 248.523724 -72.937168) (xy 248.531547 -72.882993)
			(xy 248.547037 -72.830494) (xy 248.569876 -72.780749) (xy 248.599595 -72.734783) (xy 248.617232 -72.71385)
			(xy 248.62642 -72.702487) (xy 248.638599 -72.675942) (xy 248.642779 -72.647036) (xy 248.63862 -72.618128)
			(xy 248.62646 -72.591574) (xy 248.617232 -72.580246) (xy 248.599606 -72.559303) (xy 248.569891 -72.513334)
			(xy 248.547052 -72.463589) (xy 248.531558 -72.411091) (xy 248.523727 -72.356917) (xy 248.523252 -72.329548)
			(xy 248.52369 -72.302896) (xy 248.53112 -72.250113) (xy 248.545828 -72.198878) (xy 248.556272 -72.174354)
			(xy 248.561856 -72.160208) (xy 248.565466 -72.130032) (xy 248.560054 -72.100128) (xy 248.546096 -72.073132)
			(xy 248.524823 -72.051428) (xy 248.498114 -72.036929) (xy 248.468324 -72.030916) (xy 248.453148 -72.03186)
			(xy 248.415048 -72.033892) (xy 248.387679 -72.0334) (xy 248.333501 -72.025589) (xy 248.280998 -72.010106)
			(xy 248.23125 -71.98727) (xy 248.185283 -71.957551) (xy 248.16435 -71.939912) (xy 248.153022 -71.930676)
			(xy 248.126465 -71.9185) (xy 248.097548 -71.914327) (xy 248.068631 -71.9185) (xy 248.042074 -71.930676)
			(xy 248.030746 -71.939912) (xy 248.009809 -71.957545) (xy 247.963837 -71.987257) (xy 247.914091 -72.010094)
			(xy 247.861592 -72.025587) (xy 247.807417 -72.033417) (xy 247.780048 -72.033892) (xy 247.752796 -72.0334)
			(xy 247.698845 -72.025649) (xy 247.646547 -72.010298) (xy 247.596966 -71.98766) (xy 247.551111 -71.958196)
			(xy 247.509918 -71.922505) (xy 247.474223 -71.881314) (xy 247.444755 -71.835463) (xy 247.422113 -71.785883)
			(xy 247.406758 -71.733586) (xy 247.399002 -71.679636) (xy 247.39854 -71.652384) (xy 246.61368 -71.652384)
			(xy 246.61368 -75.377548) (xy 247.042288 -75.806156) (xy 274.987923 -75.806156) (xy 274.987923 -75.751644)
			(xy 274.995681 -75.697687) (xy 275.011039 -75.645383) (xy 275.033685 -75.595797) (xy 275.063158 -75.549939)
			(xy 275.098857 -75.508742) (xy 275.140055 -75.473046) (xy 275.185915 -75.443576) (xy 275.235502 -75.420932)
			(xy 275.287806 -75.405577) (xy 275.341764 -75.397822) (xy 275.36902 -75.39736) (xy 275.396391 -75.3978)
			(xy 275.450572 -75.405622) (xy 275.503076 -75.421116) (xy 275.552823 -75.443964) (xy 275.598788 -75.473695)
			(xy 275.619718 -75.49134) (xy 275.631046 -75.500576) (xy 275.657603 -75.512752) (xy 275.68652 -75.516925)
			(xy 275.715437 -75.512752) (xy 275.741994 -75.500576) (xy 275.753322 -75.49134) (xy 275.774255 -75.473699)
			(xy 275.820223 -75.443975) (xy 275.869969 -75.421129) (xy 275.922471 -75.405633) (xy 275.976649 -75.397804)
			(xy 276.031391 -75.397804) (xy 276.085569 -75.405633) (xy 276.138071 -75.421129) (xy 276.187817 -75.443975)
			(xy 276.233785 -75.473699) (xy 276.254718 -75.49134) (xy 276.266046 -75.500576) (xy 276.292603 -75.512752)
			(xy 276.32152 -75.516925) (xy 276.350437 -75.512752) (xy 276.376994 -75.500576) (xy 276.388322 -75.49134)
			(xy 276.409255 -75.473699) (xy 276.455223 -75.443975) (xy 276.504969 -75.421129) (xy 276.557471 -75.405633)
			(xy 276.611649 -75.397804) (xy 276.666391 -75.397804) (xy 276.720569 -75.405633) (xy 276.773071 -75.421129)
			(xy 276.822817 -75.443975) (xy 276.868785 -75.473699) (xy 276.889718 -75.49134) (xy 276.901046 -75.500576)
			(xy 276.927603 -75.512752) (xy 276.95652 -75.516925) (xy 276.985437 -75.512752) (xy 277.011994 -75.500576)
			(xy 277.023322 -75.49134) (xy 277.044255 -75.473699) (xy 277.090223 -75.443975) (xy 277.139969 -75.421129)
			(xy 277.192471 -75.405633) (xy 277.246649 -75.397804) (xy 277.301391 -75.397804) (xy 277.355569 -75.405633)
			(xy 277.408071 -75.421129) (xy 277.457817 -75.443975) (xy 277.503785 -75.473699) (xy 277.524718 -75.49134)
			(xy 277.536046 -75.500576) (xy 277.562603 -75.512752) (xy 277.59152 -75.516925) (xy 277.620437 -75.512752)
			(xy 277.646994 -75.500576) (xy 277.658322 -75.49134) (xy 277.679278 -75.47373) (xy 277.725243 -75.444013)
			(xy 277.774985 -75.42117) (xy 277.827481 -75.405673) (xy 277.881652 -75.397837) (xy 277.90902 -75.39736)
			(xy 277.936268 -75.397912) (xy 277.990209 -75.40567) (xy 278.042497 -75.421025) (xy 278.092067 -75.443666)
			(xy 278.137911 -75.47313) (xy 278.179096 -75.508818) (xy 278.214782 -75.550005) (xy 278.244244 -75.59585)
			(xy 278.266882 -75.645422) (xy 278.282235 -75.697711) (xy 278.28999 -75.751652) (xy 278.28999 -75.806148)
			(xy 278.282235 -75.860089) (xy 278.266882 -75.912378) (xy 278.244244 -75.96195) (xy 278.214782 -76.007795)
			(xy 278.179096 -76.048982) (xy 278.137911 -76.08467) (xy 278.092067 -76.114134) (xy 278.042497 -76.136775)
			(xy 277.990209 -76.15213) (xy 277.936268 -76.159888) (xy 277.90902 -76.160376) (xy 277.88165 -76.159904)
			(xy 277.827471 -76.152089) (xy 277.774968 -76.136601) (xy 277.725221 -76.113761) (xy 277.679254 -76.084037)
			(xy 277.658322 -76.066396) (xy 277.646994 -76.05716) (xy 277.620437 -76.044984) (xy 277.59152 -76.040811)
			(xy 277.562603 -76.044984) (xy 277.536046 -76.05716) (xy 277.524718 -76.066396) (xy 277.503785 -76.084037)
			(xy 277.457817 -76.113761) (xy 277.408071 -76.136607) (xy 277.355569 -76.152103) (xy 277.301391 -76.159932)
			(xy 277.246649 -76.159932) (xy 277.192471 -76.152103) (xy 277.139969 -76.136607) (xy 277.090223 -76.113761)
			(xy 277.044255 -76.084037) (xy 277.023322 -76.066396) (xy 277.011994 -76.05716) (xy 276.985437 -76.044984)
			(xy 276.95652 -76.040811) (xy 276.927603 -76.044984) (xy 276.901046 -76.05716) (xy 276.889718 -76.066396)
			(xy 276.868785 -76.084037) (xy 276.822817 -76.113761) (xy 276.773071 -76.136607) (xy 276.720569 -76.152103)
			(xy 276.666391 -76.159932) (xy 276.611649 -76.159932) (xy 276.557471 -76.152103) (xy 276.504969 -76.136607)
			(xy 276.455223 -76.113761) (xy 276.409255 -76.084037) (xy 276.388322 -76.066396) (xy 276.376994 -76.05716)
			(xy 276.350437 -76.044984) (xy 276.32152 -76.040811) (xy 276.292603 -76.044984) (xy 276.266046 -76.05716)
			(xy 276.254718 -76.066396) (xy 276.233785 -76.084037) (xy 276.187817 -76.113761) (xy 276.138071 -76.136607)
			(xy 276.085569 -76.152103) (xy 276.031391 -76.159932) (xy 275.976649 -76.159932) (xy 275.922471 -76.152103)
			(xy 275.869969 -76.136607) (xy 275.820223 -76.113761) (xy 275.774255 -76.084037) (xy 275.753322 -76.066396)
			(xy 275.741994 -76.05716) (xy 275.715437 -76.044984) (xy 275.68652 -76.040811) (xy 275.657603 -76.044984)
			(xy 275.631046 -76.05716) (xy 275.619718 -76.066396) (xy 275.598789 -76.084039) (xy 275.552816 -76.113751)
			(xy 275.503067 -76.136586) (xy 275.450566 -76.152076) (xy 275.396389 -76.159903) (xy 275.36902 -76.160376)
			(xy 275.341764 -76.159978) (xy 275.287806 -76.152223) (xy 275.235502 -76.136868) (xy 275.185915 -76.114224)
			(xy 275.140055 -76.084754) (xy 275.098857 -76.049058) (xy 275.063158 -76.007861) (xy 275.033685 -75.962003)
			(xy 275.011039 -75.912417) (xy 274.995681 -75.860113) (xy 274.987923 -75.806156) (xy 247.042288 -75.806156)
			(xy 248.16308 -76.926948) (xy 257.560062 -76.926948) (xy 257.564133 -76.871326) (xy 257.576259 -76.816889)
			(xy 257.596182 -76.764798) (xy 257.623478 -76.716163) (xy 257.657564 -76.67202) (xy 257.697713 -76.633311)
			(xy 257.743071 -76.60086) (xy 257.792671 -76.575359) (xy 257.845455 -76.557352) (xy 257.900298 -76.547222)
			(xy 257.956032 -76.545185) (xy 258.011469 -76.551285) (xy 258.065426 -76.565391) (xy 258.116755 -76.587203)
			(xy 258.164361 -76.616257) (xy 258.207229 -76.651932) (xy 258.244446 -76.693469) (xy 258.275219 -76.739982)
			(xy 258.298891 -76.790479) (xy 258.314959 -76.843886) (xy 258.323079 -76.899062) (xy 258.323588 -76.926948)
			(xy 258.323079 -76.954834) (xy 258.314959 -77.01001) (xy 258.298891 -77.063417) (xy 258.275219 -77.113914)
			(xy 258.244446 -77.160427) (xy 258.207229 -77.201964) (xy 258.164361 -77.237639) (xy 258.116755 -77.266693)
			(xy 258.065426 -77.288505) (xy 258.011469 -77.302611) (xy 257.956032 -77.308711) (xy 257.900298 -77.306674)
			(xy 257.845455 -77.296544) (xy 257.792671 -77.278537) (xy 257.743071 -77.253036) (xy 257.697713 -77.220585)
			(xy 257.657564 -77.181876) (xy 257.623478 -77.137733) (xy 257.596182 -77.089098) (xy 257.576259 -77.037007)
			(xy 257.564133 -76.98257) (xy 257.560062 -76.926948) (xy 248.16308 -76.926948) (xy 249.313954 -78.077822)
			(xy 262.833104 -78.077822) (xy 262.833509 -78.051441) (xy 262.840772 -77.999182) (xy 262.855163 -77.948421)
			(xy 262.876408 -77.900125) (xy 262.904101 -77.855216) (xy 262.937715 -77.814548) (xy 262.97661 -77.778897)
			(xy 263.020043 -77.748942) (xy 263.043416 -77.7367) (xy 263.05576 -77.72997) (xy 263.076497 -77.711003)
			(xy 263.091265 -77.687094) (xy 263.098943 -77.660061) (xy 263.098945 -77.631959) (xy 263.091273 -77.604924)
			(xy 263.076509 -77.581012) (xy 263.055777 -77.562042) (xy 263.043416 -77.555344) (xy 263.020059 -77.543078)
			(xy 262.976634 -77.513121) (xy 262.937747 -77.477469) (xy 262.90414 -77.436803) (xy 262.876451 -77.391898)
			(xy 262.855209 -77.343608) (xy 262.840817 -77.292853) (xy 262.833551 -77.2406) (xy 262.833104 -77.214222)
			(xy 262.83359 -77.186971) (xy 262.841346 -77.133023) (xy 262.856701 -77.080728) (xy 262.879343 -77.031151)
			(xy 262.908809 -76.985301) (xy 262.9445 -76.94411) (xy 262.985691 -76.908419) (xy 263.031541 -76.878953)
			(xy 263.081118 -76.856311) (xy 263.133413 -76.840956) (xy 263.187361 -76.8332) (xy 263.241863 -76.8332)
			(xy 263.295811 -76.840956) (xy 263.348106 -76.856311) (xy 263.397683 -76.878953) (xy 263.443533 -76.908419)
			(xy 263.484724 -76.94411) (xy 263.520415 -76.985301) (xy 263.549881 -77.031151) (xy 263.572523 -77.080728)
			(xy 263.587878 -77.133023) (xy 263.595634 -77.186971) (xy 263.59612 -77.214222) (xy 263.595656 -77.240601)
			(xy 263.588401 -77.292857) (xy 263.574018 -77.343616) (xy 263.552782 -77.39191) (xy 263.525097 -77.43682)
			(xy 263.491491 -77.477489) (xy 263.452604 -77.513142) (xy 263.409177 -77.5431) (xy 263.385808 -77.555344)
			(xy 263.373433 -77.562015) (xy 263.352707 -77.580998) (xy 263.337949 -77.604918) (xy 263.330281 -77.631957)
			(xy 263.330283 -77.660063) (xy 263.337957 -77.6871) (xy 263.352719 -77.711017) (xy 263.373449 -77.729996)
			(xy 263.385808 -77.7367) (xy 263.409189 -77.748922) (xy 263.452614 -77.778887) (xy 263.491499 -77.814545)
			(xy 263.525104 -77.855217) (xy 263.55279 -77.900129) (xy 263.574029 -77.948425) (xy 263.588415 -77.999185)
			(xy 263.595676 -78.051442) (xy 263.59612 -78.077822) (xy 263.595634 -78.105073) (xy 263.587878 -78.159021)
			(xy 263.572523 -78.211316) (xy 263.549881 -78.260893) (xy 263.520415 -78.306743) (xy 263.484724 -78.347934)
			(xy 263.443533 -78.383625) (xy 263.397683 -78.413091) (xy 263.348106 -78.435733) (xy 263.295811 -78.451088)
			(xy 263.241863 -78.458844) (xy 263.187361 -78.458844) (xy 263.133413 -78.451088) (xy 263.081118 -78.435733)
			(xy 263.031541 -78.413091) (xy 262.985691 -78.383625) (xy 262.9445 -78.347934) (xy 262.908809 -78.306743)
			(xy 262.879343 -78.260893) (xy 262.856701 -78.211316) (xy 262.841346 -78.159021) (xy 262.83359 -78.105073)
			(xy 262.833104 -78.077822) (xy 249.313954 -78.077822) (xy 250.21413 -78.977998) (xy 258.880862 -78.977998)
			(xy 258.884933 -78.922376) (xy 258.897059 -78.867939) (xy 258.916982 -78.815848) (xy 258.944278 -78.767213)
			(xy 258.978364 -78.72307) (xy 259.018513 -78.684361) (xy 259.063871 -78.65191) (xy 259.113471 -78.626409)
			(xy 259.166255 -78.608402) (xy 259.221098 -78.598272) (xy 259.276832 -78.596235) (xy 259.332269 -78.602335)
			(xy 259.386226 -78.616441) (xy 259.437555 -78.638253) (xy 259.485161 -78.667307) (xy 259.528029 -78.702982)
			(xy 259.565246 -78.744519) (xy 259.596019 -78.791032) (xy 259.619691 -78.841529) (xy 259.635759 -78.894936)
			(xy 259.643879 -78.950112) (xy 259.644388 -78.977998) (xy 259.643879 -79.005884) (xy 259.635759 -79.06106)
			(xy 259.619691 -79.114467) (xy 259.596019 -79.164964) (xy 259.565246 -79.211477) (xy 259.528029 -79.253014)
			(xy 259.485161 -79.288689) (xy 259.437555 -79.317743) (xy 259.386226 -79.339555) (xy 259.332269 -79.353661)
			(xy 259.276832 -79.359761) (xy 259.221098 -79.357724) (xy 259.166255 -79.347594) (xy 259.113471 -79.329587)
			(xy 259.063871 -79.304086) (xy 259.018513 -79.271635) (xy 258.978364 -79.232926) (xy 258.944278 -79.188783)
			(xy 258.916982 -79.140148) (xy 258.897059 -79.088057) (xy 258.884933 -79.03362) (xy 258.880862 -78.977998)
			(xy 250.21413 -78.977998) (xy 250.77928 -79.543148) (xy 277.959312 -79.543148)
		)
		(stroke
			(width 0)
			(type solid)
		)
		(fill yes)
		(layer "In6.Cu")
		(net "GND")
	)
	(gr_poly
		(pts
			(xy 181.846474 -34.30651) (xy 181.847351 -34.279531) (xy 181.855771 -34.226213) (xy 181.871622 -34.174614)
			(xy 181.89459 -34.125765) (xy 181.924213 -34.080642) (xy 181.959902 -34.040145) (xy 182.000944 -34.005083)
			(xy 182.046518 -33.976158) (xy 182.095715 -33.953945) (xy 182.147551 -33.93889) (xy 182.200993 -33.931292)
			(xy 182.227982 -33.930844) (xy 182.256899 -33.931377) (xy 182.31407 -33.940102) (xy 182.369271 -33.957356)
			(xy 182.421235 -33.982742) (xy 182.468772 -34.01568) (xy 182.510794 -34.055415) (xy 182.528972 -34.07791)
			(xy 182.538869 -34.089715) (xy 182.564193 -34.107234) (xy 182.593586 -34.11641) (xy 182.624378 -34.11641)
			(xy 182.653771 -34.107234) (xy 182.679095 -34.089715) (xy 182.688992 -34.07791) (xy 182.707183 -34.055427)
			(xy 182.749201 -34.015692) (xy 182.796736 -33.982755) (xy 182.848698 -33.957371) (xy 182.903897 -33.940123)
			(xy 182.961066 -33.931405) (xy 182.989982 -33.930844) (xy 183.01697 -33.93131) (xy 183.070408 -33.938914)
			(xy 183.122241 -33.953973) (xy 183.171434 -33.976187) (xy 183.217005 -34.005112) (xy 183.258046 -34.040171)
			(xy 183.293736 -34.080663) (xy 183.323363 -34.125782) (xy 183.346336 -34.174625) (xy 183.362196 -34.226218)
			(xy 183.370627 -34.279532) (xy 183.37149 -34.30651) (xy 183.372252 -34.356548) (xy 187.430664 -34.356548)
			(xy 187.441078 -34.351722) (xy 187.466721 -34.340104) (xy 187.520573 -34.323698) (xy 187.576252 -34.31539)
			(xy 187.6044 -34.314892) (xy 187.632546 -34.315416) (xy 187.688221 -34.323725) (xy 187.742074 -34.340119)
			(xy 187.767722 -34.351722) (xy 187.778136 -34.356548) (xy 193.07048 -34.356548) (xy 193.33718 -34.089848)
			(xy 192.63995 -33.392618) (xy 192.62259 -33.374635) (xy 192.593178 -33.334226) (xy 192.570458 -33.289708)
			(xy 192.554991 -33.242181) (xy 192.547159 -33.192818) (xy 192.546732 -33.167828) (xy 192.546732 -31.53918)
			(xy 190.549276 -29.541724) (xy 190.539083 -29.532151) (xy 190.5147 -29.518482) (xy 190.487525 -29.511932)
			(xy 190.459592 -29.512993) (xy 190.432992 -29.521585) (xy 190.409716 -29.537064) (xy 190.391506 -29.558273)
			(xy 190.379726 -29.583622) (xy 190.377064 -29.59735) (xy 190.37235 -29.623888) (xy 190.356433 -29.675384)
			(xy 190.333428 -29.724127) (xy 190.303792 -29.769148) (xy 190.268115 -29.809549) (xy 190.227107 -29.844528)
			(xy 190.181585 -29.873387) (xy 190.132454 -29.895553) (xy 190.080693 -29.910584) (xy 190.027332 -29.918181)
			(xy 190.000382 -29.91866) (xy 189.973131 -29.918195) (xy 189.919185 -29.910436) (xy 189.866892 -29.895078)
			(xy 189.817317 -29.872434) (xy 189.77147 -29.842965) (xy 189.730283 -29.80727) (xy 189.694596 -29.766077)
			(xy 189.665135 -29.720225) (xy 189.642499 -29.670646) (xy 189.62715 -29.618351) (xy 189.6194 -29.564403)
			(xy 189.618874 -29.537152) (xy 189.619336 -29.510199) (xy 189.626918 -29.456829) (xy 189.641939 -29.405058)
			(xy 189.6641 -29.355917) (xy 189.692959 -29.310387) (xy 189.727941 -29.269373) (xy 189.768349 -29.233692)
			(xy 189.813378 -29.204057) (xy 189.862131 -29.181057) (xy 189.913637 -29.16515) (xy 189.940184 -29.16047)
			(xy 189.95391 -29.1578) (xy 189.979258 -29.146015) (xy 190.000465 -29.127804) (xy 190.015944 -29.104528)
			(xy 190.024538 -29.077929) (xy 190.025605 -29.049996) (xy 190.019063 -29.022819) (xy 190.005403 -28.99843)
			(xy 189.99581 -28.988258) (xy 188.78804 -27.780488) (xy 188.77821 -27.771211) (xy 188.754789 -27.75774)
			(xy 188.728653 -27.750892) (xy 188.701635 -27.751147) (xy 188.675633 -27.758489) (xy 188.652471 -27.7724)
			(xy 188.633775 -27.791906) (xy 188.627004 -27.803602) (xy 188.612498 -27.828926) (xy 188.576995 -27.875244)
			(xy 188.534858 -27.91562) (xy 188.487068 -27.949115) (xy 188.434739 -27.974949) (xy 188.379088 -27.99252)
			(xy 188.321411 -28.001419) (xy 188.292232 -28.001976) (xy 188.264978 -28.001515) (xy 188.211026 -27.993761)
			(xy 188.158726 -27.978408) (xy 188.109144 -27.955767) (xy 188.063289 -27.926299) (xy 188.022095 -27.890605)
			(xy 187.986401 -27.849411) (xy 187.956933 -27.803556) (xy 187.934292 -27.753974) (xy 187.918939 -27.701674)
			(xy 187.911185 -27.647722) (xy 187.910724 -27.620468) (xy 187.911273 -27.591286) (xy 187.920151 -27.5336)
			(xy 187.93771 -27.47794) (xy 187.96354 -27.425602) (xy 187.99704 -27.377809) (xy 188.037427 -27.335674)
			(xy 188.083759 -27.300182) (xy 188.109098 -27.285696) (xy 188.120754 -27.278872) (xy 188.140248 -27.260188)
			(xy 188.15415 -27.237041) (xy 188.161487 -27.211055) (xy 188.161742 -27.184055) (xy 188.154899 -27.157936)
			(xy 188.141436 -27.13453) (xy 188.132212 -27.12466) (xy 187.625228 -26.617676) (xy 186.9186 -26.617676)
			(xy 186.893616 -26.617165) (xy 186.844268 -26.609315) (xy 186.796752 -26.593854) (xy 186.752234 -26.571162)
			(xy 186.711805 -26.541796) (xy 186.69381 -26.524458) (xy 186.3725 -26.203148) (xy 185.105802 -26.203148)
			(xy 185.084655 -26.215671) (xy 185.039653 -26.235423) (xy 184.992364 -26.248809) (xy 184.943685 -26.255573)
			(xy 184.919112 -26.25598) (xy 184.888504 -26.255347) (xy 184.828188 -26.24489) (xy 184.770546 -26.22428)
			(xy 184.743598 -26.209752) (xy 184.731914 -26.203148) (xy 184.58688 -26.203148) (xy 183.337454 -24.953976)
			(xy 179.56022 -24.953976) (xy 179.535239 -24.953459) (xy 179.485897 -24.945598) (xy 179.438389 -24.930128)
			(xy 179.393879 -24.907429) (xy 179.35346 -24.878057) (xy 179.33543 -24.860758) (xy 179.15382 -24.679148)
			(xy 171.02328 -24.679148) (xy 170.56608 -25.136348) (xy 170.56608 -25.517348) (xy 179.124862 -25.517348)
			(xy 179.128933 -25.461726) (xy 179.141059 -25.407289) (xy 179.160982 -25.355198) (xy 179.188278 -25.306563)
			(xy 179.222364 -25.26242) (xy 179.262513 -25.223711) (xy 179.307871 -25.19126) (xy 179.357471 -25.165759)
			(xy 179.410255 -25.147752) (xy 179.465098 -25.137622) (xy 179.520832 -25.135585) (xy 179.576269 -25.141685)
			(xy 179.630226 -25.155791) (xy 179.681555 -25.177603) (xy 179.729161 -25.206657) (xy 179.772029 -25.242332)
			(xy 179.809246 -25.283869) (xy 179.840019 -25.330382) (xy 179.863691 -25.380879) (xy 179.879759 -25.434286)
			(xy 179.887879 -25.489462) (xy 179.888388 -25.517348) (xy 179.887879 -25.545234) (xy 179.879759 -25.60041)
			(xy 179.863691 -25.653817) (xy 179.840019 -25.704314) (xy 179.809246 -25.750827) (xy 179.772029 -25.792364)
			(xy 179.729161 -25.828039) (xy 179.681555 -25.857093) (xy 179.630226 -25.878905) (xy 179.576269 -25.893011)
			(xy 179.520832 -25.899111) (xy 179.465098 -25.897074) (xy 179.410255 -25.886944) (xy 179.357471 -25.868937)
			(xy 179.307871 -25.843436) (xy 179.262513 -25.810985) (xy 179.222364 -25.772276) (xy 179.188278 -25.728133)
			(xy 179.160982 -25.679498) (xy 179.141059 -25.627407) (xy 179.128933 -25.57297) (xy 179.124862 -25.517348)
			(xy 170.56608 -25.517348) (xy 170.56608 -26.666748) (xy 171.777698 -26.666748) (xy 171.777698 -26.612252)
			(xy 171.785453 -26.558311) (xy 171.800805 -26.506022) (xy 171.823442 -26.45645) (xy 171.852903 -26.410604)
			(xy 171.888589 -26.369417) (xy 171.929772 -26.333727) (xy 171.975615 -26.304262) (xy 172.025184 -26.281619)
			(xy 172.077472 -26.266262) (xy 172.131412 -26.258501) (xy 172.15866 -26.258012) (xy 172.185096 -26.258433)
			(xy 172.237461 -26.265724) (xy 172.28832 -26.280173) (xy 172.336698 -26.301502) (xy 172.381669 -26.329303)
			(xy 172.422373 -26.363046) (xy 172.458031 -26.402082) (xy 172.473366 -26.42362) (xy 172.482357 -26.435682)
			(xy 172.505832 -26.454465) (xy 172.533759 -26.465597) (xy 172.563718 -26.468116) (xy 172.593112 -26.461801)
			(xy 172.619393 -26.447202) (xy 172.640285 -26.425582) (xy 172.64761 -26.412444) (xy 172.659887 -26.389266)
			(xy 172.689873 -26.34623) (xy 172.725473 -26.307711) (xy 172.766017 -26.274434) (xy 172.810739 -26.247028)
			(xy 172.858795 -26.22601) (xy 172.909279 -26.211776) (xy 172.961236 -26.204596) (xy 172.987462 -26.204164)
			(xy 173.014715 -26.204681) (xy 173.068666 -26.212433) (xy 173.120964 -26.227784) (xy 173.170546 -26.250423)
			(xy 173.2164 -26.279888) (xy 173.257594 -26.315579) (xy 173.293289 -26.356769) (xy 173.322759 -26.402621)
			(xy 173.345402 -26.4522) (xy 173.360759 -26.504497) (xy 173.368517 -26.558447) (xy 173.368517 -26.612953)
			(xy 173.365354 -26.634948) (xy 175.950372 -26.634948) (xy 175.950906 -26.607186) (xy 175.958947 -26.552249)
			(xy 175.974868 -26.499058) (xy 175.998332 -26.448736) (xy 176.028842 -26.402347) (xy 176.065755 -26.360872)
			(xy 176.10829 -26.325185) (xy 176.155549 -26.296041) (xy 176.206534 -26.274056) (xy 176.260168 -26.259694)
			(xy 176.287684 -26.25598) (xy 176.301308 -26.253896) (xy 176.326816 -26.243495) (xy 176.348612 -26.226649)
			(xy 176.365105 -26.204584) (xy 176.375093 -26.178912) (xy 176.377847 -26.151502) (xy 176.373168 -26.124356)
			(xy 176.367694 -26.111708) (xy 176.356212 -26.086166) (xy 176.340041 -26.03255) (xy 176.331865 -25.977149)
			(xy 176.331372 -25.949148) (xy 176.331858 -25.921897) (xy 176.339614 -25.867949) (xy 176.354969 -25.815654)
			(xy 176.377611 -25.766077) (xy 176.407077 -25.720227) (xy 176.442768 -25.679036) (xy 176.483959 -25.643345)
			(xy 176.529809 -25.613879) (xy 176.579386 -25.591237) (xy 176.631681 -25.575882) (xy 176.685629 -25.568126)
			(xy 176.740131 -25.568126) (xy 176.794079 -25.575882) (xy 176.846374 -25.591237) (xy 176.895951 -25.613879)
			(xy 176.941801 -25.643345) (xy 176.982992 -25.679036) (xy 177.018683 -25.720227) (xy 177.048149 -25.766077)
			(xy 177.070791 -25.815654) (xy 177.086146 -25.867949) (xy 177.093902 -25.921897) (xy 177.094388 -25.949148)
			(xy 177.093906 -25.977474) (xy 177.085563 -26.033509) (xy 177.069023 -26.087693) (xy 177.057304 -26.113486)
			(xy 177.051815 -26.126112) (xy 177.047046 -26.153215) (xy 177.049687 -26.180608) (xy 177.059546 -26.206301)
			(xy 177.075906 -26.228429) (xy 177.097581 -26.245385) (xy 177.122996 -26.255939) (xy 177.150306 -26.259324)
			(xy 177.163984 -26.257758) (xy 177.176684 -26.25598) (xy 177.190308 -26.253896) (xy 177.215816 -26.243495)
			(xy 177.237612 -26.226649) (xy 177.254105 -26.204584) (xy 177.264093 -26.178912) (xy 177.266847 -26.151502)
			(xy 177.262168 -26.124356) (xy 177.256694 -26.111708) (xy 177.245212 -26.086166) (xy 177.229041 -26.03255)
			(xy 177.220865 -25.977149) (xy 177.220372 -25.949148) (xy 177.220858 -25.921897) (xy 177.228614 -25.867949)
			(xy 177.243969 -25.815654) (xy 177.266611 -25.766077) (xy 177.296077 -25.720227) (xy 177.331768 -25.679036)
			(xy 177.372959 -25.643345) (xy 177.418809 -25.613879) (xy 177.468386 -25.591237) (xy 177.520681 -25.575882)
			(xy 177.574629 -25.568126) (xy 177.629131 -25.568126) (xy 177.683079 -25.575882) (xy 177.735374 -25.591237)
			(xy 177.784951 -25.613879) (xy 177.830801 -25.643345) (xy 177.871992 -25.679036) (xy 177.907683 -25.720227)
			(xy 177.937149 -25.766077) (xy 177.959791 -25.815654) (xy 177.975146 -25.867949) (xy 177.982902 -25.921897)
			(xy 177.983388 -25.949148) (xy 177.982906 -25.977474) (xy 177.974563 -26.033509) (xy 177.958023 -26.087693)
			(xy 177.946304 -26.113486) (xy 177.940815 -26.126112) (xy 177.936046 -26.153215) (xy 177.938687 -26.180608)
			(xy 177.948546 -26.206301) (xy 177.964906 -26.228429) (xy 177.986581 -26.245385) (xy 178.011996 -26.255939)
			(xy 178.039306 -26.259324) (xy 178.052984 -26.257758) (xy 178.065684 -26.25598) (xy 178.079308 -26.253896)
			(xy 178.104816 -26.243495) (xy 178.126612 -26.226649) (xy 178.143105 -26.204584) (xy 178.153093 -26.178912)
			(xy 178.155847 -26.151502) (xy 178.151168 -26.124356) (xy 178.145694 -26.111708) (xy 178.134212 -26.086166)
			(xy 178.118041 -26.03255) (xy 178.109865 -25.977149) (xy 178.109372 -25.949148) (xy 178.109858 -25.921897)
			(xy 178.117614 -25.867949) (xy 178.132969 -25.815654) (xy 178.155611 -25.766077) (xy 178.185077 -25.720227)
			(xy 178.220768 -25.679036) (xy 178.261959 -25.643345) (xy 178.307809 -25.613879) (xy 178.357386 -25.591237)
			(xy 178.409681 -25.575882) (xy 178.463629 -25.568126) (xy 178.518131 -25.568126) (xy 178.572079 -25.575882)
			(xy 178.624374 -25.591237) (xy 178.673951 -25.613879) (xy 178.719801 -25.643345) (xy 178.760992 -25.679036)
			(xy 178.796683 -25.720227) (xy 178.826149 -25.766077) (xy 178.848791 -25.815654) (xy 178.864146 -25.867949)
			(xy 178.871902 -25.921897) (xy 178.872388 -25.949148) (xy 178.871886 -25.976911) (xy 178.863844 -26.031852)
			(xy 178.847921 -26.085046) (xy 178.824455 -26.135369) (xy 178.793942 -26.18176) (xy 178.757025 -26.223236)
			(xy 178.714485 -26.258922) (xy 178.667221 -26.288064) (xy 178.616232 -26.310046) (xy 178.562594 -26.324404)
			(xy 178.535076 -26.328116) (xy 178.521432 -26.330108) (xy 178.495903 -26.340509) (xy 178.474092 -26.357367)
			(xy 178.457592 -26.37945) (xy 178.447608 -26.405145) (xy 178.444869 -26.432575) (xy 178.449576 -26.459737)
			(xy 178.455066 -26.472388) (xy 178.466551 -26.497929) (xy 178.482719 -26.551546) (xy 178.490895 -26.606947)
			(xy 178.491388 -26.634948) (xy 178.490902 -26.662199) (xy 178.483146 -26.716147) (xy 178.467791 -26.768442)
			(xy 178.445149 -26.818019) (xy 178.415683 -26.863869) (xy 178.379992 -26.90506) (xy 178.338801 -26.940751)
			(xy 178.292951 -26.970217) (xy 178.243374 -26.992859) (xy 178.191079 -27.008214) (xy 178.137131 -27.01597)
			(xy 178.082629 -27.01597) (xy 178.028681 -27.008214) (xy 177.976386 -26.992859) (xy 177.926809 -26.970217)
			(xy 177.880959 -26.940751) (xy 177.839768 -26.90506) (xy 177.804077 -26.863869) (xy 177.774611 -26.818019)
			(xy 177.751969 -26.768442) (xy 177.736614 -26.716147) (xy 177.728858 -26.662199) (xy 177.728372 -26.634948)
			(xy 177.728856 -26.606622) (xy 177.737199 -26.550587) (xy 177.753737 -26.496403) (xy 177.765456 -26.47061)
			(xy 177.770991 -26.458001) (xy 177.775763 -26.430889) (xy 177.773122 -26.403487) (xy 177.763258 -26.377786)
			(xy 177.74689 -26.355653) (xy 177.725205 -26.338695) (xy 177.699778 -26.328144) (xy 177.672458 -26.324766)
			(xy 177.658776 -26.326338) (xy 177.646076 -26.328116) (xy 177.632432 -26.330108) (xy 177.606903 -26.340509)
			(xy 177.585092 -26.357367) (xy 177.568592 -26.37945) (xy 177.558608 -26.405145) (xy 177.555869 -26.432575)
			(xy 177.560576 -26.459737) (xy 177.566066 -26.472388) (xy 177.577551 -26.497929) (xy 177.593719 -26.551546)
			(xy 177.601895 -26.606947) (xy 177.602388 -26.634948) (xy 177.601902 -26.662199) (xy 177.594146 -26.716147)
			(xy 177.578791 -26.768442) (xy 177.556149 -26.818019) (xy 177.526683 -26.863869) (xy 177.490992 -26.90506)
			(xy 177.449801 -26.940751) (xy 177.403951 -26.970217) (xy 177.354374 -26.992859) (xy 177.302079 -27.008214)
			(xy 177.248131 -27.01597) (xy 177.193629 -27.01597) (xy 177.139681 -27.008214) (xy 177.087386 -26.992859)
			(xy 177.037809 -26.970217) (xy 176.991959 -26.940751) (xy 176.950768 -26.90506) (xy 176.915077 -26.863869)
			(xy 176.885611 -26.818019) (xy 176.862969 -26.768442) (xy 176.847614 -26.716147) (xy 176.839858 -26.662199)
			(xy 176.839372 -26.634948) (xy 176.839856 -26.606622) (xy 176.848199 -26.550587) (xy 176.864737 -26.496403)
			(xy 176.876456 -26.47061) (xy 176.881991 -26.458001) (xy 176.886763 -26.430889) (xy 176.884122 -26.403487)
			(xy 176.874258 -26.377786) (xy 176.85789 -26.355653) (xy 176.836205 -26.338695) (xy 176.810778 -26.328144)
			(xy 176.783458 -26.324766) (xy 176.769776 -26.326338) (xy 176.757076 -26.328116) (xy 176.743432 -26.330108)
			(xy 176.717903 -26.340509) (xy 176.696092 -26.357367) (xy 176.679592 -26.37945) (xy 176.669608 -26.405145)
			(xy 176.666869 -26.432575) (xy 176.671576 -26.459737) (xy 176.677066 -26.472388) (xy 176.688551 -26.497929)
			(xy 176.704719 -26.551546) (xy 176.712895 -26.606947) (xy 176.713388 -26.634948) (xy 176.712902 -26.662199)
			(xy 176.705146 -26.716147) (xy 176.689791 -26.768442) (xy 176.667149 -26.818019) (xy 176.637683 -26.863869)
			(xy 176.601992 -26.90506) (xy 176.560801 -26.940751) (xy 176.514951 -26.970217) (xy 176.465374 -26.992859)
			(xy 176.413079 -27.008214) (xy 176.359131 -27.01597) (xy 176.304629 -27.01597) (xy 176.250681 -27.008214)
			(xy 176.198386 -26.992859) (xy 176.148809 -26.970217) (xy 176.102959 -26.940751) (xy 176.061768 -26.90506)
			(xy 176.026077 -26.863869) (xy 175.996611 -26.818019) (xy 175.973969 -26.768442) (xy 175.958614 -26.716147)
			(xy 175.950858 -26.662199) (xy 175.950372 -26.634948) (xy 173.365354 -26.634948) (xy 173.360759 -26.666903)
			(xy 173.345402 -26.7192) (xy 173.322759 -26.768779) (xy 173.293289 -26.814631) (xy 173.257594 -26.855821)
			(xy 173.2164 -26.891512) (xy 173.170546 -26.920977) (xy 173.120964 -26.943616) (xy 173.068666 -26.958967)
			(xy 173.014715 -26.966719) (xy 172.987462 -26.96718) (xy 172.961027 -26.966746) (xy 172.908661 -26.959457)
			(xy 172.857803 -26.945012) (xy 172.809425 -26.923685) (xy 172.764454 -26.895885) (xy 172.723749 -26.862145)
			(xy 172.688091 -26.823109) (xy 172.672756 -26.801572) (xy 172.663864 -26.789432) (xy 172.640365 -26.770649)
			(xy 172.612416 -26.759521) (xy 172.582438 -26.757013) (xy 172.553028 -26.763343) (xy 172.526735 -26.77796)
			(xy 172.505838 -26.7996) (xy 172.498512 -26.812748) (xy 172.486215 -26.835915) (xy 172.456232 -26.87895)
			(xy 172.420635 -26.91747) (xy 172.380094 -26.950748) (xy 172.335375 -26.978156) (xy 172.287321 -26.999176)
			(xy 172.23684 -27.013412) (xy 172.184885 -27.020595) (xy 172.15866 -27.021028) (xy 172.131412 -27.020499)
			(xy 172.077472 -27.012738) (xy 172.025184 -26.997381) (xy 171.975615 -26.974738) (xy 171.929772 -26.945273)
			(xy 171.888589 -26.909583) (xy 171.852903 -26.868396) (xy 171.823442 -26.82255) (xy 171.800805 -26.772978)
			(xy 171.785453 -26.720689) (xy 171.777698 -26.666748) (xy 170.56608 -26.666748) (xy 170.56608 -27.107388)
			(xy 180.539642 -27.107388) (xy 180.543713 -27.051766) (xy 180.555839 -26.997329) (xy 180.575762 -26.945238)
			(xy 180.603058 -26.896603) (xy 180.637144 -26.85246) (xy 180.677293 -26.813751) (xy 180.722651 -26.7813)
			(xy 180.772251 -26.755799) (xy 180.825035 -26.737792) (xy 180.879878 -26.727662) (xy 180.935612 -26.725625)
			(xy 180.991049 -26.731725) (xy 181.045006 -26.745831) (xy 181.096335 -26.767643) (xy 181.143941 -26.796697)
			(xy 181.186809 -26.832372) (xy 181.224026 -26.873909) (xy 181.254799 -26.920422) (xy 181.278471 -26.970919)
			(xy 181.294539 -27.024326) (xy 181.302659 -27.079502) (xy 181.303168 -27.107388) (xy 181.302659 -27.135274)
			(xy 181.294539 -27.19045) (xy 181.278471 -27.243857) (xy 181.254799 -27.294354) (xy 181.224026 -27.340867)
			(xy 181.186809 -27.382404) (xy 181.143941 -27.418079) (xy 181.096335 -27.447133) (xy 181.045006 -27.468945)
			(xy 180.991049 -27.483051) (xy 180.935612 -27.489151) (xy 180.879878 -27.487114) (xy 180.825035 -27.476984)
			(xy 180.772251 -27.458977) (xy 180.722651 -27.433476) (xy 180.677293 -27.401025) (xy 180.637144 -27.362316)
			(xy 180.603058 -27.318173) (xy 180.575762 -27.269538) (xy 180.555839 -27.217447) (xy 180.543713 -27.16301)
			(xy 180.539642 -27.107388) (xy 170.56608 -27.107388) (xy 170.56608 -28.031948) (xy 170.743372 -28.031948)
			(xy 170.743858 -28.004697) (xy 170.751614 -27.950749) (xy 170.766969 -27.898454) (xy 170.789611 -27.848877)
			(xy 170.819077 -27.803027) (xy 170.854768 -27.761836) (xy 170.895959 -27.726145) (xy 170.941809 -27.696679)
			(xy 170.991386 -27.674037) (xy 171.043681 -27.658682) (xy 171.097629 -27.650926) (xy 171.152131 -27.650926)
			(xy 171.206079 -27.658682) (xy 171.258374 -27.674037) (xy 171.307951 -27.696679) (xy 171.353801 -27.726145)
			(xy 171.394992 -27.761836) (xy 171.430683 -27.803027) (xy 171.460149 -27.848877) (xy 171.482791 -27.898454)
			(xy 171.498146 -27.950749) (xy 171.505902 -28.004697) (xy 171.506388 -28.031948) (xy 171.505963 -28.058743)
			(xy 171.498451 -28.111804) (xy 171.483595 -28.163294) (xy 171.461687 -28.212202) (xy 171.433157 -28.257567)
			(xy 171.398566 -28.298498) (xy 171.37888 -28.316682) (xy 171.368525 -28.32644) (xy 171.3533 -28.350466)
			(xy 171.345303 -28.377762) (xy 171.345158 -28.406206) (xy 171.352875 -28.433583) (xy 171.367854 -28.457763)
			(xy 171.38893 -28.476865) (xy 171.401486 -28.48356) (xy 171.42512 -28.495655) (xy 171.469033 -28.525496)
			(xy 171.508381 -28.56114) (xy 171.542404 -28.601898) (xy 171.570445 -28.646981) (xy 171.591961 -28.695518)
			(xy 171.600337 -28.72486) (xy 174.124112 -28.72486) (xy 174.124575 -28.698208) (xy 174.132012 -28.645427)
			(xy 174.146724 -28.594193) (xy 174.168422 -28.545506) (xy 174.196685 -28.500313) (xy 174.230963 -28.459493)
			(xy 174.270589 -28.423841) (xy 174.31479 -28.39405) (xy 174.362708 -28.370701) (xy 174.413408 -28.354249)
			(xy 174.43958 -28.349194) (xy 174.453331 -28.346366) (xy 174.47862 -28.334198) (xy 174.499643 -28.315607)
			(xy 174.514814 -28.291997) (xy 174.522988 -28.265149) (xy 174.523549 -28.237091) (xy 174.516453 -28.209938)
			(xy 174.502236 -28.185742) (xy 174.492412 -28.175712) (xy 174.474221 -28.157679) (xy 174.442384 -28.117553)
			(xy 174.416201 -28.073528) (xy 174.396143 -28.026396) (xy 174.38257 -27.977005) (xy 174.375727 -27.926241)
			(xy 174.375318 -27.90063) (xy 174.375804 -27.873379) (xy 174.38356 -27.819431) (xy 174.398915 -27.767136)
			(xy 174.421557 -27.717559) (xy 174.451023 -27.671709) (xy 174.486714 -27.630518) (xy 174.527905 -27.594827)
			(xy 174.573755 -27.565361) (xy 174.623332 -27.542719) (xy 174.675627 -27.527364) (xy 174.729575 -27.519608)
			(xy 174.784077 -27.519608) (xy 174.838025 -27.527364) (xy 174.848882 -27.530552) (xy 185.020964 -27.530552)
			(xy 185.025035 -27.47493) (xy 185.037161 -27.420493) (xy 185.057084 -27.368402) (xy 185.08438 -27.319767)
			(xy 185.118466 -27.275624) (xy 185.158615 -27.236915) (xy 185.203973 -27.204464) (xy 185.253573 -27.178963)
			(xy 185.306357 -27.160956) (xy 185.3612 -27.150826) (xy 185.416934 -27.148789) (xy 185.472371 -27.154889)
			(xy 185.526328 -27.168995) (xy 185.577657 -27.190807) (xy 185.625263 -27.219861) (xy 185.668131 -27.255536)
			(xy 185.705348 -27.297073) (xy 185.736121 -27.343586) (xy 185.759793 -27.394083) (xy 185.775861 -27.44749)
			(xy 185.783981 -27.502666) (xy 185.78449 -27.530552) (xy 185.783981 -27.558438) (xy 185.775861 -27.613614)
			(xy 185.759793 -27.667021) (xy 185.736121 -27.717518) (xy 185.705348 -27.764031) (xy 185.668131 -27.805568)
			(xy 185.625263 -27.841243) (xy 185.577657 -27.870297) (xy 185.526328 -27.892109) (xy 185.472371 -27.906215)
			(xy 185.416934 -27.912315) (xy 185.3612 -27.910278) (xy 185.306357 -27.900148) (xy 185.253573 -27.882141)
			(xy 185.203973 -27.85664) (xy 185.158615 -27.824189) (xy 185.118466 -27.78548) (xy 185.08438 -27.741337)
			(xy 185.057084 -27.692702) (xy 185.037161 -27.640611) (xy 185.025035 -27.586174) (xy 185.020964 -27.530552)
			(xy 174.848882 -27.530552) (xy 174.89032 -27.542719) (xy 174.939897 -27.565361) (xy 174.985747 -27.594827)
			(xy 175.026938 -27.630518) (xy 175.062629 -27.671709) (xy 175.092095 -27.717559) (xy 175.114737 -27.767136)
			(xy 175.130092 -27.819431) (xy 175.137848 -27.873379) (xy 175.138334 -27.90063) (xy 175.137803 -27.927278)
			(xy 175.130368 -27.980053) (xy 175.115661 -28.03128) (xy 175.093968 -28.079962) (xy 175.065711 -28.125152)
			(xy 175.031441 -28.165969) (xy 174.991824 -28.20162) (xy 174.947631 -28.231411) (xy 174.899722 -28.254761)
			(xy 174.84903 -28.271218) (xy 174.822866 -28.276296) (xy 174.809122 -28.279158) (xy 174.78383 -28.291316)
			(xy 174.762802 -28.3099) (xy 174.747628 -28.333506) (xy 174.739451 -28.360351) (xy 174.738891 -28.388408)
			(xy 174.745988 -28.415558) (xy 174.760208 -28.439751) (xy 174.770034 -28.449778) (xy 174.78821 -28.467826)
			(xy 174.820051 -28.507948) (xy 174.846237 -28.551969) (xy 174.866298 -28.599098) (xy 174.879873 -28.648488)
			(xy 174.886718 -28.699249) (xy 174.887128 -28.72486) (xy 174.886664 -28.751206) (xy 174.879435 -28.8034)
			(xy 174.865096 -28.854104) (xy 174.843918 -28.902353) (xy 174.816306 -28.947231) (xy 174.782782 -28.987884)
			(xy 174.763684 -29.006038) (xy 174.753683 -29.01594) (xy 174.738953 -29.039903) (xy 174.731317 -29.066975)
			(xy 174.731356 -29.095103) (xy 174.739065 -29.122154) (xy 174.753862 -29.146076) (xy 174.763938 -29.155898)
			(xy 174.783138 -29.17405) (xy 174.816857 -29.214727) (xy 174.841886 -29.255212) (xy 176.187862 -29.255212)
			(xy 176.188401 -29.227892) (xy 176.196736 -29.173892) (xy 176.213214 -29.121796) (xy 176.237447 -29.072824)
			(xy 176.268869 -29.028123) (xy 176.28743 -29.00807) (xy 176.297817 -28.996439) (xy 176.311645 -28.968509)
			(xy 176.316404 -28.937709) (xy 176.311651 -28.906908) (xy 176.297827 -28.878975) (xy 176.28743 -28.867354)
			(xy 176.268809 -28.847348) (xy 176.237352 -28.802654) (xy 176.213104 -28.753673) (xy 176.196635 -28.701559)
			(xy 176.188332 -28.64754) (xy 176.187862 -28.620212) (xy 176.18836 -28.593563) (xy 176.196303 -28.540859)
			(xy 176.212013 -28.489929) (xy 176.235139 -28.441908) (xy 176.265163 -28.397871) (xy 176.301415 -28.3588)
			(xy 176.343086 -28.325569) (xy 176.389244 -28.29892) (xy 176.438858 -28.279448) (xy 176.49082 -28.267588)
			(xy 176.54397 -28.263605) (xy 176.59712 -28.267588) (xy 176.649082 -28.279448) (xy 176.698696 -28.29892)
			(xy 176.744854 -28.325569) (xy 176.786525 -28.3588) (xy 176.822777 -28.397871) (xy 176.852801 -28.441908)
			(xy 176.875927 -28.489929) (xy 176.891637 -28.540859) (xy 176.89958 -28.593563) (xy 176.900078 -28.620212)
			(xy 176.89957 -28.647533) (xy 176.89123 -28.701536) (xy 176.874746 -28.753633) (xy 176.850505 -28.802604)
			(xy 176.819075 -28.847302) (xy 176.80051 -28.867354) (xy 176.790105 -28.878968) (xy 176.776287 -28.906905)
			(xy 176.771535 -28.937709) (xy 176.776292 -28.968511) (xy 176.790115 -28.996446) (xy 176.80051 -29.00807)
			(xy 176.819102 -29.028102) (xy 176.850561 -29.07279) (xy 176.874814 -29.121764) (xy 176.89129 -29.173872)
			(xy 176.899602 -29.227886) (xy 176.900078 -29.255212) (xy 177.087784 -29.255212) (xy 177.088317 -29.227892)
			(xy 177.096653 -29.173891) (xy 177.113131 -29.121795) (xy 177.137366 -29.072823) (xy 177.16879 -29.028123)
			(xy 177.187352 -29.00807) (xy 177.197737 -28.996438) (xy 177.211562 -28.968508) (xy 177.21632 -28.937709)
			(xy 177.211568 -28.906909) (xy 177.197747 -28.878976) (xy 177.187352 -28.867354) (xy 177.168734 -28.847345)
			(xy 177.137277 -28.802652) (xy 177.113027 -28.753672) (xy 177.096557 -28.701559) (xy 177.088254 -28.647539)
			(xy 177.087784 -28.620212) (xy 177.088282 -28.593563) (xy 177.096225 -28.540859) (xy 177.111935 -28.489929)
			(xy 177.135061 -28.441908) (xy 177.165085 -28.397871) (xy 177.201337 -28.3588) (xy 177.243008 -28.325569)
			(xy 177.289166 -28.29892) (xy 177.33878 -28.279448) (xy 177.390742 -28.267588) (xy 177.443892 -28.263605)
			(xy 177.497042 -28.267588) (xy 177.549004 -28.279448) (xy 177.598618 -28.29892) (xy 177.644776 -28.325569)
			(xy 177.686447 -28.3588) (xy 177.722699 -28.397871) (xy 177.752723 -28.441908) (xy 177.775849 -28.489929)
			(xy 177.791559 -28.540859) (xy 177.799502 -28.593563) (xy 177.8 -28.620212) (xy 177.799486 -28.647533)
			(xy 177.791146 -28.701535) (xy 177.774664 -28.753631) (xy 177.750424 -28.802603) (xy 177.718996 -28.847302)
			(xy 177.700432 -28.867354) (xy 177.690025 -28.878967) (xy 177.676204 -28.906904) (xy 177.671452 -28.937709)
			(xy 177.676209 -28.968512) (xy 177.690035 -28.996447) (xy 177.700432 -29.00807) (xy 177.719028 -29.028099)
			(xy 177.750485 -29.072788) (xy 177.774737 -29.121763) (xy 177.791213 -29.173871) (xy 177.799524 -29.227886)
			(xy 177.8 -29.255212) (xy 177.987706 -29.255212) (xy 177.988233 -29.227892) (xy 177.996569 -29.17389)
			(xy 178.013049 -29.121794) (xy 178.037285 -29.072822) (xy 178.068711 -29.028122) (xy 178.087274 -29.00807)
			(xy 178.097657 -28.996437) (xy 178.111479 -28.968507) (xy 178.116236 -28.937709) (xy 178.111485 -28.90691)
			(xy 178.097667 -28.878977) (xy 178.087274 -28.867354) (xy 178.068643 -28.847357) (xy 178.03719 -28.802659)
			(xy 178.012945 -28.753676) (xy 177.996477 -28.701561) (xy 177.988176 -28.64754) (xy 177.987706 -28.620212)
			(xy 177.988204 -28.593563) (xy 177.996147 -28.540859) (xy 178.011857 -28.489929) (xy 178.034983 -28.441908)
			(xy 178.065007 -28.397871) (xy 178.101259 -28.3588) (xy 178.14293 -28.325569) (xy 178.189088 -28.29892)
			(xy 178.238702 -28.279448) (xy 178.290664 -28.267588) (xy 178.343814 -28.263605) (xy 178.396964 -28.267588)
			(xy 178.448926 -28.279448) (xy 178.49854 -28.29892) (xy 178.544698 -28.325569) (xy 178.586369 -28.3588)
			(xy 178.622621 -28.397871) (xy 178.652645 -28.441908) (xy 178.675771 -28.489929) (xy 178.691481 -28.540859)
			(xy 178.699424 -28.593563) (xy 178.699922 -28.620212) (xy 178.699402 -28.647533) (xy 178.691063 -28.701534)
			(xy 178.674581 -28.75363) (xy 178.650344 -28.802602) (xy 178.618917 -28.847301) (xy 178.600354 -28.867354)
			(xy 178.589945 -28.878966) (xy 178.576121 -28.906903) (xy 178.571367 -28.937709) (xy 178.576126 -28.968513)
			(xy 178.589955 -28.996448) (xy 178.600354 -29.00807) (xy 178.618936 -29.028111) (xy 178.650399 -29.072795)
			(xy 178.674655 -29.121767) (xy 178.691133 -29.173873) (xy 178.699446 -29.227887) (xy 178.699922 -29.255212)
			(xy 178.887882 -29.255212) (xy 178.888415 -29.227892) (xy 178.896751 -29.173891) (xy 178.91323 -29.121795)
			(xy 178.937464 -29.072823) (xy 178.968888 -29.028123) (xy 178.98745 -29.00807) (xy 178.997835 -28.996438)
			(xy 179.011661 -28.968508) (xy 179.016419 -28.937709) (xy 179.011666 -28.906908) (xy 178.997845 -28.878976)
			(xy 178.98745 -28.867354) (xy 178.968832 -28.847345) (xy 178.937374 -28.802652) (xy 178.913125 -28.753672)
			(xy 178.896655 -28.701559) (xy 178.888352 -28.647539) (xy 178.887882 -28.620212) (xy 178.88838 -28.593563)
			(xy 178.896323 -28.540859) (xy 178.912033 -28.489929) (xy 178.935159 -28.441908) (xy 178.965183 -28.397871)
			(xy 179.001435 -28.3588) (xy 179.043106 -28.325569) (xy 179.089264 -28.29892) (xy 179.138878 -28.279448)
			(xy 179.19084 -28.267588) (xy 179.24399 -28.263605) (xy 179.29714 -28.267588) (xy 179.349102 -28.279448)
			(xy 179.398716 -28.29892) (xy 179.444874 -28.325569) (xy 179.486545 -28.3588) (xy 179.522797 -28.397871)
			(xy 179.552821 -28.441908) (xy 179.575947 -28.489929) (xy 179.591657 -28.540859) (xy 179.5996 -28.593563)
			(xy 179.600098 -28.620212) (xy 179.599585 -28.647533) (xy 179.591245 -28.701535) (xy 179.574762 -28.753632)
			(xy 179.550523 -28.802603) (xy 179.519094 -28.847302) (xy 179.50053 -28.867354) (xy 179.490123 -28.878967)
			(xy 179.476303 -28.906904) (xy 179.47155 -28.937709) (xy 179.476308 -28.968512) (xy 179.490133 -28.996447)
			(xy 179.50053 -29.00807) (xy 179.519125 -29.028099) (xy 179.550583 -29.072788) (xy 179.574835 -29.121763)
			(xy 179.591311 -29.173871) (xy 179.599622 -29.227886) (xy 179.600098 -29.255212) (xy 179.5996 -29.281861)
			(xy 179.591657 -29.334565) (xy 179.575947 -29.385495) (xy 179.552821 -29.433516) (xy 179.522797 -29.477553)
			(xy 179.486545 -29.516624) (xy 179.444874 -29.549855) (xy 179.398716 -29.576504) (xy 179.349102 -29.595976)
			(xy 179.29714 -29.607836) (xy 179.24399 -29.61182) (xy 179.19084 -29.607836) (xy 179.138878 -29.595976)
			(xy 179.089264 -29.576504) (xy 179.043106 -29.549855) (xy 179.001435 -29.516624) (xy 178.965183 -29.477553)
			(xy 178.935159 -29.433516) (xy 178.912033 -29.385495) (xy 178.896323 -29.334565) (xy 178.88838 -29.281861)
			(xy 178.887882 -29.255212) (xy 178.699922 -29.255212) (xy 178.699424 -29.281861) (xy 178.691481 -29.334565)
			(xy 178.675771 -29.385495) (xy 178.652645 -29.433516) (xy 178.622621 -29.477553) (xy 178.586369 -29.516624)
			(xy 178.544698 -29.549855) (xy 178.49854 -29.576504) (xy 178.448926 -29.595976) (xy 178.396964 -29.607836)
			(xy 178.343814 -29.61182) (xy 178.290664 -29.607836) (xy 178.238702 -29.595976) (xy 178.189088 -29.576504)
			(xy 178.14293 -29.549855) (xy 178.101259 -29.516624) (xy 178.065007 -29.477553) (xy 178.034983 -29.433516)
			(xy 178.011857 -29.385495) (xy 177.996147 -29.334565) (xy 177.988204 -29.281861) (xy 177.987706 -29.255212)
			(xy 177.8 -29.255212) (xy 177.799502 -29.281861) (xy 177.791559 -29.334565) (xy 177.775849 -29.385495)
			(xy 177.752723 -29.433516) (xy 177.722699 -29.477553) (xy 177.686447 -29.516624) (xy 177.644776 -29.549855)
			(xy 177.598618 -29.576504) (xy 177.549004 -29.595976) (xy 177.497042 -29.607836) (xy 177.443892 -29.61182)
			(xy 177.390742 -29.607836) (xy 177.33878 -29.595976) (xy 177.289166 -29.576504) (xy 177.243008 -29.549855)
			(xy 177.201337 -29.516624) (xy 177.165085 -29.477553) (xy 177.135061 -29.433516) (xy 177.111935 -29.385495)
			(xy 177.096225 -29.334565) (xy 177.088282 -29.281861) (xy 177.087784 -29.255212) (xy 176.900078 -29.255212)
			(xy 176.89958 -29.281861) (xy 176.891637 -29.334565) (xy 176.875927 -29.385495) (xy 176.852801 -29.433516)
			(xy 176.822777 -29.477553) (xy 176.786525 -29.516624) (xy 176.744854 -29.549855) (xy 176.698696 -29.576504)
			(xy 176.649082 -29.595976) (xy 176.59712 -29.607836) (xy 176.54397 -29.61182) (xy 176.49082 -29.607836)
			(xy 176.438858 -29.595976) (xy 176.389244 -29.576504) (xy 176.343086 -29.549855) (xy 176.301415 -29.516624)
			(xy 176.265163 -29.477553) (xy 176.235139 -29.433516) (xy 176.212013 -29.385495) (xy 176.196303 -29.334565)
			(xy 176.18836 -29.281861) (xy 176.187862 -29.255212) (xy 174.841886 -29.255212) (xy 174.844641 -29.259668)
			(xy 174.865959 -29.308012) (xy 174.880402 -29.358836) (xy 174.887694 -29.411166) (xy 174.888144 -29.437584)
			(xy 174.887658 -29.464835) (xy 174.879902 -29.518783) (xy 174.864547 -29.571078) (xy 174.841905 -29.620655)
			(xy 174.812439 -29.666505) (xy 174.776748 -29.707696) (xy 174.735557 -29.743387) (xy 174.689707 -29.772853)
			(xy 174.64013 -29.795495) (xy 174.587835 -29.81085) (xy 174.533887 -29.818606) (xy 174.479385 -29.818606)
			(xy 174.425437 -29.81085) (xy 174.373142 -29.795495) (xy 174.323565 -29.772853) (xy 174.277715 -29.743387)
			(xy 174.236524 -29.707696) (xy 174.200833 -29.666505) (xy 174.171367 -29.620655) (xy 174.148725 -29.571078)
			(xy 174.13337 -29.518783) (xy 174.125614 -29.464835) (xy 174.125128 -29.437584) (xy 174.125537 -29.411236)
			(xy 174.132774 -29.359038) (xy 174.147123 -29.308333) (xy 174.168311 -29.260084) (xy 174.195934 -29.215207)
			(xy 174.229468 -29.174558) (xy 174.248572 -29.156406) (xy 174.258625 -29.146554) (xy 174.273344 -29.122575)
			(xy 174.280968 -29.095492) (xy 174.280919 -29.067355) (xy 174.2732 -29.040298) (xy 174.258397 -29.016371)
			(xy 174.248318 -29.006546) (xy 174.229102 -28.98841) (xy 174.195382 -28.947731) (xy 174.167599 -28.902787)
			(xy 174.146283 -28.854439) (xy 174.131844 -28.803612) (xy 174.124558 -28.751279) (xy 174.124112 -28.72486)
			(xy 171.600337 -28.72486) (xy 171.606535 -28.746571) (xy 171.613886 -28.799152) (xy 171.614338 -28.825698)
			(xy 171.613852 -28.852949) (xy 171.606096 -28.906897) (xy 171.590741 -28.959192) (xy 171.568099 -29.008769)
			(xy 171.538633 -29.054619) (xy 171.502942 -29.09581) (xy 171.461751 -29.131501) (xy 171.415901 -29.160967)
			(xy 171.366324 -29.183609) (xy 171.314029 -29.198964) (xy 171.260081 -29.20672) (xy 171.205579 -29.20672)
			(xy 171.151631 -29.198964) (xy 171.099336 -29.183609) (xy 171.049759 -29.160967) (xy 171.003909 -29.131501)
			(xy 170.962718 -29.09581) (xy 170.927027 -29.054619) (xy 170.897561 -29.008769) (xy 170.874919 -28.959192)
			(xy 170.859564 -28.906897) (xy 170.851808 -28.852949) (xy 170.851322 -28.825698) (xy 170.851775 -28.798904)
			(xy 170.859281 -28.745844) (xy 170.874131 -28.694354) (xy 170.896034 -28.645446) (xy 170.924559 -28.600081)
			(xy 170.959146 -28.559149) (xy 170.97883 -28.540964) (xy 170.989132 -28.531154) (xy 171.004357 -28.507141)
			(xy 171.012357 -28.479857) (xy 171.012509 -28.451425) (xy 171.004802 -28.424057) (xy 170.989836 -28.399882)
			(xy 170.968774 -28.380782) (xy 170.956224 -28.374086) (xy 170.932611 -28.361952) (xy 170.888699 -28.332116)
			(xy 170.84935 -28.296478) (xy 170.815325 -28.255726) (xy 170.787282 -28.210649) (xy 170.765763 -28.162117)
			(xy 170.751184 -28.111069) (xy 170.743827 -28.058492) (xy 170.743372 -28.031948) (xy 170.56608 -28.031948)
			(xy 170.56608 -29.775756) (xy 171.211135 -29.775756) (xy 171.211135 -29.721244) (xy 171.218893 -29.667287)
			(xy 171.234252 -29.614983) (xy 171.256899 -29.565397) (xy 171.286372 -29.51954) (xy 171.322072 -29.478344)
			(xy 171.363272 -29.442648) (xy 171.409132 -29.41318) (xy 171.45872 -29.390538) (xy 171.511026 -29.375185)
			(xy 171.564984 -29.367432) (xy 171.59224 -29.366972) (xy 171.620347 -29.367487) (xy 171.675947 -29.375781)
			(xy 171.702984 -29.383482) (xy 171.716683 -29.387092) (xy 171.744997 -29.387472) (xy 171.772331 -29.380074)
			(xy 171.796588 -29.365464) (xy 171.815909 -29.344763) (xy 171.828814 -29.319557) (xy 171.832016 -29.305758)
			(xy 171.837518 -29.280075) (xy 171.854669 -29.230431) (xy 171.878468 -29.183608) (xy 171.908465 -29.140493)
			(xy 171.944093 -29.1019) (xy 171.984677 -29.068559) (xy 172.029452 -29.0411) (xy 172.077569 -29.020042)
			(xy 172.128121 -29.005784) (xy 172.18015 -28.998594) (xy 172.206412 -28.998164) (xy 172.233661 -28.998707)
			(xy 172.287603 -29.006464) (xy 172.339892 -29.021819) (xy 172.389464 -29.04446) (xy 172.43531 -29.073924)
			(xy 172.476496 -29.109613) (xy 172.512183 -29.1508) (xy 172.541646 -29.196646) (xy 172.564285 -29.246219)
			(xy 172.579638 -29.298509) (xy 172.587394 -29.352451) (xy 172.587394 -29.406949) (xy 172.579638 -29.460891)
			(xy 172.564285 -29.513181) (xy 172.541646 -29.562754) (xy 172.512183 -29.6086) (xy 172.476496 -29.649787)
			(xy 172.43531 -29.685476) (xy 172.389464 -29.71494) (xy 172.339892 -29.737581) (xy 172.287603 -29.752936)
			(xy 172.233661 -29.760693) (xy 172.206412 -29.76118) (xy 172.178305 -29.760652) (xy 172.122705 -29.752367)
			(xy 172.095668 -29.74467) (xy 172.081963 -29.741077) (xy 172.053649 -29.740684) (xy 172.026312 -29.748074)
			(xy 172.002053 -29.762682) (xy 171.982732 -29.783384) (xy 171.969833 -29.808593) (xy 171.966636 -29.822394)
			(xy 171.962389 -29.841952) (xy 180.652674 -29.841952) (xy 180.653185 -29.814379) (xy 180.661129 -29.759809)
			(xy 180.676846 -29.70695) (xy 180.700008 -29.656904) (xy 180.730132 -29.610713) (xy 180.766591 -29.56934)
			(xy 180.787294 -29.551122) (xy 180.798239 -29.541272) (xy 180.814311 -29.516608) (xy 180.822689 -29.488388)
			(xy 180.82268 -29.45895) (xy 180.814284 -29.430735) (xy 180.798198 -29.406081) (xy 180.787294 -29.396182)
			(xy 180.76657 -29.377985) (xy 180.730101 -29.336613) (xy 180.69997 -29.29042) (xy 180.676807 -29.24037)
			(xy 180.661093 -29.187504) (xy 180.653157 -29.132928) (xy 180.652674 -29.105352) (xy 180.653133 -29.0781)
			(xy 180.660896 -29.024153) (xy 180.676256 -28.971859) (xy 180.698901 -28.922282) (xy 180.728371 -28.876433)
			(xy 180.764065 -28.835244) (xy 180.805257 -28.799553) (xy 180.851109 -28.770087) (xy 180.900687 -28.747445)
			(xy 180.952982 -28.732089) (xy 181.00693 -28.724331) (xy 181.034182 -28.723844) (xy 181.061439 -28.724338)
			(xy 181.115398 -28.732103) (xy 181.167704 -28.747462) (xy 181.217293 -28.770105) (xy 181.263159 -28.799569)
			(xy 181.304368 -28.835257) (xy 181.340083 -28.876443) (xy 181.355238 -28.899104) (xy 181.363519 -28.911031)
			(xy 181.385455 -28.930035) (xy 181.411855 -28.94209) (xy 181.440582 -28.94622) (xy 181.469309 -28.94209)
			(xy 181.495709 -28.930035) (xy 181.517645 -28.911031) (xy 181.525926 -28.899104) (xy 181.541103 -28.876457)
			(xy 181.576806 -28.835261) (xy 181.618008 -28.799565) (xy 181.66387 -28.770094) (xy 181.713459 -28.747449)
			(xy 181.765765 -28.732091) (xy 181.819725 -28.724331) (xy 181.846982 -28.723844) (xy 181.874231 -28.724395)
			(xy 181.928173 -28.732148) (xy 181.980464 -28.747498) (xy 182.030038 -28.770134) (xy 182.075886 -28.799593)
			(xy 182.117075 -28.835278) (xy 182.152767 -28.876461) (xy 182.182235 -28.922304) (xy 182.204879 -28.971874)
			(xy 182.220238 -29.024162) (xy 182.228 -29.078103) (xy 182.22849 -29.105352) (xy 182.227995 -29.132926)
			(xy 182.220049 -29.187497) (xy 182.20433 -29.240357) (xy 182.181165 -29.290403) (xy 182.151038 -29.336593)
			(xy 182.114575 -29.377965) (xy 182.09387 -29.396182) (xy 182.083024 -29.406131) (xy 182.066955 -29.430768)
			(xy 182.058569 -29.458962) (xy 182.05856 -29.488376) (xy 182.066929 -29.516575) (xy 182.082983 -29.541222)
			(xy 182.09387 -29.551122) (xy 182.114589 -29.569325) (xy 182.15106 -29.610695) (xy 182.181192 -29.656886)
			(xy 182.204357 -29.706936) (xy 182.220071 -29.7598) (xy 182.228007 -29.814377) (xy 182.22849 -29.841952)
			(xy 182.228 -29.869204) (xy 182.220249 -29.923155) (xy 182.204898 -29.975454) (xy 182.18226 -30.025035)
			(xy 182.152795 -30.070889) (xy 182.117104 -30.112083) (xy 182.075913 -30.147777) (xy 182.030061 -30.177246)
			(xy 181.980482 -30.199888) (xy 181.928185 -30.215243) (xy 181.874234 -30.222998) (xy 181.846982 -30.22346)
			(xy 181.819724 -30.222991) (xy 181.765764 -30.215222) (xy 181.713458 -30.199858) (xy 181.663868 -30.177211)
			(xy 181.618003 -30.147743) (xy 181.576795 -30.112051) (xy 181.541081 -30.070862) (xy 181.525926 -30.0482)
			(xy 181.517645 -30.036273) (xy 181.495709 -30.017269) (xy 181.469309 -30.005214) (xy 181.440582 -30.001084)
			(xy 181.411855 -30.005214) (xy 181.385455 -30.017269) (xy 181.363519 -30.036273) (xy 181.355238 -30.0482)
			(xy 181.340086 -30.070864) (xy 181.304378 -30.11206) (xy 181.263172 -30.147755) (xy 181.217306 -30.177224)
			(xy 181.167713 -30.199866) (xy 181.115403 -30.21522) (xy 181.061441 -30.222975) (xy 181.034182 -30.22346)
			(xy 181.006926 -30.223062) (xy 180.952971 -30.215301) (xy 180.900669 -30.19994) (xy 180.851085 -30.177292)
			(xy 180.80523 -30.147818) (xy 180.764036 -30.112117) (xy 180.728343 -30.070917) (xy 180.698876 -30.025057)
			(xy 180.676237 -29.975469) (xy 180.660885 -29.923165) (xy 180.653134 -29.869208) (xy 180.652674 -29.841952)
			(xy 171.962389 -29.841952) (xy 171.960443 -29.850915) (xy 171.940539 -29.905777) (xy 171.912514 -29.956969)
			(xy 171.877021 -30.003297) (xy 171.834887 -30.043679) (xy 171.787095 -30.077175) (xy 171.73476 -30.103003)
			(xy 171.679103 -30.120561) (xy 171.621421 -30.129438) (xy 171.59224 -30.129988) (xy 171.564984 -30.129568)
			(xy 171.511026 -30.121815) (xy 171.45872 -30.106462) (xy 171.409132 -30.08382) (xy 171.363272 -30.054352)
			(xy 171.322072 -30.018656) (xy 171.286372 -29.97746) (xy 171.256899 -29.931603) (xy 171.234252 -29.882017)
			(xy 171.218893 -29.829713) (xy 171.211135 -29.775756) (xy 170.56608 -29.775756) (xy 170.56608 -30.395672)
			(xy 171.824394 -30.395672) (xy 171.828465 -30.34005) (xy 171.840591 -30.285613) (xy 171.860514 -30.233522)
			(xy 171.88781 -30.184887) (xy 171.921896 -30.140744) (xy 171.962045 -30.102035) (xy 172.007403 -30.069584)
			(xy 172.057003 -30.044083) (xy 172.109787 -30.026076) (xy 172.16463 -30.015946) (xy 172.220364 -30.013909)
			(xy 172.275801 -30.020009) (xy 172.329758 -30.034115) (xy 172.381087 -30.055927) (xy 172.428693 -30.084981)
			(xy 172.471561 -30.120656) (xy 172.508778 -30.162193) (xy 172.539551 -30.208706) (xy 172.563223 -30.259203)
			(xy 172.579291 -30.31261) (xy 172.587411 -30.367786) (xy 172.58792 -30.395672) (xy 172.587411 -30.423558)
			(xy 172.579291 -30.478734) (xy 172.563223 -30.532141) (xy 172.539551 -30.582638) (xy 172.508778 -30.629151)
			(xy 172.471561 -30.670688) (xy 172.428693 -30.706363) (xy 172.381087 -30.735417) (xy 172.329758 -30.757229)
			(xy 172.275801 -30.771335) (xy 172.220364 -30.777435) (xy 172.16463 -30.775398) (xy 172.109787 -30.765268)
			(xy 172.057003 -30.747261) (xy 172.007403 -30.72176) (xy 171.962045 -30.689309) (xy 171.921896 -30.6506)
			(xy 171.88781 -30.606457) (xy 171.860514 -30.557822) (xy 171.840591 -30.505731) (xy 171.828465 -30.451294)
			(xy 171.824394 -30.395672) (xy 170.56608 -30.395672) (xy 170.56608 -31.446248) (xy 176.813144 -31.446248)
			(xy 176.813145 -31.39174) (xy 176.820904 -31.337786) (xy 176.836262 -31.285486) (xy 176.858907 -31.235903)
			(xy 176.888378 -31.190049) (xy 176.924075 -31.148855) (xy 176.965271 -31.113161) (xy 177.011128 -31.083693)
			(xy 177.060712 -31.061052) (xy 177.113013 -31.045698) (xy 177.166968 -31.037943) (xy 177.221476 -31.037946)
			(xy 177.27543 -31.045707) (xy 177.327729 -31.061067) (xy 177.377311 -31.083715) (xy 177.423164 -31.113188)
			(xy 177.464356 -31.148886) (xy 177.500048 -31.190084) (xy 177.529514 -31.235942) (xy 177.552154 -31.285527)
			(xy 177.567506 -31.337829) (xy 177.575258 -31.391784) (xy 177.575718 -31.419038) (xy 177.575718 -31.428944)
			(xy 177.575825 -31.44294) (xy 177.582765 -31.470045) (xy 177.5968 -31.49425) (xy 177.616878 -31.513737)
			(xy 177.64149 -31.527045) (xy 177.66879 -31.533174) (xy 177.696728 -31.531664) (xy 177.723209 -31.522629)
			(xy 177.734976 -31.51505) (xy 177.759047 -31.498984) (xy 177.811029 -31.473548) (xy 177.866258 -31.45626)
			(xy 177.923464 -31.447515) (xy 177.9524 -31.446978) (xy 177.979653 -31.447455) (xy 178.033604 -31.455212)
			(xy 178.085903 -31.470569) (xy 178.135483 -31.493212) (xy 178.181336 -31.52268) (xy 178.222529 -31.558374)
			(xy 178.258223 -31.599567) (xy 178.287691 -31.645421) (xy 178.310333 -31.695002) (xy 178.325689 -31.7473)
			(xy 178.333445 -31.801252) (xy 178.333444 -31.855758) (xy 178.325687 -31.909709) (xy 178.312618 -31.954216)
			(xy 179.198014 -31.954216) (xy 179.202085 -31.898594) (xy 179.214211 -31.844157) (xy 179.234134 -31.792066)
			(xy 179.26143 -31.743431) (xy 179.295516 -31.699288) (xy 179.335665 -31.660579) (xy 179.381023 -31.628128)
			(xy 179.430623 -31.602627) (xy 179.483407 -31.58462) (xy 179.53825 -31.57449) (xy 179.593984 -31.572453)
			(xy 179.649421 -31.578553) (xy 179.703378 -31.592659) (xy 179.754707 -31.614471) (xy 179.802313 -31.643525)
			(xy 179.806794 -31.647254) (xy 182.48193 -31.647254) (xy 182.48193 -31.592746) (xy 182.489687 -31.538793)
			(xy 182.505043 -31.486493) (xy 182.527686 -31.436911) (xy 182.557154 -31.391056) (xy 182.592848 -31.349861)
			(xy 182.634041 -31.314165) (xy 182.679895 -31.284694) (xy 182.729476 -31.262049) (xy 182.781776 -31.246691)
			(xy 182.835728 -31.238931) (xy 182.862982 -31.238444) (xy 182.890239 -31.238938) (xy 182.944198 -31.246703)
			(xy 182.996504 -31.262062) (xy 183.046093 -31.284705) (xy 183.091959 -31.314169) (xy 183.133168 -31.349857)
			(xy 183.168883 -31.391043) (xy 183.184038 -31.413704) (xy 183.192319 -31.425631) (xy 183.214255 -31.444635)
			(xy 183.240655 -31.45669) (xy 183.269382 -31.46082) (xy 183.298109 -31.45669) (xy 183.324509 -31.444635)
			(xy 183.346445 -31.425631) (xy 183.354726 -31.413704) (xy 183.369903 -31.391057) (xy 183.405606 -31.349861)
			(xy 183.446808 -31.314165) (xy 183.49267 -31.284694) (xy 183.542259 -31.262049) (xy 183.594565 -31.246691)
			(xy 183.648525 -31.238931) (xy 183.675782 -31.238444) (xy 183.703032 -31.239002) (xy 183.756978 -31.246756)
			(xy 183.809272 -31.262108) (xy 183.858848 -31.284747) (xy 183.904698 -31.314211) (xy 183.945887 -31.3499)
			(xy 183.981578 -31.391088) (xy 184.011044 -31.436936) (xy 184.033685 -31.486511) (xy 184.04904 -31.538804)
			(xy 184.056797 -31.59275) (xy 184.056797 -31.64725) (xy 184.04904 -31.701196) (xy 184.033685 -31.753489)
			(xy 184.011044 -31.803064) (xy 183.981578 -31.848912) (xy 183.945887 -31.8901) (xy 183.904698 -31.925789)
			(xy 183.858848 -31.955253) (xy 183.809272 -31.977892) (xy 183.756978 -31.993244) (xy 183.703032 -32.000998)
			(xy 183.675782 -32.00146) (xy 183.648524 -32.000991) (xy 183.594564 -31.993222) (xy 183.542258 -31.977858)
			(xy 183.492668 -31.955211) (xy 183.446803 -31.925743) (xy 183.405595 -31.890051) (xy 183.369881 -31.848862)
			(xy 183.354726 -31.8262) (xy 183.346445 -31.814273) (xy 183.324509 -31.795269) (xy 183.298109 -31.783214)
			(xy 183.269382 -31.779084) (xy 183.240655 -31.783214) (xy 183.214255 -31.795269) (xy 183.192319 -31.814273)
			(xy 183.184038 -31.8262) (xy 183.168886 -31.848864) (xy 183.133178 -31.89006) (xy 183.091972 -31.925755)
			(xy 183.046106 -31.955224) (xy 182.996513 -31.977866) (xy 182.944203 -31.99322) (xy 182.890241 -32.000975)
			(xy 182.862982 -32.00146) (xy 182.835728 -32.001069) (xy 182.781776 -31.993309) (xy 182.729476 -31.977951)
			(xy 182.679895 -31.955306) (xy 182.634041 -31.925835) (xy 182.592848 -31.890139) (xy 182.557154 -31.848944)
			(xy 182.527686 -31.803089) (xy 182.505043 -31.753507) (xy 182.489687 -31.701207) (xy 182.48193 -31.647254)
			(xy 179.806794 -31.647254) (xy 179.845181 -31.6792) (xy 179.882398 -31.720737) (xy 179.913171 -31.76725)
			(xy 179.936843 -31.817747) (xy 179.952911 -31.871154) (xy 179.961031 -31.92633) (xy 179.96154 -31.954216)
			(xy 179.961031 -31.982102) (xy 179.952911 -32.037278) (xy 179.936843 -32.090685) (xy 179.913171 -32.141182)
			(xy 179.882398 -32.187695) (xy 179.845181 -32.229232) (xy 179.802313 -32.264907) (xy 179.754707 -32.293961)
			(xy 179.703378 -32.315773) (xy 179.649421 -32.329879) (xy 179.593984 -32.335979) (xy 179.53825 -32.333942)
			(xy 179.483407 -32.323812) (xy 179.430623 -32.305805) (xy 179.381023 -32.280304) (xy 179.335665 -32.247853)
			(xy 179.295516 -32.209144) (xy 179.26143 -32.165001) (xy 179.234134 -32.116366) (xy 179.214211 -32.064275)
			(xy 179.202085 -32.009838) (xy 179.198014 -31.954216) (xy 178.312618 -31.954216) (xy 178.31033 -31.962007)
			(xy 178.287686 -32.011587) (xy 178.258217 -32.05744) (xy 178.222523 -32.098632) (xy 178.181329 -32.134326)
			(xy 178.135475 -32.163793) (xy 178.085894 -32.186435) (xy 178.033595 -32.20179) (xy 177.979644 -32.209545)
			(xy 177.925138 -32.209544) (xy 177.871186 -32.201786) (xy 177.818889 -32.186428) (xy 177.769309 -32.163784)
			(xy 177.723456 -32.134314) (xy 177.682264 -32.098619) (xy 177.646572 -32.057425) (xy 177.617105 -32.011571)
			(xy 177.594464 -31.961989) (xy 177.579109 -31.909691) (xy 177.571354 -31.855739) (xy 177.570892 -31.828486)
			(xy 177.570892 -31.81858) (xy 177.570823 -31.804585) (xy 177.563868 -31.777484) (xy 177.549822 -31.753286)
			(xy 177.52974 -31.733805) (xy 177.505126 -31.7205) (xy 177.477827 -31.714371) (xy 177.449888 -31.715875)
			(xy 177.423405 -31.724901) (xy 177.411634 -31.732474) (xy 177.387554 -31.748527) (xy 177.335576 -31.773968)
			(xy 177.28035 -31.791261) (xy 177.223145 -31.800008) (xy 177.19421 -31.800546) (xy 177.166956 -31.800056)
			(xy 177.113002 -31.7923) (xy 177.060701 -31.776944) (xy 177.011118 -31.754301) (xy 176.965262 -31.724832)
			(xy 176.924066 -31.689136) (xy 176.888371 -31.647942) (xy 176.858901 -31.602086) (xy 176.836258 -31.552503)
			(xy 176.820901 -31.500202) (xy 176.813144 -31.446248) (xy 170.56608 -31.446248) (xy 170.56608 -32.535622)
			(xy 180.552342 -32.535622) (xy 180.556413 -32.48) (xy 180.568539 -32.425563) (xy 180.588462 -32.373472)
			(xy 180.615758 -32.324837) (xy 180.649844 -32.280694) (xy 180.689993 -32.241985) (xy 180.735351 -32.209534)
			(xy 180.784951 -32.184033) (xy 180.837735 -32.166026) (xy 180.892578 -32.155896) (xy 180.948312 -32.153859)
			(xy 181.003749 -32.159959) (xy 181.057706 -32.174065) (xy 181.109035 -32.195877) (xy 181.156641 -32.224931)
			(xy 181.199509 -32.260606) (xy 181.236726 -32.302143) (xy 181.267499 -32.348656) (xy 181.291171 -32.399153)
			(xy 181.307239 -32.45256) (xy 181.315359 -32.507736) (xy 181.315868 -32.535622) (xy 181.315359 -32.563508)
			(xy 181.307239 -32.618684) (xy 181.291171 -32.672091) (xy 181.267499 -32.722588) (xy 181.236726 -32.769101)
			(xy 181.199509 -32.810638) (xy 181.156641 -32.846313) (xy 181.109035 -32.875367) (xy 181.057706 -32.897179)
			(xy 181.003749 -32.911285) (xy 180.948312 -32.917385) (xy 180.892578 -32.915348) (xy 180.837735 -32.905218)
			(xy 180.784951 -32.887211) (xy 180.735351 -32.86171) (xy 180.689993 -32.829259) (xy 180.649844 -32.79055)
			(xy 180.615758 -32.746407) (xy 180.588462 -32.697772) (xy 180.568539 -32.645681) (xy 180.556413 -32.591244)
			(xy 180.552342 -32.535622) (xy 170.56608 -32.535622) (xy 170.56608 -33.550352) (xy 184.716674 -33.550352)
			(xy 184.717124 -33.524036) (xy 184.724346 -33.471902) (xy 184.73866 -33.421254) (xy 184.759795 -33.373052)
			(xy 184.787351 -33.328211) (xy 184.820804 -33.287578) (xy 184.839864 -33.269428) (xy 184.849935 -33.259663)
			(xy 184.864636 -33.235778) (xy 184.87227 -33.208791) (xy 184.872261 -33.180745) (xy 184.864609 -33.153762)
			(xy 184.849894 -33.129887) (xy 184.839864 -33.120076) (xy 184.820785 -33.10194) (xy 184.787305 -33.061322)
			(xy 184.759732 -33.016482) (xy 184.738593 -32.968274) (xy 184.72429 -32.917616) (xy 184.717093 -32.865472)
			(xy 184.716674 -32.839152) (xy 184.717185 -32.811579) (xy 184.725129 -32.757009) (xy 184.740846 -32.70415)
			(xy 184.764008 -32.654104) (xy 184.794132 -32.607913) (xy 184.830591 -32.56654) (xy 184.851294 -32.548322)
			(xy 184.862239 -32.538472) (xy 184.878311 -32.513808) (xy 184.886689 -32.485588) (xy 184.88668 -32.45615)
			(xy 184.878284 -32.427935) (xy 184.862198 -32.403281) (xy 184.851294 -32.393382) (xy 184.83057 -32.375185)
			(xy 184.794101 -32.333813) (xy 184.76397 -32.28762) (xy 184.740807 -32.23757) (xy 184.725093 -32.184704)
			(xy 184.717157 -32.130128) (xy 184.716674 -32.102552) (xy 184.71716 -32.075301) (xy 184.724916 -32.021353)
			(xy 184.740271 -31.969058) (xy 184.762913 -31.919481) (xy 184.792379 -31.873631) (xy 184.82807 -31.83244)
			(xy 184.869261 -31.796749) (xy 184.915111 -31.767283) (xy 184.964688 -31.744641) (xy 185.016983 -31.729286)
			(xy 185.070931 -31.72153) (xy 185.125433 -31.72153) (xy 185.179381 -31.729286) (xy 185.231676 -31.744641)
			(xy 185.281253 -31.767283) (xy 185.327103 -31.796749) (xy 185.368294 -31.83244) (xy 185.403985 -31.873631)
			(xy 185.433451 -31.919481) (xy 185.456093 -31.969058) (xy 185.471448 -32.021353) (xy 185.479204 -32.075301)
			(xy 185.47969 -32.102552) (xy 185.479195 -32.130126) (xy 185.471249 -32.184697) (xy 185.45553 -32.237557)
			(xy 185.432365 -32.287603) (xy 185.402238 -32.333793) (xy 185.365775 -32.375165) (xy 185.34507 -32.393382)
			(xy 185.334224 -32.403331) (xy 185.318155 -32.427968) (xy 185.309769 -32.456162) (xy 185.30976 -32.485576)
			(xy 185.318129 -32.513775) (xy 185.334183 -32.538422) (xy 185.34507 -32.548322) (xy 185.365789 -32.566525)
			(xy 185.40226 -32.607895) (xy 185.432392 -32.654086) (xy 185.455557 -32.704136) (xy 185.471271 -32.757)
			(xy 185.479207 -32.811577) (xy 185.47969 -32.839152) (xy 185.479255 -32.865469) (xy 185.472031 -32.917604)
			(xy 185.457715 -32.968252) (xy 185.436577 -33.016454) (xy 185.409019 -33.061296) (xy 185.375562 -33.101927)
			(xy 185.3565 -33.120076) (xy 185.346528 -33.129934) (xy 185.331828 -33.153793) (xy 185.324184 -33.180755)
			(xy 185.324175 -33.20878) (xy 185.331802 -33.235747) (xy 185.346487 -33.259616) (xy 185.3565 -33.269428)
			(xy 185.375593 -33.287549) (xy 185.40907 -33.328172) (xy 185.436638 -33.373016) (xy 185.457775 -33.421226)
			(xy 185.472076 -33.471886) (xy 185.479271 -33.524032) (xy 185.47969 -33.550352) (xy 185.479204 -33.577603)
			(xy 185.471448 -33.631551) (xy 185.456093 -33.683846) (xy 185.433451 -33.733423) (xy 185.403985 -33.779273)
			(xy 185.368294 -33.820464) (xy 185.327103 -33.856155) (xy 185.281253 -33.885621) (xy 185.231676 -33.908263)
			(xy 185.179381 -33.923618) (xy 185.125433 -33.931374) (xy 185.070931 -33.931374) (xy 185.016983 -33.923618)
			(xy 184.964688 -33.908263) (xy 184.915111 -33.885621) (xy 184.869261 -33.856155) (xy 184.82807 -33.820464)
			(xy 184.792379 -33.779273) (xy 184.762913 -33.733423) (xy 184.740271 -33.683846) (xy 184.724916 -33.631551)
			(xy 184.71716 -33.577603) (xy 184.716674 -33.550352) (xy 170.56608 -33.550352) (xy 170.56608 -33.772348)
			(xy 171.15028 -34.356548) (xy 181.845712 -34.356548)
		)
		(stroke
			(width 0)
			(type solid)
		)
		(fill yes)
		(layer "In6.Cu")
		(net "GND")
	)
	(gr_poly
		(pts
			(xy 258.75234 -57.191656) (xy 258.780556 -57.174214) (xy 258.841609 -57.14829) (xy 258.873752 -57.140094)
			(xy 258.887722 -57.136792) (xy 259.041392 -56.982868) (xy 259.041392 -56.870346) (xy 258.986274 -56.870346)
			(xy 258.981956 -56.871108) (xy 258.965644 -56.873819) (xy 258.932704 -56.876745) (xy 258.91617 -56.87695)
			(xy 258.888917 -56.876462) (xy 258.834967 -56.868701) (xy 258.78267 -56.853342) (xy 258.733091 -56.830696)
			(xy 258.687239 -56.801226) (xy 258.646048 -56.765531) (xy 258.610356 -56.724337) (xy 258.580889 -56.678483)
			(xy 258.558248 -56.628902) (xy 258.542892 -56.576604) (xy 258.535136 -56.522653) (xy 258.535136 -56.468147)
			(xy 258.542892 -56.414196) (xy 258.558248 -56.361898) (xy 258.580889 -56.312317) (xy 258.610356 -56.266463)
			(xy 258.646048 -56.225269) (xy 258.687239 -56.189574) (xy 258.733091 -56.160104) (xy 258.78267 -56.137458)
			(xy 258.834967 -56.122099) (xy 258.888917 -56.114338) (xy 258.91617 -56.113934) (xy 258.934966 -56.114442)
			(xy 258.948679 -56.114635) (xy 258.975417 -56.108581) (xy 258.999582 -56.095633) (xy 259.019432 -56.076724)
			(xy 259.033536 -56.053216) (xy 259.04088 -56.026802) (xy 259.041392 -56.013096) (xy 259.041392 -55.961788)
			(xy 259.040952 -55.948066) (xy 259.033649 -55.921612) (xy 259.019549 -55.898067) (xy 258.999676 -55.879141)
			(xy 258.975472 -55.866207) (xy 258.948693 -55.860203) (xy 258.934966 -55.860442) (xy 258.91617 -55.86095)
			(xy 258.888917 -55.860462) (xy 258.834967 -55.852701) (xy 258.78267 -55.837342) (xy 258.733091 -55.814696)
			(xy 258.687239 -55.785226) (xy 258.646048 -55.749531) (xy 258.610356 -55.708337) (xy 258.580889 -55.662483)
			(xy 258.558248 -55.612902) (xy 258.542892 -55.560604) (xy 258.535136 -55.506653) (xy 258.535136 -55.452147)
			(xy 258.542892 -55.398196) (xy 258.558248 -55.345898) (xy 258.580889 -55.296317) (xy 258.610356 -55.250463)
			(xy 258.646048 -55.209269) (xy 258.687239 -55.173574) (xy 258.733091 -55.144104) (xy 258.78267 -55.121458)
			(xy 258.834967 -55.106099) (xy 258.888917 -55.098338) (xy 258.91617 -55.097934) (xy 258.934966 -55.098442)
			(xy 258.948679 -55.098635) (xy 258.975417 -55.092581) (xy 258.999582 -55.079633) (xy 259.019432 -55.060724)
			(xy 259.033536 -55.037216) (xy 259.04088 -55.010802) (xy 259.041392 -54.997096) (xy 259.041392 -54.811676)
			(xy 258.995418 -54.76113) (xy 258.967312 -54.758081) (xy 258.912375 -54.74475) (xy 258.860006 -54.72346)
			(xy 258.81135 -54.694676) (xy 258.767475 -54.659029) (xy 258.729338 -54.617298) (xy 258.697777 -54.570397)
			(xy 258.67348 -54.519353) (xy 258.65698 -54.465283) (xy 258.648639 -54.40937) (xy 258.648638 -54.352838)
			(xy 258.656979 -54.296925) (xy 258.673477 -54.242855) (xy 258.697772 -54.19181) (xy 258.729333 -54.144908)
			(xy 258.767469 -54.103177) (xy 258.811344 -54.067528) (xy 258.859998 -54.038744) (xy 258.912367 -54.017452)
			(xy 258.967304 -54.004121) (xy 258.995418 -54.001162) (xy 259.041392 -53.950616) (xy 259.041392 -52.796948)
			(xy 259.014603 -52.79479) (xy 258.962076 -52.78343) (xy 258.911853 -52.764304) (xy 258.865075 -52.737846)
			(xy 258.822805 -52.704659) (xy 258.786002 -52.665496) (xy 258.755504 -52.621247) (xy 258.732003 -52.572916)
			(xy 258.716032 -52.521602) (xy 258.707955 -52.468471) (xy 258.707955 -52.414729) (xy 258.716032 -52.361598)
			(xy 258.732003 -52.310284) (xy 258.755504 -52.261954) (xy 258.786002 -52.217704) (xy 258.822805 -52.178541)
			(xy 258.865075 -52.145354) (xy 258.911853 -52.118897) (xy 258.962076 -52.09977) (xy 259.014603 -52.08841)
			(xy 259.041392 -52.086256) (xy 259.041392 -52.001928) (xy 259.014605 -51.999771) (xy 258.962081 -51.98841)
			(xy 258.911861 -51.969285) (xy 258.865085 -51.942829) (xy 258.822817 -51.909644) (xy 258.786017 -51.870483)
			(xy 258.755521 -51.826235) (xy 258.732021 -51.777907) (xy 258.716051 -51.726597) (xy 258.707975 -51.673468)
			(xy 258.707975 -51.61973) (xy 258.716052 -51.566601) (xy 258.732022 -51.51529) (xy 258.755522 -51.466963)
			(xy 258.786019 -51.422716) (xy 258.822819 -51.383555) (xy 258.865087 -51.35037) (xy 258.911863 -51.323914)
			(xy 258.962083 -51.304789) (xy 259.014607 -51.293429) (xy 259.041392 -51.291236) (xy 259.041392 -49.857914)
			(xy 259.041993 -49.809385) (xy 259.051556 -49.7128) (xy 259.070544 -49.617618) (xy 259.098772 -49.524756)
			(xy 259.11683 -49.479708) (xy 259.353304 -48.908462) (xy 259.358373 -48.894864) (xy 259.361481 -48.866026)
			(xy 259.356365 -48.837475) (xy 259.343438 -48.811509) (xy 259.323739 -48.790219) (xy 259.298854 -48.775318)
			(xy 259.270785 -48.768004) (xy 259.256276 -48.768) (xy 259.24383 -48.768254) (xy 259.216572 -48.767793)
			(xy 259.162612 -48.760039) (xy 259.110304 -48.744683) (xy 259.060714 -48.72204) (xy 259.014851 -48.692569)
			(xy 258.97365 -48.656871) (xy 258.937949 -48.615673) (xy 258.908475 -48.569812) (xy 258.885827 -48.520224)
			(xy 258.870468 -48.467918) (xy 258.862709 -48.413958) (xy 258.862709 -48.359442) (xy 258.870468 -48.305482)
			(xy 258.885827 -48.253176) (xy 258.908475 -48.203588) (xy 258.937949 -48.157727) (xy 258.97365 -48.116529)
			(xy 259.014851 -48.080831) (xy 259.060714 -48.05136) (xy 259.110304 -48.028717) (xy 259.162612 -48.013361)
			(xy 259.216572 -48.005607) (xy 259.24383 -48.005238) (xy 259.269842 -48.005681) (xy 259.321382 -48.012756)
			(xy 259.371482 -48.026769) (xy 259.419213 -48.04746) (xy 259.46369 -48.074447) (xy 259.504086 -48.107228)
			(xy 259.522214 -48.125888) (xy 259.532528 -48.13608) (xy 259.557533 -48.150735) (xy 259.585646 -48.157784)
			(xy 259.614607 -48.156659) (xy 259.642089 -48.147452) (xy 259.665882 -48.130902) (xy 259.684075 -48.10834)
			(xy 259.690108 -48.095154) (xy 259.736082 -47.984664) (xy 259.74421 -47.96536) (xy 259.744464 -47.965106)
			(xy 259.722041 -47.953922) (xy 259.680301 -47.926201) (xy 259.642858 -47.892903) (xy 259.610451 -47.854686)
			(xy 259.58372 -47.812305) (xy 259.563192 -47.766595) (xy 259.549273 -47.71846) (xy 259.542237 -47.668849)
			(xy 259.541772 -47.643796) (xy 259.542321 -47.615813) (xy 259.551077 -47.560535) (xy 259.568371 -47.507307)
			(xy 259.593779 -47.45744) (xy 259.626675 -47.412161) (xy 259.666249 -47.372586) (xy 259.711526 -47.339688)
			(xy 259.761392 -47.314277) (xy 259.814619 -47.29698) (xy 259.869897 -47.288222) (xy 259.89788 -47.287688)
			(xy 259.92813 -47.288326) (xy 259.987762 -47.298536) (xy 260.016498 -47.308008) (xy 260.317742 -46.580552)
			(xy 260.317996 -46.580044) (xy 260.326632 -46.5582) (xy 260.347714 -46.507654) (xy 260.366819 -46.463358)
			(xy 260.412452 -46.37836) (xy 260.466144 -46.298209) (xy 260.527386 -46.223667) (xy 260.561074 -46.189138)
			(xy 260.73608 -46.014386) (xy 260.73608 -39.796974) (xy 260.54812 -39.609268) (xy 257.612134 -39.609268)
			(xy 257.59757 -39.609734) (xy 257.569625 -39.617949) (xy 257.545136 -39.63372) (xy 257.526097 -39.655764)
			(xy 257.514057 -39.682287) (xy 257.509995 -39.71113) (xy 257.514243 -39.739946) (xy 257.526454 -39.766391)
			(xy 257.53568 -39.77767) (xy 257.553449 -39.798661) (xy 257.583399 -39.844785) (xy 257.606422 -39.89473)
			(xy 257.622042 -39.94746) (xy 257.629935 -40.001886) (xy 257.630422 -40.029384) (xy 257.630422 -40.029638)
			(xy 257.62993 -40.057679) (xy 257.621722 -40.113158) (xy 257.605475 -40.166836) (xy 257.581538 -40.217554)
			(xy 257.55043 -40.264218) (xy 257.51282 -40.305821) (xy 257.491484 -40.324024) (xy 257.480394 -40.333772)
			(xy 257.463898 -40.358244) (xy 257.455101 -40.386416) (xy 257.454742 -40.415926) (xy 257.462849 -40.444304)
			(xy 257.478745 -40.46917) (xy 257.501097 -40.488443) (xy 257.514344 -40.494966) (xy 257.539134 -40.506632)
			(xy 257.585374 -40.536016) (xy 257.626935 -40.571713) (xy 257.662962 -40.612989) (xy 257.692714 -40.658994)
			(xy 257.715579 -40.708781) (xy 257.731087 -40.761328) (xy 257.738917 -40.815552) (xy 257.739388 -40.842946)
			(xy 257.738902 -40.870197) (xy 257.731146 -40.924145) (xy 257.715791 -40.97644) (xy 257.693149 -41.026017)
			(xy 257.663683 -41.071867) (xy 257.627992 -41.113058) (xy 257.586801 -41.148749) (xy 257.540951 -41.178215)
			(xy 257.491374 -41.200857) (xy 257.439079 -41.216212) (xy 257.385131 -41.223968) (xy 257.330629 -41.223968)
			(xy 257.276681 -41.216212) (xy 257.224386 -41.200857) (xy 257.174809 -41.178215) (xy 257.128959 -41.148749)
			(xy 257.087768 -41.113058) (xy 257.052077 -41.071867) (xy 257.022611 -41.026017) (xy 256.999969 -40.97644)
			(xy 256.984614 -40.924145) (xy 256.976858 -40.870197) (xy 256.976372 -40.842946) (xy 256.976372 -40.842692)
			(xy 256.976862 -40.81465) (xy 256.985066 -40.759168) (xy 257.00131 -40.705487) (xy 257.025243 -40.654766)
			(xy 257.05635 -40.608098) (xy 257.093959 -40.566492) (xy 257.11531 -40.548306) (xy 257.126405 -40.538558)
			(xy 257.142911 -40.514082) (xy 257.151715 -40.485905) (xy 257.15208 -40.456386) (xy 257.143974 -40.428)
			(xy 257.128076 -40.403125) (xy 257.10572 -40.383845) (xy 257.09245 -40.377364) (xy 257.067663 -40.365697)
			(xy 257.021429 -40.33631) (xy 256.979876 -40.300611) (xy 256.943857 -40.259334) (xy 256.914113 -40.213329)
			(xy 256.891258 -40.163542) (xy 256.87576 -40.110997) (xy 256.867939 -40.056776) (xy 256.867406 -40.029384)
			(xy 256.867887 -40.001887) (xy 256.875782 -39.947462) (xy 256.891406 -39.894733) (xy 256.914436 -39.844792)
			(xy 256.944394 -39.798674) (xy 256.962148 -39.77767) (xy 256.971361 -39.766395) (xy 256.98353 -39.739957)
			(xy 256.98775 -39.71116) (xy 256.983677 -39.682341) (xy 256.971642 -39.655842) (xy 256.952622 -39.633811)
			(xy 256.928162 -39.618039) (xy 256.900246 -39.609805) (xy 256.885694 -39.609268) (xy 256.293112 -39.609268)
			(xy 255.674114 -40.228012) (xy 255.650215 -40.25118) (xy 255.597412 -40.291705) (xy 255.539769 -40.324987)
			(xy 255.478273 -40.350458) (xy 255.413978 -40.36768) (xy 255.347985 -40.376359) (xy 255.314704 -40.376856)
			(xy 255.007872 -40.376856) (xy 254.994179 -40.377345) (xy 254.967799 -40.384709) (xy 254.944325 -40.39882)
			(xy 254.925445 -40.418662) (xy 254.912518 -40.442808) (xy 254.906473 -40.469521) (xy 254.907745 -40.49688)
			(xy 254.916243 -40.522917) (xy 254.931355 -40.54576) (xy 254.941324 -40.555164) (xy 254.961512 -40.573373)
			(xy 254.99704 -40.614524) (xy 255.026367 -40.660301) (xy 255.0489 -40.709776) (xy 255.064183 -40.761949)
			(xy 255.071907 -40.815763) (xy 255.072388 -40.842946) (xy 255.197862 -40.842946) (xy 255.201933 -40.787324)
			(xy 255.214059 -40.732887) (xy 255.233982 -40.680796) (xy 255.261278 -40.632161) (xy 255.295364 -40.588018)
			(xy 255.335513 -40.549309) (xy 255.380871 -40.516858) (xy 255.430471 -40.491357) (xy 255.483255 -40.47335)
			(xy 255.538098 -40.46322) (xy 255.593832 -40.461183) (xy 255.649269 -40.467283) (xy 255.703226 -40.481389)
			(xy 255.754555 -40.503201) (xy 255.802161 -40.532255) (xy 255.845029 -40.56793) (xy 255.882246 -40.609467)
			(xy 255.913019 -40.65598) (xy 255.936691 -40.706477) (xy 255.952759 -40.759884) (xy 255.960879 -40.81506)
			(xy 255.961388 -40.842946) (xy 256.086862 -40.842946) (xy 256.090933 -40.787324) (xy 256.103059 -40.732887)
			(xy 256.122982 -40.680796) (xy 256.150278 -40.632161) (xy 256.184364 -40.588018) (xy 256.224513 -40.549309)
			(xy 256.269871 -40.516858) (xy 256.319471 -40.491357) (xy 256.372255 -40.47335) (xy 256.427098 -40.46322)
			(xy 256.482832 -40.461183) (xy 256.538269 -40.467283) (xy 256.592226 -40.481389) (xy 256.643555 -40.503201)
			(xy 256.691161 -40.532255) (xy 256.734029 -40.56793) (xy 256.771246 -40.609467) (xy 256.802019 -40.65598)
			(xy 256.825691 -40.706477) (xy 256.841759 -40.759884) (xy 256.849879 -40.81506) (xy 256.850388 -40.842946)
			(xy 256.849879 -40.870832) (xy 256.841759 -40.926008) (xy 256.825691 -40.979415) (xy 256.802019 -41.029912)
			(xy 256.771246 -41.076425) (xy 256.734029 -41.117962) (xy 256.691161 -41.153637) (xy 256.643555 -41.182691)
			(xy 256.592226 -41.204503) (xy 256.538269 -41.218609) (xy 256.482832 -41.224709) (xy 256.427098 -41.222672)
			(xy 256.372255 -41.212542) (xy 256.319471 -41.194535) (xy 256.269871 -41.169034) (xy 256.224513 -41.136583)
			(xy 256.184364 -41.097874) (xy 256.150278 -41.053731) (xy 256.122982 -41.005096) (xy 256.103059 -40.953005)
			(xy 256.090933 -40.898568) (xy 256.086862 -40.842946) (xy 255.961388 -40.842946) (xy 255.960879 -40.870832)
			(xy 255.952759 -40.926008) (xy 255.936691 -40.979415) (xy 255.913019 -41.029912) (xy 255.882246 -41.076425)
			(xy 255.845029 -41.117962) (xy 255.802161 -41.153637) (xy 255.754555 -41.182691) (xy 255.703226 -41.204503)
			(xy 255.649269 -41.218609) (xy 255.593832 -41.224709) (xy 255.538098 -41.222672) (xy 255.483255 -41.212542)
			(xy 255.430471 -41.194535) (xy 255.380871 -41.169034) (xy 255.335513 -41.136583) (xy 255.295364 -41.097874)
			(xy 255.261278 -41.053731) (xy 255.233982 -41.005096) (xy 255.214059 -40.953005) (xy 255.201933 -40.898568)
			(xy 255.197862 -40.842946) (xy 255.072388 -40.842946) (xy 255.071902 -40.870197) (xy 255.064146 -40.924145)
			(xy 255.048791 -40.97644) (xy 255.026149 -41.026017) (xy 254.996683 -41.071867) (xy 254.960992 -41.113058)
			(xy 254.919801 -41.148749) (xy 254.873951 -41.178215) (xy 254.824374 -41.200857) (xy 254.772079 -41.216212)
			(xy 254.718131 -41.223968) (xy 254.663629 -41.223968) (xy 254.609681 -41.216212) (xy 254.557386 -41.200857)
			(xy 254.507809 -41.178215) (xy 254.461959 -41.148749) (xy 254.420768 -41.113058) (xy 254.385077 -41.071867)
			(xy 254.355611 -41.026017) (xy 254.332969 -40.97644) (xy 254.317614 -40.924145) (xy 254.309858 -40.870197)
			(xy 254.309372 -40.842946) (xy 254.309837 -40.815635) (xy 254.317624 -40.761571) (xy 254.333045 -40.709171)
			(xy 254.355786 -40.659507) (xy 254.38538 -40.613597) (xy 254.421222 -40.572379) (xy 254.462578 -40.536696)
			(xy 254.508602 -40.50728) (xy 254.558353 -40.484732) (xy 254.584454 -40.476678) (xy 254.621284 -40.46601)
			(xy 254.621284 -40.376856) (xy 254.416052 -40.376856) (xy 254.31369 -40.479218) (xy 254.289775 -40.502375)
			(xy 254.236976 -40.542917) (xy 254.179339 -40.576225) (xy 254.117849 -40.601731) (xy 254.053558 -40.618997)
			(xy 253.987564 -40.62773) (xy 253.95428 -40.628316) (xy 251.99086 -40.628316) (xy 251.054362 -41.56456)
			(xy 251.030462 -41.587723) (xy 250.977655 -41.628239) (xy 250.920011 -41.661513) (xy 250.858516 -41.686974)
			(xy 250.794222 -41.704188) (xy 250.728231 -41.71286) (xy 250.694952 -41.713404) (xy 246.842534 -41.713404)
			(xy 246.81475 -41.713075) (xy 246.759507 -41.707097) (xy 246.732298 -41.701466) (xy 246.71736 -41.698712)
			(xy 246.687097 -41.701106) (xy 246.658871 -41.71228) (xy 246.63517 -41.73125) (xy 246.618084 -41.756344)
			(xy 246.609121 -41.785348) (xy 246.6086 -41.800526) (xy 246.6086 -42.03954) (xy 253.897636 -42.03954)
			(xy 253.901707 -41.983918) (xy 253.913833 -41.929481) (xy 253.933756 -41.87739) (xy 253.961052 -41.828755)
			(xy 253.995138 -41.784612) (xy 254.035287 -41.745903) (xy 254.080645 -41.713452) (xy 254.130245 -41.687951)
			(xy 254.183029 -41.669944) (xy 254.237872 -41.659814) (xy 254.293606 -41.657777) (xy 254.349043 -41.663877)
			(xy 254.403 -41.677983) (xy 254.454329 -41.699795) (xy 254.501935 -41.728849) (xy 254.544803 -41.764524)
			(xy 254.58202 -41.806061) (xy 254.612793 -41.852574) (xy 254.636465 -41.903071) (xy 254.652533 -41.956478)
			(xy 254.660653 -42.011654) (xy 254.661162 -42.03954) (xy 254.660653 -42.067426) (xy 254.652533 -42.122602)
			(xy 254.636465 -42.176009) (xy 254.612793 -42.226506) (xy 254.58202 -42.273019) (xy 254.544803 -42.314556)
			(xy 254.501935 -42.350231) (xy 254.454329 -42.379285) (xy 254.403 -42.401097) (xy 254.349043 -42.415203)
			(xy 254.293606 -42.421303) (xy 254.237872 -42.419266) (xy 254.183029 -42.409136) (xy 254.130245 -42.391129)
			(xy 254.080645 -42.365628) (xy 254.035287 -42.333177) (xy 253.995138 -42.294468) (xy 253.961052 -42.250325)
			(xy 253.933756 -42.20169) (xy 253.913833 -42.149599) (xy 253.901707 -42.095162) (xy 253.897636 -42.03954)
			(xy 246.6086 -42.03954) (xy 246.6086 -42.863262) (xy 249.934728 -42.863262) (xy 249.938799 -42.80764)
			(xy 249.950925 -42.753203) (xy 249.970848 -42.701112) (xy 249.998144 -42.652477) (xy 250.03223 -42.608334)
			(xy 250.072379 -42.569625) (xy 250.117737 -42.537174) (xy 250.167337 -42.511673) (xy 250.220121 -42.493666)
			(xy 250.274964 -42.483536) (xy 250.330698 -42.481499) (xy 250.386135 -42.487599) (xy 250.440092 -42.501705)
			(xy 250.491421 -42.523517) (xy 250.539027 -42.552571) (xy 250.581895 -42.588246) (xy 250.619112 -42.629783)
			(xy 250.649885 -42.676296) (xy 250.673557 -42.726793) (xy 250.689625 -42.7802) (xy 250.697745 -42.835376)
			(xy 250.698254 -42.863262) (xy 250.697745 -42.891148) (xy 250.689625 -42.946324) (xy 250.673557 -42.999731)
			(xy 250.649885 -43.050228) (xy 250.619112 -43.096741) (xy 250.581895 -43.138278) (xy 250.539027 -43.173953)
			(xy 250.491421 -43.203007) (xy 250.440092 -43.224819) (xy 250.386135 -43.238925) (xy 250.330698 -43.245025)
			(xy 250.274964 -43.242988) (xy 250.220121 -43.232858) (xy 250.167337 -43.214851) (xy 250.117737 -43.18935)
			(xy 250.072379 -43.156899) (xy 250.03223 -43.11819) (xy 249.998144 -43.074047) (xy 249.970848 -43.025412)
			(xy 249.950925 -42.973321) (xy 249.938799 -42.918884) (xy 249.934728 -42.863262) (xy 246.6086 -42.863262)
			(xy 246.6086 -43.951906) (xy 251.107192 -43.951906) (xy 251.111263 -43.896284) (xy 251.123389 -43.841847)
			(xy 251.143312 -43.789756) (xy 251.170608 -43.741121) (xy 251.204694 -43.696978) (xy 251.244843 -43.658269)
			(xy 251.290201 -43.625818) (xy 251.339801 -43.600317) (xy 251.392585 -43.58231) (xy 251.447428 -43.57218)
			(xy 251.503162 -43.570143) (xy 251.558599 -43.576243) (xy 251.612556 -43.590349) (xy 251.663885 -43.612161)
			(xy 251.711491 -43.641215) (xy 251.754359 -43.67689) (xy 251.791576 -43.718427) (xy 251.822349 -43.76494)
			(xy 251.846021 -43.815437) (xy 251.851927 -43.835066) (xy 252.707392 -43.835066) (xy 252.711463 -43.779444)
			(xy 252.723589 -43.725007) (xy 252.743512 -43.672916) (xy 252.770808 -43.624281) (xy 252.804894 -43.580138)
			(xy 252.845043 -43.541429) (xy 252.890401 -43.508978) (xy 252.940001 -43.483477) (xy 252.992785 -43.46547)
			(xy 253.047628 -43.45534) (xy 253.103362 -43.453303) (xy 253.158799 -43.459403) (xy 253.212756 -43.473509)
			(xy 253.264085 -43.495321) (xy 253.311691 -43.524375) (xy 253.354559 -43.56005) (xy 253.391776 -43.601587)
			(xy 253.422549 -43.6481) (xy 253.446221 -43.698597) (xy 253.462289 -43.752004) (xy 253.470409 -43.80718)
			(xy 253.470918 -43.835066) (xy 253.470409 -43.862952) (xy 253.462289 -43.918128) (xy 253.446221 -43.971535)
			(xy 253.422549 -44.022032) (xy 253.391776 -44.068545) (xy 253.354559 -44.110082) (xy 253.311691 -44.145757)
			(xy 253.264085 -44.174811) (xy 253.212756 -44.196623) (xy 253.158799 -44.210729) (xy 253.103362 -44.216829)
			(xy 253.047628 -44.214792) (xy 252.992785 -44.204662) (xy 252.940001 -44.186655) (xy 252.890401 -44.161154)
			(xy 252.845043 -44.128703) (xy 252.804894 -44.089994) (xy 252.770808 -44.045851) (xy 252.743512 -43.997216)
			(xy 252.723589 -43.945125) (xy 252.711463 -43.890688) (xy 252.707392 -43.835066) (xy 251.851927 -43.835066)
			(xy 251.862089 -43.868844) (xy 251.870209 -43.92402) (xy 251.870718 -43.951906) (xy 251.870209 -43.979792)
			(xy 251.862089 -44.034968) (xy 251.846021 -44.088375) (xy 251.822349 -44.138872) (xy 251.791576 -44.185385)
			(xy 251.754359 -44.226922) (xy 251.711491 -44.262597) (xy 251.663885 -44.291651) (xy 251.612556 -44.313463)
			(xy 251.558599 -44.327569) (xy 251.503162 -44.333669) (xy 251.447428 -44.331632) (xy 251.392585 -44.321502)
			(xy 251.339801 -44.303495) (xy 251.290201 -44.277994) (xy 251.244843 -44.245543) (xy 251.204694 -44.206834)
			(xy 251.170608 -44.162691) (xy 251.143312 -44.114056) (xy 251.123389 -44.061965) (xy 251.111263 -44.007528)
			(xy 251.107192 -43.951906) (xy 246.6086 -43.951906) (xy 246.6086 -44.271946) (xy 246.7356 -44.398946)
			(xy 254.359662 -44.398946) (xy 254.363733 -44.343324) (xy 254.375859 -44.288887) (xy 254.395782 -44.236796)
			(xy 254.423078 -44.188161) (xy 254.457164 -44.144018) (xy 254.497313 -44.105309) (xy 254.542671 -44.072858)
			(xy 254.592271 -44.047357) (xy 254.645055 -44.02935) (xy 254.699898 -44.01922) (xy 254.755632 -44.017183)
			(xy 254.811069 -44.023283) (xy 254.865026 -44.037389) (xy 254.916355 -44.059201) (xy 254.963961 -44.088255)
			(xy 255.006829 -44.12393) (xy 255.044046 -44.165467) (xy 255.074819 -44.21198) (xy 255.098491 -44.262477)
			(xy 255.114559 -44.315884) (xy 255.122679 -44.37106) (xy 255.123188 -44.398946) (xy 255.122679 -44.426832)
			(xy 255.114559 -44.482008) (xy 255.098491 -44.535415) (xy 255.074819 -44.585912) (xy 255.044046 -44.632425)
			(xy 255.024045 -44.654748) (xy 257.251224 -44.654748) (xy 257.251224 -44.600252) (xy 257.25898 -44.546311)
			(xy 257.274333 -44.494023) (xy 257.296971 -44.444451) (xy 257.326434 -44.398606) (xy 257.362121 -44.357421)
			(xy 257.403306 -44.321734) (xy 257.449151 -44.292271) (xy 257.498723 -44.269633) (xy 257.551011 -44.25428)
			(xy 257.604952 -44.246524) (xy 257.6322 -44.246038) (xy 257.659775 -44.24649) (xy 257.714349 -44.254444)
			(xy 257.76721 -44.270171) (xy 257.817256 -44.293343) (xy 257.863445 -44.323479) (xy 257.904815 -44.359949)
			(xy 257.92303 -44.380658) (xy 257.932928 -44.391556) (xy 257.957578 -44.407631) (xy 257.985786 -44.416015)
			(xy 258.015214 -44.416015) (xy 258.043422 -44.407631) (xy 258.068072 -44.391556) (xy 258.07797 -44.380658)
			(xy 258.096184 -44.35995) (xy 258.137553 -44.323481) (xy 258.183743 -44.29335) (xy 258.23379 -44.270184)
			(xy 258.286652 -44.254466) (xy 258.341226 -44.246525) (xy 258.3688 -44.246038) (xy 258.395097 -44.246493)
			(xy 258.447194 -44.253711) (xy 258.497804 -44.268023) (xy 258.545965 -44.289158) (xy 258.590763 -44.316715)
			(xy 258.631346 -44.350169) (xy 258.64947 -44.369228) (xy 258.658799 -44.378871) (xy 258.681467 -44.393214)
			(xy 258.70709 -44.401152) (xy 258.733897 -44.402136) (xy 258.760033 -44.396096) (xy 258.783691 -44.383452)
			(xy 258.793742 -44.374562) (xy 258.815073 -44.355295) (xy 258.862433 -44.322728) (xy 258.914144 -44.297634)
			(xy 258.969034 -44.280582) (xy 259.025861 -44.271959) (xy 259.0546 -44.271438) (xy 259.082175 -44.27189)
			(xy 259.136749 -44.279844) (xy 259.18961 -44.295571) (xy 259.239656 -44.318743) (xy 259.285845 -44.348879)
			(xy 259.327215 -44.385349) (xy 259.34543 -44.406058) (xy 259.355328 -44.416956) (xy 259.379978 -44.433031)
			(xy 259.408186 -44.441415) (xy 259.437614 -44.441415) (xy 259.465822 -44.433031) (xy 259.490472 -44.416956)
			(xy 259.50037 -44.406058) (xy 259.518584 -44.38535) (xy 259.559953 -44.348881) (xy 259.606143 -44.31875)
			(xy 259.65619 -44.295584) (xy 259.709052 -44.279866) (xy 259.763626 -44.271925) (xy 259.7912 -44.271438)
			(xy 259.818455 -44.271832) (xy 259.872409 -44.279589) (xy 259.92471 -44.294946) (xy 259.974293 -44.31759)
			(xy 260.020149 -44.34706) (xy 260.061344 -44.382756) (xy 260.09704 -44.423951) (xy 260.12651 -44.469807)
			(xy 260.149154 -44.51939) (xy 260.164511 -44.571691) (xy 260.172268 -44.625645) (xy 260.172268 -44.680155)
			(xy 260.164511 -44.734109) (xy 260.149154 -44.78641) (xy 260.12651 -44.835993) (xy 260.09704 -44.881849)
			(xy 260.061344 -44.923044) (xy 260.020149 -44.95874) (xy 259.974293 -44.98821) (xy 259.92471 -45.010854)
			(xy 259.872409 -45.026211) (xy 259.818455 -45.033968) (xy 259.7912 -45.034454) (xy 259.763625 -45.034004)
			(xy 259.70905 -45.026051) (xy 259.65619 -45.010324) (xy 259.606143 -44.987151) (xy 259.559954 -44.957015)
			(xy 259.518585 -44.920543) (xy 259.50037 -44.899834) (xy 259.490472 -44.888936) (xy 259.465822 -44.872861)
			(xy 259.437614 -44.864477) (xy 259.408186 -44.864477) (xy 259.379978 -44.872861) (xy 259.355328 -44.888936)
			(xy 259.34543 -44.899834) (xy 259.327214 -44.920541) (xy 259.285846 -44.95701) (xy 259.239656 -44.987142)
			(xy 259.189609 -45.010308) (xy 259.136748 -45.026026) (xy 259.082174 -45.033967) (xy 259.0546 -45.034454)
			(xy 259.028303 -45.034002) (xy 258.976205 -45.026784) (xy 258.925596 -45.012471) (xy 258.877435 -44.991335)
			(xy 258.832637 -44.963778) (xy 258.792054 -44.930324) (xy 258.77393 -44.911264) (xy 258.764602 -44.901618)
			(xy 258.741937 -44.887261) (xy 258.716312 -44.879316) (xy 258.689501 -44.878332) (xy 258.663362 -44.884377)
			(xy 258.639706 -44.897033) (xy 258.629658 -44.90593) (xy 258.608326 -44.925195) (xy 258.560966 -44.957764)
			(xy 258.509256 -44.982858) (xy 258.454366 -44.999909) (xy 258.397539 -45.008533) (xy 258.3688 -45.009054)
			(xy 258.341225 -45.008604) (xy 258.28665 -45.000651) (xy 258.23379 -44.984924) (xy 258.183743 -44.961751)
			(xy 258.137554 -44.931615) (xy 258.096185 -44.895143) (xy 258.07797 -44.874434) (xy 258.068072 -44.863536)
			(xy 258.043422 -44.847461) (xy 258.015214 -44.839077) (xy 257.985786 -44.839077) (xy 257.957578 -44.847461)
			(xy 257.932928 -44.863536) (xy 257.92303 -44.874434) (xy 257.904814 -44.895141) (xy 257.863446 -44.93161)
			(xy 257.817256 -44.961742) (xy 257.767209 -44.984908) (xy 257.714348 -45.000626) (xy 257.659774 -45.008567)
			(xy 257.6322 -45.009054) (xy 257.604952 -45.008476) (xy 257.551011 -45.00072) (xy 257.498723 -44.985367)
			(xy 257.449151 -44.962729) (xy 257.403306 -44.933266) (xy 257.362121 -44.897579) (xy 257.326434 -44.856394)
			(xy 257.296971 -44.810549) (xy 257.274333 -44.760977) (xy 257.25898 -44.708689) (xy 257.251224 -44.654748)
			(xy 255.024045 -44.654748) (xy 255.006829 -44.673962) (xy 254.963961 -44.709637) (xy 254.916355 -44.738691)
			(xy 254.865026 -44.760503) (xy 254.811069 -44.774609) (xy 254.755632 -44.780709) (xy 254.699898 -44.778672)
			(xy 254.645055 -44.768542) (xy 254.592271 -44.750535) (xy 254.542671 -44.725034) (xy 254.497313 -44.692583)
			(xy 254.457164 -44.653874) (xy 254.423078 -44.609731) (xy 254.395782 -44.561096) (xy 254.375859 -44.509005)
			(xy 254.363733 -44.454568) (xy 254.359662 -44.398946) (xy 246.7356 -44.398946) (xy 248.325386 -45.988732)
			(xy 249.917456 -45.988732) (xy 249.921527 -45.93311) (xy 249.933653 -45.878673) (xy 249.953576 -45.826582)
			(xy 249.980872 -45.777947) (xy 250.014958 -45.733804) (xy 250.055107 -45.695095) (xy 250.100465 -45.662644)
			(xy 250.150065 -45.637143) (xy 250.202849 -45.619136) (xy 250.257692 -45.609006) (xy 250.313426 -45.606969)
			(xy 250.368863 -45.613069) (xy 250.42282 -45.627175) (xy 250.474149 -45.648987) (xy 250.521755 -45.678041)
			(xy 250.564623 -45.713716) (xy 250.60184 -45.755253) (xy 250.632613 -45.801766) (xy 250.656285 -45.852263)
			(xy 250.672353 -45.90567) (xy 250.680473 -45.960846) (xy 250.680982 -45.988732) (xy 250.680473 -46.016618)
			(xy 250.672353 -46.071794) (xy 250.656285 -46.125201) (xy 250.632613 -46.175698) (xy 250.60184 -46.222211)
			(xy 250.564623 -46.263748) (xy 250.521755 -46.299423) (xy 250.474149 -46.328477) (xy 250.42282 -46.350289)
			(xy 250.368863 -46.364395) (xy 250.313426 -46.370495) (xy 250.257692 -46.368458) (xy 250.202849 -46.358328)
			(xy 250.150065 -46.340321) (xy 250.100465 -46.31482) (xy 250.055107 -46.282369) (xy 250.014958 -46.24366)
			(xy 249.980872 -46.199517) (xy 249.953576 -46.150882) (xy 249.933653 -46.098791) (xy 249.921527 -46.044354)
			(xy 249.917456 -45.988732) (xy 248.325386 -45.988732) (xy 248.82856 -46.491906) (xy 251.49556 -46.491906)
			(xy 252.0696 -47.065946) (xy 253.419862 -47.065946) (xy 253.423933 -47.010324) (xy 253.436059 -46.955887)
			(xy 253.455982 -46.903796) (xy 253.483278 -46.855161) (xy 253.517364 -46.811018) (xy 253.557513 -46.772309)
			(xy 253.602871 -46.739858) (xy 253.652471 -46.714357) (xy 253.705255 -46.69635) (xy 253.760098 -46.68622)
			(xy 253.815832 -46.684183) (xy 253.871269 -46.690283) (xy 253.925226 -46.704389) (xy 253.976555 -46.726201)
			(xy 254.024161 -46.755255) (xy 254.067029 -46.79093) (xy 254.104246 -46.832467) (xy 254.135019 -46.87898)
			(xy 254.158691 -46.929477) (xy 254.174759 -46.982884) (xy 254.182879 -47.03806) (xy 254.183388 -47.065946)
			(xy 254.308862 -47.065946) (xy 254.312933 -47.010324) (xy 254.325059 -46.955887) (xy 254.344982 -46.903796)
			(xy 254.372278 -46.855161) (xy 254.406364 -46.811018) (xy 254.446513 -46.772309) (xy 254.491871 -46.739858)
			(xy 254.541471 -46.714357) (xy 254.594255 -46.69635) (xy 254.649098 -46.68622) (xy 254.704832 -46.684183)
			(xy 254.760269 -46.690283) (xy 254.814226 -46.704389) (xy 254.865555 -46.726201) (xy 254.913161 -46.755255)
			(xy 254.956029 -46.79093) (xy 254.993246 -46.832467) (xy 255.024019 -46.87898) (xy 255.047691 -46.929477)
			(xy 255.063759 -46.982884) (xy 255.071879 -47.03806) (xy 255.072388 -47.065946) (xy 255.197862 -47.065946)
			(xy 255.201933 -47.010324) (xy 255.214059 -46.955887) (xy 255.233982 -46.903796) (xy 255.261278 -46.855161)
			(xy 255.295364 -46.811018) (xy 255.335513 -46.772309) (xy 255.380871 -46.739858) (xy 255.430471 -46.714357)
			(xy 255.483255 -46.69635) (xy 255.538098 -46.68622) (xy 255.593832 -46.684183) (xy 255.649269 -46.690283)
			(xy 255.703226 -46.704389) (xy 255.754555 -46.726201) (xy 255.802161 -46.755255) (xy 255.845029 -46.79093)
			(xy 255.882246 -46.832467) (xy 255.913019 -46.87898) (xy 255.936691 -46.929477) (xy 255.952759 -46.982884)
			(xy 255.960879 -47.03806) (xy 255.961388 -47.065946) (xy 255.960891 -47.093148) (xy 256.667024 -47.093148)
			(xy 256.667024 -47.038652) (xy 256.67478 -46.984711) (xy 256.690133 -46.932423) (xy 256.712771 -46.882851)
			(xy 256.742234 -46.837006) (xy 256.777921 -46.795821) (xy 256.819106 -46.760134) (xy 256.864951 -46.730671)
			(xy 256.914523 -46.708033) (xy 256.966811 -46.69268) (xy 257.020752 -46.684924) (xy 257.048 -46.684438)
			(xy 257.075575 -46.68489) (xy 257.130149 -46.692844) (xy 257.18301 -46.708571) (xy 257.233056 -46.731743)
			(xy 257.279245 -46.761879) (xy 257.320615 -46.798349) (xy 257.33883 -46.819058) (xy 257.348728 -46.829956)
			(xy 257.373378 -46.846031) (xy 257.401586 -46.854415) (xy 257.431014 -46.854415) (xy 257.459222 -46.846031)
			(xy 257.483872 -46.829956) (xy 257.49377 -46.819058) (xy 257.511985 -46.798352) (xy 257.553356 -46.761887)
			(xy 257.599546 -46.73176) (xy 257.649593 -46.708597) (xy 257.702454 -46.692881) (xy 257.757026 -46.684941)
			(xy 257.812174 -46.684941) (xy 257.866746 -46.692881) (xy 257.919607 -46.708597) (xy 257.969654 -46.73176)
			(xy 258.015844 -46.761887) (xy 258.057215 -46.798352) (xy 258.07543 -46.819058) (xy 258.085328 -46.829956)
			(xy 258.109978 -46.846031) (xy 258.138186 -46.854415) (xy 258.167614 -46.854415) (xy 258.195822 -46.846031)
			(xy 258.220472 -46.829956) (xy 258.23037 -46.819058) (xy 258.248584 -46.79835) (xy 258.289953 -46.761881)
			(xy 258.336143 -46.73175) (xy 258.38619 -46.708584) (xy 258.439052 -46.692866) (xy 258.493626 -46.684925)
			(xy 258.5212 -46.684438) (xy 258.548455 -46.684832) (xy 258.602409 -46.692589) (xy 258.65471 -46.707946)
			(xy 258.704293 -46.73059) (xy 258.750149 -46.76006) (xy 258.791344 -46.795756) (xy 258.82704 -46.836951)
			(xy 258.85651 -46.882807) (xy 258.879154 -46.93239) (xy 258.894511 -46.984691) (xy 258.902268 -47.038645)
			(xy 258.902268 -47.093155) (xy 258.894511 -47.147109) (xy 258.879154 -47.19941) (xy 258.85651 -47.248993)
			(xy 258.82704 -47.294849) (xy 258.791344 -47.336044) (xy 258.750149 -47.37174) (xy 258.704293 -47.40121)
			(xy 258.65471 -47.423854) (xy 258.602409 -47.439211) (xy 258.548455 -47.446968) (xy 258.5212 -47.447454)
			(xy 258.493625 -47.447004) (xy 258.43905 -47.439051) (xy 258.38619 -47.423324) (xy 258.336143 -47.400151)
			(xy 258.289954 -47.370015) (xy 258.248585 -47.333543) (xy 258.23037 -47.312834) (xy 258.220472 -47.301936)
			(xy 258.195822 -47.285861) (xy 258.167614 -47.277477) (xy 258.138186 -47.277477) (xy 258.109978 -47.285861)
			(xy 258.085328 -47.301936) (xy 258.07543 -47.312834) (xy 258.057215 -47.33354) (xy 258.015844 -47.370005)
			(xy 257.969654 -47.400132) (xy 257.919607 -47.423295) (xy 257.866746 -47.439011) (xy 257.812174 -47.446951)
			(xy 257.757026 -47.446951) (xy 257.702454 -47.439011) (xy 257.649593 -47.423295) (xy 257.599546 -47.400132)
			(xy 257.553356 -47.370005) (xy 257.511985 -47.33354) (xy 257.49377 -47.312834) (xy 257.483872 -47.301936)
			(xy 257.459222 -47.285861) (xy 257.431014 -47.277477) (xy 257.401586 -47.277477) (xy 257.373378 -47.285861)
			(xy 257.348728 -47.301936) (xy 257.33883 -47.312834) (xy 257.320614 -47.333541) (xy 257.279246 -47.37001)
			(xy 257.233056 -47.400142) (xy 257.183009 -47.423308) (xy 257.130148 -47.439026) (xy 257.075574 -47.446967)
			(xy 257.048 -47.447454) (xy 257.020752 -47.446876) (xy 256.966811 -47.43912) (xy 256.914523 -47.423767)
			(xy 256.864951 -47.401129) (xy 256.819106 -47.371666) (xy 256.777921 -47.335979) (xy 256.742234 -47.294794)
			(xy 256.712771 -47.248949) (xy 256.690133 -47.199377) (xy 256.67478 -47.147089) (xy 256.667024 -47.093148)
			(xy 255.960891 -47.093148) (xy 255.960879 -47.093832) (xy 255.952759 -47.149008) (xy 255.936691 -47.202415)
			(xy 255.913019 -47.252912) (xy 255.882246 -47.299425) (xy 255.845029 -47.340962) (xy 255.802161 -47.376637)
			(xy 255.754555 -47.405691) (xy 255.703226 -47.427503) (xy 255.649269 -47.441609) (xy 255.593832 -47.447709)
			(xy 255.538098 -47.445672) (xy 255.483255 -47.435542) (xy 255.430471 -47.417535) (xy 255.380871 -47.392034)
			(xy 255.335513 -47.359583) (xy 255.295364 -47.320874) (xy 255.261278 -47.276731) (xy 255.233982 -47.228096)
			(xy 255.214059 -47.176005) (xy 255.201933 -47.121568) (xy 255.197862 -47.065946) (xy 255.072388 -47.065946)
			(xy 255.071879 -47.093832) (xy 255.063759 -47.149008) (xy 255.047691 -47.202415) (xy 255.024019 -47.252912)
			(xy 254.993246 -47.299425) (xy 254.956029 -47.340962) (xy 254.913161 -47.376637) (xy 254.865555 -47.405691)
			(xy 254.814226 -47.427503) (xy 254.760269 -47.441609) (xy 254.704832 -47.447709) (xy 254.649098 -47.445672)
			(xy 254.594255 -47.435542) (xy 254.541471 -47.417535) (xy 254.491871 -47.392034) (xy 254.446513 -47.359583)
			(xy 254.406364 -47.320874) (xy 254.372278 -47.276731) (xy 254.344982 -47.228096) (xy 254.325059 -47.176005)
			(xy 254.312933 -47.121568) (xy 254.308862 -47.065946) (xy 254.183388 -47.065946) (xy 254.182879 -47.093832)
			(xy 254.174759 -47.149008) (xy 254.158691 -47.202415) (xy 254.135019 -47.252912) (xy 254.104246 -47.299425)
			(xy 254.067029 -47.340962) (xy 254.024161 -47.376637) (xy 253.976555 -47.405691) (xy 253.925226 -47.427503)
			(xy 253.871269 -47.441609) (xy 253.815832 -47.447709) (xy 253.760098 -47.445672) (xy 253.705255 -47.435542)
			(xy 253.652471 -47.417535) (xy 253.602871 -47.392034) (xy 253.557513 -47.359583) (xy 253.517364 -47.320874)
			(xy 253.483278 -47.276731) (xy 253.455982 -47.228096) (xy 253.436059 -47.176005) (xy 253.423933 -47.121568)
			(xy 253.419862 -47.065946) (xy 252.0696 -47.065946) (xy 252.14072 -47.137066) (xy 252.14072 -48.8165)
			(xy 253.187506 -48.8165) (xy 253.191489 -48.763355) (xy 253.203347 -48.711398) (xy 253.222817 -48.661788)
			(xy 253.249462 -48.615633) (xy 253.282689 -48.573965) (xy 253.321754 -48.537715) (xy 253.365786 -48.507691)
			(xy 253.4138 -48.484565) (xy 253.464725 -48.468853) (xy 253.517423 -48.460906) (xy 253.54407 -48.460406)
			(xy 253.544324 -48.460406) (xy 253.571618 -48.460961) (xy 253.625564 -48.469318) (xy 253.677605 -48.485802)
			(xy 253.726525 -48.510028) (xy 253.771179 -48.541428) (xy 253.791212 -48.559974) (xy 253.802834 -48.570371)
			(xy 253.830768 -48.584195) (xy 253.86157 -48.588951) (xy 253.892372 -48.584195) (xy 253.920306 -48.570371)
			(xy 253.931928 -48.559974) (xy 253.951913 -48.541368) (xy 253.996563 -48.509937) (xy 254.045492 -48.485698)
			(xy 254.09755 -48.469222) (xy 254.151514 -48.460895) (xy 254.178816 -48.460406) (xy 254.17907 -48.460406)
			(xy 254.205724 -48.460849) (xy 254.258436 -48.46879) (xy 254.309376 -48.484499) (xy 254.357406 -48.507625)
			(xy 254.401452 -48.537652) (xy 254.44053 -48.573909) (xy 254.473768 -48.615585) (xy 254.500423 -48.661749)
			(xy 254.5199 -48.711371) (xy 254.531762 -48.763342) (xy 254.535746 -48.8165) (xy 254.531762 -48.869658)
			(xy 254.5199 -48.921629) (xy 254.500423 -48.971251) (xy 254.473768 -49.017415) (xy 254.44053 -49.059091)
			(xy 254.401452 -49.095348) (xy 254.357406 -49.125375) (xy 254.309376 -49.148501) (xy 254.258436 -49.16421)
			(xy 254.205724 -49.172151) (xy 254.17907 -49.172622) (xy 254.178816 -49.172622) (xy 254.151521 -49.172096)
			(xy 254.097574 -49.163731) (xy 254.045533 -49.14724) (xy 253.996614 -49.123008) (xy 253.951961 -49.091602)
			(xy 253.931928 -49.073054) (xy 253.920306 -49.062657) (xy 253.892372 -49.048833) (xy 253.86157 -49.044077)
			(xy 253.830768 -49.048833) (xy 253.802834 -49.062657) (xy 253.791212 -49.073054) (xy 253.771199 -49.091629)
			(xy 253.726558 -49.123067) (xy 253.677637 -49.147313) (xy 253.625584 -49.163796) (xy 253.571624 -49.17213)
			(xy 253.544324 -49.172622) (xy 253.54407 -49.172622) (xy 253.517423 -49.172094) (xy 253.464725 -49.164147)
			(xy 253.4138 -49.148435) (xy 253.365786 -49.125309) (xy 253.321754 -49.095285) (xy 253.282689 -49.059035)
			(xy 253.249462 -49.017367) (xy 253.222817 -48.971212) (xy 253.203347 -48.921602) (xy 253.191489 -48.869645)
			(xy 253.187506 -48.8165) (xy 252.14072 -48.8165) (xy 252.14072 -49.7167) (xy 253.187482 -49.7167)
			(xy 253.191465 -49.663552) (xy 253.203324 -49.611591) (xy 253.222795 -49.561977) (xy 253.249442 -49.51582)
			(xy 253.282671 -49.474149) (xy 253.321739 -49.437896) (xy 253.365774 -49.40787) (xy 253.413792 -49.384742)
			(xy 253.46472 -49.369029) (xy 253.517421 -49.361082) (xy 253.54407 -49.360582) (xy 253.544324 -49.360582)
			(xy 253.571618 -49.361144) (xy 253.625563 -49.3695) (xy 253.677604 -49.385983) (xy 253.726524 -49.410207)
			(xy 253.771178 -49.441605) (xy 253.791212 -49.46015) (xy 253.802834 -49.470547) (xy 253.830768 -49.484371)
			(xy 253.86157 -49.489127) (xy 253.892372 -49.484371) (xy 253.920306 -49.470547) (xy 253.931928 -49.46015)
			(xy 253.951925 -49.441557) (xy 253.99657 -49.410121) (xy 254.045496 -49.385879) (xy 254.097552 -49.369399)
			(xy 254.151515 -49.361071) (xy 254.178816 -49.360582) (xy 254.17907 -49.360582) (xy 254.205722 -49.361073)
			(xy 254.258431 -49.369014) (xy 254.309367 -49.384722) (xy 254.357394 -49.407846) (xy 254.401437 -49.437871)
			(xy 254.440513 -49.474125) (xy 254.473748 -49.515798) (xy 254.500402 -49.56196) (xy 254.519877 -49.611578)
			(xy 254.531738 -49.663545) (xy 254.535722 -49.7167) (xy 254.531738 -49.769855) (xy 254.519877 -49.821822)
			(xy 254.500402 -49.87144) (xy 254.473748 -49.917602) (xy 254.440513 -49.959275) (xy 254.401437 -49.995529)
			(xy 254.357394 -50.025554) (xy 254.309367 -50.048678) (xy 254.258431 -50.064386) (xy 254.205722 -50.072327)
			(xy 254.17907 -50.072798) (xy 254.178816 -50.072798) (xy 254.15152 -50.072278) (xy 254.097573 -50.063913)
			(xy 254.045531 -50.04742) (xy 253.996613 -50.023187) (xy 253.95196 -49.991779) (xy 253.931928 -49.97323)
			(xy 253.920306 -49.962833) (xy 253.892372 -49.949009) (xy 253.86157 -49.944253) (xy 253.830768 -49.949009)
			(xy 253.802834 -49.962833) (xy 253.791212 -49.97323) (xy 253.77121 -49.991818) (xy 253.726565 -50.023251)
			(xy 253.677641 -50.047493) (xy 253.625586 -50.063974) (xy 253.571625 -50.072306) (xy 253.544324 -50.072798)
			(xy 253.54407 -50.072798) (xy 253.517421 -50.072318) (xy 253.46472 -50.064371) (xy 253.413792 -50.048658)
			(xy 253.365774 -50.02553) (xy 253.321739 -49.995504) (xy 253.282671 -49.959251) (xy 253.249442 -49.91758)
			(xy 253.222795 -49.871423) (xy 253.203324 -49.821809) (xy 253.191465 -49.769848) (xy 253.187482 -49.7167)
			(xy 252.14072 -49.7167) (xy 252.14072 -50.6166) (xy 253.187504 -50.6166) (xy 253.191487 -50.563455)
			(xy 253.203345 -50.511497) (xy 253.222815 -50.461887) (xy 253.249461 -50.415732) (xy 253.282687 -50.374064)
			(xy 253.321753 -50.337813) (xy 253.365785 -50.307789) (xy 253.4138 -50.284663) (xy 253.464725 -50.268951)
			(xy 253.517423 -50.261004) (xy 253.54407 -50.260504) (xy 253.544324 -50.260504) (xy 253.571618 -50.26106)
			(xy 253.625564 -50.269417) (xy 253.677605 -50.2859) (xy 253.726525 -50.310126) (xy 253.771179 -50.341526)
			(xy 253.791212 -50.360072) (xy 253.802834 -50.370469) (xy 253.830768 -50.384293) (xy 253.86157 -50.389049)
			(xy 253.892372 -50.384293) (xy 253.920306 -50.370469) (xy 253.931928 -50.360072) (xy 253.951913 -50.341466)
			(xy 253.996563 -50.310035) (xy 254.045491 -50.285796) (xy 254.09755 -50.26932) (xy 254.151514 -50.260993)
			(xy 254.178816 -50.260504) (xy 254.17907 -50.260504) (xy 254.205724 -50.260951) (xy 254.258436 -50.268892)
			(xy 254.309375 -50.284601) (xy 254.357405 -50.307727) (xy 254.40145 -50.337754) (xy 254.43235 -50.366422)
			(xy 255.680462 -50.366422) (xy 255.684533 -50.3108) (xy 255.696659 -50.256363) (xy 255.716582 -50.204272)
			(xy 255.743878 -50.155637) (xy 255.777964 -50.111494) (xy 255.818113 -50.072785) (xy 255.863471 -50.040334)
			(xy 255.913071 -50.014833) (xy 255.965855 -49.996826) (xy 256.020698 -49.986696) (xy 256.076432 -49.984659)
			(xy 256.131869 -49.990759) (xy 256.185826 -50.004865) (xy 256.237155 -50.026677) (xy 256.284761 -50.055731)
			(xy 256.327629 -50.091406) (xy 256.364846 -50.132943) (xy 256.395619 -50.179456) (xy 256.419291 -50.229953)
			(xy 256.435359 -50.28336) (xy 256.443479 -50.338536) (xy 256.443988 -50.366422) (xy 256.443479 -50.394308)
			(xy 256.435359 -50.449484) (xy 256.419291 -50.502891) (xy 256.395619 -50.553388) (xy 256.364846 -50.599901)
			(xy 256.327629 -50.641438) (xy 256.284761 -50.677113) (xy 256.237155 -50.706167) (xy 256.185826 -50.727979)
			(xy 256.131869 -50.742085) (xy 256.076432 -50.748185) (xy 256.020698 -50.746148) (xy 255.965855 -50.736018)
			(xy 255.913071 -50.718011) (xy 255.863471 -50.69251) (xy 255.818113 -50.660059) (xy 255.777964 -50.62135)
			(xy 255.743878 -50.577207) (xy 255.716582 -50.528572) (xy 255.696659 -50.476481) (xy 255.684533 -50.422044)
			(xy 255.680462 -50.366422) (xy 254.43235 -50.366422) (xy 254.440529 -50.37401) (xy 254.473767 -50.415686)
			(xy 254.500421 -50.46185) (xy 254.519898 -50.511472) (xy 254.53176 -50.563442) (xy 254.535744 -50.6166)
			(xy 254.53176 -50.669758) (xy 254.519898 -50.721728) (xy 254.500421 -50.77135) (xy 254.473767 -50.817514)
			(xy 254.440529 -50.85919) (xy 254.40145 -50.895446) (xy 254.357405 -50.925473) (xy 254.309375 -50.948599)
			(xy 254.258436 -50.964308) (xy 254.205724 -50.972249) (xy 254.17907 -50.97272) (xy 254.178816 -50.97272)
			(xy 254.151521 -50.972194) (xy 254.097574 -50.963829) (xy 254.045533 -50.947338) (xy 253.996614 -50.923106)
			(xy 253.951961 -50.8917) (xy 253.931928 -50.873152) (xy 253.920306 -50.862755) (xy 253.892372 -50.848931)
			(xy 253.86157 -50.844175) (xy 253.830768 -50.848931) (xy 253.802834 -50.862755) (xy 253.791212 -50.873152)
			(xy 253.771198 -50.891726) (xy 253.726558 -50.923165) (xy 253.677637 -50.947411) (xy 253.625584 -50.963894)
			(xy 253.571624 -50.972228) (xy 253.544324 -50.97272) (xy 253.54407 -50.97272) (xy 253.517423 -50.972196)
			(xy 253.464725 -50.964249) (xy 253.4138 -50.948537) (xy 253.365785 -50.925411) (xy 253.321753 -50.895387)
			(xy 253.282687 -50.859136) (xy 253.249461 -50.817468) (xy 253.222815 -50.771313) (xy 253.203345 -50.721703)
			(xy 253.191487 -50.669745) (xy 253.187504 -50.6166) (xy 252.14072 -50.6166) (xy 252.14072 -51.5165)
			(xy 253.187527 -51.5165) (xy 253.191509 -51.463358) (xy 253.203367 -51.411404) (xy 253.222835 -51.361797)
			(xy 253.249479 -51.315645) (xy 253.282704 -51.273979) (xy 253.321767 -51.237731) (xy 253.365796 -51.207709)
			(xy 253.413808 -51.184584) (xy 253.46473 -51.168873) (xy 253.517425 -51.160926) (xy 253.54407 -51.160426)
			(xy 253.544324 -51.160426) (xy 253.571619 -51.160976) (xy 253.625565 -51.169333) (xy 253.677606 -51.185818)
			(xy 253.726526 -51.210045) (xy 253.771179 -51.241447) (xy 253.791212 -51.259994) (xy 253.802834 -51.270391)
			(xy 253.830768 -51.284215) (xy 253.86157 -51.288971) (xy 253.892372 -51.284215) (xy 253.920306 -51.270391)
			(xy 253.931928 -51.259994) (xy 253.951916 -51.241391) (xy 253.996565 -51.209959) (xy 254.045493 -51.185719)
			(xy 254.09755 -51.169242) (xy 254.151514 -51.160915) (xy 254.178816 -51.160426) (xy 254.17907 -51.160426)
			(xy 254.205725 -51.160829) (xy 254.258441 -51.168771) (xy 254.309383 -51.184481) (xy 254.357416 -51.207608)
			(xy 254.401464 -51.237637) (xy 254.440545 -51.273895) (xy 254.473785 -51.315573) (xy 254.494197 -51.350926)
			(xy 256.493262 -51.350926) (xy 256.497333 -51.295304) (xy 256.509459 -51.240867) (xy 256.529382 -51.188776)
			(xy 256.556678 -51.140141) (xy 256.590764 -51.095998) (xy 256.630913 -51.057289) (xy 256.676271 -51.024838)
			(xy 256.725871 -50.999337) (xy 256.778655 -50.98133) (xy 256.833498 -50.9712) (xy 256.889232 -50.969163)
			(xy 256.944669 -50.975263) (xy 256.998626 -50.989369) (xy 257.049955 -51.011181) (xy 257.097561 -51.040235)
			(xy 257.140429 -51.07591) (xy 257.177646 -51.117447) (xy 257.208419 -51.16396) (xy 257.232091 -51.214457)
			(xy 257.248159 -51.267864) (xy 257.256279 -51.32304) (xy 257.256788 -51.350926) (xy 257.256279 -51.378812)
			(xy 257.248159 -51.433988) (xy 257.232091 -51.487395) (xy 257.208419 -51.537892) (xy 257.177646 -51.584405)
			(xy 257.140429 -51.625942) (xy 257.097561 -51.661617) (xy 257.049955 -51.690671) (xy 256.998626 -51.712483)
			(xy 256.944669 -51.726589) (xy 256.889232 -51.732689) (xy 256.833498 -51.730652) (xy 256.778655 -51.720522)
			(xy 256.725871 -51.702515) (xy 256.676271 -51.677014) (xy 256.630913 -51.644563) (xy 256.590764 -51.605854)
			(xy 256.556678 -51.561711) (xy 256.529382 -51.513076) (xy 256.509459 -51.460985) (xy 256.497333 -51.406548)
			(xy 256.493262 -51.350926) (xy 254.494197 -51.350926) (xy 254.500441 -51.361741) (xy 254.519919 -51.411365)
			(xy 254.531782 -51.463339) (xy 254.535766 -51.5165) (xy 254.531782 -51.569661) (xy 254.519919 -51.621635)
			(xy 254.500441 -51.671259) (xy 254.473785 -51.717427) (xy 254.440545 -51.759105) (xy 254.401464 -51.795363)
			(xy 254.357416 -51.825392) (xy 254.309383 -51.848519) (xy 254.258441 -51.864229) (xy 254.205725 -51.872171)
			(xy 254.17907 -51.872642) (xy 254.178816 -51.872642) (xy 254.151521 -51.87211) (xy 254.097575 -51.863746)
			(xy 254.045534 -51.847256) (xy 253.996615 -51.823025) (xy 253.951961 -51.791621) (xy 253.931928 -51.773074)
			(xy 253.920306 -51.762677) (xy 253.892372 -51.748853) (xy 253.86157 -51.744097) (xy 253.830768 -51.748853)
			(xy 253.802834 -51.762677) (xy 253.791212 -51.773074) (xy 253.771202 -51.791652) (xy 253.72656 -51.823089)
			(xy 253.677638 -51.847334) (xy 253.625585 -51.863817) (xy 253.571624 -51.87215) (xy 253.544324 -51.872642)
			(xy 253.54407 -51.872642) (xy 253.517425 -51.872074) (xy 253.46473 -51.864127) (xy 253.413808 -51.848416)
			(xy 253.365796 -51.825291) (xy 253.321767 -51.795269) (xy 253.282704 -51.759021) (xy 253.249479 -51.717355)
			(xy 253.222835 -51.671203) (xy 253.203367 -51.621596) (xy 253.191509 -51.569642) (xy 253.187527 -51.5165)
			(xy 252.14072 -51.5165) (xy 252.14072 -51.797966) (xy 251.75464 -52.184046) (xy 247.38076 -52.184046)
			(xy 247.22328 -52.341526) (xy 247.22328 -52.939696) (xy 256.159252 -52.939696) (xy 256.163323 -52.884074)
			(xy 256.175449 -52.829637) (xy 256.195372 -52.777546) (xy 256.222668 -52.728911) (xy 256.256754 -52.684768)
			(xy 256.296903 -52.646059) (xy 256.342261 -52.613608) (xy 256.391861 -52.588107) (xy 256.444645 -52.5701)
			(xy 256.499488 -52.55997) (xy 256.555222 -52.557933) (xy 256.610659 -52.564033) (xy 256.664616 -52.578139)
			(xy 256.715945 -52.599951) (xy 256.763551 -52.629005) (xy 256.806419 -52.66468) (xy 256.843636 -52.706217)
			(xy 256.874409 -52.75273) (xy 256.898081 -52.803227) (xy 256.914149 -52.856634) (xy 256.922269 -52.91181)
			(xy 256.922778 -52.939696) (xy 256.922269 -52.967582) (xy 256.914149 -53.022758) (xy 256.898081 -53.076165)
			(xy 256.874409 -53.126662) (xy 256.843636 -53.173175) (xy 256.806419 -53.214712) (xy 256.763551 -53.250387)
			(xy 256.715945 -53.279441) (xy 256.664616 -53.301253) (xy 256.610659 -53.315359) (xy 256.555222 -53.321459)
			(xy 256.499488 -53.319422) (xy 256.444645 -53.309292) (xy 256.391861 -53.291285) (xy 256.342261 -53.265784)
			(xy 256.296903 -53.233333) (xy 256.256754 -53.194624) (xy 256.222668 -53.150481) (xy 256.195372 -53.101846)
			(xy 256.175449 -53.049755) (xy 256.163323 -52.995318) (xy 256.159252 -52.939696) (xy 247.22328 -52.939696)
			(xy 247.22328 -53.466746) (xy 247.36044 -53.603906) (xy 253.772922 -53.603906) (xy 253.776993 -53.548284)
			(xy 253.789119 -53.493847) (xy 253.809042 -53.441756) (xy 253.836338 -53.393121) (xy 253.870424 -53.348978)
			(xy 253.910573 -53.310269) (xy 253.955931 -53.277818) (xy 254.005531 -53.252317) (xy 254.058315 -53.23431)
			(xy 254.113158 -53.22418) (xy 254.168892 -53.222143) (xy 254.224329 -53.228243) (xy 254.278286 -53.242349)
			(xy 254.329615 -53.264161) (xy 254.377221 -53.293215) (xy 254.420089 -53.32889) (xy 254.457306 -53.370427)
			(xy 254.488079 -53.41694) (xy 254.511751 -53.467437) (xy 254.527819 -53.520844) (xy 254.535939 -53.57602)
			(xy 254.536123 -53.586126) (xy 255.050542 -53.586126) (xy 255.054613 -53.530504) (xy 255.066739 -53.476067)
			(xy 255.086662 -53.423976) (xy 255.113958 -53.375341) (xy 255.148044 -53.331198) (xy 255.188193 -53.292489)
			(xy 255.233551 -53.260038) (xy 255.283151 -53.234537) (xy 255.335935 -53.21653) (xy 255.390778 -53.2064)
			(xy 255.446512 -53.204363) (xy 255.501949 -53.210463) (xy 255.555906 -53.224569) (xy 255.607235 -53.246381)
			(xy 255.654841 -53.275435) (xy 255.697709 -53.31111) (xy 255.734926 -53.352647) (xy 255.765699 -53.39916)
			(xy 255.789371 -53.449657) (xy 255.805439 -53.503064) (xy 255.813559 -53.55824) (xy 255.814068 -53.586126)
			(xy 255.813559 -53.614012) (xy 255.805439 -53.669188) (xy 255.789371 -53.722595) (xy 255.765699 -53.773092)
			(xy 255.734926 -53.819605) (xy 255.697709 -53.861142) (xy 255.654841 -53.896817) (xy 255.607235 -53.925871)
			(xy 255.555906 -53.947683) (xy 255.501949 -53.961789) (xy 255.446512 -53.967889) (xy 255.390778 -53.965852)
			(xy 255.335935 -53.955722) (xy 255.283151 -53.937715) (xy 255.233551 -53.912214) (xy 255.188193 -53.879763)
			(xy 255.148044 -53.841054) (xy 255.113958 -53.796911) (xy 255.086662 -53.748276) (xy 255.066739 -53.696185)
			(xy 255.054613 -53.641748) (xy 255.050542 -53.586126) (xy 254.536123 -53.586126) (xy 254.536448 -53.603906)
			(xy 254.535939 -53.631792) (xy 254.527819 -53.686968) (xy 254.511751 -53.740375) (xy 254.488079 -53.790872)
			(xy 254.457306 -53.837385) (xy 254.420089 -53.878922) (xy 254.377221 -53.914597) (xy 254.329615 -53.943651)
			(xy 254.278286 -53.965463) (xy 254.224329 -53.979569) (xy 254.168892 -53.985669) (xy 254.113158 -53.983632)
			(xy 254.058315 -53.973502) (xy 254.005531 -53.955495) (xy 253.955931 -53.929994) (xy 253.910573 -53.897543)
			(xy 253.870424 -53.858834) (xy 253.836338 -53.814691) (xy 253.809042 -53.766056) (xy 253.789119 -53.713965)
			(xy 253.776993 -53.659528) (xy 253.772922 -53.603906) (xy 247.36044 -53.603906) (xy 248.821956 -55.065422)
			(xy 248.832621 -55.075428) (xy 248.858289 -55.089415) (xy 248.886869 -55.095554) (xy 248.916017 -55.093343)
			(xy 248.943343 -55.082963) (xy 248.966608 -55.065264) (xy 248.983903 -55.041698) (xy 248.993811 -55.014197)
			(xy 248.995184 -54.999636) (xy 248.997425 -54.970876) (xy 249.009479 -54.914464) (xy 249.029887 -54.86051)
			(xy 249.058184 -54.810242) (xy 249.093724 -54.764805) (xy 249.135699 -54.725236) (xy 249.183151 -54.692436)
			(xy 249.235 -54.667152) (xy 249.290064 -54.64996) (xy 249.347088 -54.641252) (xy 249.37593 -54.640734)
			(xy 249.40318 -54.641199) (xy 249.457126 -54.64896) (xy 249.509418 -54.664319) (xy 249.558991 -54.686964)
			(xy 249.604838 -54.716433) (xy 249.646023 -54.752128) (xy 249.68171 -54.79332) (xy 249.711171 -54.839172)
			(xy 249.733806 -54.88875) (xy 249.749155 -54.941045) (xy 249.756906 -54.994992) (xy 249.757438 -55.022242)
			(xy 249.756912 -55.051088) (xy 249.75357 -55.073042) (xy 251.127512 -55.073042) (xy 251.131583 -55.01742)
			(xy 251.143709 -54.962983) (xy 251.163632 -54.910892) (xy 251.190928 -54.862257) (xy 251.225014 -54.818114)
			(xy 251.265163 -54.779405) (xy 251.310521 -54.746954) (xy 251.360121 -54.721453) (xy 251.412905 -54.703446)
			(xy 251.467748 -54.693316) (xy 251.523482 -54.691279) (xy 251.578919 -54.697379) (xy 251.632876 -54.711485)
			(xy 251.684205 -54.733297) (xy 251.731811 -54.762351) (xy 251.774679 -54.798026) (xy 251.811896 -54.839563)
			(xy 251.842669 -54.886076) (xy 251.866341 -54.936573) (xy 251.882409 -54.98998) (xy 251.890529 -55.045156)
			(xy 251.891038 -55.073042) (xy 251.890529 -55.100928) (xy 251.882409 -55.156104) (xy 251.866341 -55.209511)
			(xy 251.842669 -55.260008) (xy 251.811896 -55.306521) (xy 251.774679 -55.348058) (xy 251.731811 -55.383733)
			(xy 251.684205 -55.412787) (xy 251.632876 -55.434599) (xy 251.578919 -55.448705) (xy 251.523482 -55.454805)
			(xy 251.467748 -55.452768) (xy 251.412905 -55.442638) (xy 251.360121 -55.424631) (xy 251.310521 -55.39913)
			(xy 251.265163 -55.366679) (xy 251.225014 -55.32797) (xy 251.190928 -55.283827) (xy 251.163632 -55.235192)
			(xy 251.143709 -55.183101) (xy 251.131583 -55.128664) (xy 251.127512 -55.073042) (xy 249.75357 -55.073042)
			(xy 249.748231 -55.108122) (xy 249.731057 -55.163198) (xy 249.705783 -55.215058) (xy 249.672986 -55.26252)
			(xy 249.633413 -55.3045) (xy 249.587969 -55.340039) (xy 249.53769 -55.368328) (xy 249.483723 -55.388721)
			(xy 249.4273 -55.400751) (xy 249.398536 -55.402988) (xy 249.383989 -55.404348) (xy 249.35653 -55.414294)
			(xy 249.333007 -55.431603) (xy 249.315341 -55.454859) (xy 249.304976 -55.482162) (xy 249.302759 -55.511283)
			(xy 249.308871 -55.539841) (xy 249.322812 -55.565504) (xy 249.33275 -55.576216) (xy 250.020328 -56.26354)
			(xy 253.93142 -56.26354) (xy 253.945793 -56.263055) (xy 253.973402 -56.255054) (xy 253.997681 -56.239664)
			(xy 254.0167 -56.21811) (xy 254.028947 -56.192105) (xy 254.033449 -56.163714) (xy 254.029848 -56.135196)
			(xy 254.01843 -56.108815) (xy 254.009652 -56.097424) (xy 253.993174 -56.0768) (xy 253.965453 -56.031873)
			(xy 253.944184 -55.983557) (xy 253.929771 -55.932773) (xy 253.922489 -55.880487) (xy 253.922022 -55.854092)
			(xy 253.922508 -55.826841) (xy 253.930264 -55.772893) (xy 253.945619 -55.720598) (xy 253.968261 -55.671021)
			(xy 253.997727 -55.625171) (xy 254.033418 -55.58398) (xy 254.074609 -55.548289) (xy 254.120459 -55.518823)
			(xy 254.170036 -55.496181) (xy 254.222331 -55.480826) (xy 254.276279 -55.47307) (xy 254.330781 -55.47307)
			(xy 254.384729 -55.480826) (xy 254.437024 -55.496181) (xy 254.486601 -55.518823) (xy 254.532451 -55.548289)
			(xy 254.573642 -55.58398) (xy 254.609333 -55.625171) (xy 254.638799 -55.671021) (xy 254.661441 -55.720598)
			(xy 254.676796 -55.772893) (xy 254.684552 -55.826841) (xy 254.685038 -55.854092) (xy 254.684591 -55.880488)
			(xy 254.677314 -55.932776) (xy 254.662898 -55.983562) (xy 254.641617 -56.031875) (xy 254.613879 -56.076792)
			(xy 254.597408 -56.097424) (xy 254.588658 -56.108822) (xy 254.577294 -56.1352) (xy 254.573728 -56.1637)
			(xy 254.578241 -56.192065) (xy 254.590477 -56.21805) (xy 254.609467 -56.239599) (xy 254.633707 -56.255005)
			(xy 254.66128 -56.263049) (xy 254.67564 -56.26354) (xy 257.35788 -56.26354) (xy 257.401022 -56.263997)
			(xy 257.486977 -56.271516) (xy 257.571949 -56.286499) (xy 257.655293 -56.308831) (xy 257.736372 -56.338343)
			(xy 257.81457 -56.37481) (xy 257.889292 -56.417954) (xy 257.959969 -56.467448) (xy 258.026063 -56.522913)
			(xy 258.056888 -56.5531) (xy 258.704334 -57.2008) (xy 258.738624 -57.2008)
		)
		(stroke
			(width 0)
			(type solid)
		)
		(fill yes)
		(layer "In6.Cu")
		(net "GND")
	)
	(gr_poly
		(pts
			(xy 83.29168 -30.851348) (xy 83.29168 -18.481548) (xy 81.552034 -16.742156) (xy 81.28254 -16.742156)
			(xy 81.253567 -16.741596) (xy 81.196339 -16.732488) (xy 81.141243 -16.714536) (xy 81.089634 -16.688183)
			(xy 81.042785 -16.654079) (xy 81.021936 -16.633952) (xy 79.468726 -15.080996) (xy 78.002638 -15.080996)
			(xy 77.987685 -15.081518) (xy 77.95906 -15.090174) (xy 77.934172 -15.106754) (xy 77.915157 -15.129836)
			(xy 77.903647 -15.157437) (xy 77.90063 -15.18719) (xy 77.906366 -15.21654) (xy 77.92036 -15.242969)
			(xy 77.930502 -15.25397) (xy 77.951108 -15.275553) (xy 77.986034 -15.323931) (xy 78.013006 -15.377155)
			(xy 78.031366 -15.433929) (xy 78.040667 -15.492868) (xy 78.041246 -15.522702) (xy 78.040759 -15.550276)
			(xy 78.032817 -15.60485) (xy 78.017099 -15.657711) (xy 77.993932 -15.707757) (xy 77.9638 -15.753946)
			(xy 77.92733 -15.795313) (xy 77.906626 -15.813532) (xy 77.895727 -15.823429) (xy 77.879652 -15.848079)
			(xy 77.871266 -15.876287) (xy 77.871267 -15.905715) (xy 77.879653 -15.933923) (xy 77.895729 -15.958572)
			(xy 77.906626 -15.968472) (xy 77.927335 -15.986686) (xy 77.963807 -16.028056) (xy 77.993944 -16.074245)
			(xy 78.017117 -16.124291) (xy 78.032844 -16.177152) (xy 78.040798 -16.231727) (xy 78.041246 -16.259302)
			(xy 78.04076 -16.286553) (xy 78.033004 -16.340501) (xy 78.017649 -16.392796) (xy 77.995007 -16.442373)
			(xy 77.965541 -16.488223) (xy 77.92985 -16.529414) (xy 77.888659 -16.565105) (xy 77.842809 -16.594571)
			(xy 77.793232 -16.617213) (xy 77.740937 -16.632568) (xy 77.686989 -16.640324) (xy 77.632487 -16.640324)
			(xy 77.578539 -16.632568) (xy 77.526244 -16.617213) (xy 77.476667 -16.594571) (xy 77.430817 -16.565105)
			(xy 77.389626 -16.529414) (xy 77.353935 -16.488223) (xy 77.324469 -16.442373) (xy 77.301827 -16.392796)
			(xy 77.286472 -16.340501) (xy 77.278716 -16.286553) (xy 77.27823 -16.259302) (xy 77.278716 -16.231727)
			(xy 77.286658 -16.177153) (xy 77.302375 -16.124291) (xy 77.32554 -16.074244) (xy 77.355671 -16.028053)
			(xy 77.392139 -15.986683) (xy 77.41285 -15.968472) (xy 77.423752 -15.958576) (xy 77.439832 -15.933927)
			(xy 77.448221 -15.905717) (xy 77.448221 -15.876286) (xy 77.439833 -15.848076) (xy 77.423753 -15.823426)
			(xy 77.41285 -15.813532) (xy 77.392142 -15.795317) (xy 77.355671 -15.753947) (xy 77.325536 -15.707758)
			(xy 77.302364 -15.657712) (xy 77.286637 -15.604851) (xy 77.278684 -15.550277) (xy 77.27823 -15.522702)
			(xy 77.278807 -15.492867) (xy 77.2881 -15.433926) (xy 77.306459 -15.377152) (xy 77.333436 -15.323929)
			(xy 77.368372 -15.275557) (xy 77.388974 -15.25397) (xy 77.399098 -15.242971) (xy 77.413042 -15.216545)
			(xy 77.418743 -15.187214) (xy 77.415712 -15.157488) (xy 77.40421 -15.129912) (xy 77.38522 -15.106843)
			(xy 77.360366 -15.090257) (xy 77.331777 -15.081572) (xy 77.316838 -15.080996) (xy 72.252586 -15.080996)
			(xy 70.7136 -16.619728) (xy 70.7136 -18.160746) (xy 74.02525 -18.160746) (xy 74.029321 -18.105124)
			(xy 74.041447 -18.050687) (xy 74.06137 -17.998596) (xy 74.088666 -17.949961) (xy 74.122752 -17.905818)
			(xy 74.162901 -17.867109) (xy 74.208259 -17.834658) (xy 74.257859 -17.809157) (xy 74.310643 -17.79115)
			(xy 74.365486 -17.78102) (xy 74.42122 -17.778983) (xy 74.476657 -17.785083) (xy 74.530614 -17.799189)
			(xy 74.581943 -17.821001) (xy 74.629549 -17.850055) (xy 74.672417 -17.88573) (xy 74.709634 -17.927267)
			(xy 74.740407 -17.97378) (xy 74.764079 -18.024277) (xy 74.780147 -18.077684) (xy 74.788267 -18.13286)
			(xy 74.788776 -18.160746) (xy 74.788461 -18.178018) (xy 77.15072 -18.178018) (xy 77.154791 -18.122396)
			(xy 77.166917 -18.067959) (xy 77.18684 -18.015868) (xy 77.214136 -17.967233) (xy 77.248222 -17.92309)
			(xy 77.288371 -17.884381) (xy 77.333729 -17.85193) (xy 77.383329 -17.826429) (xy 77.436113 -17.808422)
			(xy 77.490956 -17.798292) (xy 77.54669 -17.796255) (xy 77.602127 -17.802355) (xy 77.656084 -17.816461)
			(xy 77.707413 -17.838273) (xy 77.755019 -17.867327) (xy 77.797887 -17.903002) (xy 77.835104 -17.944539)
			(xy 77.865877 -17.991052) (xy 77.889549 -18.041549) (xy 77.905617 -18.094956) (xy 77.913737 -18.150132)
			(xy 77.914246 -18.178018) (xy 77.913737 -18.205904) (xy 77.909019 -18.237962) (xy 79.54137 -18.237962)
			(xy 79.541889 -18.210389) (xy 79.549832 -18.155819) (xy 79.565547 -18.102961) (xy 79.588707 -18.052915)
			(xy 79.61883 -18.006724) (xy 79.655288 -17.96535) (xy 79.67599 -17.947132) (xy 79.686926 -17.937272)
			(xy 79.702998 -17.912611) (xy 79.711378 -17.884393) (xy 79.711371 -17.854958) (xy 79.702977 -17.826744)
			(xy 79.686893 -17.802091) (xy 79.67599 -17.792192) (xy 79.65527 -17.773991) (xy 79.618801 -17.73262)
			(xy 79.58867 -17.686428) (xy 79.565506 -17.636378) (xy 79.549791 -17.583514) (xy 79.541854 -17.528937)
			(xy 79.54137 -17.501362) (xy 79.541856 -17.474111) (xy 79.549612 -17.420163) (xy 79.564967 -17.367868)
			(xy 79.587609 -17.318291) (xy 79.617075 -17.272441) (xy 79.652766 -17.23125) (xy 79.693957 -17.195559)
			(xy 79.739807 -17.166093) (xy 79.789384 -17.143451) (xy 79.841679 -17.128096) (xy 79.895627 -17.12034)
			(xy 79.950129 -17.12034) (xy 80.004077 -17.128096) (xy 80.056372 -17.143451) (xy 80.105949 -17.166093)
			(xy 80.151799 -17.195559) (xy 80.19299 -17.23125) (xy 80.228681 -17.272441) (xy 80.258147 -17.318291)
			(xy 80.280789 -17.367868) (xy 80.296144 -17.420163) (xy 80.3039 -17.474111) (xy 80.304386 -17.501362)
			(xy 80.303899 -17.528936) (xy 80.295952 -17.583508) (xy 80.280231 -17.636368) (xy 80.257065 -17.686414)
			(xy 80.226936 -17.732604) (xy 80.190472 -17.773976) (xy 80.169766 -17.792192) (xy 80.15891 -17.802131)
			(xy 80.142842 -17.826771) (xy 80.134458 -17.854967) (xy 80.13445 -17.884384) (xy 80.142822 -17.912584)
			(xy 80.158878 -17.937232) (xy 80.169766 -17.947132) (xy 80.190489 -17.96533) (xy 80.22696 -18.006701)
			(xy 80.257091 -18.052893) (xy 80.280255 -18.102944) (xy 80.295969 -18.155809) (xy 80.303904 -18.210386)
			(xy 80.304386 -18.237962) (xy 80.3039 -18.265213) (xy 80.296144 -18.319161) (xy 80.280789 -18.371456)
			(xy 80.258147 -18.421033) (xy 80.228681 -18.466883) (xy 80.19299 -18.508074) (xy 80.151799 -18.543765)
			(xy 80.106327 -18.572988) (xy 81.670142 -18.572988) (xy 81.674213 -18.517366) (xy 81.686339 -18.462929)
			(xy 81.706262 -18.410838) (xy 81.733558 -18.362203) (xy 81.767644 -18.31806) (xy 81.807793 -18.279351)
			(xy 81.853151 -18.2469) (xy 81.902751 -18.221399) (xy 81.955535 -18.203392) (xy 82.010378 -18.193262)
			(xy 82.066112 -18.191225) (xy 82.121549 -18.197325) (xy 82.175506 -18.211431) (xy 82.226835 -18.233243)
			(xy 82.274441 -18.262297) (xy 82.317309 -18.297972) (xy 82.354526 -18.339509) (xy 82.385299 -18.386022)
			(xy 82.408971 -18.436519) (xy 82.425039 -18.489926) (xy 82.433159 -18.545102) (xy 82.433668 -18.572988)
			(xy 82.433159 -18.600874) (xy 82.425039 -18.65605) (xy 82.408971 -18.709457) (xy 82.385299 -18.759954)
			(xy 82.354526 -18.806467) (xy 82.317309 -18.848004) (xy 82.274441 -18.883679) (xy 82.226835 -18.912733)
			(xy 82.175506 -18.934545) (xy 82.121549 -18.948651) (xy 82.066112 -18.954751) (xy 82.010378 -18.952714)
			(xy 81.955535 -18.942584) (xy 81.902751 -18.924577) (xy 81.853151 -18.899076) (xy 81.807793 -18.866625)
			(xy 81.767644 -18.827916) (xy 81.733558 -18.783773) (xy 81.706262 -18.735138) (xy 81.686339 -18.683047)
			(xy 81.674213 -18.62861) (xy 81.670142 -18.572988) (xy 80.106327 -18.572988) (xy 80.105949 -18.573231)
			(xy 80.056372 -18.595873) (xy 80.004077 -18.611228) (xy 79.950129 -18.618984) (xy 79.895627 -18.618984)
			(xy 79.841679 -18.611228) (xy 79.789384 -18.595873) (xy 79.739807 -18.573231) (xy 79.693957 -18.543765)
			(xy 79.652766 -18.508074) (xy 79.617075 -18.466883) (xy 79.587609 -18.421033) (xy 79.564967 -18.371456)
			(xy 79.549612 -18.319161) (xy 79.541856 -18.265213) (xy 79.54137 -18.237962) (xy 77.909019 -18.237962)
			(xy 77.905617 -18.26108) (xy 77.889549 -18.314487) (xy 77.865877 -18.364984) (xy 77.835104 -18.411497)
			(xy 77.797887 -18.453034) (xy 77.755019 -18.488709) (xy 77.707413 -18.517763) (xy 77.656084 -18.539575)
			(xy 77.602127 -18.553681) (xy 77.54669 -18.559781) (xy 77.490956 -18.557744) (xy 77.436113 -18.547614)
			(xy 77.383329 -18.529607) (xy 77.333729 -18.504106) (xy 77.288371 -18.471655) (xy 77.248222 -18.432946)
			(xy 77.214136 -18.388803) (xy 77.18684 -18.340168) (xy 77.166917 -18.288077) (xy 77.154791 -18.23364)
			(xy 77.15072 -18.178018) (xy 74.788461 -18.178018) (xy 74.788267 -18.188632) (xy 74.780147 -18.243808)
			(xy 74.764079 -18.297215) (xy 74.740407 -18.347712) (xy 74.709634 -18.394225) (xy 74.672417 -18.435762)
			(xy 74.629549 -18.471437) (xy 74.581943 -18.500491) (xy 74.530614 -18.522303) (xy 74.476657 -18.536409)
			(xy 74.42122 -18.542509) (xy 74.365486 -18.540472) (xy 74.310643 -18.530342) (xy 74.257859 -18.512335)
			(xy 74.208259 -18.486834) (xy 74.162901 -18.454383) (xy 74.122752 -18.415674) (xy 74.088666 -18.371531)
			(xy 74.06137 -18.322896) (xy 74.041447 -18.270805) (xy 74.029321 -18.216368) (xy 74.02525 -18.160746)
			(xy 70.7136 -18.160746) (xy 70.7136 -19.220942) (xy 76.404722 -19.220942) (xy 76.408793 -19.16532)
			(xy 76.420919 -19.110883) (xy 76.440842 -19.058792) (xy 76.468138 -19.010157) (xy 76.502224 -18.966014)
			(xy 76.542373 -18.927305) (xy 76.587731 -18.894854) (xy 76.637331 -18.869353) (xy 76.690115 -18.851346)
			(xy 76.744958 -18.841216) (xy 76.800692 -18.839179) (xy 76.856129 -18.845279) (xy 76.910086 -18.859385)
			(xy 76.961415 -18.881197) (xy 77.009021 -18.910251) (xy 77.051889 -18.945926) (xy 77.089106 -18.987463)
			(xy 77.119879 -19.033976) (xy 77.143551 -19.084473) (xy 77.159619 -19.13788) (xy 77.167739 -19.193056)
			(xy 77.168248 -19.220942) (xy 77.167739 -19.248828) (xy 77.163657 -19.276568) (xy 78.474568 -19.276568)
			(xy 78.478639 -19.220946) (xy 78.490765 -19.166509) (xy 78.510688 -19.114418) (xy 78.537984 -19.065783)
			(xy 78.57207 -19.02164) (xy 78.612219 -18.982931) (xy 78.657577 -18.95048) (xy 78.707177 -18.924979)
			(xy 78.759961 -18.906972) (xy 78.814804 -18.896842) (xy 78.870538 -18.894805) (xy 78.925975 -18.900905)
			(xy 78.979932 -18.915011) (xy 79.031261 -18.936823) (xy 79.078867 -18.965877) (xy 79.121735 -19.001552)
			(xy 79.158952 -19.043089) (xy 79.189725 -19.089602) (xy 79.213397 -19.140099) (xy 79.229465 -19.193506)
			(xy 79.237585 -19.248682) (xy 79.238094 -19.276568) (xy 79.237585 -19.304454) (xy 79.229465 -19.35963)
			(xy 79.213397 -19.413037) (xy 79.189725 -19.463534) (xy 79.158952 -19.510047) (xy 79.121735 -19.551584)
			(xy 79.078867 -19.587259) (xy 79.031261 -19.616313) (xy 78.979932 -19.638125) (xy 78.925975 -19.652231)
			(xy 78.870538 -19.658331) (xy 78.814804 -19.656294) (xy 78.759961 -19.646164) (xy 78.707177 -19.628157)
			(xy 78.657577 -19.602656) (xy 78.612219 -19.570205) (xy 78.57207 -19.531496) (xy 78.537984 -19.487353)
			(xy 78.510688 -19.438718) (xy 78.490765 -19.386627) (xy 78.478639 -19.33219) (xy 78.474568 -19.276568)
			(xy 77.163657 -19.276568) (xy 77.159619 -19.304004) (xy 77.143551 -19.357411) (xy 77.119879 -19.407908)
			(xy 77.089106 -19.454421) (xy 77.051889 -19.495958) (xy 77.009021 -19.531633) (xy 76.961415 -19.560687)
			(xy 76.910086 -19.582499) (xy 76.856129 -19.596605) (xy 76.800692 -19.602705) (xy 76.744958 -19.600668)
			(xy 76.690115 -19.590538) (xy 76.637331 -19.572531) (xy 76.587731 -19.54703) (xy 76.542373 -19.514579)
			(xy 76.502224 -19.47587) (xy 76.468138 -19.431727) (xy 76.440842 -19.383092) (xy 76.420919 -19.331001)
			(xy 76.408793 -19.276564) (xy 76.404722 -19.220942) (xy 70.7136 -19.220942) (xy 70.7136 -19.839753)
			(xy 81.008163 -19.839753) (xy 81.008163 -19.785247) (xy 81.015921 -19.731295) (xy 81.031277 -19.678997)
			(xy 81.053921 -19.629417) (xy 81.08339 -19.583563) (xy 81.119085 -19.542371) (xy 81.160279 -19.506678)
			(xy 81.206134 -19.477211) (xy 81.255716 -19.45457) (xy 81.308015 -19.439216) (xy 81.361967 -19.431462)
			(xy 81.38922 -19.431) (xy 81.420118 -19.431619) (xy 81.481103 -19.441596) (xy 81.539679 -19.461284)
			(xy 81.567274 -19.475196) (xy 81.58046 -19.481564) (xy 81.609164 -19.487283) (xy 81.638314 -19.484641)
			(xy 81.665523 -19.473856) (xy 81.688566 -19.45581) (xy 81.705558 -19.431978) (xy 81.710784 -19.4183)
			(xy 81.71975 -19.393576) (xy 81.743518 -19.346661) (xy 81.773502 -19.303454) (xy 81.809135 -19.264773)
			(xy 81.849741 -19.231351) (xy 81.894552 -19.203821) (xy 81.942718 -19.182704) (xy 81.993328 -19.168401)
			(xy 82.045422 -19.161183) (xy 82.071718 -19.160744) (xy 82.098965 -19.161327) (xy 82.152904 -19.169085)
			(xy 82.20519 -19.18444) (xy 82.254758 -19.207079) (xy 82.300601 -19.236542) (xy 82.341784 -19.272229)
			(xy 82.377469 -19.313414) (xy 82.40693 -19.359257) (xy 82.429567 -19.408827) (xy 82.444919 -19.461114)
			(xy 82.452674 -19.515053) (xy 82.452674 -19.569547) (xy 82.444919 -19.623486) (xy 82.429567 -19.675773)
			(xy 82.40693 -19.725343) (xy 82.377469 -19.771186) (xy 82.341784 -19.812371) (xy 82.300601 -19.848058)
			(xy 82.254758 -19.877521) (xy 82.20519 -19.90016) (xy 82.152904 -19.915515) (xy 82.098965 -19.923273)
			(xy 82.071718 -19.92376) (xy 82.040819 -19.923169) (xy 81.979833 -19.913181) (xy 81.921258 -19.893482)
			(xy 81.893664 -19.879564) (xy 81.88045 -19.873264) (xy 81.851758 -19.867541) (xy 81.82262 -19.870174)
			(xy 81.795419 -19.880946) (xy 81.772379 -19.898976) (xy 81.755384 -19.92279) (xy 81.750154 -19.93646)
			(xy 81.741218 -19.961196) (xy 81.71745 -20.008115) (xy 81.687464 -20.051325) (xy 81.651828 -20.090007)
			(xy 81.611218 -20.123429) (xy 81.566402 -20.150958) (xy 81.518231 -20.172071) (xy 81.467616 -20.18637)
			(xy 81.415518 -20.193581) (xy 81.38922 -20.194016) (xy 81.361967 -20.193538) (xy 81.308015 -20.185784)
			(xy 81.255716 -20.17043) (xy 81.206134 -20.147789) (xy 81.160279 -20.118322) (xy 81.119085 -20.082629)
			(xy 81.08339 -20.041437) (xy 81.053921 -19.995583) (xy 81.031277 -19.946003) (xy 81.015921 -19.893705)
			(xy 81.008163 -19.839753) (xy 70.7136 -19.839753) (xy 70.7136 -20.944078) (xy 76.224382 -20.944078)
			(xy 76.228453 -20.888456) (xy 76.240579 -20.834019) (xy 76.260502 -20.781928) (xy 76.287798 -20.733293)
			(xy 76.321884 -20.68915) (xy 76.362033 -20.650441) (xy 76.407391 -20.61799) (xy 76.456991 -20.592489)
			(xy 76.509775 -20.574482) (xy 76.564618 -20.564352) (xy 76.620352 -20.562315) (xy 76.675789 -20.568415)
			(xy 76.729746 -20.582521) (xy 76.781075 -20.604333) (xy 76.828681 -20.633387) (xy 76.871549 -20.669062)
			(xy 76.908766 -20.710599) (xy 76.939539 -20.757112) (xy 76.963211 -20.807609) (xy 76.979279 -20.861016)
			(xy 76.987399 -20.916192) (xy 76.987908 -20.944078) (xy 76.987399 -20.971964) (xy 76.979279 -21.02714)
			(xy 76.963211 -21.080547) (xy 76.939539 -21.131044) (xy 76.908766 -21.177557) (xy 76.871549 -21.219094)
			(xy 76.828681 -21.254769) (xy 76.781075 -21.283823) (xy 76.729746 -21.305635) (xy 76.675789 -21.319741)
			(xy 76.620352 -21.325841) (xy 76.564618 -21.323804) (xy 76.509775 -21.313674) (xy 76.456991 -21.295667)
			(xy 76.407391 -21.270166) (xy 76.362033 -21.237715) (xy 76.321884 -21.199006) (xy 76.287798 -21.154863)
			(xy 76.260502 -21.106228) (xy 76.240579 -21.054137) (xy 76.228453 -20.9997) (xy 76.224382 -20.944078)
			(xy 70.7136 -20.944078) (xy 70.7136 -21.416772) (xy 81.628742 -21.416772) (xy 81.62926 -21.387965)
			(xy 81.637934 -21.331007) (xy 81.655066 -21.275999) (xy 81.680266 -21.224189) (xy 81.712965 -21.176752)
			(xy 81.752418 -21.134766) (xy 81.79773 -21.099183) (xy 81.822544 -21.08454) (xy 81.834696 -21.07709)
			(xy 81.854691 -21.056799) (xy 81.86829 -21.031767) (xy 81.874431 -21.003949) (xy 81.872634 -20.975518)
			(xy 81.86304 -20.948695) (xy 81.846397 -20.925574) (xy 81.835498 -20.916392) (xy 81.813248 -20.898197)
			(xy 81.773976 -20.856231) (xy 81.741439 -20.808852) (xy 81.716371 -20.757131) (xy 81.699339 -20.702237)
			(xy 81.690727 -20.64541) (xy 81.69021 -20.616672) (xy 81.690696 -20.589421) (xy 81.698452 -20.535473)
			(xy 81.713807 -20.483178) (xy 81.736449 -20.433601) (xy 81.765915 -20.387751) (xy 81.801606 -20.34656)
			(xy 81.842797 -20.310869) (xy 81.888647 -20.281403) (xy 81.938224 -20.258761) (xy 81.990519 -20.243406)
			(xy 82.044467 -20.23565) (xy 82.098969 -20.23565) (xy 82.152917 -20.243406) (xy 82.205212 -20.258761)
			(xy 82.254789 -20.281403) (xy 82.300639 -20.310869) (xy 82.34183 -20.34656) (xy 82.377521 -20.387751)
			(xy 82.406987 -20.433601) (xy 82.429629 -20.483178) (xy 82.444984 -20.535473) (xy 82.45274 -20.589421)
			(xy 82.453226 -20.616672) (xy 82.452709 -20.645478) (xy 82.44403 -20.702435) (xy 82.426896 -20.757441)
			(xy 82.401694 -20.80925) (xy 82.368997 -20.856686) (xy 82.329546 -20.898674) (xy 82.284236 -20.934259)
			(xy 82.259424 -20.948904) (xy 82.247234 -20.956295) (xy 82.227242 -20.976601) (xy 82.213648 -21.001645)
			(xy 82.207513 -21.029473) (xy 82.209317 -21.057911) (xy 82.218918 -21.084741) (xy 82.235567 -21.107867)
			(xy 82.24647 -21.117052) (xy 82.268707 -21.135261) (xy 82.307977 -21.177227) (xy 82.340514 -21.224603)
			(xy 82.365583 -21.276321) (xy 82.382619 -21.331212) (xy 82.391237 -21.388035) (xy 82.391758 -21.416772)
			(xy 82.391272 -21.444023) (xy 82.383516 -21.497971) (xy 82.368161 -21.550266) (xy 82.345519 -21.599843)
			(xy 82.316053 -21.645693) (xy 82.280362 -21.686884) (xy 82.239171 -21.722575) (xy 82.193321 -21.752041)
			(xy 82.143744 -21.774683) (xy 82.091449 -21.790038) (xy 82.037501 -21.797794) (xy 81.982999 -21.797794)
			(xy 81.929051 -21.790038) (xy 81.876756 -21.774683) (xy 81.827179 -21.752041) (xy 81.781329 -21.722575)
			(xy 81.740138 -21.686884) (xy 81.704447 -21.645693) (xy 81.674981 -21.599843) (xy 81.652339 -21.550266)
			(xy 81.636984 -21.497971) (xy 81.629228 -21.444023) (xy 81.628742 -21.416772) (xy 70.7136 -21.416772)
			(xy 70.7136 -22.581362) (xy 74.63866 -22.581362) (xy 74.642731 -22.52574) (xy 74.654857 -22.471303)
			(xy 74.67478 -22.419212) (xy 74.702076 -22.370577) (xy 74.736162 -22.326434) (xy 74.776311 -22.287725)
			(xy 74.821669 -22.255274) (xy 74.871269 -22.229773) (xy 74.924053 -22.211766) (xy 74.978896 -22.201636)
			(xy 75.03463 -22.199599) (xy 75.090067 -22.205699) (xy 75.144024 -22.219805) (xy 75.195353 -22.241617)
			(xy 75.242959 -22.270671) (xy 75.285827 -22.306346) (xy 75.323044 -22.347883) (xy 75.353817 -22.394396)
			(xy 75.377489 -22.444893) (xy 75.393557 -22.4983) (xy 75.401677 -22.553476) (xy 75.402186 -22.581362)
			(xy 75.401677 -22.609248) (xy 75.393557 -22.664424) (xy 75.377489 -22.717831) (xy 75.357227 -22.761053)
			(xy 79.21164 -22.761053) (xy 79.21164 -22.706547) (xy 79.219397 -22.652596) (xy 79.234752 -22.600298)
			(xy 79.257394 -22.550717) (xy 79.286861 -22.504863) (xy 79.322554 -22.463669) (xy 79.363745 -22.427974)
			(xy 79.409598 -22.398504) (xy 79.459177 -22.37586) (xy 79.511474 -22.360501) (xy 79.565425 -22.352741)
			(xy 79.592678 -22.352254) (xy 79.618793 -22.352689) (xy 79.670533 -22.35983) (xy 79.720814 -22.373967)
			(xy 79.768694 -22.394835) (xy 79.813277 -22.422045) (xy 79.853729 -22.455085) (xy 79.871824 -22.47392)
			(xy 79.881243 -22.483397) (xy 79.903906 -22.497534) (xy 79.929458 -22.505316) (xy 79.956154 -22.506211)
			(xy 79.98217 -22.500157) (xy 80.005729 -22.487569) (xy 80.025221 -22.469307) (xy 80.032606 -22.458172)
			(xy 80.047649 -22.43498) (xy 80.083338 -22.392766) (xy 80.124745 -22.356144) (xy 80.171003 -22.325881)
			(xy 80.221144 -22.302609) (xy 80.274118 -22.286817) (xy 80.328817 -22.278834) (xy 80.356456 -22.27834)
			(xy 80.383714 -22.278704) (xy 80.437677 -22.286457) (xy 80.489987 -22.301811) (xy 80.539579 -22.324454)
			(xy 80.585443 -22.353924) (xy 80.626646 -22.389623) (xy 80.662349 -22.430822) (xy 80.691825 -22.476683)
			(xy 80.714474 -22.526272) (xy 80.729834 -22.57858) (xy 80.737593 -22.632542) (xy 80.737593 -22.687058)
			(xy 80.729834 -22.74102) (xy 80.714474 -22.793328) (xy 80.691825 -22.842917) (xy 80.662349 -22.888778)
			(xy 80.626646 -22.929977) (xy 80.585443 -22.965676) (xy 80.539579 -22.995146) (xy 80.489987 -23.017789)
			(xy 80.437677 -23.033143) (xy 80.383714 -23.040896) (xy 80.356456 -23.041356) (xy 80.33034 -23.040961)
			(xy 80.278598 -23.033812) (xy 80.228317 -23.019667) (xy 80.180437 -22.998791) (xy 80.135854 -22.971575)
			(xy 80.095404 -22.938528) (xy 80.07731 -22.91969) (xy 80.067857 -22.910248) (xy 80.045203 -22.896108)
			(xy 80.019659 -22.888321) (xy 79.992969 -22.887421) (xy 79.966958 -22.893469) (xy 79.943403 -22.90605)
			(xy 79.923913 -22.924307) (xy 79.916528 -22.935438) (xy 79.901532 -22.958663) (xy 79.865835 -23.000875)
			(xy 79.82442 -23.037495) (xy 79.778154 -23.067754) (xy 79.728005 -23.091021) (xy 79.675024 -23.106806)
			(xy 79.620319 -23.114781) (xy 79.592678 -23.11527) (xy 79.565425 -23.114859) (xy 79.511474 -23.107099)
			(xy 79.459177 -23.09174) (xy 79.409598 -23.069096) (xy 79.363745 -23.039626) (xy 79.322554 -23.003931)
			(xy 79.286861 -22.962737) (xy 79.257394 -22.916883) (xy 79.234752 -22.867302) (xy 79.219397 -22.815004)
			(xy 79.21164 -22.761053) (xy 75.357227 -22.761053) (xy 75.353817 -22.768328) (xy 75.323044 -22.814841)
			(xy 75.285827 -22.856378) (xy 75.242959 -22.892053) (xy 75.195353 -22.921107) (xy 75.144024 -22.942919)
			(xy 75.090067 -22.957025) (xy 75.03463 -22.963125) (xy 74.978896 -22.961088) (xy 74.924053 -22.950958)
			(xy 74.871269 -22.932951) (xy 74.821669 -22.90745) (xy 74.776311 -22.874999) (xy 74.736162 -22.83629)
			(xy 74.702076 -22.792147) (xy 74.67478 -22.743512) (xy 74.654857 -22.691421) (xy 74.642731 -22.636984)
			(xy 74.63866 -22.581362) (xy 70.7136 -22.581362) (xy 70.7136 -24.313896) (xy 77.804262 -24.313896)
			(xy 77.808333 -24.258274) (xy 77.820459 -24.203837) (xy 77.840382 -24.151746) (xy 77.867678 -24.103111)
			(xy 77.901764 -24.058968) (xy 77.941913 -24.020259) (xy 77.987271 -23.987808) (xy 78.036871 -23.962307)
			(xy 78.089655 -23.9443) (xy 78.144498 -23.93417) (xy 78.200232 -23.932133) (xy 78.255669 -23.938233)
			(xy 78.309626 -23.952339) (xy 78.360955 -23.974151) (xy 78.408561 -24.003205) (xy 78.451429 -24.03888)
			(xy 78.488646 -24.080417) (xy 78.519419 -24.12693) (xy 78.543091 -24.177427) (xy 78.559159 -24.230834)
			(xy 78.567279 -24.28601) (xy 78.567788 -24.313896) (xy 78.567279 -24.341782) (xy 78.559159 -24.396958)
			(xy 78.543091 -24.450365) (xy 78.519419 -24.500862) (xy 78.488646 -24.547375) (xy 78.45228 -24.587962)
			(xy 79.23606 -24.587962) (xy 79.240131 -24.53234) (xy 79.252257 -24.477903) (xy 79.27218 -24.425812)
			(xy 79.299476 -24.377177) (xy 79.333562 -24.333034) (xy 79.373711 -24.294325) (xy 79.419069 -24.261874)
			(xy 79.468669 -24.236373) (xy 79.521453 -24.218366) (xy 79.576296 -24.208236) (xy 79.63203 -24.206199)
			(xy 79.687467 -24.212299) (xy 79.741424 -24.226405) (xy 79.792753 -24.248217) (xy 79.840359 -24.277271)
			(xy 79.883227 -24.312946) (xy 79.920444 -24.354483) (xy 79.951217 -24.400996) (xy 79.974889 -24.451493)
			(xy 79.990957 -24.5049) (xy 79.999077 -24.560076) (xy 79.999586 -24.587962) (xy 79.999077 -24.615848)
			(xy 79.990957 -24.671024) (xy 79.974889 -24.724431) (xy 79.951217 -24.774928) (xy 79.920444 -24.821441)
			(xy 79.883227 -24.862978) (xy 79.840359 -24.898653) (xy 79.792753 -24.927707) (xy 79.741424 -24.949519)
			(xy 79.687467 -24.963625) (xy 79.63203 -24.969725) (xy 79.576296 -24.967688) (xy 79.521453 -24.957558)
			(xy 79.468669 -24.939551) (xy 79.419069 -24.91405) (xy 79.373711 -24.881599) (xy 79.333562 -24.84289)
			(xy 79.299476 -24.798747) (xy 79.27218 -24.750112) (xy 79.252257 -24.698021) (xy 79.240131 -24.643584)
			(xy 79.23606 -24.587962) (xy 78.45228 -24.587962) (xy 78.451429 -24.588912) (xy 78.408561 -24.624587)
			(xy 78.360955 -24.653641) (xy 78.309626 -24.675453) (xy 78.255669 -24.689559) (xy 78.200232 -24.695659)
			(xy 78.144498 -24.693622) (xy 78.089655 -24.683492) (xy 78.036871 -24.665485) (xy 77.987271 -24.639984)
			(xy 77.941913 -24.607533) (xy 77.901764 -24.568824) (xy 77.867678 -24.524681) (xy 77.840382 -24.476046)
			(xy 77.820459 -24.423955) (xy 77.808333 -24.369518) (xy 77.804262 -24.313896) (xy 70.7136 -24.313896)
			(xy 70.7136 -25.616408) (xy 70.02272 -26.307288) (xy 59.79414 -26.307288) (xy 59.403375 -26.698053)
			(xy 72.09964 -26.698053) (xy 72.09964 -26.643547) (xy 72.107397 -26.589596) (xy 72.122752 -26.537298)
			(xy 72.145394 -26.487717) (xy 72.174861 -26.441863) (xy 72.210554 -26.400669) (xy 72.251745 -26.364974)
			(xy 72.297598 -26.335504) (xy 72.347177 -26.31286) (xy 72.399474 -26.297501) (xy 72.453425 -26.289741)
			(xy 72.480678 -26.289254) (xy 72.507935 -26.289747) (xy 72.561894 -26.297511) (xy 72.6142 -26.312871)
			(xy 72.66379 -26.335513) (xy 72.709656 -26.364978) (xy 72.750865 -26.400666) (xy 72.786579 -26.441853)
			(xy 72.801734 -26.464514) (xy 72.810015 -26.476441) (xy 72.831951 -26.495445) (xy 72.858351 -26.5075)
			(xy 72.887078 -26.51163) (xy 72.915805 -26.5075) (xy 72.942205 -26.495445) (xy 72.964141 -26.476441)
			(xy 72.972422 -26.464514) (xy 72.987539 -26.441825) (xy 73.023252 -26.400629) (xy 73.064464 -26.364935)
			(xy 73.110336 -26.335469) (xy 73.159935 -26.312831) (xy 73.21225 -26.297482) (xy 73.266218 -26.289735)
			(xy 73.293478 -26.289254) (xy 73.320729 -26.289792) (xy 73.374677 -26.297545) (xy 73.426972 -26.312898)
			(xy 73.47655 -26.335537) (xy 73.522402 -26.365001) (xy 73.563593 -26.400692) (xy 73.599285 -26.441881)
			(xy 73.628752 -26.48773) (xy 73.651394 -26.537307) (xy 73.66675 -26.589601) (xy 73.674507 -26.643549)
			(xy 73.674507 -26.698051) (xy 73.66675 -26.751999) (xy 73.651394 -26.804293) (xy 73.628752 -26.85387)
			(xy 73.599285 -26.899719) (xy 73.563593 -26.940908) (xy 73.522402 -26.976599) (xy 73.47655 -27.006063)
			(xy 73.426972 -27.028702) (xy 73.374677 -27.044055) (xy 73.320729 -27.051808) (xy 73.293478 -27.05227)
			(xy 73.26622 -27.0518) (xy 73.212261 -27.044031) (xy 73.159954 -27.028666) (xy 73.110365 -27.00602)
			(xy 73.064499 -26.976552) (xy 73.023291 -26.940861) (xy 72.987577 -26.899672) (xy 72.972422 -26.87701)
			(xy 72.964141 -26.865083) (xy 72.942205 -26.846079) (xy 72.915805 -26.834024) (xy 72.887078 -26.829894)
			(xy 72.858351 -26.834024) (xy 72.831951 -26.846079) (xy 72.810015 -26.865083) (xy 72.801734 -26.87701)
			(xy 72.786588 -26.899679) (xy 72.750879 -26.940873) (xy 72.709671 -26.976568) (xy 72.663804 -27.006036)
			(xy 72.614211 -27.028677) (xy 72.5619 -27.044031) (xy 72.507937 -27.051786) (xy 72.480678 -27.05227)
			(xy 72.453425 -27.051859) (xy 72.399474 -27.044099) (xy 72.347177 -27.02874) (xy 72.297598 -27.006096)
			(xy 72.251745 -26.976626) (xy 72.210554 -26.940931) (xy 72.174861 -26.899737) (xy 72.145394 -26.853883)
			(xy 72.122752 -26.804302) (xy 72.107397 -26.752004) (xy 72.09964 -26.698053) (xy 59.403375 -26.698053)
			(xy 58.83148 -27.269948) (xy 58.83148 -28.331922) (xy 61.80277 -28.331922) (xy 61.806841 -28.2763)
			(xy 61.818967 -28.221863) (xy 61.83889 -28.169772) (xy 61.866186 -28.121137) (xy 61.900272 -28.076994)
			(xy 61.940421 -28.038285) (xy 61.985779 -28.005834) (xy 62.035379 -27.980333) (xy 62.088163 -27.962326)
			(xy 62.143006 -27.952196) (xy 62.19874 -27.950159) (xy 62.254177 -27.956259) (xy 62.308134 -27.970365)
			(xy 62.359463 -27.992177) (xy 62.407069 -28.021231) (xy 62.449937 -28.056906) (xy 62.487154 -28.098443)
			(xy 62.517927 -28.144956) (xy 62.541599 -28.195453) (xy 62.557667 -28.24886) (xy 62.565787 -28.304036)
			(xy 62.566296 -28.331922) (xy 62.565787 -28.359808) (xy 62.561368 -28.389834) (xy 64.102994 -28.389834)
			(xy 64.107065 -28.334212) (xy 64.119191 -28.279775) (xy 64.139114 -28.227684) (xy 64.16641 -28.179049)
			(xy 64.200496 -28.134906) (xy 64.240645 -28.096197) (xy 64.286003 -28.063746) (xy 64.335603 -28.038245)
			(xy 64.388387 -28.020238) (xy 64.44323 -28.010108) (xy 64.498964 -28.008071) (xy 64.554401 -28.014171)
			(xy 64.608358 -28.028277) (xy 64.659687 -28.050089) (xy 64.707293 -28.079143) (xy 64.750161 -28.114818)
			(xy 64.787378 -28.156355) (xy 64.818151 -28.202868) (xy 64.820305 -28.207462) (xy 66.166238 -28.207462)
			(xy 66.166725 -28.18014) (xy 66.17507 -28.126136) (xy 66.191558 -28.074039) (xy 66.215804 -28.025068)
			(xy 66.247239 -27.980371) (xy 66.265806 -27.96032) (xy 66.276244 -27.94873) (xy 66.290071 -27.920786)
			(xy 66.294822 -27.889972) (xy 66.290054 -27.859161) (xy 66.276212 -27.831225) (xy 66.265806 -27.819604)
			(xy 66.247204 -27.799581) (xy 66.215746 -27.754891) (xy 66.191495 -27.705914) (xy 66.175021 -27.653805)
			(xy 66.166712 -27.599788) (xy 66.166238 -27.572462) (xy 66.166736 -27.545813) (xy 66.174679 -27.493109)
			(xy 66.190389 -27.442179) (xy 66.213515 -27.394158) (xy 66.243539 -27.350121) (xy 66.279791 -27.31105)
			(xy 66.321462 -27.277819) (xy 66.36762 -27.25117) (xy 66.417234 -27.231698) (xy 66.469196 -27.219838)
			(xy 66.522346 -27.215855) (xy 66.575496 -27.219838) (xy 66.627458 -27.231698) (xy 66.677072 -27.25117)
			(xy 66.72323 -27.277819) (xy 66.764901 -27.31105) (xy 66.801153 -27.350121) (xy 66.831177 -27.394158)
			(xy 66.854303 -27.442179) (xy 66.870013 -27.493109) (xy 66.877956 -27.545813) (xy 66.878454 -27.572462)
			(xy 66.877922 -27.599782) (xy 66.869589 -27.653784) (xy 66.853111 -27.705881) (xy 66.828875 -27.754853)
			(xy 66.797449 -27.799552) (xy 66.778886 -27.819604) (xy 66.768524 -27.831256) (xy 66.75469 -27.859178)
			(xy 66.749926 -27.889972) (xy 66.754674 -27.92077) (xy 66.768492 -27.948699) (xy 66.778886 -27.96032)
			(xy 66.797498 -27.980334) (xy 66.828955 -28.025027) (xy 66.853205 -28.074005) (xy 66.869676 -28.126117)
			(xy 66.877982 -28.180135) (xy 66.878454 -28.207462) (xy 67.06616 -28.207462) (xy 67.066669 -28.180141)
			(xy 67.075011 -28.126139) (xy 67.091496 -28.074043) (xy 67.115736 -28.025072) (xy 67.147164 -27.980372)
			(xy 67.165728 -27.96032) (xy 67.176164 -27.948729) (xy 67.189988 -27.920785) (xy 67.194738 -27.889972)
			(xy 67.189971 -27.859162) (xy 67.176132 -27.831226) (xy 67.165728 -27.819604) (xy 67.14713 -27.799577)
			(xy 67.115671 -27.754889) (xy 67.091418 -27.705913) (xy 67.074943 -27.653804) (xy 67.066634 -27.599788)
			(xy 67.06616 -27.572462) (xy 67.066658 -27.545813) (xy 67.074601 -27.493109) (xy 67.090311 -27.442179)
			(xy 67.113437 -27.394158) (xy 67.143461 -27.350121) (xy 67.179713 -27.31105) (xy 67.221384 -27.277819)
			(xy 67.267542 -27.25117) (xy 67.317156 -27.231698) (xy 67.369118 -27.219838) (xy 67.422268 -27.215855)
			(xy 67.475418 -27.219838) (xy 67.52738 -27.231698) (xy 67.576994 -27.25117) (xy 67.623152 -27.277819)
			(xy 67.664823 -27.31105) (xy 67.701075 -27.350121) (xy 67.731099 -27.394158) (xy 67.754225 -27.442179)
			(xy 67.769935 -27.493109) (xy 67.777878 -27.545813) (xy 67.778376 -27.572462) (xy 67.777838 -27.599782)
			(xy 67.769505 -27.653783) (xy 67.753029 -27.70588) (xy 67.728794 -27.754852) (xy 67.69737 -27.799552)
			(xy 67.678808 -27.819604) (xy 67.668452 -27.831259) (xy 67.65463 -27.859181) (xy 67.649869 -27.889972)
			(xy 67.654613 -27.920766) (xy 67.668421 -27.948696) (xy 67.678808 -27.96032) (xy 67.697423 -27.980331)
			(xy 67.728879 -28.025025) (xy 67.753128 -28.074004) (xy 67.769599 -28.126116) (xy 67.777904 -28.180135)
			(xy 67.778376 -28.207462) (xy 67.966082 -28.207462) (xy 67.966585 -28.180141) (xy 67.974928 -28.126139)
			(xy 67.991414 -28.074042) (xy 68.015655 -28.025071) (xy 68.047085 -27.980372) (xy 68.06565 -27.96032)
			(xy 68.076084 -27.948728) (xy 68.089905 -27.920784) (xy 68.094654 -27.889972) (xy 68.089888 -27.859163)
			(xy 68.076052 -27.831226) (xy 68.06565 -27.819604) (xy 68.047056 -27.799574) (xy 68.015595 -27.754887)
			(xy 67.991341 -27.705912) (xy 67.974866 -27.653804) (xy 67.966556 -27.599788) (xy 67.966082 -27.572462)
			(xy 67.96658 -27.545813) (xy 67.974523 -27.493109) (xy 67.990233 -27.442179) (xy 68.013359 -27.394158)
			(xy 68.043383 -27.350121) (xy 68.079635 -27.31105) (xy 68.121306 -27.277819) (xy 68.167464 -27.25117)
			(xy 68.217078 -27.231698) (xy 68.26904 -27.219838) (xy 68.32219 -27.215855) (xy 68.37534 -27.219838)
			(xy 68.427302 -27.231698) (xy 68.476916 -27.25117) (xy 68.523074 -27.277819) (xy 68.564745 -27.31105)
			(xy 68.600997 -27.350121) (xy 68.631021 -27.394158) (xy 68.654147 -27.442179) (xy 68.669857 -27.493109)
			(xy 68.6778 -27.545813) (xy 68.678298 -27.572462) (xy 68.677754 -27.599782) (xy 68.669422 -27.653782)
			(xy 68.652946 -27.705879) (xy 68.628713 -27.754851) (xy 68.597291 -27.799551) (xy 68.57873 -27.819604)
			(xy 68.568372 -27.831258) (xy 68.554547 -27.85918) (xy 68.549785 -27.889972) (xy 68.55453 -27.920767)
			(xy 68.568341 -27.948697) (xy 68.57873 -27.96032) (xy 68.597349 -27.980328) (xy 68.628804 -28.025023)
			(xy 68.653051 -28.074003) (xy 68.669521 -28.126116) (xy 68.677826 -28.180135) (xy 68.678298 -28.207462)
			(xy 68.866258 -28.207462) (xy 68.86674 -28.18014) (xy 68.875085 -28.126136) (xy 68.891574 -28.074038)
			(xy 68.915821 -28.025067) (xy 68.947258 -27.98037) (xy 68.965826 -27.96032) (xy 68.976262 -27.948729)
			(xy 68.990086 -27.920785) (xy 68.994836 -27.889972) (xy 68.99007 -27.859162) (xy 68.976231 -27.831225)
			(xy 68.965826 -27.819604) (xy 68.947228 -27.799578) (xy 68.915768 -27.754889) (xy 68.891516 -27.705913)
			(xy 68.875041 -27.653804) (xy 68.866732 -27.599788) (xy 68.866258 -27.572462) (xy 68.866756 -27.545813)
			(xy 68.874699 -27.493109) (xy 68.890409 -27.442179) (xy 68.913535 -27.394158) (xy 68.943559 -27.350121)
			(xy 68.979811 -27.31105) (xy 69.021482 -27.277819) (xy 69.06764 -27.25117) (xy 69.117254 -27.231698)
			(xy 69.169216 -27.219838) (xy 69.222366 -27.215855) (xy 69.275516 -27.219838) (xy 69.327478 -27.231698)
			(xy 69.377092 -27.25117) (xy 69.42325 -27.277819) (xy 69.464921 -27.31105) (xy 69.501173 -27.350121)
			(xy 69.531197 -27.394158) (xy 69.554323 -27.442179) (xy 69.570033 -27.493109) (xy 69.577976 -27.545813)
			(xy 69.578474 -27.572462) (xy 69.577937 -27.599782) (xy 69.569604 -27.653783) (xy 69.553127 -27.70588)
			(xy 69.528893 -27.754852) (xy 69.497468 -27.799552) (xy 69.478906 -27.819604) (xy 69.468551 -27.831259)
			(xy 69.454728 -27.859181) (xy 69.449967 -27.889972) (xy 69.453879 -27.915362) (xy 70.95617 -27.915362)
			(xy 70.956679 -27.886623) (xy 70.965306 -27.829795) (xy 70.98236 -27.774904) (xy 71.007455 -27.723193)
			(xy 71.040022 -27.675831) (xy 71.059294 -27.654504) (xy 71.069401 -27.642999) (xy 71.082736 -27.615442)
			(xy 71.087312 -27.585172) (xy 71.082719 -27.554905) (xy 71.069369 -27.527355) (xy 71.059294 -27.51582)
			(xy 71.040015 -27.4945) (xy 71.007448 -27.447137) (xy 70.982356 -27.395424) (xy 70.965308 -27.340531)
			(xy 70.956689 -27.283702) (xy 70.95617 -27.254962) (xy 70.956656 -27.227711) (xy 70.964412 -27.173763)
			(xy 70.979767 -27.121468) (xy 71.002409 -27.071891) (xy 71.031875 -27.026041) (xy 71.067566 -26.98485)
			(xy 71.108757 -26.949159) (xy 71.154607 -26.919693) (xy 71.204184 -26.897051) (xy 71.256479 -26.881696)
			(xy 71.310427 -26.87394) (xy 71.364929 -26.87394) (xy 71.418877 -26.881696) (xy 71.471172 -26.897051)
			(xy 71.520749 -26.919693) (xy 71.566599 -26.949159) (xy 71.60779 -26.98485) (xy 71.643481 -27.026041)
			(xy 71.672947 -27.071891) (xy 71.695589 -27.121468) (xy 71.710944 -27.173763) (xy 71.7187 -27.227711)
			(xy 71.719186 -27.254962) (xy 71.718677 -27.283701) (xy 71.710047 -27.340528) (xy 71.692992 -27.395418)
			(xy 71.667898 -27.44713) (xy 71.635332 -27.494492) (xy 71.616062 -27.51582) (xy 71.606025 -27.527383)
			(xy 71.592674 -27.554918) (xy 71.588081 -27.585172) (xy 71.592658 -27.615429) (xy 71.605993 -27.642971)
			(xy 71.616062 -27.654504) (xy 71.635315 -27.675847) (xy 71.667883 -27.723204) (xy 71.692979 -27.774912)
			(xy 71.710034 -27.829799) (xy 71.718662 -27.886624) (xy 71.719186 -27.915362) (xy 71.7187 -27.942613)
			(xy 71.710944 -27.996561) (xy 71.695589 -28.048856) (xy 71.672947 -28.098433) (xy 71.643481 -28.144283)
			(xy 71.60779 -28.185474) (xy 71.566599 -28.221165) (xy 71.520749 -28.250631) (xy 71.471172 -28.273273)
			(xy 71.418877 -28.288628) (xy 71.364929 -28.296384) (xy 71.310427 -28.296384) (xy 71.256479 -28.288628)
			(xy 71.204184 -28.273273) (xy 71.154607 -28.250631) (xy 71.108757 -28.221165) (xy 71.067566 -28.185474)
			(xy 71.031875 -28.144283) (xy 71.002409 -28.098433) (xy 70.979767 -28.048856) (xy 70.964412 -27.996561)
			(xy 70.956656 -27.942613) (xy 70.95617 -27.915362) (xy 69.453879 -27.915362) (xy 69.454712 -27.920766)
			(xy 69.468519 -27.948696) (xy 69.478906 -27.96032) (xy 69.497521 -27.980331) (xy 69.528977 -28.025025)
			(xy 69.553226 -28.074004) (xy 69.569697 -28.126116) (xy 69.578002 -28.180135) (xy 69.578474 -28.207462)
			(xy 69.577976 -28.234111) (xy 69.570033 -28.286815) (xy 69.554323 -28.337745) (xy 69.531197 -28.385766)
			(xy 69.501173 -28.429803) (xy 69.464921 -28.468874) (xy 69.42325 -28.502105) (xy 69.377092 -28.528754)
			(xy 69.327478 -28.548226) (xy 69.275516 -28.560086) (xy 69.222366 -28.56407) (xy 69.169216 -28.560086)
			(xy 69.117254 -28.548226) (xy 69.06764 -28.528754) (xy 69.021482 -28.502105) (xy 68.979811 -28.468874)
			(xy 68.943559 -28.429803) (xy 68.913535 -28.385766) (xy 68.890409 -28.337745) (xy 68.874699 -28.286815)
			(xy 68.866756 -28.234111) (xy 68.866258 -28.207462) (xy 68.678298 -28.207462) (xy 68.6778 -28.234111)
			(xy 68.669857 -28.286815) (xy 68.654147 -28.337745) (xy 68.631021 -28.385766) (xy 68.600997 -28.429803)
			(xy 68.564745 -28.468874) (xy 68.523074 -28.502105) (xy 68.476916 -28.528754) (xy 68.427302 -28.548226)
			(xy 68.37534 -28.560086) (xy 68.32219 -28.56407) (xy 68.26904 -28.560086) (xy 68.217078 -28.548226)
			(xy 68.167464 -28.528754) (xy 68.121306 -28.502105) (xy 68.079635 -28.468874) (xy 68.043383 -28.429803)
			(xy 68.013359 -28.385766) (xy 67.990233 -28.337745) (xy 67.974523 -28.286815) (xy 67.96658 -28.234111)
			(xy 67.966082 -28.207462) (xy 67.778376 -28.207462) (xy 67.777878 -28.234111) (xy 67.769935 -28.286815)
			(xy 67.754225 -28.337745) (xy 67.731099 -28.385766) (xy 67.701075 -28.429803) (xy 67.664823 -28.468874)
			(xy 67.623152 -28.502105) (xy 67.576994 -28.528754) (xy 67.52738 -28.548226) (xy 67.475418 -28.560086)
			(xy 67.422268 -28.56407) (xy 67.369118 -28.560086) (xy 67.317156 -28.548226) (xy 67.267542 -28.528754)
			(xy 67.221384 -28.502105) (xy 67.179713 -28.468874) (xy 67.143461 -28.429803) (xy 67.113437 -28.385766)
			(xy 67.090311 -28.337745) (xy 67.074601 -28.286815) (xy 67.066658 -28.234111) (xy 67.06616 -28.207462)
			(xy 66.878454 -28.207462) (xy 66.877956 -28.234111) (xy 66.870013 -28.286815) (xy 66.854303 -28.337745)
			(xy 66.831177 -28.385766) (xy 66.801153 -28.429803) (xy 66.764901 -28.468874) (xy 66.72323 -28.502105)
			(xy 66.677072 -28.528754) (xy 66.627458 -28.548226) (xy 66.575496 -28.560086) (xy 66.522346 -28.56407)
			(xy 66.469196 -28.560086) (xy 66.417234 -28.548226) (xy 66.36762 -28.528754) (xy 66.321462 -28.502105)
			(xy 66.279791 -28.468874) (xy 66.243539 -28.429803) (xy 66.213515 -28.385766) (xy 66.190389 -28.337745)
			(xy 66.174679 -28.286815) (xy 66.166736 -28.234111) (xy 66.166238 -28.207462) (xy 64.820305 -28.207462)
			(xy 64.841823 -28.253365) (xy 64.857891 -28.306772) (xy 64.866011 -28.361948) (xy 64.86652 -28.389834)
			(xy 64.866011 -28.41772) (xy 64.857891 -28.472896) (xy 64.841823 -28.526303) (xy 64.818151 -28.5768)
			(xy 64.787378 -28.623313) (xy 64.761709 -28.651962) (xy 76.118974 -28.651962) (xy 76.11943 -28.625646)
			(xy 76.126651 -28.573513) (xy 76.140964 -28.522865) (xy 76.162098 -28.474663) (xy 76.189652 -28.429821)
			(xy 76.223104 -28.389189) (xy 76.242164 -28.371038) (xy 76.252225 -28.361264) (xy 76.266926 -28.337381)
			(xy 76.274562 -28.310397) (xy 76.274555 -28.282352) (xy 76.266905 -28.255371) (xy 76.252193 -28.231497)
			(xy 76.242164 -28.221686) (xy 76.22309 -28.203546) (xy 76.189609 -28.162928) (xy 76.162036 -28.118089)
			(xy 76.140896 -28.069882) (xy 76.126591 -28.019225) (xy 76.119394 -27.967081) (xy 76.118974 -27.940762)
			(xy 76.119492 -27.913189) (xy 76.127435 -27.858619) (xy 76.14315 -27.805761) (xy 76.16631 -27.755715)
			(xy 76.196433 -27.709524) (xy 76.232891 -27.66815) (xy 76.253594 -27.649932) (xy 76.264529 -27.640072)
			(xy 76.280601 -27.615411) (xy 76.28898 -27.587193) (xy 76.288973 -27.557758) (xy 76.28058 -27.529544)
			(xy 76.264497 -27.504891) (xy 76.253594 -27.494992) (xy 76.232875 -27.47679) (xy 76.196405 -27.435419)
			(xy 76.166274 -27.389227) (xy 76.14311 -27.339177) (xy 76.127395 -27.286313) (xy 76.119458 -27.231737)
			(xy 76.118974 -27.204162) (xy 76.11946 -27.176911) (xy 76.127216 -27.122963) (xy 76.142571 -27.070668)
			(xy 76.165213 -27.021091) (xy 76.194679 -26.975241) (xy 76.23037 -26.93405) (xy 76.271561 -26.898359)
			(xy 76.317411 -26.868893) (xy 76.366988 -26.846251) (xy 76.419283 -26.830896) (xy 76.473231 -26.82314)
			(xy 76.527733 -26.82314) (xy 76.581681 -26.830896) (xy 76.633976 -26.846251) (xy 76.683553 -26.868893)
			(xy 76.729403 -26.898359) (xy 76.770594 -26.93405) (xy 76.806285 -26.975241) (xy 76.835751 -27.021091)
			(xy 76.858393 -27.070668) (xy 76.873748 -27.122963) (xy 76.881504 -27.176911) (xy 76.88199 -27.204162)
			(xy 76.881502 -27.231736) (xy 76.873554 -27.286308) (xy 76.857834 -27.339167) (xy 76.834668 -27.389213)
			(xy 76.804539 -27.435404) (xy 76.768076 -27.476776) (xy 76.74737 -27.494992) (xy 76.736514 -27.504931)
			(xy 76.720445 -27.529571) (xy 76.71206 -27.557767) (xy 76.712053 -27.587184) (xy 76.720425 -27.615384)
			(xy 76.736481 -27.640032) (xy 76.74737 -27.649932) (xy 76.768094 -27.66813) (xy 76.804564 -27.7095)
			(xy 76.834696 -27.755693) (xy 76.85786 -27.805744) (xy 76.873573 -27.858609) (xy 76.881508 -27.913186)
			(xy 76.88199 -27.940762) (xy 76.881561 -27.967079) (xy 76.874337 -28.019214) (xy 76.860019 -28.069863)
			(xy 76.83888 -28.118065) (xy 76.81132 -28.162906) (xy 76.777862 -28.203537) (xy 76.7588 -28.221686)
			(xy 76.748818 -28.231534) (xy 76.734119 -28.255397) (xy 76.726476 -28.282361) (xy 76.726469 -28.310388)
			(xy 76.734098 -28.337356) (xy 76.748785 -28.361226) (xy 76.7588 -28.371038) (xy 76.777898 -28.389154)
			(xy 76.811374 -28.429779) (xy 76.838942 -28.474623) (xy 76.860078 -28.522834) (xy 76.874378 -28.573495)
			(xy 76.881572 -28.625641) (xy 76.88199 -28.651962) (xy 78.62697 -28.651962) (xy 78.627428 -28.625646)
			(xy 78.634648 -28.573513) (xy 78.648961 -28.522865) (xy 78.670095 -28.474663) (xy 78.697649 -28.429821)
			(xy 78.731101 -28.389189) (xy 78.75016 -28.371038) (xy 78.760222 -28.361264) (xy 78.774923 -28.337381)
			(xy 78.782559 -28.310397) (xy 78.782552 -28.282352) (xy 78.774902 -28.255371) (xy 78.760189 -28.231496)
			(xy 78.75016 -28.221686) (xy 78.731085 -28.203546) (xy 78.697605 -28.162928) (xy 78.670032 -28.118089)
			(xy 78.648892 -28.069883) (xy 78.634587 -28.019225) (xy 78.62739 -27.967081) (xy 78.62697 -27.940762)
			(xy 78.627489 -27.913189) (xy 78.635432 -27.858619) (xy 78.651147 -27.805761) (xy 78.674307 -27.755715)
			(xy 78.70443 -27.709524) (xy 78.740888 -27.66815) (xy 78.76159 -27.649932) (xy 78.772526 -27.640072)
			(xy 78.788598 -27.615411) (xy 78.796978 -27.587193) (xy 78.796971 -27.557758) (xy 78.788577 -27.529544)
			(xy 78.772493 -27.504891) (xy 78.76159 -27.494992) (xy 78.74087 -27.476791) (xy 78.704401 -27.43542)
			(xy 78.67427 -27.389228) (xy 78.651106 -27.339178) (xy 78.635391 -27.286314) (xy 78.627454 -27.231737)
			(xy 78.62697 -27.204162) (xy 78.627456 -27.176911) (xy 78.635212 -27.122963) (xy 78.650567 -27.070668)
			(xy 78.673209 -27.021091) (xy 78.702675 -26.975241) (xy 78.738366 -26.93405) (xy 78.779557 -26.898359)
			(xy 78.825407 -26.868893) (xy 78.874984 -26.846251) (xy 78.927279 -26.830896) (xy 78.981227 -26.82314)
			(xy 79.035729 -26.82314) (xy 79.089677 -26.830896) (xy 79.141972 -26.846251) (xy 79.191549 -26.868893)
			(xy 79.237399 -26.898359) (xy 79.27859 -26.93405) (xy 79.314281 -26.975241) (xy 79.343747 -27.021091)
			(xy 79.366389 -27.070668) (xy 79.381744 -27.122963) (xy 79.3895 -27.176911) (xy 79.389986 -27.204162)
			(xy 79.389499 -27.231736) (xy 79.381552 -27.286308) (xy 79.365831 -27.339168) (xy 79.342665 -27.389214)
			(xy 79.312536 -27.435404) (xy 79.276072 -27.476776) (xy 79.255366 -27.494992) (xy 79.24451 -27.504931)
			(xy 79.228442 -27.529571) (xy 79.220058 -27.557767) (xy 79.22005 -27.587184) (xy 79.228422 -27.615384)
			(xy 79.244478 -27.640032) (xy 79.255366 -27.649932) (xy 79.276089 -27.66813) (xy 79.31256 -27.709501)
			(xy 79.342691 -27.755693) (xy 79.365855 -27.805744) (xy 79.381569 -27.858609) (xy 79.389504 -27.913186)
			(xy 79.389986 -27.940762) (xy 79.389559 -27.967079) (xy 79.382334 -28.019214) (xy 79.368016 -28.069863)
			(xy 79.346877 -28.118065) (xy 79.319317 -28.162906) (xy 79.285858 -28.203537) (xy 79.266796 -28.221686)
			(xy 79.256814 -28.231534) (xy 79.242116 -28.255397) (xy 79.234473 -28.282361) (xy 79.234466 -28.310388)
			(xy 79.242095 -28.337356) (xy 79.256782 -28.361226) (xy 79.266796 -28.371038) (xy 79.285893 -28.389155)
			(xy 79.31937 -28.429779) (xy 79.346938 -28.474623) (xy 79.368073 -28.522834) (xy 79.382374 -28.573495)
			(xy 79.389568 -28.625641) (xy 79.389986 -28.651962) (xy 79.3895 -28.679213) (xy 79.381744 -28.733161)
			(xy 79.366389 -28.785456) (xy 79.343747 -28.835033) (xy 79.314281 -28.880883) (xy 79.27859 -28.922074)
			(xy 79.237399 -28.957765) (xy 79.191549 -28.987231) (xy 79.141972 -29.009873) (xy 79.089677 -29.025228)
			(xy 79.035729 -29.032984) (xy 78.981227 -29.032984) (xy 78.927279 -29.025228) (xy 78.874984 -29.009873)
			(xy 78.825407 -28.987231) (xy 78.779557 -28.957765) (xy 78.738366 -28.922074) (xy 78.702675 -28.880883)
			(xy 78.673209 -28.835033) (xy 78.650567 -28.785456) (xy 78.635212 -28.733161) (xy 78.627456 -28.679213)
			(xy 78.62697 -28.651962) (xy 76.88199 -28.651962) (xy 76.881504 -28.679213) (xy 76.873748 -28.733161)
			(xy 76.858393 -28.785456) (xy 76.835751 -28.835033) (xy 76.806285 -28.880883) (xy 76.770594 -28.922074)
			(xy 76.729403 -28.957765) (xy 76.683553 -28.987231) (xy 76.633976 -29.009873) (xy 76.581681 -29.025228)
			(xy 76.527733 -29.032984) (xy 76.473231 -29.032984) (xy 76.419283 -29.025228) (xy 76.366988 -29.009873)
			(xy 76.317411 -28.987231) (xy 76.271561 -28.957765) (xy 76.23037 -28.922074) (xy 76.194679 -28.880883)
			(xy 76.165213 -28.835033) (xy 76.142571 -28.785456) (xy 76.127216 -28.733161) (xy 76.11946 -28.679213)
			(xy 76.118974 -28.651962) (xy 64.761709 -28.651962) (xy 64.750161 -28.66485) (xy 64.707293 -28.700525)
			(xy 64.659687 -28.729579) (xy 64.608358 -28.751391) (xy 64.554401 -28.765497) (xy 64.498964 -28.771597)
			(xy 64.44323 -28.76956) (xy 64.388387 -28.75943) (xy 64.335603 -28.741423) (xy 64.286003 -28.715922)
			(xy 64.240645 -28.683471) (xy 64.200496 -28.644762) (xy 64.16641 -28.600619) (xy 64.139114 -28.551984)
			(xy 64.119191 -28.499893) (xy 64.107065 -28.445456) (xy 64.102994 -28.389834) (xy 62.561368 -28.389834)
			(xy 62.557667 -28.414984) (xy 62.541599 -28.468391) (xy 62.517927 -28.518888) (xy 62.487154 -28.565401)
			(xy 62.449937 -28.606938) (xy 62.407069 -28.642613) (xy 62.359463 -28.671667) (xy 62.308134 -28.693479)
			(xy 62.254177 -28.707585) (xy 62.19874 -28.713685) (xy 62.143006 -28.711648) (xy 62.088163 -28.701518)
			(xy 62.035379 -28.683511) (xy 61.985779 -28.65801) (xy 61.940421 -28.625559) (xy 61.900272 -28.58685)
			(xy 61.866186 -28.542707) (xy 61.83889 -28.494072) (xy 61.818967 -28.441981) (xy 61.806841 -28.387544)
			(xy 61.80277 -28.331922) (xy 58.83148 -28.331922) (xy 58.83148 -29.347922) (xy 61.80277 -29.347922)
			(xy 61.806841 -29.2923) (xy 61.818967 -29.237863) (xy 61.83889 -29.185772) (xy 61.866186 -29.137137)
			(xy 61.900272 -29.092994) (xy 61.940421 -29.054285) (xy 61.985779 -29.021834) (xy 62.035379 -28.996333)
			(xy 62.088163 -28.978326) (xy 62.143006 -28.968196) (xy 62.19874 -28.966159) (xy 62.254177 -28.972259)
			(xy 62.308134 -28.986365) (xy 62.359463 -29.008177) (xy 62.407069 -29.037231) (xy 62.449937 -29.072906)
			(xy 62.487154 -29.114443) (xy 62.517927 -29.160956) (xy 62.541599 -29.211453) (xy 62.557667 -29.26486)
			(xy 62.565787 -29.320036) (xy 62.566296 -29.347922) (xy 62.565787 -29.375808) (xy 62.5632 -29.393388)
			(xy 64.111122 -29.393388) (xy 64.115193 -29.337766) (xy 64.127319 -29.283329) (xy 64.147242 -29.231238)
			(xy 64.174538 -29.182603) (xy 64.208624 -29.13846) (xy 64.248773 -29.099751) (xy 64.294131 -29.0673)
			(xy 64.343731 -29.041799) (xy 64.396515 -29.023792) (xy 64.451358 -29.013662) (xy 64.507092 -29.011625)
			(xy 64.562529 -29.017725) (xy 64.616486 -29.031831) (xy 64.667815 -29.053643) (xy 64.715421 -29.082697)
			(xy 64.758289 -29.118372) (xy 64.795506 -29.159909) (xy 64.826279 -29.206422) (xy 64.849951 -29.256919)
			(xy 64.866019 -29.310326) (xy 64.874139 -29.365502) (xy 64.874594 -29.390453) (xy 71.46464 -29.390453)
			(xy 71.46464 -29.335947) (xy 71.472397 -29.281996) (xy 71.487752 -29.229698) (xy 71.510394 -29.180117)
			(xy 71.539861 -29.134263) (xy 71.575554 -29.093069) (xy 71.616745 -29.057374) (xy 71.662598 -29.027904)
			(xy 71.712177 -29.00526) (xy 71.764474 -28.989901) (xy 71.818425 -28.982141) (xy 71.845678 -28.981654)
			(xy 71.874595 -28.982168) (xy 71.931768 -28.990895) (xy 71.986967 -29.008152) (xy 72.03893 -29.033545)
			(xy 72.086463 -29.06649) (xy 72.128479 -29.106233) (xy 72.146668 -29.12872) (xy 72.156565 -29.140525)
			(xy 72.181889 -29.158044) (xy 72.211282 -29.16722) (xy 72.242074 -29.16722) (xy 72.271467 -29.158044)
			(xy 72.296791 -29.140525) (xy 72.306688 -29.12872) (xy 72.324891 -29.106246) (xy 72.366908 -29.06651)
			(xy 72.41444 -29.033569) (xy 72.466399 -29.008179) (xy 72.521595 -28.990921) (xy 72.578763 -28.98219)
			(xy 72.607678 -28.981654) (xy 72.634929 -28.982192) (xy 72.688877 -28.989945) (xy 72.741172 -29.005298)
			(xy 72.79075 -29.027937) (xy 72.836602 -29.057401) (xy 72.877793 -29.093092) (xy 72.913485 -29.134281)
			(xy 72.942952 -29.18013) (xy 72.965594 -29.229707) (xy 72.98095 -29.282001) (xy 72.988707 -29.335949)
			(xy 72.988707 -29.390451) (xy 72.98095 -29.444399) (xy 72.965594 -29.496693) (xy 72.942952 -29.54627)
			(xy 72.913485 -29.592119) (xy 72.877793 -29.633308) (xy 72.836602 -29.668999) (xy 72.79075 -29.698463)
			(xy 72.741172 -29.721102) (xy 72.688877 -29.736455) (xy 72.634929 -29.744208) (xy 72.607678 -29.74467)
			(xy 72.578763 -29.744107) (xy 72.521593 -29.735389) (xy 72.466395 -29.71814) (xy 72.414433 -29.692757)
			(xy 72.366898 -29.659821) (xy 72.324879 -29.620086) (xy 72.306688 -29.597604) (xy 72.296791 -29.585799)
			(xy 72.271467 -29.56828) (xy 72.242074 -29.559104) (xy 72.211282 -29.559104) (xy 72.181889 -29.56828)
			(xy 72.156565 -29.585799) (xy 72.146668 -29.597604) (xy 72.128496 -29.620104) (xy 72.086472 -29.659838)
			(xy 72.038933 -29.692775) (xy 71.986968 -29.71816) (xy 71.931767 -29.735413) (xy 71.874595 -29.744137)
			(xy 71.845678 -29.74467) (xy 71.818425 -29.744259) (xy 71.764474 -29.736499) (xy 71.712177 -29.72114)
			(xy 71.662598 -29.698496) (xy 71.616745 -29.669026) (xy 71.575554 -29.633331) (xy 71.539861 -29.592137)
			(xy 71.510394 -29.546283) (xy 71.487752 -29.496702) (xy 71.472397 -29.444404) (xy 71.46464 -29.390453)
			(xy 64.874594 -29.390453) (xy 64.874648 -29.393388) (xy 64.874139 -29.421274) (xy 64.866019 -29.47645)
			(xy 64.849951 -29.529857) (xy 64.826279 -29.580354) (xy 64.795506 -29.626867) (xy 64.758289 -29.668404)
			(xy 64.715421 -29.704079) (xy 64.667815 -29.733133) (xy 64.616486 -29.754945) (xy 64.562529 -29.769051)
			(xy 64.507092 -29.775151) (xy 64.451358 -29.773114) (xy 64.396515 -29.762984) (xy 64.343731 -29.744977)
			(xy 64.294131 -29.719476) (xy 64.248773 -29.687025) (xy 64.208624 -29.648316) (xy 64.174538 -29.604173)
			(xy 64.147242 -29.555538) (xy 64.127319 -29.503447) (xy 64.115193 -29.44901) (xy 64.111122 -29.393388)
			(xy 62.5632 -29.393388) (xy 62.557667 -29.430984) (xy 62.541599 -29.484391) (xy 62.517927 -29.534888)
			(xy 62.487154 -29.581401) (xy 62.449937 -29.622938) (xy 62.407069 -29.658613) (xy 62.359463 -29.687667)
			(xy 62.308134 -29.709479) (xy 62.254177 -29.723585) (xy 62.19874 -29.729685) (xy 62.143006 -29.727648)
			(xy 62.088163 -29.717518) (xy 62.035379 -29.699511) (xy 61.985779 -29.67401) (xy 61.940421 -29.641559)
			(xy 61.900272 -29.60285) (xy 61.866186 -29.558707) (xy 61.83889 -29.510072) (xy 61.818967 -29.457981)
			(xy 61.806841 -29.403544) (xy 61.80277 -29.347922) (xy 58.83148 -29.347922) (xy 58.83148 -30.714188)
			(xy 66.559682 -30.714188) (xy 66.563753 -30.658566) (xy 66.575879 -30.604129) (xy 66.595802 -30.552038)
			(xy 66.623098 -30.503403) (xy 66.657184 -30.45926) (xy 66.697333 -30.420551) (xy 66.742691 -30.3881)
			(xy 66.792291 -30.362599) (xy 66.845075 -30.344592) (xy 66.899918 -30.334462) (xy 66.955652 -30.332425)
			(xy 67.011089 -30.338525) (xy 67.065046 -30.352631) (xy 67.116375 -30.374443) (xy 67.163981 -30.403497)
			(xy 67.206849 -30.439172) (xy 67.244066 -30.480709) (xy 67.274839 -30.527222) (xy 67.298511 -30.577719)
			(xy 67.314579 -30.631126) (xy 67.322699 -30.686302) (xy 67.323208 -30.714188) (xy 67.322699 -30.742074)
			(xy 67.320448 -30.757368) (xy 67.992496 -30.757368) (xy 67.996567 -30.701746) (xy 68.008693 -30.647309)
			(xy 68.028616 -30.595218) (xy 68.055912 -30.546583) (xy 68.089998 -30.50244) (xy 68.130147 -30.463731)
			(xy 68.175505 -30.43128) (xy 68.225105 -30.405779) (xy 68.277889 -30.387772) (xy 68.332732 -30.377642)
			(xy 68.388466 -30.375605) (xy 68.443903 -30.381705) (xy 68.49786 -30.395811) (xy 68.549189 -30.417623)
			(xy 68.596795 -30.446677) (xy 68.639663 -30.482352) (xy 68.67688 -30.523889) (xy 68.689014 -30.54223)
			(xy 69.67042 -30.54223) (xy 69.674491 -30.486608) (xy 69.686617 -30.432171) (xy 69.70654 -30.38008)
			(xy 69.733836 -30.331445) (xy 69.767922 -30.287302) (xy 69.808071 -30.248593) (xy 69.853429 -30.216142)
			(xy 69.903029 -30.190641) (xy 69.955813 -30.172634) (xy 70.010656 -30.162504) (xy 70.06639 -30.160467)
			(xy 70.121827 -30.166567) (xy 70.175784 -30.180673) (xy 70.227113 -30.202485) (xy 70.274719 -30.231539)
			(xy 70.317587 -30.267214) (xy 70.354804 -30.308751) (xy 70.385577 -30.355264) (xy 70.409249 -30.405761)
			(xy 70.425317 -30.459168) (xy 70.433437 -30.514344) (xy 70.433946 -30.54223) (xy 70.433437 -30.570116)
			(xy 70.425317 -30.625292) (xy 70.409249 -30.678699) (xy 70.385577 -30.729196) (xy 70.354804 -30.775709)
			(xy 70.317587 -30.817246) (xy 70.274719 -30.852921) (xy 70.227113 -30.881975) (xy 70.175784 -30.903787)
			(xy 70.121827 -30.917893) (xy 70.06639 -30.923993) (xy 70.010656 -30.921956) (xy 69.955813 -30.911826)
			(xy 69.903029 -30.893819) (xy 69.853429 -30.868318) (xy 69.808071 -30.835867) (xy 69.767922 -30.797158)
			(xy 69.733836 -30.753015) (xy 69.70654 -30.70438) (xy 69.686617 -30.652289) (xy 69.674491 -30.597852)
			(xy 69.67042 -30.54223) (xy 68.689014 -30.54223) (xy 68.707653 -30.570402) (xy 68.731325 -30.620899)
			(xy 68.747393 -30.674306) (xy 68.755513 -30.729482) (xy 68.756022 -30.757368) (xy 68.755513 -30.785254)
			(xy 68.747393 -30.84043) (xy 68.731325 -30.893837) (xy 68.707653 -30.944334) (xy 68.67688 -30.990847)
			(xy 68.639663 -31.032384) (xy 68.596795 -31.068059) (xy 68.549189 -31.097113) (xy 68.49786 -31.118925)
			(xy 68.443903 -31.133031) (xy 68.388466 -31.139131) (xy 68.332732 -31.137094) (xy 68.277889 -31.126964)
			(xy 68.225105 -31.108957) (xy 68.175505 -31.083456) (xy 68.130147 -31.051005) (xy 68.089998 -31.012296)
			(xy 68.055912 -30.968153) (xy 68.028616 -30.919518) (xy 68.008693 -30.867427) (xy 67.996567 -30.81299)
			(xy 67.992496 -30.757368) (xy 67.320448 -30.757368) (xy 67.314579 -30.79725) (xy 67.298511 -30.850657)
			(xy 67.274839 -30.901154) (xy 67.244066 -30.947667) (xy 67.206849 -30.989204) (xy 67.163981 -31.024879)
			(xy 67.116375 -31.053933) (xy 67.065046 -31.075745) (xy 67.011089 -31.089851) (xy 66.955652 -31.095951)
			(xy 66.899918 -31.093914) (xy 66.845075 -31.083784) (xy 66.792291 -31.065777) (xy 66.742691 -31.040276)
			(xy 66.697333 -31.007825) (xy 66.657184 -30.969116) (xy 66.623098 -30.924973) (xy 66.595802 -30.876338)
			(xy 66.575879 -30.824247) (xy 66.563753 -30.76981) (xy 66.559682 -30.714188) (xy 58.83148 -30.714188)
			(xy 58.83148 -31.874968) (xy 67.159122 -31.874968) (xy 67.163193 -31.819346) (xy 67.175319 -31.764909)
			(xy 67.195242 -31.712818) (xy 67.222538 -31.664183) (xy 67.256624 -31.62004) (xy 67.296773 -31.581331)
			(xy 67.342131 -31.54888) (xy 67.391731 -31.523379) (xy 67.444515 -31.505372) (xy 67.499358 -31.495242)
			(xy 67.555092 -31.493205) (xy 67.610529 -31.499305) (xy 67.664486 -31.513411) (xy 67.715815 -31.535223)
			(xy 67.763421 -31.564277) (xy 67.806289 -31.599952) (xy 67.843506 -31.641489) (xy 67.874279 -31.688002)
			(xy 67.897951 -31.738499) (xy 67.914019 -31.791906) (xy 67.922139 -31.847082) (xy 67.922648 -31.874968)
			(xy 67.922139 -31.902854) (xy 67.914019 -31.95803) (xy 67.897951 -32.011437) (xy 67.874279 -32.061934)
			(xy 67.843506 -32.108447) (xy 67.806289 -32.149984) (xy 67.763421 -32.185659) (xy 67.715815 -32.214713)
			(xy 67.664486 -32.236525) (xy 67.610529 -32.250631) (xy 67.555092 -32.256731) (xy 67.499358 -32.254694)
			(xy 67.444515 -32.244564) (xy 67.391731 -32.226557) (xy 67.342131 -32.201056) (xy 67.296773 -32.168605)
			(xy 67.256624 -32.129896) (xy 67.222538 -32.085753) (xy 67.195242 -32.037118) (xy 67.175319 -31.985027)
			(xy 67.163193 -31.93059) (xy 67.159122 -31.874968) (xy 58.83148 -31.874968) (xy 58.83148 -32.944562)
			(xy 60.14542 -32.944562) (xy 60.149491 -32.88894) (xy 60.161617 -32.834503) (xy 60.18154 -32.782412)
			(xy 60.208836 -32.733777) (xy 60.242922 -32.689634) (xy 60.283071 -32.650925) (xy 60.328429 -32.618474)
			(xy 60.378029 -32.592973) (xy 60.430813 -32.574966) (xy 60.485656 -32.564836) (xy 60.54139 -32.562799)
			(xy 60.596827 -32.568899) (xy 60.650784 -32.583005) (xy 60.702113 -32.604817) (xy 60.749719 -32.633871)
			(xy 60.792587 -32.669546) (xy 60.829804 -32.711083) (xy 60.860577 -32.757596) (xy 60.884249 -32.808093)
			(xy 60.900317 -32.8615) (xy 60.908392 -32.916368) (xy 69.67042 -32.916368) (xy 69.674491 -32.860746)
			(xy 69.686617 -32.806309) (xy 69.70654 -32.754218) (xy 69.733836 -32.705583) (xy 69.767922 -32.66144)
			(xy 69.808071 -32.622731) (xy 69.853429 -32.59028) (xy 69.903029 -32.564779) (xy 69.955813 -32.546772)
			(xy 70.010656 -32.536642) (xy 70.06639 -32.534605) (xy 70.121827 -32.540705) (xy 70.175784 -32.554811)
			(xy 70.227113 -32.576623) (xy 70.274719 -32.605677) (xy 70.317587 -32.641352) (xy 70.354804 -32.682889)
			(xy 70.385577 -32.729402) (xy 70.409249 -32.779899) (xy 70.425317 -32.833306) (xy 70.433437 -32.888482)
			(xy 70.433946 -32.916368) (xy 70.433437 -32.944254) (xy 70.425317 -32.99943) (xy 70.409249 -33.052837)
			(xy 70.385577 -33.103334) (xy 70.354804 -33.149847) (xy 70.317587 -33.191384) (xy 70.274719 -33.227059)
			(xy 70.227113 -33.256113) (xy 70.175784 -33.277925) (xy 70.121827 -33.292031) (xy 70.06639 -33.298131)
			(xy 70.010656 -33.296094) (xy 69.955813 -33.285964) (xy 69.903029 -33.267957) (xy 69.853429 -33.242456)
			(xy 69.808071 -33.210005) (xy 69.767922 -33.171296) (xy 69.733836 -33.127153) (xy 69.70654 -33.078518)
			(xy 69.686617 -33.026427) (xy 69.674491 -32.97199) (xy 69.67042 -32.916368) (xy 60.908392 -32.916368)
			(xy 60.908437 -32.916676) (xy 60.908946 -32.944562) (xy 60.908437 -32.972448) (xy 60.900317 -33.027624)
			(xy 60.884249 -33.081031) (xy 60.860577 -33.131528) (xy 60.829804 -33.178041) (xy 60.792587 -33.219578)
			(xy 60.749719 -33.255253) (xy 60.702113 -33.284307) (xy 60.650784 -33.306119) (xy 60.596827 -33.320225)
			(xy 60.54139 -33.326325) (xy 60.485656 -33.324288) (xy 60.430813 -33.314158) (xy 60.378029 -33.296151)
			(xy 60.328429 -33.27065) (xy 60.283071 -33.238199) (xy 60.242922 -33.19949) (xy 60.208836 -33.155347)
			(xy 60.18154 -33.106712) (xy 60.161617 -33.054621) (xy 60.149491 -33.000184) (xy 60.14542 -32.944562)
			(xy 58.83148 -32.944562) (xy 58.83148 -33.696148) (xy 59.265312 -34.12998) (xy 80.013048 -34.12998)
		)
		(stroke
			(width 0)
			(type solid)
		)
		(fill yes)
		(layer "In6.Cu")
		(net "GND")
	)
	(gr_poly
		(pts
			(xy 369.844828 -261.78383) (xy 369.865289 -261.770684) (xy 369.909255 -261.749898) (xy 369.955794 -261.735785)
			(xy 370.0039 -261.728651) (xy 370.052532 -261.728651) (xy 370.100638 -261.735785) (xy 370.147177 -261.749898)
			(xy 370.191143 -261.770684) (xy 370.211604 -261.78383) (xy 370.784374 -261.78383) (xy 370.804837 -261.770689)
			(xy 370.848804 -261.74991) (xy 370.895343 -261.7358) (xy 370.943447 -261.728666) (xy 370.967762 -261.728204)
			(xy 370.990379 -261.728572) (xy 371.035191 -261.734736) (xy 371.078743 -261.746953) (xy 371.120223 -261.764996)
			(xy 371.13972 -261.776464) (xy 371.151912 -261.78383) (xy 371.291358 -261.78383) (xy 371.355112 -261.720076)
			(xy 371.364993 -261.709497) (xy 371.378907 -261.684128) (xy 371.385131 -261.655872) (xy 371.383162 -261.627005)
			(xy 371.373161 -261.599854) (xy 371.355933 -261.576609) (xy 371.332866 -261.559142) (xy 371.319552 -261.553452)
			(xy 371.296454 -261.544127) (xy 371.253135 -261.519541) (xy 371.213995 -261.488732) (xy 371.179922 -261.452399)
			(xy 371.151688 -261.411364) (xy 371.129931 -261.366557) (xy 371.115144 -261.318992) (xy 371.107663 -261.269747)
			(xy 371.107208 -261.244842) (xy 371.107688 -261.218869) (xy 371.115807 -261.167563) (xy 371.131853 -261.118158)
			(xy 371.15543 -261.071872) (xy 371.185957 -261.029844) (xy 371.222683 -260.993109) (xy 371.264704 -260.962572)
			(xy 371.310984 -260.938984) (xy 371.360385 -260.922926) (xy 371.41169 -260.914794) (xy 371.437662 -260.914388)
			(xy 371.463797 -260.914888) (xy 371.515414 -260.923122) (xy 371.565093 -260.939376) (xy 371.611595 -260.963245)
			(xy 371.653762 -260.994133) (xy 371.690543 -261.031271) (xy 371.721023 -261.073735) (xy 371.744441 -261.120465)
			(xy 371.760214 -261.170298) (xy 371.76456 -261.196074) (xy 371.7671 -261.212584) (xy 371.814852 -261.260336)
			(xy 371.898418 -261.17677) (xy 371.898418 -260.76402) (xy 371.855746 -260.757162) (xy 371.8302 -260.752573)
			(xy 371.780855 -260.736487) (xy 371.734632 -260.712886) (xy 371.692666 -260.682349) (xy 371.655989 -260.645628)
			(xy 371.625503 -260.603625) (xy 371.601958 -260.557372) (xy 371.585932 -260.508008) (xy 371.57782 -260.456746)
			(xy 371.577821 -260.404845) (xy 371.585935 -260.353583) (xy 371.601962 -260.30422) (xy 371.625508 -260.257968)
			(xy 371.655995 -260.215966) (xy 371.692672 -260.179245) (xy 371.734639 -260.148709) (xy 371.780863 -260.125109)
			(xy 371.830208 -260.109025) (xy 371.855746 -260.104382) (xy 371.898418 -260.097524) (xy 371.898418 -259.136388)
			(xy 371.855746 -259.12953) (xy 371.830194 -259.124941) (xy 371.780839 -259.108854) (xy 371.734606 -259.085249)
			(xy 371.69263 -259.054707) (xy 371.655945 -259.01798) (xy 371.625452 -258.975969) (xy 371.6019 -258.929708)
			(xy 371.58587 -258.880334) (xy 371.577754 -258.829062) (xy 371.577753 -258.777151) (xy 371.585867 -258.725878)
			(xy 371.601895 -258.676504) (xy 371.625445 -258.630242) (xy 371.655937 -258.58823) (xy 371.692621 -258.551501)
			(xy 371.734595 -258.520958) (xy 371.780828 -258.497351) (xy 371.830182 -258.481262) (xy 371.855746 -258.47675)
			(xy 371.898418 -258.469892) (xy 371.898418 -258.25069) (xy 371.841522 -258.193794) (xy 371.831238 -258.18414)
			(xy 371.806617 -258.170403) (xy 371.779175 -258.163929) (xy 371.75101 -258.165215) (xy 371.724272 -258.174162)
			(xy 371.701004 -258.190086) (xy 371.691662 -258.200652) (xy 371.675862 -258.218916) (xy 371.63987 -258.251111)
			(xy 371.599576 -258.277727) (xy 371.555838 -258.298195) (xy 371.509587 -258.312081) (xy 371.461808 -258.319089)
			(xy 371.437662 -258.319524) (xy 371.411698 -258.319012) (xy 371.360409 -258.310883) (xy 371.311023 -258.29483)
			(xy 371.264757 -258.27125) (xy 371.222749 -258.240723) (xy 371.186033 -258.204) (xy 371.155514 -258.161985)
			(xy 371.131944 -258.115714) (xy 371.115901 -258.066325) (xy 371.107783 -258.015035) (xy 371.107208 -257.98907)
			(xy 371.107649 -257.964926) (xy 371.114672 -257.917151) (xy 371.128564 -257.870905) (xy 371.149031 -257.827169)
			(xy 371.175638 -257.786872) (xy 371.207819 -257.750871) (xy 371.22608 -257.73507) (xy 371.236603 -257.725695)
			(xy 371.252479 -257.702423) (xy 371.2614 -257.6757) (xy 371.262688 -257.647557) (xy 371.256245 -257.620132)
			(xy 371.242561 -257.595506) (xy 371.232938 -257.58521) (xy 371.118892 -257.471164) (xy 371.087904 -257.483102)
			(xy 371.059058 -257.493636) (xy 370.998718 -257.505015) (xy 370.968016 -257.505708) (xy 370.943675 -257.505269)
			(xy 370.89552 -257.498118) (xy 370.848935 -257.483982) (xy 370.804927 -257.463167) (xy 370.764446 -257.436124)
			(xy 370.728369 -257.403437) (xy 370.697476 -257.365812) (xy 370.684552 -257.34518) (xy 370.31168 -257.34518)
			(xy 370.297768 -257.367411) (xy 370.264041 -257.407566) (xy 370.224396 -257.441892) (xy 370.179828 -257.469527)
			(xy 370.131455 -257.489776) (xy 370.080491 -257.502133) (xy 370.028216 -257.506287) (xy 369.975941 -257.502133)
			(xy 369.924977 -257.489776) (xy 369.876604 -257.469527) (xy 369.832036 -257.441892) (xy 369.792391 -257.407566)
			(xy 369.758664 -257.367411) (xy 369.744752 -257.34518) (xy 369.634008 -257.34518) (xy 369.317778 -257.02895)
			(xy 369.317778 -256.77114) (xy 369.233958 -256.77114) (xy 369.220496 -256.801366) (xy 369.207084 -256.829678)
			(xy 369.171281 -256.881077) (xy 369.149376 -256.903474) (xy 369.140032 -256.913167) (xy 369.126353 -256.936346)
			(xy 369.119219 -256.962298) (xy 369.119127 -256.989212) (xy 369.126084 -257.015212) (xy 369.139603 -257.038484)
			(xy 369.148868 -257.048254) (xy 369.167068 -257.066989) (xy 369.197916 -257.109135) (xy 369.221749 -257.155609)
			(xy 369.237973 -257.205255) (xy 369.246183 -257.256835) (xy 369.246658 -257.28295) (xy 369.246149 -257.308917)
			(xy 369.238024 -257.360212) (xy 369.221976 -257.409605) (xy 369.198398 -257.455879) (xy 369.167872 -257.497895)
			(xy 369.131149 -257.534618) (xy 369.089133 -257.565144) (xy 369.042859 -257.588722) (xy 368.993466 -257.60477)
			(xy 368.942171 -257.612895) (xy 368.890237 -257.612895) (xy 368.838942 -257.60477) (xy 368.789549 -257.588722)
			(xy 368.743275 -257.565144) (xy 368.701259 -257.534618) (xy 368.664536 -257.497895) (xy 368.63401 -257.455879)
			(xy 368.610432 -257.409605) (xy 368.594384 -257.360212) (xy 368.586259 -257.308917) (xy 368.58575 -257.28295)
			(xy 368.586263 -257.256548) (xy 368.59465 -257.204414) (xy 368.611218 -257.154277) (xy 368.635546 -257.107412)
			(xy 368.667016 -257.06501) (xy 368.685572 -257.046222) (xy 368.694912 -257.036527) (xy 368.708583 -257.013347)
			(xy 368.715712 -256.987398) (xy 368.715803 -256.960487) (xy 368.70885 -256.93449) (xy 368.695337 -256.911218)
			(xy 368.68608 -256.901442) (xy 368.667878 -256.882708) (xy 368.637026 -256.840564) (xy 368.61319 -256.794089)
			(xy 368.596964 -256.744443) (xy 368.588754 -256.692861) (xy 368.58829 -256.666746) (xy 368.588769 -256.640776)
			(xy 368.596889 -256.589473) (xy 368.612935 -256.540074) (xy 368.636513 -256.493793) (xy 368.667042 -256.451771)
			(xy 368.703769 -256.415043) (xy 368.745791 -256.384514) (xy 368.792072 -256.360936) (xy 368.841472 -256.344889)
			(xy 368.892774 -256.33677) (xy 368.918744 -256.336292) (xy 368.94373 -256.33673) (xy 368.993138 -256.344213)
			(xy 369.040857 -256.359045) (xy 369.063524 -256.369566) (xy 369.075732 -256.375066) (xy 369.102017 -256.380128)
			(xy 369.128713 -256.378179) (xy 369.153983 -256.369351) (xy 369.176087 -256.354254) (xy 369.193502 -256.333926)
			(xy 369.205029 -256.309767) (xy 369.207796 -256.296668) (xy 369.212975 -256.271147) (xy 369.229801 -256.221865)
			(xy 369.253627 -256.17556) (xy 369.283943 -256.13322) (xy 369.320104 -256.095747) (xy 369.361337 -256.063941)
			(xy 369.383818 -256.050796) (xy 369.389914 -256.047494) (xy 370.296948 -255.14046) (xy 370.30665 -255.130099)
			(xy 370.320422 -255.105291) (xy 370.326837 -255.077652) (xy 370.325402 -255.049315) (xy 370.316227 -255.022465)
			(xy 370.300019 -254.999176) (xy 370.289328 -254.989838) (xy 370.270641 -254.974056) (xy 370.237673 -254.937926)
			(xy 370.210387 -254.897333) (xy 370.189377 -254.853164) (xy 370.175104 -254.806382) (xy 370.167877 -254.758007)
			(xy 370.167408 -254.733552) (xy 370.167921 -254.707586) (xy 370.176051 -254.656295) (xy 370.192103 -254.606906)
			(xy 370.215683 -254.560636) (xy 370.246209 -254.518624) (xy 370.282931 -254.481903) (xy 370.324945 -254.451378)
			(xy 370.371215 -254.427799) (xy 370.420604 -254.411749) (xy 370.471896 -254.40362) (xy 370.497862 -254.403098)
			(xy 370.52232 -254.403538) (xy 370.570702 -254.410749) (xy 370.61749 -254.425018) (xy 370.661662 -254.446034)
			(xy 370.702249 -254.473337) (xy 370.738365 -254.506329) (xy 370.754148 -254.525018) (xy 370.763482 -254.535709)
			(xy 370.786776 -254.551902) (xy 370.813623 -254.561068) (xy 370.841956 -254.5625) (xy 370.869592 -254.556089)
			(xy 370.8944 -254.542328) (xy 370.90477 -254.532638) (xy 370.935758 -254.50165) (xy 370.935758 -254.251206)
			(xy 370.89588 -254.242316) (xy 370.870329 -254.236099) (xy 370.821465 -254.216677) (xy 370.776293 -254.189763)
			(xy 370.735951 -254.156037) (xy 370.701458 -254.116349) (xy 370.673683 -254.071701) (xy 370.653327 -254.023218)
			(xy 370.640904 -253.972124) (xy 370.636727 -253.919708) (xy 370.640902 -253.867291) (xy 370.653322 -253.816197)
			(xy 370.673676 -253.767713) (xy 370.701448 -253.723064) (xy 370.73594 -253.683374) (xy 370.77628 -253.649646)
			(xy 370.821451 -253.62273) (xy 370.870314 -253.603305) (xy 370.89588 -253.597156) (xy 370.935758 -253.588266)
			(xy 370.935758 -249.2375) (xy 370.935232 -249.222061) (xy 370.92603 -249.192588) (xy 370.908437 -249.167213)
			(xy 370.884063 -249.148259) (xy 370.855136 -249.137458) (xy 370.839746 -249.136154) (xy 370.81343 -249.134198)
			(xy 370.76187 -249.122978) (xy 370.712748 -249.103708) (xy 370.667312 -249.076876) (xy 370.626718 -249.043165)
			(xy 370.591997 -249.003431) (xy 370.564032 -248.958684) (xy 370.543533 -248.910061) (xy 370.531021 -248.858799)
			(xy 370.526815 -248.8062) (xy 370.531021 -248.753602) (xy 370.543532 -248.702339) (xy 370.564031 -248.653717)
			(xy 370.591997 -248.60897) (xy 370.626717 -248.569236) (xy 370.667311 -248.535525) (xy 370.712747 -248.508693)
			(xy 370.761869 -248.489422) (xy 370.813429 -248.478203) (xy 370.839746 -248.476262) (xy 370.855121 -248.474871)
			(xy 370.884019 -248.464054) (xy 370.908381 -248.445116) (xy 370.925992 -248.419778) (xy 370.93525 -248.390343)
			(xy 370.935758 -248.374916) (xy 370.935758 -247.609614) (xy 370.935234 -247.594174) (xy 370.926034 -247.564697)
			(xy 370.908442 -247.539318) (xy 370.884067 -247.520361) (xy 370.855139 -247.509559) (xy 370.839746 -247.508268)
			(xy 370.81344 -247.506297) (xy 370.761902 -247.495054) (xy 370.712805 -247.475766) (xy 370.667395 -247.448924)
			(xy 370.626826 -247.41521) (xy 370.592127 -247.375478) (xy 370.564181 -247.33074) (xy 370.543696 -247.28213)
			(xy 370.531193 -247.230883) (xy 370.52699 -247.178301) (xy 370.531193 -247.125719) (xy 370.543695 -247.074472)
			(xy 370.56418 -247.025862) (xy 370.592126 -246.981124) (xy 370.626824 -246.941392) (xy 370.667393 -246.907677)
			(xy 370.712803 -246.880835) (xy 370.7619 -246.861547) (xy 370.813437 -246.850303) (xy 370.839746 -246.848376)
			(xy 370.855116 -246.846984) (xy 370.884003 -246.836164) (xy 370.90835 -246.817223) (xy 370.925941 -246.791884)
			(xy 370.935177 -246.762453) (xy 370.935758 -246.74703) (xy 370.935758 -245.981982) (xy 370.935229 -245.966545)
			(xy 370.926024 -245.937076) (xy 370.90843 -245.911706) (xy 370.884057 -245.892756) (xy 370.855134 -245.881958)
			(xy 370.839746 -245.880636) (xy 370.813442 -245.878665) (xy 370.76191 -245.867423) (xy 370.712817 -245.848137)
			(xy 370.667412 -245.821297) (xy 370.626847 -245.787585) (xy 370.592152 -245.747858) (xy 370.564208 -245.703124)
			(xy 370.543726 -245.654518) (xy 370.531225 -245.603276) (xy 370.527022 -245.550699) (xy 370.531225 -245.498122)
			(xy 370.543726 -245.446881) (xy 370.564209 -245.398275) (xy 370.592153 -245.353541) (xy 370.626848 -245.313814)
			(xy 370.667413 -245.280102) (xy 370.712818 -245.253263) (xy 370.761911 -245.233977) (xy 370.813443 -245.222735)
			(xy 370.839746 -245.220744) (xy 370.85512 -245.219353) (xy 370.884016 -245.208535) (xy 370.908375 -245.189597)
			(xy 370.925981 -245.164259) (xy 370.935235 -245.134824) (xy 370.935758 -245.119398) (xy 370.935758 -244.354096)
			(xy 370.935231 -244.338658) (xy 370.926028 -244.309185) (xy 370.908435 -244.283812) (xy 370.884061 -244.264858)
			(xy 370.855136 -244.254058) (xy 370.839746 -244.25275) (xy 370.81343 -244.250794) (xy 370.761871 -244.239574)
			(xy 370.712749 -244.220304) (xy 370.667314 -244.193473) (xy 370.626721 -244.159762) (xy 370.592 -244.120028)
			(xy 370.564035 -244.075282) (xy 370.543536 -244.02666) (xy 370.531025 -243.975399) (xy 370.526819 -243.9228)
			(xy 370.531025 -243.870202) (xy 370.543536 -243.81894) (xy 370.564035 -243.770319) (xy 370.592 -243.725572)
			(xy 370.62672 -243.685839) (xy 370.667314 -243.652128) (xy 370.712749 -243.625296) (xy 370.76187 -243.606026)
			(xy 370.81343 -243.594806) (xy 370.839746 -243.592858) (xy 370.855121 -243.591467) (xy 370.884019 -243.58065)
			(xy 370.90838 -243.561712) (xy 370.925989 -243.536374) (xy 370.935247 -243.506939) (xy 370.935758 -243.491512)
			(xy 370.935758 -242.72621) (xy 370.935233 -242.71077) (xy 370.926033 -242.681294) (xy 370.908441 -242.655917)
			(xy 370.884066 -242.63696) (xy 370.855138 -242.626159) (xy 370.839746 -242.624864) (xy 370.81344 -242.622893)
			(xy 370.761903 -242.61165) (xy 370.712807 -242.592362) (xy 370.667397 -242.565521) (xy 370.626828 -242.531806)
			(xy 370.59213 -242.492076) (xy 370.564184 -242.447338) (xy 370.5437 -242.398729) (xy 370.531197 -242.347482)
			(xy 370.526994 -242.294901) (xy 370.531197 -242.24232) (xy 370.543699 -242.191073) (xy 370.564183 -242.142464)
			(xy 370.592129 -242.097726) (xy 370.626827 -242.057995) (xy 370.667396 -242.02428) (xy 370.712805 -241.997439)
			(xy 370.761901 -241.978151) (xy 370.813438 -241.966907) (xy 370.839746 -241.964972) (xy 370.855121 -241.963581)
			(xy 370.884021 -241.952764) (xy 370.908385 -241.933827) (xy 370.925997 -241.908489) (xy 370.935259 -241.879054)
			(xy 370.935758 -241.863626) (xy 370.935758 -241.098578) (xy 370.935229 -241.083141) (xy 370.926023 -241.053673)
			(xy 370.908429 -241.028305) (xy 370.884056 -241.009355) (xy 370.855133 -240.998558) (xy 370.839746 -240.997232)
			(xy 370.813432 -240.995276) (xy 370.761875 -240.984057) (xy 370.712756 -240.964788) (xy 370.667324 -240.937957)
			(xy 370.626732 -240.904248) (xy 370.592014 -240.864517) (xy 370.564051 -240.819773) (xy 370.543553 -240.771153)
			(xy 370.531043 -240.719895) (xy 370.526837 -240.667299) (xy 370.531043 -240.614704) (xy 370.543554 -240.563445)
			(xy 370.564051 -240.514826) (xy 370.592015 -240.470082) (xy 370.626734 -240.430351) (xy 370.667325 -240.396642)
			(xy 370.712758 -240.369812) (xy 370.761877 -240.350543) (xy 370.813433 -240.339324) (xy 370.839746 -240.33734)
			(xy 370.85512 -240.335949) (xy 370.884015 -240.325131) (xy 370.908373 -240.306192) (xy 370.925979 -240.280854)
			(xy 370.935232 -240.25142) (xy 370.935758 -240.235994) (xy 370.935758 -239.470692) (xy 370.935231 -239.455254)
			(xy 370.926027 -239.425782) (xy 370.908434 -239.40041) (xy 370.88406 -239.381457) (xy 370.855135 -239.370658)
			(xy 370.839746 -239.369346) (xy 370.813564 -239.367402) (xy 370.762258 -239.356276) (xy 370.713354 -239.337185)
			(xy 370.66808 -239.310608) (xy 370.627573 -239.277212) (xy 370.59285 -239.237837) (xy 370.57838 -239.21593)
			(xy 370.197634 -239.21593) (xy 370.18354 -239.237334) (xy 370.14981 -239.275912) (xy 370.110529 -239.308821)
			(xy 370.066639 -239.335273) (xy 370.019192 -239.354634) (xy 369.969325 -239.366439) (xy 369.918234 -239.370406)
			(xy 369.867143 -239.366439) (xy 369.817276 -239.354634) (xy 369.769829 -239.335273) (xy 369.725939 -239.308821)
			(xy 369.686658 -239.275912) (xy 369.652928 -239.237334) (xy 369.638834 -239.21593) (xy 368.738658 -239.21593)
			(xy 368.62893 -239.325658) (xy 368.627406 -239.344454) (xy 368.624798 -239.370188) (xy 368.612601 -239.420452)
			(xy 368.592723 -239.468202) (xy 368.56565 -239.512273) (xy 368.532041 -239.551589) (xy 368.492719 -239.585189)
			(xy 368.448643 -239.612254) (xy 368.400888 -239.632122) (xy 368.350622 -239.644308) (xy 368.324892 -239.646968)
			(xy 368.306096 -239.648492) (xy 368.243358 -239.71123) (xy 368.243358 -240.704116) (xy 368.55908 -240.704116)
			(xy 368.559497 -240.679563) (xy 368.566743 -240.630995) (xy 368.581092 -240.584033) (xy 368.602229 -240.539709)
			(xy 368.629689 -240.498999) (xy 368.645948 -240.480596) (xy 368.655738 -240.469096) (xy 368.668757 -240.441863)
			(xy 368.67323 -240.412012) (xy 368.668764 -240.382159) (xy 368.655751 -240.354924) (xy 368.645948 -240.343436)
			(xy 368.629692 -240.325029) (xy 368.602222 -240.284326) (xy 368.581082 -240.240004) (xy 368.566739 -240.19304)
			(xy 368.559509 -240.144469) (xy 368.55908 -240.119916) (xy 368.559544 -240.093945) (xy 368.567667 -240.042644)
			(xy 368.583717 -239.993244) (xy 368.607298 -239.946964) (xy 368.637828 -239.904944) (xy 368.674557 -239.868217)
			(xy 368.71658 -239.837688) (xy 368.762861 -239.81411) (xy 368.812261 -239.798063) (xy 368.863563 -239.789942)
			(xy 368.889534 -239.789462) (xy 368.918729 -239.790081) (xy 368.976218 -239.800294) (xy 369.003834 -239.809782)
			(xy 369.016671 -239.814147) (xy 369.043676 -239.816516) (xy 369.07035 -239.811682) (xy 369.094806 -239.799988)
			(xy 369.115314 -239.782261) (xy 369.130425 -239.759754) (xy 369.135152 -239.747044) (xy 369.143893 -239.722872)
			(xy 369.167742 -239.677341) (xy 369.198352 -239.636052) (xy 369.234987 -239.6) (xy 369.276762 -239.570056)
			(xy 369.32267 -239.546941) (xy 369.371603 -239.531213) (xy 369.422381 -239.523252) (xy 369.44808 -239.522762)
			(xy 369.474052 -239.523211) (xy 369.525356 -239.531334) (xy 369.574757 -239.547383) (xy 369.62104 -239.570963)
			(xy 369.663064 -239.601493) (xy 369.699794 -239.638221) (xy 369.730327 -239.680243) (xy 369.753909 -239.726524)
			(xy 369.769961 -239.775925) (xy 369.778087 -239.827228) (xy 369.778087 -239.879172) (xy 369.778085 -239.879183)
			(xy 370.058189 -239.879183) (xy 370.058189 -239.827249) (xy 370.066314 -239.775954) (xy 370.082362 -239.726561)
			(xy 370.10594 -239.680287) (xy 370.136466 -239.638271) (xy 370.173189 -239.601548) (xy 370.215205 -239.571022)
			(xy 370.261479 -239.547444) (xy 370.310872 -239.531396) (xy 370.362167 -239.523271) (xy 370.414101 -239.523271)
			(xy 370.465396 -239.531396) (xy 370.514789 -239.547444) (xy 370.561063 -239.571022) (xy 370.603079 -239.601548)
			(xy 370.639802 -239.638271) (xy 370.670328 -239.680287) (xy 370.693906 -239.726561) (xy 370.709954 -239.775954)
			(xy 370.718079 -239.827249) (xy 370.718588 -239.853216) (xy 370.718079 -239.879183) (xy 370.709954 -239.930478)
			(xy 370.693906 -239.979871) (xy 370.670328 -240.026145) (xy 370.639802 -240.068161) (xy 370.603079 -240.104884)
			(xy 370.561063 -240.13541) (xy 370.514789 -240.158988) (xy 370.465396 -240.175036) (xy 370.414101 -240.183161)
			(xy 370.362167 -240.183161) (xy 370.310872 -240.175036) (xy 370.261479 -240.158988) (xy 370.215205 -240.13541)
			(xy 370.173189 -240.104884) (xy 370.136466 -240.068161) (xy 370.10594 -240.026145) (xy 370.082362 -239.979871)
			(xy 370.066314 -239.930478) (xy 370.058189 -239.879183) (xy 369.778085 -239.879183) (xy 369.769961 -239.930475)
			(xy 369.753909 -239.979876) (xy 369.730327 -240.026157) (xy 369.699794 -240.068179) (xy 369.663064 -240.104907)
			(xy 369.62104 -240.135437) (xy 369.574757 -240.159017) (xy 369.525356 -240.175066) (xy 369.474052 -240.183189)
			(xy 369.44808 -240.18367) (xy 369.418884 -240.183071) (xy 369.361396 -240.172845) (xy 369.33378 -240.16335)
			(xy 369.320927 -240.159044) (xy 369.293933 -240.156675) (xy 369.267269 -240.161503) (xy 369.24282 -240.173185)
			(xy 369.222312 -240.190897) (xy 369.207195 -240.213386) (xy 369.202462 -240.226088) (xy 369.194751 -240.247645)
			(xy 369.174248 -240.288578) (xy 369.14829 -240.32629) (xy 369.13312 -240.343436) (xy 369.123301 -240.354913)
			(xy 369.11029 -240.382155) (xy 369.105825 -240.412012) (xy 369.110297 -240.441868) (xy 369.123315 -240.469107)
			(xy 369.13312 -240.480596) (xy 369.149402 -240.49898) (xy 369.176866 -240.539691) (xy 369.198 -240.584019)
			(xy 369.212337 -240.630988) (xy 369.219562 -240.679561) (xy 369.219988 -240.704116) (xy 369.219479 -240.730083)
			(xy 369.211354 -240.781378) (xy 369.195306 -240.830771) (xy 369.171728 -240.877045) (xy 369.141202 -240.919061)
			(xy 369.104479 -240.955784) (xy 369.062463 -240.98631) (xy 369.016189 -241.009888) (xy 368.966796 -241.025936)
			(xy 368.915501 -241.034061) (xy 368.863567 -241.034061) (xy 368.812272 -241.025936) (xy 368.762879 -241.009888)
			(xy 368.716605 -240.98631) (xy 368.674589 -240.955784) (xy 368.637866 -240.919061) (xy 368.60734 -240.877045)
			(xy 368.583762 -240.830771) (xy 368.567714 -240.781378) (xy 368.559589 -240.730083) (xy 368.55908 -240.704116)
			(xy 368.243358 -240.704116) (xy 368.243358 -241.507069) (xy 370.058189 -241.507069) (xy 370.058189 -241.455135)
			(xy 370.066314 -241.40384) (xy 370.082362 -241.354447) (xy 370.10594 -241.308173) (xy 370.136466 -241.266157)
			(xy 370.173189 -241.229434) (xy 370.215205 -241.198908) (xy 370.261479 -241.17533) (xy 370.310872 -241.159282)
			(xy 370.362167 -241.151157) (xy 370.414101 -241.151157) (xy 370.465396 -241.159282) (xy 370.514789 -241.17533)
			(xy 370.561063 -241.198908) (xy 370.603079 -241.229434) (xy 370.639802 -241.266157) (xy 370.670328 -241.308173)
			(xy 370.693906 -241.354447) (xy 370.709954 -241.40384) (xy 370.718079 -241.455135) (xy 370.718588 -241.481102)
			(xy 370.718079 -241.507069) (xy 370.709954 -241.558364) (xy 370.693906 -241.607757) (xy 370.670328 -241.654031)
			(xy 370.639802 -241.696047) (xy 370.603079 -241.73277) (xy 370.561063 -241.763296) (xy 370.514789 -241.786874)
			(xy 370.465396 -241.802922) (xy 370.414101 -241.811047) (xy 370.362167 -241.811047) (xy 370.310872 -241.802922)
			(xy 370.261479 -241.786874) (xy 370.215205 -241.763296) (xy 370.173189 -241.73277) (xy 370.136466 -241.696047)
			(xy 370.10594 -241.654031) (xy 370.082362 -241.607757) (xy 370.066314 -241.558364) (xy 370.058189 -241.507069)
			(xy 368.243358 -241.507069) (xy 368.243358 -243.134955) (xy 370.057935 -243.134955) (xy 370.057935 -243.083021)
			(xy 370.06606 -243.031726) (xy 370.082108 -242.982333) (xy 370.105686 -242.936059) (xy 370.136212 -242.894043)
			(xy 370.172935 -242.85732) (xy 370.214951 -242.826794) (xy 370.261225 -242.803216) (xy 370.310618 -242.787168)
			(xy 370.361913 -242.779043) (xy 370.413847 -242.779043) (xy 370.465142 -242.787168) (xy 370.514535 -242.803216)
			(xy 370.560809 -242.826794) (xy 370.602825 -242.85732) (xy 370.639548 -242.894043) (xy 370.670074 -242.936059)
			(xy 370.693652 -242.982333) (xy 370.7097 -243.031726) (xy 370.717825 -243.083021) (xy 370.718334 -243.108988)
			(xy 370.717825 -243.134955) (xy 370.7097 -243.18625) (xy 370.693652 -243.235643) (xy 370.670074 -243.281917)
			(xy 370.639548 -243.323933) (xy 370.602825 -243.360656) (xy 370.560809 -243.391182) (xy 370.514535 -243.41476)
			(xy 370.465142 -243.430808) (xy 370.413847 -243.438933) (xy 370.361913 -243.438933) (xy 370.310618 -243.430808)
			(xy 370.261225 -243.41476) (xy 370.214951 -243.391182) (xy 370.172935 -243.360656) (xy 370.136212 -243.323933)
			(xy 370.105686 -243.281917) (xy 370.082108 -243.235643) (xy 370.06606 -243.18625) (xy 370.057935 -243.134955)
			(xy 368.243358 -243.134955) (xy 368.243358 -245.09857) (xy 367.742978 -245.59895) (xy 368.58575 -245.59895)
			(xy 368.586195 -245.574398) (xy 368.593435 -245.525832) (xy 368.607778 -245.47887) (xy 368.628909 -245.434546)
			(xy 368.656362 -245.393835) (xy 368.672618 -245.37543) (xy 368.682369 -245.363901) (xy 368.695383 -245.336677)
			(xy 368.699859 -245.306837) (xy 368.695404 -245.276993) (xy 368.682411 -245.24976) (xy 368.672618 -245.23827)
			(xy 368.656373 -245.219854) (xy 368.628903 -245.179153) (xy 368.607761 -245.134833) (xy 368.593415 -245.087871)
			(xy 368.586181 -245.039302) (xy 368.58575 -245.01475) (xy 368.586195 -244.990198) (xy 368.593435 -244.941632)
			(xy 368.607778 -244.89467) (xy 368.628909 -244.850346) (xy 368.656362 -244.809635) (xy 368.672618 -244.79123)
			(xy 368.682369 -244.779701) (xy 368.695383 -244.752477) (xy 368.699859 -244.722637) (xy 368.695404 -244.692793)
			(xy 368.682411 -244.66556) (xy 368.672618 -244.65407) (xy 368.656373 -244.635654) (xy 368.628903 -244.594953)
			(xy 368.607761 -244.550633) (xy 368.593415 -244.503671) (xy 368.586181 -244.455102) (xy 368.58575 -244.43055)
			(xy 368.586195 -244.405998) (xy 368.593435 -244.357432) (xy 368.607778 -244.31047) (xy 368.628909 -244.266146)
			(xy 368.656362 -244.225435) (xy 368.672618 -244.20703) (xy 368.682369 -244.195501) (xy 368.695383 -244.168277)
			(xy 368.699859 -244.138437) (xy 368.695404 -244.108593) (xy 368.682411 -244.08136) (xy 368.672618 -244.06987)
			(xy 368.656373 -244.051454) (xy 368.628903 -244.010753) (xy 368.607761 -243.966433) (xy 368.593415 -243.919471)
			(xy 368.586181 -243.870902) (xy 368.58575 -243.84635) (xy 368.586259 -243.820383) (xy 368.594384 -243.769088)
			(xy 368.610432 -243.719695) (xy 368.63401 -243.673421) (xy 368.664536 -243.631405) (xy 368.701259 -243.594682)
			(xy 368.743275 -243.564156) (xy 368.789549 -243.540578) (xy 368.838942 -243.52453) (xy 368.890237 -243.516405)
			(xy 368.942171 -243.516405) (xy 368.993466 -243.52453) (xy 369.042859 -243.540578) (xy 369.089133 -243.564156)
			(xy 369.131149 -243.594682) (xy 369.167872 -243.631405) (xy 369.198398 -243.673421) (xy 369.221976 -243.719695)
			(xy 369.238024 -243.769088) (xy 369.246149 -243.820383) (xy 369.246658 -243.84635) (xy 369.246211 -243.870902)
			(xy 369.238971 -243.919468) (xy 369.230021 -243.948771) (xy 369.588035 -243.948771) (xy 369.588035 -243.896837)
			(xy 369.59616 -243.845542) (xy 369.612208 -243.796149) (xy 369.635786 -243.749875) (xy 369.666312 -243.707859)
			(xy 369.703035 -243.671136) (xy 369.745051 -243.64061) (xy 369.791325 -243.617032) (xy 369.840718 -243.600984)
			(xy 369.892013 -243.592859) (xy 369.943947 -243.592859) (xy 369.995242 -243.600984) (xy 370.044635 -243.617032)
			(xy 370.090909 -243.64061) (xy 370.132925 -243.671136) (xy 370.169648 -243.707859) (xy 370.200174 -243.749875)
			(xy 370.223752 -243.796149) (xy 370.2398 -243.845542) (xy 370.247925 -243.896837) (xy 370.248434 -243.922804)
			(xy 370.247925 -243.948771) (xy 370.2398 -244.000066) (xy 370.223752 -244.049459) (xy 370.200174 -244.095733)
			(xy 370.169648 -244.137749) (xy 370.132925 -244.174472) (xy 370.090909 -244.204998) (xy 370.044635 -244.228576)
			(xy 369.995242 -244.244624) (xy 369.943947 -244.252749) (xy 369.892013 -244.252749) (xy 369.840718 -244.244624)
			(xy 369.791325 -244.228576) (xy 369.745051 -244.204998) (xy 369.703035 -244.174472) (xy 369.666312 -244.137749)
			(xy 369.635786 -244.095733) (xy 369.612208 -244.049459) (xy 369.59616 -244.000066) (xy 369.588035 -243.948771)
			(xy 369.230021 -243.948771) (xy 369.224628 -243.966429) (xy 369.203498 -244.010754) (xy 369.176046 -244.051465)
			(xy 369.15979 -244.06987) (xy 369.14994 -244.081322) (xy 369.136937 -244.108573) (xy 369.132479 -244.138437)
			(xy 369.136958 -244.168298) (xy 369.149982 -244.195539) (xy 369.15979 -244.20703) (xy 369.177453 -244.227015)
			(xy 369.206727 -244.271599) (xy 369.228443 -244.320312) (xy 369.235736 -244.345968) (xy 369.23952 -244.358821)
			(xy 369.252854 -244.38205) (xy 369.271786 -244.400997) (xy 369.295005 -244.41435) (xy 369.320903 -244.421184)
			(xy 369.347687 -244.421026) (xy 369.360704 -244.41785) (xy 369.382135 -244.412391) (xy 369.425968 -244.406523)
			(xy 369.44808 -244.406166) (xy 369.474052 -244.406607) (xy 369.525357 -244.41473) (xy 369.574759 -244.430779)
			(xy 369.621042 -244.454359) (xy 369.663066 -244.48489) (xy 369.699797 -244.521618) (xy 369.73033 -244.563641)
			(xy 369.753913 -244.609923) (xy 369.769965 -244.659324) (xy 369.778091 -244.710628) (xy 369.778091 -244.762333)
			(xy 370.057935 -244.762333) (xy 370.057935 -244.710399) (xy 370.06606 -244.659104) (xy 370.082108 -244.609711)
			(xy 370.105686 -244.563437) (xy 370.136212 -244.521421) (xy 370.172935 -244.484698) (xy 370.214951 -244.454172)
			(xy 370.261225 -244.430594) (xy 370.310618 -244.414546) (xy 370.361913 -244.406421) (xy 370.413847 -244.406421)
			(xy 370.465142 -244.414546) (xy 370.514535 -244.430594) (xy 370.560809 -244.454172) (xy 370.602825 -244.484698)
			(xy 370.639548 -244.521421) (xy 370.670074 -244.563437) (xy 370.693652 -244.609711) (xy 370.7097 -244.659104)
			(xy 370.717825 -244.710399) (xy 370.718334 -244.736366) (xy 370.717825 -244.762333) (xy 370.7097 -244.813628)
			(xy 370.693652 -244.863021) (xy 370.670074 -244.909295) (xy 370.639548 -244.951311) (xy 370.602825 -244.988034)
			(xy 370.560809 -245.01856) (xy 370.514535 -245.042138) (xy 370.465142 -245.058186) (xy 370.413847 -245.066311)
			(xy 370.361913 -245.066311) (xy 370.310618 -245.058186) (xy 370.261225 -245.042138) (xy 370.214951 -245.01856)
			(xy 370.172935 -244.988034) (xy 370.136212 -244.951311) (xy 370.105686 -244.909295) (xy 370.082108 -244.863021)
			(xy 370.06606 -244.813628) (xy 370.057935 -244.762333) (xy 369.778091 -244.762333) (xy 369.778091 -244.762572)
			(xy 369.769965 -244.813876) (xy 369.753913 -244.863277) (xy 369.73033 -244.909559) (xy 369.699797 -244.951582)
			(xy 369.663066 -244.98831) (xy 369.621042 -245.018841) (xy 369.574759 -245.04242) (xy 369.525357 -245.05847)
			(xy 369.474052 -245.066593) (xy 369.44808 -245.067074) (xy 369.424441 -245.066668) (xy 369.377649 -245.059912)
			(xy 369.354862 -245.053612) (xy 369.339705 -245.049717) (xy 369.308432 -245.050409) (xy 369.278833 -245.06053)
			(xy 369.253685 -245.079133) (xy 369.235344 -245.104473) (xy 369.229894 -245.119144) (xy 369.222179 -245.141047)
			(xy 369.201495 -245.182623) (xy 369.175197 -245.220896) (xy 369.15979 -245.23827) (xy 369.14994 -245.249722)
			(xy 369.136937 -245.276973) (xy 369.132479 -245.306837) (xy 369.136958 -245.336698) (xy 369.149982 -245.363939)
			(xy 369.15979 -245.37543) (xy 369.176036 -245.393845) (xy 369.203506 -245.434546) (xy 369.224647 -245.478867)
			(xy 369.238993 -245.525829) (xy 369.246227 -245.574397) (xy 369.246267 -245.576657) (xy 369.588289 -245.576657)
			(xy 369.588289 -245.524723) (xy 369.596414 -245.473428) (xy 369.612462 -245.424035) (xy 369.63604 -245.377761)
			(xy 369.666566 -245.335745) (xy 369.703289 -245.299022) (xy 369.745305 -245.268496) (xy 369.791579 -245.244918)
			(xy 369.840972 -245.22887) (xy 369.892267 -245.220745) (xy 369.944201 -245.220745) (xy 369.995496 -245.22887)
			(xy 370.044889 -245.244918) (xy 370.091163 -245.268496) (xy 370.133179 -245.299022) (xy 370.169902 -245.335745)
			(xy 370.200428 -245.377761) (xy 370.224006 -245.424035) (xy 370.240054 -245.473428) (xy 370.248179 -245.524723)
			(xy 370.248688 -245.55069) (xy 370.248179 -245.576657) (xy 370.240054 -245.627952) (xy 370.224006 -245.677345)
			(xy 370.200428 -245.723619) (xy 370.169902 -245.765635) (xy 370.133179 -245.802358) (xy 370.091163 -245.832884)
			(xy 370.044889 -245.856462) (xy 369.995496 -245.87251) (xy 369.944201 -245.880635) (xy 369.892267 -245.880635)
			(xy 369.840972 -245.87251) (xy 369.791579 -245.856462) (xy 369.745305 -245.832884) (xy 369.703289 -245.802358)
			(xy 369.666566 -245.765635) (xy 369.63604 -245.723619) (xy 369.612462 -245.677345) (xy 369.596414 -245.627952)
			(xy 369.588289 -245.576657) (xy 369.246267 -245.576657) (xy 369.246658 -245.59895) (xy 369.246149 -245.624917)
			(xy 369.238024 -245.676212) (xy 369.221976 -245.725605) (xy 369.198398 -245.771879) (xy 369.167872 -245.813895)
			(xy 369.131149 -245.850618) (xy 369.089133 -245.881144) (xy 369.042859 -245.904722) (xy 368.993466 -245.92077)
			(xy 368.942171 -245.928895) (xy 368.890237 -245.928895) (xy 368.838942 -245.92077) (xy 368.789549 -245.904722)
			(xy 368.743275 -245.881144) (xy 368.701259 -245.850618) (xy 368.664536 -245.813895) (xy 368.63401 -245.771879)
			(xy 368.610432 -245.725605) (xy 368.594384 -245.676212) (xy 368.586259 -245.624917) (xy 368.58575 -245.59895)
			(xy 367.742978 -245.59895) (xy 366.951455 -246.390473) (xy 369.118389 -246.390473) (xy 369.118389 -246.338539)
			(xy 369.126514 -246.287244) (xy 369.142562 -246.237851) (xy 369.16614 -246.191577) (xy 369.196666 -246.149561)
			(xy 369.233389 -246.112838) (xy 369.275405 -246.082312) (xy 369.321679 -246.058734) (xy 369.371072 -246.042686)
			(xy 369.422367 -246.034561) (xy 369.474301 -246.034561) (xy 369.525596 -246.042686) (xy 369.574989 -246.058734)
			(xy 369.621263 -246.082312) (xy 369.663279 -246.112838) (xy 369.700002 -246.149561) (xy 369.730528 -246.191577)
			(xy 369.754106 -246.237851) (xy 369.770154 -246.287244) (xy 369.778279 -246.338539) (xy 369.778788 -246.364506)
			(xy 369.778279 -246.390473) (xy 370.058189 -246.390473) (xy 370.058189 -246.338539) (xy 370.066314 -246.287244)
			(xy 370.082362 -246.237851) (xy 370.10594 -246.191577) (xy 370.136466 -246.149561) (xy 370.173189 -246.112838)
			(xy 370.215205 -246.082312) (xy 370.261479 -246.058734) (xy 370.310872 -246.042686) (xy 370.362167 -246.034561)
			(xy 370.414101 -246.034561) (xy 370.465396 -246.042686) (xy 370.514789 -246.058734) (xy 370.561063 -246.082312)
			(xy 370.603079 -246.112838) (xy 370.639802 -246.149561) (xy 370.670328 -246.191577) (xy 370.693906 -246.237851)
			(xy 370.709954 -246.287244) (xy 370.718079 -246.338539) (xy 370.718588 -246.364506) (xy 370.718079 -246.390473)
			(xy 370.709954 -246.441768) (xy 370.693906 -246.491161) (xy 370.670328 -246.537435) (xy 370.639802 -246.579451)
			(xy 370.603079 -246.616174) (xy 370.561063 -246.6467) (xy 370.514789 -246.670278) (xy 370.465396 -246.686326)
			(xy 370.414101 -246.694451) (xy 370.362167 -246.694451) (xy 370.310872 -246.686326) (xy 370.261479 -246.670278)
			(xy 370.215205 -246.6467) (xy 370.173189 -246.616174) (xy 370.136466 -246.579451) (xy 370.10594 -246.537435)
			(xy 370.082362 -246.491161) (xy 370.066314 -246.441768) (xy 370.058189 -246.390473) (xy 369.778279 -246.390473)
			(xy 369.770154 -246.441768) (xy 369.754106 -246.491161) (xy 369.730528 -246.537435) (xy 369.700002 -246.579451)
			(xy 369.663279 -246.616174) (xy 369.621263 -246.6467) (xy 369.574989 -246.670278) (xy 369.525596 -246.686326)
			(xy 369.474301 -246.694451) (xy 369.422367 -246.694451) (xy 369.371072 -246.686326) (xy 369.321679 -246.670278)
			(xy 369.275405 -246.6467) (xy 369.233389 -246.616174) (xy 369.196666 -246.579451) (xy 369.16614 -246.537435)
			(xy 369.142562 -246.491161) (xy 369.126514 -246.441768) (xy 369.118389 -246.390473) (xy 366.951455 -246.390473)
			(xy 366.805718 -246.53621) (xy 366.805718 -247.204289) (xy 369.588289 -247.204289) (xy 369.588289 -247.152355)
			(xy 369.596414 -247.10106) (xy 369.612462 -247.051667) (xy 369.63604 -247.005393) (xy 369.666566 -246.963377)
			(xy 369.703289 -246.926654) (xy 369.745305 -246.896128) (xy 369.791579 -246.87255) (xy 369.840972 -246.856502)
			(xy 369.892267 -246.848377) (xy 369.944201 -246.848377) (xy 369.995496 -246.856502) (xy 370.044889 -246.87255)
			(xy 370.091163 -246.896128) (xy 370.133179 -246.926654) (xy 370.169902 -246.963377) (xy 370.200428 -247.005393)
			(xy 370.224006 -247.051667) (xy 370.240054 -247.10106) (xy 370.248179 -247.152355) (xy 370.248688 -247.178322)
			(xy 370.248179 -247.204289) (xy 370.240054 -247.255584) (xy 370.224006 -247.304977) (xy 370.200428 -247.351251)
			(xy 370.169902 -247.393267) (xy 370.133179 -247.42999) (xy 370.091163 -247.460516) (xy 370.044889 -247.484094)
			(xy 369.995496 -247.500142) (xy 369.944201 -247.508267) (xy 369.892267 -247.508267) (xy 369.840972 -247.500142)
			(xy 369.791579 -247.484094) (xy 369.745305 -247.460516) (xy 369.703289 -247.42999) (xy 369.666566 -247.393267)
			(xy 369.63604 -247.351251) (xy 369.612462 -247.304977) (xy 369.596414 -247.255584) (xy 369.588289 -247.204289)
			(xy 366.805718 -247.204289) (xy 366.805718 -248.27103) (xy 366.888552 -248.353864) (xy 368.562681 -248.353864)
			(xy 368.562681 -248.301936) (xy 368.570804 -248.250646) (xy 368.586851 -248.201259) (xy 368.610425 -248.15499)
			(xy 368.640947 -248.112978) (xy 368.677665 -248.076258) (xy 368.719675 -248.045734) (xy 368.765943 -248.022157)
			(xy 368.815329 -248.006108) (xy 368.866618 -247.997983) (xy 368.892582 -247.997472) (xy 368.917878 -247.997897)
			(xy 368.967886 -248.005547) (xy 368.99215 -248.012712) (xy 369.006047 -248.016483) (xy 369.034814 -248.017158)
			(xy 369.062627 -248.009776) (xy 369.087273 -247.994926) (xy 369.106796 -247.973786) (xy 369.119642 -247.948038)
			(xy 369.122706 -247.933972) (xy 369.127662 -247.908846) (xy 369.144363 -247.860432) (xy 369.16833 -247.815173)
			(xy 369.19899 -247.774151) (xy 369.235608 -247.738347) (xy 369.277309 -247.708618) (xy 369.323096 -247.685675)
			(xy 369.371873 -247.670066) (xy 369.422473 -247.662166) (xy 369.44808 -247.661684) (xy 369.474053 -247.662089)
			(xy 369.525361 -247.670213) (xy 369.574766 -247.686263) (xy 369.621051 -247.709844) (xy 369.663078 -247.740376)
			(xy 369.699811 -247.777107) (xy 369.730345 -247.819132) (xy 369.753929 -247.865416) (xy 369.769982 -247.91482)
			(xy 369.778109 -247.966127) (xy 369.778109 -248.018073) (xy 369.778104 -248.018105) (xy 370.057935 -248.018105)
			(xy 370.057935 -247.966171) (xy 370.06606 -247.914876) (xy 370.082108 -247.865483) (xy 370.105686 -247.819209)
			(xy 370.136212 -247.777193) (xy 370.172935 -247.74047) (xy 370.214951 -247.709944) (xy 370.261225 -247.686366)
			(xy 370.310618 -247.670318) (xy 370.361913 -247.662193) (xy 370.413847 -247.662193) (xy 370.465142 -247.670318)
			(xy 370.514535 -247.686366) (xy 370.560809 -247.709944) (xy 370.602825 -247.74047) (xy 370.639548 -247.777193)
			(xy 370.670074 -247.819209) (xy 370.693652 -247.865483) (xy 370.7097 -247.914876) (xy 370.717825 -247.966171)
			(xy 370.718334 -247.992138) (xy 370.717825 -248.018105) (xy 370.7097 -248.0694) (xy 370.693652 -248.118793)
			(xy 370.670074 -248.165067) (xy 370.639548 -248.207083) (xy 370.602825 -248.243806) (xy 370.560809 -248.274332)
			(xy 370.514535 -248.29791) (xy 370.465142 -248.313958) (xy 370.413847 -248.322083) (xy 370.361913 -248.322083)
			(xy 370.310618 -248.313958) (xy 370.261225 -248.29791) (xy 370.214951 -248.274332) (xy 370.172935 -248.243806)
			(xy 370.136212 -248.207083) (xy 370.105686 -248.165067) (xy 370.082108 -248.118793) (xy 370.06606 -248.0694)
			(xy 370.057935 -248.018105) (xy 369.778104 -248.018105) (xy 369.769982 -248.06938) (xy 369.753929 -248.118784)
			(xy 369.730345 -248.165068) (xy 369.699811 -248.207093) (xy 369.663078 -248.243824) (xy 369.621051 -248.274356)
			(xy 369.574766 -248.297937) (xy 369.525361 -248.313987) (xy 369.474053 -248.322111) (xy 369.44808 -248.322592)
			(xy 369.422784 -248.322177) (xy 369.372775 -248.314521) (xy 369.348512 -248.307352) (xy 369.334636 -248.303488)
			(xy 369.305853 -248.30282) (xy 369.278027 -248.310215) (xy 369.253373 -248.325084) (xy 369.233851 -248.346246)
			(xy 369.221012 -248.372016) (xy 369.217956 -248.386092) (xy 369.212915 -248.4112) (xy 369.196223 -248.459609)
			(xy 369.172266 -248.504865) (xy 369.141618 -248.545886) (xy 369.105011 -248.581691) (xy 369.06332 -248.611423)
			(xy 369.017544 -248.63437) (xy 368.968777 -248.649985) (xy 368.918185 -248.657893) (xy 368.892582 -248.65838)
			(xy 368.866618 -248.657817) (xy 368.815329 -248.649692) (xy 368.765943 -248.633643) (xy 368.719675 -248.610066)
			(xy 368.677665 -248.579542) (xy 368.640947 -248.542822) (xy 368.610425 -248.50081) (xy 368.586851 -248.454541)
			(xy 368.570804 -248.405154) (xy 368.562681 -248.353864) (xy 366.888552 -248.353864) (xy 367.667546 -249.132858)
			(xy 368.598924 -249.132858) (xy 368.598926 -249.080918) (xy 368.607053 -249.029617) (xy 368.623106 -248.980219)
			(xy 368.646689 -248.93394) (xy 368.677222 -248.891921) (xy 368.713951 -248.855196) (xy 368.755974 -248.824668)
			(xy 368.802256 -248.801091) (xy 368.851656 -248.785044) (xy 368.902958 -248.776923) (xy 368.954898 -248.776927)
			(xy 369.006199 -248.785057) (xy 369.055596 -248.801112) (xy 369.101873 -248.824698) (xy 369.112162 -248.832175)
			(xy 369.588289 -248.832175) (xy 369.588289 -248.780241) (xy 369.596414 -248.728946) (xy 369.612462 -248.679553)
			(xy 369.63604 -248.633279) (xy 369.666566 -248.591263) (xy 369.703289 -248.55454) (xy 369.745305 -248.524014)
			(xy 369.791579 -248.500436) (xy 369.840972 -248.484388) (xy 369.892267 -248.476263) (xy 369.944201 -248.476263)
			(xy 369.995496 -248.484388) (xy 370.044889 -248.500436) (xy 370.091163 -248.524014) (xy 370.133179 -248.55454)
			(xy 370.169902 -248.591263) (xy 370.200428 -248.633279) (xy 370.224006 -248.679553) (xy 370.240054 -248.728946)
			(xy 370.248179 -248.780241) (xy 370.248688 -248.806208) (xy 370.248179 -248.832175) (xy 370.240054 -248.88347)
			(xy 370.224006 -248.932863) (xy 370.200428 -248.979137) (xy 370.169902 -249.021153) (xy 370.133179 -249.057876)
			(xy 370.091163 -249.088402) (xy 370.044889 -249.11198) (xy 369.995496 -249.128028) (xy 369.944201 -249.136153)
			(xy 369.892267 -249.136153) (xy 369.840972 -249.128028) (xy 369.791579 -249.11198) (xy 369.745305 -249.088402)
			(xy 369.703289 -249.057876) (xy 369.666566 -249.021153) (xy 369.63604 -248.979137) (xy 369.612462 -248.932863)
			(xy 369.596414 -248.88347) (xy 369.588289 -248.832175) (xy 369.112162 -248.832175) (xy 369.143891 -248.855232)
			(xy 369.180615 -248.891964) (xy 369.21114 -248.933988) (xy 369.234715 -248.980271) (xy 369.25076 -249.029671)
			(xy 369.258879 -249.080974) (xy 369.259358 -249.106944) (xy 369.259113 -249.124675) (xy 369.255298 -249.159931)
			(xy 369.251738 -249.177302) (xy 369.249013 -249.191697) (xy 369.251156 -249.22091) (xy 369.261494 -249.248316)
			(xy 369.279178 -249.271666) (xy 369.302758 -249.289044) (xy 369.330297 -249.299023) (xy 369.359535 -249.300785)
			(xy 369.373912 -249.297952) (xy 369.3922 -249.294016) (xy 369.429374 -249.289815) (xy 369.44808 -249.28957)
			(xy 369.474049 -249.290034) (xy 369.525347 -249.298155) (xy 369.574744 -249.314202) (xy 369.621022 -249.337778)
			(xy 369.663042 -249.368304) (xy 369.699769 -249.405027) (xy 369.7303 -249.447043) (xy 369.753882 -249.493318)
			(xy 369.769935 -249.542713) (xy 369.778063 -249.59401) (xy 369.778066 -249.645947) (xy 369.778059 -249.645991)
			(xy 370.057935 -249.645991) (xy 370.057935 -249.594057) (xy 370.06606 -249.542762) (xy 370.082108 -249.493369)
			(xy 370.105686 -249.447095) (xy 370.136212 -249.405079) (xy 370.172935 -249.368356) (xy 370.214951 -249.33783)
			(xy 370.261225 -249.314252) (xy 370.310618 -249.298204) (xy 370.361913 -249.290079) (xy 370.413847 -249.290079)
			(xy 370.465142 -249.298204) (xy 370.514535 -249.314252) (xy 370.560809 -249.33783) (xy 370.602825 -249.368356)
			(xy 370.639548 -249.405079) (xy 370.670074 -249.447095) (xy 370.693652 -249.493369) (xy 370.7097 -249.542762)
			(xy 370.717825 -249.594057) (xy 370.718334 -249.620024) (xy 370.717825 -249.645991) (xy 370.7097 -249.697286)
			(xy 370.693652 -249.746679) (xy 370.670074 -249.792953) (xy 370.639548 -249.834969) (xy 370.602825 -249.871692)
			(xy 370.560809 -249.902218) (xy 370.514535 -249.925796) (xy 370.465142 -249.941844) (xy 370.413847 -249.949969)
			(xy 370.361913 -249.949969) (xy 370.310618 -249.941844) (xy 370.261225 -249.925796) (xy 370.214951 -249.902218)
			(xy 370.172935 -249.871692) (xy 370.136212 -249.834969) (xy 370.105686 -249.792953) (xy 370.082108 -249.746679)
			(xy 370.06606 -249.697286) (xy 370.057935 -249.645991) (xy 369.778059 -249.645991) (xy 369.769945 -249.697246)
			(xy 369.753899 -249.746642) (xy 369.730323 -249.792921) (xy 369.699797 -249.834941) (xy 369.663074 -249.871669)
			(xy 369.621058 -249.902199) (xy 369.574783 -249.925782) (xy 369.525389 -249.941835) (xy 369.474091 -249.949963)
			(xy 369.422154 -249.949966) (xy 369.370855 -249.941845) (xy 369.321459 -249.925799) (xy 369.275181 -249.902223)
			(xy 369.23316 -249.871698) (xy 369.196432 -249.834975) (xy 369.165901 -249.792959) (xy 369.142319 -249.746684)
			(xy 369.126266 -249.69729) (xy 369.118137 -249.645993) (xy 369.117626 -249.620024) (xy 369.117866 -249.602293)
			(xy 369.121684 -249.567037) (xy 369.125246 -249.549666) (xy 369.127798 -249.535247) (xy 369.125672 -249.50606)
			(xy 369.115358 -249.478674) (xy 369.097703 -249.455335) (xy 369.074155 -249.43796) (xy 369.046648 -249.427973)
			(xy 369.017438 -249.426195) (xy 369.003072 -249.429016) (xy 368.984784 -249.432954) (xy 368.94761 -249.437154)
			(xy 368.928904 -249.437398) (xy 368.902934 -249.436875) (xy 368.851632 -249.42875) (xy 368.802234 -249.4127)
			(xy 368.755954 -249.389119) (xy 368.713933 -249.358589) (xy 368.677206 -249.321861) (xy 368.646677 -249.279839)
			(xy 368.623097 -249.233559) (xy 368.607048 -249.18416) (xy 368.598924 -249.132858) (xy 367.667546 -249.132858)
			(xy 368.342418 -249.80773) (xy 368.342418 -251.44095) (xy 368.58575 -251.44095) (xy 368.586195 -251.416398)
			(xy 368.593435 -251.367832) (xy 368.607778 -251.32087) (xy 368.628909 -251.276546) (xy 368.656362 -251.235835)
			(xy 368.672618 -251.21743) (xy 368.682369 -251.205901) (xy 368.695383 -251.178677) (xy 368.699859 -251.148837)
			(xy 368.695404 -251.118993) (xy 368.682411 -251.09176) (xy 368.672618 -251.08027) (xy 368.656373 -251.061854)
			(xy 368.628903 -251.021153) (xy 368.607761 -250.976833) (xy 368.593415 -250.929871) (xy 368.586181 -250.881302)
			(xy 368.58575 -250.85675) (xy 368.586259 -250.830783) (xy 368.594384 -250.779488) (xy 368.610432 -250.730095)
			(xy 368.63401 -250.683821) (xy 368.664536 -250.641805) (xy 368.701259 -250.605082) (xy 368.743275 -250.574556)
			(xy 368.789549 -250.550978) (xy 368.838942 -250.53493) (xy 368.890237 -250.526805) (xy 368.942171 -250.526805)
			(xy 368.993466 -250.53493) (xy 369.042859 -250.550978) (xy 369.089133 -250.574556) (xy 369.131149 -250.605082)
			(xy 369.167872 -250.641805) (xy 369.198398 -250.683821) (xy 369.221976 -250.730095) (xy 369.238024 -250.779488)
			(xy 369.246149 -250.830783) (xy 369.246658 -250.85675) (xy 369.246211 -250.881302) (xy 369.238971 -250.929868)
			(xy 369.224628 -250.976829) (xy 369.203498 -251.021154) (xy 369.176046 -251.061865) (xy 369.15979 -251.08027)
			(xy 369.14994 -251.091722) (xy 369.136937 -251.118973) (xy 369.132479 -251.148837) (xy 369.136958 -251.178698)
			(xy 369.149982 -251.205939) (xy 369.15979 -251.21743) (xy 369.176036 -251.235845) (xy 369.203506 -251.276546)
			(xy 369.224647 -251.320867) (xy 369.238993 -251.367829) (xy 369.246227 -251.416397) (xy 369.246658 -251.44095)
			(xy 369.246149 -251.466917) (xy 369.238024 -251.518212) (xy 369.221976 -251.567605) (xy 369.198398 -251.613879)
			(xy 369.167872 -251.655895) (xy 369.131149 -251.692618) (xy 369.089133 -251.723144) (xy 369.042859 -251.746722)
			(xy 368.993466 -251.76277) (xy 368.942171 -251.770895) (xy 368.890237 -251.770895) (xy 368.838942 -251.76277)
			(xy 368.789549 -251.746722) (xy 368.743275 -251.723144) (xy 368.701259 -251.692618) (xy 368.664536 -251.655895)
			(xy 368.63401 -251.613879) (xy 368.610432 -251.567605) (xy 368.594384 -251.518212) (xy 368.586259 -251.466917)
			(xy 368.58575 -251.44095) (xy 368.342418 -251.44095) (xy 368.342418 -253.19355) (xy 368.58575 -253.19355)
			(xy 368.586195 -253.168998) (xy 368.593435 -253.120432) (xy 368.607778 -253.07347) (xy 368.628909 -253.029146)
			(xy 368.656362 -252.988435) (xy 368.672618 -252.97003) (xy 368.682369 -252.958501) (xy 368.695383 -252.931277)
			(xy 368.699859 -252.901437) (xy 368.695404 -252.871593) (xy 368.682411 -252.84436) (xy 368.672618 -252.83287)
			(xy 368.656373 -252.814454) (xy 368.628903 -252.773753) (xy 368.607761 -252.729433) (xy 368.593415 -252.682471)
			(xy 368.586181 -252.633902) (xy 368.58575 -252.60935) (xy 368.586259 -252.583383) (xy 368.594384 -252.532088)
			(xy 368.610432 -252.482695) (xy 368.63401 -252.436421) (xy 368.664536 -252.394405) (xy 368.701259 -252.357682)
			(xy 368.743275 -252.327156) (xy 368.789549 -252.303578) (xy 368.838942 -252.28753) (xy 368.890237 -252.279405)
			(xy 368.942171 -252.279405) (xy 368.993466 -252.28753) (xy 369.042859 -252.303578) (xy 369.089133 -252.327156)
			(xy 369.131149 -252.357682) (xy 369.167872 -252.394405) (xy 369.198398 -252.436421) (xy 369.221976 -252.482695)
			(xy 369.238024 -252.532088) (xy 369.246149 -252.583383) (xy 369.246658 -252.60935) (xy 369.246211 -252.633902)
			(xy 369.238971 -252.682468) (xy 369.224628 -252.729429) (xy 369.203498 -252.773754) (xy 369.176046 -252.814465)
			(xy 369.15979 -252.83287) (xy 369.14994 -252.844322) (xy 369.136937 -252.871573) (xy 369.132479 -252.901437)
			(xy 369.136958 -252.931298) (xy 369.149982 -252.958539) (xy 369.15979 -252.97003) (xy 369.176036 -252.988445)
			(xy 369.203506 -253.029146) (xy 369.224647 -253.073467) (xy 369.238993 -253.120429) (xy 369.246227 -253.168997)
			(xy 369.246658 -253.19355) (xy 369.246149 -253.219517) (xy 369.238024 -253.270812) (xy 369.221976 -253.320205)
			(xy 369.198398 -253.366479) (xy 369.167872 -253.408495) (xy 369.131149 -253.445218) (xy 369.089133 -253.475744)
			(xy 369.042859 -253.499322) (xy 368.993466 -253.51537) (xy 368.942171 -253.523495) (xy 368.890237 -253.523495)
			(xy 368.838942 -253.51537) (xy 368.789549 -253.499322) (xy 368.743275 -253.475744) (xy 368.701259 -253.445218)
			(xy 368.664536 -253.408495) (xy 368.63401 -253.366479) (xy 368.610432 -253.320205) (xy 368.594384 -253.270812)
			(xy 368.586259 -253.219517) (xy 368.58575 -253.19355) (xy 368.342418 -253.19355) (xy 368.342418 -253.945703)
			(xy 369.698271 -253.945703) (xy 369.698271 -253.893769) (xy 369.706396 -253.842474) (xy 369.722444 -253.793081)
			(xy 369.746022 -253.746807) (xy 369.776548 -253.704791) (xy 369.813271 -253.668068) (xy 369.855287 -253.637542)
			(xy 369.901561 -253.613964) (xy 369.950954 -253.597916) (xy 370.002249 -253.589791) (xy 370.054183 -253.589791)
			(xy 370.105478 -253.597916) (xy 370.154871 -253.613964) (xy 370.201145 -253.637542) (xy 370.243161 -253.668068)
			(xy 370.279884 -253.704791) (xy 370.31041 -253.746807) (xy 370.333988 -253.793081) (xy 370.350036 -253.842474)
			(xy 370.358161 -253.893769) (xy 370.35867 -253.919736) (xy 370.358161 -253.945703) (xy 370.350036 -253.996998)
			(xy 370.333988 -254.046391) (xy 370.31041 -254.092665) (xy 370.279884 -254.134681) (xy 370.243161 -254.171404)
			(xy 370.201145 -254.20193) (xy 370.154871 -254.225508) (xy 370.105478 -254.241556) (xy 370.054183 -254.249681)
			(xy 370.002249 -254.249681) (xy 369.950954 -254.241556) (xy 369.901561 -254.225508) (xy 369.855287 -254.20193)
			(xy 369.813271 -254.171404) (xy 369.776548 -254.134681) (xy 369.746022 -254.092665) (xy 369.722444 -254.046391)
			(xy 369.706396 -253.996998) (xy 369.698271 -253.945703) (xy 368.342418 -253.945703) (xy 368.342418 -254.52451)
			(xy 368.136678 -254.73025) (xy 368.136678 -255.53035) (xy 368.58575 -255.53035) (xy 368.586195 -255.505798)
			(xy 368.593435 -255.457232) (xy 368.607778 -255.41027) (xy 368.628909 -255.365946) (xy 368.656362 -255.325235)
			(xy 368.672618 -255.30683) (xy 368.682369 -255.295301) (xy 368.695383 -255.268077) (xy 368.699859 -255.238237)
			(xy 368.695404 -255.208393) (xy 368.682411 -255.18116) (xy 368.672618 -255.16967) (xy 368.656373 -255.151254)
			(xy 368.628903 -255.110553) (xy 368.607761 -255.066233) (xy 368.593415 -255.019271) (xy 368.586181 -254.970702)
			(xy 368.58575 -254.94615) (xy 368.586209 -254.920181) (xy 368.594341 -254.868884) (xy 368.610397 -254.81949)
			(xy 368.633981 -254.773216) (xy 368.664513 -254.731201) (xy 368.701242 -254.694478) (xy 368.743262 -254.663953)
			(xy 368.78954 -254.640376) (xy 368.838937 -254.624328) (xy 368.890235 -254.616205) (xy 368.916204 -254.615696)
			(xy 368.940134 -254.616117) (xy 368.987493 -254.623027) (xy 369.033362 -254.636687) (xy 369.076785 -254.656812)
			(xy 369.097052 -254.669544) (xy 369.110119 -254.677397) (xy 369.139424 -254.68575) (xy 369.169889 -254.685101)
			(xy 369.198811 -254.675506) (xy 369.223623 -254.657817) (xy 369.242123 -254.633604) (xy 369.247928 -254.619506)
			(xy 369.257023 -254.596023) (xy 369.28137 -254.551943) (xy 369.312125 -254.512068) (xy 369.348574 -254.477321)
			(xy 369.389873 -254.448508) (xy 369.435067 -254.426296) (xy 369.483108 -254.411199) (xy 369.532883 -254.403567)
			(xy 369.558062 -254.403098) (xy 369.584029 -254.403674) (xy 369.635326 -254.411793) (xy 369.68472 -254.427837)
			(xy 369.730996 -254.451411) (xy 369.773015 -254.481935) (xy 369.80974 -254.518656) (xy 369.840269 -254.560671)
			(xy 369.863848 -254.606945) (xy 369.879898 -254.656337) (xy 369.888023 -254.707633) (xy 369.888023 -254.759567)
			(xy 369.879898 -254.810863) (xy 369.863848 -254.860255) (xy 369.840269 -254.906529) (xy 369.80974 -254.948544)
			(xy 369.773015 -254.985265) (xy 369.730996 -255.015789) (xy 369.68472 -255.039363) (xy 369.635326 -255.055407)
			(xy 369.584029 -255.063526) (xy 369.558062 -255.064006) (xy 369.534133 -255.063553) (xy 369.486776 -255.056653)
			(xy 369.440906 -255.043002) (xy 369.397482 -255.022886) (xy 369.377214 -255.010158) (xy 369.364169 -255.002264)
			(xy 369.334856 -254.993916) (xy 369.304384 -254.994572) (xy 369.275458 -255.004175) (xy 369.250643 -255.021873)
			(xy 369.232143 -255.046094) (xy 369.226338 -255.060196) (xy 369.218629 -255.080266) (xy 369.198733 -255.118379)
			(xy 369.174055 -255.153585) (xy 369.15979 -255.16967) (xy 369.14994 -255.181122) (xy 369.136937 -255.208373)
			(xy 369.132479 -255.238237) (xy 369.136958 -255.268098) (xy 369.149982 -255.295339) (xy 369.15979 -255.30683)
			(xy 369.176036 -255.325245) (xy 369.203506 -255.365946) (xy 369.224647 -255.410267) (xy 369.238993 -255.457229)
			(xy 369.246227 -255.505797) (xy 369.246658 -255.53035) (xy 369.246149 -255.556317) (xy 369.238024 -255.607612)
			(xy 369.221976 -255.657005) (xy 369.198398 -255.703279) (xy 369.167872 -255.745295) (xy 369.131149 -255.782018)
			(xy 369.089133 -255.812544) (xy 369.042859 -255.836122) (xy 368.993466 -255.85217) (xy 368.942171 -255.860295)
			(xy 368.890237 -255.860295) (xy 368.838942 -255.85217) (xy 368.789549 -255.836122) (xy 368.743275 -255.812544)
			(xy 368.701259 -255.782018) (xy 368.664536 -255.745295) (xy 368.63401 -255.703279) (xy 368.610432 -255.657005)
			(xy 368.594384 -255.607612) (xy 368.586259 -255.556317) (xy 368.58575 -255.53035) (xy 368.136678 -255.53035)
			(xy 368.136678 -258.015037) (xy 370.167917 -258.015037) (xy 370.167917 -257.963103) (xy 370.176042 -257.911808)
			(xy 370.19209 -257.862415) (xy 370.215668 -257.816141) (xy 370.246194 -257.774125) (xy 370.282917 -257.737402)
			(xy 370.324933 -257.706876) (xy 370.371207 -257.683298) (xy 370.4206 -257.66725) (xy 370.471895 -257.659125)
			(xy 370.523829 -257.659125) (xy 370.575124 -257.66725) (xy 370.624517 -257.683298) (xy 370.670791 -257.706876)
			(xy 370.712807 -257.737402) (xy 370.74953 -257.774125) (xy 370.780056 -257.816141) (xy 370.803634 -257.862415)
			(xy 370.819682 -257.911808) (xy 370.827807 -257.963103) (xy 370.828316 -257.98907) (xy 370.827807 -258.015037)
			(xy 370.819682 -258.066332) (xy 370.803634 -258.115725) (xy 370.780056 -258.161999) (xy 370.74953 -258.204015)
			(xy 370.712807 -258.240738) (xy 370.670791 -258.271264) (xy 370.624517 -258.294842) (xy 370.575124 -258.31089)
			(xy 370.523829 -258.319015) (xy 370.471895 -258.319015) (xy 370.4206 -258.31089) (xy 370.371207 -258.294842)
			(xy 370.324933 -258.271264) (xy 370.282917 -258.240738) (xy 370.246194 -258.204015) (xy 370.215668 -258.161999)
			(xy 370.19209 -258.115725) (xy 370.176042 -258.066332) (xy 370.167917 -258.015037) (xy 368.136678 -258.015037)
			(xy 368.136678 -258.477317) (xy 368.586259 -258.477317) (xy 368.586259 -258.425383) (xy 368.594384 -258.374088)
			(xy 368.610432 -258.324695) (xy 368.63401 -258.278421) (xy 368.664536 -258.236405) (xy 368.701259 -258.199682)
			(xy 368.743275 -258.169156) (xy 368.789549 -258.145578) (xy 368.838942 -258.12953) (xy 368.890237 -258.121405)
			(xy 368.942171 -258.121405) (xy 368.993466 -258.12953) (xy 369.042859 -258.145578) (xy 369.089133 -258.169156)
			(xy 369.131149 -258.199682) (xy 369.167872 -258.236405) (xy 369.198398 -258.278421) (xy 369.221976 -258.324695)
			(xy 369.238024 -258.374088) (xy 369.246149 -258.425383) (xy 369.246658 -258.45135) (xy 369.246149 -258.477317)
			(xy 369.238024 -258.528612) (xy 369.221976 -258.578005) (xy 369.198398 -258.624279) (xy 369.167872 -258.666295)
			(xy 369.131149 -258.703018) (xy 369.089133 -258.733544) (xy 369.042859 -258.757122) (xy 368.993466 -258.77317)
			(xy 368.942171 -258.781295) (xy 368.890237 -258.781295) (xy 368.838942 -258.77317) (xy 368.789549 -258.757122)
			(xy 368.743275 -258.733544) (xy 368.701259 -258.703018) (xy 368.664536 -258.666295) (xy 368.63401 -258.624279)
			(xy 368.610432 -258.578005) (xy 368.594384 -258.528612) (xy 368.586259 -258.477317) (xy 368.136678 -258.477317)
			(xy 368.136678 -258.829107) (xy 370.637817 -258.829107) (xy 370.637817 -258.777173) (xy 370.645942 -258.725878)
			(xy 370.66199 -258.676485) (xy 370.685568 -258.630211) (xy 370.716094 -258.588195) (xy 370.752817 -258.551472)
			(xy 370.794833 -258.520946) (xy 370.841107 -258.497368) (xy 370.8905 -258.48132) (xy 370.941795 -258.473195)
			(xy 370.993729 -258.473195) (xy 371.045024 -258.48132) (xy 371.094417 -258.497368) (xy 371.140691 -258.520946)
			(xy 371.182707 -258.551472) (xy 371.21943 -258.588195) (xy 371.249956 -258.630211) (xy 371.273534 -258.676485)
			(xy 371.289582 -258.725878) (xy 371.297707 -258.777173) (xy 371.298216 -258.80314) (xy 371.297707 -258.829107)
			(xy 371.289582 -258.880402) (xy 371.273534 -258.929795) (xy 371.249956 -258.976069) (xy 371.21943 -259.018085)
			(xy 371.182707 -259.054808) (xy 371.140691 -259.085334) (xy 371.094417 -259.108912) (xy 371.045024 -259.12496)
			(xy 370.993729 -259.133085) (xy 370.941795 -259.133085) (xy 370.8905 -259.12496) (xy 370.841107 -259.108912)
			(xy 370.794833 -259.085334) (xy 370.752817 -259.054808) (xy 370.716094 -259.018085) (xy 370.685568 -258.976069)
			(xy 370.66199 -258.929795) (xy 370.645942 -258.880402) (xy 370.637817 -258.829107) (xy 368.136678 -258.829107)
			(xy 368.136678 -259.44957) (xy 368.419126 -259.732018) (xy 368.429091 -259.741379) (xy 368.452838 -259.754906)
			(xy 368.479325 -259.761642) (xy 368.506649 -259.761105) (xy 368.53285 -259.753333) (xy 368.556048 -259.738883)
			(xy 368.574577 -259.718793) (xy 368.587107 -259.694505) (xy 368.590322 -259.681218) (xy 368.595933 -259.65681)
			(xy 368.613526 -259.609923) (xy 368.637993 -259.566226) (xy 368.668773 -259.526722) (xy 368.705161 -259.492314)
			(xy 368.746325 -259.46379) (xy 368.79132 -259.441804) (xy 368.839118 -259.42686) (xy 368.888624 -259.419298)
			(xy 368.913664 -259.418836) (xy 368.939635 -259.419316) (xy 368.99094 -259.427437) (xy 369.040341 -259.443483)
			(xy 369.086625 -259.467061) (xy 369.12865 -259.497589) (xy 369.165381 -259.534315) (xy 369.195915 -259.576336)
			(xy 369.219499 -259.622616) (xy 369.226098 -259.642923) (xy 370.167917 -259.642923) (xy 370.167917 -259.590989)
			(xy 370.176042 -259.539694) (xy 370.19209 -259.490301) (xy 370.215668 -259.444027) (xy 370.246194 -259.402011)
			(xy 370.282917 -259.365288) (xy 370.324933 -259.334762) (xy 370.371207 -259.311184) (xy 370.4206 -259.295136)
			(xy 370.471895 -259.287011) (xy 370.523829 -259.287011) (xy 370.575124 -259.295136) (xy 370.624517 -259.311184)
			(xy 370.670791 -259.334762) (xy 370.712807 -259.365288) (xy 370.74953 -259.402011) (xy 370.780056 -259.444027)
			(xy 370.803634 -259.490301) (xy 370.819682 -259.539694) (xy 370.827807 -259.590989) (xy 370.828316 -259.616956)
			(xy 370.827807 -259.642923) (xy 371.107717 -259.642923) (xy 371.107717 -259.590989) (xy 371.115842 -259.539694)
			(xy 371.13189 -259.490301) (xy 371.155468 -259.444027) (xy 371.185994 -259.402011) (xy 371.222717 -259.365288)
			(xy 371.264733 -259.334762) (xy 371.311007 -259.311184) (xy 371.3604 -259.295136) (xy 371.411695 -259.287011)
			(xy 371.463629 -259.287011) (xy 371.514924 -259.295136) (xy 371.564317 -259.311184) (xy 371.610591 -259.334762)
			(xy 371.652607 -259.365288) (xy 371.68933 -259.402011) (xy 371.719856 -259.444027) (xy 371.743434 -259.490301)
			(xy 371.759482 -259.539694) (xy 371.767607 -259.590989) (xy 371.768116 -259.616956) (xy 371.767607 -259.642923)
			(xy 371.759482 -259.694218) (xy 371.743434 -259.743611) (xy 371.719856 -259.789885) (xy 371.68933 -259.831901)
			(xy 371.652607 -259.868624) (xy 371.610591 -259.89915) (xy 371.564317 -259.922728) (xy 371.514924 -259.938776)
			(xy 371.463629 -259.946901) (xy 371.411695 -259.946901) (xy 371.3604 -259.938776) (xy 371.311007 -259.922728)
			(xy 371.264733 -259.89915) (xy 371.222717 -259.868624) (xy 371.185994 -259.831901) (xy 371.155468 -259.789885)
			(xy 371.13189 -259.743611) (xy 371.115842 -259.694218) (xy 371.107717 -259.642923) (xy 370.827807 -259.642923)
			(xy 370.819682 -259.694218) (xy 370.803634 -259.743611) (xy 370.780056 -259.789885) (xy 370.74953 -259.831901)
			(xy 370.712807 -259.868624) (xy 370.670791 -259.89915) (xy 370.624517 -259.922728) (xy 370.575124 -259.938776)
			(xy 370.523829 -259.946901) (xy 370.471895 -259.946901) (xy 370.4206 -259.938776) (xy 370.371207 -259.922728)
			(xy 370.324933 -259.89915) (xy 370.282917 -259.868624) (xy 370.246194 -259.831901) (xy 370.215668 -259.789885)
			(xy 370.19209 -259.743611) (xy 370.176042 -259.694218) (xy 370.167917 -259.642923) (xy 369.226098 -259.642923)
			(xy 369.235553 -259.672016) (xy 369.24368 -259.723319) (xy 369.244118 -259.74929) (xy 369.243629 -259.774378)
			(xy 369.235997 -259.823972) (xy 369.220951 -259.87184) (xy 369.210336 -259.894578) (xy 369.205256 -259.905246)
			(xy 369.205256 -259.96773) (xy 369.284758 -259.96773) (xy 369.317778 -260.00075) (xy 369.317778 -260.456739)
			(xy 369.698271 -260.456739) (xy 369.698271 -260.404805) (xy 369.706396 -260.35351) (xy 369.722444 -260.304117)
			(xy 369.746022 -260.257843) (xy 369.776548 -260.215827) (xy 369.813271 -260.179104) (xy 369.855287 -260.148578)
			(xy 369.901561 -260.125) (xy 369.950954 -260.108952) (xy 370.002249 -260.100827) (xy 370.054183 -260.100827)
			(xy 370.105478 -260.108952) (xy 370.154871 -260.125) (xy 370.201145 -260.148578) (xy 370.243161 -260.179104)
			(xy 370.279884 -260.215827) (xy 370.31041 -260.257843) (xy 370.333988 -260.304117) (xy 370.350036 -260.35351)
			(xy 370.358161 -260.404805) (xy 370.35867 -260.430772) (xy 370.358161 -260.456739) (xy 370.638071 -260.456739)
			(xy 370.638071 -260.404805) (xy 370.646196 -260.35351) (xy 370.662244 -260.304117) (xy 370.685822 -260.257843)
			(xy 370.716348 -260.215827) (xy 370.753071 -260.179104) (xy 370.795087 -260.148578) (xy 370.841361 -260.125)
			(xy 370.890754 -260.108952) (xy 370.942049 -260.100827) (xy 370.993983 -260.100827) (xy 371.045278 -260.108952)
			(xy 371.094671 -260.125) (xy 371.140945 -260.148578) (xy 371.182961 -260.179104) (xy 371.219684 -260.215827)
			(xy 371.25021 -260.257843) (xy 371.273788 -260.304117) (xy 371.289836 -260.35351) (xy 371.297961 -260.404805)
			(xy 371.29847 -260.430772) (xy 371.297961 -260.456739) (xy 371.289836 -260.508034) (xy 371.273788 -260.557427)
			(xy 371.25021 -260.603701) (xy 371.219684 -260.645717) (xy 371.182961 -260.68244) (xy 371.140945 -260.712966)
			(xy 371.094671 -260.736544) (xy 371.045278 -260.752592) (xy 370.993983 -260.760717) (xy 370.942049 -260.760717)
			(xy 370.890754 -260.752592) (xy 370.841361 -260.736544) (xy 370.795087 -260.712966) (xy 370.753071 -260.68244)
			(xy 370.716348 -260.645717) (xy 370.685822 -260.603701) (xy 370.662244 -260.557427) (xy 370.646196 -260.508034)
			(xy 370.638071 -260.456739) (xy 370.358161 -260.456739) (xy 370.350036 -260.508034) (xy 370.333988 -260.557427)
			(xy 370.31041 -260.603701) (xy 370.279884 -260.645717) (xy 370.243161 -260.68244) (xy 370.201145 -260.712966)
			(xy 370.154871 -260.736544) (xy 370.105478 -260.752592) (xy 370.054183 -260.760717) (xy 370.002249 -260.760717)
			(xy 369.950954 -260.752592) (xy 369.901561 -260.736544) (xy 369.855287 -260.712966) (xy 369.813271 -260.68244)
			(xy 369.776548 -260.645717) (xy 369.746022 -260.603701) (xy 369.722444 -260.557427) (xy 369.706396 -260.508034)
			(xy 369.698271 -260.456739) (xy 369.317778 -260.456739) (xy 369.317778 -261.270809) (xy 370.167917 -261.270809)
			(xy 370.167917 -261.218875) (xy 370.176042 -261.16758) (xy 370.19209 -261.118187) (xy 370.215668 -261.071913)
			(xy 370.246194 -261.029897) (xy 370.282917 -260.993174) (xy 370.324933 -260.962648) (xy 370.371207 -260.93907)
			(xy 370.4206 -260.923022) (xy 370.471895 -260.914897) (xy 370.523829 -260.914897) (xy 370.575124 -260.923022)
			(xy 370.624517 -260.93907) (xy 370.670791 -260.962648) (xy 370.712807 -260.993174) (xy 370.74953 -261.029897)
			(xy 370.780056 -261.071913) (xy 370.803634 -261.118187) (xy 370.819682 -261.16758) (xy 370.827807 -261.218875)
			(xy 370.828316 -261.244842) (xy 370.827807 -261.270809) (xy 370.819682 -261.322104) (xy 370.803634 -261.371497)
			(xy 370.780056 -261.417771) (xy 370.74953 -261.459787) (xy 370.712807 -261.49651) (xy 370.670791 -261.527036)
			(xy 370.624517 -261.550614) (xy 370.575124 -261.566662) (xy 370.523829 -261.574787) (xy 370.471895 -261.574787)
			(xy 370.4206 -261.566662) (xy 370.371207 -261.550614) (xy 370.324933 -261.527036) (xy 370.282917 -261.49651)
			(xy 370.246194 -261.459787) (xy 370.215668 -261.417771) (xy 370.19209 -261.371497) (xy 370.176042 -261.322104)
			(xy 370.167917 -261.270809) (xy 369.317778 -261.270809) (xy 369.317778 -261.46887) (xy 369.632738 -261.78383)
		)
		(stroke
			(width 0)
			(type solid)
		)
		(fill yes)
		(layer "In6.Cu")
		(net "PVCCD_HV_CPU0")
	)
	(gr_poly
		(pts
			(xy 122.296936 -261.451852) (xy 122.276108 -261.417562) (xy 122.264544 -261.397991) (xy 122.246311 -261.35635)
			(xy 122.233963 -261.312601) (xy 122.227734 -261.267571) (xy 122.22734 -261.244842) (xy 122.227849 -261.218875)
			(xy 122.235974 -261.16758) (xy 122.252022 -261.118187) (xy 122.2756 -261.071913) (xy 122.306126 -261.029897)
			(xy 122.342849 -260.993174) (xy 122.384865 -260.962648) (xy 122.431139 -260.93907) (xy 122.480532 -260.923022)
			(xy 122.531827 -260.914897) (xy 122.583761 -260.914897) (xy 122.635056 -260.923022) (xy 122.684449 -260.93907)
			(xy 122.730723 -260.962648) (xy 122.772739 -260.993174) (xy 122.809462 -261.029897) (xy 122.839988 -261.071913)
			(xy 122.863566 -261.118187) (xy 122.879614 -261.16758) (xy 122.887739 -261.218875) (xy 122.888248 -261.244842)
			(xy 122.887708 -261.272145) (xy 122.878773 -261.326015) (xy 122.870468 -261.35203) (xy 122.866423 -261.365247)
			(xy 122.864794 -261.392829) (xy 122.870621 -261.419837) (xy 122.883475 -261.444295) (xy 122.902416 -261.464411)
			(xy 122.926056 -261.478712) (xy 122.952666 -261.486151) (xy 122.96648 -261.48665) (xy 123.088908 -261.48665)
			(xy 123.102739 -261.486198) (xy 123.129391 -261.478792) (xy 123.153074 -261.464499) (xy 123.172047 -261.444369)
			(xy 123.184915 -261.419883) (xy 123.190734 -261.39284) (xy 123.189074 -261.365228) (xy 123.18492 -261.35203)
			(xy 123.176617 -261.326015) (xy 123.167682 -261.272145) (xy 123.16714 -261.244842) (xy 123.16762 -261.21887)
			(xy 123.175739 -261.167566) (xy 123.191786 -261.118163) (xy 123.215363 -261.071879) (xy 123.245891 -261.029854)
			(xy 123.282617 -260.993122) (xy 123.324638 -260.962588) (xy 123.370919 -260.939004) (xy 123.420319 -260.922951)
			(xy 123.471622 -260.914823) (xy 123.497594 -260.914388) (xy 123.515 -260.914624) (xy 123.549618 -260.918312)
			(xy 123.566682 -260.921754) (xy 123.581578 -260.924387) (xy 123.611703 -260.921802) (xy 123.639752 -260.910516)
			(xy 123.663271 -260.891516) (xy 123.6802 -260.866465) (xy 123.689059 -260.837557) (xy 123.689618 -260.82244)
			(xy 123.689618 -260.609334) (xy 123.677204 -260.58927) (xy 123.657618 -260.546346) (xy 123.644349 -260.501069)
			(xy 123.63767 -260.454363) (xy 123.637294 -260.430772) (xy 123.63772 -260.407186) (xy 123.644431 -260.360495)
			(xy 123.657698 -260.315227) (xy 123.677255 -260.2723) (xy 123.689618 -260.25221) (xy 123.689618 -260.039358)
			(xy 123.689075 -260.02423) (xy 123.680232 -259.995296) (xy 123.663306 -259.970218) (xy 123.639778 -259.951196)
			(xy 123.611712 -259.939897) (xy 123.581568 -259.937311) (xy 123.566682 -259.940044) (xy 123.549616 -259.943477)
			(xy 123.515 -259.947169) (xy 123.497594 -259.94741) (xy 123.471631 -259.9469) (xy 123.420343 -259.938776)
			(xy 123.370958 -259.922729) (xy 123.324691 -259.899154) (xy 123.282681 -259.868632) (xy 123.245964 -259.831914)
			(xy 123.215442 -259.789904) (xy 123.191868 -259.743637) (xy 123.175822 -259.694251) (xy 123.167699 -259.642963)
			(xy 123.167699 -259.591037) (xy 123.175822 -259.539749) (xy 123.191868 -259.490363) (xy 123.215442 -259.444096)
			(xy 123.245964 -259.402086) (xy 123.282681 -259.365368) (xy 123.324691 -259.334846) (xy 123.370958 -259.311271)
			(xy 123.420343 -259.295224) (xy 123.471631 -259.2871) (xy 123.497594 -259.286502) (xy 123.515 -259.286738)
			(xy 123.549618 -259.290426) (xy 123.566682 -259.293868) (xy 123.581579 -259.296501) (xy 123.611704 -259.293916)
			(xy 123.639755 -259.28263) (xy 123.663276 -259.26363) (xy 123.680209 -259.23858) (xy 123.689071 -259.209672)
			(xy 123.689618 -259.194554) (xy 123.689618 -258.981702) (xy 123.67763 -258.962358) (xy 123.65851 -258.921062)
			(xy 123.651518 -258.899406) (xy 123.647962 -258.887214) (xy 123.529852 -258.769104) (xy 123.519299 -258.759242)
			(xy 123.493998 -258.745336) (xy 123.465814 -258.739074) (xy 123.437005 -258.740958) (xy 123.409877 -258.750836)
			(xy 123.386602 -258.767919) (xy 123.369045 -258.790837) (xy 123.358611 -258.817756) (xy 123.356878 -258.832096)
			(xy 123.354283 -258.856477) (xy 123.342812 -258.904144) (xy 123.324424 -258.949594) (xy 123.299522 -258.991828)
			(xy 123.268654 -259.029919) (xy 123.232496 -259.063031) (xy 123.191843 -259.090437) (xy 123.147587 -259.111536)
			(xy 123.100699 -259.125864) (xy 123.052208 -259.133107) (xy 123.027694 -259.133594) (xy 123.001726 -259.133084)
			(xy 122.950429 -259.12496) (xy 122.901035 -259.108911) (xy 122.854759 -259.085333) (xy 122.812741 -259.054808)
			(xy 122.776014 -259.018085) (xy 122.745484 -258.97607) (xy 122.721902 -258.929797) (xy 122.705848 -258.880404)
			(xy 122.697718 -258.829108) (xy 122.69724 -258.80314) (xy 122.697683 -258.778622) (xy 122.704923 -258.730123)
			(xy 122.719251 -258.683227) (xy 122.740351 -258.638963) (xy 122.767761 -258.598303) (xy 122.800878 -258.56214)
			(xy 122.838975 -258.531267) (xy 122.881216 -258.506363) (xy 122.926674 -258.487975) (xy 122.97435 -258.476505)
			(xy 122.998738 -258.473956) (xy 123.013053 -258.472177) (xy 123.039913 -258.461692) (xy 123.062775 -258.444122)
			(xy 123.079818 -258.420864) (xy 123.089685 -258.393772) (xy 123.091591 -258.365001) (xy 123.085383 -258.336844)
			(xy 123.071557 -258.311542) (xy 123.06173 -258.300982) (xy 122.958352 -258.197604) (xy 122.948149 -258.188017)
			(xy 122.923736 -258.174335) (xy 122.896524 -258.167796) (xy 122.868559 -258.168892) (xy 122.841942 -258.177539)
			(xy 122.818674 -258.193089) (xy 122.809254 -258.203446) (xy 122.793479 -258.221308) (xy 122.757677 -258.252758)
			(xy 122.717729 -258.278741) (xy 122.674464 -258.298718) (xy 122.628779 -258.312275) (xy 122.581621 -258.319131)
			(xy 122.557794 -258.319524) (xy 122.531826 -258.319041) (xy 122.480529 -258.310915) (xy 122.431135 -258.294864)
			(xy 122.384861 -258.271284) (xy 122.342845 -258.240754) (xy 122.306122 -258.204028) (xy 122.275598 -258.162008)
			(xy 122.252022 -258.115731) (xy 122.235977 -258.066336) (xy 122.227856 -258.015038) (xy 122.22734 -257.98907)
			(xy 122.227759 -257.965245) (xy 122.23461 -257.918089) (xy 122.248164 -257.872407) (xy 122.268141 -257.829146)
			(xy 122.294125 -257.789204) (xy 122.325579 -257.75341) (xy 122.343418 -257.73761) (xy 122.353754 -257.728181)
			(xy 122.369269 -257.704911) (xy 122.377892 -257.678306) (xy 122.378979 -257.65036) (xy 122.372448 -257.623165)
			(xy 122.358787 -257.598761) (xy 122.34926 -257.588512) (xy 122.234198 -257.47345) (xy 122.203718 -257.48488)
			(xy 122.175819 -257.494597) (xy 122.117684 -257.505067) (xy 122.088148 -257.505708) (xy 122.062178 -257.505229)
			(xy 122.010875 -257.497109) (xy 121.961475 -257.481063) (xy 121.915194 -257.457485) (xy 121.873172 -257.426957)
			(xy 121.836445 -257.390229) (xy 121.805916 -257.348207) (xy 121.782338 -257.301927) (xy 121.766291 -257.252527)
			(xy 121.758171 -257.201224) (xy 121.757694 -257.175254) (xy 121.758351 -257.145721) (xy 121.768832 -257.087591)
			(xy 121.778522 -257.059684) (xy 121.789952 -257.029204) (xy 121.414286 -256.653538) (xy 121.392188 -256.636774)
			(xy 121.384603 -256.631112) (xy 121.366594 -256.625332) (xy 121.347714 -256.626476) (xy 121.330534 -256.634387)
			(xy 121.317391 -256.64799) (xy 121.310076 -256.665432) (xy 121.309384 -256.674874) (xy 121.308298 -256.700475)
			(xy 121.299196 -256.750899) (xy 121.282415 -256.799312) (xy 121.25836 -256.844552) (xy 121.227606 -256.885535)
			(xy 121.209562 -256.903728) (xy 121.200213 -256.913422) (xy 121.186525 -256.936604) (xy 121.179381 -256.962562)
			(xy 121.179281 -256.989484) (xy 121.18623 -257.015494) (xy 121.199745 -257.038778) (xy 121.209054 -257.048508)
			(xy 121.227251 -257.067244) (xy 121.258094 -257.109391) (xy 121.28192 -257.155866) (xy 121.298137 -257.205512)
			(xy 121.306339 -257.25709) (xy 121.306844 -257.283204) (xy 121.306335 -257.309171) (xy 121.29821 -257.360466)
			(xy 121.282162 -257.409859) (xy 121.258584 -257.456133) (xy 121.228058 -257.498149) (xy 121.191335 -257.534872)
			(xy 121.149319 -257.565398) (xy 121.103045 -257.588976) (xy 121.053652 -257.605024) (xy 121.002357 -257.613149)
			(xy 120.950423 -257.613149) (xy 120.899128 -257.605024) (xy 120.849735 -257.588976) (xy 120.803461 -257.565398)
			(xy 120.761445 -257.534872) (xy 120.724722 -257.498149) (xy 120.694196 -257.456133) (xy 120.670618 -257.409859)
			(xy 120.65457 -257.360466) (xy 120.646445 -257.309171) (xy 120.645936 -257.283204) (xy 120.646452 -257.256803)
			(xy 120.654845 -257.204673) (xy 120.671418 -257.15454) (xy 120.69575 -257.107679) (xy 120.727221 -257.065282)
			(xy 120.745758 -257.046476) (xy 120.755106 -257.036782) (xy 120.768793 -257.013598) (xy 120.775935 -256.987641)
			(xy 120.776037 -256.960719) (xy 120.769089 -256.934709) (xy 120.755578 -256.911423) (xy 120.746266 -256.901696)
			(xy 120.728068 -256.882961) (xy 120.697222 -256.840815) (xy 120.673394 -256.794339) (xy 120.657176 -256.744694)
			(xy 120.648973 -256.693114) (xy 120.648476 -256.667) (xy 120.648959 -256.641032) (xy 120.657084 -256.589734)
			(xy 120.673134 -256.54034) (xy 120.696714 -256.494064) (xy 120.727244 -256.452047) (xy 120.76397 -256.415324)
			(xy 120.80599 -256.384799) (xy 120.852267 -256.361223) (xy 120.901663 -256.345177) (xy 120.952962 -256.337057)
			(xy 120.97893 -256.336546) (xy 121.003873 -256.337003) (xy 121.053191 -256.344503) (xy 121.100822 -256.359329)
			(xy 121.123456 -256.36982) (xy 121.135661 -256.375316) (xy 121.161938 -256.380373) (xy 121.188625 -256.378419)
			(xy 121.213885 -256.369588) (xy 121.235976 -256.354488) (xy 121.253378 -256.33416) (xy 121.264891 -256.310004)
			(xy 121.267728 -256.296922) (xy 121.273226 -256.270101) (xy 121.291348 -256.218438) (xy 121.303796 -256.194052)
			(xy 121.309638 -256.182876) (xy 121.309638 -256.10439) (xy 122.3137 -255.100328) (xy 122.324383 -255.08887)
			(xy 122.338824 -255.061089) (xy 122.344177 -255.03024) (xy 122.339938 -254.999219) (xy 122.326507 -254.970936)
			(xy 122.31624 -254.959104) (xy 122.299615 -254.940646) (xy 122.271531 -254.899674) (xy 122.2499 -254.854957)
			(xy 122.23521 -254.807506) (xy 122.227792 -254.758389) (xy 122.22734 -254.733552) (xy 122.227853 -254.707587)
			(xy 122.235983 -254.656297) (xy 122.252036 -254.606911) (xy 122.275616 -254.560643) (xy 122.306143 -254.518633)
			(xy 122.342865 -254.481916) (xy 122.384879 -254.451394) (xy 122.43115 -254.42782) (xy 122.480538 -254.411773)
			(xy 122.531829 -254.40365) (xy 122.557794 -254.403098) (xy 122.582628 -254.403551) (xy 122.631737 -254.410993)
			(xy 122.67918 -254.425695) (xy 122.723891 -254.447328) (xy 122.764864 -254.475403) (xy 122.783346 -254.491998)
			(xy 122.795175 -254.502266) (xy 122.823451 -254.515704) (xy 122.85447 -254.519938) (xy 122.885313 -254.51457)
			(xy 122.913078 -254.500105) (xy 122.92457 -254.489458) (xy 122.945398 -254.46863) (xy 122.945398 -254.241808)
			(xy 122.912378 -254.229362) (xy 122.889028 -254.220168) (xy 122.845192 -254.195747) (xy 122.805552 -254.164978)
			(xy 122.77102 -254.128569) (xy 122.74239 -254.087358) (xy 122.72032 -254.042291) (xy 122.705318 -253.994406)
			(xy 122.697729 -253.944803) (xy 122.697727 -253.894622) (xy 122.705312 -253.845019) (xy 122.720311 -253.797132)
			(xy 122.742377 -253.752064) (xy 122.771004 -253.71085) (xy 122.805533 -253.674439) (xy 122.845171 -253.643667)
			(xy 122.889005 -253.619242) (xy 122.912378 -253.61011) (xy 122.945398 -253.597664) (xy 122.945398 -249.1867)
			(xy 122.944996 -249.177079) (xy 122.937902 -249.159194) (xy 122.924685 -249.14521) (xy 122.907228 -249.13712)
			(xy 122.897646 -249.136154) (xy 122.871438 -249.134052) (xy 122.820126 -249.122596) (xy 122.771274 -249.103163)
			(xy 122.726114 -249.076241) (xy 122.685785 -249.042511) (xy 122.651303 -249.002822) (xy 122.623539 -248.958176)
			(xy 122.603191 -248.909698) (xy 122.590774 -248.85861) (xy 122.5866 -248.8062) (xy 122.590774 -248.753791)
			(xy 122.603191 -248.702703) (xy 122.623538 -248.654225) (xy 122.651303 -248.609578) (xy 122.685784 -248.56989)
			(xy 122.726113 -248.536159) (xy 122.771273 -248.509238) (xy 122.820125 -248.489804) (xy 122.871437 -248.478348)
			(xy 122.897646 -248.476262) (xy 122.907212 -248.475263) (xy 122.924622 -248.467121) (xy 122.937829 -248.453158)
			(xy 122.944992 -248.435323) (xy 122.945398 -248.425716) (xy 122.945398 -247.95861) (xy 123.566174 -247.337834)
			(xy 123.552966 -247.306338) (xy 123.544822 -247.285991) (xy 123.533379 -247.243685) (xy 123.527645 -247.200236)
			(xy 123.527312 -247.178322) (xy 123.527863 -247.150745) (xy 123.537019 -247.096356) (xy 123.555078 -247.044243)
			(xy 123.581541 -246.995852) (xy 123.598178 -246.973852) (xy 123.598178 -246.78259) (xy 123.597749 -246.769321)
			(xy 123.590901 -246.743681) (xy 123.577671 -246.720674) (xy 123.558955 -246.701859) (xy 123.53602 -246.688507)
			(xy 123.510416 -246.681523) (xy 123.483878 -246.68138) (xy 123.470924 -246.684292) (xy 123.450458 -246.689279)
			(xy 123.408674 -246.694629) (xy 123.387612 -246.69496) (xy 123.361642 -246.694478) (xy 123.31034 -246.686354)
			(xy 123.260941 -246.670305) (xy 123.214661 -246.646726) (xy 123.172639 -246.616197) (xy 123.135911 -246.57947)
			(xy 123.10538 -246.537449) (xy 123.081799 -246.49117) (xy 123.065748 -246.441772) (xy 123.057623 -246.39047)
			(xy 123.057623 -246.33853) (xy 123.065748 -246.287228) (xy 123.081799 -246.23783) (xy 123.10538 -246.191551)
			(xy 123.135911 -246.14953) (xy 123.172639 -246.112803) (xy 123.214661 -246.082274) (xy 123.260941 -246.058695)
			(xy 123.31034 -246.042646) (xy 123.361642 -246.034522) (xy 123.387612 -246.034052) (xy 123.408674 -246.034383)
			(xy 123.450457 -246.039737) (xy 123.470924 -246.04472) (xy 123.483875 -246.047659) (xy 123.510421 -246.047516)
			(xy 123.536033 -246.04053) (xy 123.558976 -246.027175) (xy 123.577699 -246.008355) (xy 123.590934 -245.985343)
			(xy 123.597786 -245.959695) (xy 123.598178 -245.946422) (xy 123.598178 -245.75516) (xy 123.583365 -245.735631)
			(xy 123.55906 -245.693067) (xy 123.541308 -245.64738) (xy 123.5305 -245.599572) (xy 123.526871 -245.550692)
			(xy 123.530502 -245.501812) (xy 123.541313 -245.454005) (xy 123.559067 -245.408319) (xy 123.583374 -245.365756)
			(xy 123.598178 -245.34622) (xy 123.598178 -245.154704) (xy 123.59775 -245.141433) (xy 123.590905 -245.11579)
			(xy 123.577676 -245.09278) (xy 123.55896 -245.073962) (xy 123.536022 -245.060608) (xy 123.510417 -245.053623)
			(xy 123.483876 -245.05348) (xy 123.470924 -245.056406) (xy 123.450458 -245.061392) (xy 123.408674 -245.066742)
			(xy 123.387612 -245.067074) (xy 123.361641 -245.066592) (xy 123.310337 -245.058468) (xy 123.260936 -245.042418)
			(xy 123.214654 -245.018838) (xy 123.17263 -244.988307) (xy 123.1359 -244.951579) (xy 123.105368 -244.909557)
			(xy 123.081786 -244.863275) (xy 123.065735 -244.813875) (xy 123.057609 -244.762571) (xy 123.057609 -244.710629)
			(xy 123.065735 -244.659325) (xy 123.081786 -244.609925) (xy 123.105368 -244.563643) (xy 123.1359 -244.521621)
			(xy 123.17263 -244.484893) (xy 123.214654 -244.454362) (xy 123.260936 -244.430782) (xy 123.310337 -244.414732)
			(xy 123.361641 -244.406608) (xy 123.387612 -244.406166) (xy 123.408674 -244.406497) (xy 123.450457 -244.411851)
			(xy 123.470924 -244.416834) (xy 123.483876 -244.419773) (xy 123.510423 -244.419629) (xy 123.536035 -244.412643)
			(xy 123.55898 -244.399289) (xy 123.577705 -244.380469) (xy 123.590942 -244.357457) (xy 123.597798 -244.33181)
			(xy 123.598178 -244.318536) (xy 123.598178 -244.127274) (xy 123.583364 -244.107745) (xy 123.559057 -244.065181)
			(xy 123.541303 -244.019493) (xy 123.530493 -243.971684) (xy 123.526862 -243.922803) (xy 123.530492 -243.873922)
			(xy 123.541301 -243.826113) (xy 123.559054 -243.780425) (xy 123.58336 -243.73786) (xy 123.598178 -243.718334)
			(xy 123.598178 -243.527072) (xy 123.597746 -243.513804) (xy 123.590896 -243.488168) (xy 123.577665 -243.465166)
			(xy 123.55895 -243.446355) (xy 123.536017 -243.433006) (xy 123.510416 -243.426023) (xy 123.483881 -243.425879)
			(xy 123.470924 -243.428774) (xy 123.450458 -243.433761) (xy 123.408674 -243.439111) (xy 123.387612 -243.439442)
			(xy 123.361643 -243.43896) (xy 123.310344 -243.430837) (xy 123.260948 -243.414789) (xy 123.21467 -243.39121)
			(xy 123.172651 -243.360683) (xy 123.135925 -243.323958) (xy 123.105396 -243.28194) (xy 123.081816 -243.235663)
			(xy 123.065766 -243.186267) (xy 123.057641 -243.134969) (xy 123.057641 -243.083031) (xy 123.065766 -243.031733)
			(xy 123.081816 -242.982337) (xy 123.105396 -242.93606) (xy 123.135925 -242.894042) (xy 123.172651 -242.857317)
			(xy 123.21467 -242.82679) (xy 123.260948 -242.803211) (xy 123.310344 -242.787163) (xy 123.361643 -242.77904)
			(xy 123.387612 -242.778534) (xy 123.408674 -242.778865) (xy 123.450457 -242.784218) (xy 123.470924 -242.789202)
			(xy 123.483874 -242.792142) (xy 123.510419 -242.791998) (xy 123.536029 -242.785013) (xy 123.558971 -242.771657)
			(xy 123.577691 -242.752836) (xy 123.590923 -242.729824) (xy 123.597771 -242.704177) (xy 123.598178 -242.690904)
			(xy 123.598178 -242.499388) (xy 123.583363 -242.479859) (xy 123.559054 -242.437294) (xy 123.541298 -242.391606)
			(xy 123.530486 -242.343797) (xy 123.526854 -242.294914) (xy 123.530482 -242.246031) (xy 123.54129 -242.198221)
			(xy 123.559042 -242.152531) (xy 123.583347 -242.109965) (xy 123.598178 -242.090448) (xy 123.598178 -241.899186)
			(xy 123.597748 -241.885917) (xy 123.5909 -241.860278) (xy 123.57767 -241.837272) (xy 123.558954 -241.818458)
			(xy 123.536019 -241.805107) (xy 123.510416 -241.798123) (xy 123.483879 -241.79798) (xy 123.470924 -241.800888)
			(xy 123.450458 -241.805875) (xy 123.408674 -241.811225) (xy 123.387612 -241.811556) (xy 123.361642 -241.811074)
			(xy 123.310341 -241.802951) (xy 123.260943 -241.786902) (xy 123.214663 -241.763322) (xy 123.172642 -241.732794)
			(xy 123.135914 -241.696067) (xy 123.105384 -241.654047) (xy 123.081803 -241.607769) (xy 123.065752 -241.558371)
			(xy 123.057627 -241.50707) (xy 123.057627 -241.45513) (xy 123.065752 -241.403829) (xy 123.081803 -241.354431)
			(xy 123.105384 -241.308153) (xy 123.135914 -241.266133) (xy 123.172642 -241.229406) (xy 123.214663 -241.198878)
			(xy 123.260943 -241.175298) (xy 123.310341 -241.159249) (xy 123.361642 -241.151126) (xy 123.387612 -241.150648)
			(xy 123.408674 -241.150979) (xy 123.450457 -241.156333) (xy 123.470924 -241.161316) (xy 123.483875 -241.164255)
			(xy 123.510421 -241.164112) (xy 123.536032 -241.157126) (xy 123.558975 -241.143771) (xy 123.577697 -241.124951)
			(xy 123.590931 -241.101938) (xy 123.597783 -241.076291) (xy 123.598178 -241.063018) (xy 123.598178 -240.871756)
			(xy 123.587733 -240.858141) (xy 123.569411 -240.829125) (xy 123.561602 -240.813844) (xy 123.557792 -240.806224)
			(xy 123.41606 -240.664492) (xy 123.405866 -240.654924) (xy 123.381484 -240.641263) (xy 123.354312 -240.63472)
			(xy 123.326384 -240.635783) (xy 123.299788 -240.644374) (xy 123.276516 -240.65985) (xy 123.258306 -240.681052)
			(xy 123.246523 -240.706395) (xy 123.243848 -240.720118) (xy 123.239205 -240.745601) (xy 123.223038 -240.794808)
			(xy 123.199394 -240.84089) (xy 123.168851 -240.882721) (xy 123.132156 -240.919275) (xy 123.090209 -240.949658)
			(xy 123.044036 -240.973125) (xy 122.994767 -240.989103) (xy 122.943609 -240.997199) (xy 122.917712 -240.99774)
			(xy 122.891742 -240.997258) (xy 122.840443 -240.989134) (xy 122.791045 -240.973085) (xy 122.744767 -240.949506)
			(xy 122.702748 -240.918977) (xy 122.666021 -240.882251) (xy 122.635493 -240.840231) (xy 122.611914 -240.793953)
			(xy 122.595865 -240.744555) (xy 122.587742 -240.693256) (xy 122.587258 -240.667286) (xy 122.587756 -240.641382)
			(xy 122.595831 -240.590207) (xy 122.611795 -240.54092) (xy 122.635258 -240.494729) (xy 122.665644 -240.452767)
			(xy 122.702208 -240.416064) (xy 122.744053 -240.385518) (xy 122.790154 -240.361879) (xy 122.83938 -240.345727)
			(xy 122.86488 -240.34115) (xy 122.878604 -240.33848) (xy 122.903949 -240.326696) (xy 122.925152 -240.308486)
			(xy 122.940628 -240.285212) (xy 122.949219 -240.258616) (xy 122.950283 -240.230686) (xy 122.943739 -240.203514)
			(xy 122.930077 -240.17913) (xy 122.920506 -240.168938) (xy 122.876818 -240.12525) (xy 122.635772 -240.12525)
			(xy 122.61496 -240.139044) (xy 122.570061 -240.16088) (xy 122.52239 -240.175719) (xy 122.47303 -240.183224)
			(xy 122.423102 -240.183224) (xy 122.373742 -240.175719) (xy 122.326071 -240.16088) (xy 122.281172 -240.139044)
			(xy 122.26036 -240.12525) (xy 121.695718 -240.12525) (xy 121.674907 -240.139043) (xy 121.630008 -240.160877)
			(xy 121.582336 -240.17571) (xy 121.532975 -240.183205) (xy 121.508012 -240.18367) (xy 121.478879 -240.183054)
			(xy 121.421517 -240.172838) (xy 121.393966 -240.16335) (xy 121.381109 -240.159078) (xy 121.354126 -240.156746)
			(xy 121.327479 -240.161586) (xy 121.30304 -240.173258) (xy 121.282526 -240.190942) (xy 121.267379 -240.213394)
			(xy 121.262648 -240.226088) (xy 121.254963 -240.247694) (xy 121.234466 -240.288716) (xy 121.208494 -240.326509)
			(xy 121.193306 -240.34369) (xy 121.183499 -240.35518) (xy 121.170479 -240.38242) (xy 121.166004 -240.412278)
			(xy 121.170466 -240.442138) (xy 121.183474 -240.469383) (xy 121.193306 -240.48085) (xy 121.20956 -240.499255)
			(xy 121.237009 -240.539968) (xy 121.258135 -240.584292) (xy 121.272474 -240.631254) (xy 121.27971 -240.679819)
			(xy 121.280174 -240.70437) (xy 121.279665 -240.730337) (xy 121.27154 -240.781632) (xy 121.255492 -240.831025)
			(xy 121.231914 -240.877299) (xy 121.201388 -240.919315) (xy 121.164665 -240.956038) (xy 121.122649 -240.986564)
			(xy 121.076375 -241.010142) (xy 121.026982 -241.02619) (xy 120.975687 -241.034315) (xy 120.923753 -241.034315)
			(xy 120.872458 -241.02619) (xy 120.823065 -241.010142) (xy 120.776791 -240.986564) (xy 120.734775 -240.956038)
			(xy 120.698052 -240.919315) (xy 120.667526 -240.877299) (xy 120.643948 -240.831025) (xy 120.6279 -240.781632)
			(xy 120.619775 -240.730337) (xy 120.619266 -240.70437) (xy 120.619696 -240.679817) (xy 120.626927 -240.631247)
			(xy 120.641272 -240.584284) (xy 120.662412 -240.539963) (xy 120.689882 -240.49926) (xy 120.706134 -240.48085)
			(xy 120.715937 -240.469363) (xy 120.728947 -240.442128) (xy 120.73341 -240.412278) (xy 120.728934 -240.382429)
			(xy 120.715912 -240.3552) (xy 120.706134 -240.34369) (xy 120.689846 -240.325248) (xy 120.662346 -240.284448)
			(xy 120.641196 -240.240023) (xy 120.626863 -240.192955) (xy 120.622822 -240.168684) (xy 120.616472 -240.12525)
			(xy 120.550178 -240.12525) (xy 120.352058 -240.32337) (xy 120.352058 -241.507069) (xy 122.118121 -241.507069)
			(xy 122.118121 -241.455135) (xy 122.126246 -241.40384) (xy 122.142294 -241.354447) (xy 122.165872 -241.308173)
			(xy 122.196398 -241.266157) (xy 122.233121 -241.229434) (xy 122.275137 -241.198908) (xy 122.321411 -241.17533)
			(xy 122.370804 -241.159282) (xy 122.422099 -241.151157) (xy 122.474033 -241.151157) (xy 122.525328 -241.159282)
			(xy 122.574721 -241.17533) (xy 122.620995 -241.198908) (xy 122.663011 -241.229434) (xy 122.699734 -241.266157)
			(xy 122.73026 -241.308173) (xy 122.753838 -241.354447) (xy 122.769886 -241.40384) (xy 122.778011 -241.455135)
			(xy 122.77852 -241.481102) (xy 122.778011 -241.507069) (xy 122.769886 -241.558364) (xy 122.753838 -241.607757)
			(xy 122.73026 -241.654031) (xy 122.699734 -241.696047) (xy 122.663011 -241.73277) (xy 122.620995 -241.763296)
			(xy 122.574721 -241.786874) (xy 122.525328 -241.802922) (xy 122.474033 -241.811047) (xy 122.422099 -241.811047)
			(xy 122.370804 -241.802922) (xy 122.321411 -241.786874) (xy 122.275137 -241.763296) (xy 122.233121 -241.73277)
			(xy 122.196398 -241.696047) (xy 122.165872 -241.654031) (xy 122.142294 -241.607757) (xy 122.126246 -241.558364)
			(xy 122.118121 -241.507069) (xy 120.352058 -241.507069) (xy 120.352058 -242.320885) (xy 122.588021 -242.320885)
			(xy 122.588021 -242.268951) (xy 122.596146 -242.217656) (xy 122.612194 -242.168263) (xy 122.635772 -242.121989)
			(xy 122.666298 -242.079973) (xy 122.703021 -242.04325) (xy 122.745037 -242.012724) (xy 122.791311 -241.989146)
			(xy 122.840704 -241.973098) (xy 122.891999 -241.964973) (xy 122.943933 -241.964973) (xy 122.995228 -241.973098)
			(xy 123.044621 -241.989146) (xy 123.090895 -242.012724) (xy 123.132911 -242.04325) (xy 123.169634 -242.079973)
			(xy 123.20016 -242.121989) (xy 123.223738 -242.168263) (xy 123.239786 -242.217656) (xy 123.247911 -242.268951)
			(xy 123.24842 -242.294918) (xy 123.247911 -242.320885) (xy 123.239786 -242.37218) (xy 123.223738 -242.421573)
			(xy 123.20016 -242.467847) (xy 123.169634 -242.509863) (xy 123.132911 -242.546586) (xy 123.090895 -242.577112)
			(xy 123.044621 -242.60069) (xy 122.995228 -242.616738) (xy 122.943933 -242.624863) (xy 122.891999 -242.624863)
			(xy 122.840704 -242.616738) (xy 122.791311 -242.60069) (xy 122.745037 -242.577112) (xy 122.703021 -242.546586)
			(xy 122.666298 -242.509863) (xy 122.635772 -242.467847) (xy 122.612194 -242.421573) (xy 122.596146 -242.37218)
			(xy 122.588021 -242.320885) (xy 120.352058 -242.320885) (xy 120.352058 -243.134955) (xy 122.117867 -243.134955)
			(xy 122.117867 -243.083021) (xy 122.125992 -243.031726) (xy 122.14204 -242.982333) (xy 122.165618 -242.936059)
			(xy 122.196144 -242.894043) (xy 122.232867 -242.85732) (xy 122.274883 -242.826794) (xy 122.321157 -242.803216)
			(xy 122.37055 -242.787168) (xy 122.421845 -242.779043) (xy 122.473779 -242.779043) (xy 122.525074 -242.787168)
			(xy 122.574467 -242.803216) (xy 122.620741 -242.826794) (xy 122.662757 -242.85732) (xy 122.69948 -242.894043)
			(xy 122.730006 -242.936059) (xy 122.753584 -242.982333) (xy 122.769632 -243.031726) (xy 122.777757 -243.083021)
			(xy 122.778266 -243.108988) (xy 122.777757 -243.134955) (xy 122.769632 -243.18625) (xy 122.753584 -243.235643)
			(xy 122.730006 -243.281917) (xy 122.69948 -243.323933) (xy 122.662757 -243.360656) (xy 122.620741 -243.391182)
			(xy 122.574467 -243.41476) (xy 122.525074 -243.430808) (xy 122.473779 -243.438933) (xy 122.421845 -243.438933)
			(xy 122.37055 -243.430808) (xy 122.321157 -243.41476) (xy 122.274883 -243.391182) (xy 122.232867 -243.360656)
			(xy 122.196144 -243.323933) (xy 122.165618 -243.281917) (xy 122.14204 -243.235643) (xy 122.125992 -243.18625)
			(xy 122.117867 -243.134955) (xy 120.352058 -243.134955) (xy 120.352058 -244.25783) (xy 119.010684 -245.599204)
			(xy 120.645936 -245.599204) (xy 120.646357 -245.574651) (xy 120.653604 -245.526084) (xy 120.667952 -245.479122)
			(xy 120.689088 -245.434799) (xy 120.716546 -245.394088) (xy 120.732804 -245.375684) (xy 120.742601 -245.364191)
			(xy 120.755612 -245.336955) (xy 120.760079 -245.307103) (xy 120.755613 -245.277251) (xy 120.742604 -245.250014)
			(xy 120.732804 -245.238524) (xy 120.716535 -245.220128) (xy 120.689068 -245.179422) (xy 120.667932 -245.135096)
			(xy 120.653591 -245.08813) (xy 120.646364 -245.039558) (xy 120.645936 -245.015004) (xy 120.646357 -244.990451)
			(xy 120.653604 -244.941884) (xy 120.667952 -244.894922) (xy 120.689088 -244.850599) (xy 120.716546 -244.809888)
			(xy 120.732804 -244.791484) (xy 120.742601 -244.779991) (xy 120.755612 -244.752755) (xy 120.760079 -244.722903)
			(xy 120.755613 -244.693051) (xy 120.742604 -244.665814) (xy 120.732804 -244.654324) (xy 120.716535 -244.635928)
			(xy 120.689068 -244.595222) (xy 120.667932 -244.550896) (xy 120.653591 -244.50393) (xy 120.646364 -244.455358)
			(xy 120.645936 -244.430804) (xy 120.646357 -244.406251) (xy 120.653604 -244.357684) (xy 120.667952 -244.310722)
			(xy 120.689088 -244.266399) (xy 120.716546 -244.225688) (xy 120.732804 -244.207284) (xy 120.742601 -244.195791)
			(xy 120.755612 -244.168555) (xy 120.760079 -244.138703) (xy 120.755613 -244.108851) (xy 120.742604 -244.081614)
			(xy 120.732804 -244.070124) (xy 120.716535 -244.051728) (xy 120.689068 -244.011022) (xy 120.667932 -243.966696)
			(xy 120.653591 -243.91973) (xy 120.646364 -243.871158) (xy 120.645936 -243.846604) (xy 120.646445 -243.820637)
			(xy 120.65457 -243.769342) (xy 120.670618 -243.719949) (xy 120.694196 -243.673675) (xy 120.724722 -243.631659)
			(xy 120.761445 -243.594936) (xy 120.803461 -243.56441) (xy 120.849735 -243.540832) (xy 120.899128 -243.524784)
			(xy 120.950423 -243.516659) (xy 121.002357 -243.516659) (xy 121.053652 -243.524784) (xy 121.103045 -243.540832)
			(xy 121.149319 -243.56441) (xy 121.191335 -243.594936) (xy 121.228058 -243.631659) (xy 121.258584 -243.673675)
			(xy 121.282162 -243.719949) (xy 121.29821 -243.769342) (xy 121.306335 -243.820637) (xy 121.306844 -243.846604)
			(xy 121.306433 -243.871157) (xy 121.299185 -243.919725) (xy 121.290309 -243.948771) (xy 121.647967 -243.948771)
			(xy 121.647967 -243.896837) (xy 121.656092 -243.845542) (xy 121.67214 -243.796149) (xy 121.695718 -243.749875)
			(xy 121.726244 -243.707859) (xy 121.762967 -243.671136) (xy 121.804983 -243.64061) (xy 121.851257 -243.617032)
			(xy 121.90065 -243.600984) (xy 121.951945 -243.592859) (xy 122.003879 -243.592859) (xy 122.055174 -243.600984)
			(xy 122.104567 -243.617032) (xy 122.150841 -243.64061) (xy 122.192857 -243.671136) (xy 122.22958 -243.707859)
			(xy 122.260106 -243.749875) (xy 122.283684 -243.796149) (xy 122.299732 -243.845542) (xy 122.307857 -243.896837)
			(xy 122.308366 -243.922804) (xy 122.307857 -243.948771) (xy 122.587767 -243.948771) (xy 122.587767 -243.896837)
			(xy 122.595892 -243.845542) (xy 122.61194 -243.796149) (xy 122.635518 -243.749875) (xy 122.666044 -243.707859)
			(xy 122.702767 -243.671136) (xy 122.744783 -243.64061) (xy 122.791057 -243.617032) (xy 122.84045 -243.600984)
			(xy 122.891745 -243.592859) (xy 122.943679 -243.592859) (xy 122.994974 -243.600984) (xy 123.044367 -243.617032)
			(xy 123.090641 -243.64061) (xy 123.132657 -243.671136) (xy 123.16938 -243.707859) (xy 123.199906 -243.749875)
			(xy 123.223484 -243.796149) (xy 123.239532 -243.845542) (xy 123.247657 -243.896837) (xy 123.248166 -243.922804)
			(xy 123.247657 -243.948771) (xy 123.239532 -244.000066) (xy 123.223484 -244.049459) (xy 123.199906 -244.095733)
			(xy 123.16938 -244.137749) (xy 123.132657 -244.174472) (xy 123.090641 -244.204998) (xy 123.044367 -244.228576)
			(xy 122.994974 -244.244624) (xy 122.943679 -244.252749) (xy 122.891745 -244.252749) (xy 122.84045 -244.244624)
			(xy 122.791057 -244.228576) (xy 122.744783 -244.204998) (xy 122.702767 -244.174472) (xy 122.666044 -244.137749)
			(xy 122.635518 -244.095733) (xy 122.61194 -244.049459) (xy 122.595892 -244.000066) (xy 122.587767 -243.948771)
			(xy 122.307857 -243.948771) (xy 122.299732 -244.000066) (xy 122.283684 -244.049459) (xy 122.260106 -244.095733)
			(xy 122.22958 -244.137749) (xy 122.192857 -244.174472) (xy 122.150841 -244.204998) (xy 122.104567 -244.228576)
			(xy 122.055174 -244.244624) (xy 122.003879 -244.252749) (xy 121.951945 -244.252749) (xy 121.90065 -244.244624)
			(xy 121.851257 -244.228576) (xy 121.804983 -244.204998) (xy 121.762967 -244.174472) (xy 121.726244 -244.137749)
			(xy 121.695718 -244.095733) (xy 121.67214 -244.049459) (xy 121.656092 -244.000066) (xy 121.647967 -243.948771)
			(xy 121.290309 -243.948771) (xy 121.284834 -243.966687) (xy 121.263696 -244.011011) (xy 121.236235 -244.051721)
			(xy 121.219976 -244.070124) (xy 121.210172 -244.081612) (xy 121.197165 -244.10885) (xy 121.1927 -244.138703)
			(xy 121.197167 -244.168555) (xy 121.210176 -244.195793) (xy 121.219976 -244.207284) (xy 121.237573 -244.227248)
			(xy 121.266744 -244.271756) (xy 121.288394 -244.320369) (xy 121.295668 -244.345968) (xy 121.299529 -244.358806)
			(xy 121.312935 -244.382011) (xy 121.331911 -244.400934) (xy 121.355152 -244.414278) (xy 121.381062 -244.421123)
			(xy 121.40786 -244.421002) (xy 121.42089 -244.41785) (xy 121.442256 -244.412391) (xy 121.485963 -244.40653)
			(xy 121.508012 -244.406166) (xy 121.53398 -244.406636) (xy 121.585277 -244.414763) (xy 121.634671 -244.430813)
			(xy 121.680946 -244.454393) (xy 121.722963 -244.484921) (xy 121.759686 -244.521647) (xy 121.790213 -244.563664)
			(xy 121.813791 -244.60994) (xy 121.82984 -244.659335) (xy 121.837965 -244.710632) (xy 121.837965 -244.762333)
			(xy 122.117867 -244.762333) (xy 122.117867 -244.710399) (xy 122.125992 -244.659104) (xy 122.14204 -244.609711)
			(xy 122.165618 -244.563437) (xy 122.196144 -244.521421) (xy 122.232867 -244.484698) (xy 122.274883 -244.454172)
			(xy 122.321157 -244.430594) (xy 122.37055 -244.414546) (xy 122.421845 -244.406421) (xy 122.473779 -244.406421)
			(xy 122.525074 -244.414546) (xy 122.574467 -244.430594) (xy 122.620741 -244.454172) (xy 122.662757 -244.484698)
			(xy 122.69948 -244.521421) (xy 122.730006 -244.563437) (xy 122.753584 -244.609711) (xy 122.769632 -244.659104)
			(xy 122.777757 -244.710399) (xy 122.778266 -244.736366) (xy 122.777757 -244.762333) (xy 122.769632 -244.813628)
			(xy 122.753584 -244.863021) (xy 122.730006 -244.909295) (xy 122.69948 -244.951311) (xy 122.662757 -244.988034)
			(xy 122.620741 -245.01856) (xy 122.574467 -245.042138) (xy 122.525074 -245.058186) (xy 122.473779 -245.066311)
			(xy 122.421845 -245.066311) (xy 122.37055 -245.058186) (xy 122.321157 -245.042138) (xy 122.274883 -245.01856)
			(xy 122.232867 -244.988034) (xy 122.196144 -244.951311) (xy 122.165618 -244.909295) (xy 122.14204 -244.863021)
			(xy 122.125992 -244.813628) (xy 122.117867 -244.762333) (xy 121.837965 -244.762333) (xy 121.837965 -244.762568)
			(xy 121.82984 -244.813865) (xy 121.813791 -244.86326) (xy 121.790213 -244.909536) (xy 121.759686 -244.951553)
			(xy 121.722963 -244.988279) (xy 121.680946 -245.018807) (xy 121.634671 -245.042387) (xy 121.585277 -245.058437)
			(xy 121.53398 -245.066564) (xy 121.508012 -245.067074) (xy 121.484437 -245.066661) (xy 121.437773 -245.059901)
			(xy 121.415048 -245.053612) (xy 121.399894 -245.049703) (xy 121.368619 -245.050398) (xy 121.339019 -245.060523)
			(xy 121.31387 -245.079128) (xy 121.295529 -245.104471) (xy 121.29008 -245.119144) (xy 121.282396 -245.141098)
			(xy 121.261713 -245.182759) (xy 121.235399 -245.221113) (xy 121.219976 -245.238524) (xy 121.210172 -245.250012)
			(xy 121.197165 -245.27725) (xy 121.1927 -245.307103) (xy 121.197167 -245.336955) (xy 121.210176 -245.364193)
			(xy 121.219976 -245.375684) (xy 121.236245 -245.394079) (xy 121.263713 -245.434786) (xy 121.28485 -245.479111)
			(xy 121.29919 -245.526078) (xy 121.306417 -245.57465) (xy 121.306452 -245.576657) (xy 121.648221 -245.576657)
			(xy 121.648221 -245.524723) (xy 121.656346 -245.473428) (xy 121.672394 -245.424035) (xy 121.695972 -245.377761)
			(xy 121.726498 -245.335745) (xy 121.763221 -245.299022) (xy 121.805237 -245.268496) (xy 121.851511 -245.244918)
			(xy 121.900904 -245.22887) (xy 121.952199 -245.220745) (xy 122.004133 -245.220745) (xy 122.055428 -245.22887)
			(xy 122.104821 -245.244918) (xy 122.151095 -245.268496) (xy 122.193111 -245.299022) (xy 122.229834 -245.335745)
			(xy 122.26036 -245.377761) (xy 122.283938 -245.424035) (xy 122.299986 -245.473428) (xy 122.308111 -245.524723)
			(xy 122.30862 -245.55069) (xy 122.308111 -245.576657) (xy 122.588021 -245.576657) (xy 122.588021 -245.524723)
			(xy 122.596146 -245.473428) (xy 122.612194 -245.424035) (xy 122.635772 -245.377761) (xy 122.666298 -245.335745)
			(xy 122.703021 -245.299022) (xy 122.745037 -245.268496) (xy 122.791311 -245.244918) (xy 122.840704 -245.22887)
			(xy 122.891999 -245.220745) (xy 122.943933 -245.220745) (xy 122.995228 -245.22887) (xy 123.044621 -245.244918)
			(xy 123.090895 -245.268496) (xy 123.132911 -245.299022) (xy 123.169634 -245.335745) (xy 123.20016 -245.377761)
			(xy 123.223738 -245.424035) (xy 123.239786 -245.473428) (xy 123.247911 -245.524723) (xy 123.24842 -245.55069)
			(xy 123.247911 -245.576657) (xy 123.239786 -245.627952) (xy 123.223738 -245.677345) (xy 123.20016 -245.723619)
			(xy 123.169634 -245.765635) (xy 123.132911 -245.802358) (xy 123.090895 -245.832884) (xy 123.044621 -245.856462)
			(xy 122.995228 -245.87251) (xy 122.943933 -245.880635) (xy 122.891999 -245.880635) (xy 122.840704 -245.87251)
			(xy 122.791311 -245.856462) (xy 122.745037 -245.832884) (xy 122.703021 -245.802358) (xy 122.666298 -245.765635)
			(xy 122.635772 -245.723619) (xy 122.612194 -245.677345) (xy 122.596146 -245.627952) (xy 122.588021 -245.576657)
			(xy 122.308111 -245.576657) (xy 122.299986 -245.627952) (xy 122.283938 -245.677345) (xy 122.26036 -245.723619)
			(xy 122.229834 -245.765635) (xy 122.193111 -245.802358) (xy 122.151095 -245.832884) (xy 122.104821 -245.856462)
			(xy 122.055428 -245.87251) (xy 122.004133 -245.880635) (xy 121.952199 -245.880635) (xy 121.900904 -245.87251)
			(xy 121.851511 -245.856462) (xy 121.805237 -245.832884) (xy 121.763221 -245.802358) (xy 121.726498 -245.765635)
			(xy 121.695972 -245.723619) (xy 121.672394 -245.677345) (xy 121.656346 -245.627952) (xy 121.648221 -245.576657)
			(xy 121.306452 -245.576657) (xy 121.306844 -245.599204) (xy 121.306335 -245.625171) (xy 121.29821 -245.676466)
			(xy 121.282162 -245.725859) (xy 121.258584 -245.772133) (xy 121.228058 -245.814149) (xy 121.191335 -245.850872)
			(xy 121.149319 -245.881398) (xy 121.103045 -245.904976) (xy 121.053652 -245.921024) (xy 121.002357 -245.929149)
			(xy 120.950423 -245.929149) (xy 120.899128 -245.921024) (xy 120.849735 -245.904976) (xy 120.803461 -245.881398)
			(xy 120.761445 -245.850872) (xy 120.724722 -245.814149) (xy 120.694196 -245.772133) (xy 120.670618 -245.725859)
			(xy 120.65457 -245.676466) (xy 120.646445 -245.625171) (xy 120.645936 -245.599204) (xy 119.010684 -245.599204)
			(xy 118.556278 -246.05361) (xy 118.556278 -246.351298) (xy 118.583964 -246.365268) (xy 118.606774 -246.377556)
			(xy 118.624441 -246.390473) (xy 121.178321 -246.390473) (xy 121.178321 -246.338539) (xy 121.186446 -246.287244)
			(xy 121.202494 -246.237851) (xy 121.226072 -246.191577) (xy 121.256598 -246.149561) (xy 121.293321 -246.112838)
			(xy 121.335337 -246.082312) (xy 121.381611 -246.058734) (xy 121.431004 -246.042686) (xy 121.482299 -246.034561)
			(xy 121.534233 -246.034561) (xy 121.585528 -246.042686) (xy 121.634921 -246.058734) (xy 121.681195 -246.082312)
			(xy 121.723211 -246.112838) (xy 121.759934 -246.149561) (xy 121.79046 -246.191577) (xy 121.814038 -246.237851)
			(xy 121.830086 -246.287244) (xy 121.838211 -246.338539) (xy 121.83872 -246.364506) (xy 121.838211 -246.390473)
			(xy 122.118121 -246.390473) (xy 122.118121 -246.338539) (xy 122.126246 -246.287244) (xy 122.142294 -246.237851)
			(xy 122.165872 -246.191577) (xy 122.196398 -246.149561) (xy 122.233121 -246.112838) (xy 122.275137 -246.082312)
			(xy 122.321411 -246.058734) (xy 122.370804 -246.042686) (xy 122.422099 -246.034561) (xy 122.474033 -246.034561)
			(xy 122.525328 -246.042686) (xy 122.574721 -246.058734) (xy 122.620995 -246.082312) (xy 122.663011 -246.112838)
			(xy 122.699734 -246.149561) (xy 122.73026 -246.191577) (xy 122.753838 -246.237851) (xy 122.769886 -246.287244)
			(xy 122.778011 -246.338539) (xy 122.77852 -246.364506) (xy 122.778011 -246.390473) (xy 122.769886 -246.441768)
			(xy 122.753838 -246.491161) (xy 122.73026 -246.537435) (xy 122.699734 -246.579451) (xy 122.663011 -246.616174)
			(xy 122.620995 -246.6467) (xy 122.574721 -246.670278) (xy 122.525328 -246.686326) (xy 122.474033 -246.694451)
			(xy 122.422099 -246.694451) (xy 122.370804 -246.686326) (xy 122.321411 -246.670278) (xy 122.275137 -246.6467)
			(xy 122.233121 -246.616174) (xy 122.196398 -246.579451) (xy 122.165872 -246.537435) (xy 122.142294 -246.491161)
			(xy 122.126246 -246.441768) (xy 122.118121 -246.390473) (xy 121.838211 -246.390473) (xy 121.830086 -246.441768)
			(xy 121.814038 -246.491161) (xy 121.79046 -246.537435) (xy 121.759934 -246.579451) (xy 121.723211 -246.616174)
			(xy 121.681195 -246.6467) (xy 121.634921 -246.670278) (xy 121.585528 -246.686326) (xy 121.534233 -246.694451)
			(xy 121.482299 -246.694451) (xy 121.431004 -246.686326) (xy 121.381611 -246.670278) (xy 121.335337 -246.6467)
			(xy 121.293321 -246.616174) (xy 121.256598 -246.579451) (xy 121.226072 -246.537435) (xy 121.202494 -246.491161)
			(xy 121.186446 -246.441768) (xy 121.178321 -246.390473) (xy 118.624441 -246.390473) (xy 118.648597 -246.408134)
			(xy 118.685139 -246.44486) (xy 118.715508 -246.486835) (xy 118.73896 -246.533032) (xy 118.75492 -246.582321)
			(xy 118.763 -246.633496) (xy 118.763 -246.685304) (xy 118.75492 -246.736479) (xy 118.73896 -246.785768)
			(xy 118.715508 -246.831965) (xy 118.685139 -246.87394) (xy 118.648597 -246.910666) (xy 118.606774 -246.941244)
			(xy 118.583964 -246.953532) (xy 118.556278 -246.967502) (xy 118.556278 -247.204289) (xy 121.648221 -247.204289)
			(xy 121.648221 -247.152355) (xy 121.656346 -247.10106) (xy 121.672394 -247.051667) (xy 121.695972 -247.005393)
			(xy 121.726498 -246.963377) (xy 121.763221 -246.926654) (xy 121.805237 -246.896128) (xy 121.851511 -246.87255)
			(xy 121.900904 -246.856502) (xy 121.952199 -246.848377) (xy 122.004133 -246.848377) (xy 122.055428 -246.856502)
			(xy 122.104821 -246.87255) (xy 122.151095 -246.896128) (xy 122.193111 -246.926654) (xy 122.229834 -246.963377)
			(xy 122.26036 -247.005393) (xy 122.283938 -247.051667) (xy 122.299986 -247.10106) (xy 122.308111 -247.152355)
			(xy 122.30862 -247.178322) (xy 122.308111 -247.204289) (xy 122.588021 -247.204289) (xy 122.588021 -247.152355)
			(xy 122.596146 -247.10106) (xy 122.612194 -247.051667) (xy 122.635772 -247.005393) (xy 122.666298 -246.963377)
			(xy 122.703021 -246.926654) (xy 122.745037 -246.896128) (xy 122.791311 -246.87255) (xy 122.840704 -246.856502)
			(xy 122.891999 -246.848377) (xy 122.943933 -246.848377) (xy 122.995228 -246.856502) (xy 123.044621 -246.87255)
			(xy 123.090895 -246.896128) (xy 123.132911 -246.926654) (xy 123.169634 -246.963377) (xy 123.20016 -247.005393)
			(xy 123.223738 -247.051667) (xy 123.239786 -247.10106) (xy 123.247911 -247.152355) (xy 123.24842 -247.178322)
			(xy 123.247911 -247.204289) (xy 123.239786 -247.255584) (xy 123.223738 -247.304977) (xy 123.20016 -247.351251)
			(xy 123.169634 -247.393267) (xy 123.132911 -247.42999) (xy 123.090895 -247.460516) (xy 123.044621 -247.484094)
			(xy 122.995228 -247.500142) (xy 122.943933 -247.508267) (xy 122.891999 -247.508267) (xy 122.840704 -247.500142)
			(xy 122.791311 -247.484094) (xy 122.745037 -247.460516) (xy 122.703021 -247.42999) (xy 122.666298 -247.393267)
			(xy 122.635772 -247.351251) (xy 122.612194 -247.304977) (xy 122.596146 -247.255584) (xy 122.588021 -247.204289)
			(xy 122.308111 -247.204289) (xy 122.299986 -247.255584) (xy 122.283938 -247.304977) (xy 122.26036 -247.351251)
			(xy 122.229834 -247.393267) (xy 122.193111 -247.42999) (xy 122.151095 -247.460516) (xy 122.104821 -247.484094)
			(xy 122.055428 -247.500142) (xy 122.004133 -247.508267) (xy 121.952199 -247.508267) (xy 121.900904 -247.500142)
			(xy 121.851511 -247.484094) (xy 121.805237 -247.460516) (xy 121.763221 -247.42999) (xy 121.726498 -247.393267)
			(xy 121.695972 -247.351251) (xy 121.672394 -247.304977) (xy 121.656346 -247.255584) (xy 121.648221 -247.204289)
			(xy 118.556278 -247.204289) (xy 118.556278 -248.12879) (xy 118.781655 -248.354167) (xy 120.622835 -248.354167)
			(xy 120.622835 -248.302233) (xy 120.630959 -248.250938) (xy 120.647007 -248.201545) (xy 120.670583 -248.15527)
			(xy 120.701108 -248.113253) (xy 120.737829 -248.076528) (xy 120.779843 -248.046) (xy 120.826115 -248.022419)
			(xy 120.875507 -248.006367) (xy 120.926801 -247.998238) (xy 120.952768 -247.997726) (xy 120.978001 -247.998156)
			(xy 121.027881 -248.005812) (xy 121.052082 -248.012966) (xy 121.06597 -248.016894) (xy 121.094811 -248.017583)
			(xy 121.12269 -248.010161) (xy 121.147371 -247.995222) (xy 121.166876 -247.973964) (xy 121.17964 -247.948091)
			(xy 121.182638 -247.933972) (xy 121.187658 -247.90886) (xy 121.204355 -247.860452) (xy 121.228316 -247.815196)
			(xy 121.258967 -247.774176) (xy 121.295577 -247.738372) (xy 121.33727 -247.708642) (xy 121.383047 -247.685694)
			(xy 121.431816 -247.67008) (xy 121.482409 -247.662171) (xy 121.508012 -247.661684) (xy 121.533982 -247.662118)
			(xy 121.585281 -247.670245) (xy 121.634678 -247.686297) (xy 121.680955 -247.709878) (xy 121.722974 -247.740408)
			(xy 121.7597 -247.777135) (xy 121.790229 -247.819155) (xy 121.813808 -247.865433) (xy 121.829858 -247.914831)
			(xy 121.837983 -247.96613) (xy 121.837983 -248.01807) (xy 121.837977 -248.018105) (xy 122.117867 -248.018105)
			(xy 122.117867 -247.966171) (xy 122.125992 -247.914876) (xy 122.14204 -247.865483) (xy 122.165618 -247.819209)
			(xy 122.196144 -247.777193) (xy 122.232867 -247.74047) (xy 122.274883 -247.709944) (xy 122.321157 -247.686366)
			(xy 122.37055 -247.670318) (xy 122.421845 -247.662193) (xy 122.473779 -247.662193) (xy 122.525074 -247.670318)
			(xy 122.574467 -247.686366) (xy 122.620741 -247.709944) (xy 122.662757 -247.74047) (xy 122.69948 -247.777193)
			(xy 122.730006 -247.819209) (xy 122.753584 -247.865483) (xy 122.769632 -247.914876) (xy 122.777757 -247.966171)
			(xy 122.778266 -247.992138) (xy 122.777757 -248.018105) (xy 122.769632 -248.0694) (xy 122.753584 -248.118793)
			(xy 122.730006 -248.165067) (xy 122.69948 -248.207083) (xy 122.662757 -248.243806) (xy 122.620741 -248.274332)
			(xy 122.574467 -248.29791) (xy 122.525074 -248.313958) (xy 122.473779 -248.322083) (xy 122.421845 -248.322083)
			(xy 122.37055 -248.313958) (xy 122.321157 -248.29791) (xy 122.274883 -248.274332) (xy 122.232867 -248.243806)
			(xy 122.196144 -248.207083) (xy 122.165618 -248.165067) (xy 122.14204 -248.118793) (xy 122.125992 -248.0694)
			(xy 122.117867 -248.018105) (xy 121.837977 -248.018105) (xy 121.829858 -248.069369) (xy 121.813808 -248.118767)
			(xy 121.790229 -248.165045) (xy 121.7597 -248.207065) (xy 121.722974 -248.243792) (xy 121.680955 -248.274322)
			(xy 121.634678 -248.297903) (xy 121.585281 -248.313955) (xy 121.533982 -248.322082) (xy 121.508012 -248.322592)
			(xy 121.482779 -248.322166) (xy 121.432899 -248.314507) (xy 121.408698 -248.307352) (xy 121.394802 -248.303466)
			(xy 121.365971 -248.302784) (xy 121.338102 -248.310205) (xy 121.313428 -248.325135) (xy 121.293923 -248.346378)
			(xy 121.281148 -248.372234) (xy 121.278142 -248.386346) (xy 121.273154 -248.411465) (xy 121.256453 -248.459875)
			(xy 121.232488 -248.505131) (xy 121.201832 -248.546151) (xy 121.165218 -248.581955) (xy 121.123522 -248.611684)
			(xy 121.077741 -248.63463) (xy 121.028969 -248.650242) (xy 120.978373 -248.658148) (xy 120.952768 -248.658634)
			(xy 120.926801 -248.658162) (xy 120.875507 -248.650033) (xy 120.826115 -248.633981) (xy 120.779843 -248.6104)
			(xy 120.737829 -248.579872) (xy 120.701108 -248.543147) (xy 120.670583 -248.50113) (xy 120.647007 -248.454855)
			(xy 120.630959 -248.405462) (xy 120.622835 -248.354167) (xy 118.781655 -248.354167) (xy 119.560648 -249.13316)
			(xy 120.659165 -249.13316) (xy 120.659166 -249.081228) (xy 120.667291 -249.029935) (xy 120.683339 -248.980544)
			(xy 120.706917 -248.934273) (xy 120.737443 -248.892259) (xy 120.774165 -248.855537) (xy 120.816179 -248.825013)
			(xy 120.862452 -248.801436) (xy 120.911843 -248.785389) (xy 120.963136 -248.777265) (xy 121.015068 -248.777265)
			(xy 121.066361 -248.78539) (xy 121.115752 -248.801438) (xy 121.162024 -248.825015) (xy 121.171879 -248.832175)
			(xy 121.648221 -248.832175) (xy 121.648221 -248.780241) (xy 121.656346 -248.728946) (xy 121.672394 -248.679553)
			(xy 121.695972 -248.633279) (xy 121.726498 -248.591263) (xy 121.763221 -248.55454) (xy 121.805237 -248.524014)
			(xy 121.851511 -248.500436) (xy 121.900904 -248.484388) (xy 121.952199 -248.476263) (xy 122.004133 -248.476263)
			(xy 122.055428 -248.484388) (xy 122.104821 -248.500436) (xy 122.151095 -248.524014) (xy 122.193111 -248.55454)
			(xy 122.229834 -248.591263) (xy 122.26036 -248.633279) (xy 122.283938 -248.679553) (xy 122.299986 -248.728946)
			(xy 122.308111 -248.780241) (xy 122.30862 -248.806208) (xy 122.308111 -248.832175) (xy 122.299986 -248.88347)
			(xy 122.283938 -248.932863) (xy 122.26036 -248.979137) (xy 122.229834 -249.021153) (xy 122.193111 -249.057876)
			(xy 122.151095 -249.088402) (xy 122.104821 -249.11198) (xy 122.055428 -249.128028) (xy 122.004133 -249.136153)
			(xy 121.952199 -249.136153) (xy 121.900904 -249.128028) (xy 121.851511 -249.11198) (xy 121.805237 -249.088402)
			(xy 121.763221 -249.057876) (xy 121.726498 -249.021153) (xy 121.695972 -248.979137) (xy 121.672394 -248.932863)
			(xy 121.656346 -248.88347) (xy 121.648221 -248.832175) (xy 121.171879 -248.832175) (xy 121.204038 -248.85554)
			(xy 121.24076 -248.892262) (xy 121.271285 -248.934276) (xy 121.294862 -248.980548) (xy 121.31091 -249.029939)
			(xy 121.319035 -249.081232) (xy 121.319544 -249.107198) (xy 121.319287 -249.124865) (xy 121.315473 -249.159993)
			(xy 121.311924 -249.177302) (xy 121.309216 -249.191699) (xy 121.311359 -249.220909) (xy 121.321695 -249.248312)
			(xy 121.339377 -249.27166) (xy 121.362952 -249.289038) (xy 121.390487 -249.299018) (xy 121.419722 -249.300782)
			(xy 121.434098 -249.297952) (xy 121.452325 -249.294031) (xy 121.48937 -249.289827) (xy 121.508012 -249.28957)
			(xy 121.533978 -249.290068) (xy 121.585269 -249.298194) (xy 121.634659 -249.314243) (xy 121.680929 -249.33782)
			(xy 121.722942 -249.368346) (xy 121.759662 -249.405067) (xy 121.790186 -249.447081) (xy 121.813762 -249.493353)
			(xy 121.829809 -249.542742) (xy 121.837933 -249.594034) (xy 121.837933 -249.645966) (xy 121.837929 -249.645991)
			(xy 122.117867 -249.645991) (xy 122.117867 -249.594057) (xy 122.125992 -249.542762) (xy 122.14204 -249.493369)
			(xy 122.165618 -249.447095) (xy 122.196144 -249.405079) (xy 122.232867 -249.368356) (xy 122.274883 -249.33783)
			(xy 122.321157 -249.314252) (xy 122.37055 -249.298204) (xy 122.421845 -249.290079) (xy 122.473779 -249.290079)
			(xy 122.525074 -249.298204) (xy 122.574467 -249.314252) (xy 122.620741 -249.33783) (xy 122.662757 -249.368356)
			(xy 122.69948 -249.405079) (xy 122.730006 -249.447095) (xy 122.753584 -249.493369) (xy 122.769632 -249.542762)
			(xy 122.777757 -249.594057) (xy 122.778266 -249.620024) (xy 122.777757 -249.645991) (xy 122.769632 -249.697286)
			(xy 122.753584 -249.746679) (xy 122.730006 -249.792953) (xy 122.69948 -249.834969) (xy 122.662757 -249.871692)
			(xy 122.620741 -249.902218) (xy 122.574467 -249.925796) (xy 122.525074 -249.941844) (xy 122.473779 -249.949969)
			(xy 122.421845 -249.949969) (xy 122.37055 -249.941844) (xy 122.321157 -249.925796) (xy 122.274883 -249.902218)
			(xy 122.232867 -249.871692) (xy 122.196144 -249.834969) (xy 122.165618 -249.792953) (xy 122.14204 -249.746679)
			(xy 122.125992 -249.697286) (xy 122.117867 -249.645991) (xy 121.837929 -249.645991) (xy 121.829809 -249.697258)
			(xy 121.813762 -249.746647) (xy 121.790186 -249.792919) (xy 121.759662 -249.834933) (xy 121.722942 -249.871654)
			(xy 121.680929 -249.90218) (xy 121.634659 -249.925757) (xy 121.585269 -249.941806) (xy 121.533978 -249.949932)
			(xy 121.482046 -249.949934) (xy 121.430754 -249.941812) (xy 121.381364 -249.925766) (xy 121.335091 -249.902192)
			(xy 121.293076 -249.87167) (xy 121.256353 -249.834951) (xy 121.225827 -249.792939) (xy 121.202247 -249.74667)
			(xy 121.186196 -249.697281) (xy 121.178069 -249.64599) (xy 121.177558 -249.620024) (xy 121.177803 -249.602357)
			(xy 121.181625 -249.567228) (xy 121.185178 -249.54992) (xy 121.187861 -249.535519) (xy 121.185723 -249.506312)
			(xy 121.175392 -249.47891) (xy 121.157714 -249.455562) (xy 121.134142 -249.438184) (xy 121.10661 -249.428204)
			(xy 121.077378 -249.426439) (xy 121.063004 -249.42927) (xy 121.044777 -249.433191) (xy 121.007732 -249.437395)
			(xy 120.98909 -249.437652) (xy 120.963124 -249.437134) (xy 120.911831 -249.429008) (xy 120.862441 -249.412959)
			(xy 120.816169 -249.389381) (xy 120.774156 -249.358855) (xy 120.737435 -249.322132) (xy 120.706911 -249.280117)
			(xy 120.683335 -249.233845) (xy 120.667288 -249.184453) (xy 120.659165 -249.13316) (xy 119.560648 -249.13316)
			(xy 120.128538 -249.70105) (xy 120.128538 -251.441204) (xy 120.645936 -251.441204) (xy 120.646357 -251.416651)
			(xy 120.653604 -251.368084) (xy 120.667952 -251.321122) (xy 120.689088 -251.276799) (xy 120.716546 -251.236088)
			(xy 120.732804 -251.217684) (xy 120.742601 -251.206191) (xy 120.755612 -251.178955) (xy 120.760079 -251.149103)
			(xy 120.755613 -251.119251) (xy 120.742604 -251.092014) (xy 120.732804 -251.080524) (xy 120.716535 -251.062128)
			(xy 120.689068 -251.021422) (xy 120.667932 -250.977096) (xy 120.653591 -250.93013) (xy 120.646364 -250.881558)
			(xy 120.645936 -250.857004) (xy 120.646445 -250.831037) (xy 120.65457 -250.779742) (xy 120.670618 -250.730349)
			(xy 120.694196 -250.684075) (xy 120.724722 -250.642059) (xy 120.761445 -250.605336) (xy 120.803461 -250.57481)
			(xy 120.849735 -250.551232) (xy 120.899128 -250.535184) (xy 120.950423 -250.527059) (xy 121.002357 -250.527059)
			(xy 121.053652 -250.535184) (xy 121.103045 -250.551232) (xy 121.149319 -250.57481) (xy 121.191335 -250.605336)
			(xy 121.228058 -250.642059) (xy 121.258584 -250.684075) (xy 121.282162 -250.730349) (xy 121.29821 -250.779742)
			(xy 121.306335 -250.831037) (xy 121.306844 -250.857004) (xy 121.306433 -250.881557) (xy 121.299185 -250.930125)
			(xy 121.284834 -250.977087) (xy 121.263696 -251.021411) (xy 121.236235 -251.062121) (xy 121.219976 -251.080524)
			(xy 121.210172 -251.092012) (xy 121.197165 -251.11925) (xy 121.1927 -251.149103) (xy 121.197167 -251.178955)
			(xy 121.210176 -251.206193) (xy 121.219976 -251.217684) (xy 121.236245 -251.236079) (xy 121.263713 -251.276786)
			(xy 121.28485 -251.321111) (xy 121.29919 -251.368078) (xy 121.306417 -251.41665) (xy 121.306844 -251.441204)
			(xy 121.306335 -251.467171) (xy 121.29821 -251.518466) (xy 121.282162 -251.567859) (xy 121.258584 -251.614133)
			(xy 121.228058 -251.656149) (xy 121.191335 -251.692872) (xy 121.149319 -251.723398) (xy 121.103045 -251.746976)
			(xy 121.053652 -251.763024) (xy 121.002357 -251.771149) (xy 120.950423 -251.771149) (xy 120.899128 -251.763024)
			(xy 120.849735 -251.746976) (xy 120.803461 -251.723398) (xy 120.761445 -251.692872) (xy 120.724722 -251.656149)
			(xy 120.694196 -251.614133) (xy 120.670618 -251.567859) (xy 120.65457 -251.518466) (xy 120.646445 -251.467171)
			(xy 120.645936 -251.441204) (xy 120.128538 -251.441204) (xy 120.128538 -253.193804) (xy 120.645936 -253.193804)
			(xy 120.646357 -253.169251) (xy 120.653604 -253.120684) (xy 120.667952 -253.073722) (xy 120.689088 -253.029399)
			(xy 120.716546 -252.988688) (xy 120.732804 -252.970284) (xy 120.742601 -252.958791) (xy 120.755612 -252.931555)
			(xy 120.760079 -252.901703) (xy 120.755613 -252.871851) (xy 120.742604 -252.844614) (xy 120.732804 -252.833124)
			(xy 120.716535 -252.814728) (xy 120.689068 -252.774022) (xy 120.667932 -252.729696) (xy 120.653591 -252.68273)
			(xy 120.646364 -252.634158) (xy 120.645936 -252.609604) (xy 120.646445 -252.583637) (xy 120.65457 -252.532342)
			(xy 120.670618 -252.482949) (xy 120.694196 -252.436675) (xy 120.724722 -252.394659) (xy 120.761445 -252.357936)
			(xy 120.803461 -252.32741) (xy 120.849735 -252.303832) (xy 120.899128 -252.287784) (xy 120.950423 -252.279659)
			(xy 121.002357 -252.279659) (xy 121.053652 -252.287784) (xy 121.103045 -252.303832) (xy 121.149319 -252.32741)
			(xy 121.191335 -252.357936) (xy 121.228058 -252.394659) (xy 121.258584 -252.436675) (xy 121.282162 -252.482949)
			(xy 121.29821 -252.532342) (xy 121.306335 -252.583637) (xy 121.306844 -252.609604) (xy 121.306433 -252.634157)
			(xy 121.299185 -252.682725) (xy 121.284834 -252.729687) (xy 121.263696 -252.774011) (xy 121.236235 -252.814721)
			(xy 121.219976 -252.833124) (xy 121.210172 -252.844612) (xy 121.197165 -252.87185) (xy 121.1927 -252.901703)
			(xy 121.197167 -252.931555) (xy 121.210176 -252.958793) (xy 121.219976 -252.970284) (xy 121.236245 -252.988679)
			(xy 121.263713 -253.029386) (xy 121.28485 -253.073711) (xy 121.29919 -253.120678) (xy 121.306417 -253.16925)
			(xy 121.306844 -253.193804) (xy 121.306335 -253.219771) (xy 121.29821 -253.271066) (xy 121.282162 -253.320459)
			(xy 121.258584 -253.366733) (xy 121.228058 -253.408749) (xy 121.191335 -253.445472) (xy 121.149319 -253.475998)
			(xy 121.103045 -253.499576) (xy 121.053652 -253.515624) (xy 121.002357 -253.523749) (xy 120.950423 -253.523749)
			(xy 120.899128 -253.515624) (xy 120.849735 -253.499576) (xy 120.803461 -253.475998) (xy 120.761445 -253.445472)
			(xy 120.724722 -253.408749) (xy 120.694196 -253.366733) (xy 120.670618 -253.320459) (xy 120.65457 -253.271066)
			(xy 120.646445 -253.219771) (xy 120.645936 -253.193804) (xy 120.128538 -253.193804) (xy 120.128538 -253.945703)
			(xy 121.758203 -253.945703) (xy 121.758203 -253.893769) (xy 121.766328 -253.842474) (xy 121.782376 -253.793081)
			(xy 121.805954 -253.746807) (xy 121.83648 -253.704791) (xy 121.873203 -253.668068) (xy 121.915219 -253.637542)
			(xy 121.961493 -253.613964) (xy 122.010886 -253.597916) (xy 122.062181 -253.589791) (xy 122.114115 -253.589791)
			(xy 122.16541 -253.597916) (xy 122.214803 -253.613964) (xy 122.261077 -253.637542) (xy 122.303093 -253.668068)
			(xy 122.339816 -253.704791) (xy 122.370342 -253.746807) (xy 122.39392 -253.793081) (xy 122.409968 -253.842474)
			(xy 122.418093 -253.893769) (xy 122.418602 -253.919736) (xy 122.418093 -253.945703) (xy 122.409968 -253.996998)
			(xy 122.39392 -254.046391) (xy 122.370342 -254.092665) (xy 122.339816 -254.134681) (xy 122.303093 -254.171404)
			(xy 122.261077 -254.20193) (xy 122.214803 -254.225508) (xy 122.16541 -254.241556) (xy 122.114115 -254.249681)
			(xy 122.062181 -254.249681) (xy 122.010886 -254.241556) (xy 121.961493 -254.225508) (xy 121.915219 -254.20193)
			(xy 121.873203 -254.171404) (xy 121.83648 -254.134681) (xy 121.805954 -254.092665) (xy 121.782376 -254.046391)
			(xy 121.766328 -253.996998) (xy 121.758203 -253.945703) (xy 120.128538 -253.945703) (xy 120.128538 -255.530604)
			(xy 120.645936 -255.530604) (xy 120.646357 -255.506051) (xy 120.653604 -255.457484) (xy 120.667952 -255.410522)
			(xy 120.689088 -255.366199) (xy 120.716546 -255.325488) (xy 120.732804 -255.307084) (xy 120.742601 -255.295591)
			(xy 120.755612 -255.268355) (xy 120.760079 -255.238503) (xy 120.755613 -255.208651) (xy 120.742604 -255.181414)
			(xy 120.732804 -255.169924) (xy 120.716535 -255.151528) (xy 120.689068 -255.110822) (xy 120.667932 -255.066496)
			(xy 120.653591 -255.01953) (xy 120.646364 -254.970958) (xy 120.645936 -254.946404) (xy 120.646459 -254.920437)
			(xy 120.654582 -254.869143) (xy 120.67063 -254.819752) (xy 120.694206 -254.773479) (xy 120.724731 -254.731463)
			(xy 120.761452 -254.69474) (xy 120.803467 -254.664213) (xy 120.849739 -254.640635) (xy 120.89913 -254.624586)
			(xy 120.950423 -254.61646) (xy 120.97639 -254.61595) (xy 121.00028 -254.616339) (xy 121.047563 -254.62321)
			(xy 121.093366 -254.636811) (xy 121.136737 -254.656858) (xy 121.156984 -254.669544) (xy 121.17003 -254.677435)
			(xy 121.199343 -254.685783) (xy 121.229814 -254.685127) (xy 121.25874 -254.675525) (xy 121.283554 -254.657828)
			(xy 121.302055 -254.633608) (xy 121.30786 -254.619506) (xy 121.317012 -254.596047) (xy 121.341353 -254.55197)
			(xy 121.372099 -254.512096) (xy 121.40854 -254.477349) (xy 121.449831 -254.448533) (xy 121.495017 -254.426316)
			(xy 121.54305 -254.411212) (xy 121.592818 -254.403572) (xy 121.617994 -254.403098) (xy 121.64396 -254.403676)
			(xy 121.695252 -254.411799) (xy 121.744642 -254.427846) (xy 121.790914 -254.451422) (xy 121.832928 -254.481946)
			(xy 121.86965 -254.518667) (xy 121.900175 -254.560681) (xy 121.923751 -254.606952) (xy 121.939799 -254.656342)
			(xy 121.947923 -254.707634) (xy 121.947923 -254.759566) (xy 121.939799 -254.810858) (xy 121.923751 -254.860248)
			(xy 121.900175 -254.906519) (xy 121.86965 -254.948533) (xy 121.832928 -254.985254) (xy 121.790914 -255.015778)
			(xy 121.744642 -255.039354) (xy 121.695252 -255.055401) (xy 121.64396 -255.063524) (xy 121.617994 -255.064006)
			(xy 121.594106 -255.063568) (xy 121.546825 -255.05671) (xy 121.501022 -255.043124) (xy 121.457649 -255.023091)
			(xy 121.4374 -255.010412) (xy 121.424288 -255.002643) (xy 121.395001 -254.994287) (xy 121.364553 -254.994926)
			(xy 121.335643 -255.004505) (xy 121.310836 -255.022173) (xy 121.292334 -255.046363) (xy 121.286524 -255.06045)
			(xy 121.278805 -255.080516) (xy 121.258914 -255.118631) (xy 121.23424 -255.153838) (xy 121.219976 -255.169924)
			(xy 121.210172 -255.181412) (xy 121.197165 -255.20865) (xy 121.1927 -255.238503) (xy 121.197167 -255.268355)
			(xy 121.210176 -255.295593) (xy 121.219976 -255.307084) (xy 121.236245 -255.325479) (xy 121.263713 -255.366186)
			(xy 121.28485 -255.410511) (xy 121.29919 -255.457478) (xy 121.306417 -255.50605) (xy 121.306844 -255.530604)
			(xy 121.306335 -255.556571) (xy 121.29821 -255.607866) (xy 121.282162 -255.657259) (xy 121.258584 -255.703533)
			(xy 121.228058 -255.745549) (xy 121.191335 -255.782272) (xy 121.149319 -255.812798) (xy 121.103045 -255.836376)
			(xy 121.053652 -255.852424) (xy 121.002357 -255.860549) (xy 120.950423 -255.860549) (xy 120.899128 -255.852424)
			(xy 120.849735 -255.836376) (xy 120.803461 -255.812798) (xy 120.761445 -255.782272) (xy 120.724722 -255.745549)
			(xy 120.694196 -255.703533) (xy 120.670618 -255.657259) (xy 120.65457 -255.607866) (xy 120.646445 -255.556571)
			(xy 120.645936 -255.530604) (xy 120.128538 -255.530604) (xy 120.128538 -258.477571) (xy 120.646445 -258.477571)
			(xy 120.646445 -258.425637) (xy 120.65457 -258.374342) (xy 120.670618 -258.324949) (xy 120.694196 -258.278675)
			(xy 120.724722 -258.236659) (xy 120.761445 -258.199936) (xy 120.803461 -258.16941) (xy 120.849735 -258.145832)
			(xy 120.899128 -258.129784) (xy 120.950423 -258.121659) (xy 121.002357 -258.121659) (xy 121.053652 -258.129784)
			(xy 121.103045 -258.145832) (xy 121.149319 -258.16941) (xy 121.191335 -258.199936) (xy 121.228058 -258.236659)
			(xy 121.258584 -258.278675) (xy 121.282162 -258.324949) (xy 121.29821 -258.374342) (xy 121.306335 -258.425637)
			(xy 121.306844 -258.451604) (xy 121.306335 -258.477571) (xy 121.29821 -258.528866) (xy 121.282162 -258.578259)
			(xy 121.258584 -258.624533) (xy 121.228058 -258.666549) (xy 121.191335 -258.703272) (xy 121.149319 -258.733798)
			(xy 121.103045 -258.757376) (xy 121.053652 -258.773424) (xy 121.002357 -258.781549) (xy 120.950423 -258.781549)
			(xy 120.899128 -258.773424) (xy 120.849735 -258.757376) (xy 120.803461 -258.733798) (xy 120.761445 -258.703272)
			(xy 120.724722 -258.666549) (xy 120.694196 -258.624533) (xy 120.670618 -258.578259) (xy 120.65457 -258.528866)
			(xy 120.646445 -258.477571) (xy 120.128538 -258.477571) (xy 120.128538 -258.77393) (xy 120.813322 -259.458714)
			(xy 120.844818 -259.445252) (xy 120.865313 -259.43698) (xy 120.907947 -259.425325) (xy 120.951751 -259.419442)
			(xy 120.97385 -259.41909) (xy 120.999813 -259.419603) (xy 121.0511 -259.427734) (xy 121.100483 -259.443787)
			(xy 121.146747 -259.467369) (xy 121.188752 -259.497896) (xy 121.225465 -259.53462) (xy 121.255981 -259.576634)
			(xy 121.279549 -259.622904) (xy 121.28605 -259.642923) (xy 122.227849 -259.642923) (xy 122.227849 -259.590989)
			(xy 122.235974 -259.539694) (xy 122.252022 -259.490301) (xy 122.2756 -259.444027) (xy 122.306126 -259.402011)
			(xy 122.342849 -259.365288) (xy 122.384865 -259.334762) (xy 122.431139 -259.311184) (xy 122.480532 -259.295136)
			(xy 122.531827 -259.287011) (xy 122.583761 -259.287011) (xy 122.635056 -259.295136) (xy 122.684449 -259.311184)
			(xy 122.730723 -259.334762) (xy 122.772739 -259.365288) (xy 122.809462 -259.402011) (xy 122.839988 -259.444027)
			(xy 122.863566 -259.490301) (xy 122.879614 -259.539694) (xy 122.887739 -259.590989) (xy 122.888248 -259.616956)
			(xy 122.887739 -259.642923) (xy 122.879614 -259.694218) (xy 122.863566 -259.743611) (xy 122.839988 -259.789885)
			(xy 122.809462 -259.831901) (xy 122.772739 -259.868624) (xy 122.730723 -259.89915) (xy 122.684449 -259.922728)
			(xy 122.635056 -259.938776) (xy 122.583761 -259.946901) (xy 122.531827 -259.946901) (xy 122.480532 -259.938776)
			(xy 122.431139 -259.922728) (xy 122.384865 -259.89915) (xy 122.342849 -259.868624) (xy 122.306126 -259.831901)
			(xy 122.2756 -259.789885) (xy 122.252022 -259.743611) (xy 122.235974 -259.694218) (xy 122.227849 -259.642923)
			(xy 121.28605 -259.642923) (xy 121.295588 -259.672292) (xy 121.303704 -259.72358) (xy 121.304304 -259.749544)
			(xy 121.303972 -259.771645) (xy 121.298112 -259.815457) (xy 121.286449 -259.858093) (xy 121.278142 -259.878576)
			(xy 121.26468 -259.910072) (xy 121.375678 -260.02107) (xy 121.375678 -260.456739) (xy 121.758203 -260.456739)
			(xy 121.758203 -260.404805) (xy 121.766328 -260.35351) (xy 121.782376 -260.304117) (xy 121.805954 -260.257843)
			(xy 121.83648 -260.215827) (xy 121.873203 -260.179104) (xy 121.915219 -260.148578) (xy 121.961493 -260.125)
			(xy 122.010886 -260.108952) (xy 122.062181 -260.100827) (xy 122.114115 -260.100827) (xy 122.16541 -260.108952)
			(xy 122.214803 -260.125) (xy 122.261077 -260.148578) (xy 122.303093 -260.179104) (xy 122.339816 -260.215827)
			(xy 122.370342 -260.257843) (xy 122.39392 -260.304117) (xy 122.409968 -260.35351) (xy 122.418093 -260.404805)
			(xy 122.418602 -260.430772) (xy 122.418093 -260.456739) (xy 122.698003 -260.456739) (xy 122.698003 -260.404805)
			(xy 122.706128 -260.35351) (xy 122.722176 -260.304117) (xy 122.745754 -260.257843) (xy 122.77628 -260.215827)
			(xy 122.813003 -260.179104) (xy 122.855019 -260.148578) (xy 122.901293 -260.125) (xy 122.950686 -260.108952)
			(xy 123.001981 -260.100827) (xy 123.053915 -260.100827) (xy 123.10521 -260.108952) (xy 123.154603 -260.125)
			(xy 123.200877 -260.148578) (xy 123.242893 -260.179104) (xy 123.279616 -260.215827) (xy 123.310142 -260.257843)
			(xy 123.33372 -260.304117) (xy 123.349768 -260.35351) (xy 123.357893 -260.404805) (xy 123.358402 -260.430772)
			(xy 123.357893 -260.456739) (xy 123.349768 -260.508034) (xy 123.33372 -260.557427) (xy 123.310142 -260.603701)
			(xy 123.279616 -260.645717) (xy 123.242893 -260.68244) (xy 123.200877 -260.712966) (xy 123.154603 -260.736544)
			(xy 123.10521 -260.752592) (xy 123.053915 -260.760717) (xy 123.001981 -260.760717) (xy 122.950686 -260.752592)
			(xy 122.901293 -260.736544) (xy 122.855019 -260.712966) (xy 122.813003 -260.68244) (xy 122.77628 -260.645717)
			(xy 122.745754 -260.603701) (xy 122.722176 -260.557427) (xy 122.706128 -260.508034) (xy 122.698003 -260.456739)
			(xy 122.418093 -260.456739) (xy 122.409968 -260.508034) (xy 122.39392 -260.557427) (xy 122.370342 -260.603701)
			(xy 122.339816 -260.645717) (xy 122.303093 -260.68244) (xy 122.261077 -260.712966) (xy 122.214803 -260.736544)
			(xy 122.16541 -260.752592) (xy 122.114115 -260.760717) (xy 122.062181 -260.760717) (xy 122.010886 -260.752592)
			(xy 121.961493 -260.736544) (xy 121.915219 -260.712966) (xy 121.873203 -260.68244) (xy 121.83648 -260.645717)
			(xy 121.805954 -260.603701) (xy 121.782376 -260.557427) (xy 121.766328 -260.508034) (xy 121.758203 -260.456739)
			(xy 121.375678 -260.456739) (xy 121.375678 -261.36727) (xy 121.373138 -261.36981) (xy 121.373138 -261.52475)
			(xy 121.454418 -261.60603) (xy 122.142758 -261.60603)
		)
		(stroke
			(width 0)
			(type solid)
		)
		(fill yes)
		(layer "In6.Cu")
		(net "PVCCD_HV_CPU1")
	)
	(gr_poly
		(pts
			(xy 436.860442 -34.335974) (xy 436.863675 -34.308033) (xy 436.877301 -34.253464) (xy 436.898791 -34.201486)
			(xy 436.927679 -34.153226) (xy 436.963339 -34.10973) (xy 437.004998 -34.071941) (xy 437.051754 -34.040678)
			(xy 437.102593 -34.016617) (xy 437.156414 -34.000281) (xy 437.212049 -33.992024) (xy 437.268295 -33.992024)
			(xy 437.32393 -34.000281) (xy 437.377751 -34.016617) (xy 437.42859 -34.040678) (xy 437.475346 -34.071941)
			(xy 437.517005 -34.10973) (xy 437.552665 -34.153226) (xy 437.581553 -34.201486) (xy 437.603043 -34.253464)
			(xy 437.616669 -34.308033) (xy 437.619902 -34.335974) (xy 437.624474 -34.381948) (xy 455.98588 -34.381948)
			(xy 456.767692 -33.599882) (xy 456.767692 -16.759174) (xy 453.687434 -13.678916) (xy 453.05091 -13.678916)
			(xy 453.036646 -13.67934) (xy 453.009206 -13.687135) (xy 452.985003 -13.70223) (xy 452.965931 -13.723441)
			(xy 452.953485 -13.749108) (xy 452.94864 -13.777219) (xy 452.949818 -13.791438) (xy 452.950891 -13.801882)
			(xy 452.952033 -13.822849) (xy 452.952104 -13.833348) (xy 452.951618 -13.860599) (xy 452.943862 -13.914547)
			(xy 452.928507 -13.966842) (xy 452.905865 -14.016419) (xy 452.876399 -14.062269) (xy 452.840708 -14.10346)
			(xy 452.799517 -14.139151) (xy 452.753667 -14.168617) (xy 452.70409 -14.191259) (xy 452.651795 -14.206614)
			(xy 452.597847 -14.21437) (xy 452.543345 -14.21437) (xy 452.489397 -14.206614) (xy 452.437102 -14.191259)
			(xy 452.387525 -14.168617) (xy 452.341675 -14.139151) (xy 452.300484 -14.10346) (xy 452.264793 -14.062269)
			(xy 452.235327 -14.016419) (xy 452.212685 -13.966842) (xy 452.19733 -13.914547) (xy 452.189574 -13.860599)
			(xy 452.189088 -13.833348) (xy 452.189153 -13.822849) (xy 452.190299 -13.801882) (xy 452.191374 -13.791438)
			(xy 452.19242 -13.777229) (xy 452.187523 -13.749175) (xy 452.175073 -13.723562) (xy 452.156038 -13.702379)
			(xy 452.131895 -13.687274) (xy 452.104521 -13.679419) (xy 452.090282 -13.678916) (xy 451.660514 -13.678916)
			(xy 451.649592 -13.714984) (xy 451.641311 -13.740785) (xy 451.618475 -13.789925) (xy 451.588915 -13.835338)
			(xy 451.553226 -13.876112) (xy 451.512126 -13.911424) (xy 451.466442 -13.940565) (xy 451.417094 -13.962948)
			(xy 451.365076 -13.978121) (xy 451.311433 -13.985781) (xy 451.28434 -13.986256) (xy 451.257086 -13.985773)
			(xy 451.203131 -13.978021) (xy 451.150829 -13.96267) (xy 451.101243 -13.940032) (xy 451.055385 -13.910568)
			(xy 451.014186 -13.874877) (xy 450.978485 -13.833686) (xy 450.94901 -13.787834) (xy 450.926361 -13.738254)
			(xy 450.910997 -13.685955) (xy 450.903233 -13.632002) (xy 450.902832 -13.604748) (xy 450.902992 -13.589633)
			(xy 450.90541 -13.559498) (xy 450.907658 -13.54455) (xy 450.909497 -13.529981) (xy 450.905703 -13.500875)
			(xy 450.893794 -13.474047) (xy 450.87475 -13.45171) (xy 450.850144 -13.435706) (xy 450.822004 -13.427356)
			(xy 450.807328 -13.426948) (xy 450.501766 -13.426948) (xy 450.486555 -13.427504) (xy 450.457477 -13.436446)
			(xy 450.432324 -13.453556) (xy 450.413326 -13.477317) (xy 450.402171 -13.505619) (xy 450.399847 -13.535952)
			(xy 450.402706 -13.5509) (xy 450.407104 -13.571704) (xy 450.41181 -13.613966) (xy 450.412104 -13.635228)
			(xy 450.411618 -13.662479) (xy 450.403862 -13.716427) (xy 450.388507 -13.768722) (xy 450.365865 -13.818299)
			(xy 450.336399 -13.864149) (xy 450.300708 -13.90534) (xy 450.259517 -13.941031) (xy 450.213667 -13.970497)
			(xy 450.16409 -13.993139) (xy 450.111795 -14.008494) (xy 450.057847 -14.01625) (xy 450.003345 -14.01625)
			(xy 449.949397 -14.008494) (xy 449.897102 -13.993139) (xy 449.847525 -13.970497) (xy 449.801675 -13.941031)
			(xy 449.760484 -13.90534) (xy 449.724793 -13.864149) (xy 449.695327 -13.818299) (xy 449.672685 -13.768722)
			(xy 449.65733 -13.716427) (xy 449.649574 -13.662479) (xy 449.649088 -13.635228) (xy 449.649365 -13.613965)
			(xy 449.654076 -13.571702) (xy 449.658486 -13.5509) (xy 449.661273 -13.535952) (xy 449.658927 -13.505652)
			(xy 449.647769 -13.477384) (xy 449.628788 -13.45365) (xy 449.603664 -13.436552) (xy 449.574621 -13.427603)
			(xy 449.559426 -13.426948) (xy 449.35648 -13.426948) (xy 449.342803 -13.427383) (xy 449.31643 -13.434644)
			(xy 449.292942 -13.448663) (xy 449.274032 -13.468428) (xy 449.261067 -13.492514) (xy 449.254981 -13.519182)
			(xy 449.255134 -13.532866) (xy 449.255388 -13.548868) (xy 449.254902 -13.576119) (xy 449.247146 -13.630067)
			(xy 449.231791 -13.682362) (xy 449.209149 -13.731939) (xy 449.179683 -13.777789) (xy 449.143992 -13.81898)
			(xy 449.102801 -13.854671) (xy 449.056951 -13.884137) (xy 449.007374 -13.906779) (xy 448.955079 -13.922134)
			(xy 448.901131 -13.92989) (xy 448.846629 -13.92989) (xy 448.792681 -13.922134) (xy 448.740386 -13.906779)
			(xy 448.690809 -13.884137) (xy 448.644959 -13.854671) (xy 448.603768 -13.81898) (xy 448.568077 -13.777789)
			(xy 448.538611 -13.731939) (xy 448.515969 -13.682362) (xy 448.500614 -13.630067) (xy 448.492858 -13.576119)
			(xy 448.492372 -13.548868) (xy 448.492626 -13.532866) (xy 448.492759 -13.51919) (xy 448.486623 -13.492548)
			(xy 448.473643 -13.468486) (xy 448.454748 -13.448727) (xy 448.43129 -13.434684) (xy 448.404949 -13.427363)
			(xy 448.39128 -13.426948) (xy 448.21856 -13.426948) (xy 448.205242 -13.427349) (xy 448.179516 -13.434253)
			(xy 448.156454 -13.447581) (xy 448.137627 -13.466424) (xy 448.124319 -13.489498) (xy 448.117437 -13.51523)
			(xy 448.11696 -13.528548) (xy 448.116474 -13.555799) (xy 448.108718 -13.609747) (xy 448.093363 -13.662042)
			(xy 448.070721 -13.711619) (xy 448.041255 -13.757469) (xy 448.005564 -13.79866) (xy 447.964373 -13.834351)
			(xy 447.918523 -13.863817) (xy 447.868946 -13.886459) (xy 447.816651 -13.901814) (xy 447.762703 -13.90957)
			(xy 447.708201 -13.90957) (xy 447.654253 -13.901814) (xy 447.601958 -13.886459) (xy 447.552381 -13.863817)
			(xy 447.506531 -13.834351) (xy 447.46534 -13.79866) (xy 447.429649 -13.757469) (xy 447.400183 -13.711619)
			(xy 447.377541 -13.662042) (xy 447.362186 -13.609747) (xy 447.35443 -13.555799) (xy 447.353944 -13.528548)
			(xy 447.353555 -13.515218) (xy 447.346667 -13.489463) (xy 447.333347 -13.466369) (xy 447.314504 -13.447509)
			(xy 447.291422 -13.434169) (xy 447.265674 -13.427257) (xy 447.252344 -13.426948) (xy 445.88938 -13.426948)
			(xy 445.36868 -13.947648) (xy 445.36868 -15.998698) (xy 450.297804 -15.998698) (xy 450.298267 -15.971123)
			(xy 450.30622 -15.91655) (xy 450.321945 -15.86369) (xy 450.345116 -15.813644) (xy 450.375249 -15.767455)
			(xy 450.411717 -15.726084) (xy 450.432424 -15.707868) (xy 450.443321 -15.69797) (xy 450.459389 -15.673319)
			(xy 450.46777 -15.645112) (xy 450.467769 -15.615686) (xy 450.459388 -15.587479) (xy 450.443319 -15.562828)
			(xy 450.432424 -15.552928) (xy 450.411728 -15.5347) (xy 450.375256 -15.493336) (xy 450.345121 -15.447149)
			(xy 450.321952 -15.397105) (xy 450.306233 -15.344245) (xy 450.298291 -15.289672) (xy 450.297804 -15.262098)
			(xy 450.29829 -15.234847) (xy 450.306046 -15.180899) (xy 450.321401 -15.128604) (xy 450.344043 -15.079027)
			(xy 450.373509 -15.033177) (xy 450.4092 -14.991986) (xy 450.450391 -14.956295) (xy 450.496241 -14.926829)
			(xy 450.545818 -14.904187) (xy 450.598113 -14.888832) (xy 450.652061 -14.881076) (xy 450.706563 -14.881076)
			(xy 450.760511 -14.888832) (xy 450.812806 -14.904187) (xy 450.862383 -14.926829) (xy 450.908233 -14.956295)
			(xy 450.949424 -14.991986) (xy 450.985115 -15.033177) (xy 451.014581 -15.079027) (xy 451.037223 -15.128604)
			(xy 451.052578 -15.180899) (xy 451.060334 -15.234847) (xy 451.06082 -15.262098) (xy 451.060346 -15.289672)
			(xy 451.052394 -15.344244) (xy 451.03667 -15.397104) (xy 451.013502 -15.44715) (xy 450.983371 -15.493339)
			(xy 450.946906 -15.534711) (xy 450.9262 -15.552928) (xy 450.915305 -15.562829) (xy 450.899233 -15.587479)
			(xy 450.890849 -15.615685) (xy 450.890849 -15.645112) (xy 450.899232 -15.673319) (xy 450.915304 -15.697969)
			(xy 450.9262 -15.707868) (xy 450.946899 -15.726092) (xy 450.98337 -15.767458) (xy 451.013504 -15.813646)
			(xy 451.036672 -15.863691) (xy 451.052391 -15.916551) (xy 451.060333 -15.971124) (xy 451.06082 -15.998698)
			(xy 451.060334 -16.025949) (xy 451.052578 -16.079897) (xy 451.037223 -16.132192) (xy 451.014581 -16.181769)
			(xy 450.985115 -16.227619) (xy 450.949424 -16.26881) (xy 450.908233 -16.304501) (xy 450.862383 -16.333967)
			(xy 450.812806 -16.356609) (xy 450.760511 -16.371964) (xy 450.706563 -16.37972) (xy 450.652061 -16.37972)
			(xy 450.598113 -16.371964) (xy 450.545818 -16.356609) (xy 450.496241 -16.333967) (xy 450.450391 -16.304501)
			(xy 450.4092 -16.26881) (xy 450.373509 -16.227619) (xy 450.344043 -16.181769) (xy 450.321401 -16.132192)
			(xy 450.306046 -16.079897) (xy 450.29829 -16.025949) (xy 450.297804 -15.998698) (xy 445.36868 -15.998698)
			(xy 445.36868 -18.446242) (xy 446.165984 -18.446242) (xy 446.170055 -18.39062) (xy 446.182181 -18.336183)
			(xy 446.202104 -18.284092) (xy 446.2294 -18.235457) (xy 446.263486 -18.191314) (xy 446.303635 -18.152605)
			(xy 446.348993 -18.120154) (xy 446.398593 -18.094653) (xy 446.451377 -18.076646) (xy 446.50622 -18.066516)
			(xy 446.561954 -18.064479) (xy 446.617391 -18.070579) (xy 446.671348 -18.084685) (xy 446.722677 -18.106497)
			(xy 446.770283 -18.135551) (xy 446.813151 -18.171226) (xy 446.850368 -18.212763) (xy 446.881141 -18.259276)
			(xy 446.904813 -18.309773) (xy 446.920881 -18.36318) (xy 446.929001 -18.418356) (xy 446.92951 -18.446242)
			(xy 446.929195 -18.463514) (xy 449.291454 -18.463514) (xy 449.295525 -18.407892) (xy 449.307651 -18.353455)
			(xy 449.327574 -18.301364) (xy 449.35487 -18.252729) (xy 449.388956 -18.208586) (xy 449.429105 -18.169877)
			(xy 449.474463 -18.137426) (xy 449.524063 -18.111925) (xy 449.576847 -18.093918) (xy 449.63169 -18.083788)
			(xy 449.687424 -18.081751) (xy 449.742861 -18.087851) (xy 449.796818 -18.101957) (xy 449.848147 -18.123769)
			(xy 449.895753 -18.152823) (xy 449.938621 -18.188498) (xy 449.975838 -18.230035) (xy 450.006611 -18.276548)
			(xy 450.030283 -18.327045) (xy 450.046351 -18.380452) (xy 450.054471 -18.435628) (xy 450.05498 -18.463514)
			(xy 450.054471 -18.4914) (xy 450.046351 -18.546576) (xy 450.030283 -18.599983) (xy 450.018171 -18.62582)
			(xy 450.615302 -18.62582) (xy 450.619373 -18.570198) (xy 450.631499 -18.515761) (xy 450.651422 -18.46367)
			(xy 450.678718 -18.415035) (xy 450.712804 -18.370892) (xy 450.752953 -18.332183) (xy 450.798311 -18.299732)
			(xy 450.847911 -18.274231) (xy 450.900695 -18.256224) (xy 450.955538 -18.246094) (xy 451.011272 -18.244057)
			(xy 451.066709 -18.250157) (xy 451.120666 -18.264263) (xy 451.171995 -18.286075) (xy 451.219601 -18.315129)
			(xy 451.262469 -18.350804) (xy 451.299686 -18.392341) (xy 451.330459 -18.438854) (xy 451.354131 -18.489351)
			(xy 451.364392 -18.523458) (xy 451.682104 -18.523458) (xy 451.682608 -18.495885) (xy 451.690553 -18.441314)
			(xy 451.70627 -18.388454) (xy 451.729433 -18.338408) (xy 451.759559 -18.292218) (xy 451.79602 -18.250845)
			(xy 451.816724 -18.232628) (xy 451.827661 -18.222771) (xy 451.843728 -18.198108) (xy 451.852104 -18.16989)
			(xy 451.852096 -18.140456) (xy 451.843705 -18.112242) (xy 451.827625 -18.087588) (xy 451.816724 -18.077688)
			(xy 451.796009 -18.059481) (xy 451.759538 -18.018112) (xy 451.729405 -17.971922) (xy 451.70624 -17.921873)
			(xy 451.690525 -17.869009) (xy 451.682588 -17.814433) (xy 451.682104 -17.786858) (xy 451.68259 -17.759607)
			(xy 451.690346 -17.705659) (xy 451.705701 -17.653364) (xy 451.728343 -17.603787) (xy 451.757809 -17.557937)
			(xy 451.7935 -17.516746) (xy 451.834691 -17.481055) (xy 451.880541 -17.451589) (xy 451.930118 -17.428947)
			(xy 451.982413 -17.413592) (xy 452.036361 -17.405836) (xy 452.090863 -17.405836) (xy 452.144811 -17.413592)
			(xy 452.197106 -17.428947) (xy 452.246683 -17.451589) (xy 452.292533 -17.481055) (xy 452.333724 -17.516746)
			(xy 452.369415 -17.557937) (xy 452.398881 -17.603787) (xy 452.421523 -17.653364) (xy 452.436878 -17.705659)
			(xy 452.444634 -17.759607) (xy 452.44512 -17.786858) (xy 452.444618 -17.814431) (xy 452.436672 -17.869002)
			(xy 452.420954 -17.921861) (xy 452.39779 -17.971907) (xy 452.367665 -18.018098) (xy 452.331204 -18.059471)
			(xy 452.3105 -18.077688) (xy 452.299645 -18.087629) (xy 452.283572 -18.112268) (xy 452.275183 -18.140464)
			(xy 452.275176 -18.169882) (xy 452.283549 -18.198083) (xy 452.299609 -18.222729) (xy 452.3105 -18.232628)
			(xy 452.331228 -18.250821) (xy 452.367697 -18.292194) (xy 452.397827 -18.338387) (xy 452.42099 -18.388439)
			(xy 452.436703 -18.441305) (xy 452.444637 -18.495882) (xy 452.44512 -18.523458) (xy 452.444634 -18.550709)
			(xy 452.436878 -18.604657) (xy 452.421523 -18.656952) (xy 452.398881 -18.706529) (xy 452.369415 -18.752379)
			(xy 452.333724 -18.79357) (xy 452.292533 -18.829261) (xy 452.246683 -18.858727) (xy 452.197106 -18.881369)
			(xy 452.144811 -18.896724) (xy 452.090863 -18.90448) (xy 452.036361 -18.90448) (xy 451.982413 -18.896724)
			(xy 451.930118 -18.881369) (xy 451.880541 -18.858727) (xy 451.834691 -18.829261) (xy 451.7935 -18.79357)
			(xy 451.757809 -18.752379) (xy 451.728343 -18.706529) (xy 451.705701 -18.656952) (xy 451.690346 -18.604657)
			(xy 451.68259 -18.550709) (xy 451.682104 -18.523458) (xy 451.364392 -18.523458) (xy 451.370199 -18.542758)
			(xy 451.378319 -18.597934) (xy 451.378828 -18.62582) (xy 451.378319 -18.653706) (xy 451.370199 -18.708882)
			(xy 451.354131 -18.762289) (xy 451.330459 -18.812786) (xy 451.299686 -18.859299) (xy 451.262469 -18.900836)
			(xy 451.219601 -18.936511) (xy 451.171995 -18.965565) (xy 451.120666 -18.987377) (xy 451.066709 -19.001483)
			(xy 451.011272 -19.007583) (xy 450.955538 -19.005546) (xy 450.900695 -18.995416) (xy 450.847911 -18.977409)
			(xy 450.798311 -18.951908) (xy 450.752953 -18.919457) (xy 450.712804 -18.880748) (xy 450.678718 -18.836605)
			(xy 450.651422 -18.78797) (xy 450.631499 -18.735879) (xy 450.619373 -18.681442) (xy 450.615302 -18.62582)
			(xy 450.018171 -18.62582) (xy 450.006611 -18.65048) (xy 449.975838 -18.696993) (xy 449.938621 -18.73853)
			(xy 449.895753 -18.774205) (xy 449.848147 -18.803259) (xy 449.796818 -18.825071) (xy 449.742861 -18.839177)
			(xy 449.687424 -18.845277) (xy 449.63169 -18.84324) (xy 449.576847 -18.83311) (xy 449.524063 -18.815103)
			(xy 449.474463 -18.789602) (xy 449.429105 -18.757151) (xy 449.388956 -18.718442) (xy 449.35487 -18.674299)
			(xy 449.327574 -18.625664) (xy 449.307651 -18.573573) (xy 449.295525 -18.519136) (xy 449.291454 -18.463514)
			(xy 446.929195 -18.463514) (xy 446.929001 -18.474128) (xy 446.920881 -18.529304) (xy 446.904813 -18.582711)
			(xy 446.881141 -18.633208) (xy 446.850368 -18.679721) (xy 446.813151 -18.721258) (xy 446.770283 -18.756933)
			(xy 446.722677 -18.785987) (xy 446.671348 -18.807799) (xy 446.617391 -18.821905) (xy 446.561954 -18.828005)
			(xy 446.50622 -18.825968) (xy 446.451377 -18.815838) (xy 446.398593 -18.797831) (xy 446.348993 -18.77233)
			(xy 446.303635 -18.739879) (xy 446.263486 -18.70117) (xy 446.2294 -18.657027) (xy 446.202104 -18.608392)
			(xy 446.182181 -18.556301) (xy 446.170055 -18.501864) (xy 446.165984 -18.446242) (xy 445.36868 -18.446242)
			(xy 445.36868 -19.506438) (xy 448.687442 -19.506438) (xy 448.691513 -19.450816) (xy 448.703639 -19.396379)
			(xy 448.723562 -19.344288) (xy 448.750858 -19.295653) (xy 448.784944 -19.25151) (xy 448.825093 -19.212801)
			(xy 448.870451 -19.18035) (xy 448.920051 -19.154849) (xy 448.972835 -19.136842) (xy 449.027678 -19.126712)
			(xy 449.083412 -19.124675) (xy 449.138849 -19.130775) (xy 449.192806 -19.144881) (xy 449.244135 -19.166693)
			(xy 449.291741 -19.195747) (xy 449.334609 -19.231422) (xy 449.371826 -19.272959) (xy 449.402599 -19.319472)
			(xy 449.411916 -19.339348) (xy 453.045106 -19.339348) (xy 453.045106 -19.284852) (xy 453.052861 -19.230911)
			(xy 453.068214 -19.178623) (xy 453.090851 -19.129052) (xy 453.120312 -19.083206) (xy 453.155997 -19.04202)
			(xy 453.197181 -19.006331) (xy 453.243024 -18.976866) (xy 453.292593 -18.954225) (xy 453.34488 -18.938868)
			(xy 453.39882 -18.931108) (xy 453.426068 -18.93062) (xy 453.452759 -18.931048) (xy 453.505623 -18.938468)
			(xy 453.556937 -18.953181) (xy 453.6057 -18.9749) (xy 453.650961 -19.003203) (xy 453.671686 -19.020028)
			(xy 453.683668 -19.029415) (xy 453.711676 -19.041295) (xy 453.741941 -19.044396) (xy 453.771777 -19.038442)
			(xy 453.798534 -19.023963) (xy 453.819837 -19.002243) (xy 453.833796 -18.97521) (xy 453.83704 -18.960338)
			(xy 453.84216 -18.934245) (xy 453.858715 -18.883713) (xy 453.882129 -18.83597) (xy 453.911946 -18.791942)
			(xy 453.94759 -18.752482) (xy 453.988368 -18.718356) (xy 454.033492 -18.690223) (xy 454.082085 -18.668631)
			(xy 454.133206 -18.653996) (xy 454.185865 -18.646604) (xy 454.212452 -18.64614) (xy 454.239706 -18.6466)
			(xy 454.293659 -18.654352) (xy 454.34596 -18.669704) (xy 454.395543 -18.692345) (xy 454.441399 -18.721812)
			(xy 454.482594 -18.757506) (xy 454.518288 -18.798701) (xy 454.547755 -18.844557) (xy 454.570396 -18.89414)
			(xy 454.585748 -18.946441) (xy 454.5935 -19.000394) (xy 454.59396 -19.027648) (xy 454.593489 -19.054251)
			(xy 454.586114 -19.106944) (xy 454.571485 -19.1581) (xy 454.549886 -19.206726) (xy 454.521737 -19.251877)
			(xy 454.487586 -19.292676) (xy 454.448093 -19.328331) (xy 454.42632 -19.343624) (xy 454.41484 -19.35196)
			(xy 454.396633 -19.373702) (xy 454.385114 -19.399615) (xy 454.381172 -19.427699) (xy 454.385113 -19.455782)
			(xy 454.396632 -19.481696) (xy 454.414838 -19.503439) (xy 454.42632 -19.511772) (xy 454.448077 -19.527085)
			(xy 454.487558 -19.562747) (xy 454.521704 -19.603547) (xy 454.549852 -19.648694) (xy 454.571456 -19.697312)
			(xy 454.586099 -19.748461) (xy 454.593495 -19.801147) (xy 454.59396 -19.827748) (xy 454.593474 -19.854999)
			(xy 454.585718 -19.908947) (xy 454.570363 -19.961242) (xy 454.547721 -20.010819) (xy 454.518255 -20.056669)
			(xy 454.482564 -20.09786) (xy 454.441373 -20.133551) (xy 454.395523 -20.163017) (xy 454.345946 -20.185659)
			(xy 454.293651 -20.201014) (xy 454.239703 -20.20877) (xy 454.185201 -20.20877) (xy 454.131253 -20.201014)
			(xy 454.078958 -20.185659) (xy 454.029381 -20.163017) (xy 453.983531 -20.133551) (xy 453.94234 -20.09786)
			(xy 453.906649 -20.056669) (xy 453.877183 -20.010819) (xy 453.854541 -19.961242) (xy 453.839186 -19.908947)
			(xy 453.83143 -19.854999) (xy 453.830944 -19.827748) (xy 453.83141 -19.801144) (xy 453.838786 -19.748451)
			(xy 453.853416 -19.697295) (xy 453.875015 -19.64867) (xy 453.903165 -19.603519) (xy 453.937317 -19.56272)
			(xy 453.97681 -19.527064) (xy 453.998584 -19.511772) (xy 454.010068 -19.503441) (xy 454.028274 -19.481698)
			(xy 454.039793 -19.455783) (xy 454.043733 -19.427699) (xy 454.039792 -19.399615) (xy 454.028273 -19.3737)
			(xy 454.010066 -19.351958) (xy 453.998584 -19.343624) (xy 453.99038 -19.338018) (xy 453.974496 -19.326074)
			(xy 453.966834 -19.319748) (xy 453.954892 -19.310292) (xy 453.926864 -19.298389) (xy 453.896573 -19.295278)
			(xy 453.866711 -19.301235) (xy 453.839932 -19.31573) (xy 453.818617 -19.337476) (xy 453.80466 -19.36454)
			(xy 453.80148 -19.379438) (xy 453.796323 -19.405524) (xy 453.779772 -19.456054) (xy 453.756363 -19.503796)
			(xy 453.72655 -19.547823) (xy 453.690911 -19.587284) (xy 453.650136 -19.621411) (xy 453.605017 -19.649545)
			(xy 453.556427 -19.671139) (xy 453.505309 -19.685776) (xy 453.452654 -19.69317) (xy 453.426068 -19.693636)
			(xy 453.39882 -19.693092) (xy 453.34488 -19.685332) (xy 453.292593 -19.669975) (xy 453.243024 -19.647334)
			(xy 453.197181 -19.617869) (xy 453.155997 -19.58218) (xy 453.120312 -19.540994) (xy 453.090851 -19.495148)
			(xy 453.068214 -19.445577) (xy 453.052861 -19.393289) (xy 453.045106 -19.339348) (xy 449.411916 -19.339348)
			(xy 449.426271 -19.369969) (xy 449.442339 -19.423376) (xy 449.450459 -19.478552) (xy 449.450968 -19.506438)
			(xy 449.450459 -19.534324) (xy 449.442339 -19.5895) (xy 449.426271 -19.642907) (xy 449.402599 -19.693404)
			(xy 449.371826 -19.739917) (xy 449.334609 -19.781454) (xy 449.291741 -19.817129) (xy 449.244135 -19.846183)
			(xy 449.192806 -19.867995) (xy 449.138849 -19.882101) (xy 449.083412 -19.888201) (xy 449.027678 -19.886164)
			(xy 448.972835 -19.876034) (xy 448.920051 -19.858027) (xy 448.870451 -19.832526) (xy 448.825093 -19.800075)
			(xy 448.784944 -19.761366) (xy 448.750858 -19.717223) (xy 448.723562 -19.668588) (xy 448.703639 -19.616497)
			(xy 448.691513 -19.56206) (xy 448.687442 -19.506438) (xy 445.36868 -19.506438) (xy 445.36868 -21.236178)
			(xy 448.479162 -21.236178) (xy 448.483233 -21.180556) (xy 448.495359 -21.126119) (xy 448.515282 -21.074028)
			(xy 448.542578 -21.025393) (xy 448.576664 -20.98125) (xy 448.616813 -20.942541) (xy 448.662171 -20.91009)
			(xy 448.711771 -20.884589) (xy 448.764555 -20.866582) (xy 448.819398 -20.856452) (xy 448.875132 -20.854415)
			(xy 448.930569 -20.860515) (xy 448.984526 -20.874621) (xy 449.035855 -20.896433) (xy 449.083461 -20.925487)
			(xy 449.126329 -20.961162) (xy 449.163546 -21.002699) (xy 449.194319 -21.049212) (xy 449.217991 -21.099709)
			(xy 449.234059 -21.153116) (xy 449.242179 -21.208292) (xy 449.242688 -21.236178) (xy 449.242179 -21.264064)
			(xy 449.234059 -21.31924) (xy 449.217991 -21.372647) (xy 449.194319 -21.423144) (xy 449.163546 -21.469657)
			(xy 449.126329 -21.511194) (xy 449.083461 -21.546869) (xy 449.035855 -21.575923) (xy 448.984526 -21.597735)
			(xy 448.930569 -21.611841) (xy 448.875132 -21.617941) (xy 448.819398 -21.615904) (xy 448.764555 -21.605774)
			(xy 448.711771 -21.587767) (xy 448.662171 -21.562266) (xy 448.616813 -21.529815) (xy 448.576664 -21.491106)
			(xy 448.542578 -21.446963) (xy 448.515282 -21.398328) (xy 448.495359 -21.346237) (xy 448.483233 -21.2918)
			(xy 448.479162 -21.236178) (xy 445.36868 -21.236178) (xy 445.36868 -21.623528) (xy 453.717152 -21.623528)
			(xy 453.717637 -21.595899) (xy 453.725599 -21.541219) (xy 453.741363 -21.488258) (xy 453.764597 -21.438123)
			(xy 453.794816 -21.391861) (xy 453.83139 -21.35044) (xy 453.873553 -21.314725) (xy 453.89673 -21.299678)
			(xy 453.908805 -21.291585) (xy 453.928135 -21.269892) (xy 453.940583 -21.243638) (xy 453.945145 -21.214942)
			(xy 453.941451 -21.186121) (xy 453.9298 -21.159504) (xy 453.92086 -21.14804) (xy 453.90395 -21.127324)
			(xy 453.875493 -21.082051) (xy 453.85365 -21.033242) (xy 453.838851 -20.981856) (xy 453.831387 -20.928905)
			(xy 453.830944 -20.902168) (xy 453.83143 -20.874917) (xy 453.839186 -20.820969) (xy 453.854541 -20.768674)
			(xy 453.877183 -20.719097) (xy 453.906649 -20.673247) (xy 453.94234 -20.632056) (xy 453.983531 -20.596365)
			(xy 454.029381 -20.566899) (xy 454.078958 -20.544257) (xy 454.131253 -20.528902) (xy 454.185201 -20.521146)
			(xy 454.239703 -20.521146) (xy 454.293651 -20.528902) (xy 454.345946 -20.544257) (xy 454.395523 -20.566899)
			(xy 454.441373 -20.596365) (xy 454.482564 -20.632056) (xy 454.518255 -20.673247) (xy 454.547721 -20.719097)
			(xy 454.570363 -20.768674) (xy 454.585718 -20.820969) (xy 454.593474 -20.874917) (xy 454.59396 -20.902168)
			(xy 454.593513 -20.929798) (xy 454.585549 -20.984482) (xy 454.569782 -21.037446) (xy 454.546543 -21.087583)
			(xy 454.516317 -21.133844) (xy 454.479735 -21.175263) (xy 454.437563 -21.210974) (xy 454.414382 -21.226018)
			(xy 454.402311 -21.234117) (xy 454.382979 -21.255808) (xy 454.370529 -21.282061) (xy 454.365967 -21.310756)
			(xy 454.369661 -21.339576) (xy 454.381312 -21.366193) (xy 454.390252 -21.377656) (xy 454.407162 -21.398372)
			(xy 454.435619 -21.443645) (xy 454.457462 -21.492455) (xy 454.472261 -21.54384) (xy 454.479725 -21.596791)
			(xy 454.480168 -21.623528) (xy 454.479682 -21.650779) (xy 454.471926 -21.704727) (xy 454.456571 -21.757022)
			(xy 454.433929 -21.806599) (xy 454.404463 -21.852449) (xy 454.368772 -21.89364) (xy 454.327581 -21.929331)
			(xy 454.281731 -21.958797) (xy 454.232154 -21.981439) (xy 454.179859 -21.996794) (xy 454.125911 -22.00455)
			(xy 454.071409 -22.00455) (xy 454.017461 -21.996794) (xy 453.965166 -21.981439) (xy 453.915589 -21.958797)
			(xy 453.869739 -21.929331) (xy 453.828548 -21.89364) (xy 453.792857 -21.852449) (xy 453.763391 -21.806599)
			(xy 453.740749 -21.757022) (xy 453.725394 -21.704727) (xy 453.717638 -21.650779) (xy 453.717152 -21.623528)
			(xy 445.36868 -21.623528) (xy 445.36868 -22.426422) (xy 450.115176 -22.426422) (xy 450.119247 -22.3708)
			(xy 450.131373 -22.316363) (xy 450.151296 -22.264272) (xy 450.178592 -22.215637) (xy 450.212678 -22.171494)
			(xy 450.252827 -22.132785) (xy 450.298185 -22.100334) (xy 450.347785 -22.074833) (xy 450.400569 -22.056826)
			(xy 450.455412 -22.046696) (xy 450.511146 -22.044659) (xy 450.566583 -22.050759) (xy 450.62054 -22.064865)
			(xy 450.671869 -22.086677) (xy 450.719475 -22.115731) (xy 450.762343 -22.151406) (xy 450.79956 -22.192943)
			(xy 450.830333 -22.239456) (xy 450.854005 -22.289953) (xy 450.870073 -22.34336) (xy 450.878193 -22.398536)
			(xy 450.878234 -22.400768) (xy 452.115172 -22.400768) (xy 452.119243 -22.345146) (xy 452.131369 -22.290709)
			(xy 452.151292 -22.238618) (xy 452.178588 -22.189983) (xy 452.212674 -22.14584) (xy 452.252823 -22.107131)
			(xy 452.298181 -22.07468) (xy 452.347781 -22.049179) (xy 452.400565 -22.031172) (xy 452.455408 -22.021042)
			(xy 452.511142 -22.019005) (xy 452.566579 -22.025105) (xy 452.620536 -22.039211) (xy 452.671865 -22.061023)
			(xy 452.719471 -22.090077) (xy 452.762339 -22.125752) (xy 452.799556 -22.167289) (xy 452.830329 -22.213802)
			(xy 452.854001 -22.264299) (xy 452.870069 -22.317706) (xy 452.878189 -22.372882) (xy 452.878698 -22.400768)
			(xy 452.878189 -22.428654) (xy 452.870069 -22.48383) (xy 452.854001 -22.537237) (xy 452.830329 -22.587734)
			(xy 452.799556 -22.634247) (xy 452.762339 -22.675784) (xy 452.719471 -22.711459) (xy 452.671865 -22.740513)
			(xy 452.620536 -22.762325) (xy 452.566579 -22.776431) (xy 452.511142 -22.782531) (xy 452.455408 -22.780494)
			(xy 452.400565 -22.770364) (xy 452.347781 -22.752357) (xy 452.298181 -22.726856) (xy 452.252823 -22.694405)
			(xy 452.212674 -22.655696) (xy 452.178588 -22.611553) (xy 452.151292 -22.562918) (xy 452.131369 -22.510827)
			(xy 452.119243 -22.45639) (xy 452.115172 -22.400768) (xy 450.878234 -22.400768) (xy 450.878702 -22.426422)
			(xy 450.878193 -22.454308) (xy 450.870073 -22.509484) (xy 450.854005 -22.562891) (xy 450.830333 -22.613388)
			(xy 450.79956 -22.659901) (xy 450.762343 -22.701438) (xy 450.719475 -22.737113) (xy 450.671869 -22.766167)
			(xy 450.62054 -22.787979) (xy 450.566583 -22.802085) (xy 450.511146 -22.808185) (xy 450.455412 -22.806148)
			(xy 450.400569 -22.796018) (xy 450.347785 -22.778011) (xy 450.298185 -22.75251) (xy 450.252827 -22.720059)
			(xy 450.212678 -22.68135) (xy 450.178592 -22.637207) (xy 450.151296 -22.588572) (xy 450.131373 -22.536481)
			(xy 450.119247 -22.482044) (xy 450.115176 -22.426422) (xy 445.36868 -22.426422) (xy 445.36868 -22.866858)
			(xy 446.779394 -22.866858) (xy 446.783465 -22.811236) (xy 446.795591 -22.756799) (xy 446.815514 -22.704708)
			(xy 446.84281 -22.656073) (xy 446.876896 -22.61193) (xy 446.917045 -22.573221) (xy 446.962403 -22.54077)
			(xy 447.012003 -22.515269) (xy 447.064787 -22.497262) (xy 447.11963 -22.487132) (xy 447.175364 -22.485095)
			(xy 447.230801 -22.491195) (xy 447.284758 -22.505301) (xy 447.336087 -22.527113) (xy 447.383693 -22.556167)
			(xy 447.426561 -22.591842) (xy 447.463778 -22.633379) (xy 447.494551 -22.679892) (xy 447.518223 -22.730389)
			(xy 447.534291 -22.783796) (xy 447.542411 -22.838972) (xy 447.54292 -22.866858) (xy 447.542411 -22.894744)
			(xy 447.534291 -22.94992) (xy 447.518223 -23.003327) (xy 447.510755 -23.019258) (xy 451.351394 -23.019258)
			(xy 451.355465 -22.963636) (xy 451.367591 -22.909199) (xy 451.387514 -22.857108) (xy 451.41481 -22.808473)
			(xy 451.448896 -22.76433) (xy 451.489045 -22.725621) (xy 451.534403 -22.69317) (xy 451.584003 -22.667669)
			(xy 451.636787 -22.649662) (xy 451.69163 -22.639532) (xy 451.747364 -22.637495) (xy 451.802801 -22.643595)
			(xy 451.856758 -22.657701) (xy 451.908087 -22.679513) (xy 451.955693 -22.708567) (xy 451.998561 -22.744242)
			(xy 452.035778 -22.785779) (xy 452.066551 -22.832292) (xy 452.090223 -22.882789) (xy 452.106291 -22.936196)
			(xy 452.114411 -22.991372) (xy 452.11492 -23.019258) (xy 452.114411 -23.047144) (xy 452.106291 -23.10232)
			(xy 452.090223 -23.155727) (xy 452.066551 -23.206224) (xy 452.035778 -23.252737) (xy 451.998561 -23.294274)
			(xy 451.955693 -23.329949) (xy 451.908087 -23.359003) (xy 451.856758 -23.380815) (xy 451.802801 -23.394921)
			(xy 451.747364 -23.401021) (xy 451.69163 -23.398984) (xy 451.636787 -23.388854) (xy 451.584003 -23.370847)
			(xy 451.534403 -23.345346) (xy 451.489045 -23.312895) (xy 451.448896 -23.274186) (xy 451.41481 -23.230043)
			(xy 451.387514 -23.181408) (xy 451.367591 -23.129317) (xy 451.355465 -23.07488) (xy 451.351394 -23.019258)
			(xy 447.510755 -23.019258) (xy 447.494551 -23.053824) (xy 447.463778 -23.100337) (xy 447.426561 -23.141874)
			(xy 447.383693 -23.177549) (xy 447.336087 -23.206603) (xy 447.284758 -23.228415) (xy 447.230801 -23.242521)
			(xy 447.175364 -23.248621) (xy 447.11963 -23.246584) (xy 447.064787 -23.236454) (xy 447.012003 -23.218447)
			(xy 446.962403 -23.192946) (xy 446.917045 -23.160495) (xy 446.876896 -23.121786) (xy 446.84281 -23.077643)
			(xy 446.815514 -23.029008) (xy 446.795591 -22.976917) (xy 446.783465 -22.92248) (xy 446.779394 -22.866858)
			(xy 445.36868 -22.866858) (xy 445.36868 -24.873458) (xy 451.376794 -24.873458) (xy 451.380865 -24.817836)
			(xy 451.392991 -24.763399) (xy 451.412914 -24.711308) (xy 451.44021 -24.662673) (xy 451.474296 -24.61853)
			(xy 451.514445 -24.579821) (xy 451.559803 -24.54737) (xy 451.609403 -24.521869) (xy 451.662187 -24.503862)
			(xy 451.71703 -24.493732) (xy 451.772764 -24.491695) (xy 451.828201 -24.497795) (xy 451.882158 -24.511901)
			(xy 451.933487 -24.533713) (xy 451.981093 -24.562767) (xy 452.023961 -24.598442) (xy 452.061178 -24.639979)
			(xy 452.091951 -24.686492) (xy 452.115623 -24.736989) (xy 452.131691 -24.790396) (xy 452.139811 -24.845572)
			(xy 452.14032 -24.873458) (xy 452.139811 -24.901344) (xy 452.131691 -24.95652) (xy 452.115623 -25.009927)
			(xy 452.091951 -25.060424) (xy 452.061178 -25.106937) (xy 452.023961 -25.148474) (xy 451.981093 -25.184149)
			(xy 451.933487 -25.213203) (xy 451.882158 -25.235015) (xy 451.828201 -25.249121) (xy 451.772764 -25.255221)
			(xy 451.71703 -25.253184) (xy 451.662187 -25.243054) (xy 451.609403 -25.225047) (xy 451.559803 -25.199546)
			(xy 451.514445 -25.167095) (xy 451.474296 -25.128386) (xy 451.44021 -25.084243) (xy 451.412914 -25.035608)
			(xy 451.392991 -24.983517) (xy 451.380865 -24.92908) (xy 451.376794 -24.873458) (xy 445.36868 -24.873458)
			(xy 445.36868 -26.416508) (xy 444.801632 -26.983556) (xy 446.780313 -26.983556) (xy 446.780313 -26.929044)
			(xy 446.788071 -26.875086) (xy 446.803429 -26.822781) (xy 446.826075 -26.773195) (xy 446.855548 -26.727336)
			(xy 446.891247 -26.686138) (xy 446.932445 -26.650441) (xy 446.978305 -26.62097) (xy 447.027892 -26.598325)
			(xy 447.080197 -26.582969) (xy 447.134156 -26.575212) (xy 447.161412 -26.57475) (xy 447.18867 -26.575219)
			(xy 447.24263 -26.582987) (xy 447.294937 -26.598351) (xy 447.344526 -26.620998) (xy 447.390392 -26.650466)
			(xy 447.4316 -26.686158) (xy 447.467313 -26.727348) (xy 447.482468 -26.75001) (xy 447.490749 -26.761937)
			(xy 447.512685 -26.780941) (xy 447.539085 -26.792996) (xy 447.567812 -26.797126) (xy 447.596539 -26.792996)
			(xy 447.622939 -26.780941) (xy 447.644875 -26.761937) (xy 447.653156 -26.75001) (xy 447.668315 -26.727351)
			(xy 447.704021 -26.686155) (xy 447.745226 -26.650459) (xy 447.791091 -26.620989) (xy 447.840683 -26.598347)
			(xy 447.892992 -26.582991) (xy 447.946954 -26.575235) (xy 447.974212 -26.57475) (xy 448.00146 -26.575321)
			(xy 448.0554 -26.583078) (xy 448.107688 -26.598432) (xy 448.157258 -26.621072) (xy 448.203102 -26.650535)
			(xy 448.244286 -26.686223) (xy 448.279972 -26.727408) (xy 448.309434 -26.773253) (xy 448.332072 -26.822824)
			(xy 448.347425 -26.875112) (xy 448.35518 -26.929052) (xy 448.35518 -26.983548) (xy 448.347425 -27.037488)
			(xy 448.332072 -27.089776) (xy 448.309434 -27.139347) (xy 448.279972 -27.185192) (xy 448.244286 -27.226377)
			(xy 448.203102 -27.262065) (xy 448.157258 -27.291528) (xy 448.107688 -27.314168) (xy 448.0554 -27.329522)
			(xy 448.00146 -27.337279) (xy 447.974212 -27.337766) (xy 447.946955 -27.337272) (xy 447.892997 -27.329506)
			(xy 447.840691 -27.314147) (xy 447.791101 -27.291504) (xy 447.745236 -27.26204) (xy 447.704027 -27.226352)
			(xy 447.668312 -27.185166) (xy 447.653156 -27.162506) (xy 447.644875 -27.150579) (xy 447.622939 -27.131575)
			(xy 447.596539 -27.11952) (xy 447.567812 -27.11539) (xy 447.539085 -27.11952) (xy 447.512685 -27.131575)
			(xy 447.490749 -27.150579) (xy 447.482468 -27.162506) (xy 447.467298 -27.185158) (xy 447.431593 -27.226353)
			(xy 447.39039 -27.262049) (xy 447.344527 -27.291519) (xy 447.294937 -27.314163) (xy 447.24263 -27.329521)
			(xy 447.18867 -27.337279) (xy 447.161412 -27.337766) (xy 447.134156 -27.337388) (xy 447.080197 -27.329631)
			(xy 447.027892 -27.314275) (xy 446.978305 -27.29163) (xy 446.932445 -27.262159) (xy 446.891247 -27.226462)
			(xy 446.855548 -27.185264) (xy 446.826075 -27.139405) (xy 446.803429 -27.089819) (xy 446.788071 -27.037514)
			(xy 446.780313 -26.983556) (xy 444.801632 -26.983556) (xy 444.5889 -27.196288) (xy 434.4162 -27.196288)
			(xy 434.01488 -27.597608) (xy 434.01488 -28.412948) (xy 434.648862 -28.412948) (xy 434.652933 -28.357326)
			(xy 434.665059 -28.302889) (xy 434.684982 -28.250798) (xy 434.712278 -28.202163) (xy 434.746364 -28.15802)
			(xy 434.786513 -28.119311) (xy 434.831871 -28.08686) (xy 434.881471 -28.061359) (xy 434.934255 -28.043352)
			(xy 434.989098 -28.033222) (xy 435.044832 -28.031185) (xy 435.100269 -28.037285) (xy 435.154226 -28.051391)
			(xy 435.205555 -28.073203) (xy 435.253161 -28.102257) (xy 435.296029 -28.137932) (xy 435.333246 -28.179469)
			(xy 435.364019 -28.225982) (xy 435.387691 -28.276479) (xy 435.403759 -28.329886) (xy 435.411879 -28.385062)
			(xy 435.412388 -28.412948) (xy 435.411879 -28.440834) (xy 435.403759 -28.49601) (xy 435.387691 -28.549417)
			(xy 435.364019 -28.599914) (xy 435.352438 -28.617418) (xy 436.483504 -28.617418) (xy 436.487575 -28.561796)
			(xy 436.499701 -28.507359) (xy 436.519624 -28.455268) (xy 436.54692 -28.406633) (xy 436.581006 -28.36249)
			(xy 436.621155 -28.323781) (xy 436.666513 -28.29133) (xy 436.716113 -28.265829) (xy 436.768897 -28.247822)
			(xy 436.82374 -28.237692) (xy 436.879474 -28.235655) (xy 436.934911 -28.241755) (xy 436.988868 -28.255861)
			(xy 437.040197 -28.277673) (xy 437.087803 -28.306727) (xy 437.130671 -28.342402) (xy 437.167888 -28.383939)
			(xy 437.198661 -28.430452) (xy 437.222333 -28.480949) (xy 437.238401 -28.534356) (xy 437.246521 -28.589532)
			(xy 437.24703 -28.617418) (xy 437.246521 -28.645304) (xy 437.242102 -28.67533) (xy 438.783728 -28.67533)
			(xy 438.787799 -28.619708) (xy 438.799925 -28.565271) (xy 438.819848 -28.51318) (xy 438.847144 -28.464545)
			(xy 438.88123 -28.420402) (xy 438.921379 -28.381693) (xy 438.966737 -28.349242) (xy 439.016337 -28.323741)
			(xy 439.069121 -28.305734) (xy 439.123964 -28.295604) (xy 439.179698 -28.293567) (xy 439.235135 -28.299667)
			(xy 439.289092 -28.313773) (xy 439.340421 -28.335585) (xy 439.388027 -28.364639) (xy 439.430895 -28.400314)
			(xy 439.468112 -28.441851) (xy 439.498885 -28.488364) (xy 439.501039 -28.492958) (xy 440.846972 -28.492958)
			(xy 440.847475 -28.465637) (xy 440.855819 -28.411635) (xy 440.872304 -28.359538) (xy 440.896546 -28.310567)
			(xy 440.927975 -28.265868) (xy 440.94654 -28.245816) (xy 440.956979 -28.234228) (xy 440.970801 -28.206283)
			(xy 440.975549 -28.17547) (xy 440.970782 -28.144659) (xy 440.956944 -28.116722) (xy 440.94654 -28.1051)
			(xy 440.927942 -28.085073) (xy 440.896482 -28.040385) (xy 440.872229 -27.991409) (xy 440.855754 -27.9393)
			(xy 440.847445 -27.885284) (xy 440.846972 -27.857958) (xy 440.84747 -27.831309) (xy 440.855413 -27.778605)
			(xy 440.871123 -27.727675) (xy 440.894249 -27.679654) (xy 440.924273 -27.635617) (xy 440.960525 -27.596546)
			(xy 441.002196 -27.563315) (xy 441.048354 -27.536666) (xy 441.097968 -27.517194) (xy 441.14993 -27.505334)
			(xy 441.20308 -27.501351) (xy 441.25623 -27.505334) (xy 441.308192 -27.517194) (xy 441.357806 -27.536666)
			(xy 441.403964 -27.563315) (xy 441.445635 -27.596546) (xy 441.481887 -27.635617) (xy 441.511911 -27.679654)
			(xy 441.535037 -27.727675) (xy 441.550747 -27.778605) (xy 441.55869 -27.831309) (xy 441.559188 -27.857958)
			(xy 441.558644 -27.885278) (xy 441.550312 -27.939278) (xy 441.533837 -27.991375) (xy 441.509604 -28.040347)
			(xy 441.478182 -28.085047) (xy 441.45962 -28.1051) (xy 441.449267 -28.116757) (xy 441.435442 -28.144679)
			(xy 441.43068 -28.17547) (xy 441.435424 -28.206263) (xy 441.449232 -28.234193) (xy 441.45962 -28.245816)
			(xy 441.478236 -28.265827) (xy 441.509691 -28.310521) (xy 441.533939 -28.3595) (xy 441.55041 -28.411612)
			(xy 441.558716 -28.465631) (xy 441.559188 -28.492958) (xy 441.746894 -28.492958) (xy 441.747391 -28.465636)
			(xy 441.755735 -28.411634) (xy 441.772222 -28.359537) (xy 441.796465 -28.310566) (xy 441.827896 -28.265868)
			(xy 441.846462 -28.245816) (xy 441.856899 -28.234227) (xy 441.870718 -28.206282) (xy 441.875465 -28.17547)
			(xy 441.8707 -28.14466) (xy 441.856864 -28.116723) (xy 441.846462 -28.1051) (xy 441.827868 -28.08507)
			(xy 441.796407 -28.040383) (xy 441.772153 -27.991408) (xy 441.755677 -27.9393) (xy 441.747368 -27.885284)
			(xy 441.746894 -27.857958) (xy 441.747392 -27.831309) (xy 441.755335 -27.778605) (xy 441.771045 -27.727675)
			(xy 441.794171 -27.679654) (xy 441.824195 -27.635617) (xy 441.860447 -27.596546) (xy 441.902118 -27.563315)
			(xy 441.948276 -27.536666) (xy 441.99789 -27.517194) (xy 442.049852 -27.505334) (xy 442.103002 -27.501351)
			(xy 442.156152 -27.505334) (xy 442.208114 -27.517194) (xy 442.257728 -27.536666) (xy 442.303886 -27.563315)
			(xy 442.345557 -27.596546) (xy 442.381809 -27.635617) (xy 442.411833 -27.679654) (xy 442.434959 -27.727675)
			(xy 442.450669 -27.778605) (xy 442.458612 -27.831309) (xy 442.45911 -27.857958) (xy 442.45856 -27.885278)
			(xy 442.450229 -27.939278) (xy 442.433754 -27.991374) (xy 442.409523 -28.040346) (xy 442.378102 -28.085047)
			(xy 442.359542 -28.1051) (xy 442.349187 -28.116756) (xy 442.335359 -28.144678) (xy 442.330596 -28.17547)
			(xy 442.335341 -28.206264) (xy 442.349152 -28.234194) (xy 442.359542 -28.245816) (xy 442.378144 -28.265839)
			(xy 442.409604 -28.310528) (xy 442.433857 -28.359504) (xy 442.450331 -28.411614) (xy 442.458638 -28.465631)
			(xy 442.45911 -28.492958) (xy 442.646816 -28.492958) (xy 442.647307 -28.465636) (xy 442.655652 -28.411633)
			(xy 442.672139 -28.359536) (xy 442.696384 -28.310565) (xy 442.727817 -28.265867) (xy 442.746384 -28.245816)
			(xy 442.756819 -28.234226) (xy 442.770635 -28.206281) (xy 442.775381 -28.17547) (xy 442.770617 -28.144661)
			(xy 442.756784 -28.116724) (xy 442.746384 -28.1051) (xy 442.727777 -28.085082) (xy 442.69632 -28.04039)
			(xy 442.67207 -27.991412) (xy 442.655597 -27.939302) (xy 442.647289 -27.885285) (xy 442.646816 -27.857958)
			(xy 442.647314 -27.831309) (xy 442.655257 -27.778605) (xy 442.670967 -27.727675) (xy 442.694093 -27.679654)
			(xy 442.724117 -27.635617) (xy 442.760369 -27.596546) (xy 442.80204 -27.563315) (xy 442.848198 -27.536666)
			(xy 442.897812 -27.517194) (xy 442.949774 -27.505334) (xy 443.002924 -27.501351) (xy 443.056074 -27.505334)
			(xy 443.108036 -27.517194) (xy 443.15765 -27.536666) (xy 443.203808 -27.563315) (xy 443.245479 -27.596546)
			(xy 443.281731 -27.635617) (xy 443.311755 -27.679654) (xy 443.334881 -27.727675) (xy 443.350591 -27.778605)
			(xy 443.358534 -27.831309) (xy 443.359032 -27.857958) (xy 443.358476 -27.885277) (xy 443.350145 -27.939277)
			(xy 443.333672 -27.991373) (xy 443.309442 -28.040345) (xy 443.278023 -28.085046) (xy 443.259464 -28.1051)
			(xy 443.249107 -28.116755) (xy 443.235276 -28.144677) (xy 443.230512 -28.17547) (xy 443.235258 -28.206265)
			(xy 443.249072 -28.234195) (xy 443.259464 -28.245816) (xy 443.27807 -28.265836) (xy 443.309529 -28.310526)
			(xy 443.33378 -28.359503) (xy 443.350253 -28.411614) (xy 443.35856 -28.465631) (xy 443.359032 -28.492958)
			(xy 443.546992 -28.492958) (xy 443.547489 -28.465636) (xy 443.555834 -28.411634) (xy 443.57232 -28.359537)
			(xy 443.596563 -28.310566) (xy 443.627995 -28.265868) (xy 443.64656 -28.245816) (xy 443.656998 -28.234228)
			(xy 443.670816 -28.206282) (xy 443.675564 -28.17547) (xy 443.670798 -28.14466) (xy 443.656963 -28.116723)
			(xy 443.64656 -28.1051) (xy 443.627966 -28.08507) (xy 443.596504 -28.040383) (xy 443.57225 -27.991408)
			(xy 443.555775 -27.9393) (xy 443.547466 -27.885284) (xy 443.546992 -27.857958) (xy 443.54749 -27.831309)
			(xy 443.555433 -27.778605) (xy 443.571143 -27.727675) (xy 443.594269 -27.679654) (xy 443.624293 -27.635617)
			(xy 443.660545 -27.596546) (xy 443.702216 -27.563315) (xy 443.748374 -27.536666) (xy 443.797988 -27.517194)
			(xy 443.84995 -27.505334) (xy 443.9031 -27.501351) (xy 443.95625 -27.505334) (xy 444.008212 -27.517194)
			(xy 444.057826 -27.536666) (xy 444.103984 -27.563315) (xy 444.145655 -27.596546) (xy 444.181907 -27.635617)
			(xy 444.211931 -27.679654) (xy 444.235057 -27.727675) (xy 444.250767 -27.778605) (xy 444.25871 -27.831309)
			(xy 444.259208 -27.857958) (xy 444.258659 -27.885278) (xy 444.250327 -27.939278) (xy 444.233853 -27.991374)
			(xy 444.209621 -28.040346) (xy 444.178201 -28.085047) (xy 444.15964 -28.1051) (xy 444.149285 -28.116756)
			(xy 444.135458 -28.144678) (xy 444.130695 -28.17547) (xy 444.134607 -28.200858) (xy 445.636904 -28.200858)
			(xy 445.637401 -28.172118) (xy 445.64603 -28.11529) (xy 445.663086 -28.060398) (xy 445.688184 -28.008687)
			(xy 445.720755 -27.961326) (xy 445.740028 -27.94) (xy 445.750145 -27.928501) (xy 445.763488 -27.900943)
			(xy 445.768067 -27.870669) (xy 445.76347 -27.840398) (xy 445.75011 -27.812849) (xy 445.740028 -27.801316)
			(xy 445.720736 -27.780008) (xy 445.688173 -27.73264) (xy 445.663085 -27.680924) (xy 445.646039 -27.626029)
			(xy 445.637422 -27.569198) (xy 445.636904 -27.540458) (xy 445.63739 -27.513207) (xy 445.645146 -27.459259)
			(xy 445.660501 -27.406964) (xy 445.683143 -27.357387) (xy 445.712609 -27.311537) (xy 445.7483 -27.270346)
			(xy 445.789491 -27.234655) (xy 445.835341 -27.205189) (xy 445.884918 -27.182547) (xy 445.937213 -27.167192)
			(xy 445.991161 -27.159436) (xy 446.045663 -27.159436) (xy 446.099611 -27.167192) (xy 446.151906 -27.182547)
			(xy 446.201483 -27.205189) (xy 446.247333 -27.234655) (xy 446.288524 -27.270346) (xy 446.324215 -27.311537)
			(xy 446.353681 -27.357387) (xy 446.376323 -27.406964) (xy 446.391678 -27.459259) (xy 446.399434 -27.513207)
			(xy 446.39992 -27.540458) (xy 446.399426 -27.569198) (xy 446.390795 -27.626026) (xy 446.373738 -27.680917)
			(xy 446.34864 -27.732628) (xy 446.316069 -27.77999) (xy 446.296796 -27.801316) (xy 446.286768 -27.812884)
			(xy 446.273426 -27.840419) (xy 446.268835 -27.870669) (xy 446.273408 -27.900922) (xy 446.286733 -27.928465)
			(xy 446.296796 -27.94) (xy 446.316083 -27.961313) (xy 446.348649 -28.008678) (xy 446.37374 -28.060393)
			(xy 446.390786 -28.115287) (xy 446.399403 -28.172118) (xy 446.39992 -28.200858) (xy 446.399434 -28.228109)
			(xy 446.391678 -28.282057) (xy 446.376323 -28.334352) (xy 446.353681 -28.383929) (xy 446.324215 -28.429779)
			(xy 446.288524 -28.47097) (xy 446.247333 -28.506661) (xy 446.201483 -28.536127) (xy 446.151906 -28.558769)
			(xy 446.099611 -28.574124) (xy 446.045663 -28.58188) (xy 445.991161 -28.58188) (xy 445.937213 -28.574124)
			(xy 445.884918 -28.558769) (xy 445.835341 -28.536127) (xy 445.789491 -28.506661) (xy 445.7483 -28.47097)
			(xy 445.712609 -28.429779) (xy 445.683143 -28.383929) (xy 445.660501 -28.334352) (xy 445.645146 -28.282057)
			(xy 445.63739 -28.228109) (xy 445.636904 -28.200858) (xy 444.134607 -28.200858) (xy 444.13544 -28.206264)
			(xy 444.14925 -28.234194) (xy 444.15964 -28.245816) (xy 444.178242 -28.265839) (xy 444.209702 -28.310528)
			(xy 444.233955 -28.359504) (xy 444.250428 -28.411614) (xy 444.258736 -28.465631) (xy 444.259208 -28.492958)
			(xy 444.25871 -28.519607) (xy 444.250767 -28.572311) (xy 444.235057 -28.623241) (xy 444.211931 -28.671262)
			(xy 444.181907 -28.715299) (xy 444.145655 -28.75437) (xy 444.103984 -28.787601) (xy 444.057826 -28.81425)
			(xy 444.008212 -28.833722) (xy 443.95625 -28.845582) (xy 443.9031 -28.849566) (xy 443.84995 -28.845582)
			(xy 443.797988 -28.833722) (xy 443.748374 -28.81425) (xy 443.702216 -28.787601) (xy 443.660545 -28.75437)
			(xy 443.624293 -28.715299) (xy 443.594269 -28.671262) (xy 443.571143 -28.623241) (xy 443.555433 -28.572311)
			(xy 443.54749 -28.519607) (xy 443.546992 -28.492958) (xy 443.359032 -28.492958) (xy 443.358534 -28.519607)
			(xy 443.350591 -28.572311) (xy 443.334881 -28.623241) (xy 443.311755 -28.671262) (xy 443.281731 -28.715299)
			(xy 443.245479 -28.75437) (xy 443.203808 -28.787601) (xy 443.15765 -28.81425) (xy 443.108036 -28.833722)
			(xy 443.056074 -28.845582) (xy 443.002924 -28.849566) (xy 442.949774 -28.845582) (xy 442.897812 -28.833722)
			(xy 442.848198 -28.81425) (xy 442.80204 -28.787601) (xy 442.760369 -28.75437) (xy 442.724117 -28.715299)
			(xy 442.694093 -28.671262) (xy 442.670967 -28.623241) (xy 442.655257 -28.572311) (xy 442.647314 -28.519607)
			(xy 442.646816 -28.492958) (xy 442.45911 -28.492958) (xy 442.458612 -28.519607) (xy 442.450669 -28.572311)
			(xy 442.434959 -28.623241) (xy 442.411833 -28.671262) (xy 442.381809 -28.715299) (xy 442.345557 -28.75437)
			(xy 442.303886 -28.787601) (xy 442.257728 -28.81425) (xy 442.208114 -28.833722) (xy 442.156152 -28.845582)
			(xy 442.103002 -28.849566) (xy 442.049852 -28.845582) (xy 441.99789 -28.833722) (xy 441.948276 -28.81425)
			(xy 441.902118 -28.787601) (xy 441.860447 -28.75437) (xy 441.824195 -28.715299) (xy 441.794171 -28.671262)
			(xy 441.771045 -28.623241) (xy 441.755335 -28.572311) (xy 441.747392 -28.519607) (xy 441.746894 -28.492958)
			(xy 441.559188 -28.492958) (xy 441.55869 -28.519607) (xy 441.550747 -28.572311) (xy 441.535037 -28.623241)
			(xy 441.511911 -28.671262) (xy 441.481887 -28.715299) (xy 441.445635 -28.75437) (xy 441.403964 -28.787601)
			(xy 441.357806 -28.81425) (xy 441.308192 -28.833722) (xy 441.25623 -28.845582) (xy 441.20308 -28.849566)
			(xy 441.14993 -28.845582) (xy 441.097968 -28.833722) (xy 441.048354 -28.81425) (xy 441.002196 -28.787601)
			(xy 440.960525 -28.75437) (xy 440.924273 -28.715299) (xy 440.894249 -28.671262) (xy 440.871123 -28.623241)
			(xy 440.855413 -28.572311) (xy 440.84747 -28.519607) (xy 440.846972 -28.492958) (xy 439.501039 -28.492958)
			(xy 439.522557 -28.538861) (xy 439.538625 -28.592268) (xy 439.546745 -28.647444) (xy 439.547254 -28.67533)
			(xy 439.546745 -28.703216) (xy 439.538625 -28.758392) (xy 439.522557 -28.811799) (xy 439.498885 -28.862296)
			(xy 439.482767 -28.886658) (xy 449.015104 -28.886658) (xy 449.015548 -28.860342) (xy 449.02277 -28.808207)
			(xy 449.037085 -28.757559) (xy 449.058221 -28.709357) (xy 449.085778 -28.664515) (xy 449.119233 -28.623884)
			(xy 449.138294 -28.605734) (xy 449.148357 -28.595962) (xy 449.163053 -28.572078) (xy 449.170686 -28.545093)
			(xy 449.170678 -28.51705) (xy 449.16303 -28.49007) (xy 449.148321 -28.466194) (xy 449.138294 -28.456382)
			(xy 449.119205 -28.438257) (xy 449.085728 -28.397635) (xy 449.058159 -28.352792) (xy 449.037022 -28.304583)
			(xy 449.02272 -28.253923) (xy 449.015523 -28.201778) (xy 449.015104 -28.175458) (xy 449.015608 -28.147885)
			(xy 449.023553 -28.093314) (xy 449.03927 -28.040454) (xy 449.062433 -27.990408) (xy 449.092559 -27.944218)
			(xy 449.12902 -27.902845) (xy 449.149724 -27.884628) (xy 449.160661 -27.874771) (xy 449.176728 -27.850108)
			(xy 449.185104 -27.82189) (xy 449.185096 -27.792456) (xy 449.176705 -27.764242) (xy 449.160625 -27.739588)
			(xy 449.149724 -27.729688) (xy 449.129009 -27.711481) (xy 449.092538 -27.670112) (xy 449.062405 -27.623922)
			(xy 449.03924 -27.573873) (xy 449.023525 -27.521009) (xy 449.015588 -27.466433) (xy 449.015104 -27.438858)
			(xy 449.01559 -27.411607) (xy 449.023346 -27.357659) (xy 449.038701 -27.305364) (xy 449.061343 -27.255787)
			(xy 449.090809 -27.209937) (xy 449.1265 -27.168746) (xy 449.167691 -27.133055) (xy 449.213541 -27.103589)
			(xy 449.263118 -27.080947) (xy 449.315413 -27.065592) (xy 449.369361 -27.057836) (xy 449.423863 -27.057836)
			(xy 449.477811 -27.065592) (xy 449.530106 -27.080947) (xy 449.579683 -27.103589) (xy 449.625533 -27.133055)
			(xy 449.666724 -27.168746) (xy 449.702415 -27.209937) (xy 449.731881 -27.255787) (xy 449.754523 -27.305364)
			(xy 449.769878 -27.357659) (xy 449.777634 -27.411607) (xy 449.77812 -27.438858) (xy 449.777618 -27.466431)
			(xy 449.769672 -27.521002) (xy 449.753954 -27.573861) (xy 449.73079 -27.623907) (xy 449.700665 -27.670098)
			(xy 449.664204 -27.711471) (xy 449.6435 -27.729688) (xy 449.632645 -27.739629) (xy 449.616572 -27.764268)
			(xy 449.608183 -27.792464) (xy 449.608176 -27.821882) (xy 449.616549 -27.850083) (xy 449.632609 -27.874729)
			(xy 449.6435 -27.884628) (xy 449.664228 -27.902821) (xy 449.700697 -27.944194) (xy 449.730827 -27.990387)
			(xy 449.75399 -28.040439) (xy 449.769703 -28.093305) (xy 449.777637 -28.147882) (xy 449.77812 -28.175458)
			(xy 449.777679 -28.201774) (xy 449.770455 -28.253909) (xy 449.75614 -28.304557) (xy 449.735003 -28.352759)
			(xy 449.707446 -28.3976) (xy 449.673991 -28.438232) (xy 449.65493 -28.456382) (xy 449.64495 -28.466233)
			(xy 449.630245 -28.490093) (xy 449.6226 -28.517058) (xy 449.622592 -28.545085) (xy 449.630222 -28.572054)
			(xy 449.644913 -28.595923) (xy 449.65493 -28.605734) (xy 449.674013 -28.623866) (xy 449.707493 -28.664485)
			(xy 449.735065 -28.709326) (xy 449.756203 -28.757534) (xy 449.770506 -28.808193) (xy 449.777701 -28.860338)
			(xy 449.77812 -28.886658) (xy 449.777634 -28.913909) (xy 449.774248 -28.937458) (xy 452.799704 -28.937458)
			(xy 452.800148 -28.911142) (xy 452.80737 -28.859007) (xy 452.821685 -28.808359) (xy 452.842821 -28.760157)
			(xy 452.870378 -28.715315) (xy 452.903833 -28.674684) (xy 452.922894 -28.656534) (xy 452.932957 -28.646762)
			(xy 452.947653 -28.622878) (xy 452.955286 -28.595893) (xy 452.955278 -28.56785) (xy 452.94763 -28.54087)
			(xy 452.932921 -28.516994) (xy 452.922894 -28.507182) (xy 452.903805 -28.489057) (xy 452.870328 -28.448435)
			(xy 452.842759 -28.403592) (xy 452.821622 -28.355383) (xy 452.80732 -28.304723) (xy 452.800123 -28.252578)
			(xy 452.799704 -28.226258) (xy 452.800208 -28.198685) (xy 452.808153 -28.144114) (xy 452.82387 -28.091254)
			(xy 452.847033 -28.041208) (xy 452.877159 -27.995018) (xy 452.91362 -27.953645) (xy 452.934324 -27.935428)
			(xy 452.945261 -27.925571) (xy 452.961328 -27.900908) (xy 452.969704 -27.87269) (xy 452.969696 -27.843256)
			(xy 452.961305 -27.815042) (xy 452.945225 -27.790388) (xy 452.934324 -27.780488) (xy 452.913609 -27.762281)
			(xy 452.877138 -27.720912) (xy 452.847005 -27.674722) (xy 452.82384 -27.624673) (xy 452.808125 -27.571809)
			(xy 452.800188 -27.517233) (xy 452.799704 -27.489658) (xy 452.80019 -27.462407) (xy 452.807946 -27.408459)
			(xy 452.823301 -27.356164) (xy 452.845943 -27.306587) (xy 452.875409 -27.260737) (xy 452.9111 -27.219546)
			(xy 452.952291 -27.183855) (xy 452.998141 -27.154389) (xy 453.047718 -27.131747) (xy 453.100013 -27.116392)
			(xy 453.153961 -27.108636) (xy 453.208463 -27.108636) (xy 453.262411 -27.116392) (xy 453.314706 -27.131747)
			(xy 453.364283 -27.154389) (xy 453.410133 -27.183855) (xy 453.451324 -27.219546) (xy 453.487015 -27.260737)
			(xy 453.516481 -27.306587) (xy 453.539123 -27.356164) (xy 453.554478 -27.408459) (xy 453.562234 -27.462407)
			(xy 453.56272 -27.489658) (xy 453.562218 -27.517231) (xy 453.554272 -27.571802) (xy 453.538554 -27.624661)
			(xy 453.51539 -27.674707) (xy 453.485265 -27.720898) (xy 453.448804 -27.762271) (xy 453.4281 -27.780488)
			(xy 453.417245 -27.790429) (xy 453.401172 -27.815068) (xy 453.392783 -27.843264) (xy 453.392776 -27.872682)
			(xy 453.401149 -27.900883) (xy 453.417209 -27.925529) (xy 453.4281 -27.935428) (xy 453.448828 -27.953621)
			(xy 453.485297 -27.994994) (xy 453.515427 -28.041187) (xy 453.53859 -28.091239) (xy 453.554303 -28.144105)
			(xy 453.562237 -28.198682) (xy 453.56272 -28.226258) (xy 453.562279 -28.252574) (xy 453.555055 -28.304709)
			(xy 453.54074 -28.355357) (xy 453.519603 -28.403559) (xy 453.492046 -28.4484) (xy 453.458591 -28.489032)
			(xy 453.43953 -28.507182) (xy 453.42955 -28.517033) (xy 453.414845 -28.540893) (xy 453.4072 -28.567858)
			(xy 453.407192 -28.595885) (xy 453.414822 -28.622854) (xy 453.429513 -28.646723) (xy 453.43953 -28.656534)
			(xy 453.458613 -28.674666) (xy 453.492093 -28.715285) (xy 453.519665 -28.760126) (xy 453.540803 -28.808334)
			(xy 453.555106 -28.858993) (xy 453.562301 -28.911138) (xy 453.56272 -28.937458) (xy 453.562234 -28.964709)
			(xy 453.554478 -29.018657) (xy 453.539123 -29.070952) (xy 453.516481 -29.120529) (xy 453.487015 -29.166379)
			(xy 453.451324 -29.20757) (xy 453.410133 -29.243261) (xy 453.364283 -29.272727) (xy 453.314706 -29.295369)
			(xy 453.262411 -29.310724) (xy 453.208463 -29.31848) (xy 453.153961 -29.31848) (xy 453.100013 -29.310724)
			(xy 453.047718 -29.295369) (xy 452.998141 -29.272727) (xy 452.952291 -29.243261) (xy 452.9111 -29.20757)
			(xy 452.875409 -29.166379) (xy 452.845943 -29.120529) (xy 452.823301 -29.070952) (xy 452.807946 -29.018657)
			(xy 452.80019 -28.964709) (xy 452.799704 -28.937458) (xy 449.774248 -28.937458) (xy 449.769878 -28.967857)
			(xy 449.754523 -29.020152) (xy 449.731881 -29.069729) (xy 449.702415 -29.115579) (xy 449.666724 -29.15677)
			(xy 449.625533 -29.192461) (xy 449.579683 -29.221927) (xy 449.530106 -29.244569) (xy 449.477811 -29.259924)
			(xy 449.423863 -29.26768) (xy 449.369361 -29.26768) (xy 449.315413 -29.259924) (xy 449.263118 -29.244569)
			(xy 449.213541 -29.221927) (xy 449.167691 -29.192461) (xy 449.1265 -29.15677) (xy 449.090809 -29.115579)
			(xy 449.061343 -29.069729) (xy 449.038701 -29.020152) (xy 449.023346 -28.967857) (xy 449.01559 -28.913909)
			(xy 449.015104 -28.886658) (xy 439.482767 -28.886658) (xy 439.468112 -28.908809) (xy 439.430895 -28.950346)
			(xy 439.388027 -28.986021) (xy 439.340421 -29.015075) (xy 439.289092 -29.036887) (xy 439.235135 -29.050993)
			(xy 439.179698 -29.057093) (xy 439.123964 -29.055056) (xy 439.069121 -29.044926) (xy 439.016337 -29.026919)
			(xy 438.966737 -29.001418) (xy 438.921379 -28.968967) (xy 438.88123 -28.930258) (xy 438.847144 -28.886115)
			(xy 438.819848 -28.83748) (xy 438.799925 -28.785389) (xy 438.787799 -28.730952) (xy 438.783728 -28.67533)
			(xy 437.242102 -28.67533) (xy 437.238401 -28.70048) (xy 437.222333 -28.753887) (xy 437.198661 -28.804384)
			(xy 437.167888 -28.850897) (xy 437.130671 -28.892434) (xy 437.087803 -28.928109) (xy 437.040197 -28.957163)
			(xy 436.988868 -28.978975) (xy 436.934911 -28.993081) (xy 436.879474 -28.999181) (xy 436.82374 -28.997144)
			(xy 436.768897 -28.987014) (xy 436.716113 -28.969007) (xy 436.666513 -28.943506) (xy 436.621155 -28.911055)
			(xy 436.581006 -28.872346) (xy 436.54692 -28.828203) (xy 436.519624 -28.779568) (xy 436.499701 -28.727477)
			(xy 436.487575 -28.67304) (xy 436.483504 -28.617418) (xy 435.352438 -28.617418) (xy 435.333246 -28.646427)
			(xy 435.296029 -28.687964) (xy 435.253161 -28.723639) (xy 435.205555 -28.752693) (xy 435.154226 -28.774505)
			(xy 435.100269 -28.788611) (xy 435.044832 -28.794711) (xy 434.989098 -28.792674) (xy 434.934255 -28.782544)
			(xy 434.881471 -28.764537) (xy 434.831871 -28.739036) (xy 434.786513 -28.706585) (xy 434.746364 -28.667876)
			(xy 434.712278 -28.623733) (xy 434.684982 -28.575098) (xy 434.665059 -28.523007) (xy 434.652933 -28.46857)
			(xy 434.648862 -28.412948) (xy 434.01488 -28.412948) (xy 434.01488 -29.936948) (xy 434.598062 -29.936948)
			(xy 434.602133 -29.881326) (xy 434.614259 -29.826889) (xy 434.634182 -29.774798) (xy 434.661478 -29.726163)
			(xy 434.695564 -29.68202) (xy 434.735713 -29.643311) (xy 434.781071 -29.61086) (xy 434.830671 -29.585359)
			(xy 434.883455 -29.567352) (xy 434.938298 -29.557222) (xy 434.994032 -29.555185) (xy 435.049469 -29.561285)
			(xy 435.103426 -29.575391) (xy 435.154755 -29.597203) (xy 435.202361 -29.626257) (xy 435.210966 -29.633418)
			(xy 436.483504 -29.633418) (xy 436.487575 -29.577796) (xy 436.499701 -29.523359) (xy 436.519624 -29.471268)
			(xy 436.54692 -29.422633) (xy 436.581006 -29.37849) (xy 436.621155 -29.339781) (xy 436.666513 -29.30733)
			(xy 436.716113 -29.281829) (xy 436.768897 -29.263822) (xy 436.82374 -29.253692) (xy 436.879474 -29.251655)
			(xy 436.934911 -29.257755) (xy 436.988868 -29.271861) (xy 437.040197 -29.293673) (xy 437.087803 -29.322727)
			(xy 437.130671 -29.358402) (xy 437.167888 -29.399939) (xy 437.198661 -29.446452) (xy 437.222333 -29.496949)
			(xy 437.238401 -29.550356) (xy 437.246521 -29.605532) (xy 437.24703 -29.633418) (xy 437.246521 -29.661304)
			(xy 437.238401 -29.71648) (xy 437.222333 -29.769887) (xy 437.198661 -29.820384) (xy 437.167888 -29.866897)
			(xy 437.130671 -29.908434) (xy 437.087803 -29.944109) (xy 437.040197 -29.973163) (xy 436.988868 -29.994975)
			(xy 436.948502 -30.005528) (xy 438.804302 -30.005528) (xy 438.808373 -29.949906) (xy 438.820499 -29.895469)
			(xy 438.840422 -29.843378) (xy 438.867718 -29.794743) (xy 438.901804 -29.7506) (xy 438.941953 -29.711891)
			(xy 438.987311 -29.67944) (xy 439.036911 -29.653939) (xy 439.089695 -29.635932) (xy 439.144538 -29.625802)
			(xy 439.200272 -29.623765) (xy 439.255709 -29.629865) (xy 439.309666 -29.643971) (xy 439.360995 -29.665783)
			(xy 439.377664 -29.675956) (xy 446.145313 -29.675956) (xy 446.145313 -29.621444) (xy 446.153071 -29.567486)
			(xy 446.168429 -29.515181) (xy 446.191075 -29.465595) (xy 446.220548 -29.419736) (xy 446.256247 -29.378538)
			(xy 446.297445 -29.342841) (xy 446.343305 -29.31337) (xy 446.392892 -29.290725) (xy 446.445197 -29.275369)
			(xy 446.499156 -29.267612) (xy 446.526412 -29.26715) (xy 446.555327 -29.267713) (xy 446.612497 -29.27643)
			(xy 446.667696 -29.293678) (xy 446.719659 -29.319061) (xy 446.767193 -29.351998) (xy 446.809211 -29.391733)
			(xy 446.827402 -29.414216) (xy 446.837299 -29.426021) (xy 446.862623 -29.44354) (xy 446.892016 -29.452716)
			(xy 446.922808 -29.452716) (xy 446.952201 -29.44354) (xy 446.977525 -29.426021) (xy 446.987422 -29.414216)
			(xy 447.005605 -29.391725) (xy 447.047626 -29.35199) (xy 447.095162 -29.319051) (xy 447.147125 -29.293664)
			(xy 447.202324 -29.27641) (xy 447.259495 -29.267683) (xy 447.288412 -29.26715) (xy 447.31566 -29.267721)
			(xy 447.3696 -29.275478) (xy 447.421888 -29.290832) (xy 447.471458 -29.313472) (xy 447.517302 -29.342935)
			(xy 447.558486 -29.378623) (xy 447.594172 -29.419808) (xy 447.623634 -29.465653) (xy 447.646272 -29.515224)
			(xy 447.661625 -29.567512) (xy 447.66938 -29.621452) (xy 447.66938 -29.675948) (xy 447.661625 -29.729888)
			(xy 447.646272 -29.782176) (xy 447.623634 -29.831747) (xy 447.594172 -29.877592) (xy 447.558486 -29.918777)
			(xy 447.517302 -29.954465) (xy 447.471458 -29.983928) (xy 447.421888 -30.006568) (xy 447.3696 -30.021922)
			(xy 447.31566 -30.029679) (xy 447.288412 -30.030166) (xy 447.259495 -30.029652) (xy 447.202323 -30.020924)
			(xy 447.147123 -30.003666) (xy 447.095161 -29.978273) (xy 447.047628 -29.945329) (xy 447.005612 -29.905586)
			(xy 446.987422 -29.8831) (xy 446.977525 -29.871295) (xy 446.952201 -29.853776) (xy 446.922808 -29.8446)
			(xy 446.892016 -29.8446) (xy 446.862623 -29.853776) (xy 446.837299 -29.871295) (xy 446.827402 -29.8831)
			(xy 446.80921 -29.905583) (xy 446.76719 -29.945318) (xy 446.719656 -29.978257) (xy 446.667695 -30.003645)
			(xy 446.612497 -30.020902) (xy 446.555328 -30.029631) (xy 446.526412 -30.030166) (xy 446.499156 -30.029788)
			(xy 446.445197 -30.022031) (xy 446.392892 -30.006675) (xy 446.343305 -29.98403) (xy 446.297445 -29.954559)
			(xy 446.256247 -29.918862) (xy 446.220548 -29.877664) (xy 446.191075 -29.831805) (xy 446.168429 -29.782219)
			(xy 446.153071 -29.729914) (xy 446.145313 -29.675956) (xy 439.377664 -29.675956) (xy 439.408601 -29.694837)
			(xy 439.451469 -29.730512) (xy 439.488686 -29.772049) (xy 439.519459 -29.818562) (xy 439.543131 -29.869059)
			(xy 439.559199 -29.922466) (xy 439.567319 -29.977642) (xy 439.567828 -30.005528) (xy 439.567319 -30.033414)
			(xy 439.559199 -30.08859) (xy 439.543131 -30.141997) (xy 439.519459 -30.192494) (xy 439.488686 -30.239007)
			(xy 439.451469 -30.280544) (xy 439.408601 -30.316219) (xy 439.360995 -30.345273) (xy 439.309666 -30.367085)
			(xy 439.255709 -30.381191) (xy 439.200272 -30.387291) (xy 439.144538 -30.385254) (xy 439.089695 -30.375124)
			(xy 439.036911 -30.357117) (xy 438.987311 -30.331616) (xy 438.941953 -30.299165) (xy 438.901804 -30.260456)
			(xy 438.867718 -30.216313) (xy 438.840422 -30.167678) (xy 438.820499 -30.115587) (xy 438.808373 -30.06115)
			(xy 438.804302 -30.005528) (xy 436.948502 -30.005528) (xy 436.934911 -30.009081) (xy 436.879474 -30.015181)
			(xy 436.82374 -30.013144) (xy 436.768897 -30.003014) (xy 436.716113 -29.985007) (xy 436.666513 -29.959506)
			(xy 436.621155 -29.927055) (xy 436.581006 -29.888346) (xy 436.54692 -29.844203) (xy 436.519624 -29.795568)
			(xy 436.499701 -29.743477) (xy 436.487575 -29.68904) (xy 436.483504 -29.633418) (xy 435.210966 -29.633418)
			(xy 435.245229 -29.661932) (xy 435.282446 -29.703469) (xy 435.313219 -29.749982) (xy 435.336891 -29.800479)
			(xy 435.352959 -29.853886) (xy 435.361079 -29.909062) (xy 435.361588 -29.936948) (xy 435.361079 -29.964834)
			(xy 435.352959 -30.02001) (xy 435.336891 -30.073417) (xy 435.313219 -30.123914) (xy 435.282446 -30.170427)
			(xy 435.245229 -30.211964) (xy 435.202361 -30.247639) (xy 435.154755 -30.276693) (xy 435.103426 -30.298505)
			(xy 435.049469 -30.312611) (xy 434.994032 -30.318711) (xy 434.938298 -30.316674) (xy 434.883455 -30.306544)
			(xy 434.830671 -30.288537) (xy 434.781071 -30.263036) (xy 434.735713 -30.230585) (xy 434.695564 -30.191876)
			(xy 434.661478 -30.147733) (xy 434.634182 -30.099098) (xy 434.614259 -30.047007) (xy 434.602133 -29.99257)
			(xy 434.598062 -29.936948) (xy 434.01488 -29.936948) (xy 434.01488 -30.706568) (xy 441.506862 -30.706568)
			(xy 441.510933 -30.650946) (xy 441.523059 -30.596509) (xy 441.542982 -30.544418) (xy 441.570278 -30.495783)
			(xy 441.604364 -30.45164) (xy 441.644513 -30.412931) (xy 441.689871 -30.38048) (xy 441.739471 -30.354979)
			(xy 441.792255 -30.336972) (xy 441.847098 -30.326842) (xy 441.902832 -30.324805) (xy 441.958269 -30.330905)
			(xy 442.012226 -30.345011) (xy 442.063555 -30.366823) (xy 442.111161 -30.395877) (xy 442.154029 -30.431552)
			(xy 442.191066 -30.472888) (xy 444.326262 -30.472888) (xy 444.330333 -30.417266) (xy 444.342459 -30.362829)
			(xy 444.362382 -30.310738) (xy 444.389678 -30.262103) (xy 444.423764 -30.21796) (xy 444.463913 -30.179251)
			(xy 444.509271 -30.1468) (xy 444.558871 -30.121299) (xy 444.611655 -30.103292) (xy 444.666498 -30.093162)
			(xy 444.722232 -30.091125) (xy 444.777669 -30.097225) (xy 444.831626 -30.111331) (xy 444.882955 -30.133143)
			(xy 444.930561 -30.162197) (xy 444.973429 -30.197872) (xy 445.010646 -30.239409) (xy 445.041419 -30.285922)
			(xy 445.065091 -30.336419) (xy 445.081159 -30.389826) (xy 445.089279 -30.445002) (xy 445.089788 -30.472888)
			(xy 445.089279 -30.500774) (xy 445.081159 -30.55595) (xy 445.065091 -30.609357) (xy 445.041419 -30.659854)
			(xy 445.010646 -30.706367) (xy 444.973429 -30.747904) (xy 444.930561 -30.783579) (xy 444.882955 -30.812633)
			(xy 444.831626 -30.834445) (xy 444.777669 -30.848551) (xy 444.722232 -30.854651) (xy 444.666498 -30.852614)
			(xy 444.611655 -30.842484) (xy 444.558871 -30.824477) (xy 444.509271 -30.798976) (xy 444.463913 -30.766525)
			(xy 444.423764 -30.727816) (xy 444.389678 -30.683673) (xy 444.362382 -30.635038) (xy 444.342459 -30.582947)
			(xy 444.330333 -30.52851) (xy 444.326262 -30.472888) (xy 442.191066 -30.472888) (xy 442.191246 -30.473089)
			(xy 442.222019 -30.519602) (xy 442.245691 -30.570099) (xy 442.261759 -30.623506) (xy 442.269879 -30.678682)
			(xy 442.270388 -30.706568) (xy 442.269879 -30.734454) (xy 442.261759 -30.78963) (xy 442.245691 -30.843037)
			(xy 442.222019 -30.893534) (xy 442.191246 -30.940047) (xy 442.154029 -30.981584) (xy 442.111161 -31.017259)
			(xy 442.063555 -31.046313) (xy 442.012226 -31.068125) (xy 441.958269 -31.082231) (xy 441.902832 -31.088331)
			(xy 441.847098 -31.086294) (xy 441.792255 -31.076164) (xy 441.739471 -31.058157) (xy 441.689871 -31.032656)
			(xy 441.644513 -31.000205) (xy 441.604364 -30.961496) (xy 441.570278 -30.917353) (xy 441.542982 -30.868718)
			(xy 441.523059 -30.816627) (xy 441.510933 -30.76219) (xy 441.506862 -30.706568) (xy 434.01488 -30.706568)
			(xy 434.01488 -31.229808) (xy 442.850522 -31.229808) (xy 442.854593 -31.174186) (xy 442.866719 -31.119749)
			(xy 442.886642 -31.067658) (xy 442.913938 -31.019023) (xy 442.948024 -30.97488) (xy 442.988173 -30.936171)
			(xy 443.033531 -30.90372) (xy 443.083131 -30.878219) (xy 443.135915 -30.860212) (xy 443.190758 -30.850082)
			(xy 443.246492 -30.848045) (xy 443.301929 -30.854145) (xy 443.355886 -30.868251) (xy 443.407215 -30.890063)
			(xy 443.454821 -30.919117) (xy 443.497689 -30.954792) (xy 443.534906 -30.996329) (xy 443.565679 -31.042842)
			(xy 443.589351 -31.093339) (xy 443.605419 -31.146746) (xy 443.613539 -31.201922) (xy 443.614048 -31.229808)
			(xy 443.613539 -31.257694) (xy 443.605419 -31.31287) (xy 443.589351 -31.366277) (xy 443.565679 -31.416774)
			(xy 443.534906 -31.463287) (xy 443.497689 -31.504824) (xy 443.454821 -31.540499) (xy 443.407215 -31.569553)
			(xy 443.355886 -31.591365) (xy 443.301929 -31.605471) (xy 443.246492 -31.611571) (xy 443.190758 -31.609534)
			(xy 443.135915 -31.599404) (xy 443.083131 -31.581397) (xy 443.033531 -31.555896) (xy 442.988173 -31.523445)
			(xy 442.948024 -31.484736) (xy 442.913938 -31.440593) (xy 442.886642 -31.391958) (xy 442.866719 -31.339867)
			(xy 442.854593 -31.28543) (xy 442.850522 -31.229808) (xy 434.01488 -31.229808) (xy 434.01488 -32.095948)
			(xy 434.4924 -32.573468) (xy 446.226182 -32.573468) (xy 446.230253 -32.517846) (xy 446.242379 -32.463409)
			(xy 446.262302 -32.411318) (xy 446.289598 -32.362683) (xy 446.323684 -32.31854) (xy 446.363833 -32.279831)
			(xy 446.409191 -32.24738) (xy 446.458791 -32.221879) (xy 446.511575 -32.203872) (xy 446.566418 -32.193742)
			(xy 446.622152 -32.191705) (xy 446.677589 -32.197805) (xy 446.731546 -32.211911) (xy 446.782875 -32.233723)
			(xy 446.830481 -32.262777) (xy 446.873349 -32.298452) (xy 446.910566 -32.339989) (xy 446.941339 -32.386502)
			(xy 446.965011 -32.436999) (xy 446.981079 -32.490406) (xy 446.989199 -32.545582) (xy 446.989708 -32.573468)
			(xy 446.989199 -32.601354) (xy 446.981079 -32.65653) (xy 446.965011 -32.709937) (xy 446.941339 -32.760434)
			(xy 446.910566 -32.806947) (xy 446.873349 -32.848484) (xy 446.830481 -32.884159) (xy 446.782875 -32.913213)
			(xy 446.731546 -32.935025) (xy 446.677589 -32.949131) (xy 446.622152 -32.955231) (xy 446.566418 -32.953194)
			(xy 446.511575 -32.943064) (xy 446.458791 -32.925057) (xy 446.409191 -32.899556) (xy 446.363833 -32.867105)
			(xy 446.323684 -32.828396) (xy 446.289598 -32.784253) (xy 446.262302 -32.735618) (xy 446.242379 -32.683527)
			(xy 446.230253 -32.62909) (xy 446.226182 -32.573468) (xy 434.4924 -32.573468) (xy 434.877464 -32.958532)
			(xy 434.884682 -32.965184) (xy 434.90271 -32.972899) (xy 434.922317 -32.973246) (xy 434.940608 -32.966173)
			(xy 434.948076 -32.959802) (xy 434.969373 -32.940655) (xy 435.016635 -32.908313) (xy 435.068201 -32.883401)
			(xy 435.122912 -32.866478) (xy 435.179538 -32.857926) (xy 435.208172 -32.85744) (xy 435.235425 -32.857901)
			(xy 435.289376 -32.865655) (xy 435.341675 -32.88101) (xy 435.391255 -32.903651) (xy 435.437109 -32.933119)
			(xy 435.478301 -32.968814) (xy 435.513993 -33.010007) (xy 435.543458 -33.055862) (xy 435.566097 -33.105444)
			(xy 435.581449 -33.157743) (xy 435.5892 -33.211695) (xy 435.58968 -33.238948) (xy 435.589165 -33.26758)
			(xy 435.580605 -33.324201) (xy 435.563685 -33.378909) (xy 435.538784 -33.430476) (xy 435.50646 -33.477745)
			(xy 435.487318 -33.499044) (xy 435.45379 -33.534858) (xy 435.988968 -34.070036) (xy 436.023258 -34.0487)
			(xy 436.045994 -34.03516) (xy 436.094406 -34.013793) (xy 436.145304 -33.999315) (xy 436.197713 -33.992005)
			(xy 436.224172 -33.99155) (xy 436.252295 -33.992049) (xy 436.307932 -34.000303) (xy 436.361754 -34.016634)
			(xy 436.412596 -34.04069) (xy 436.459355 -34.07195) (xy 436.501018 -34.109736) (xy 436.536682 -34.153228)
			(xy 436.565576 -34.201485) (xy 436.587071 -34.253461) (xy 436.600703 -34.30803) (xy 436.603902 -34.335974)
			(xy 436.608474 -34.381948) (xy 436.85587 -34.381948)
		)
		(stroke
			(width 0)
			(type solid)
		)
		(fill yes)
		(layer "In6.Cu")
		(net "GND")
	)
	(gr_poly
		(pts
			(xy 119.307102 -271.13738) (xy 119.320914 -271.136931) (xy 119.34753 -271.129541) (xy 119.371186 -271.115279)
			(xy 119.390146 -271.09519) (xy 119.403017 -271.070749) (xy 119.408854 -271.043749) (xy 119.408448 -271.029938)
			(xy 119.40794 -271.011396) (xy 119.408449 -270.985429) (xy 119.416574 -270.934134) (xy 119.432622 -270.884741)
			(xy 119.4562 -270.838467) (xy 119.486726 -270.796451) (xy 119.523449 -270.759728) (xy 119.565465 -270.729202)
			(xy 119.611739 -270.705624) (xy 119.661132 -270.689576) (xy 119.712427 -270.681451) (xy 119.764361 -270.681451)
			(xy 119.815656 -270.689576) (xy 119.865049 -270.705624) (xy 119.911323 -270.729202) (xy 119.953339 -270.759728)
			(xy 119.990062 -270.796451) (xy 120.020588 -270.838467) (xy 120.044166 -270.884741) (xy 120.060214 -270.934134)
			(xy 120.068339 -270.985429) (xy 120.068848 -271.011396) (xy 120.06834 -271.029938) (xy 120.068016 -271.043738)
			(xy 120.073885 -271.070698) (xy 120.086758 -271.095102) (xy 120.105696 -271.115169) (xy 120.129315 -271.129431)
			(xy 120.155891 -271.136849) (xy 120.169686 -271.13738) (xy 120.246902 -271.13738) (xy 120.260714 -271.136931)
			(xy 120.28733 -271.129541) (xy 120.310986 -271.115279) (xy 120.329946 -271.09519) (xy 120.342817 -271.070749)
			(xy 120.348654 -271.043749) (xy 120.348248 -271.029938) (xy 120.34774 -271.011396) (xy 120.348249 -270.985429)
			(xy 120.356374 -270.934134) (xy 120.372422 -270.884741) (xy 120.396 -270.838467) (xy 120.426526 -270.796451)
			(xy 120.463249 -270.759728) (xy 120.505265 -270.729202) (xy 120.551539 -270.705624) (xy 120.600932 -270.689576)
			(xy 120.652227 -270.681451) (xy 120.704161 -270.681451) (xy 120.755456 -270.689576) (xy 120.804849 -270.705624)
			(xy 120.851123 -270.729202) (xy 120.893139 -270.759728) (xy 120.929862 -270.796451) (xy 120.960388 -270.838467)
			(xy 120.983966 -270.884741) (xy 121.000014 -270.934134) (xy 121.008139 -270.985429) (xy 121.008648 -271.011396)
			(xy 121.00814 -271.029938) (xy 121.007816 -271.043738) (xy 121.013685 -271.070698) (xy 121.026558 -271.095102)
			(xy 121.045496 -271.115169) (xy 121.069115 -271.129431) (xy 121.095691 -271.136849) (xy 121.109486 -271.13738)
			(xy 121.186702 -271.13738) (xy 121.200514 -271.136931) (xy 121.22713 -271.129541) (xy 121.250786 -271.115279)
			(xy 121.269746 -271.09519) (xy 121.282617 -271.070749) (xy 121.288454 -271.043749) (xy 121.288048 -271.029938)
			(xy 121.28754 -271.011396) (xy 121.288049 -270.985429) (xy 121.296174 -270.934134) (xy 121.312222 -270.884741)
			(xy 121.3358 -270.838467) (xy 121.366326 -270.796451) (xy 121.403049 -270.759728) (xy 121.445065 -270.729202)
			(xy 121.491339 -270.705624) (xy 121.540732 -270.689576) (xy 121.592027 -270.681451) (xy 121.643961 -270.681451)
			(xy 121.695256 -270.689576) (xy 121.744649 -270.705624) (xy 121.790923 -270.729202) (xy 121.832939 -270.759728)
			(xy 121.869662 -270.796451) (xy 121.900188 -270.838467) (xy 121.923766 -270.884741) (xy 121.939814 -270.934134)
			(xy 121.947939 -270.985429) (xy 121.948448 -271.011396) (xy 121.94794 -271.029938) (xy 121.947616 -271.043738)
			(xy 121.953485 -271.070698) (xy 121.966358 -271.095102) (xy 121.985296 -271.115169) (xy 122.008915 -271.129431)
			(xy 122.035491 -271.136849) (xy 122.049286 -271.13738) (xy 122.126756 -271.13738) (xy 122.140563 -271.136924)
			(xy 122.167167 -271.129526) (xy 122.19081 -271.11526) (xy 122.209758 -271.095173) (xy 122.22262 -271.070738)
			(xy 122.228455 -271.043748) (xy 122.228102 -271.029938) (xy 122.227594 -271.011396) (xy 122.228103 -270.985429)
			(xy 122.236228 -270.934134) (xy 122.252276 -270.884741) (xy 122.275854 -270.838467) (xy 122.30638 -270.796451)
			(xy 122.343103 -270.759728) (xy 122.385119 -270.729202) (xy 122.431393 -270.705624) (xy 122.480786 -270.689576)
			(xy 122.532081 -270.681451) (xy 122.584015 -270.681451) (xy 122.63531 -270.689576) (xy 122.684703 -270.705624)
			(xy 122.730977 -270.729202) (xy 122.772993 -270.759728) (xy 122.809716 -270.796451) (xy 122.840242 -270.838467)
			(xy 122.86382 -270.884741) (xy 122.879868 -270.934134) (xy 122.887993 -270.985429) (xy 122.888502 -271.011396)
			(xy 122.887994 -271.029938) (xy 122.887669 -271.04374) (xy 122.893538 -271.070705) (xy 122.90641 -271.095115)
			(xy 122.925346 -271.115188) (xy 122.948965 -271.129461) (xy 122.975543 -271.136889) (xy 122.98934 -271.13738)
			(xy 123.066302 -271.13738) (xy 123.080114 -271.136931) (xy 123.10673 -271.129541) (xy 123.130386 -271.115279)
			(xy 123.149346 -271.09519) (xy 123.162217 -271.070749) (xy 123.168054 -271.043749) (xy 123.167648 -271.029938)
			(xy 123.16714 -271.011396) (xy 123.167649 -270.985429) (xy 123.175774 -270.934134) (xy 123.191822 -270.884741)
			(xy 123.2154 -270.838467) (xy 123.245926 -270.796451) (xy 123.282649 -270.759728) (xy 123.324665 -270.729202)
			(xy 123.370939 -270.705624) (xy 123.420332 -270.689576) (xy 123.471627 -270.681451) (xy 123.523561 -270.681451)
			(xy 123.574856 -270.689576) (xy 123.624249 -270.705624) (xy 123.670523 -270.729202) (xy 123.712539 -270.759728)
			(xy 123.749262 -270.796451) (xy 123.779788 -270.838467) (xy 123.803366 -270.884741) (xy 123.819414 -270.934134)
			(xy 123.827539 -270.985429) (xy 123.828048 -271.011396) (xy 123.82754 -271.029938) (xy 123.827216 -271.043738)
			(xy 123.833085 -271.070698) (xy 123.845958 -271.095102) (xy 123.864896 -271.115169) (xy 123.888515 -271.129431)
			(xy 123.915091 -271.136849) (xy 123.928886 -271.13738) (xy 124.006102 -271.13738) (xy 124.019914 -271.136931)
			(xy 124.04653 -271.129541) (xy 124.070186 -271.115279) (xy 124.089146 -271.09519) (xy 124.102017 -271.070749)
			(xy 124.107854 -271.043749) (xy 124.107448 -271.029938) (xy 124.10694 -271.011396) (xy 124.10745 -270.985429)
			(xy 124.115574 -270.934134) (xy 124.131623 -270.884741) (xy 124.155201 -270.838468) (xy 124.185727 -270.796452)
			(xy 124.22245 -270.759729) (xy 124.264466 -270.729202) (xy 124.31074 -270.705624) (xy 124.360132 -270.689575)
			(xy 124.411427 -270.68145) (xy 124.437394 -270.680942) (xy 124.464508 -270.681495) (xy 124.518006 -270.690358)
			(xy 124.569341 -270.707832) (xy 124.617137 -270.733449) (xy 124.660113 -270.76652) (xy 124.697116 -270.806161)
			(xy 124.727156 -270.851308) (xy 124.749426 -270.900752) (xy 124.756926 -270.926814) (xy 124.761412 -270.941368)
			(xy 124.777601 -270.967145) (xy 124.800663 -270.987011) (xy 124.828552 -270.999206) (xy 124.858796 -271.002647)
			(xy 124.888712 -270.997029) (xy 124.915647 -270.982851) (xy 124.926852 -270.972534) (xy 125.221746 -270.67764)
			(xy 125.221746 -270.573754) (xy 125.221195 -270.558586) (xy 125.212298 -270.529584) (xy 125.195275 -270.504474)
			(xy 125.171626 -270.485474) (xy 125.143439 -270.47426) (xy 125.113201 -270.471821) (xy 125.083581 -270.478372)
			(xy 125.070108 -270.485362) (xy 125.045133 -270.498767) (xy 124.991738 -270.517778) (xy 124.935887 -270.527428)
			(xy 124.907548 -270.528034) (xy 124.881578 -270.527555) (xy 124.830276 -270.519436) (xy 124.780876 -270.503392)
			(xy 124.734595 -270.479816) (xy 124.692571 -270.44929) (xy 124.655841 -270.412565) (xy 124.625309 -270.370546)
			(xy 124.601727 -270.324268) (xy 124.585675 -270.274871) (xy 124.577549 -270.22357) (xy 124.577549 -270.17163)
			(xy 124.585675 -270.120329) (xy 124.601727 -270.070932) (xy 124.625309 -270.024654) (xy 124.655841 -269.982635)
			(xy 124.692571 -269.94591) (xy 124.734595 -269.915384) (xy 124.780876 -269.891808) (xy 124.830276 -269.875764)
			(xy 124.881578 -269.867645) (xy 124.907548 -269.867126) (xy 124.935891 -269.867685) (xy 124.991752 -269.87732)
			(xy 125.045142 -269.896368) (xy 125.070108 -269.909798) (xy 125.083576 -269.916774) (xy 125.11318 -269.923294)
			(xy 125.143393 -269.920837) (xy 125.171555 -269.909619) (xy 125.195183 -269.890629) (xy 125.212197 -269.86554)
			(xy 125.221097 -269.836563) (xy 125.221746 -269.821406) (xy 125.221746 -269.675102) (xy 125.199441 -269.662673)
			(xy 125.158615 -269.632008) (xy 125.122992 -269.595429) (xy 125.093419 -269.553806) (xy 125.070601 -269.508129)
			(xy 125.055079 -269.459486) (xy 125.047225 -269.409034) (xy 125.047224 -269.357975) (xy 125.055077 -269.307523)
			(xy 125.070597 -269.25888) (xy 125.093414 -269.213202) (xy 125.122986 -269.171578) (xy 125.158608 -269.134998)
			(xy 125.199433 -269.104332) (xy 125.221746 -269.091918) (xy 125.221746 -268.945868) (xy 125.221183 -268.930709)
			(xy 125.212273 -268.901731) (xy 125.195247 -268.876645) (xy 125.171607 -268.857663) (xy 125.143436 -268.846459)
			(xy 125.113216 -268.84402) (xy 125.083612 -268.85056) (xy 125.070108 -268.857476) (xy 125.045134 -268.870883)
			(xy 124.991739 -268.889899) (xy 124.935888 -268.899552) (xy 124.907548 -268.900148) (xy 124.881577 -268.899669)
			(xy 124.830273 -268.89155) (xy 124.780871 -268.875505) (xy 124.734587 -268.851928) (xy 124.692562 -268.821401)
			(xy 124.655831 -268.784674) (xy 124.625297 -268.742654) (xy 124.601714 -268.696374) (xy 124.585661 -268.646974)
			(xy 124.577535 -268.595671) (xy 124.577535 -268.543729) (xy 124.585661 -268.492426) (xy 124.601714 -268.443026)
			(xy 124.625297 -268.396746) (xy 124.655831 -268.354726) (xy 124.692562 -268.317999) (xy 124.734587 -268.287472)
			(xy 124.780871 -268.263895) (xy 124.830273 -268.24785) (xy 124.881577 -268.239731) (xy 124.907548 -268.23924)
			(xy 124.935891 -268.239799) (xy 124.991752 -268.249435) (xy 125.045141 -268.268483) (xy 125.070108 -268.281912)
			(xy 125.083576 -268.288887) (xy 125.113181 -268.295406) (xy 125.143396 -268.292949) (xy 125.171558 -268.281731)
			(xy 125.195188 -268.262742) (xy 125.212204 -268.237654) (xy 125.221107 -268.208677) (xy 125.221746 -268.19352)
			(xy 125.221746 -268.04747) (xy 125.199444 -268.035041) (xy 125.158623 -268.004377) (xy 125.123004 -267.967799)
			(xy 125.093436 -267.926178) (xy 125.070621 -267.880504) (xy 125.055103 -267.831865) (xy 125.047252 -267.781417)
			(xy 125.047253 -267.730362) (xy 125.055108 -267.679915) (xy 125.070629 -267.631276) (xy 125.093446 -267.585604)
			(xy 125.123017 -267.543985) (xy 125.158638 -267.507409) (xy 125.199461 -267.476748) (xy 125.221746 -267.464286)
			(xy 125.221746 -267.317982) (xy 125.221185 -267.302822) (xy 125.212277 -267.273839) (xy 125.195252 -267.24875)
			(xy 125.17161 -267.229765) (xy 125.143436 -267.218559) (xy 125.113214 -267.21612) (xy 125.083607 -267.222662)
			(xy 125.070108 -267.22959) (xy 125.045133 -267.242997) (xy 124.991739 -267.262012) (xy 124.935888 -267.271665)
			(xy 124.907548 -267.272262) (xy 124.881576 -267.271783) (xy 124.830269 -267.263663) (xy 124.780865 -267.247617)
			(xy 124.73458 -267.22404) (xy 124.692553 -267.193511) (xy 124.65582 -267.156783) (xy 124.625285 -267.114761)
			(xy 124.601701 -267.068479) (xy 124.585648 -267.019077) (xy 124.577521 -266.967772) (xy 124.577521 -266.915828)
			(xy 124.585648 -266.864523) (xy 124.601701 -266.815121) (xy 124.625285 -266.768839) (xy 124.65582 -266.726817)
			(xy 124.692553 -266.690089) (xy 124.73458 -266.65956) (xy 124.780865 -266.635983) (xy 124.830269 -266.619937)
			(xy 124.881576 -266.611817) (xy 124.907548 -266.611354) (xy 124.935891 -266.611913) (xy 124.991752 -266.621549)
			(xy 125.045141 -266.640598) (xy 125.070108 -266.654026) (xy 125.083577 -266.661001) (xy 125.113183 -266.667518)
			(xy 125.143398 -266.665061) (xy 125.171561 -266.653844) (xy 125.195192 -266.634855) (xy 125.212211 -266.609768)
			(xy 125.221117 -266.580791) (xy 125.221746 -266.565634) (xy 125.221746 -266.419838) (xy 125.199438 -266.407409)
			(xy 125.158607 -266.376743) (xy 125.122978 -266.340163) (xy 125.093401 -266.298537) (xy 125.070577 -266.252857)
			(xy 125.055052 -266.20421) (xy 125.047194 -266.153754) (xy 125.047191 -266.102689) (xy 125.055042 -266.052232)
			(xy 125.070561 -266.003583) (xy 125.093378 -265.9579) (xy 125.122951 -265.916271) (xy 125.158575 -265.879685)
			(xy 125.199402 -265.849015) (xy 125.221746 -265.836654) (xy 125.221746 -265.69035) (xy 125.221194 -265.675182)
			(xy 125.212297 -265.646181) (xy 125.195274 -265.621073) (xy 125.171625 -265.602074) (xy 125.143439 -265.59086)
			(xy 125.113202 -265.588421) (xy 125.083583 -265.594971) (xy 125.070108 -265.601958) (xy 125.045133 -265.615363)
			(xy 124.991738 -265.634374) (xy 124.935887 -265.644025) (xy 124.907548 -265.64463) (xy 124.881578 -265.644151)
			(xy 124.830277 -265.636032) (xy 124.780878 -265.619988) (xy 124.734597 -265.596413) (xy 124.692574 -265.565887)
			(xy 124.655844 -265.529163) (xy 124.625313 -265.487144) (xy 124.60173 -265.440867) (xy 124.585679 -265.39147)
			(xy 124.577553 -265.34017) (xy 124.577553 -265.28823) (xy 124.585679 -265.23693) (xy 124.60173 -265.187533)
			(xy 124.625313 -265.141256) (xy 124.655844 -265.099237) (xy 124.692574 -265.062513) (xy 124.734597 -265.031987)
			(xy 124.780878 -265.008412) (xy 124.830277 -264.992368) (xy 124.881578 -264.984249) (xy 124.907548 -264.983722)
			(xy 124.935891 -264.984281) (xy 124.991752 -264.993916) (xy 125.045142 -265.012964) (xy 125.070108 -265.026394)
			(xy 125.083575 -265.03337) (xy 125.113179 -265.03989) (xy 125.143393 -265.037433) (xy 125.171554 -265.026216)
			(xy 125.195182 -265.007226) (xy 125.212195 -264.982136) (xy 125.221094 -264.953159) (xy 125.221746 -264.938002)
			(xy 125.221746 -264.791952) (xy 125.199445 -264.779523) (xy 125.158627 -264.74886) (xy 125.123011 -264.712283)
			(xy 125.093445 -264.670663) (xy 125.070633 -264.624991) (xy 125.055117 -264.576353) (xy 125.047267 -264.525907)
			(xy 125.04727 -264.474855) (xy 125.055125 -264.42441) (xy 125.070647 -264.375774) (xy 125.093464 -264.330105)
			(xy 125.123035 -264.288488) (xy 125.158655 -264.251915) (xy 125.199477 -264.221257) (xy 125.221746 -264.208768)
			(xy 125.221746 -264.062718) (xy 125.22119 -264.047554) (xy 125.212288 -264.018561) (xy 125.195263 -263.993462)
			(xy 125.171618 -263.97447) (xy 125.143438 -263.96326) (xy 125.113208 -263.96082) (xy 125.083594 -263.967367)
			(xy 125.070108 -263.974326) (xy 125.045133 -263.987731) (xy 124.991738 -264.006745) (xy 124.935887 -264.016396)
			(xy 124.907548 -264.016998) (xy 124.881573 -264.016519) (xy 124.830261 -264.008399) (xy 124.780852 -263.992351)
			(xy 124.734561 -263.96877) (xy 124.69253 -263.938239) (xy 124.655793 -263.901507) (xy 124.625255 -263.85948)
			(xy 124.601668 -263.813193) (xy 124.585613 -263.763786) (xy 124.577485 -263.712475) (xy 124.577485 -263.660525)
			(xy 124.585613 -263.609214) (xy 124.601668 -263.559807) (xy 124.625255 -263.51352) (xy 124.655793 -263.471493)
			(xy 124.69253 -263.434761) (xy 124.734561 -263.40423) (xy 124.780852 -263.380649) (xy 124.830261 -263.364601)
			(xy 124.881573 -263.356481) (xy 124.907548 -263.35609) (xy 124.935892 -263.356649) (xy 124.991753 -263.366283)
			(xy 125.045143 -263.385329) (xy 125.070108 -263.398762) (xy 125.083579 -263.405735) (xy 125.113187 -263.412251)
			(xy 125.143404 -263.409792) (xy 125.171569 -263.398576) (xy 125.195204 -263.379589) (xy 125.212229 -263.354504)
			(xy 125.221144 -263.325528) (xy 125.221746 -263.31037) (xy 125.221746 -263.164066) (xy 125.199471 -263.151615)
			(xy 125.158707 -263.120921) (xy 125.123143 -263.084328) (xy 125.093622 -263.042707) (xy 125.070846 -262.997044)
			(xy 125.055355 -262.948424) (xy 125.047518 -262.898002) (xy 125.04752 -262.846974) (xy 125.055361 -262.796552)
			(xy 125.070855 -262.747933) (xy 125.093635 -262.702272) (xy 125.123159 -262.660653) (xy 125.158726 -262.624063)
			(xy 125.199492 -262.593372) (xy 125.221746 -262.580882) (xy 125.221746 -262.434832) (xy 125.221192 -262.419666)
			(xy 125.212292 -262.39067) (xy 125.195268 -262.365567) (xy 125.171621 -262.346572) (xy 125.143438 -262.33536)
			(xy 125.113205 -262.33292) (xy 125.083589 -262.339469) (xy 125.070108 -262.34644) (xy 125.045133 -262.359845)
			(xy 124.991738 -262.378857) (xy 124.935887 -262.388508) (xy 124.907548 -262.389112) (xy 124.88158 -262.388633)
			(xy 124.830281 -262.380515) (xy 124.780884 -262.364471) (xy 124.734606 -262.340897) (xy 124.692586 -262.310373)
			(xy 124.655858 -262.273651) (xy 124.625328 -262.231635) (xy 124.601747 -262.18536) (xy 124.585696 -262.135966)
			(xy 124.577571 -262.084668) (xy 124.577571 -262.032732) (xy 124.585696 -261.981434) (xy 124.601747 -261.93204)
			(xy 124.625328 -261.885765) (xy 124.655858 -261.843749) (xy 124.692586 -261.807027) (xy 124.734606 -261.776503)
			(xy 124.780884 -261.752929) (xy 124.830281 -261.736885) (xy 124.88158 -261.728767) (xy 124.907548 -261.728204)
			(xy 124.932767 -261.728655) (xy 124.982625 -261.736277) (xy 125.030743 -261.751397) (xy 125.075999 -261.773664)
			(xy 125.11734 -261.802558) (xy 125.135894 -261.819644) (xy 125.150626 -261.833868) (xy 125.221746 -261.833868)
			(xy 125.221746 -261.728458) (xy 125.096778 -261.60349) (xy 122.521218 -261.60349) (xy 122.34545 -261.779258)
			(xy 122.339134 -261.786235) (xy 122.331589 -261.803459) (xy 122.330752 -261.822244) (xy 122.336733 -261.840071)
			(xy 122.342402 -261.847584) (xy 122.360227 -261.870009) (xy 122.388671 -261.919725) (xy 122.408124 -261.973599)
			(xy 122.418001 -262.030019) (xy 122.418602 -262.058658) (xy 122.418093 -262.084625) (xy 122.697749 -262.084625)
			(xy 122.697749 -262.032691) (xy 122.705874 -261.981396) (xy 122.721922 -261.932003) (xy 122.7455 -261.885729)
			(xy 122.776026 -261.843713) (xy 122.812749 -261.80699) (xy 122.854765 -261.776464) (xy 122.901039 -261.752886)
			(xy 122.950432 -261.736838) (xy 123.001727 -261.728713) (xy 123.053661 -261.728713) (xy 123.104956 -261.736838)
			(xy 123.154349 -261.752886) (xy 123.200623 -261.776464) (xy 123.242639 -261.80699) (xy 123.279362 -261.843713)
			(xy 123.309888 -261.885729) (xy 123.333466 -261.932003) (xy 123.349514 -261.981396) (xy 123.357639 -262.032691)
			(xy 123.358148 -262.058658) (xy 123.357639 -262.084625) (xy 123.637803 -262.084625) (xy 123.637803 -262.032691)
			(xy 123.645928 -261.981396) (xy 123.661976 -261.932003) (xy 123.685554 -261.885729) (xy 123.71608 -261.843713)
			(xy 123.752803 -261.80699) (xy 123.794819 -261.776464) (xy 123.841093 -261.752886) (xy 123.890486 -261.736838)
			(xy 123.941781 -261.728713) (xy 123.993715 -261.728713) (xy 124.04501 -261.736838) (xy 124.094403 -261.752886)
			(xy 124.140677 -261.776464) (xy 124.182693 -261.80699) (xy 124.219416 -261.843713) (xy 124.249942 -261.885729)
			(xy 124.27352 -261.932003) (xy 124.289568 -261.981396) (xy 124.297693 -262.032691) (xy 124.298202 -262.058658)
			(xy 124.297693 -262.084625) (xy 124.289568 -262.13592) (xy 124.27352 -262.185313) (xy 124.249942 -262.231587)
			(xy 124.219416 -262.273603) (xy 124.182693 -262.310326) (xy 124.140677 -262.340852) (xy 124.094403 -262.36443)
			(xy 124.04501 -262.380478) (xy 123.993715 -262.388603) (xy 123.941781 -262.388603) (xy 123.890486 -262.380478)
			(xy 123.841093 -262.36443) (xy 123.794819 -262.340852) (xy 123.752803 -262.310326) (xy 123.71608 -262.273603)
			(xy 123.685554 -262.231587) (xy 123.661976 -262.185313) (xy 123.645928 -262.13592) (xy 123.637803 -262.084625)
			(xy 123.357639 -262.084625) (xy 123.349514 -262.13592) (xy 123.333466 -262.185313) (xy 123.309888 -262.231587)
			(xy 123.279362 -262.273603) (xy 123.242639 -262.310326) (xy 123.200623 -262.340852) (xy 123.154349 -262.36443)
			(xy 123.104956 -262.380478) (xy 123.053661 -262.388603) (xy 123.001727 -262.388603) (xy 122.950432 -262.380478)
			(xy 122.901039 -262.36443) (xy 122.854765 -262.340852) (xy 122.812749 -262.310326) (xy 122.776026 -262.273603)
			(xy 122.7455 -262.231587) (xy 122.721922 -262.185313) (xy 122.705874 -262.13592) (xy 122.697749 -262.084625)
			(xy 122.418093 -262.084625) (xy 122.409968 -262.13592) (xy 122.39392 -262.185313) (xy 122.370342 -262.231587)
			(xy 122.339816 -262.273603) (xy 122.303093 -262.310326) (xy 122.261077 -262.340852) (xy 122.214803 -262.36443)
			(xy 122.16541 -262.380478) (xy 122.114115 -262.388603) (xy 122.062181 -262.388603) (xy 122.010886 -262.380478)
			(xy 121.961493 -262.36443) (xy 121.915219 -262.340852) (xy 121.873203 -262.310326) (xy 121.83648 -262.273603)
			(xy 121.805954 -262.231587) (xy 121.782376 -262.185313) (xy 121.766328 -262.13592) (xy 121.758203 -262.084625)
			(xy 121.757694 -262.058658) (xy 121.758157 -262.033365) (xy 121.765809 -261.983363) (xy 121.772934 -261.95909)
			(xy 121.776607 -261.945962) (xy 121.777616 -261.918731) (xy 121.771385 -261.892203) (xy 121.75836 -261.868268)
			(xy 121.739467 -261.848631) (xy 121.716052 -261.834691) (xy 121.689784 -261.827441) (xy 121.67616 -261.82701)
			(xy 121.352818 -261.82701) (xy 121.218198 -261.69239) (xy 121.218198 -260.720586) (xy 120.83288 -260.335268)
			(xy 119.45366 -260.335268) (xy 119.09298 -260.695948) (xy 119.09298 -263.30357) (xy 119.375633 -263.30357)
			(xy 119.375633 -263.25163) (xy 119.383759 -263.200328) (xy 119.39981 -263.15093) (xy 119.423392 -263.104651)
			(xy 119.453923 -263.062631) (xy 119.490653 -263.025905) (xy 119.532675 -262.995377) (xy 119.578956 -262.971799)
			(xy 119.628356 -262.955752) (xy 119.679658 -262.947631) (xy 119.705628 -262.94715) (xy 119.732142 -262.947677)
			(xy 119.784486 -262.956165) (xy 119.834799 -262.972918) (xy 119.858536 -262.984742) (xy 119.872252 -262.991257)
			(xy 119.902084 -262.996822) (xy 119.932234 -262.993381) (xy 119.960044 -262.981237) (xy 119.983062 -262.961461)
			(xy 119.991632 -262.948928) (xy 120.0069 -262.925775) (xy 120.043972 -262.884529) (xy 120.087412 -262.850053)
			(xy 120.135998 -262.823315) (xy 120.188368 -262.805066) (xy 120.243049 -262.795818) (xy 120.270778 -262.795258)
			(xy 120.296749 -262.795715) (xy 120.348053 -262.803838) (xy 120.397454 -262.819886) (xy 120.443737 -262.843466)
			(xy 120.48576 -262.873995) (xy 120.510208 -262.898441) (xy 121.288049 -262.898441) (xy 121.288049 -262.846507)
			(xy 121.296174 -262.795212) (xy 121.312222 -262.745819) (xy 121.3358 -262.699545) (xy 121.366326 -262.657529)
			(xy 121.403049 -262.620806) (xy 121.445065 -262.59028) (xy 121.491339 -262.566702) (xy 121.540732 -262.550654)
			(xy 121.592027 -262.542529) (xy 121.643961 -262.542529) (xy 121.695256 -262.550654) (xy 121.744649 -262.566702)
			(xy 121.790923 -262.59028) (xy 121.832939 -262.620806) (xy 121.869662 -262.657529) (xy 121.900188 -262.699545)
			(xy 121.923766 -262.745819) (xy 121.939814 -262.795212) (xy 121.947939 -262.846507) (xy 121.948448 -262.872474)
			(xy 121.947939 -262.898441) (xy 122.228103 -262.898441) (xy 122.228103 -262.846507) (xy 122.236228 -262.795212)
			(xy 122.252276 -262.745819) (xy 122.275854 -262.699545) (xy 122.30638 -262.657529) (xy 122.343103 -262.620806)
			(xy 122.385119 -262.59028) (xy 122.431393 -262.566702) (xy 122.480786 -262.550654) (xy 122.532081 -262.542529)
			(xy 122.584015 -262.542529) (xy 122.63531 -262.550654) (xy 122.684703 -262.566702) (xy 122.730977 -262.59028)
			(xy 122.772993 -262.620806) (xy 122.809716 -262.657529) (xy 122.840242 -262.699545) (xy 122.86382 -262.745819)
			(xy 122.879868 -262.795212) (xy 122.887993 -262.846507) (xy 122.888502 -262.872474) (xy 122.887993 -262.898441)
			(xy 123.167649 -262.898441) (xy 123.167649 -262.846507) (xy 123.175774 -262.795212) (xy 123.191822 -262.745819)
			(xy 123.2154 -262.699545) (xy 123.245926 -262.657529) (xy 123.282649 -262.620806) (xy 123.324665 -262.59028)
			(xy 123.370939 -262.566702) (xy 123.420332 -262.550654) (xy 123.471627 -262.542529) (xy 123.523561 -262.542529)
			(xy 123.574856 -262.550654) (xy 123.624249 -262.566702) (xy 123.670523 -262.59028) (xy 123.712539 -262.620806)
			(xy 123.749262 -262.657529) (xy 123.779788 -262.699545) (xy 123.803366 -262.745819) (xy 123.819414 -262.795212)
			(xy 123.827539 -262.846507) (xy 123.828048 -262.872474) (xy 123.827539 -262.898441) (xy 124.107449 -262.898441)
			(xy 124.107449 -262.846507) (xy 124.115574 -262.795212) (xy 124.131622 -262.745819) (xy 124.1552 -262.699545)
			(xy 124.185726 -262.657529) (xy 124.222449 -262.620806) (xy 124.264465 -262.59028) (xy 124.310739 -262.566702)
			(xy 124.360132 -262.550654) (xy 124.411427 -262.542529) (xy 124.463361 -262.542529) (xy 124.514656 -262.550654)
			(xy 124.564049 -262.566702) (xy 124.610323 -262.59028) (xy 124.652339 -262.620806) (xy 124.689062 -262.657529)
			(xy 124.719588 -262.699545) (xy 124.743166 -262.745819) (xy 124.759214 -262.795212) (xy 124.767339 -262.846507)
			(xy 124.767848 -262.872474) (xy 124.767339 -262.898441) (xy 124.759214 -262.949736) (xy 124.743166 -262.999129)
			(xy 124.719588 -263.045403) (xy 124.689062 -263.087419) (xy 124.652339 -263.124142) (xy 124.610323 -263.154668)
			(xy 124.564049 -263.178246) (xy 124.514656 -263.194294) (xy 124.463361 -263.202419) (xy 124.411427 -263.202419)
			(xy 124.360132 -263.194294) (xy 124.310739 -263.178246) (xy 124.264465 -263.154668) (xy 124.222449 -263.124142)
			(xy 124.185726 -263.087419) (xy 124.1552 -263.045403) (xy 124.131622 -262.999129) (xy 124.115574 -262.949736)
			(xy 124.107449 -262.898441) (xy 123.827539 -262.898441) (xy 123.819414 -262.949736) (xy 123.803366 -262.999129)
			(xy 123.779788 -263.045403) (xy 123.749262 -263.087419) (xy 123.712539 -263.124142) (xy 123.670523 -263.154668)
			(xy 123.624249 -263.178246) (xy 123.574856 -263.194294) (xy 123.523561 -263.202419) (xy 123.471627 -263.202419)
			(xy 123.420332 -263.194294) (xy 123.370939 -263.178246) (xy 123.324665 -263.154668) (xy 123.282649 -263.124142)
			(xy 123.245926 -263.087419) (xy 123.2154 -263.045403) (xy 123.191822 -262.999129) (xy 123.175774 -262.949736)
			(xy 123.167649 -262.898441) (xy 122.887993 -262.898441) (xy 122.879868 -262.949736) (xy 122.86382 -262.999129)
			(xy 122.840242 -263.045403) (xy 122.809716 -263.087419) (xy 122.772993 -263.124142) (xy 122.730977 -263.154668)
			(xy 122.684703 -263.178246) (xy 122.63531 -263.194294) (xy 122.584015 -263.202419) (xy 122.532081 -263.202419)
			(xy 122.480786 -263.194294) (xy 122.431393 -263.178246) (xy 122.385119 -263.154668) (xy 122.343103 -263.124142)
			(xy 122.30638 -263.087419) (xy 122.275854 -263.045403) (xy 122.252276 -262.999129) (xy 122.236228 -262.949736)
			(xy 122.228103 -262.898441) (xy 121.947939 -262.898441) (xy 121.939814 -262.949736) (xy 121.923766 -262.999129)
			(xy 121.900188 -263.045403) (xy 121.869662 -263.087419) (xy 121.832939 -263.124142) (xy 121.790923 -263.154668)
			(xy 121.744649 -263.178246) (xy 121.695256 -263.194294) (xy 121.643961 -263.202419) (xy 121.592027 -263.202419)
			(xy 121.540732 -263.194294) (xy 121.491339 -263.178246) (xy 121.445065 -263.154668) (xy 121.403049 -263.124142)
			(xy 121.366326 -263.087419) (xy 121.3358 -263.045403) (xy 121.312222 -262.999129) (xy 121.296174 -262.949736)
			(xy 121.288049 -262.898441) (xy 120.510208 -262.898441) (xy 120.522491 -262.910723) (xy 120.553023 -262.952745)
			(xy 120.576605 -262.999025) (xy 120.592657 -263.048426) (xy 120.600783 -263.099729) (xy 120.600783 -263.151671)
			(xy 120.592657 -263.202974) (xy 120.576605 -263.252375) (xy 120.553023 -263.298655) (xy 120.522491 -263.340677)
			(xy 120.48576 -263.377405) (xy 120.443737 -263.407934) (xy 120.397454 -263.431514) (xy 120.348053 -263.447562)
			(xy 120.296749 -263.455685) (xy 120.270778 -263.456166) (xy 120.244264 -263.455646) (xy 120.191919 -263.447157)
			(xy 120.141607 -263.430401) (xy 120.11787 -263.418574) (xy 120.104153 -263.41206) (xy 120.074322 -263.406492)
			(xy 120.044171 -263.409932) (xy 120.01636 -263.422076) (xy 119.993343 -263.441854) (xy 119.984774 -263.454388)
			(xy 119.969475 -263.47752) (xy 119.932412 -263.51877) (xy 119.88898 -263.553251) (xy 119.840399 -263.579994)
			(xy 119.788034 -263.598247) (xy 119.733356 -263.607497) (xy 119.705628 -263.608058) (xy 119.679658 -263.607569)
			(xy 119.628356 -263.599448) (xy 119.578956 -263.583401) (xy 119.532675 -263.559823) (xy 119.490653 -263.529295)
			(xy 119.453923 -263.492569) (xy 119.423392 -263.450549) (xy 119.39981 -263.40427) (xy 119.383759 -263.354872)
			(xy 119.375633 -263.30357) (xy 119.09298 -263.30357) (xy 119.09298 -263.712511) (xy 121.758203 -263.712511)
			(xy 121.758203 -263.660577) (xy 121.766328 -263.609282) (xy 121.782376 -263.559889) (xy 121.805954 -263.513615)
			(xy 121.83648 -263.471599) (xy 121.873203 -263.434876) (xy 121.915219 -263.40435) (xy 121.961493 -263.380772)
			(xy 122.010886 -263.364724) (xy 122.062181 -263.356599) (xy 122.114115 -263.356599) (xy 122.16541 -263.364724)
			(xy 122.214803 -263.380772) (xy 122.261077 -263.40435) (xy 122.303093 -263.434876) (xy 122.339816 -263.471599)
			(xy 122.370342 -263.513615) (xy 122.39392 -263.559889) (xy 122.409968 -263.609282) (xy 122.418093 -263.660577)
			(xy 122.418602 -263.686544) (xy 122.418093 -263.712511) (xy 122.697749 -263.712511) (xy 122.697749 -263.660577)
			(xy 122.705874 -263.609282) (xy 122.721922 -263.559889) (xy 122.7455 -263.513615) (xy 122.776026 -263.471599)
			(xy 122.812749 -263.434876) (xy 122.854765 -263.40435) (xy 122.901039 -263.380772) (xy 122.950432 -263.364724)
			(xy 123.001727 -263.356599) (xy 123.053661 -263.356599) (xy 123.104956 -263.364724) (xy 123.154349 -263.380772)
			(xy 123.200623 -263.40435) (xy 123.242639 -263.434876) (xy 123.279362 -263.471599) (xy 123.309888 -263.513615)
			(xy 123.333466 -263.559889) (xy 123.349514 -263.609282) (xy 123.357639 -263.660577) (xy 123.358148 -263.686544)
			(xy 123.357639 -263.712511) (xy 123.637803 -263.712511) (xy 123.637803 -263.660577) (xy 123.645928 -263.609282)
			(xy 123.661976 -263.559889) (xy 123.685554 -263.513615) (xy 123.71608 -263.471599) (xy 123.752803 -263.434876)
			(xy 123.794819 -263.40435) (xy 123.841093 -263.380772) (xy 123.890486 -263.364724) (xy 123.941781 -263.356599)
			(xy 123.993715 -263.356599) (xy 124.04501 -263.364724) (xy 124.094403 -263.380772) (xy 124.140677 -263.40435)
			(xy 124.182693 -263.434876) (xy 124.219416 -263.471599) (xy 124.249942 -263.513615) (xy 124.27352 -263.559889)
			(xy 124.289568 -263.609282) (xy 124.297693 -263.660577) (xy 124.298202 -263.686544) (xy 124.297693 -263.712511)
			(xy 124.289568 -263.763806) (xy 124.27352 -263.813199) (xy 124.249942 -263.859473) (xy 124.219416 -263.901489)
			(xy 124.182693 -263.938212) (xy 124.140677 -263.968738) (xy 124.094403 -263.992316) (xy 124.04501 -264.008364)
			(xy 123.993715 -264.016489) (xy 123.941781 -264.016489) (xy 123.890486 -264.008364) (xy 123.841093 -263.992316)
			(xy 123.794819 -263.968738) (xy 123.752803 -263.938212) (xy 123.71608 -263.901489) (xy 123.685554 -263.859473)
			(xy 123.661976 -263.813199) (xy 123.645928 -263.763806) (xy 123.637803 -263.712511) (xy 123.357639 -263.712511)
			(xy 123.349514 -263.763806) (xy 123.333466 -263.813199) (xy 123.309888 -263.859473) (xy 123.279362 -263.901489)
			(xy 123.242639 -263.938212) (xy 123.200623 -263.968738) (xy 123.154349 -263.992316) (xy 123.104956 -264.008364)
			(xy 123.053661 -264.016489) (xy 123.001727 -264.016489) (xy 122.950432 -264.008364) (xy 122.901039 -263.992316)
			(xy 122.854765 -263.968738) (xy 122.812749 -263.938212) (xy 122.776026 -263.901489) (xy 122.7455 -263.859473)
			(xy 122.721922 -263.813199) (xy 122.705874 -263.763806) (xy 122.697749 -263.712511) (xy 122.418093 -263.712511)
			(xy 122.409968 -263.763806) (xy 122.39392 -263.813199) (xy 122.370342 -263.859473) (xy 122.339816 -263.901489)
			(xy 122.303093 -263.938212) (xy 122.261077 -263.968738) (xy 122.214803 -263.992316) (xy 122.16541 -264.008364)
			(xy 122.114115 -264.016489) (xy 122.062181 -264.016489) (xy 122.010886 -264.008364) (xy 121.961493 -263.992316)
			(xy 121.915219 -263.968738) (xy 121.873203 -263.938212) (xy 121.83648 -263.901489) (xy 121.805954 -263.859473)
			(xy 121.782376 -263.813199) (xy 121.766328 -263.763806) (xy 121.758203 -263.712511) (xy 119.09298 -263.712511)
			(xy 119.09298 -264.190226) (xy 119.058944 -264.224262) (xy 119.052578 -264.231163) (xy 119.044898 -264.248278)
			(xy 119.043907 -264.26701) (xy 119.049738 -264.284839) (xy 119.055388 -264.292334) (xy 119.072662 -264.314561)
			(xy 119.100168 -264.363672) (xy 119.11895 -264.416736) (xy 119.128465 -264.472215) (xy 119.129048 -264.50036)
			(xy 119.128568 -264.526327) (xy 119.408449 -264.526327) (xy 119.408449 -264.474393) (xy 119.416574 -264.423098)
			(xy 119.432622 -264.373705) (xy 119.4562 -264.327431) (xy 119.486726 -264.285415) (xy 119.523449 -264.248692)
			(xy 119.565465 -264.218166) (xy 119.611739 -264.194588) (xy 119.661132 -264.17854) (xy 119.712427 -264.170415)
			(xy 119.764361 -264.170415) (xy 119.815656 -264.17854) (xy 119.865049 -264.194588) (xy 119.911323 -264.218166)
			(xy 119.953339 -264.248692) (xy 119.990062 -264.285415) (xy 120.020588 -264.327431) (xy 120.044166 -264.373705)
			(xy 120.060214 -264.423098) (xy 120.068339 -264.474393) (xy 120.068848 -264.50036) (xy 120.068339 -264.526327)
			(xy 120.348249 -264.526327) (xy 120.348249 -264.474393) (xy 120.356374 -264.423098) (xy 120.372422 -264.373705)
			(xy 120.396 -264.327431) (xy 120.426526 -264.285415) (xy 120.463249 -264.248692) (xy 120.505265 -264.218166)
			(xy 120.551539 -264.194588) (xy 120.600932 -264.17854) (xy 120.652227 -264.170415) (xy 120.704161 -264.170415)
			(xy 120.755456 -264.17854) (xy 120.804849 -264.194588) (xy 120.851123 -264.218166) (xy 120.893139 -264.248692)
			(xy 120.929862 -264.285415) (xy 120.960388 -264.327431) (xy 120.983966 -264.373705) (xy 121.000014 -264.423098)
			(xy 121.008139 -264.474393) (xy 121.008648 -264.50036) (xy 121.008139 -264.526327) (xy 121.288049 -264.526327)
			(xy 121.288049 -264.474393) (xy 121.296174 -264.423098) (xy 121.312222 -264.373705) (xy 121.3358 -264.327431)
			(xy 121.366326 -264.285415) (xy 121.403049 -264.248692) (xy 121.445065 -264.218166) (xy 121.491339 -264.194588)
			(xy 121.540732 -264.17854) (xy 121.592027 -264.170415) (xy 121.643961 -264.170415) (xy 121.695256 -264.17854)
			(xy 121.744649 -264.194588) (xy 121.790923 -264.218166) (xy 121.832939 -264.248692) (xy 121.869662 -264.285415)
			(xy 121.900188 -264.327431) (xy 121.923766 -264.373705) (xy 121.939814 -264.423098) (xy 121.947939 -264.474393)
			(xy 121.948448 -264.50036) (xy 121.947939 -264.526327) (xy 122.227849 -264.526327) (xy 122.227849 -264.474393)
			(xy 122.235974 -264.423098) (xy 122.252022 -264.373705) (xy 122.2756 -264.327431) (xy 122.306126 -264.285415)
			(xy 122.342849 -264.248692) (xy 122.384865 -264.218166) (xy 122.431139 -264.194588) (xy 122.480532 -264.17854)
			(xy 122.531827 -264.170415) (xy 122.583761 -264.170415) (xy 122.635056 -264.17854) (xy 122.684449 -264.194588)
			(xy 122.730723 -264.218166) (xy 122.772739 -264.248692) (xy 122.809462 -264.285415) (xy 122.839988 -264.327431)
			(xy 122.863566 -264.373705) (xy 122.879614 -264.423098) (xy 122.887739 -264.474393) (xy 122.888248 -264.50036)
			(xy 122.887739 -264.526327) (xy 123.167649 -264.526327) (xy 123.167649 -264.474393) (xy 123.175774 -264.423098)
			(xy 123.191822 -264.373705) (xy 123.2154 -264.327431) (xy 123.245926 -264.285415) (xy 123.282649 -264.248692)
			(xy 123.324665 -264.218166) (xy 123.370939 -264.194588) (xy 123.420332 -264.17854) (xy 123.471627 -264.170415)
			(xy 123.523561 -264.170415) (xy 123.574856 -264.17854) (xy 123.624249 -264.194588) (xy 123.670523 -264.218166)
			(xy 123.712539 -264.248692) (xy 123.749262 -264.285415) (xy 123.779788 -264.327431) (xy 123.803366 -264.373705)
			(xy 123.819414 -264.423098) (xy 123.827539 -264.474393) (xy 123.828048 -264.50036) (xy 123.827539 -264.526327)
			(xy 124.107449 -264.526327) (xy 124.107449 -264.474393) (xy 124.115574 -264.423098) (xy 124.131622 -264.373705)
			(xy 124.1552 -264.327431) (xy 124.185726 -264.285415) (xy 124.222449 -264.248692) (xy 124.264465 -264.218166)
			(xy 124.310739 -264.194588) (xy 124.360132 -264.17854) (xy 124.411427 -264.170415) (xy 124.463361 -264.170415)
			(xy 124.514656 -264.17854) (xy 124.564049 -264.194588) (xy 124.610323 -264.218166) (xy 124.652339 -264.248692)
			(xy 124.689062 -264.285415) (xy 124.719588 -264.327431) (xy 124.743166 -264.373705) (xy 124.759214 -264.423098)
			(xy 124.767339 -264.474393) (xy 124.767848 -264.50036) (xy 124.767339 -264.526327) (xy 124.759214 -264.577622)
			(xy 124.743166 -264.627015) (xy 124.719588 -264.673289) (xy 124.689062 -264.715305) (xy 124.652339 -264.752028)
			(xy 124.610323 -264.782554) (xy 124.564049 -264.806132) (xy 124.514656 -264.82218) (xy 124.463361 -264.830305)
			(xy 124.411427 -264.830305) (xy 124.360132 -264.82218) (xy 124.310739 -264.806132) (xy 124.264465 -264.782554)
			(xy 124.222449 -264.752028) (xy 124.185726 -264.715305) (xy 124.1552 -264.673289) (xy 124.131622 -264.627015)
			(xy 124.115574 -264.577622) (xy 124.107449 -264.526327) (xy 123.827539 -264.526327) (xy 123.819414 -264.577622)
			(xy 123.803366 -264.627015) (xy 123.779788 -264.673289) (xy 123.749262 -264.715305) (xy 123.712539 -264.752028)
			(xy 123.670523 -264.782554) (xy 123.624249 -264.806132) (xy 123.574856 -264.82218) (xy 123.523561 -264.830305)
			(xy 123.471627 -264.830305) (xy 123.420332 -264.82218) (xy 123.370939 -264.806132) (xy 123.324665 -264.782554)
			(xy 123.282649 -264.752028) (xy 123.245926 -264.715305) (xy 123.2154 -264.673289) (xy 123.191822 -264.627015)
			(xy 123.175774 -264.577622) (xy 123.167649 -264.526327) (xy 122.887739 -264.526327) (xy 122.879614 -264.577622)
			(xy 122.863566 -264.627015) (xy 122.839988 -264.673289) (xy 122.809462 -264.715305) (xy 122.772739 -264.752028)
			(xy 122.730723 -264.782554) (xy 122.684449 -264.806132) (xy 122.635056 -264.82218) (xy 122.583761 -264.830305)
			(xy 122.531827 -264.830305) (xy 122.480532 -264.82218) (xy 122.431139 -264.806132) (xy 122.384865 -264.782554)
			(xy 122.342849 -264.752028) (xy 122.306126 -264.715305) (xy 122.2756 -264.673289) (xy 122.252022 -264.627015)
			(xy 122.235974 -264.577622) (xy 122.227849 -264.526327) (xy 121.947939 -264.526327) (xy 121.939814 -264.577622)
			(xy 121.923766 -264.627015) (xy 121.900188 -264.673289) (xy 121.869662 -264.715305) (xy 121.832939 -264.752028)
			(xy 121.790923 -264.782554) (xy 121.744649 -264.806132) (xy 121.695256 -264.82218) (xy 121.643961 -264.830305)
			(xy 121.592027 -264.830305) (xy 121.540732 -264.82218) (xy 121.491339 -264.806132) (xy 121.445065 -264.782554)
			(xy 121.403049 -264.752028) (xy 121.366326 -264.715305) (xy 121.3358 -264.673289) (xy 121.312222 -264.627015)
			(xy 121.296174 -264.577622) (xy 121.288049 -264.526327) (xy 121.008139 -264.526327) (xy 121.000014 -264.577622)
			(xy 120.983966 -264.627015) (xy 120.960388 -264.673289) (xy 120.929862 -264.715305) (xy 120.893139 -264.752028)
			(xy 120.851123 -264.782554) (xy 120.804849 -264.806132) (xy 120.755456 -264.82218) (xy 120.704161 -264.830305)
			(xy 120.652227 -264.830305) (xy 120.600932 -264.82218) (xy 120.551539 -264.806132) (xy 120.505265 -264.782554)
			(xy 120.463249 -264.752028) (xy 120.426526 -264.715305) (xy 120.396 -264.673289) (xy 120.372422 -264.627015)
			(xy 120.356374 -264.577622) (xy 120.348249 -264.526327) (xy 120.068339 -264.526327) (xy 120.060214 -264.577622)
			(xy 120.044166 -264.627015) (xy 120.020588 -264.673289) (xy 119.990062 -264.715305) (xy 119.953339 -264.752028)
			(xy 119.911323 -264.782554) (xy 119.865049 -264.806132) (xy 119.815656 -264.82218) (xy 119.764361 -264.830305)
			(xy 119.712427 -264.830305) (xy 119.661132 -264.82218) (xy 119.611739 -264.806132) (xy 119.565465 -264.782554)
			(xy 119.523449 -264.752028) (xy 119.486726 -264.715305) (xy 119.4562 -264.673289) (xy 119.432622 -264.627015)
			(xy 119.416574 -264.577622) (xy 119.408449 -264.526327) (xy 119.128568 -264.526327) (xy 119.128568 -264.526331)
			(xy 119.120448 -264.577635) (xy 119.104402 -264.627036) (xy 119.080824 -264.673319) (xy 119.050296 -264.715343)
			(xy 119.013569 -264.752074) (xy 118.971548 -264.782606) (xy 118.925268 -264.806189) (xy 118.875868 -264.82224)
			(xy 118.824565 -264.830365) (xy 118.798594 -264.830814) (xy 118.770449 -264.830247) (xy 118.71497 -264.820718)
			(xy 118.661905 -264.801935) (xy 118.612786 -264.774441) (xy 118.590568 -264.757154) (xy 118.555008 -264.728198)
			(xy 118.434612 -264.848594) (xy 118.425028 -264.858861) (xy 118.411392 -264.883403) (xy 118.404948 -264.91073)
			(xy 118.406183 -264.938778) (xy 118.415004 -264.965433) (xy 118.430745 -264.988681) (xy 118.452218 -265.006769)
			(xy 118.464838 -265.012932) (xy 118.489279 -265.024596) (xy 118.534309 -265.054673) (xy 118.573838 -265.091685)
			(xy 118.606809 -265.134642) (xy 118.632342 -265.182397) (xy 118.649754 -265.233673) (xy 118.658579 -265.2871)
			(xy 118.659148 -265.314176) (xy 118.658665 -265.339508) (xy 118.658567 -265.340143) (xy 118.938803 -265.340143)
			(xy 118.938803 -265.288209) (xy 118.946928 -265.236914) (xy 118.962976 -265.187521) (xy 118.986554 -265.141247)
			(xy 119.01708 -265.099231) (xy 119.053803 -265.062508) (xy 119.095819 -265.031982) (xy 119.142093 -265.008404)
			(xy 119.191486 -264.992356) (xy 119.242781 -264.984231) (xy 119.294715 -264.984231) (xy 119.34601 -264.992356)
			(xy 119.395403 -265.008404) (xy 119.441677 -265.031982) (xy 119.483693 -265.062508) (xy 119.520416 -265.099231)
			(xy 119.550942 -265.141247) (xy 119.57452 -265.187521) (xy 119.590568 -265.236914) (xy 119.598693 -265.288209)
			(xy 119.599202 -265.314176) (xy 119.598693 -265.340143) (xy 119.878603 -265.340143) (xy 119.878603 -265.288209)
			(xy 119.886728 -265.236914) (xy 119.902776 -265.187521) (xy 119.926354 -265.141247) (xy 119.95688 -265.099231)
			(xy 119.993603 -265.062508) (xy 120.035619 -265.031982) (xy 120.081893 -265.008404) (xy 120.131286 -264.992356)
			(xy 120.182581 -264.984231) (xy 120.234515 -264.984231) (xy 120.28581 -264.992356) (xy 120.335203 -265.008404)
			(xy 120.381477 -265.031982) (xy 120.423493 -265.062508) (xy 120.460216 -265.099231) (xy 120.490742 -265.141247)
			(xy 120.51432 -265.187521) (xy 120.530368 -265.236914) (xy 120.538493 -265.288209) (xy 120.539002 -265.314176)
			(xy 120.538493 -265.340143) (xy 121.758203 -265.340143) (xy 121.758203 -265.288209) (xy 121.766328 -265.236914)
			(xy 121.782376 -265.187521) (xy 121.805954 -265.141247) (xy 121.83648 -265.099231) (xy 121.873203 -265.062508)
			(xy 121.915219 -265.031982) (xy 121.961493 -265.008404) (xy 122.010886 -264.992356) (xy 122.062181 -264.984231)
			(xy 122.114115 -264.984231) (xy 122.16541 -264.992356) (xy 122.214803 -265.008404) (xy 122.261077 -265.031982)
			(xy 122.303093 -265.062508) (xy 122.339816 -265.099231) (xy 122.370342 -265.141247) (xy 122.39392 -265.187521)
			(xy 122.409968 -265.236914) (xy 122.418093 -265.288209) (xy 122.418602 -265.314176) (xy 122.418093 -265.340143)
			(xy 122.698003 -265.340143) (xy 122.698003 -265.288209) (xy 122.706128 -265.236914) (xy 122.722176 -265.187521)
			(xy 122.745754 -265.141247) (xy 122.77628 -265.099231) (xy 122.813003 -265.062508) (xy 122.855019 -265.031982)
			(xy 122.901293 -265.008404) (xy 122.950686 -264.992356) (xy 123.001981 -264.984231) (xy 123.053915 -264.984231)
			(xy 123.10521 -264.992356) (xy 123.154603 -265.008404) (xy 123.200877 -265.031982) (xy 123.242893 -265.062508)
			(xy 123.279616 -265.099231) (xy 123.310142 -265.141247) (xy 123.33372 -265.187521) (xy 123.349768 -265.236914)
			(xy 123.357893 -265.288209) (xy 123.358402 -265.314176) (xy 123.357893 -265.340143) (xy 123.637803 -265.340143)
			(xy 123.637803 -265.288209) (xy 123.645928 -265.236914) (xy 123.661976 -265.187521) (xy 123.685554 -265.141247)
			(xy 123.71608 -265.099231) (xy 123.752803 -265.062508) (xy 123.794819 -265.031982) (xy 123.841093 -265.008404)
			(xy 123.890486 -264.992356) (xy 123.941781 -264.984231) (xy 123.993715 -264.984231) (xy 124.04501 -264.992356)
			(xy 124.094403 -265.008404) (xy 124.140677 -265.031982) (xy 124.182693 -265.062508) (xy 124.219416 -265.099231)
			(xy 124.249942 -265.141247) (xy 124.27352 -265.187521) (xy 124.289568 -265.236914) (xy 124.297693 -265.288209)
			(xy 124.298202 -265.314176) (xy 124.297693 -265.340143) (xy 124.289568 -265.391438) (xy 124.27352 -265.440831)
			(xy 124.249942 -265.487105) (xy 124.219416 -265.529121) (xy 124.182693 -265.565844) (xy 124.140677 -265.59637)
			(xy 124.094403 -265.619948) (xy 124.04501 -265.635996) (xy 123.993715 -265.644121) (xy 123.941781 -265.644121)
			(xy 123.890486 -265.635996) (xy 123.841093 -265.619948) (xy 123.794819 -265.59637) (xy 123.752803 -265.565844)
			(xy 123.71608 -265.529121) (xy 123.685554 -265.487105) (xy 123.661976 -265.440831) (xy 123.645928 -265.391438)
			(xy 123.637803 -265.340143) (xy 123.357893 -265.340143) (xy 123.349768 -265.391438) (xy 123.33372 -265.440831)
			(xy 123.310142 -265.487105) (xy 123.279616 -265.529121) (xy 123.242893 -265.565844) (xy 123.200877 -265.59637)
			(xy 123.154603 -265.619948) (xy 123.10521 -265.635996) (xy 123.053915 -265.644121) (xy 123.001981 -265.644121)
			(xy 122.950686 -265.635996) (xy 122.901293 -265.619948) (xy 122.855019 -265.59637) (xy 122.813003 -265.565844)
			(xy 122.77628 -265.529121) (xy 122.745754 -265.487105) (xy 122.722176 -265.440831) (xy 122.706128 -265.391438)
			(xy 122.698003 -265.340143) (xy 122.418093 -265.340143) (xy 122.409968 -265.391438) (xy 122.39392 -265.440831)
			(xy 122.370342 -265.487105) (xy 122.339816 -265.529121) (xy 122.303093 -265.565844) (xy 122.261077 -265.59637)
			(xy 122.214803 -265.619948) (xy 122.16541 -265.635996) (xy 122.114115 -265.644121) (xy 122.062181 -265.644121)
			(xy 122.010886 -265.635996) (xy 121.961493 -265.619948) (xy 121.915219 -265.59637) (xy 121.873203 -265.565844)
			(xy 121.83648 -265.529121) (xy 121.805954 -265.487105) (xy 121.782376 -265.440831) (xy 121.766328 -265.391438)
			(xy 121.758203 -265.340143) (xy 120.538493 -265.340143) (xy 120.530368 -265.391438) (xy 120.51432 -265.440831)
			(xy 120.490742 -265.487105) (xy 120.460216 -265.529121) (xy 120.423493 -265.565844) (xy 120.381477 -265.59637)
			(xy 120.335203 -265.619948) (xy 120.28581 -265.635996) (xy 120.234515 -265.644121) (xy 120.182581 -265.644121)
			(xy 120.131286 -265.635996) (xy 120.081893 -265.619948) (xy 120.035619 -265.59637) (xy 119.993603 -265.565844)
			(xy 119.95688 -265.529121) (xy 119.926354 -265.487105) (xy 119.902776 -265.440831) (xy 119.886728 -265.391438)
			(xy 119.878603 -265.340143) (xy 119.598693 -265.340143) (xy 119.590568 -265.391438) (xy 119.57452 -265.440831)
			(xy 119.550942 -265.487105) (xy 119.520416 -265.529121) (xy 119.483693 -265.565844) (xy 119.441677 -265.59637)
			(xy 119.395403 -265.619948) (xy 119.34601 -265.635996) (xy 119.294715 -265.644121) (xy 119.242781 -265.644121)
			(xy 119.191486 -265.635996) (xy 119.142093 -265.619948) (xy 119.095819 -265.59637) (xy 119.053803 -265.565844)
			(xy 119.01708 -265.529121) (xy 118.986554 -265.487105) (xy 118.962976 -265.440831) (xy 118.946928 -265.391438)
			(xy 118.938803 -265.340143) (xy 118.658567 -265.340143) (xy 118.650935 -265.389579) (xy 118.635652 -265.437883)
			(xy 118.613176 -265.483289) (xy 118.584031 -265.524731) (xy 118.548903 -265.561239) (xy 118.508613 -265.591957)
			(xy 118.464106 -265.616164) (xy 118.416426 -265.633295) (xy 118.36669 -265.642946) (xy 118.341394 -265.644376)
			(xy 118.331658 -265.645202) (xy 118.313853 -265.653211) (xy 118.300334 -265.667296) (xy 118.293062 -265.685414)
			(xy 118.292626 -265.695176) (xy 118.292626 -266.154467) (xy 118.468649 -266.154467) (xy 118.468649 -266.102533)
			(xy 118.476774 -266.051238) (xy 118.492822 -266.001845) (xy 118.5164 -265.955571) (xy 118.546926 -265.913555)
			(xy 118.583649 -265.876832) (xy 118.625665 -265.846306) (xy 118.671939 -265.822728) (xy 118.721332 -265.80668)
			(xy 118.772627 -265.798555) (xy 118.824561 -265.798555) (xy 118.875856 -265.80668) (xy 118.925249 -265.822728)
			(xy 118.971523 -265.846306) (xy 119.013539 -265.876832) (xy 119.050262 -265.913555) (xy 119.080788 -265.955571)
			(xy 119.104366 -266.001845) (xy 119.120414 -266.051238) (xy 119.128539 -266.102533) (xy 119.129048 -266.1285)
			(xy 119.128544 -266.154213) (xy 119.408449 -266.154213) (xy 119.408449 -266.102279) (xy 119.416574 -266.050984)
			(xy 119.432622 -266.001591) (xy 119.4562 -265.955317) (xy 119.486726 -265.913301) (xy 119.523449 -265.876578)
			(xy 119.565465 -265.846052) (xy 119.611739 -265.822474) (xy 119.661132 -265.806426) (xy 119.712427 -265.798301)
			(xy 119.764361 -265.798301) (xy 119.815656 -265.806426) (xy 119.865049 -265.822474) (xy 119.911323 -265.846052)
			(xy 119.953339 -265.876578) (xy 119.990062 -265.913301) (xy 120.020588 -265.955317) (xy 120.044166 -266.001591)
			(xy 120.060214 -266.050984) (xy 120.068339 -266.102279) (xy 120.068848 -266.128246) (xy 120.068339 -266.154213)
			(xy 120.348249 -266.154213) (xy 120.348249 -266.102279) (xy 120.356374 -266.050984) (xy 120.372422 -266.001591)
			(xy 120.396 -265.955317) (xy 120.426526 -265.913301) (xy 120.463249 -265.876578) (xy 120.505265 -265.846052)
			(xy 120.551539 -265.822474) (xy 120.600932 -265.806426) (xy 120.652227 -265.798301) (xy 120.704161 -265.798301)
			(xy 120.755456 -265.806426) (xy 120.804849 -265.822474) (xy 120.851123 -265.846052) (xy 120.893139 -265.876578)
			(xy 120.929862 -265.913301) (xy 120.960388 -265.955317) (xy 120.983966 -266.001591) (xy 121.000014 -266.050984)
			(xy 121.008139 -266.102279) (xy 121.008648 -266.128246) (xy 121.008139 -266.154213) (xy 122.227849 -266.154213)
			(xy 122.227849 -266.102279) (xy 122.235974 -266.050984) (xy 122.252022 -266.001591) (xy 122.2756 -265.955317)
			(xy 122.306126 -265.913301) (xy 122.342849 -265.876578) (xy 122.384865 -265.846052) (xy 122.431139 -265.822474)
			(xy 122.480532 -265.806426) (xy 122.531827 -265.798301) (xy 122.583761 -265.798301) (xy 122.635056 -265.806426)
			(xy 122.684449 -265.822474) (xy 122.730723 -265.846052) (xy 122.772739 -265.876578) (xy 122.809462 -265.913301)
			(xy 122.839988 -265.955317) (xy 122.863566 -266.001591) (xy 122.879614 -266.050984) (xy 122.887739 -266.102279)
			(xy 122.888248 -266.128246) (xy 122.887739 -266.154213) (xy 123.167649 -266.154213) (xy 123.167649 -266.102279)
			(xy 123.175774 -266.050984) (xy 123.191822 -266.001591) (xy 123.2154 -265.955317) (xy 123.245926 -265.913301)
			(xy 123.282649 -265.876578) (xy 123.324665 -265.846052) (xy 123.370939 -265.822474) (xy 123.420332 -265.806426)
			(xy 123.471627 -265.798301) (xy 123.523561 -265.798301) (xy 123.574856 -265.806426) (xy 123.624249 -265.822474)
			(xy 123.670523 -265.846052) (xy 123.712539 -265.876578) (xy 123.749262 -265.913301) (xy 123.779788 -265.955317)
			(xy 123.803366 -266.001591) (xy 123.819414 -266.050984) (xy 123.827539 -266.102279) (xy 123.828048 -266.128246)
			(xy 123.827539 -266.154213) (xy 124.107449 -266.154213) (xy 124.107449 -266.102279) (xy 124.115574 -266.050984)
			(xy 124.131622 -266.001591) (xy 124.1552 -265.955317) (xy 124.185726 -265.913301) (xy 124.222449 -265.876578)
			(xy 124.264465 -265.846052) (xy 124.310739 -265.822474) (xy 124.360132 -265.806426) (xy 124.411427 -265.798301)
			(xy 124.463361 -265.798301) (xy 124.514656 -265.806426) (xy 124.564049 -265.822474) (xy 124.610323 -265.846052)
			(xy 124.652339 -265.876578) (xy 124.689062 -265.913301) (xy 124.719588 -265.955317) (xy 124.743166 -266.001591)
			(xy 124.759214 -266.050984) (xy 124.767339 -266.102279) (xy 124.767848 -266.128246) (xy 124.767339 -266.154213)
			(xy 124.759214 -266.205508) (xy 124.743166 -266.254901) (xy 124.719588 -266.301175) (xy 124.689062 -266.343191)
			(xy 124.652339 -266.379914) (xy 124.610323 -266.41044) (xy 124.564049 -266.434018) (xy 124.514656 -266.450066)
			(xy 124.463361 -266.458191) (xy 124.411427 -266.458191) (xy 124.360132 -266.450066) (xy 124.310739 -266.434018)
			(xy 124.264465 -266.41044) (xy 124.222449 -266.379914) (xy 124.185726 -266.343191) (xy 124.1552 -266.301175)
			(xy 124.131622 -266.254901) (xy 124.115574 -266.205508) (xy 124.107449 -266.154213) (xy 123.827539 -266.154213)
			(xy 123.819414 -266.205508) (xy 123.803366 -266.254901) (xy 123.779788 -266.301175) (xy 123.749262 -266.343191)
			(xy 123.712539 -266.379914) (xy 123.670523 -266.41044) (xy 123.624249 -266.434018) (xy 123.574856 -266.450066)
			(xy 123.523561 -266.458191) (xy 123.471627 -266.458191) (xy 123.420332 -266.450066) (xy 123.370939 -266.434018)
			(xy 123.324665 -266.41044) (xy 123.282649 -266.379914) (xy 123.245926 -266.343191) (xy 123.2154 -266.301175)
			(xy 123.191822 -266.254901) (xy 123.175774 -266.205508) (xy 123.167649 -266.154213) (xy 122.887739 -266.154213)
			(xy 122.879614 -266.205508) (xy 122.863566 -266.254901) (xy 122.839988 -266.301175) (xy 122.809462 -266.343191)
			(xy 122.772739 -266.379914) (xy 122.730723 -266.41044) (xy 122.684449 -266.434018) (xy 122.635056 -266.450066)
			(xy 122.583761 -266.458191) (xy 122.531827 -266.458191) (xy 122.480532 -266.450066) (xy 122.431139 -266.434018)
			(xy 122.384865 -266.41044) (xy 122.342849 -266.379914) (xy 122.306126 -266.343191) (xy 122.2756 -266.301175)
			(xy 122.252022 -266.254901) (xy 122.235974 -266.205508) (xy 122.227849 -266.154213) (xy 121.008139 -266.154213)
			(xy 121.000014 -266.205508) (xy 120.983966 -266.254901) (xy 120.960388 -266.301175) (xy 120.929862 -266.343191)
			(xy 120.893139 -266.379914) (xy 120.851123 -266.41044) (xy 120.804849 -266.434018) (xy 120.755456 -266.450066)
			(xy 120.704161 -266.458191) (xy 120.652227 -266.458191) (xy 120.600932 -266.450066) (xy 120.551539 -266.434018)
			(xy 120.505265 -266.41044) (xy 120.463249 -266.379914) (xy 120.426526 -266.343191) (xy 120.396 -266.301175)
			(xy 120.372422 -266.254901) (xy 120.356374 -266.205508) (xy 120.348249 -266.154213) (xy 120.068339 -266.154213)
			(xy 120.060214 -266.205508) (xy 120.044166 -266.254901) (xy 120.020588 -266.301175) (xy 119.990062 -266.343191)
			(xy 119.953339 -266.379914) (xy 119.911323 -266.41044) (xy 119.865049 -266.434018) (xy 119.815656 -266.450066)
			(xy 119.764361 -266.458191) (xy 119.712427 -266.458191) (xy 119.661132 -266.450066) (xy 119.611739 -266.434018)
			(xy 119.565465 -266.41044) (xy 119.523449 -266.379914) (xy 119.486726 -266.343191) (xy 119.4562 -266.301175)
			(xy 119.432622 -266.254901) (xy 119.416574 -266.205508) (xy 119.408449 -266.154213) (xy 119.128544 -266.154213)
			(xy 119.128539 -266.154467) (xy 119.120414 -266.205762) (xy 119.104366 -266.255155) (xy 119.080788 -266.301429)
			(xy 119.050262 -266.343445) (xy 119.013539 -266.380168) (xy 118.971523 -266.410694) (xy 118.925249 -266.434272)
			(xy 118.875856 -266.45032) (xy 118.824561 -266.458445) (xy 118.772627 -266.458445) (xy 118.721332 -266.45032)
			(xy 118.671939 -266.434272) (xy 118.625665 -266.410694) (xy 118.583649 -266.380168) (xy 118.546926 -266.343445)
			(xy 118.5164 -266.301429) (xy 118.492822 -266.255155) (xy 118.476774 -266.205762) (xy 118.468649 -266.154467)
			(xy 118.292626 -266.154467) (xy 118.292626 -266.560808) (xy 118.293065 -266.570568) (xy 118.30035 -266.588678)
			(xy 118.313865 -266.602763) (xy 118.331659 -266.610789) (xy 118.341394 -266.611608) (xy 118.366671 -266.613087)
			(xy 118.416368 -266.622772) (xy 118.464006 -266.639926) (xy 118.508469 -266.664145) (xy 118.548717 -266.694864)
			(xy 118.583808 -266.731363) (xy 118.612921 -266.772789) (xy 118.635373 -266.81817) (xy 118.65064 -266.866445)
			(xy 118.658364 -266.916484) (xy 118.658364 -266.967116) (xy 118.658262 -266.967775) (xy 121.758203 -266.967775)
			(xy 121.758203 -266.915841) (xy 121.766328 -266.864546) (xy 121.782376 -266.815153) (xy 121.805954 -266.768879)
			(xy 121.83648 -266.726863) (xy 121.873203 -266.69014) (xy 121.915219 -266.659614) (xy 121.961493 -266.636036)
			(xy 122.010886 -266.619988) (xy 122.062181 -266.611863) (xy 122.114115 -266.611863) (xy 122.16541 -266.619988)
			(xy 122.214803 -266.636036) (xy 122.261077 -266.659614) (xy 122.303093 -266.69014) (xy 122.339816 -266.726863)
			(xy 122.370342 -266.768879) (xy 122.39392 -266.815153) (xy 122.409968 -266.864546) (xy 122.418093 -266.915841)
			(xy 122.418602 -266.941808) (xy 122.418093 -266.967775) (xy 122.698003 -266.967775) (xy 122.698003 -266.915841)
			(xy 122.706128 -266.864546) (xy 122.722176 -266.815153) (xy 122.745754 -266.768879) (xy 122.77628 -266.726863)
			(xy 122.813003 -266.69014) (xy 122.855019 -266.659614) (xy 122.901293 -266.636036) (xy 122.950686 -266.619988)
			(xy 123.001981 -266.611863) (xy 123.053915 -266.611863) (xy 123.10521 -266.619988) (xy 123.154603 -266.636036)
			(xy 123.200877 -266.659614) (xy 123.242893 -266.69014) (xy 123.279616 -266.726863) (xy 123.310142 -266.768879)
			(xy 123.33372 -266.815153) (xy 123.349768 -266.864546) (xy 123.357893 -266.915841) (xy 123.358402 -266.941808)
			(xy 123.357893 -266.967775) (xy 123.637803 -266.967775) (xy 123.637803 -266.915841) (xy 123.645928 -266.864546)
			(xy 123.661976 -266.815153) (xy 123.685554 -266.768879) (xy 123.71608 -266.726863) (xy 123.752803 -266.69014)
			(xy 123.794819 -266.659614) (xy 123.841093 -266.636036) (xy 123.890486 -266.619988) (xy 123.941781 -266.611863)
			(xy 123.993715 -266.611863) (xy 124.04501 -266.619988) (xy 124.094403 -266.636036) (xy 124.140677 -266.659614)
			(xy 124.182693 -266.69014) (xy 124.219416 -266.726863) (xy 124.249942 -266.768879) (xy 124.27352 -266.815153)
			(xy 124.289568 -266.864546) (xy 124.297693 -266.915841) (xy 124.298202 -266.941808) (xy 124.297693 -266.967775)
			(xy 124.289568 -267.01907) (xy 124.27352 -267.068463) (xy 124.249942 -267.114737) (xy 124.219416 -267.156753)
			(xy 124.182693 -267.193476) (xy 124.140677 -267.224002) (xy 124.094403 -267.24758) (xy 124.04501 -267.263628)
			(xy 123.993715 -267.271753) (xy 123.941781 -267.271753) (xy 123.890486 -267.263628) (xy 123.841093 -267.24758)
			(xy 123.794819 -267.224002) (xy 123.752803 -267.193476) (xy 123.71608 -267.156753) (xy 123.685554 -267.114737)
			(xy 123.661976 -267.068463) (xy 123.645928 -267.01907) (xy 123.637803 -266.967775) (xy 123.357893 -266.967775)
			(xy 123.349768 -267.01907) (xy 123.33372 -267.068463) (xy 123.310142 -267.114737) (xy 123.279616 -267.156753)
			(xy 123.242893 -267.193476) (xy 123.200877 -267.224002) (xy 123.154603 -267.24758) (xy 123.10521 -267.263628)
			(xy 123.053915 -267.271753) (xy 123.001981 -267.271753) (xy 122.950686 -267.263628) (xy 122.901293 -267.24758)
			(xy 122.855019 -267.224002) (xy 122.813003 -267.193476) (xy 122.77628 -267.156753) (xy 122.745754 -267.114737)
			(xy 122.722176 -267.068463) (xy 122.706128 -267.01907) (xy 122.698003 -266.967775) (xy 122.418093 -266.967775)
			(xy 122.409968 -267.01907) (xy 122.39392 -267.068463) (xy 122.370342 -267.114737) (xy 122.339816 -267.156753)
			(xy 122.303093 -267.193476) (xy 122.261077 -267.224002) (xy 122.214803 -267.24758) (xy 122.16541 -267.263628)
			(xy 122.114115 -267.271753) (xy 122.062181 -267.271753) (xy 122.010886 -267.263628) (xy 121.961493 -267.24758)
			(xy 121.915219 -267.224002) (xy 121.873203 -267.193476) (xy 121.83648 -267.156753) (xy 121.805954 -267.114737)
			(xy 121.782376 -267.068463) (xy 121.766328 -267.01907) (xy 121.758203 -266.967775) (xy 118.658262 -266.967775)
			(xy 118.65064 -267.017155) (xy 118.635373 -267.065431) (xy 118.612921 -267.110812) (xy 118.583808 -267.152237)
			(xy 118.548717 -267.188736) (xy 118.508469 -267.219455) (xy 118.464005 -267.243675) (xy 118.416367 -267.260828)
			(xy 118.366671 -267.270513) (xy 118.341394 -267.272008) (xy 118.33166 -267.272835) (xy 118.313861 -267.280845)
			(xy 118.300351 -267.294931) (xy 118.293089 -267.313048) (xy 118.292626 -267.322808) (xy 118.292626 -267.781845)
			(xy 119.408449 -267.781845) (xy 119.408449 -267.729911) (xy 119.416574 -267.678616) (xy 119.432622 -267.629223)
			(xy 119.4562 -267.582949) (xy 119.486726 -267.540933) (xy 119.523449 -267.50421) (xy 119.565465 -267.473684)
			(xy 119.611739 -267.450106) (xy 119.661132 -267.434058) (xy 119.712427 -267.425933) (xy 119.764361 -267.425933)
			(xy 119.815656 -267.434058) (xy 119.865049 -267.450106) (xy 119.911323 -267.473684) (xy 119.953339 -267.50421)
			(xy 119.990062 -267.540933) (xy 120.020588 -267.582949) (xy 120.044166 -267.629223) (xy 120.060214 -267.678616)
			(xy 120.068339 -267.729911) (xy 120.068848 -267.755878) (xy 120.068339 -267.781845) (xy 123.167649 -267.781845)
			(xy 123.167649 -267.729911) (xy 123.175774 -267.678616) (xy 123.191822 -267.629223) (xy 123.2154 -267.582949)
			(xy 123.245926 -267.540933) (xy 123.282649 -267.50421) (xy 123.324665 -267.473684) (xy 123.370939 -267.450106)
			(xy 123.420332 -267.434058) (xy 123.471627 -267.425933) (xy 123.523561 -267.425933) (xy 123.574856 -267.434058)
			(xy 123.624249 -267.450106) (xy 123.670523 -267.473684) (xy 123.712539 -267.50421) (xy 123.749262 -267.540933)
			(xy 123.779788 -267.582949) (xy 123.803366 -267.629223) (xy 123.819414 -267.678616) (xy 123.827539 -267.729911)
			(xy 123.828048 -267.755878) (xy 123.827539 -267.781845) (xy 124.107449 -267.781845) (xy 124.107449 -267.729911)
			(xy 124.115574 -267.678616) (xy 124.131622 -267.629223) (xy 124.1552 -267.582949) (xy 124.185726 -267.540933)
			(xy 124.222449 -267.50421) (xy 124.264465 -267.473684) (xy 124.310739 -267.450106) (xy 124.360132 -267.434058)
			(xy 124.411427 -267.425933) (xy 124.463361 -267.425933) (xy 124.514656 -267.434058) (xy 124.564049 -267.450106)
			(xy 124.610323 -267.473684) (xy 124.652339 -267.50421) (xy 124.689062 -267.540933) (xy 124.719588 -267.582949)
			(xy 124.743166 -267.629223) (xy 124.759214 -267.678616) (xy 124.767339 -267.729911) (xy 124.767848 -267.755878)
			(xy 124.767339 -267.781845) (xy 124.759214 -267.83314) (xy 124.743166 -267.882533) (xy 124.719588 -267.928807)
			(xy 124.689062 -267.970823) (xy 124.652339 -268.007546) (xy 124.610323 -268.038072) (xy 124.564049 -268.06165)
			(xy 124.514656 -268.077698) (xy 124.463361 -268.085823) (xy 124.411427 -268.085823) (xy 124.360132 -268.077698)
			(xy 124.310739 -268.06165) (xy 124.264465 -268.038072) (xy 124.222449 -268.007546) (xy 124.185726 -267.970823)
			(xy 124.1552 -267.928807) (xy 124.131622 -267.882533) (xy 124.115574 -267.83314) (xy 124.107449 -267.781845)
			(xy 123.827539 -267.781845) (xy 123.819414 -267.83314) (xy 123.803366 -267.882533) (xy 123.779788 -267.928807)
			(xy 123.749262 -267.970823) (xy 123.712539 -268.007546) (xy 123.670523 -268.038072) (xy 123.624249 -268.06165)
			(xy 123.574856 -268.077698) (xy 123.523561 -268.085823) (xy 123.471627 -268.085823) (xy 123.420332 -268.077698)
			(xy 123.370939 -268.06165) (xy 123.324665 -268.038072) (xy 123.282649 -268.007546) (xy 123.245926 -267.970823)
			(xy 123.2154 -267.928807) (xy 123.191822 -267.882533) (xy 123.175774 -267.83314) (xy 123.167649 -267.781845)
			(xy 120.068339 -267.781845) (xy 120.060214 -267.83314) (xy 120.044166 -267.882533) (xy 120.020588 -267.928807)
			(xy 119.990062 -267.970823) (xy 119.953339 -268.007546) (xy 119.911323 -268.038072) (xy 119.865049 -268.06165)
			(xy 119.815656 -268.077698) (xy 119.764361 -268.085823) (xy 119.712427 -268.085823) (xy 119.661132 -268.077698)
			(xy 119.611739 -268.06165) (xy 119.565465 -268.038072) (xy 119.523449 -268.007546) (xy 119.486726 -267.970823)
			(xy 119.4562 -267.928807) (xy 119.432622 -267.882533) (xy 119.416574 -267.83314) (xy 119.408449 -267.781845)
			(xy 118.292626 -267.781845) (xy 118.292626 -268.188694) (xy 118.293062 -268.198456) (xy 118.300345 -268.216571)
			(xy 118.313861 -268.23066) (xy 118.331657 -268.238689) (xy 118.341394 -268.239494) (xy 118.366701 -268.240913)
			(xy 118.416463 -268.25054) (xy 118.464171 -268.267654) (xy 118.508706 -268.291852) (xy 118.549025 -268.322566)
			(xy 118.58418 -268.359077) (xy 118.613348 -268.400527) (xy 118.635845 -268.445946) (xy 118.651142 -268.494267)
			(xy 118.658882 -268.544357) (xy 118.658882 -268.595042) (xy 118.658786 -268.595661) (xy 122.697749 -268.595661)
			(xy 122.697749 -268.543727) (xy 122.705874 -268.492432) (xy 122.721922 -268.443039) (xy 122.7455 -268.396765)
			(xy 122.776026 -268.354749) (xy 122.812749 -268.318026) (xy 122.854765 -268.2875) (xy 122.901039 -268.263922)
			(xy 122.950432 -268.247874) (xy 123.001727 -268.239749) (xy 123.053661 -268.239749) (xy 123.104956 -268.247874)
			(xy 123.154349 -268.263922) (xy 123.200623 -268.2875) (xy 123.242639 -268.318026) (xy 123.279362 -268.354749)
			(xy 123.309888 -268.396765) (xy 123.333466 -268.443039) (xy 123.349514 -268.492432) (xy 123.357639 -268.543727)
			(xy 123.358148 -268.569694) (xy 123.357639 -268.595661) (xy 123.637803 -268.595661) (xy 123.637803 -268.543727)
			(xy 123.645928 -268.492432) (xy 123.661976 -268.443039) (xy 123.685554 -268.396765) (xy 123.71608 -268.354749)
			(xy 123.752803 -268.318026) (xy 123.794819 -268.2875) (xy 123.841093 -268.263922) (xy 123.890486 -268.247874)
			(xy 123.941781 -268.239749) (xy 123.993715 -268.239749) (xy 124.04501 -268.247874) (xy 124.094403 -268.263922)
			(xy 124.140677 -268.2875) (xy 124.182693 -268.318026) (xy 124.219416 -268.354749) (xy 124.249942 -268.396765)
			(xy 124.27352 -268.443039) (xy 124.289568 -268.492432) (xy 124.297693 -268.543727) (xy 124.298202 -268.569694)
			(xy 124.297693 -268.595661) (xy 124.289568 -268.646956) (xy 124.27352 -268.696349) (xy 124.249942 -268.742623)
			(xy 124.219416 -268.784639) (xy 124.182693 -268.821362) (xy 124.140677 -268.851888) (xy 124.094403 -268.875466)
			(xy 124.04501 -268.891514) (xy 123.993715 -268.899639) (xy 123.941781 -268.899639) (xy 123.890486 -268.891514)
			(xy 123.841093 -268.875466) (xy 123.794819 -268.851888) (xy 123.752803 -268.821362) (xy 123.71608 -268.784639)
			(xy 123.685554 -268.742623) (xy 123.661976 -268.696349) (xy 123.645928 -268.646956) (xy 123.637803 -268.595661)
			(xy 123.357639 -268.595661) (xy 123.349514 -268.646956) (xy 123.333466 -268.696349) (xy 123.309888 -268.742623)
			(xy 123.279362 -268.784639) (xy 123.242639 -268.821362) (xy 123.200623 -268.851888) (xy 123.154349 -268.875466)
			(xy 123.104956 -268.891514) (xy 123.053661 -268.899639) (xy 123.001727 -268.899639) (xy 122.950432 -268.891514)
			(xy 122.901039 -268.875466) (xy 122.854765 -268.851888) (xy 122.812749 -268.821362) (xy 122.776026 -268.784639)
			(xy 122.7455 -268.742623) (xy 122.721922 -268.696349) (xy 122.705874 -268.646956) (xy 122.697749 -268.595661)
			(xy 118.658786 -268.595661) (xy 118.651142 -268.645132) (xy 118.635845 -268.693454) (xy 118.613348 -268.738872)
			(xy 118.58418 -268.780323) (xy 118.549025 -268.816834) (xy 118.508707 -268.847548) (xy 118.464171 -268.871746)
			(xy 118.416463 -268.888859) (xy 118.366701 -268.898487) (xy 118.341394 -268.899894) (xy 118.331659 -268.900721)
			(xy 118.313858 -268.90873) (xy 118.300344 -268.922816) (xy 118.293077 -268.940933) (xy 118.292626 -268.950694)
			(xy 118.292626 -269.409477) (xy 120.348249 -269.409477) (xy 120.348249 -269.357543) (xy 120.356374 -269.306248)
			(xy 120.372422 -269.256855) (xy 120.396 -269.210581) (xy 120.426526 -269.168565) (xy 120.463249 -269.131842)
			(xy 120.505265 -269.101316) (xy 120.551539 -269.077738) (xy 120.600932 -269.06169) (xy 120.652227 -269.053565)
			(xy 120.704161 -269.053565) (xy 120.755456 -269.06169) (xy 120.804849 -269.077738) (xy 120.851123 -269.101316)
			(xy 120.893139 -269.131842) (xy 120.929862 -269.168565) (xy 120.960388 -269.210581) (xy 120.983966 -269.256855)
			(xy 121.000014 -269.306248) (xy 121.008139 -269.357543) (xy 121.008648 -269.38351) (xy 121.008139 -269.409477)
			(xy 122.227849 -269.409477) (xy 122.227849 -269.357543) (xy 122.235974 -269.306248) (xy 122.252022 -269.256855)
			(xy 122.2756 -269.210581) (xy 122.306126 -269.168565) (xy 122.342849 -269.131842) (xy 122.384865 -269.101316)
			(xy 122.431139 -269.077738) (xy 122.480532 -269.06169) (xy 122.531827 -269.053565) (xy 122.583761 -269.053565)
			(xy 122.635056 -269.06169) (xy 122.684449 -269.077738) (xy 122.730723 -269.101316) (xy 122.772739 -269.131842)
			(xy 122.809462 -269.168565) (xy 122.839988 -269.210581) (xy 122.863566 -269.256855) (xy 122.879614 -269.306248)
			(xy 122.887739 -269.357543) (xy 122.888248 -269.38351) (xy 122.887739 -269.409477) (xy 123.167649 -269.409477)
			(xy 123.167649 -269.357543) (xy 123.175774 -269.306248) (xy 123.191822 -269.256855) (xy 123.2154 -269.210581)
			(xy 123.245926 -269.168565) (xy 123.282649 -269.131842) (xy 123.324665 -269.101316) (xy 123.370939 -269.077738)
			(xy 123.420332 -269.06169) (xy 123.471627 -269.053565) (xy 123.523561 -269.053565) (xy 123.574856 -269.06169)
			(xy 123.624249 -269.077738) (xy 123.670523 -269.101316) (xy 123.712539 -269.131842) (xy 123.749262 -269.168565)
			(xy 123.779788 -269.210581) (xy 123.803366 -269.256855) (xy 123.819414 -269.306248) (xy 123.827539 -269.357543)
			(xy 123.828048 -269.38351) (xy 123.827539 -269.409477) (xy 124.107449 -269.409477) (xy 124.107449 -269.357543)
			(xy 124.115574 -269.306248) (xy 124.131622 -269.256855) (xy 124.1552 -269.210581) (xy 124.185726 -269.168565)
			(xy 124.222449 -269.131842) (xy 124.264465 -269.101316) (xy 124.310739 -269.077738) (xy 124.360132 -269.06169)
			(xy 124.411427 -269.053565) (xy 124.463361 -269.053565) (xy 124.514656 -269.06169) (xy 124.564049 -269.077738)
			(xy 124.610323 -269.101316) (xy 124.652339 -269.131842) (xy 124.689062 -269.168565) (xy 124.719588 -269.210581)
			(xy 124.743166 -269.256855) (xy 124.759214 -269.306248) (xy 124.767339 -269.357543) (xy 124.767848 -269.38351)
			(xy 124.767339 -269.409477) (xy 124.759214 -269.460772) (xy 124.743166 -269.510165) (xy 124.719588 -269.556439)
			(xy 124.689062 -269.598455) (xy 124.652339 -269.635178) (xy 124.610323 -269.665704) (xy 124.564049 -269.689282)
			(xy 124.514656 -269.70533) (xy 124.463361 -269.713455) (xy 124.411427 -269.713455) (xy 124.360132 -269.70533)
			(xy 124.310739 -269.689282) (xy 124.264465 -269.665704) (xy 124.222449 -269.635178) (xy 124.185726 -269.598455)
			(xy 124.1552 -269.556439) (xy 124.131622 -269.510165) (xy 124.115574 -269.460772) (xy 124.107449 -269.409477)
			(xy 123.827539 -269.409477) (xy 123.819414 -269.460772) (xy 123.803366 -269.510165) (xy 123.779788 -269.556439)
			(xy 123.749262 -269.598455) (xy 123.712539 -269.635178) (xy 123.670523 -269.665704) (xy 123.624249 -269.689282)
			(xy 123.574856 -269.70533) (xy 123.523561 -269.713455) (xy 123.471627 -269.713455) (xy 123.420332 -269.70533)
			(xy 123.370939 -269.689282) (xy 123.324665 -269.665704) (xy 123.282649 -269.635178) (xy 123.245926 -269.598455)
			(xy 123.2154 -269.556439) (xy 123.191822 -269.510165) (xy 123.175774 -269.460772) (xy 123.167649 -269.409477)
			(xy 122.887739 -269.409477) (xy 122.879614 -269.460772) (xy 122.863566 -269.510165) (xy 122.839988 -269.556439)
			(xy 122.809462 -269.598455) (xy 122.772739 -269.635178) (xy 122.730723 -269.665704) (xy 122.684449 -269.689282)
			(xy 122.635056 -269.70533) (xy 122.583761 -269.713455) (xy 122.531827 -269.713455) (xy 122.480532 -269.70533)
			(xy 122.431139 -269.689282) (xy 122.384865 -269.665704) (xy 122.342849 -269.635178) (xy 122.306126 -269.598455)
			(xy 122.2756 -269.556439) (xy 122.252022 -269.510165) (xy 122.235974 -269.460772) (xy 122.227849 -269.409477)
			(xy 121.008139 -269.409477) (xy 121.000014 -269.460772) (xy 120.983966 -269.510165) (xy 120.960388 -269.556439)
			(xy 120.929862 -269.598455) (xy 120.893139 -269.635178) (xy 120.851123 -269.665704) (xy 120.804849 -269.689282)
			(xy 120.755456 -269.70533) (xy 120.704161 -269.713455) (xy 120.652227 -269.713455) (xy 120.600932 -269.70533)
			(xy 120.551539 -269.689282) (xy 120.505265 -269.665704) (xy 120.463249 -269.635178) (xy 120.426526 -269.598455)
			(xy 120.396 -269.556439) (xy 120.372422 -269.510165) (xy 120.356374 -269.460772) (xy 120.348249 -269.409477)
			(xy 118.292626 -269.409477) (xy 118.292626 -269.81658) (xy 118.29306 -269.826344) (xy 118.30034 -269.844463)
			(xy 118.313856 -269.858557) (xy 118.331655 -269.866588) (xy 118.341394 -269.86738) (xy 118.366701 -269.868799)
			(xy 118.416463 -269.878426) (xy 118.464172 -269.895539) (xy 118.508708 -269.919736) (xy 118.549027 -269.950449)
			(xy 118.584184 -269.986959) (xy 118.613353 -270.028409) (xy 118.635852 -270.073827) (xy 118.651152 -270.122147)
			(xy 118.658894 -270.172238) (xy 118.659402 -270.19758) (xy 118.658899 -270.223547) (xy 122.698003 -270.223547)
			(xy 122.698003 -270.171613) (xy 122.706128 -270.120318) (xy 122.722176 -270.070925) (xy 122.745754 -270.024651)
			(xy 122.77628 -269.982635) (xy 122.813003 -269.945912) (xy 122.855019 -269.915386) (xy 122.901293 -269.891808)
			(xy 122.950686 -269.87576) (xy 123.001981 -269.867635) (xy 123.053915 -269.867635) (xy 123.10521 -269.87576)
			(xy 123.154603 -269.891808) (xy 123.200877 -269.915386) (xy 123.242893 -269.945912) (xy 123.279616 -269.982635)
			(xy 123.310142 -270.024651) (xy 123.33372 -270.070925) (xy 123.349768 -270.120318) (xy 123.357893 -270.171613)
			(xy 123.358402 -270.19758) (xy 123.357893 -270.223547) (xy 123.637803 -270.223547) (xy 123.637803 -270.171613)
			(xy 123.645928 -270.120318) (xy 123.661976 -270.070925) (xy 123.685554 -270.024651) (xy 123.71608 -269.982635)
			(xy 123.752803 -269.945912) (xy 123.794819 -269.915386) (xy 123.841093 -269.891808) (xy 123.890486 -269.87576)
			(xy 123.941781 -269.867635) (xy 123.993715 -269.867635) (xy 124.04501 -269.87576) (xy 124.094403 -269.891808)
			(xy 124.140677 -269.915386) (xy 124.182693 -269.945912) (xy 124.219416 -269.982635) (xy 124.249942 -270.024651)
			(xy 124.27352 -270.070925) (xy 124.289568 -270.120318) (xy 124.297693 -270.171613) (xy 124.298202 -270.19758)
			(xy 124.297693 -270.223547) (xy 124.289568 -270.274842) (xy 124.27352 -270.324235) (xy 124.249942 -270.370509)
			(xy 124.219416 -270.412525) (xy 124.182693 -270.449248) (xy 124.140677 -270.479774) (xy 124.094403 -270.503352)
			(xy 124.04501 -270.5194) (xy 123.993715 -270.527525) (xy 123.941781 -270.527525) (xy 123.890486 -270.5194)
			(xy 123.841093 -270.503352) (xy 123.794819 -270.479774) (xy 123.752803 -270.449248) (xy 123.71608 -270.412525)
			(xy 123.685554 -270.370509) (xy 123.661976 -270.324235) (xy 123.645928 -270.274842) (xy 123.637803 -270.223547)
			(xy 123.357893 -270.223547) (xy 123.349768 -270.274842) (xy 123.33372 -270.324235) (xy 123.310142 -270.370509)
			(xy 123.279616 -270.412525) (xy 123.242893 -270.449248) (xy 123.200877 -270.479774) (xy 123.154603 -270.503352)
			(xy 123.10521 -270.5194) (xy 123.053915 -270.527525) (xy 123.001981 -270.527525) (xy 122.950686 -270.5194)
			(xy 122.901293 -270.503352) (xy 122.855019 -270.479774) (xy 122.813003 -270.449248) (xy 122.77628 -270.412525)
			(xy 122.745754 -270.370509) (xy 122.722176 -270.324235) (xy 122.706128 -270.274842) (xy 122.698003 -270.223547)
			(xy 118.658899 -270.223547) (xy 118.658892 -270.223906) (xy 118.650545 -270.275893) (xy 118.634058 -270.325899)
			(xy 118.609849 -270.372656) (xy 118.578531 -270.414982) (xy 118.540897 -270.451806) (xy 118.497899 -270.482195)
			(xy 118.47449 -270.494252) (xy 118.46231 -270.500766) (xy 118.441719 -270.51916) (xy 118.426809 -270.542399)
			(xy 118.418673 -270.568783) (xy 118.417904 -270.596382) (xy 118.424559 -270.623179) (xy 118.438151 -270.647212)
			(xy 118.447566 -270.65732) (xy 118.564406 -270.77416) (xy 118.599712 -270.74749) (xy 118.621337 -270.731833)
			(xy 118.668582 -270.706974) (xy 118.719209 -270.690033) (xy 118.771901 -270.68145) (xy 118.798594 -270.680942)
			(xy 118.824564 -270.681424) (xy 118.875864 -270.689549) (xy 118.925261 -270.705598) (xy 118.97154 -270.729177)
			(xy 119.01356 -270.759706) (xy 119.050288 -270.796432) (xy 119.080818 -270.838451) (xy 119.104398 -270.884729)
			(xy 119.120449 -270.934126) (xy 119.128575 -270.985426) (xy 119.129048 -271.011396) (xy 119.12854 -271.029938)
			(xy 119.128216 -271.043738) (xy 119.134085 -271.070698) (xy 119.146958 -271.095102) (xy 119.165896 -271.115169)
			(xy 119.189515 -271.129431) (xy 119.216091 -271.136849) (xy 119.229886 -271.13738)
		)
		(stroke
			(width 0)
			(type solid)
		)
		(fill yes)
		(layer "In6.Cu")
		(net "PVCCINFAON_CPU1")
	)
	(gr_poly
		(pts
			(xy 349.908368 -225.83267) (xy 349.922638 -225.812294) (xy 349.956303 -225.775673) (xy 349.995076 -225.744511)
			(xy 350.038082 -225.719511) (xy 350.084348 -225.70124) (xy 350.132831 -225.69011) (xy 350.182434 -225.686371)
			(xy 350.232037 -225.69011) (xy 350.28052 -225.70124) (xy 350.326786 -225.719511) (xy 350.369792 -225.744511)
			(xy 350.408565 -225.775673) (xy 350.44223 -225.812294) (xy 350.4565 -225.83267) (xy 350.848168 -225.83267)
			(xy 350.863666 -225.81062) (xy 350.900633 -225.771405) (xy 350.943474 -225.738709) (xy 350.991053 -225.713398)
			(xy 351.042109 -225.696143) (xy 351.095288 -225.687403) (xy 351.122234 -225.686874) (xy 351.153339 -225.68759)
			(xy 351.214451 -225.69923) (xy 351.243646 -225.709988) (xy 351.274888 -225.72218) (xy 351.38868 -225.608388)
			(xy 351.398354 -225.598053) (xy 351.412107 -225.573323) (xy 351.418566 -225.545772) (xy 351.417237 -225.517506)
			(xy 351.408223 -225.490683) (xy 351.392211 -225.467351) (xy 351.381568 -225.45802) (xy 351.363117 -225.442257)
			(xy 351.330591 -225.406244) (xy 351.303685 -225.365859) (xy 351.28298 -225.321971) (xy 351.268921 -225.275525)
			(xy 351.26181 -225.227521) (xy 351.261426 -225.203258) (xy 351.261905 -225.178039) (xy 351.269576 -225.128187)
			(xy 351.284733 -225.08008) (xy 351.307024 -225.034835) (xy 351.335932 -224.993502) (xy 351.370784 -224.957043)
			(xy 351.410772 -224.926302) (xy 351.432622 -224.913698) (xy 351.459038 -224.89922) (xy 351.459038 -224.752154)
			(xy 351.458594 -224.738495) (xy 351.451346 -224.712155) (xy 351.437381 -224.688676) (xy 351.417696 -224.669734)
			(xy 351.393697 -224.656683) (xy 351.367098 -224.650454) (xy 351.339799 -224.651493) (xy 351.313751 -224.659725)
			(xy 351.302066 -224.66681) (xy 351.281893 -224.679419) (xy 351.238698 -224.699347) (xy 351.193093 -224.712882)
			(xy 351.146019 -224.719744) (xy 351.122234 -224.72015) (xy 351.096244 -224.719643) (xy 351.044903 -224.711517)
			(xy 350.995465 -224.69546) (xy 350.949148 -224.671866) (xy 350.907092 -224.641318) (xy 350.870332 -224.604566)
			(xy 350.839774 -224.562517) (xy 350.81617 -224.516205) (xy 350.800101 -224.466771) (xy 350.791963 -224.415432)
			(xy 350.791526 -224.389442) (xy 350.791999 -224.363972) (xy 350.799815 -224.313636) (xy 350.815253 -224.265093)
			(xy 350.837949 -224.219489) (xy 350.867366 -224.177902) (xy 350.902809 -224.141315) (xy 350.94344 -224.110592)
			(xy 350.9883 -224.086459) (xy 351.036329 -224.069487) (xy 351.061274 -224.064322) (xy 351.084388 -224.060004)
			(xy 351.287842 -223.707452) (xy 351.279968 -223.685608) (xy 351.271169 -223.65897) (xy 351.261726 -223.603674)
			(xy 351.261172 -223.575626) (xy 351.261648 -223.550378) (xy 351.269322 -223.500467) (xy 351.284497 -223.452305)
			(xy 351.306819 -223.407009) (xy 351.335769 -223.365635) (xy 351.370674 -223.329145) (xy 351.410722 -223.298386)
			(xy 351.432622 -223.285812) (xy 351.459038 -223.271334) (xy 351.459038 -223.124014) (xy 351.458589 -223.110359)
			(xy 351.451335 -223.084029) (xy 351.437368 -223.06056) (xy 351.417685 -223.041627) (xy 351.393692 -223.028581)
			(xy 351.3671 -223.022354) (xy 351.339809 -223.023391) (xy 351.313767 -223.031617) (xy 351.302066 -223.03867)
			(xy 351.281896 -223.051282) (xy 351.238702 -223.071209) (xy 351.193095 -223.08473) (xy 351.146019 -223.091563)
			(xy 351.122234 -223.09201) (xy 351.096266 -223.09153) (xy 351.04497 -223.08341) (xy 350.995575 -223.067365)
			(xy 350.949299 -223.043791) (xy 350.907281 -223.013267) (xy 350.870555 -222.976545) (xy 350.840027 -222.93453)
			(xy 350.816448 -222.888256) (xy 350.800398 -222.838863) (xy 350.792273 -222.787568) (xy 350.792273 -222.735632)
			(xy 350.800398 -222.684337) (xy 350.816448 -222.634944) (xy 350.840027 -222.58867) (xy 350.870555 -222.546655)
			(xy 350.907281 -222.509933) (xy 350.949299 -222.479409) (xy 350.995575 -222.455835) (xy 351.04497 -222.43979)
			(xy 351.096266 -222.43167) (xy 351.122234 -222.431102) (xy 351.146017 -222.431538) (xy 351.193088 -222.438397)
			(xy 351.238692 -222.451925) (xy 351.281888 -222.471844) (xy 351.302066 -222.484442) (xy 351.313767 -222.491512)
			(xy 351.339814 -222.499779) (xy 351.36712 -222.500841) (xy 351.393731 -222.494622) (xy 351.417739 -222.481568)
			(xy 351.437425 -222.462614) (xy 351.451378 -222.439118) (xy 351.4586 -222.412762) (xy 351.459038 -222.399098)
			(xy 351.459038 -222.251778) (xy 351.432622 -222.2373) (xy 351.41075 -222.224727) (xy 351.370755 -222.193981)
			(xy 351.335897 -222.157514) (xy 351.306986 -222.116174) (xy 351.284693 -222.07092) (xy 351.269535 -222.022804)
			(xy 351.261866 -221.972943) (xy 351.261863 -221.922496) (xy 351.269527 -221.872634) (xy 351.284678 -221.824516)
			(xy 351.306966 -221.779259) (xy 351.335873 -221.737916) (xy 351.370726 -221.701445) (xy 351.410718 -221.670694)
			(xy 351.432622 -221.65818) (xy 351.459038 -221.643702) (xy 351.459038 -221.496382) (xy 351.458585 -221.48273)
			(xy 351.451326 -221.456408) (xy 351.437358 -221.432947) (xy 351.417677 -221.414021) (xy 351.393688 -221.40098)
			(xy 351.367102 -221.394755) (xy 351.339817 -221.39579) (xy 351.31378 -221.404011) (xy 351.302066 -221.411038)
			(xy 351.281897 -221.423651) (xy 351.238703 -221.44358) (xy 351.193095 -221.457102) (xy 351.146019 -221.463936)
			(xy 351.122234 -221.464378) (xy 351.096262 -221.463898) (xy 351.044958 -221.455777) (xy 350.995555 -221.439731)
			(xy 350.949271 -221.416153) (xy 350.907245 -221.385625) (xy 350.870512 -221.348899) (xy 350.839977 -221.306879)
			(xy 350.816392 -221.260599) (xy 350.800336 -221.211199) (xy 350.792207 -221.159896) (xy 350.79178 -221.133924)
			(xy 350.792352 -221.106101) (xy 350.801669 -221.051242) (xy 350.820044 -220.998718) (xy 350.846957 -220.950014)
			(xy 350.881649 -220.906507) (xy 350.902016 -220.887544) (xy 350.912033 -220.878034) (xy 350.927004 -220.854835)
			(xy 350.935196 -220.828468) (xy 350.936008 -220.80087) (xy 350.92938 -220.774067) (xy 350.9158 -220.750028)
			(xy 350.906334 -220.73997) (xy 350.788732 -220.622368) (xy 350.759014 -220.632782) (xy 350.733112 -220.640987)
			(xy 350.6795 -220.649792) (xy 350.652334 -220.650308) (xy 350.626364 -220.649828) (xy 350.575064 -220.641707)
			(xy 350.525666 -220.625659) (xy 350.479387 -220.602081) (xy 350.437367 -220.571552) (xy 350.400641 -220.534824)
			(xy 350.370113 -220.492803) (xy 350.346536 -220.446523) (xy 350.330491 -220.397125) (xy 350.322371 -220.345824)
			(xy 350.32188 -220.319854) (xy 350.322386 -220.292687) (xy 350.33119 -220.239073) (xy 350.339406 -220.213174)
			(xy 350.34982 -220.183456) (xy 349.72752 -219.561156) (xy 349.716575 -219.550947) (xy 349.690207 -219.53682)
			(xy 349.660875 -219.530943) (xy 349.631099 -219.53382) (xy 349.603435 -219.545205) (xy 349.580259 -219.564119)
			(xy 349.563561 -219.58894) (xy 349.55861 -219.603066) (xy 349.550407 -219.628071) (xy 349.527195 -219.675297)
			(xy 349.49679 -219.718246) (xy 349.45996 -219.755832) (xy 349.417637 -219.787103) (xy 349.370892 -219.811269)
			(xy 349.320906 -219.827718) (xy 349.268945 -219.836034) (xy 349.242634 -219.836492) (xy 349.216664 -219.835985)
			(xy 349.165363 -219.827865) (xy 349.115963 -219.81182) (xy 349.069682 -219.788245) (xy 349.027658 -219.75772)
			(xy 348.990927 -219.720997) (xy 348.960393 -219.67898) (xy 348.936807 -219.632704) (xy 348.920751 -219.583308)
			(xy 348.91262 -219.532008) (xy 348.91218 -219.506038) (xy 348.912693 -219.479732) (xy 348.921033 -219.427784)
			(xy 348.937492 -219.377812) (xy 348.961656 -219.331076) (xy 348.992914 -219.288755) (xy 349.030478 -219.251917)
			(xy 349.073401 -219.221491) (xy 349.1206 -219.198245) (xy 349.145606 -219.190062) (xy 349.159734 -219.185135)
			(xy 349.18452 -219.1684) (xy 349.203406 -219.145212) (xy 349.214779 -219.117553) (xy 349.217666 -219.087786)
			(xy 349.211821 -219.058457) (xy 349.197743 -219.032071) (xy 349.187516 -219.021152) (xy 349.119698 -218.953334)
			(xy 349.108688 -218.943071) (xy 349.082149 -218.928903) (xy 349.052631 -218.923092) (xy 349.022702 -218.926143)
			(xy 348.994965 -218.937791) (xy 348.983046 -218.946984) (xy 348.960647 -218.9647) (xy 348.911025 -218.992957)
			(xy 348.857288 -219.012274) (xy 348.801032 -219.022076) (xy 348.77248 -219.022676) (xy 348.746513 -219.022165)
			(xy 348.695219 -219.014039) (xy 348.645828 -218.997988) (xy 348.599555 -218.97441) (xy 348.55754 -218.943884)
			(xy 348.520818 -218.907161) (xy 348.490291 -218.865146) (xy 348.466712 -218.818874) (xy 348.450662 -218.769483)
			(xy 348.442535 -218.718189) (xy 348.442026 -218.692222) (xy 348.442637 -218.664242) (xy 348.452086 -218.609083)
			(xy 348.460822 -218.582494) (xy 348.468442 -218.560396) (xy 348.264734 -218.20759) (xy 348.241874 -218.203272)
			(xy 348.216944 -218.198123) (xy 348.16894 -218.181185) (xy 348.124103 -218.157082) (xy 348.083495 -218.126387)
			(xy 348.048076 -218.089825) (xy 348.018686 -218.048262) (xy 347.99602 -218.002682) (xy 347.980614 -217.954165)
			(xy 347.972835 -217.903858) (xy 347.97238 -217.878406) (xy 347.972889 -217.852439) (xy 347.981014 -217.801144)
			(xy 347.997062 -217.751751) (xy 348.02064 -217.705477) (xy 348.051166 -217.663461) (xy 348.087889 -217.626738)
			(xy 348.129905 -217.596212) (xy 348.176179 -217.572634) (xy 348.225572 -217.556586) (xy 348.276867 -217.548461)
			(xy 348.328801 -217.548461) (xy 348.380096 -217.556586) (xy 348.429489 -217.572634) (xy 348.475763 -217.596212)
			(xy 348.517779 -217.626738) (xy 348.554502 -217.663461) (xy 348.585028 -217.705477) (xy 348.608606 -217.751751)
			(xy 348.624654 -217.801144) (xy 348.632779 -217.852439) (xy 348.633288 -217.878406) (xy 348.632674 -217.906386)
			(xy 348.623221 -217.961543) (xy 348.614492 -217.988134) (xy 348.606872 -218.010232) (xy 348.81058 -218.363038)
			(xy 348.83344 -218.367356) (xy 348.836488 -218.368118) (xy 348.841314 -218.36888) (xy 348.89694 -218.36888)
			(xy 348.89694 -217.495882) (xy 348.896532 -217.482089) (xy 348.889236 -217.45549) (xy 348.875075 -217.43182)
			(xy 348.855085 -217.412815) (xy 348.830732 -217.399866) (xy 348.803798 -217.393921) (xy 348.790006 -217.394282)
			(xy 348.772734 -217.39479) (xy 348.74676 -217.39431) (xy 348.695451 -217.386188) (xy 348.646045 -217.370139)
			(xy 348.599757 -217.346559) (xy 348.557729 -217.316027) (xy 348.520995 -217.279297) (xy 348.490459 -217.237272)
			(xy 348.466874 -217.190987) (xy 348.45082 -217.141582) (xy 348.442693 -217.090274) (xy 348.442693 -217.038326)
			(xy 348.45082 -216.987018) (xy 348.466874 -216.937613) (xy 348.490459 -216.891328) (xy 348.520995 -216.849303)
			(xy 348.557729 -216.812573) (xy 348.599757 -216.782041) (xy 348.646045 -216.758461) (xy 348.695451 -216.742412)
			(xy 348.74676 -216.73429) (xy 348.772734 -216.733882) (xy 348.790006 -216.73439) (xy 348.803787 -216.734652)
			(xy 348.830684 -216.728678) (xy 348.855004 -216.715731) (xy 348.874977 -216.696752) (xy 348.889149 -216.673124)
			(xy 348.896487 -216.646567) (xy 348.89694 -216.63279) (xy 348.89694 -216.57183) (xy 348.380304 -216.57183)
			(xy 348.374716 -216.5731) (xy 348.356975 -216.576789) (xy 348.320953 -216.580739) (xy 348.302834 -216.580974)
			(xy 348.284715 -216.580743) (xy 348.248692 -216.576797) (xy 348.230952 -216.5731) (xy 348.225364 -216.57183)
			(xy 347.440504 -216.57183) (xy 347.434916 -216.5731) (xy 347.417175 -216.576789) (xy 347.381153 -216.580739)
			(xy 347.363034 -216.580974) (xy 347.344915 -216.580743) (xy 347.308892 -216.576797) (xy 347.291152 -216.5731)
			(xy 347.285564 -216.57183) (xy 346.500704 -216.57183) (xy 346.495116 -216.5731) (xy 346.477375 -216.576789)
			(xy 346.441353 -216.580739) (xy 346.423234 -216.580974) (xy 346.405115 -216.580743) (xy 346.369092 -216.576797)
			(xy 346.351352 -216.5731) (xy 346.345764 -216.57183) (xy 345.560904 -216.57183) (xy 345.555316 -216.5731)
			(xy 345.537575 -216.576789) (xy 345.501553 -216.580739) (xy 345.483434 -216.580974) (xy 345.465315 -216.580743)
			(xy 345.429292 -216.576797) (xy 345.411552 -216.5731) (xy 345.405964 -216.57183) (xy 344.621104 -216.57183)
			(xy 344.615516 -216.5731) (xy 344.597775 -216.576789) (xy 344.561753 -216.580739) (xy 344.543634 -216.580974)
			(xy 344.525515 -216.580743) (xy 344.489492 -216.576797) (xy 344.471752 -216.5731) (xy 344.466164 -216.57183)
			(xy 343.681304 -216.57183) (xy 343.675716 -216.5731) (xy 343.657975 -216.576789) (xy 343.621953 -216.580739)
			(xy 343.603834 -216.580974) (xy 343.585715 -216.580743) (xy 343.549692 -216.576797) (xy 343.531952 -216.5731)
			(xy 343.526364 -216.57183) (xy 342.741504 -216.57183) (xy 342.735916 -216.5731) (xy 342.718175 -216.576789)
			(xy 342.682153 -216.580739) (xy 342.664034 -216.580974) (xy 342.645915 -216.580743) (xy 342.609892 -216.576797)
			(xy 342.592152 -216.5731) (xy 342.586564 -216.57183) (xy 341.801704 -216.57183) (xy 341.796116 -216.5731)
			(xy 341.778375 -216.576789) (xy 341.742353 -216.580739) (xy 341.724234 -216.580974) (xy 341.706115 -216.580743)
			(xy 341.670092 -216.576797) (xy 341.652352 -216.5731) (xy 341.646764 -216.57183) (xy 340.861904 -216.57183)
			(xy 340.856316 -216.5731) (xy 340.838575 -216.576789) (xy 340.802553 -216.580739) (xy 340.784434 -216.580974)
			(xy 340.766315 -216.580743) (xy 340.730292 -216.576797) (xy 340.712552 -216.5731) (xy 340.706964 -216.57183)
			(xy 339.922104 -216.57183) (xy 339.916516 -216.5731) (xy 339.898775 -216.576789) (xy 339.862753 -216.580739)
			(xy 339.844634 -216.580974) (xy 339.826515 -216.580743) (xy 339.790492 -216.576797) (xy 339.772752 -216.5731)
			(xy 339.767164 -216.57183) (xy 338.982304 -216.57183) (xy 338.976716 -216.5731) (xy 338.958975 -216.576789)
			(xy 338.922953 -216.580739) (xy 338.904834 -216.580974) (xy 338.886715 -216.580743) (xy 338.850692 -216.576797)
			(xy 338.832952 -216.5731) (xy 338.827364 -216.57183) (xy 338.215478 -216.57183) (xy 337.813904 -216.973404)
			(xy 337.819238 -217.000074) (xy 337.822206 -217.015974) (xy 337.825391 -217.048163) (xy 337.825588 -217.064336)
			(xy 337.825076 -217.090302) (xy 337.816948 -217.141595) (xy 337.800896 -217.190985) (xy 337.777317 -217.237256)
			(xy 337.746791 -217.27927) (xy 337.710069 -217.315992) (xy 337.668055 -217.346518) (xy 337.621783 -217.370097)
			(xy 337.572393 -217.386148) (xy 337.5211 -217.394276) (xy 337.495134 -217.39479) (xy 337.4681 -217.394246)
			(xy 337.414754 -217.38544) (xy 337.363552 -217.368073) (xy 337.315856 -217.342608) (xy 337.272938 -217.309723)
			(xy 337.235942 -217.270295) (xy 337.205853 -217.225373) (xy 337.183472 -217.176155) (xy 337.169395 -217.123951)
			(xy 337.166204 -217.097102) (xy 337.164167 -217.081771) (xy 337.152101 -217.053312) (xy 337.132065 -217.029773)
			(xy 337.105898 -217.013316) (xy 337.076003 -217.005452) (xy 337.06054 -217.005662) (xy 337.024726 -217.006424)
			(xy 336.989674 -217.005662) (xy 336.974213 -217.005492) (xy 336.944327 -217.013366) (xy 336.918162 -217.029814)
			(xy 336.898111 -217.053333) (xy 336.88601 -217.081772) (xy 336.88401 -217.097102) (xy 336.880796 -217.123951)
			(xy 336.866752 -217.176167) (xy 336.844391 -217.225398) (xy 336.814311 -217.27033) (xy 336.777316 -217.309763)
			(xy 336.734391 -217.342645) (xy 336.686685 -217.368097) (xy 336.635471 -217.38544) (xy 336.582116 -217.39421)
			(xy 336.55508 -217.39479) (xy 336.542888 -217.394536) (xy 336.529231 -217.394453) (xy 336.502651 -217.400679)
			(xy 336.478674 -217.413732) (xy 336.459017 -217.432675) (xy 336.445088 -217.456154) (xy 336.437883 -217.482486)
			(xy 336.437478 -217.496136) (xy 336.437478 -218.78163) (xy 336.514948 -218.8591) (xy 337.067906 -218.8591)
			(xy 337.082511 -218.858635) (xy 337.110529 -218.850381) (xy 337.135058 -218.834522) (xy 337.154085 -218.812361)
			(xy 337.166049 -218.785714) (xy 337.169968 -218.75677) (xy 337.168236 -218.74226) (xy 337.16645 -218.729828)
			(xy 337.164542 -218.704781) (xy 337.164426 -218.692222) (xy 337.165037 -218.664242) (xy 337.174486 -218.609083)
			(xy 337.183222 -218.582494) (xy 337.190842 -218.560396) (xy 336.987134 -218.20759) (xy 336.964274 -218.203272)
			(xy 336.939344 -218.198123) (xy 336.89134 -218.181185) (xy 336.846503 -218.157082) (xy 336.805895 -218.126387)
			(xy 336.770476 -218.089825) (xy 336.741086 -218.048262) (xy 336.71842 -218.002682) (xy 336.703014 -217.954165)
			(xy 336.695235 -217.903858) (xy 336.69478 -217.878406) (xy 336.695289 -217.852439) (xy 336.703414 -217.801144)
			(xy 336.719462 -217.751751) (xy 336.74304 -217.705477) (xy 336.773566 -217.663461) (xy 336.810289 -217.626738)
			(xy 336.852305 -217.596212) (xy 336.898579 -217.572634) (xy 336.947972 -217.556586) (xy 336.999267 -217.548461)
			(xy 337.051201 -217.548461) (xy 337.102496 -217.556586) (xy 337.151889 -217.572634) (xy 337.198163 -217.596212)
			(xy 337.240179 -217.626738) (xy 337.276902 -217.663461) (xy 337.307428 -217.705477) (xy 337.331006 -217.751751)
			(xy 337.347054 -217.801144) (xy 337.355179 -217.852439) (xy 337.355688 -217.878406) (xy 337.63458 -217.878406)
			(xy 337.635045 -217.852954) (xy 337.642823 -217.802648) (xy 337.658227 -217.754131) (xy 337.680892 -217.708551)
			(xy 337.710281 -217.666988) (xy 337.745698 -217.630426) (xy 337.786305 -217.59973) (xy 337.831141 -217.575628)
			(xy 337.879144 -217.558689) (xy 337.904074 -217.55354) (xy 337.926934 -217.549222) (xy 338.130642 -217.196162)
			(xy 338.123022 -217.174064) (xy 338.114276 -217.147478) (xy 338.104834 -217.092317) (xy 338.104226 -217.064336)
			(xy 338.104735 -217.038369) (xy 338.11286 -216.987074) (xy 338.128908 -216.937681) (xy 338.152486 -216.891407)
			(xy 338.183012 -216.849391) (xy 338.219735 -216.812668) (xy 338.261751 -216.782142) (xy 338.308025 -216.758564)
			(xy 338.357418 -216.742516) (xy 338.408713 -216.734391) (xy 338.460647 -216.734391) (xy 338.511942 -216.742516)
			(xy 338.561335 -216.758564) (xy 338.607609 -216.782142) (xy 338.649625 -216.812668) (xy 338.686348 -216.849391)
			(xy 338.716874 -216.891407) (xy 338.740452 -216.937681) (xy 338.7565 -216.987074) (xy 338.764625 -217.038369)
			(xy 338.765134 -217.064336) (xy 338.764696 -217.089789) (xy 338.764616 -217.090303) (xy 339.044789 -217.090303)
			(xy 339.044789 -217.038369) (xy 339.052914 -216.987074) (xy 339.068962 -216.937681) (xy 339.09254 -216.891407)
			(xy 339.123066 -216.849391) (xy 339.159789 -216.812668) (xy 339.201805 -216.782142) (xy 339.248079 -216.758564)
			(xy 339.297472 -216.742516) (xy 339.348767 -216.734391) (xy 339.400701 -216.734391) (xy 339.451996 -216.742516)
			(xy 339.501389 -216.758564) (xy 339.547663 -216.782142) (xy 339.589679 -216.812668) (xy 339.626402 -216.849391)
			(xy 339.656928 -216.891407) (xy 339.680506 -216.937681) (xy 339.696554 -216.987074) (xy 339.704679 -217.038369)
			(xy 339.705188 -217.064336) (xy 339.704679 -217.090303) (xy 339.696554 -217.141598) (xy 339.680506 -217.190991)
			(xy 339.656928 -217.237265) (xy 339.626402 -217.279281) (xy 339.589679 -217.316004) (xy 339.547663 -217.34653)
			(xy 339.501389 -217.370108) (xy 339.451996 -217.386156) (xy 339.400701 -217.394281) (xy 339.348767 -217.394281)
			(xy 339.297472 -217.386156) (xy 339.248079 -217.370108) (xy 339.201805 -217.34653) (xy 339.159789 -217.316004)
			(xy 339.123066 -217.279281) (xy 339.09254 -217.237265) (xy 339.068962 -217.190991) (xy 339.052914 -217.141598)
			(xy 339.044789 -217.090303) (xy 338.764616 -217.090303) (xy 338.756912 -217.140095) (xy 338.741503 -217.188612)
			(xy 338.718834 -217.234192) (xy 338.689442 -217.275754) (xy 338.654022 -217.312316) (xy 338.613412 -217.343011)
			(xy 338.568575 -217.367114) (xy 338.520571 -217.384053) (xy 338.49564 -217.389202) (xy 338.47278 -217.39352)
			(xy 338.269072 -217.74658) (xy 338.276692 -217.768678) (xy 338.285424 -217.795268) (xy 338.294875 -217.850426)
			(xy 338.295488 -217.878406) (xy 338.57438 -217.878406) (xy 338.574889 -217.852439) (xy 338.583014 -217.801144)
			(xy 338.599062 -217.751751) (xy 338.62264 -217.705477) (xy 338.653166 -217.663461) (xy 338.689889 -217.626738)
			(xy 338.731905 -217.596212) (xy 338.778179 -217.572634) (xy 338.827572 -217.556586) (xy 338.878867 -217.548461)
			(xy 338.930801 -217.548461) (xy 338.982096 -217.556586) (xy 339.031489 -217.572634) (xy 339.077763 -217.596212)
			(xy 339.119779 -217.626738) (xy 339.156502 -217.663461) (xy 339.187028 -217.705477) (xy 339.210606 -217.751751)
			(xy 339.226654 -217.801144) (xy 339.234779 -217.852439) (xy 339.235288 -217.878406) (xy 339.51418 -217.878406)
			(xy 339.514645 -217.852954) (xy 339.522423 -217.802648) (xy 339.537827 -217.754131) (xy 339.560492 -217.708551)
			(xy 339.589881 -217.666988) (xy 339.625298 -217.630426) (xy 339.665905 -217.59973) (xy 339.710741 -217.575628)
			(xy 339.758744 -217.558689) (xy 339.783674 -217.55354) (xy 339.806534 -217.549222) (xy 340.010242 -217.196162)
			(xy 340.002622 -217.174064) (xy 339.993876 -217.147478) (xy 339.984434 -217.092317) (xy 339.983826 -217.064336)
			(xy 339.984335 -217.038369) (xy 339.99246 -216.987074) (xy 340.008508 -216.937681) (xy 340.032086 -216.891407)
			(xy 340.062612 -216.849391) (xy 340.099335 -216.812668) (xy 340.141351 -216.782142) (xy 340.187625 -216.758564)
			(xy 340.237018 -216.742516) (xy 340.288313 -216.734391) (xy 340.340247 -216.734391) (xy 340.391542 -216.742516)
			(xy 340.440935 -216.758564) (xy 340.487209 -216.782142) (xy 340.529225 -216.812668) (xy 340.565948 -216.849391)
			(xy 340.596474 -216.891407) (xy 340.620052 -216.937681) (xy 340.6361 -216.987074) (xy 340.644225 -217.038369)
			(xy 340.644734 -217.064336) (xy 340.644296 -217.089789) (xy 340.644216 -217.090303) (xy 340.924389 -217.090303)
			(xy 340.924389 -217.038369) (xy 340.932514 -216.987074) (xy 340.948562 -216.937681) (xy 340.97214 -216.891407)
			(xy 341.002666 -216.849391) (xy 341.039389 -216.812668) (xy 341.081405 -216.782142) (xy 341.127679 -216.758564)
			(xy 341.177072 -216.742516) (xy 341.228367 -216.734391) (xy 341.280301 -216.734391) (xy 341.331596 -216.742516)
			(xy 341.380989 -216.758564) (xy 341.427263 -216.782142) (xy 341.469279 -216.812668) (xy 341.506002 -216.849391)
			(xy 341.536528 -216.891407) (xy 341.560106 -216.937681) (xy 341.576154 -216.987074) (xy 341.584279 -217.038369)
			(xy 341.584788 -217.064336) (xy 341.584279 -217.090303) (xy 341.576154 -217.141598) (xy 341.560106 -217.190991)
			(xy 341.536528 -217.237265) (xy 341.506002 -217.279281) (xy 341.469279 -217.316004) (xy 341.427263 -217.34653)
			(xy 341.380989 -217.370108) (xy 341.331596 -217.386156) (xy 341.280301 -217.394281) (xy 341.228367 -217.394281)
			(xy 341.177072 -217.386156) (xy 341.127679 -217.370108) (xy 341.081405 -217.34653) (xy 341.039389 -217.316004)
			(xy 341.002666 -217.279281) (xy 340.97214 -217.237265) (xy 340.948562 -217.190991) (xy 340.932514 -217.141598)
			(xy 340.924389 -217.090303) (xy 340.644216 -217.090303) (xy 340.636512 -217.140095) (xy 340.621103 -217.188612)
			(xy 340.598434 -217.234192) (xy 340.569042 -217.275754) (xy 340.533622 -217.312316) (xy 340.493012 -217.343011)
			(xy 340.448175 -217.367114) (xy 340.400171 -217.384053) (xy 340.37524 -217.389202) (xy 340.35238 -217.39352)
			(xy 340.148672 -217.74658) (xy 340.156292 -217.768678) (xy 340.165024 -217.795268) (xy 340.174475 -217.850426)
			(xy 340.175088 -217.878406) (xy 340.45398 -217.878406) (xy 340.454489 -217.852439) (xy 340.462614 -217.801144)
			(xy 340.478662 -217.751751) (xy 340.50224 -217.705477) (xy 340.532766 -217.663461) (xy 340.569489 -217.626738)
			(xy 340.611505 -217.596212) (xy 340.657779 -217.572634) (xy 340.707172 -217.556586) (xy 340.758467 -217.548461)
			(xy 340.810401 -217.548461) (xy 340.861696 -217.556586) (xy 340.911089 -217.572634) (xy 340.957363 -217.596212)
			(xy 340.999379 -217.626738) (xy 341.036102 -217.663461) (xy 341.066628 -217.705477) (xy 341.090206 -217.751751)
			(xy 341.106254 -217.801144) (xy 341.114379 -217.852439) (xy 341.114888 -217.878406) (xy 341.39378 -217.878406)
			(xy 341.394245 -217.852954) (xy 341.402023 -217.802648) (xy 341.417427 -217.754131) (xy 341.440092 -217.708551)
			(xy 341.469481 -217.666988) (xy 341.504898 -217.630426) (xy 341.545505 -217.59973) (xy 341.590341 -217.575628)
			(xy 341.638344 -217.558689) (xy 341.663274 -217.55354) (xy 341.686134 -217.549222) (xy 341.889842 -217.196162)
			(xy 341.882222 -217.174064) (xy 341.873476 -217.147478) (xy 341.864034 -217.092317) (xy 341.863426 -217.064336)
			(xy 341.863935 -217.038369) (xy 341.87206 -216.987074) (xy 341.888108 -216.937681) (xy 341.911686 -216.891407)
			(xy 341.942212 -216.849391) (xy 341.978935 -216.812668) (xy 342.020951 -216.782142) (xy 342.067225 -216.758564)
			(xy 342.116618 -216.742516) (xy 342.167913 -216.734391) (xy 342.219847 -216.734391) (xy 342.271142 -216.742516)
			(xy 342.320535 -216.758564) (xy 342.366809 -216.782142) (xy 342.408825 -216.812668) (xy 342.445548 -216.849391)
			(xy 342.476074 -216.891407) (xy 342.499652 -216.937681) (xy 342.5157 -216.987074) (xy 342.523825 -217.038369)
			(xy 342.524334 -217.064336) (xy 342.523896 -217.089789) (xy 342.523816 -217.090303) (xy 342.803989 -217.090303)
			(xy 342.803989 -217.038369) (xy 342.812114 -216.987074) (xy 342.828162 -216.937681) (xy 342.85174 -216.891407)
			(xy 342.882266 -216.849391) (xy 342.918989 -216.812668) (xy 342.961005 -216.782142) (xy 343.007279 -216.758564)
			(xy 343.056672 -216.742516) (xy 343.107967 -216.734391) (xy 343.159901 -216.734391) (xy 343.211196 -216.742516)
			(xy 343.260589 -216.758564) (xy 343.306863 -216.782142) (xy 343.348879 -216.812668) (xy 343.385602 -216.849391)
			(xy 343.416128 -216.891407) (xy 343.439706 -216.937681) (xy 343.455754 -216.987074) (xy 343.463879 -217.038369)
			(xy 343.464388 -217.064336) (xy 343.463879 -217.090303) (xy 343.455754 -217.141598) (xy 343.439706 -217.190991)
			(xy 343.416128 -217.237265) (xy 343.385602 -217.279281) (xy 343.348879 -217.316004) (xy 343.306863 -217.34653)
			(xy 343.260589 -217.370108) (xy 343.211196 -217.386156) (xy 343.159901 -217.394281) (xy 343.107967 -217.394281)
			(xy 343.056672 -217.386156) (xy 343.007279 -217.370108) (xy 342.961005 -217.34653) (xy 342.918989 -217.316004)
			(xy 342.882266 -217.279281) (xy 342.85174 -217.237265) (xy 342.828162 -217.190991) (xy 342.812114 -217.141598)
			(xy 342.803989 -217.090303) (xy 342.523816 -217.090303) (xy 342.516112 -217.140095) (xy 342.500703 -217.188612)
			(xy 342.478034 -217.234192) (xy 342.448642 -217.275754) (xy 342.413222 -217.312316) (xy 342.372612 -217.343011)
			(xy 342.327775 -217.367114) (xy 342.279771 -217.384053) (xy 342.25484 -217.389202) (xy 342.23198 -217.39352)
			(xy 342.028272 -217.74658) (xy 342.035892 -217.768678) (xy 342.044624 -217.795268) (xy 342.054075 -217.850426)
			(xy 342.054688 -217.878406) (xy 342.33358 -217.878406) (xy 342.334089 -217.852439) (xy 342.342214 -217.801144)
			(xy 342.358262 -217.751751) (xy 342.38184 -217.705477) (xy 342.412366 -217.663461) (xy 342.449089 -217.626738)
			(xy 342.491105 -217.596212) (xy 342.537379 -217.572634) (xy 342.586772 -217.556586) (xy 342.638067 -217.548461)
			(xy 342.690001 -217.548461) (xy 342.741296 -217.556586) (xy 342.790689 -217.572634) (xy 342.836963 -217.596212)
			(xy 342.878979 -217.626738) (xy 342.915702 -217.663461) (xy 342.946228 -217.705477) (xy 342.969806 -217.751751)
			(xy 342.985854 -217.801144) (xy 342.993979 -217.852439) (xy 342.994488 -217.878406) (xy 343.27338 -217.878406)
			(xy 343.273845 -217.852954) (xy 343.281623 -217.802648) (xy 343.297027 -217.754131) (xy 343.319692 -217.708551)
			(xy 343.349081 -217.666988) (xy 343.384498 -217.630426) (xy 343.425105 -217.59973) (xy 343.469941 -217.575628)
			(xy 343.517944 -217.558689) (xy 343.542874 -217.55354) (xy 343.565734 -217.549222) (xy 343.769442 -217.196162)
			(xy 343.761822 -217.174064) (xy 343.753076 -217.147478) (xy 343.743634 -217.092317) (xy 343.743026 -217.064336)
			(xy 343.743535 -217.038369) (xy 343.75166 -216.987074) (xy 343.767708 -216.937681) (xy 343.791286 -216.891407)
			(xy 343.821812 -216.849391) (xy 343.858535 -216.812668) (xy 343.900551 -216.782142) (xy 343.946825 -216.758564)
			(xy 343.996218 -216.742516) (xy 344.047513 -216.734391) (xy 344.099447 -216.734391) (xy 344.150742 -216.742516)
			(xy 344.200135 -216.758564) (xy 344.246409 -216.782142) (xy 344.288425 -216.812668) (xy 344.325148 -216.849391)
			(xy 344.355674 -216.891407) (xy 344.379252 -216.937681) (xy 344.3953 -216.987074) (xy 344.403425 -217.038369)
			(xy 344.403934 -217.064336) (xy 344.403496 -217.089789) (xy 344.403416 -217.090303) (xy 344.683589 -217.090303)
			(xy 344.683589 -217.038369) (xy 344.691714 -216.987074) (xy 344.707762 -216.937681) (xy 344.73134 -216.891407)
			(xy 344.761866 -216.849391) (xy 344.798589 -216.812668) (xy 344.840605 -216.782142) (xy 344.886879 -216.758564)
			(xy 344.936272 -216.742516) (xy 344.987567 -216.734391) (xy 345.039501 -216.734391) (xy 345.090796 -216.742516)
			(xy 345.140189 -216.758564) (xy 345.186463 -216.782142) (xy 345.228479 -216.812668) (xy 345.265202 -216.849391)
			(xy 345.295728 -216.891407) (xy 345.319306 -216.937681) (xy 345.335354 -216.987074) (xy 345.343479 -217.038369)
			(xy 345.343988 -217.064336) (xy 345.343479 -217.090303) (xy 345.335354 -217.141598) (xy 345.319306 -217.190991)
			(xy 345.295728 -217.237265) (xy 345.265202 -217.279281) (xy 345.228479 -217.316004) (xy 345.186463 -217.34653)
			(xy 345.140189 -217.370108) (xy 345.090796 -217.386156) (xy 345.039501 -217.394281) (xy 344.987567 -217.394281)
			(xy 344.936272 -217.386156) (xy 344.886879 -217.370108) (xy 344.840605 -217.34653) (xy 344.798589 -217.316004)
			(xy 344.761866 -217.279281) (xy 344.73134 -217.237265) (xy 344.707762 -217.190991) (xy 344.691714 -217.141598)
			(xy 344.683589 -217.090303) (xy 344.403416 -217.090303) (xy 344.395712 -217.140095) (xy 344.380303 -217.188612)
			(xy 344.357634 -217.234192) (xy 344.328242 -217.275754) (xy 344.292822 -217.312316) (xy 344.252212 -217.343011)
			(xy 344.207375 -217.367114) (xy 344.159371 -217.384053) (xy 344.13444 -217.389202) (xy 344.11158 -217.39352)
			(xy 343.907872 -217.74658) (xy 343.915492 -217.768678) (xy 343.924224 -217.795268) (xy 343.933675 -217.850426)
			(xy 343.934288 -217.878406) (xy 344.21318 -217.878406) (xy 344.213689 -217.852439) (xy 344.221814 -217.801144)
			(xy 344.237862 -217.751751) (xy 344.26144 -217.705477) (xy 344.291966 -217.663461) (xy 344.328689 -217.626738)
			(xy 344.370705 -217.596212) (xy 344.416979 -217.572634) (xy 344.466372 -217.556586) (xy 344.517667 -217.548461)
			(xy 344.569601 -217.548461) (xy 344.620896 -217.556586) (xy 344.670289 -217.572634) (xy 344.716563 -217.596212)
			(xy 344.758579 -217.626738) (xy 344.795302 -217.663461) (xy 344.825828 -217.705477) (xy 344.849406 -217.751751)
			(xy 344.865454 -217.801144) (xy 344.873579 -217.852439) (xy 344.874088 -217.878406) (xy 345.15298 -217.878406)
			(xy 345.153445 -217.852954) (xy 345.161223 -217.802648) (xy 345.176627 -217.754131) (xy 345.199292 -217.708551)
			(xy 345.228681 -217.666988) (xy 345.264098 -217.630426) (xy 345.304705 -217.59973) (xy 345.349541 -217.575628)
			(xy 345.397544 -217.558689) (xy 345.422474 -217.55354) (xy 345.445334 -217.549222) (xy 345.649042 -217.196162)
			(xy 345.641422 -217.174064) (xy 345.632676 -217.147478) (xy 345.623234 -217.092317) (xy 345.622626 -217.064336)
			(xy 345.623135 -217.038369) (xy 345.63126 -216.987074) (xy 345.647308 -216.937681) (xy 345.670886 -216.891407)
			(xy 345.701412 -216.849391) (xy 345.738135 -216.812668) (xy 345.780151 -216.782142) (xy 345.826425 -216.758564)
			(xy 345.875818 -216.742516) (xy 345.927113 -216.734391) (xy 345.979047 -216.734391) (xy 346.030342 -216.742516)
			(xy 346.079735 -216.758564) (xy 346.126009 -216.782142) (xy 346.168025 -216.812668) (xy 346.204748 -216.849391)
			(xy 346.235274 -216.891407) (xy 346.258852 -216.937681) (xy 346.2749 -216.987074) (xy 346.283025 -217.038369)
			(xy 346.283534 -217.064336) (xy 346.283096 -217.089789) (xy 346.283016 -217.090303) (xy 346.563189 -217.090303)
			(xy 346.563189 -217.038369) (xy 346.571314 -216.987074) (xy 346.587362 -216.937681) (xy 346.61094 -216.891407)
			(xy 346.641466 -216.849391) (xy 346.678189 -216.812668) (xy 346.720205 -216.782142) (xy 346.766479 -216.758564)
			(xy 346.815872 -216.742516) (xy 346.867167 -216.734391) (xy 346.919101 -216.734391) (xy 346.970396 -216.742516)
			(xy 347.019789 -216.758564) (xy 347.066063 -216.782142) (xy 347.108079 -216.812668) (xy 347.144802 -216.849391)
			(xy 347.175328 -216.891407) (xy 347.198906 -216.937681) (xy 347.214954 -216.987074) (xy 347.223079 -217.038369)
			(xy 347.223588 -217.064336) (xy 347.223079 -217.090303) (xy 347.214954 -217.141598) (xy 347.198906 -217.190991)
			(xy 347.175328 -217.237265) (xy 347.144802 -217.279281) (xy 347.108079 -217.316004) (xy 347.066063 -217.34653)
			(xy 347.019789 -217.370108) (xy 346.970396 -217.386156) (xy 346.919101 -217.394281) (xy 346.867167 -217.394281)
			(xy 346.815872 -217.386156) (xy 346.766479 -217.370108) (xy 346.720205 -217.34653) (xy 346.678189 -217.316004)
			(xy 346.641466 -217.279281) (xy 346.61094 -217.237265) (xy 346.587362 -217.190991) (xy 346.571314 -217.141598)
			(xy 346.563189 -217.090303) (xy 346.283016 -217.090303) (xy 346.275312 -217.140095) (xy 346.259903 -217.188612)
			(xy 346.237234 -217.234192) (xy 346.207842 -217.275754) (xy 346.172422 -217.312316) (xy 346.131812 -217.343011)
			(xy 346.086975 -217.367114) (xy 346.038971 -217.384053) (xy 346.01404 -217.389202) (xy 345.99118 -217.39352)
			(xy 345.787472 -217.74658) (xy 345.795092 -217.768678) (xy 345.803824 -217.795268) (xy 345.813275 -217.850426)
			(xy 345.813888 -217.878406) (xy 346.09278 -217.878406) (xy 346.093289 -217.852439) (xy 346.101414 -217.801144)
			(xy 346.117462 -217.751751) (xy 346.14104 -217.705477) (xy 346.171566 -217.663461) (xy 346.208289 -217.626738)
			(xy 346.250305 -217.596212) (xy 346.296579 -217.572634) (xy 346.345972 -217.556586) (xy 346.397267 -217.548461)
			(xy 346.449201 -217.548461) (xy 346.500496 -217.556586) (xy 346.549889 -217.572634) (xy 346.596163 -217.596212)
			(xy 346.638179 -217.626738) (xy 346.674902 -217.663461) (xy 346.705428 -217.705477) (xy 346.729006 -217.751751)
			(xy 346.745054 -217.801144) (xy 346.753179 -217.852439) (xy 346.753688 -217.878406) (xy 347.03258 -217.878406)
			(xy 347.033045 -217.852954) (xy 347.040823 -217.802648) (xy 347.056227 -217.754131) (xy 347.078892 -217.708551)
			(xy 347.108281 -217.666988) (xy 347.143698 -217.630426) (xy 347.184305 -217.59973) (xy 347.229141 -217.575628)
			(xy 347.277144 -217.558689) (xy 347.302074 -217.55354) (xy 347.324934 -217.549222) (xy 347.528642 -217.196162)
			(xy 347.521022 -217.174064) (xy 347.512276 -217.147478) (xy 347.502834 -217.092317) (xy 347.502226 -217.064336)
			(xy 347.502735 -217.038369) (xy 347.51086 -216.987074) (xy 347.526908 -216.937681) (xy 347.550486 -216.891407)
			(xy 347.581012 -216.849391) (xy 347.617735 -216.812668) (xy 347.659751 -216.782142) (xy 347.706025 -216.758564)
			(xy 347.755418 -216.742516) (xy 347.806713 -216.734391) (xy 347.858647 -216.734391) (xy 347.909942 -216.742516)
			(xy 347.959335 -216.758564) (xy 348.005609 -216.782142) (xy 348.047625 -216.812668) (xy 348.084348 -216.849391)
			(xy 348.114874 -216.891407) (xy 348.138452 -216.937681) (xy 348.1545 -216.987074) (xy 348.162625 -217.038369)
			(xy 348.163134 -217.064336) (xy 348.162696 -217.089789) (xy 348.154912 -217.140095) (xy 348.139503 -217.188612)
			(xy 348.116834 -217.234192) (xy 348.087442 -217.275754) (xy 348.052022 -217.312316) (xy 348.011412 -217.343011)
			(xy 347.966575 -217.367114) (xy 347.918571 -217.384053) (xy 347.89364 -217.389202) (xy 347.87078 -217.39352)
			(xy 347.667072 -217.74658) (xy 347.674692 -217.768678) (xy 347.683424 -217.795268) (xy 347.692875 -217.850426)
			(xy 347.693488 -217.878406) (xy 347.692979 -217.904373) (xy 347.684854 -217.955668) (xy 347.668806 -218.005061)
			(xy 347.645228 -218.051335) (xy 347.614702 -218.093351) (xy 347.577979 -218.130074) (xy 347.535963 -218.1606)
			(xy 347.489689 -218.184178) (xy 347.440296 -218.200226) (xy 347.389001 -218.208351) (xy 347.337067 -218.208351)
			(xy 347.285772 -218.200226) (xy 347.236379 -218.184178) (xy 347.190105 -218.1606) (xy 347.148089 -218.130074)
			(xy 347.111366 -218.093351) (xy 347.08084 -218.051335) (xy 347.057262 -218.005061) (xy 347.041214 -217.955668)
			(xy 347.033089 -217.904373) (xy 347.03258 -217.878406) (xy 346.753688 -217.878406) (xy 346.753137 -217.906392)
			(xy 346.743686 -217.96156) (xy 346.734892 -217.988134) (xy 346.727272 -218.010232) (xy 346.93098 -218.363038)
			(xy 346.95384 -218.367356) (xy 346.978759 -218.372533) (xy 347.026743 -218.389497) (xy 347.07156 -218.413614)
			(xy 347.112152 -218.444313) (xy 347.147561 -218.48087) (xy 347.17695 -218.522421) (xy 347.199624 -218.567984)
			(xy 347.215049 -218.616484) (xy 347.22286 -218.666775) (xy 347.223334 -218.692222) (xy 347.222825 -218.718189)
			(xy 347.2147 -218.769484) (xy 347.198652 -218.818877) (xy 347.175074 -218.865151) (xy 347.144548 -218.907167)
			(xy 347.107825 -218.94389) (xy 347.065809 -218.974416) (xy 347.019535 -218.997994) (xy 346.970142 -219.014042)
			(xy 346.918847 -219.022167) (xy 346.866913 -219.022167) (xy 346.815618 -219.014042) (xy 346.766225 -218.997994)
			(xy 346.719951 -218.974416) (xy 346.677935 -218.94389) (xy 346.641212 -218.907167) (xy 346.610686 -218.865151)
			(xy 346.587108 -218.818877) (xy 346.57106 -218.769484) (xy 346.562935 -218.718189) (xy 346.562426 -218.692222)
			(xy 346.562983 -218.664236) (xy 346.57243 -218.609068) (xy 346.581222 -218.582494) (xy 346.588842 -218.560396)
			(xy 346.385134 -218.20759) (xy 346.362274 -218.203272) (xy 346.337363 -218.198058) (xy 346.289382 -218.181098)
			(xy 346.244566 -218.156986) (xy 346.203974 -218.126292) (xy 346.168565 -218.08974) (xy 346.139175 -218.048193)
			(xy 346.116498 -218.002634) (xy 346.101071 -217.954138) (xy 346.093256 -217.903851) (xy 346.09278 -217.878406)
			(xy 345.813888 -217.878406) (xy 345.813379 -217.904373) (xy 345.805254 -217.955668) (xy 345.789206 -218.005061)
			(xy 345.765628 -218.051335) (xy 345.735102 -218.093351) (xy 345.698379 -218.130074) (xy 345.656363 -218.1606)
			(xy 345.610089 -218.184178) (xy 345.560696 -218.200226) (xy 345.509401 -218.208351) (xy 345.457467 -218.208351)
			(xy 345.406172 -218.200226) (xy 345.356779 -218.184178) (xy 345.310505 -218.1606) (xy 345.268489 -218.130074)
			(xy 345.231766 -218.093351) (xy 345.20124 -218.051335) (xy 345.177662 -218.005061) (xy 345.161614 -217.955668)
			(xy 345.153489 -217.904373) (xy 345.15298 -217.878406) (xy 344.874088 -217.878406) (xy 344.873537 -217.906392)
			(xy 344.864086 -217.96156) (xy 344.855292 -217.988134) (xy 344.847672 -218.010232) (xy 345.05138 -218.363038)
			(xy 345.07424 -218.367356) (xy 345.099159 -218.372533) (xy 345.147143 -218.389497) (xy 345.19196 -218.413614)
			(xy 345.232552 -218.444313) (xy 345.267961 -218.48087) (xy 345.29735 -218.522421) (xy 345.320024 -218.567984)
			(xy 345.335449 -218.616484) (xy 345.34326 -218.666775) (xy 345.343734 -218.692222) (xy 345.343225 -218.718189)
			(xy 345.3351 -218.769484) (xy 345.319052 -218.818877) (xy 345.295474 -218.865151) (xy 345.264948 -218.907167)
			(xy 345.228225 -218.94389) (xy 345.186209 -218.974416) (xy 345.139935 -218.997994) (xy 345.090542 -219.014042)
			(xy 345.039247 -219.022167) (xy 344.987313 -219.022167) (xy 344.936018 -219.014042) (xy 344.886625 -218.997994)
			(xy 344.840351 -218.974416) (xy 344.798335 -218.94389) (xy 344.761612 -218.907167) (xy 344.731086 -218.865151)
			(xy 344.707508 -218.818877) (xy 344.69146 -218.769484) (xy 344.683335 -218.718189) (xy 344.682826 -218.692222)
			(xy 344.683383 -218.664236) (xy 344.69283 -218.609068) (xy 344.701622 -218.582494) (xy 344.709242 -218.560396)
			(xy 344.505534 -218.20759) (xy 344.482674 -218.203272) (xy 344.457763 -218.198058) (xy 344.409782 -218.181098)
			(xy 344.364966 -218.156986) (xy 344.324374 -218.126292) (xy 344.288965 -218.08974) (xy 344.259575 -218.048193)
			(xy 344.236898 -218.002634) (xy 344.221471 -217.954138) (xy 344.213656 -217.903851) (xy 344.21318 -217.878406)
			(xy 343.934288 -217.878406) (xy 343.933779 -217.904373) (xy 343.925654 -217.955668) (xy 343.909606 -218.005061)
			(xy 343.886028 -218.051335) (xy 343.855502 -218.093351) (xy 343.818779 -218.130074) (xy 343.776763 -218.1606)
			(xy 343.730489 -218.184178) (xy 343.681096 -218.200226) (xy 343.629801 -218.208351) (xy 343.577867 -218.208351)
			(xy 343.526572 -218.200226) (xy 343.477179 -218.184178) (xy 343.430905 -218.1606) (xy 343.388889 -218.130074)
			(xy 343.352166 -218.093351) (xy 343.32164 -218.051335) (xy 343.298062 -218.005061) (xy 343.282014 -217.955668)
			(xy 343.273889 -217.904373) (xy 343.27338 -217.878406) (xy 342.994488 -217.878406) (xy 342.993937 -217.906392)
			(xy 342.984486 -217.96156) (xy 342.975692 -217.988134) (xy 342.968072 -218.010232) (xy 343.17178 -218.363038)
			(xy 343.19464 -218.367356) (xy 343.219559 -218.372533) (xy 343.267543 -218.389497) (xy 343.31236 -218.413614)
			(xy 343.352952 -218.444313) (xy 343.388361 -218.48087) (xy 343.41775 -218.522421) (xy 343.440424 -218.567984)
			(xy 343.455849 -218.616484) (xy 343.46366 -218.666775) (xy 343.464134 -218.692222) (xy 343.463625 -218.718189)
			(xy 343.4555 -218.769484) (xy 343.439452 -218.818877) (xy 343.415874 -218.865151) (xy 343.385348 -218.907167)
			(xy 343.348625 -218.94389) (xy 343.306609 -218.974416) (xy 343.260335 -218.997994) (xy 343.210942 -219.014042)
			(xy 343.159647 -219.022167) (xy 343.107713 -219.022167) (xy 343.056418 -219.014042) (xy 343.007025 -218.997994)
			(xy 342.960751 -218.974416) (xy 342.918735 -218.94389) (xy 342.882012 -218.907167) (xy 342.851486 -218.865151)
			(xy 342.827908 -218.818877) (xy 342.81186 -218.769484) (xy 342.803735 -218.718189) (xy 342.803226 -218.692222)
			(xy 342.803783 -218.664236) (xy 342.81323 -218.609068) (xy 342.822022 -218.582494) (xy 342.829642 -218.560396)
			(xy 342.625934 -218.20759) (xy 342.603074 -218.203272) (xy 342.578163 -218.198058) (xy 342.530182 -218.181098)
			(xy 342.485366 -218.156986) (xy 342.444774 -218.126292) (xy 342.409365 -218.08974) (xy 342.379975 -218.048193)
			(xy 342.357298 -218.002634) (xy 342.341871 -217.954138) (xy 342.334056 -217.903851) (xy 342.33358 -217.878406)
			(xy 342.054688 -217.878406) (xy 342.054179 -217.904373) (xy 342.046054 -217.955668) (xy 342.030006 -218.005061)
			(xy 342.006428 -218.051335) (xy 341.975902 -218.093351) (xy 341.939179 -218.130074) (xy 341.897163 -218.1606)
			(xy 341.850889 -218.184178) (xy 341.801496 -218.200226) (xy 341.750201 -218.208351) (xy 341.698267 -218.208351)
			(xy 341.646972 -218.200226) (xy 341.597579 -218.184178) (xy 341.551305 -218.1606) (xy 341.509289 -218.130074)
			(xy 341.472566 -218.093351) (xy 341.44204 -218.051335) (xy 341.418462 -218.005061) (xy 341.402414 -217.955668)
			(xy 341.394289 -217.904373) (xy 341.39378 -217.878406) (xy 341.114888 -217.878406) (xy 341.114337 -217.906392)
			(xy 341.104886 -217.96156) (xy 341.096092 -217.988134) (xy 341.088472 -218.010232) (xy 341.29218 -218.363038)
			(xy 341.31504 -218.367356) (xy 341.339959 -218.372533) (xy 341.387943 -218.389497) (xy 341.43276 -218.413614)
			(xy 341.473352 -218.444313) (xy 341.508761 -218.48087) (xy 341.53815 -218.522421) (xy 341.560824 -218.567984)
			(xy 341.576249 -218.616484) (xy 341.58406 -218.666775) (xy 341.584534 -218.692222) (xy 341.584025 -218.718189)
			(xy 341.5759 -218.769484) (xy 341.559852 -218.818877) (xy 341.536274 -218.865151) (xy 341.505748 -218.907167)
			(xy 341.469025 -218.94389) (xy 341.427009 -218.974416) (xy 341.380735 -218.997994) (xy 341.331342 -219.014042)
			(xy 341.280047 -219.022167) (xy 341.228113 -219.022167) (xy 341.176818 -219.014042) (xy 341.127425 -218.997994)
			(xy 341.081151 -218.974416) (xy 341.039135 -218.94389) (xy 341.002412 -218.907167) (xy 340.971886 -218.865151)
			(xy 340.948308 -218.818877) (xy 340.93226 -218.769484) (xy 340.924135 -218.718189) (xy 340.923626 -218.692222)
			(xy 340.924183 -218.664236) (xy 340.93363 -218.609068) (xy 340.942422 -218.582494) (xy 340.950042 -218.560396)
			(xy 340.746334 -218.20759) (xy 340.723474 -218.203272) (xy 340.698563 -218.198058) (xy 340.650582 -218.181098)
			(xy 340.605766 -218.156986) (xy 340.565174 -218.126292) (xy 340.529765 -218.08974) (xy 340.500375 -218.048193)
			(xy 340.477698 -218.002634) (xy 340.462271 -217.954138) (xy 340.454456 -217.903851) (xy 340.45398 -217.878406)
			(xy 340.175088 -217.878406) (xy 340.174579 -217.904373) (xy 340.166454 -217.955668) (xy 340.150406 -218.005061)
			(xy 340.126828 -218.051335) (xy 340.096302 -218.093351) (xy 340.059579 -218.130074) (xy 340.017563 -218.1606)
			(xy 339.971289 -218.184178) (xy 339.921896 -218.200226) (xy 339.870601 -218.208351) (xy 339.818667 -218.208351)
			(xy 339.767372 -218.200226) (xy 339.717979 -218.184178) (xy 339.671705 -218.1606) (xy 339.629689 -218.130074)
			(xy 339.592966 -218.093351) (xy 339.56244 -218.051335) (xy 339.538862 -218.005061) (xy 339.522814 -217.955668)
			(xy 339.514689 -217.904373) (xy 339.51418 -217.878406) (xy 339.235288 -217.878406) (xy 339.234737 -217.906392)
			(xy 339.225286 -217.96156) (xy 339.216492 -217.988134) (xy 339.208872 -218.010232) (xy 339.41258 -218.363038)
			(xy 339.43544 -218.367356) (xy 339.460359 -218.372533) (xy 339.508343 -218.389497) (xy 339.55316 -218.413614)
			(xy 339.593752 -218.444313) (xy 339.629161 -218.48087) (xy 339.65855 -218.522421) (xy 339.681224 -218.567984)
			(xy 339.696649 -218.616484) (xy 339.70446 -218.666775) (xy 339.704934 -218.692222) (xy 339.704425 -218.718189)
			(xy 339.6963 -218.769484) (xy 339.680252 -218.818877) (xy 339.656674 -218.865151) (xy 339.626148 -218.907167)
			(xy 339.589425 -218.94389) (xy 339.547409 -218.974416) (xy 339.501135 -218.997994) (xy 339.451742 -219.014042)
			(xy 339.400447 -219.022167) (xy 339.348513 -219.022167) (xy 339.297218 -219.014042) (xy 339.247825 -218.997994)
			(xy 339.201551 -218.974416) (xy 339.159535 -218.94389) (xy 339.122812 -218.907167) (xy 339.092286 -218.865151)
			(xy 339.068708 -218.818877) (xy 339.05266 -218.769484) (xy 339.044535 -218.718189) (xy 339.044026 -218.692222)
			(xy 339.044583 -218.664236) (xy 339.05403 -218.609068) (xy 339.062822 -218.582494) (xy 339.070442 -218.560396)
			(xy 338.866734 -218.20759) (xy 338.843874 -218.203272) (xy 338.818963 -218.198058) (xy 338.770982 -218.181098)
			(xy 338.726166 -218.156986) (xy 338.685574 -218.126292) (xy 338.650165 -218.08974) (xy 338.620775 -218.048193)
			(xy 338.598098 -218.002634) (xy 338.582671 -217.954138) (xy 338.574856 -217.903851) (xy 338.57438 -217.878406)
			(xy 338.295488 -217.878406) (xy 338.294979 -217.904373) (xy 338.286854 -217.955668) (xy 338.270806 -218.005061)
			(xy 338.247228 -218.051335) (xy 338.216702 -218.093351) (xy 338.179979 -218.130074) (xy 338.137963 -218.1606)
			(xy 338.091689 -218.184178) (xy 338.042296 -218.200226) (xy 337.991001 -218.208351) (xy 337.939067 -218.208351)
			(xy 337.887772 -218.200226) (xy 337.838379 -218.184178) (xy 337.792105 -218.1606) (xy 337.750089 -218.130074)
			(xy 337.713366 -218.093351) (xy 337.68284 -218.051335) (xy 337.659262 -218.005061) (xy 337.643214 -217.955668)
			(xy 337.635089 -217.904373) (xy 337.63458 -217.878406) (xy 337.355688 -217.878406) (xy 337.355074 -217.906386)
			(xy 337.345621 -217.961543) (xy 337.336892 -217.988134) (xy 337.329272 -218.010232) (xy 337.53298 -218.363038)
			(xy 337.55584 -218.367356) (xy 337.580772 -218.372505) (xy 337.628779 -218.389443) (xy 337.67362 -218.413545)
			(xy 337.714233 -218.44424) (xy 337.749658 -218.480801) (xy 337.779055 -218.522363) (xy 337.801729 -218.567942)
			(xy 337.817144 -218.61646) (xy 337.824934 -218.666768) (xy 337.825334 -218.692222) (xy 337.825216 -218.704781)
			(xy 337.823308 -218.729827) (xy 337.821524 -218.74226) (xy 337.819818 -218.756755) (xy 337.8238 -218.785656)
			(xy 337.835787 -218.812254) (xy 337.854802 -218.834381) (xy 337.879294 -218.850232) (xy 337.907268 -218.858517)
			(xy 337.921854 -218.8591) (xy 338.214208 -218.8591) (xy 338.609178 -219.25407) (xy 338.690458 -219.25407)
			(xy 338.70392 -219.243656) (xy 338.725691 -219.227657) (xy 338.773352 -219.202222) (xy 338.824517 -219.18488)
			(xy 338.877822 -219.176095) (xy 338.904834 -219.175584) (xy 338.928104 -219.175976) (xy 338.974184 -219.182496)
			(xy 339.018894 -219.195415) (xy 339.061349 -219.214478) (xy 339.100711 -219.239308) (xy 339.118702 -219.25407)
			(xy 339.630766 -219.25407) (xy 339.650809 -219.23773) (xy 339.694974 -219.210834) (xy 339.742786 -219.19114)
			(xy 339.793082 -219.179128) (xy 339.844634 -219.175092) (xy 339.896186 -219.179128) (xy 339.946482 -219.19114)
			(xy 339.994294 -219.210834) (xy 340.038459 -219.23773) (xy 340.058502 -219.25407) (xy 340.570566 -219.25407)
			(xy 340.590609 -219.23773) (xy 340.634774 -219.210834) (xy 340.682586 -219.19114) (xy 340.732882 -219.179128)
			(xy 340.784434 -219.175092) (xy 340.835986 -219.179128) (xy 340.886282 -219.19114) (xy 340.934094 -219.210834)
			(xy 340.978259 -219.23773) (xy 340.998302 -219.25407) (xy 341.510366 -219.25407) (xy 341.530409 -219.23773)
			(xy 341.574574 -219.210834) (xy 341.622386 -219.19114) (xy 341.672682 -219.179128) (xy 341.724234 -219.175092)
			(xy 341.775786 -219.179128) (xy 341.826082 -219.19114) (xy 341.873894 -219.210834) (xy 341.918059 -219.23773)
			(xy 341.938102 -219.25407) (xy 342.450166 -219.25407) (xy 342.470209 -219.23773) (xy 342.514374 -219.210834)
			(xy 342.562186 -219.19114) (xy 342.612482 -219.179128) (xy 342.664034 -219.175092) (xy 342.715586 -219.179128)
			(xy 342.765882 -219.19114) (xy 342.813694 -219.210834) (xy 342.857859 -219.23773) (xy 342.877902 -219.25407)
			(xy 343.389966 -219.25407) (xy 343.410009 -219.23773) (xy 343.454174 -219.210834) (xy 343.501986 -219.19114)
			(xy 343.552282 -219.179128) (xy 343.603834 -219.175092) (xy 343.655386 -219.179128) (xy 343.705682 -219.19114)
			(xy 343.753494 -219.210834) (xy 343.797659 -219.23773) (xy 343.817702 -219.25407) (xy 344.329766 -219.25407)
			(xy 344.34777 -219.239325) (xy 344.387132 -219.214502) (xy 344.429585 -219.195441) (xy 344.474291 -219.182517)
			(xy 344.520366 -219.175986) (xy 344.543634 -219.175584) (xy 344.5696 -219.176069) (xy 344.620893 -219.184199)
			(xy 344.670283 -219.200252) (xy 344.716553 -219.223834) (xy 344.758564 -219.254364) (xy 344.795283 -219.29109)
			(xy 344.825803 -219.333109) (xy 344.849375 -219.379384) (xy 344.865418 -219.428777) (xy 344.873536 -219.480071)
			(xy 344.874088 -219.506038) (xy 344.873694 -219.529013) (xy 344.873275 -219.532005) (xy 345.153489 -219.532005)
			(xy 345.153489 -219.480071) (xy 345.161614 -219.428776) (xy 345.177662 -219.379383) (xy 345.20124 -219.333109)
			(xy 345.231766 -219.291093) (xy 345.268489 -219.25437) (xy 345.310505 -219.223844) (xy 345.356779 -219.200266)
			(xy 345.406172 -219.184218) (xy 345.457467 -219.176093) (xy 345.509401 -219.176093) (xy 345.560696 -219.184218)
			(xy 345.610089 -219.200266) (xy 345.656363 -219.223844) (xy 345.698379 -219.25437) (xy 345.735102 -219.291093)
			(xy 345.765628 -219.333109) (xy 345.789206 -219.379383) (xy 345.805254 -219.428776) (xy 345.813379 -219.480071)
			(xy 345.813888 -219.506038) (xy 345.813379 -219.532005) (xy 346.093289 -219.532005) (xy 346.093289 -219.480071)
			(xy 346.101414 -219.428776) (xy 346.117462 -219.379383) (xy 346.14104 -219.333109) (xy 346.171566 -219.291093)
			(xy 346.208289 -219.25437) (xy 346.250305 -219.223844) (xy 346.296579 -219.200266) (xy 346.345972 -219.184218)
			(xy 346.397267 -219.176093) (xy 346.449201 -219.176093) (xy 346.500496 -219.184218) (xy 346.549889 -219.200266)
			(xy 346.596163 -219.223844) (xy 346.638179 -219.25437) (xy 346.674902 -219.291093) (xy 346.705428 -219.333109)
			(xy 346.729006 -219.379383) (xy 346.745054 -219.428776) (xy 346.753179 -219.480071) (xy 346.753688 -219.506038)
			(xy 346.753179 -219.532005) (xy 347.033089 -219.532005) (xy 347.033089 -219.480071) (xy 347.041214 -219.428776)
			(xy 347.057262 -219.379383) (xy 347.08084 -219.333109) (xy 347.111366 -219.291093) (xy 347.148089 -219.25437)
			(xy 347.190105 -219.223844) (xy 347.236379 -219.200266) (xy 347.285772 -219.184218) (xy 347.337067 -219.176093)
			(xy 347.389001 -219.176093) (xy 347.440296 -219.184218) (xy 347.489689 -219.200266) (xy 347.535963 -219.223844)
			(xy 347.577979 -219.25437) (xy 347.614702 -219.291093) (xy 347.645228 -219.333109) (xy 347.668806 -219.379383)
			(xy 347.684854 -219.428776) (xy 347.692979 -219.480071) (xy 347.693488 -219.506038) (xy 347.692979 -219.532005)
			(xy 347.972889 -219.532005) (xy 347.972889 -219.480071) (xy 347.981014 -219.428776) (xy 347.997062 -219.379383)
			(xy 348.02064 -219.333109) (xy 348.051166 -219.291093) (xy 348.087889 -219.25437) (xy 348.129905 -219.223844)
			(xy 348.176179 -219.200266) (xy 348.225572 -219.184218) (xy 348.276867 -219.176093) (xy 348.328801 -219.176093)
			(xy 348.380096 -219.184218) (xy 348.429489 -219.200266) (xy 348.475763 -219.223844) (xy 348.517779 -219.25437)
			(xy 348.554502 -219.291093) (xy 348.585028 -219.333109) (xy 348.608606 -219.379383) (xy 348.624654 -219.428776)
			(xy 348.632779 -219.480071) (xy 348.633288 -219.506038) (xy 348.632779 -219.532005) (xy 348.624654 -219.5833)
			(xy 348.608606 -219.632693) (xy 348.585028 -219.678967) (xy 348.554502 -219.720983) (xy 348.517779 -219.757706)
			(xy 348.475763 -219.788232) (xy 348.429489 -219.81181) (xy 348.380096 -219.827858) (xy 348.328801 -219.835983)
			(xy 348.276867 -219.835983) (xy 348.225572 -219.827858) (xy 348.176179 -219.81181) (xy 348.129905 -219.788232)
			(xy 348.087889 -219.757706) (xy 348.051166 -219.720983) (xy 348.02064 -219.678967) (xy 347.997062 -219.632693)
			(xy 347.981014 -219.5833) (xy 347.972889 -219.532005) (xy 347.692979 -219.532005) (xy 347.684854 -219.5833)
			(xy 347.668806 -219.632693) (xy 347.645228 -219.678967) (xy 347.614702 -219.720983) (xy 347.577979 -219.757706)
			(xy 347.535963 -219.788232) (xy 347.489689 -219.81181) (xy 347.440296 -219.827858) (xy 347.389001 -219.835983)
			(xy 347.337067 -219.835983) (xy 347.285772 -219.827858) (xy 347.236379 -219.81181) (xy 347.190105 -219.788232)
			(xy 347.148089 -219.757706) (xy 347.111366 -219.720983) (xy 347.08084 -219.678967) (xy 347.057262 -219.632693)
			(xy 347.041214 -219.5833) (xy 347.033089 -219.532005) (xy 346.753179 -219.532005) (xy 346.745054 -219.5833)
			(xy 346.729006 -219.632693) (xy 346.705428 -219.678967) (xy 346.674902 -219.720983) (xy 346.638179 -219.757706)
			(xy 346.596163 -219.788232) (xy 346.549889 -219.81181) (xy 346.500496 -219.827858) (xy 346.449201 -219.835983)
			(xy 346.397267 -219.835983) (xy 346.345972 -219.827858) (xy 346.296579 -219.81181) (xy 346.250305 -219.788232)
			(xy 346.208289 -219.757706) (xy 346.171566 -219.720983) (xy 346.14104 -219.678967) (xy 346.117462 -219.632693)
			(xy 346.101414 -219.5833) (xy 346.093289 -219.532005) (xy 345.813379 -219.532005) (xy 345.805254 -219.5833)
			(xy 345.789206 -219.632693) (xy 345.765628 -219.678967) (xy 345.735102 -219.720983) (xy 345.698379 -219.757706)
			(xy 345.656363 -219.788232) (xy 345.610089 -219.81181) (xy 345.560696 -219.827858) (xy 345.509401 -219.835983)
			(xy 345.457467 -219.835983) (xy 345.406172 -219.827858) (xy 345.356779 -219.81181) (xy 345.310505 -219.788232)
			(xy 345.268489 -219.757706) (xy 345.231766 -219.720983) (xy 345.20124 -219.678967) (xy 345.177662 -219.632693)
			(xy 345.161614 -219.5833) (xy 345.153489 -219.532005) (xy 344.873275 -219.532005) (xy 344.867322 -219.574518)
			(xy 344.861388 -219.596716) (xy 344.85326 -219.625672) (xy 345.47429 -220.246702) (xy 345.484999 -220.25668)
			(xy 345.510738 -220.270594) (xy 345.539363 -220.27665) (xy 345.568532 -220.274352) (xy 345.595856 -220.263889)
			(xy 345.619099 -220.246117) (xy 345.636358 -220.222491) (xy 345.641676 -220.208856) (xy 345.650658 -220.185109)
			(xy 345.674855 -220.140476) (xy 345.705588 -220.100066) (xy 345.742136 -220.064827) (xy 345.78364 -220.035587)
			(xy 345.829125 -220.013034) (xy 345.877523 -219.997696) (xy 345.927695 -219.989934) (xy 345.95308 -219.9894)
			(xy 345.97905 -219.989908) (xy 346.03035 -219.998029) (xy 346.079748 -220.014076) (xy 346.126028 -220.037651)
			(xy 346.16805 -220.068177) (xy 346.20478 -220.104899) (xy 346.235314 -220.146916) (xy 346.258899 -220.193191)
			(xy 346.274955 -220.242586) (xy 346.283087 -220.293885) (xy 346.283534 -220.319854) (xy 346.283062 -220.345302)
			(xy 346.282981 -220.345821) (xy 346.563189 -220.345821) (xy 346.563189 -220.293887) (xy 346.571314 -220.242592)
			(xy 346.587362 -220.193199) (xy 346.61094 -220.146925) (xy 346.641466 -220.104909) (xy 346.678189 -220.068186)
			(xy 346.720205 -220.03766) (xy 346.766479 -220.014082) (xy 346.815872 -219.998034) (xy 346.867167 -219.989909)
			(xy 346.919101 -219.989909) (xy 346.970396 -219.998034) (xy 347.019789 -220.014082) (xy 347.066063 -220.03766)
			(xy 347.108079 -220.068186) (xy 347.144802 -220.104909) (xy 347.175328 -220.146925) (xy 347.198906 -220.193199)
			(xy 347.214954 -220.242592) (xy 347.223079 -220.293887) (xy 347.223588 -220.319854) (xy 347.223079 -220.345821)
			(xy 347.214954 -220.397116) (xy 347.198906 -220.446509) (xy 347.175328 -220.492783) (xy 347.144802 -220.534799)
			(xy 347.108079 -220.571522) (xy 347.066063 -220.602048) (xy 347.019789 -220.625626) (xy 346.970396 -220.641674)
			(xy 346.919101 -220.649799) (xy 346.867167 -220.649799) (xy 346.815872 -220.641674) (xy 346.766479 -220.625626)
			(xy 346.720205 -220.602048) (xy 346.678189 -220.571522) (xy 346.641466 -220.534799) (xy 346.61094 -220.492783)
			(xy 346.587362 -220.446509) (xy 346.571314 -220.397116) (xy 346.563189 -220.345821) (xy 346.282981 -220.345821)
			(xy 346.275254 -220.395596) (xy 346.259831 -220.444099) (xy 346.237158 -220.489665) (xy 346.20777 -220.531219)
			(xy 346.172361 -220.567779) (xy 346.131768 -220.598481) (xy 346.08695 -220.6226) (xy 346.038965 -220.639565)
			(xy 346.01404 -220.64472) (xy 345.99118 -220.649038) (xy 345.787472 -221.002098) (xy 345.795092 -221.024196)
			(xy 345.803884 -221.050771) (xy 345.81333 -221.105938) (xy 345.813888 -221.133924) (xy 346.09278 -221.133924)
			(xy 346.093289 -221.107957) (xy 346.101414 -221.056662) (xy 346.117462 -221.007269) (xy 346.14104 -220.960995)
			(xy 346.171566 -220.918979) (xy 346.208289 -220.882256) (xy 346.250305 -220.85173) (xy 346.296579 -220.828152)
			(xy 346.345972 -220.812104) (xy 346.397267 -220.803979) (xy 346.449201 -220.803979) (xy 346.500496 -220.812104)
			(xy 346.549889 -220.828152) (xy 346.596163 -220.85173) (xy 346.638179 -220.882256) (xy 346.674902 -220.918979)
			(xy 346.705428 -220.960995) (xy 346.729006 -221.007269) (xy 346.745054 -221.056662) (xy 346.753179 -221.107957)
			(xy 346.753688 -221.133924) (xy 347.03258 -221.133924) (xy 347.032971 -221.108469) (xy 347.040761 -221.05816)
			(xy 347.056176 -221.009641) (xy 347.078851 -220.964061) (xy 347.108249 -220.922499) (xy 347.143675 -220.885938)
			(xy 347.18429 -220.855244) (xy 347.229132 -220.831143) (xy 347.277141 -220.814206) (xy 347.302074 -220.809058)
			(xy 347.324934 -220.80474) (xy 347.528642 -220.45168) (xy 347.521022 -220.429582) (xy 347.512281 -220.402995)
			(xy 347.502835 -220.347835) (xy 347.502226 -220.319854) (xy 347.502735 -220.293887) (xy 347.51086 -220.242592)
			(xy 347.526908 -220.193199) (xy 347.550486 -220.146925) (xy 347.581012 -220.104909) (xy 347.617735 -220.068186)
			(xy 347.659751 -220.03766) (xy 347.706025 -220.014082) (xy 347.755418 -219.998034) (xy 347.806713 -219.989909)
			(xy 347.858647 -219.989909) (xy 347.909942 -219.998034) (xy 347.959335 -220.014082) (xy 348.005609 -220.03766)
			(xy 348.047625 -220.068186) (xy 348.084348 -220.104909) (xy 348.114874 -220.146925) (xy 348.138452 -220.193199)
			(xy 348.1545 -220.242592) (xy 348.162625 -220.293887) (xy 348.163134 -220.319854) (xy 348.162712 -220.345307)
			(xy 348.162632 -220.345821) (xy 348.442789 -220.345821) (xy 348.442789 -220.293887) (xy 348.450914 -220.242592)
			(xy 348.466962 -220.193199) (xy 348.49054 -220.146925) (xy 348.521066 -220.104909) (xy 348.557789 -220.068186)
			(xy 348.599805 -220.03766) (xy 348.646079 -220.014082) (xy 348.695472 -219.998034) (xy 348.746767 -219.989909)
			(xy 348.798701 -219.989909) (xy 348.849996 -219.998034) (xy 348.899389 -220.014082) (xy 348.945663 -220.03766)
			(xy 348.987679 -220.068186) (xy 349.024402 -220.104909) (xy 349.054928 -220.146925) (xy 349.078506 -220.193199)
			(xy 349.094554 -220.242592) (xy 349.102679 -220.293887) (xy 349.103188 -220.319854) (xy 349.102679 -220.345821)
			(xy 349.094554 -220.397116) (xy 349.078506 -220.446509) (xy 349.054928 -220.492783) (xy 349.024402 -220.534799)
			(xy 348.987679 -220.571522) (xy 348.945663 -220.602048) (xy 348.899389 -220.625626) (xy 348.849996 -220.641674)
			(xy 348.798701 -220.649799) (xy 348.746767 -220.649799) (xy 348.695472 -220.641674) (xy 348.646079 -220.625626)
			(xy 348.599805 -220.602048) (xy 348.557789 -220.571522) (xy 348.521066 -220.534799) (xy 348.49054 -220.492783)
			(xy 348.466962 -220.446509) (xy 348.450914 -220.397116) (xy 348.442789 -220.345821) (xy 348.162632 -220.345821)
			(xy 348.154926 -220.395615) (xy 348.139514 -220.444132) (xy 348.116843 -220.489711) (xy 348.087449 -220.531273)
			(xy 348.052027 -220.567835) (xy 348.011416 -220.59853) (xy 347.966577 -220.622632) (xy 347.918571 -220.639571)
			(xy 347.89364 -220.64472) (xy 347.87078 -220.649038) (xy 347.667072 -221.002098) (xy 347.674692 -221.024196)
			(xy 347.683429 -221.050785) (xy 347.692877 -221.105944) (xy 347.693488 -221.133924) (xy 347.97238 -221.133924)
			(xy 347.972889 -221.107957) (xy 347.981014 -221.056662) (xy 347.997062 -221.007269) (xy 348.02064 -220.960995)
			(xy 348.051166 -220.918979) (xy 348.087889 -220.882256) (xy 348.129905 -220.85173) (xy 348.176179 -220.828152)
			(xy 348.225572 -220.812104) (xy 348.276867 -220.803979) (xy 348.328801 -220.803979) (xy 348.380096 -220.812104)
			(xy 348.429489 -220.828152) (xy 348.475763 -220.85173) (xy 348.517779 -220.882256) (xy 348.554502 -220.918979)
			(xy 348.585028 -220.960995) (xy 348.608606 -221.007269) (xy 348.624654 -221.056662) (xy 348.632779 -221.107957)
			(xy 348.633288 -221.133924) (xy 348.91218 -221.133924) (xy 348.912571 -221.108469) (xy 348.920361 -221.05816)
			(xy 348.935776 -221.009641) (xy 348.958451 -220.964061) (xy 348.987849 -220.922499) (xy 349.023275 -220.885938)
			(xy 349.06389 -220.855244) (xy 349.108732 -220.831143) (xy 349.156741 -220.814206) (xy 349.181674 -220.809058)
			(xy 349.204534 -220.80474) (xy 349.408242 -220.45168) (xy 349.400622 -220.429582) (xy 349.391881 -220.402995)
			(xy 349.382435 -220.347835) (xy 349.381826 -220.319854) (xy 349.382335 -220.293887) (xy 349.39046 -220.242592)
			(xy 349.406508 -220.193199) (xy 349.430086 -220.146925) (xy 349.460612 -220.104909) (xy 349.497335 -220.068186)
			(xy 349.539351 -220.03766) (xy 349.585625 -220.014082) (xy 349.635018 -219.998034) (xy 349.686313 -219.989909)
			(xy 349.738247 -219.989909) (xy 349.789542 -219.998034) (xy 349.838935 -220.014082) (xy 349.885209 -220.03766)
			(xy 349.927225 -220.068186) (xy 349.963948 -220.104909) (xy 349.994474 -220.146925) (xy 350.018052 -220.193199)
			(xy 350.0341 -220.242592) (xy 350.042225 -220.293887) (xy 350.042734 -220.319854) (xy 350.042312 -220.345307)
			(xy 350.034526 -220.395615) (xy 350.019114 -220.444132) (xy 349.996443 -220.489711) (xy 349.967049 -220.531273)
			(xy 349.931627 -220.567835) (xy 349.891016 -220.59853) (xy 349.846177 -220.622632) (xy 349.798171 -220.639571)
			(xy 349.77324 -220.64472) (xy 349.75038 -220.649038) (xy 349.546672 -221.002098) (xy 349.554292 -221.024196)
			(xy 349.563029 -221.050785) (xy 349.572477 -221.105944) (xy 349.573088 -221.133924) (xy 349.85198 -221.133924)
			(xy 349.852489 -221.107957) (xy 349.860614 -221.056662) (xy 349.876662 -221.007269) (xy 349.90024 -220.960995)
			(xy 349.930766 -220.918979) (xy 349.967489 -220.882256) (xy 350.009505 -220.85173) (xy 350.055779 -220.828152)
			(xy 350.105172 -220.812104) (xy 350.156467 -220.803979) (xy 350.208401 -220.803979) (xy 350.259696 -220.812104)
			(xy 350.309089 -220.828152) (xy 350.355363 -220.85173) (xy 350.397379 -220.882256) (xy 350.434102 -220.918979)
			(xy 350.464628 -220.960995) (xy 350.488206 -221.007269) (xy 350.504254 -221.056662) (xy 350.512379 -221.107957)
			(xy 350.512888 -221.133924) (xy 350.512342 -221.16191) (xy 350.502887 -221.217078) (xy 350.494092 -221.243652)
			(xy 350.486472 -221.26575) (xy 350.69018 -221.618556) (xy 350.71304 -221.622874) (xy 350.737963 -221.628034)
			(xy 350.785948 -221.644999) (xy 350.830766 -221.669118) (xy 350.871359 -221.699819) (xy 350.906768 -221.736378)
			(xy 350.936156 -221.777931) (xy 350.95883 -221.823497) (xy 350.974253 -221.871999) (xy 350.982061 -221.922292)
			(xy 350.982534 -221.94774) (xy 350.982025 -221.973707) (xy 350.9739 -222.025002) (xy 350.957852 -222.074395)
			(xy 350.934274 -222.120669) (xy 350.903748 -222.162685) (xy 350.867025 -222.199408) (xy 350.825009 -222.229934)
			(xy 350.778735 -222.253512) (xy 350.729342 -222.26956) (xy 350.678047 -222.277685) (xy 350.626113 -222.277685)
			(xy 350.574818 -222.26956) (xy 350.525425 -222.253512) (xy 350.479151 -222.229934) (xy 350.437135 -222.199408)
			(xy 350.400412 -222.162685) (xy 350.369886 -222.120669) (xy 350.346308 -222.074395) (xy 350.33026 -222.025002)
			(xy 350.322135 -221.973707) (xy 350.321626 -221.94774) (xy 350.322187 -221.919755) (xy 350.331631 -221.864587)
			(xy 350.340422 -221.838012) (xy 350.348042 -221.815914) (xy 350.144334 -221.463108) (xy 350.121474 -221.45879)
			(xy 350.096545 -221.453653) (xy 350.048558 -221.436688) (xy 350.003737 -221.412568) (xy 349.963143 -221.381864)
			(xy 349.927734 -221.345302) (xy 349.898346 -221.303745) (xy 349.875674 -221.258175) (xy 349.860254 -221.209669)
			(xy 349.85245 -221.159373) (xy 349.85198 -221.133924) (xy 349.573088 -221.133924) (xy 349.572579 -221.159891)
			(xy 349.564454 -221.211186) (xy 349.548406 -221.260579) (xy 349.524828 -221.306853) (xy 349.494302 -221.348869)
			(xy 349.457579 -221.385592) (xy 349.415563 -221.416118) (xy 349.369289 -221.439696) (xy 349.319896 -221.455744)
			(xy 349.268601 -221.463869) (xy 349.216667 -221.463869) (xy 349.165372 -221.455744) (xy 349.115979 -221.439696)
			(xy 349.069705 -221.416118) (xy 349.027689 -221.385592) (xy 348.990966 -221.348869) (xy 348.96044 -221.306853)
			(xy 348.936862 -221.260579) (xy 348.920814 -221.211186) (xy 348.912689 -221.159891) (xy 348.91218 -221.133924)
			(xy 348.633288 -221.133924) (xy 348.632742 -221.16191) (xy 348.623287 -221.217078) (xy 348.614492 -221.243652)
			(xy 348.606872 -221.26575) (xy 348.81058 -221.618556) (xy 348.83344 -221.622874) (xy 348.858363 -221.628034)
			(xy 348.906348 -221.644999) (xy 348.951166 -221.669118) (xy 348.991759 -221.699819) (xy 349.027168 -221.736378)
			(xy 349.056556 -221.777931) (xy 349.07923 -221.823497) (xy 349.094653 -221.871999) (xy 349.102461 -221.922292)
			(xy 349.102934 -221.94774) (xy 349.102425 -221.973707) (xy 349.382335 -221.973707) (xy 349.382335 -221.921773)
			(xy 349.39046 -221.870478) (xy 349.406508 -221.821085) (xy 349.430086 -221.774811) (xy 349.460612 -221.732795)
			(xy 349.497335 -221.696072) (xy 349.539351 -221.665546) (xy 349.585625 -221.641968) (xy 349.635018 -221.62592)
			(xy 349.686313 -221.617795) (xy 349.738247 -221.617795) (xy 349.789542 -221.62592) (xy 349.838935 -221.641968)
			(xy 349.885209 -221.665546) (xy 349.927225 -221.696072) (xy 349.963948 -221.732795) (xy 349.994474 -221.774811)
			(xy 350.018052 -221.821085) (xy 350.0341 -221.870478) (xy 350.042225 -221.921773) (xy 350.042734 -221.94774)
			(xy 350.042225 -221.973707) (xy 350.0341 -222.025002) (xy 350.018052 -222.074395) (xy 349.994474 -222.120669)
			(xy 349.963948 -222.162685) (xy 349.927225 -222.199408) (xy 349.885209 -222.229934) (xy 349.838935 -222.253512)
			(xy 349.789542 -222.26956) (xy 349.738247 -222.277685) (xy 349.686313 -222.277685) (xy 349.635018 -222.26956)
			(xy 349.585625 -222.253512) (xy 349.539351 -222.229934) (xy 349.497335 -222.199408) (xy 349.460612 -222.162685)
			(xy 349.430086 -222.120669) (xy 349.406508 -222.074395) (xy 349.39046 -222.025002) (xy 349.382335 -221.973707)
			(xy 349.102425 -221.973707) (xy 349.0943 -222.025002) (xy 349.078252 -222.074395) (xy 349.054674 -222.120669)
			(xy 349.024148 -222.162685) (xy 348.987425 -222.199408) (xy 348.945409 -222.229934) (xy 348.899135 -222.253512)
			(xy 348.849742 -222.26956) (xy 348.798447 -222.277685) (xy 348.746513 -222.277685) (xy 348.695218 -222.26956)
			(xy 348.645825 -222.253512) (xy 348.599551 -222.229934) (xy 348.557535 -222.199408) (xy 348.520812 -222.162685)
			(xy 348.490286 -222.120669) (xy 348.466708 -222.074395) (xy 348.45066 -222.025002) (xy 348.442535 -221.973707)
			(xy 348.442026 -221.94774) (xy 348.442587 -221.919755) (xy 348.452031 -221.864587) (xy 348.460822 -221.838012)
			(xy 348.468442 -221.815914) (xy 348.264734 -221.463108) (xy 348.241874 -221.45879) (xy 348.216945 -221.453653)
			(xy 348.168958 -221.436688) (xy 348.124137 -221.412568) (xy 348.083543 -221.381864) (xy 348.048134 -221.345302)
			(xy 348.018746 -221.303745) (xy 347.996074 -221.258175) (xy 347.980654 -221.209669) (xy 347.97285 -221.159373)
			(xy 347.97238 -221.133924) (xy 347.693488 -221.133924) (xy 347.692979 -221.159891) (xy 347.684854 -221.211186)
			(xy 347.668806 -221.260579) (xy 347.645228 -221.306853) (xy 347.614702 -221.348869) (xy 347.577979 -221.385592)
			(xy 347.535963 -221.416118) (xy 347.489689 -221.439696) (xy 347.440296 -221.455744) (xy 347.389001 -221.463869)
			(xy 347.337067 -221.463869) (xy 347.285772 -221.455744) (xy 347.236379 -221.439696) (xy 347.190105 -221.416118)
			(xy 347.148089 -221.385592) (xy 347.111366 -221.348869) (xy 347.08084 -221.306853) (xy 347.057262 -221.260579)
			(xy 347.041214 -221.211186) (xy 347.033089 -221.159891) (xy 347.03258 -221.133924) (xy 346.753688 -221.133924)
			(xy 346.753142 -221.16191) (xy 346.743687 -221.217078) (xy 346.734892 -221.243652) (xy 346.727272 -221.26575)
			(xy 346.93098 -221.618556) (xy 346.95384 -221.622874) (xy 346.978763 -221.628034) (xy 347.026748 -221.644999)
			(xy 347.071566 -221.669118) (xy 347.112159 -221.699819) (xy 347.147568 -221.736378) (xy 347.176956 -221.777931)
			(xy 347.19963 -221.823497) (xy 347.215053 -221.871999) (xy 347.222861 -221.922292) (xy 347.223334 -221.94774)
			(xy 347.222825 -221.973707) (xy 347.2147 -222.025002) (xy 347.198652 -222.074395) (xy 347.175074 -222.120669)
			(xy 347.144548 -222.162685) (xy 347.107825 -222.199408) (xy 347.065809 -222.229934) (xy 347.019535 -222.253512)
			(xy 346.970142 -222.26956) (xy 346.918847 -222.277685) (xy 346.866913 -222.277685) (xy 346.815618 -222.26956)
			(xy 346.766225 -222.253512) (xy 346.719951 -222.229934) (xy 346.677935 -222.199408) (xy 346.641212 -222.162685)
			(xy 346.610686 -222.120669) (xy 346.587108 -222.074395) (xy 346.57106 -222.025002) (xy 346.562935 -221.973707)
			(xy 346.562426 -221.94774) (xy 346.562987 -221.919755) (xy 346.572431 -221.864587) (xy 346.581222 -221.838012)
			(xy 346.588842 -221.815914) (xy 346.385134 -221.463108) (xy 346.362274 -221.45879) (xy 346.337345 -221.453653)
			(xy 346.289358 -221.436688) (xy 346.244537 -221.412568) (xy 346.203943 -221.381864) (xy 346.168534 -221.345302)
			(xy 346.139146 -221.303745) (xy 346.116474 -221.258175) (xy 346.101054 -221.209669) (xy 346.09325 -221.159373)
			(xy 346.09278 -221.133924) (xy 345.813888 -221.133924) (xy 345.813364 -221.160396) (xy 345.804922 -221.212662)
			(xy 345.788258 -221.262914) (xy 345.763798 -221.309869) (xy 345.732167 -221.352325) (xy 345.713558 -221.37116)
			(xy 345.713558 -222.16491) (xy 346.071698 -222.52305) (xy 346.194634 -222.52305) (xy 346.213195 -222.505906)
			(xy 346.254557 -222.476888) (xy 346.299856 -222.45451) (xy 346.348036 -222.439295) (xy 346.397971 -222.431597)
			(xy 346.448497 -222.431597) (xy 346.498432 -222.439295) (xy 346.546612 -222.45451) (xy 346.591911 -222.476888)
			(xy 346.633273 -222.505906) (xy 346.651834 -222.52305) (xy 347.134434 -222.52305) (xy 347.152995 -222.505906)
			(xy 347.194357 -222.476888) (xy 347.239656 -222.45451) (xy 347.287836 -222.439295) (xy 347.337771 -222.431597)
			(xy 347.388297 -222.431597) (xy 347.438232 -222.439295) (xy 347.486412 -222.45451) (xy 347.531711 -222.476888)
			(xy 347.573073 -222.505906) (xy 347.591634 -222.52305) (xy 348.074234 -222.52305) (xy 348.092796 -222.505907)
			(xy 348.134158 -222.476889) (xy 348.179457 -222.454509) (xy 348.227636 -222.439289) (xy 348.277571 -222.431584)
			(xy 348.302834 -222.431102) (xy 348.328801 -222.431614) (xy 348.380094 -222.439742) (xy 348.429485 -222.455793)
			(xy 348.475757 -222.479372) (xy 348.517772 -222.509898) (xy 348.554495 -222.54662) (xy 348.585023 -222.588634)
			(xy 348.608603 -222.634906) (xy 348.624656 -222.684296) (xy 348.632785 -222.735589) (xy 348.633288 -222.761556)
			(xy 348.633034 -222.777304) (xy 348.632453 -222.787523) (xy 348.912689 -222.787523) (xy 348.912689 -222.735589)
			(xy 348.920814 -222.684294) (xy 348.936862 -222.634901) (xy 348.96044 -222.588627) (xy 348.990966 -222.546611)
			(xy 349.027689 -222.509888) (xy 349.069705 -222.479362) (xy 349.115979 -222.455784) (xy 349.165372 -222.439736)
			(xy 349.216667 -222.431611) (xy 349.268601 -222.431611) (xy 349.319896 -222.439736) (xy 349.369289 -222.455784)
			(xy 349.415563 -222.479362) (xy 349.457579 -222.509888) (xy 349.494302 -222.546611) (xy 349.524828 -222.588627)
			(xy 349.548406 -222.634901) (xy 349.564454 -222.684294) (xy 349.572579 -222.735589) (xy 349.573088 -222.761556)
			(xy 349.572579 -222.787523) (xy 349.852489 -222.787523) (xy 349.852489 -222.735589) (xy 349.860614 -222.684294)
			(xy 349.876662 -222.634901) (xy 349.90024 -222.588627) (xy 349.930766 -222.546611) (xy 349.967489 -222.509888)
			(xy 350.009505 -222.479362) (xy 350.055779 -222.455784) (xy 350.105172 -222.439736) (xy 350.156467 -222.431611)
			(xy 350.208401 -222.431611) (xy 350.259696 -222.439736) (xy 350.309089 -222.455784) (xy 350.355363 -222.479362)
			(xy 350.397379 -222.509888) (xy 350.434102 -222.546611) (xy 350.464628 -222.588627) (xy 350.488206 -222.634901)
			(xy 350.504254 -222.684294) (xy 350.512379 -222.735589) (xy 350.512888 -222.761556) (xy 350.512379 -222.787523)
			(xy 350.504254 -222.838818) (xy 350.488206 -222.888211) (xy 350.464628 -222.934485) (xy 350.434102 -222.976501)
			(xy 350.397379 -223.013224) (xy 350.355363 -223.04375) (xy 350.309089 -223.067328) (xy 350.259696 -223.083376)
			(xy 350.208401 -223.091501) (xy 350.156467 -223.091501) (xy 350.105172 -223.083376) (xy 350.055779 -223.067328)
			(xy 350.009505 -223.04375) (xy 349.967489 -223.013224) (xy 349.930766 -222.976501) (xy 349.90024 -222.934485)
			(xy 349.876662 -222.888211) (xy 349.860614 -222.838818) (xy 349.852489 -222.787523) (xy 349.572579 -222.787523)
			(xy 349.564454 -222.838818) (xy 349.548406 -222.888211) (xy 349.524828 -222.934485) (xy 349.494302 -222.976501)
			(xy 349.457579 -223.013224) (xy 349.415563 -223.04375) (xy 349.369289 -223.067328) (xy 349.319896 -223.083376)
			(xy 349.268601 -223.091501) (xy 349.216667 -223.091501) (xy 349.165372 -223.083376) (xy 349.115979 -223.067328)
			(xy 349.069705 -223.04375) (xy 349.027689 -223.013224) (xy 348.990966 -222.976501) (xy 348.96044 -222.934485)
			(xy 348.936862 -222.888211) (xy 348.920814 -222.838818) (xy 348.912689 -222.787523) (xy 348.632453 -222.787523)
			(xy 348.631764 -222.799656) (xy 348.637098 -222.80499) (xy 348.637098 -223.09836) (xy 348.783656 -223.244918)
			(xy 348.801944 -223.246442) (xy 348.826316 -223.249047) (xy 348.873966 -223.260534) (xy 348.919396 -223.278934)
			(xy 348.961609 -223.303843) (xy 348.99968 -223.334714) (xy 349.032774 -223.37087) (xy 349.060163 -223.411517)
			(xy 349.081248 -223.455765) (xy 349.095566 -223.502641) (xy 349.102802 -223.551119) (xy 349.103188 -223.575626)
			(xy 349.102728 -223.600604) (xy 349.095203 -223.649989) (xy 349.08033 -223.697678) (xy 349.058446 -223.742585)
			(xy 349.030051 -223.783685) (xy 349.013272 -223.802194) (xy 349.006865 -223.809664) (xy 348.999753 -223.827995)
			(xy 349.000035 -223.847656) (xy 349.007671 -223.865775) (xy 349.014288 -223.87306) (xy 349.109792 -223.968564)
			(xy 349.11953 -223.97768) (xy 349.142628 -223.991006) (xy 349.168386 -223.997901) (xy 349.195051 -223.997896)
			(xy 349.220807 -223.990991) (xy 349.243899 -223.977658) (xy 349.262755 -223.958803) (xy 349.269812 -223.947482)
			(xy 349.408242 -223.707452) (xy 349.400368 -223.685608) (xy 349.391569 -223.65897) (xy 349.382126 -223.603674)
			(xy 349.381572 -223.575626) (xy 349.382082 -223.549639) (xy 349.390212 -223.498304) (xy 349.406273 -223.448874)
			(xy 349.429869 -223.402564) (xy 349.460419 -223.360516) (xy 349.49717 -223.323765) (xy 349.539218 -223.293215)
			(xy 349.585528 -223.269619) (xy 349.634958 -223.253558) (xy 349.686293 -223.245428) (xy 349.738267 -223.245428)
			(xy 349.789602 -223.253558) (xy 349.839032 -223.269619) (xy 349.885342 -223.293215) (xy 349.92739 -223.323765)
			(xy 349.964141 -223.360516) (xy 349.994691 -223.402564) (xy 350.018287 -223.448874) (xy 350.034348 -223.498304)
			(xy 350.042478 -223.549639) (xy 350.042988 -223.575626) (xy 350.042516 -223.601109) (xy 350.042441 -223.601593)
			(xy 350.322389 -223.601593) (xy 350.322389 -223.549659) (xy 350.330514 -223.498364) (xy 350.346562 -223.448971)
			(xy 350.37014 -223.402697) (xy 350.400666 -223.360681) (xy 350.437389 -223.323958) (xy 350.479405 -223.293432)
			(xy 350.525679 -223.269854) (xy 350.575072 -223.253806) (xy 350.626367 -223.245681) (xy 350.678301 -223.245681)
			(xy 350.729596 -223.253806) (xy 350.778989 -223.269854) (xy 350.825263 -223.293432) (xy 350.867279 -223.323958)
			(xy 350.904002 -223.360681) (xy 350.934528 -223.402697) (xy 350.958106 -223.448971) (xy 350.974154 -223.498364)
			(xy 350.982279 -223.549659) (xy 350.982788 -223.575626) (xy 350.982279 -223.601593) (xy 350.974154 -223.652888)
			(xy 350.958106 -223.702281) (xy 350.934528 -223.748555) (xy 350.904002 -223.790571) (xy 350.867279 -223.827294)
			(xy 350.825263 -223.85782) (xy 350.778989 -223.881398) (xy 350.729596 -223.897446) (xy 350.678301 -223.905571)
			(xy 350.626367 -223.905571) (xy 350.575072 -223.897446) (xy 350.525679 -223.881398) (xy 350.479405 -223.85782)
			(xy 350.437389 -223.827294) (xy 350.400666 -223.790571) (xy 350.37014 -223.748555) (xy 350.346562 -223.702281)
			(xy 350.330514 -223.652888) (xy 350.322389 -223.601593) (xy 350.042441 -223.601593) (xy 350.034695 -223.651471)
			(xy 350.019241 -223.700038) (xy 349.996522 -223.74566) (xy 349.967073 -223.787257) (xy 349.931593 -223.823846)
			(xy 349.890921 -223.854559) (xy 349.846019 -223.878671) (xy 349.79795 -223.89561) (xy 349.772986 -223.900746)
			(xy 349.749872 -223.905064) (xy 349.546672 -224.257362) (xy 349.554546 -224.27946) (xy 349.563348 -224.306098)
			(xy 349.572795 -224.361393) (xy 349.573342 -224.389442) (xy 349.851726 -224.389442) (xy 349.852236 -224.363455)
			(xy 349.860366 -224.31212) (xy 349.876427 -224.26269) (xy 349.900023 -224.21638) (xy 349.930573 -224.174332)
			(xy 349.967324 -224.137581) (xy 350.009372 -224.107031) (xy 350.055682 -224.083435) (xy 350.105112 -224.067374)
			(xy 350.156447 -224.059244) (xy 350.208421 -224.059244) (xy 350.259756 -224.067374) (xy 350.309186 -224.083435)
			(xy 350.355496 -224.107031) (xy 350.397544 -224.137581) (xy 350.434295 -224.174332) (xy 350.464845 -224.21638)
			(xy 350.488441 -224.26269) (xy 350.504502 -224.31212) (xy 350.512632 -224.363455) (xy 350.513142 -224.389442)
			(xy 350.512591 -224.417491) (xy 350.503146 -224.472786) (xy 350.494346 -224.499424) (xy 350.486472 -224.521522)
			(xy 350.689926 -224.87382) (xy 350.712786 -224.878138) (xy 350.737747 -224.883289) (xy 350.785814 -224.900227)
			(xy 350.830715 -224.924337) (xy 350.871387 -224.955049) (xy 350.906867 -224.991635) (xy 350.936316 -225.03323)
			(xy 350.959037 -225.07885) (xy 350.974492 -225.127415) (xy 350.982315 -225.177776) (xy 350.982788 -225.203258)
			(xy 350.982278 -225.229245) (xy 350.974148 -225.28058) (xy 350.958087 -225.33001) (xy 350.934491 -225.37632)
			(xy 350.903941 -225.418368) (xy 350.86719 -225.455119) (xy 350.825142 -225.485669) (xy 350.778832 -225.509265)
			(xy 350.729402 -225.525326) (xy 350.678067 -225.533456) (xy 350.626093 -225.533456) (xy 350.574758 -225.525326)
			(xy 350.525328 -225.509265) (xy 350.479018 -225.485669) (xy 350.43697 -225.455119) (xy 350.400219 -225.418368)
			(xy 350.369669 -225.37632) (xy 350.346073 -225.33001) (xy 350.330012 -225.28058) (xy 350.321882 -225.229245)
			(xy 350.321372 -225.203258) (xy 350.321922 -225.175209) (xy 350.331367 -225.119914) (xy 350.340168 -225.093276)
			(xy 350.348042 -225.071178) (xy 350.144588 -224.71888) (xy 350.121728 -224.714562) (xy 350.096769 -224.709401)
			(xy 350.048702 -224.692465) (xy 350.0038 -224.668356) (xy 349.963128 -224.637646) (xy 349.927648 -224.601061)
			(xy 349.898199 -224.559467) (xy 349.875478 -224.513848) (xy 349.860023 -224.465284) (xy 349.852199 -224.414924)
			(xy 349.851726 -224.389442) (xy 349.573342 -224.389442) (xy 349.572865 -224.414966) (xy 349.565016 -224.465406)
			(xy 349.54951 -224.514041) (xy 349.526715 -224.559716) (xy 349.497173 -224.601346) (xy 349.461586 -224.637944)
			(xy 349.420798 -224.668639) (xy 349.375779 -224.692702) (xy 349.351854 -224.701608) (xy 349.317818 -224.713546)
			(xy 349.317818 -225.64217) (xy 349.405448 -225.7298) (xy 349.427395 -225.742778) (xy 349.467376 -225.774418)
			(xy 349.502037 -225.811811) (xy 349.5167 -225.83267)
		)
		(stroke
			(width 0)
			(type solid)
		)
		(fill yes)
		(layer "In6.Cu")
		(net "PVCCFA_EHV_FIVRA_CPU0")
	)
	(gr_poly
		(pts
			(xy 106.120692 -222.301816) (xy 106.13466 -222.301379) (xy 106.161549 -222.293805) (xy 106.185376 -222.279223)
			(xy 106.204355 -222.258725) (xy 106.217065 -222.233849) (xy 106.222552 -222.206458) (xy 106.220405 -222.178605)
			(xy 106.210785 -222.152379) (xy 106.202988 -222.14078) (xy 106.188328 -222.119565) (xy 106.165074 -222.073541)
			(xy 106.149253 -222.024463) (xy 106.14125 -221.973523) (xy 106.140758 -221.94774) (xy 106.141231 -221.922292)
			(xy 106.149039 -221.871999) (xy 106.164462 -221.823496) (xy 106.187135 -221.77793) (xy 106.216523 -221.736376)
			(xy 106.251932 -221.699816) (xy 106.292525 -221.669114) (xy 106.337343 -221.644995) (xy 106.385327 -221.628028)
			(xy 106.410252 -221.622874) (xy 106.433112 -221.618556) (xy 106.637074 -221.264988) (xy 106.629454 -221.243144)
			(xy 106.620795 -221.216673) (xy 106.611479 -221.161769) (xy 106.610912 -221.133924) (xy 106.611421 -221.107957)
			(xy 106.619546 -221.056662) (xy 106.635594 -221.007269) (xy 106.659172 -220.960995) (xy 106.689698 -220.918979)
			(xy 106.726421 -220.882256) (xy 106.768437 -220.85173) (xy 106.814711 -220.828152) (xy 106.864104 -220.812104)
			(xy 106.915399 -220.803979) (xy 106.967333 -220.803979) (xy 107.018628 -220.812104) (xy 107.068021 -220.828152)
			(xy 107.114295 -220.85173) (xy 107.156311 -220.882256) (xy 107.193034 -220.918979) (xy 107.22356 -220.960995)
			(xy 107.247138 -221.007269) (xy 107.263186 -221.056662) (xy 107.271311 -221.107957) (xy 107.27182 -221.133924)
			(xy 107.271347 -221.159396) (xy 107.263524 -221.209737) (xy 107.248068 -221.25828) (xy 107.225343 -221.303875)
			(xy 107.19589 -221.345443) (xy 107.160405 -221.381997) (xy 107.119731 -221.412671) (xy 107.07483 -221.436739)
			(xy 107.026768 -221.453631) (xy 107.001818 -221.45879) (xy 106.978704 -221.463108) (xy 106.77525 -221.815914)
			(xy 106.78287 -221.838012) (xy 106.791661 -221.864587) (xy 106.801105 -221.919755) (xy 106.801666 -221.94774)
			(xy 106.801169 -221.973521) (xy 106.793156 -222.024458) (xy 106.777332 -222.073533) (xy 106.75408 -222.119555)
			(xy 106.739436 -222.14078) (xy 106.731622 -222.152358) (xy 106.722033 -222.178582) (xy 106.719907 -222.206423)
			(xy 106.725405 -222.233799) (xy 106.738115 -222.258661) (xy 106.757086 -222.279149) (xy 106.780898 -222.29373)
			(xy 106.807771 -222.301314) (xy 106.821732 -222.301816) (xy 108.000292 -222.301816) (xy 108.01426 -222.301379)
			(xy 108.041149 -222.293805) (xy 108.064976 -222.279223) (xy 108.083955 -222.258725) (xy 108.096665 -222.233849)
			(xy 108.102152 -222.206458) (xy 108.100005 -222.178605) (xy 108.090385 -222.152379) (xy 108.082588 -222.14078)
			(xy 108.067928 -222.119565) (xy 108.044674 -222.073541) (xy 108.028853 -222.024463) (xy 108.02085 -221.973523)
			(xy 108.020358 -221.94774) (xy 108.020831 -221.922292) (xy 108.028639 -221.871999) (xy 108.044062 -221.823496)
			(xy 108.066735 -221.77793) (xy 108.096123 -221.736376) (xy 108.131532 -221.699816) (xy 108.172125 -221.669114)
			(xy 108.216943 -221.644995) (xy 108.264927 -221.628028) (xy 108.289852 -221.622874) (xy 108.312712 -221.618556)
			(xy 108.516674 -221.264988) (xy 108.509054 -221.243144) (xy 108.500395 -221.216673) (xy 108.491079 -221.161769)
			(xy 108.490512 -221.133924) (xy 108.491021 -221.107957) (xy 108.499146 -221.056662) (xy 108.515194 -221.007269)
			(xy 108.538772 -220.960995) (xy 108.569298 -220.918979) (xy 108.606021 -220.882256) (xy 108.648037 -220.85173)
			(xy 108.694311 -220.828152) (xy 108.743704 -220.812104) (xy 108.794999 -220.803979) (xy 108.846933 -220.803979)
			(xy 108.898228 -220.812104) (xy 108.947621 -220.828152) (xy 108.993895 -220.85173) (xy 109.035911 -220.882256)
			(xy 109.072634 -220.918979) (xy 109.10316 -220.960995) (xy 109.126738 -221.007269) (xy 109.142786 -221.056662)
			(xy 109.150911 -221.107957) (xy 109.15142 -221.133924) (xy 109.150947 -221.159396) (xy 109.143124 -221.209737)
			(xy 109.127668 -221.25828) (xy 109.104943 -221.303875) (xy 109.07549 -221.345443) (xy 109.040005 -221.381997)
			(xy 108.999331 -221.412671) (xy 108.95443 -221.436739) (xy 108.906368 -221.453631) (xy 108.881418 -221.45879)
			(xy 108.858304 -221.463108) (xy 108.65485 -221.815914) (xy 108.66247 -221.838012) (xy 108.671261 -221.864587)
			(xy 108.680705 -221.919755) (xy 108.681266 -221.94774) (xy 108.680769 -221.973521) (xy 108.672756 -222.024458)
			(xy 108.656932 -222.073533) (xy 108.63368 -222.119555) (xy 108.619036 -222.14078) (xy 108.611222 -222.152358)
			(xy 108.601633 -222.178582) (xy 108.599507 -222.206423) (xy 108.605005 -222.233799) (xy 108.617715 -222.258661)
			(xy 108.636686 -222.279149) (xy 108.660498 -222.29373) (xy 108.687371 -222.301314) (xy 108.701332 -222.301816)
			(xy 108.940092 -222.301816) (xy 108.95406 -222.301379) (xy 108.980949 -222.293805) (xy 109.004776 -222.279223)
			(xy 109.023755 -222.258725) (xy 109.036465 -222.233849) (xy 109.041952 -222.206458) (xy 109.039805 -222.178605)
			(xy 109.030185 -222.152379) (xy 109.022388 -222.14078) (xy 109.007728 -222.119565) (xy 108.984474 -222.073541)
			(xy 108.968653 -222.024463) (xy 108.96065 -221.973523) (xy 108.960158 -221.94774) (xy 108.960667 -221.921773)
			(xy 108.968792 -221.870478) (xy 108.98484 -221.821085) (xy 109.008418 -221.774811) (xy 109.038944 -221.732795)
			(xy 109.075667 -221.696072) (xy 109.117683 -221.665546) (xy 109.163957 -221.641968) (xy 109.21335 -221.62592)
			(xy 109.264645 -221.617795) (xy 109.316579 -221.617795) (xy 109.367874 -221.62592) (xy 109.417267 -221.641968)
			(xy 109.463541 -221.665546) (xy 109.505557 -221.696072) (xy 109.54228 -221.732795) (xy 109.572806 -221.774811)
			(xy 109.596384 -221.821085) (xy 109.612432 -221.870478) (xy 109.620557 -221.921773) (xy 109.621066 -221.94774)
			(xy 109.620569 -221.973521) (xy 109.612556 -222.024458) (xy 109.596732 -222.073533) (xy 109.57348 -222.119555)
			(xy 109.558836 -222.14078) (xy 109.551022 -222.152358) (xy 109.541433 -222.178582) (xy 109.539307 -222.206423)
			(xy 109.544805 -222.233799) (xy 109.557515 -222.258661) (xy 109.576486 -222.279149) (xy 109.600298 -222.29373)
			(xy 109.627171 -222.301314) (xy 109.641132 -222.301816) (xy 109.880146 -222.301816) (xy 109.894118 -222.301384)
			(xy 109.921019 -222.293818) (xy 109.944858 -222.279238) (xy 109.963847 -222.258737) (xy 109.976563 -222.233854)
			(xy 109.982052 -222.206454) (xy 109.979902 -222.178592) (xy 109.970274 -222.152359) (xy 109.962442 -222.14078)
			(xy 109.94778 -222.119566) (xy 109.924522 -222.073543) (xy 109.908698 -222.024464) (xy 109.900694 -221.973523)
			(xy 109.900212 -221.94774) (xy 109.900685 -221.922293) (xy 109.908494 -221.872003) (xy 109.923918 -221.823503)
			(xy 109.946592 -221.77794) (xy 109.975982 -221.73639) (xy 110.011392 -221.699835) (xy 110.051986 -221.669139)
			(xy 110.096805 -221.645026) (xy 110.14479 -221.628068) (xy 110.169706 -221.622874) (xy 110.192566 -221.618556)
			(xy 110.396528 -221.265242) (xy 110.388654 -221.243398) (xy 110.379977 -221.216866) (xy 110.370655 -221.161833)
			(xy 110.370112 -221.133924) (xy 110.370619 -221.107955) (xy 110.378741 -221.056655) (xy 110.394787 -221.007257)
			(xy 110.418363 -220.960977) (xy 110.448888 -220.918955) (xy 110.485611 -220.882226) (xy 110.527627 -220.851693)
			(xy 110.573903 -220.828109) (xy 110.623298 -220.812054) (xy 110.674597 -220.803924) (xy 110.700566 -220.80347)
			(xy 110.726699 -220.803986) (xy 110.778309 -220.812251) (xy 110.827976 -220.828533) (xy 110.851442 -220.840046)
			(xy 110.864912 -220.846393) (xy 110.89418 -220.851797) (xy 110.923764 -220.848537) (xy 110.951152 -220.836889)
			(xy 110.974022 -220.817841) (xy 110.990431 -220.79301) (xy 110.998987 -220.764504) (xy 110.999524 -220.749622)
			(xy 110.999524 -220.60281) (xy 110.977395 -220.58888) (xy 110.937437 -220.555156) (xy 110.903289 -220.515559)
			(xy 110.875804 -220.471078) (xy 110.855668 -220.422824) (xy 110.843383 -220.372) (xy 110.839256 -220.319876)
			(xy 110.84339 -220.267753) (xy 110.855683 -220.216931) (xy 110.875826 -220.168679) (xy 110.903317 -220.124202)
			(xy 110.937471 -220.084611) (xy 110.977434 -220.050892) (xy 110.999524 -220.036898) (xy 110.999524 -219.89034)
			(xy 110.999002 -219.87546) (xy 110.990419 -219.846964) (xy 110.973998 -219.822144) (xy 110.951128 -219.803101)
			(xy 110.923745 -219.791446) (xy 110.894165 -219.788166) (xy 110.864894 -219.793538) (xy 110.851442 -219.799916)
			(xy 110.827974 -219.811423) (xy 110.778308 -219.827701) (xy 110.726698 -219.835957) (xy 110.700566 -219.836492)
			(xy 110.674598 -219.83598) (xy 110.623301 -219.827851) (xy 110.573907 -219.811797) (xy 110.527633 -219.788215)
			(xy 110.485617 -219.757684) (xy 110.448893 -219.720958) (xy 110.418367 -219.678938) (xy 110.39479 -219.632662)
			(xy 110.378741 -219.583266) (xy 110.370617 -219.531969) (xy 110.370617 -219.480032) (xy 110.378741 -219.428734)
			(xy 110.39479 -219.379339) (xy 110.418367 -219.333062) (xy 110.448893 -219.291042) (xy 110.485617 -219.254316)
			(xy 110.527633 -219.223785) (xy 110.573907 -219.200203) (xy 110.623301 -219.184149) (xy 110.674598 -219.17602)
			(xy 110.700566 -219.175584) (xy 110.726699 -219.1761) (xy 110.778309 -219.184365) (xy 110.827975 -219.200648)
			(xy 110.851442 -219.21216) (xy 110.864913 -219.218506) (xy 110.894182 -219.22391) (xy 110.923766 -219.220649)
			(xy 110.951156 -219.209001) (xy 110.974026 -219.189954) (xy 110.990438 -219.165124) (xy 110.998997 -219.136618)
			(xy 110.999524 -219.121736) (xy 110.999524 -218.97467) (xy 110.97745 -218.960726) (xy 110.937599 -218.926995)
			(xy 110.903547 -218.887418) (xy 110.876142 -218.842979) (xy 110.856066 -218.794784) (xy 110.843818 -218.744031)
			(xy 110.839703 -218.691983) (xy 110.843823 -218.639936) (xy 110.856076 -218.589185) (xy 110.876157 -218.540991)
			(xy 110.903567 -218.496555) (xy 110.937622 -218.456981) (xy 110.977477 -218.423255) (xy 110.999524 -218.409266)
			(xy 110.999524 -218.262708) (xy 110.999011 -218.247821) (xy 110.990439 -218.219307) (xy 110.97402 -218.194469)
			(xy 110.951144 -218.175411) (xy 110.923749 -218.163747) (xy 110.894156 -218.160466) (xy 110.864871 -218.165846)
			(xy 110.851442 -218.172284) (xy 110.827974 -218.183792) (xy 110.778308 -218.200072) (xy 110.726699 -218.208328)
			(xy 110.700566 -218.20886) (xy 110.6746 -218.208348) (xy 110.623309 -218.20022) (xy 110.573921 -218.184168)
			(xy 110.527651 -218.160589) (xy 110.485639 -218.130062) (xy 110.44892 -218.093339) (xy 110.418397 -218.051325)
			(xy 110.394821 -218.005053) (xy 110.378774 -217.955664) (xy 110.37065 -217.904372) (xy 110.370112 -217.878406)
			(xy 110.370587 -217.852961) (xy 110.3784 -217.802674) (xy 110.393828 -217.754178) (xy 110.416504 -217.70862)
			(xy 110.445895 -217.667074) (xy 110.481305 -217.630524) (xy 110.521898 -217.599831) (xy 110.566715 -217.575722)
			(xy 110.614697 -217.558766) (xy 110.639606 -217.55354) (xy 110.662466 -217.549222) (xy 110.866428 -217.195908)
			(xy 110.858808 -217.17381) (xy 110.85009 -217.147282) (xy 110.840644 -217.092252) (xy 110.840012 -217.064336)
			(xy 110.840444 -217.040088) (xy 110.847545 -216.992115) (xy 110.861584 -216.945696) (xy 110.88226 -216.901829)
			(xy 110.909129 -216.861457) (xy 110.941613 -216.825447) (xy 110.979013 -216.794575) (xy 110.999524 -216.781634)
			(xy 110.999524 -216.634822) (xy 110.998999 -216.619944) (xy 110.990414 -216.591453) (xy 110.973992 -216.566638)
			(xy 110.951124 -216.547598) (xy 110.923743 -216.535946) (xy 110.894168 -216.532666) (xy 110.8649 -216.538036)
			(xy 110.851442 -216.544398) (xy 110.827974 -216.555905) (xy 110.778308 -216.572185) (xy 110.726699 -216.58044)
			(xy 110.700566 -216.580974) (xy 110.673531 -216.580433) (xy 110.620182 -216.57163) (xy 110.568976 -216.554266)
			(xy 110.521277 -216.528802) (xy 110.478356 -216.495918) (xy 110.441358 -216.456488) (xy 110.411266 -216.411565)
			(xy 110.388885 -216.362344) (xy 110.374809 -216.310138) (xy 110.371636 -216.283286) (xy 110.369596 -216.267961)
			(xy 110.357526 -216.239516) (xy 110.337487 -216.215994) (xy 110.311322 -216.199556) (xy 110.281433 -216.191712)
			(xy 110.265972 -216.191846) (xy 110.230412 -216.192608) (xy 110.190534 -216.192608) (xy 110.175559 -216.193132)
			(xy 110.146894 -216.201807) (xy 110.121976 -216.218422) (xy 110.102946 -216.241548) (xy 110.09144 -216.269199)
			(xy 110.089442 -216.284048) (xy 110.086373 -216.309428) (xy 110.073414 -216.358878) (xy 110.052992 -216.405742)
			(xy 110.025596 -216.448902) (xy 109.991878 -216.487326) (xy 109.952645 -216.520098) (xy 109.908832 -216.546436)
			(xy 109.861485 -216.565712) (xy 109.811734 -216.577464) (xy 109.760766 -216.581413) (xy 109.709798 -216.577464)
			(xy 109.660047 -216.565712) (xy 109.6127 -216.546436) (xy 109.568887 -216.520098) (xy 109.529654 -216.487326)
			(xy 109.495936 -216.448902) (xy 109.46854 -216.405742) (xy 109.448118 -216.358878) (xy 109.435159 -216.309428)
			(xy 109.43209 -216.284048) (xy 109.430068 -216.269203) (xy 109.418565 -216.241555) (xy 109.399542 -216.218429)
			(xy 109.37463 -216.201811) (xy 109.345971 -216.19313) (xy 109.330998 -216.192608) (xy 109.290612 -216.192608)
			(xy 109.25556 -216.191846) (xy 109.240099 -216.191678) (xy 109.210215 -216.199554) (xy 109.184051 -216.216003)
			(xy 109.164001 -216.23952) (xy 109.151898 -216.267957) (xy 109.149896 -216.283286) (xy 109.146878 -216.308727)
			(xy 109.133996 -216.358311) (xy 109.113619 -216.405314) (xy 109.086234 -216.44861) (xy 109.052497 -216.487163)
			(xy 109.013216 -216.52005) (xy 108.969332 -216.546483) (xy 108.921896 -216.565829) (xy 108.872042 -216.577625)
			(xy 108.820966 -216.581589) (xy 108.76989 -216.577625) (xy 108.720036 -216.565829) (xy 108.6726 -216.546483)
			(xy 108.628716 -216.52005) (xy 108.589435 -216.487163) (xy 108.555698 -216.44861) (xy 108.528313 -216.405314)
			(xy 108.507936 -216.358311) (xy 108.495054 -216.308727) (xy 108.492036 -216.283286) (xy 108.489996 -216.267961)
			(xy 108.477926 -216.239516) (xy 108.457887 -216.215994) (xy 108.431722 -216.199556) (xy 108.401833 -216.191712)
			(xy 108.386372 -216.191846) (xy 108.350812 -216.192608) (xy 108.31576 -216.191846) (xy 108.300299 -216.191678)
			(xy 108.270415 -216.199554) (xy 108.244251 -216.216003) (xy 108.224201 -216.23952) (xy 108.212098 -216.267957)
			(xy 108.210096 -216.283286) (xy 108.206883 -216.310136) (xy 108.19284 -216.362352) (xy 108.170481 -216.411584)
			(xy 108.140401 -216.456517) (xy 108.103405 -216.495951) (xy 108.060481 -216.528833) (xy 108.012774 -216.554285)
			(xy 107.961558 -216.571627) (xy 107.908202 -216.580396) (xy 107.881166 -216.580974) (xy 107.8552 -216.580462)
			(xy 107.803908 -216.572334) (xy 107.754519 -216.556282) (xy 107.708248 -216.532703) (xy 107.666235 -216.502177)
			(xy 107.629514 -216.465454) (xy 107.598989 -216.42344) (xy 107.575412 -216.377168) (xy 107.559363 -216.327779)
			(xy 107.551237 -216.276486) (xy 107.550712 -216.25052) (xy 107.551203 -216.224426) (xy 107.559402 -216.172886)
			(xy 107.575599 -216.123275) (xy 107.599392 -216.076827) (xy 107.63019 -216.034695) (xy 107.667226 -215.997927)
			(xy 107.688126 -215.982296) (xy 107.700381 -215.972838) (xy 107.718988 -215.948116) (xy 107.729362 -215.918965)
			(xy 107.730556 -215.888046) (xy 107.72246 -215.858182) (xy 107.714542 -215.844882) (xy 107.695502 -215.8144)
			(xy 107.662621 -215.750488) (xy 107.635953 -215.683744) (xy 107.615738 -215.614771) (xy 107.602159 -215.544191)
			(xy 107.595339 -215.472641) (xy 107.594908 -215.436704) (xy 107.595142 -215.408851) (xy 107.599208 -215.353295)
			(xy 107.603036 -215.325706) (xy 107.575566 -215.314604) (xy 107.522292 -215.288663) (xy 107.49661 -215.27389)
			(xy 107.487866 -215.269239) (xy 107.468294 -215.266333) (xy 107.449081 -215.271062) (xy 107.433094 -215.282721)
			(xy 107.427522 -215.290908) (xy 107.409481 -215.319442) (xy 107.369036 -215.3735) (xy 107.34675 -215.398858)
			(xy 107.334059 -215.43646) (xy 107.301865 -215.509004) (xy 107.282488 -215.543638) (xy 107.126024 -215.814656)
			(xy 107.107736 -215.844628) (xy 107.099853 -215.857936) (xy 107.09171 -215.887761) (xy 107.092843 -215.918657)
			(xy 107.103149 -215.947805) (xy 107.121687 -215.972547) (xy 107.133898 -215.982042) (xy 107.154858 -215.997665)
			(xy 107.192028 -216.034421) (xy 107.22294 -216.076576) (xy 107.246822 -216.123076) (xy 107.263076 -216.172759)
			(xy 107.271297 -216.224383) (xy 107.27182 -216.25052) (xy 107.271336 -216.276487) (xy 107.263208 -216.327782)
			(xy 107.247156 -216.377174) (xy 107.223575 -216.423446) (xy 107.193045 -216.46546) (xy 107.156319 -216.50218)
			(xy 107.1143 -216.532703) (xy 107.068024 -216.556277) (xy 107.018629 -216.572321) (xy 106.967333 -216.58044)
			(xy 106.941366 -216.580974) (xy 106.914331 -216.580433) (xy 106.860982 -216.57163) (xy 106.809776 -216.554266)
			(xy 106.762077 -216.528802) (xy 106.719156 -216.495918) (xy 106.682158 -216.456488) (xy 106.652066 -216.411565)
			(xy 106.629685 -216.362344) (xy 106.615609 -216.310138) (xy 106.612436 -216.283286) (xy 106.610396 -216.267961)
			(xy 106.598326 -216.239516) (xy 106.578287 -216.215994) (xy 106.552122 -216.199556) (xy 106.522233 -216.191712)
			(xy 106.506772 -216.191846) (xy 106.471212 -216.192608) (xy 106.43616 -216.191846) (xy 106.420699 -216.191678)
			(xy 106.390815 -216.199554) (xy 106.364651 -216.216003) (xy 106.344601 -216.23952) (xy 106.332498 -216.267957)
			(xy 106.330496 -216.283286) (xy 106.327283 -216.310136) (xy 106.31324 -216.362352) (xy 106.290881 -216.411584)
			(xy 106.260801 -216.456517) (xy 106.223805 -216.495951) (xy 106.180881 -216.528833) (xy 106.133174 -216.554285)
			(xy 106.081958 -216.571627) (xy 106.028602 -216.580396) (xy 106.001566 -216.580974) (xy 105.9756 -216.580462)
			(xy 105.924308 -216.572334) (xy 105.874919 -216.556282) (xy 105.828648 -216.532703) (xy 105.786635 -216.502177)
			(xy 105.749914 -216.465454) (xy 105.719389 -216.42344) (xy 105.695812 -216.377168) (xy 105.679763 -216.327779)
			(xy 105.671637 -216.276486) (xy 105.671112 -216.25052) (xy 105.671603 -216.224426) (xy 105.679802 -216.172886)
			(xy 105.695999 -216.123275) (xy 105.719792 -216.076827) (xy 105.75059 -216.034695) (xy 105.787626 -215.997927)
			(xy 105.808526 -215.982296) (xy 105.820781 -215.972838) (xy 105.839388 -215.948116) (xy 105.849762 -215.918965)
			(xy 105.850956 -215.888046) (xy 105.84286 -215.858182) (xy 105.834942 -215.844882) (xy 105.815902 -215.8144)
			(xy 105.783021 -215.750488) (xy 105.756353 -215.683744) (xy 105.736138 -215.614771) (xy 105.722559 -215.544191)
			(xy 105.715739 -215.472641) (xy 105.715308 -215.436704) (xy 105.715542 -215.408851) (xy 105.719608 -215.353295)
			(xy 105.723436 -215.325706) (xy 105.695966 -215.314604) (xy 105.642692 -215.288663) (xy 105.61701 -215.27389)
			(xy 105.608266 -215.269239) (xy 105.588694 -215.266333) (xy 105.569481 -215.271062) (xy 105.553494 -215.282721)
			(xy 105.547922 -215.290908) (xy 105.529881 -215.319442) (xy 105.489436 -215.3735) (xy 105.46715 -215.398858)
			(xy 105.454459 -215.43646) (xy 105.422265 -215.509004) (xy 105.402888 -215.543638) (xy 105.246424 -215.814656)
			(xy 105.228136 -215.844628) (xy 105.220253 -215.857936) (xy 105.21211 -215.887761) (xy 105.213243 -215.918657)
			(xy 105.223549 -215.947805) (xy 105.242087 -215.972547) (xy 105.254298 -215.982042) (xy 105.275258 -215.997665)
			(xy 105.312428 -216.034421) (xy 105.34334 -216.076576) (xy 105.367222 -216.123076) (xy 105.383476 -216.172759)
			(xy 105.391697 -216.224383) (xy 105.39222 -216.25052) (xy 105.391736 -216.276487) (xy 105.383608 -216.327782)
			(xy 105.367556 -216.377174) (xy 105.343975 -216.423446) (xy 105.313445 -216.46546) (xy 105.276719 -216.50218)
			(xy 105.2347 -216.532703) (xy 105.188424 -216.556277) (xy 105.139029 -216.572321) (xy 105.087733 -216.58044)
			(xy 105.061766 -216.580974) (xy 105.034731 -216.580433) (xy 104.981382 -216.57163) (xy 104.930176 -216.554266)
			(xy 104.882477 -216.528802) (xy 104.839556 -216.495918) (xy 104.802558 -216.456488) (xy 104.772466 -216.411565)
			(xy 104.750085 -216.362344) (xy 104.736009 -216.310138) (xy 104.732836 -216.283286) (xy 104.730796 -216.267961)
			(xy 104.718726 -216.239516) (xy 104.698687 -216.215994) (xy 104.672522 -216.199556) (xy 104.642633 -216.191712)
			(xy 104.627172 -216.191846) (xy 104.591612 -216.192608) (xy 104.55656 -216.191846) (xy 104.541099 -216.191678)
			(xy 104.511215 -216.199554) (xy 104.485051 -216.216003) (xy 104.465001 -216.23952) (xy 104.452898 -216.267957)
			(xy 104.450896 -216.283286) (xy 104.447683 -216.310136) (xy 104.43364 -216.362352) (xy 104.411281 -216.411584)
			(xy 104.381201 -216.456517) (xy 104.344205 -216.495951) (xy 104.301281 -216.528833) (xy 104.253574 -216.554285)
			(xy 104.202358 -216.571627) (xy 104.149002 -216.580396) (xy 104.121966 -216.580974) (xy 104.096 -216.580462)
			(xy 104.044708 -216.572334) (xy 103.995319 -216.556282) (xy 103.949048 -216.532703) (xy 103.907035 -216.502177)
			(xy 103.870314 -216.465454) (xy 103.839789 -216.42344) (xy 103.816212 -216.377168) (xy 103.800163 -216.327779)
			(xy 103.792037 -216.276486) (xy 103.791512 -216.25052) (xy 103.792003 -216.224426) (xy 103.800202 -216.172886)
			(xy 103.816399 -216.123275) (xy 103.840192 -216.076827) (xy 103.87099 -216.034695) (xy 103.908026 -215.997927)
			(xy 103.928926 -215.982296) (xy 103.941181 -215.972838) (xy 103.959788 -215.948116) (xy 103.970162 -215.918965)
			(xy 103.971356 -215.888046) (xy 103.96326 -215.858182) (xy 103.955342 -215.844882) (xy 103.936302 -215.8144)
			(xy 103.903421 -215.750488) (xy 103.876753 -215.683744) (xy 103.856538 -215.614771) (xy 103.842959 -215.544191)
			(xy 103.836139 -215.472641) (xy 103.835708 -215.436704) (xy 103.835942 -215.408851) (xy 103.840008 -215.353295)
			(xy 103.843836 -215.325706) (xy 103.816366 -215.314604) (xy 103.763092 -215.288663) (xy 103.73741 -215.27389)
			(xy 103.728666 -215.269239) (xy 103.709094 -215.266333) (xy 103.689881 -215.271062) (xy 103.673894 -215.282721)
			(xy 103.668322 -215.290908) (xy 103.650281 -215.319442) (xy 103.609836 -215.3735) (xy 103.58755 -215.398858)
			(xy 103.574859 -215.43646) (xy 103.542665 -215.509004) (xy 103.523288 -215.543638) (xy 103.366824 -215.814656)
			(xy 103.348536 -215.844628) (xy 103.340653 -215.857936) (xy 103.33251 -215.887761) (xy 103.333643 -215.918657)
			(xy 103.343949 -215.947805) (xy 103.362487 -215.972547) (xy 103.374698 -215.982042) (xy 103.395658 -215.997665)
			(xy 103.432828 -216.034421) (xy 103.46374 -216.076576) (xy 103.487622 -216.123076) (xy 103.503876 -216.172759)
			(xy 103.512097 -216.224383) (xy 103.51262 -216.25052) (xy 103.512136 -216.276487) (xy 103.504008 -216.327782)
			(xy 103.487956 -216.377174) (xy 103.464375 -216.423446) (xy 103.433845 -216.46546) (xy 103.397119 -216.50218)
			(xy 103.3551 -216.532703) (xy 103.308824 -216.556277) (xy 103.259429 -216.572321) (xy 103.208133 -216.58044)
			(xy 103.182166 -216.580974) (xy 103.155131 -216.580433) (xy 103.101782 -216.57163) (xy 103.050576 -216.554266)
			(xy 103.002877 -216.528802) (xy 102.959956 -216.495918) (xy 102.922958 -216.456488) (xy 102.892866 -216.411565)
			(xy 102.870485 -216.362344) (xy 102.856409 -216.310138) (xy 102.853236 -216.283286) (xy 102.851196 -216.267961)
			(xy 102.839126 -216.239516) (xy 102.819087 -216.215994) (xy 102.792922 -216.199556) (xy 102.763033 -216.191712)
			(xy 102.747572 -216.191846) (xy 102.712012 -216.192608) (xy 102.67696 -216.191846) (xy 102.661499 -216.191678)
			(xy 102.631615 -216.199554) (xy 102.605451 -216.216003) (xy 102.585401 -216.23952) (xy 102.573298 -216.267957)
			(xy 102.571296 -216.283286) (xy 102.568083 -216.310136) (xy 102.55404 -216.362352) (xy 102.531681 -216.411584)
			(xy 102.501601 -216.456517) (xy 102.464605 -216.495951) (xy 102.421681 -216.528833) (xy 102.373974 -216.554285)
			(xy 102.322758 -216.571627) (xy 102.269402 -216.580396) (xy 102.242366 -216.580974) (xy 102.2164 -216.580462)
			(xy 102.165108 -216.572334) (xy 102.115719 -216.556282) (xy 102.069448 -216.532703) (xy 102.027435 -216.502177)
			(xy 101.990714 -216.465454) (xy 101.960189 -216.42344) (xy 101.936612 -216.377168) (xy 101.920563 -216.327779)
			(xy 101.912437 -216.276486) (xy 101.911912 -216.25052) (xy 101.912403 -216.224426) (xy 101.920602 -216.172886)
			(xy 101.936799 -216.123275) (xy 101.960592 -216.076827) (xy 101.99139 -216.034695) (xy 102.028426 -215.997927)
			(xy 102.049326 -215.982296) (xy 102.061581 -215.972838) (xy 102.080188 -215.948116) (xy 102.090562 -215.918965)
			(xy 102.091756 -215.888046) (xy 102.08366 -215.858182) (xy 102.075742 -215.844882) (xy 102.056702 -215.8144)
			(xy 102.023821 -215.750488) (xy 101.997153 -215.683744) (xy 101.976938 -215.614771) (xy 101.963359 -215.544191)
			(xy 101.956539 -215.472641) (xy 101.956108 -215.436704) (xy 101.956342 -215.408851) (xy 101.960408 -215.353295)
			(xy 101.964236 -215.325706) (xy 101.936766 -215.314604) (xy 101.883492 -215.288663) (xy 101.85781 -215.27389)
			(xy 101.849066 -215.269239) (xy 101.829494 -215.266333) (xy 101.810281 -215.271062) (xy 101.794294 -215.282721)
			(xy 101.788722 -215.290908) (xy 101.770681 -215.319442) (xy 101.730236 -215.3735) (xy 101.70795 -215.398858)
			(xy 101.695259 -215.43646) (xy 101.663065 -215.509004) (xy 101.643688 -215.543638) (xy 101.487224 -215.814656)
			(xy 101.468936 -215.844628) (xy 101.461053 -215.857936) (xy 101.45291 -215.887761) (xy 101.454043 -215.918657)
			(xy 101.464349 -215.947805) (xy 101.482887 -215.972547) (xy 101.495098 -215.982042) (xy 101.516058 -215.997665)
			(xy 101.553228 -216.034421) (xy 101.58414 -216.076576) (xy 101.608022 -216.123076) (xy 101.624276 -216.172759)
			(xy 101.632497 -216.224383) (xy 101.63302 -216.25052) (xy 101.632484 -216.277051) (xy 101.62399 -216.329428)
			(xy 101.60724 -216.379777) (xy 101.582663 -216.426804) (xy 101.550891 -216.469302) (xy 101.512739 -216.506179)
			(xy 101.469187 -216.53649) (xy 101.421353 -216.559456) (xy 101.370464 -216.574488) (xy 101.344222 -216.578434)
			(xy 101.299772 -216.584022) (xy 101.299772 -217.298524) (xy 101.300172 -217.308045) (xy 101.307135 -217.325767)
			(xy 101.320091 -217.339722) (xy 101.337248 -217.347981) (xy 101.356237 -217.349403) (xy 101.374433 -217.34379)
			(xy 101.389322 -217.33192) (xy 101.394514 -217.323924) (xy 101.468174 -217.196162) (xy 101.460554 -217.174064)
			(xy 101.451756 -217.14749) (xy 101.442299 -217.092322) (xy 101.441758 -217.064336) (xy 101.442267 -217.038369)
			(xy 101.450392 -216.987074) (xy 101.46644 -216.937681) (xy 101.490018 -216.891407) (xy 101.520544 -216.849391)
			(xy 101.557267 -216.812668) (xy 101.599283 -216.782142) (xy 101.645557 -216.758564) (xy 101.69495 -216.742516)
			(xy 101.746245 -216.734391) (xy 101.798179 -216.734391) (xy 101.849474 -216.742516) (xy 101.898867 -216.758564)
			(xy 101.945141 -216.782142) (xy 101.987157 -216.812668) (xy 102.02388 -216.849391) (xy 102.054406 -216.891407)
			(xy 102.077984 -216.937681) (xy 102.094032 -216.987074) (xy 102.102157 -217.038369) (xy 102.102666 -217.064336)
			(xy 102.102195 -217.089785) (xy 102.102115 -217.090303) (xy 102.382321 -217.090303) (xy 102.382321 -217.038369)
			(xy 102.390446 -216.987074) (xy 102.406494 -216.937681) (xy 102.430072 -216.891407) (xy 102.460598 -216.849391)
			(xy 102.497321 -216.812668) (xy 102.539337 -216.782142) (xy 102.585611 -216.758564) (xy 102.635004 -216.742516)
			(xy 102.686299 -216.734391) (xy 102.738233 -216.734391) (xy 102.789528 -216.742516) (xy 102.838921 -216.758564)
			(xy 102.885195 -216.782142) (xy 102.927211 -216.812668) (xy 102.963934 -216.849391) (xy 102.99446 -216.891407)
			(xy 103.018038 -216.937681) (xy 103.034086 -216.987074) (xy 103.042211 -217.038369) (xy 103.04272 -217.064336)
			(xy 103.042211 -217.090303) (xy 103.034086 -217.141598) (xy 103.018038 -217.190991) (xy 102.99446 -217.237265)
			(xy 102.963934 -217.279281) (xy 102.927211 -217.316004) (xy 102.885195 -217.34653) (xy 102.838921 -217.370108)
			(xy 102.789528 -217.386156) (xy 102.738233 -217.394281) (xy 102.686299 -217.394281) (xy 102.635004 -217.386156)
			(xy 102.585611 -217.370108) (xy 102.539337 -217.34653) (xy 102.497321 -217.316004) (xy 102.460598 -217.279281)
			(xy 102.430072 -217.237265) (xy 102.406494 -217.190991) (xy 102.390446 -217.141598) (xy 102.382321 -217.090303)
			(xy 102.102115 -217.090303) (xy 102.09439 -217.140083) (xy 102.07897 -217.18859) (xy 102.056298 -217.234161)
			(xy 102.026912 -217.27572) (xy 101.991504 -217.312284) (xy 101.950911 -217.342992) (xy 101.906092 -217.367116)
			(xy 101.858106 -217.384087) (xy 101.833172 -217.389202) (xy 101.810312 -217.39352) (xy 101.606604 -217.74658)
			(xy 101.614224 -217.768678) (xy 101.623016 -217.795252) (xy 101.632465 -217.85042) (xy 101.63302 -217.878406)
			(xy 101.911912 -217.878406) (xy 101.912421 -217.852439) (xy 101.920546 -217.801144) (xy 101.936594 -217.751751)
			(xy 101.960172 -217.705477) (xy 101.990698 -217.663461) (xy 102.027421 -217.626738) (xy 102.069437 -217.596212)
			(xy 102.115711 -217.572634) (xy 102.165104 -217.556586) (xy 102.216399 -217.548461) (xy 102.268333 -217.548461)
			(xy 102.319628 -217.556586) (xy 102.369021 -217.572634) (xy 102.415295 -217.596212) (xy 102.457311 -217.626738)
			(xy 102.494034 -217.663461) (xy 102.52456 -217.705477) (xy 102.548138 -217.751751) (xy 102.564186 -217.801144)
			(xy 102.572311 -217.852439) (xy 102.57282 -217.878406) (xy 102.851712 -217.878406) (xy 102.852233 -217.852957)
			(xy 102.860009 -217.802656) (xy 102.875409 -217.754143) (xy 102.898068 -217.708567) (xy 102.92745 -217.667006)
			(xy 102.962859 -217.630444) (xy 103.003458 -217.599746) (xy 103.048285 -217.575639) (xy 103.09628 -217.558693)
			(xy 103.121206 -217.55354) (xy 103.144066 -217.549222) (xy 103.347774 -217.196162) (xy 103.340154 -217.174064)
			(xy 103.331409 -217.147478) (xy 103.321966 -217.092317) (xy 103.321358 -217.064336) (xy 103.321867 -217.038369)
			(xy 103.329992 -216.987074) (xy 103.34604 -216.937681) (xy 103.369618 -216.891407) (xy 103.400144 -216.849391)
			(xy 103.436867 -216.812668) (xy 103.478883 -216.782142) (xy 103.525157 -216.758564) (xy 103.57455 -216.742516)
			(xy 103.625845 -216.734391) (xy 103.677779 -216.734391) (xy 103.729074 -216.742516) (xy 103.778467 -216.758564)
			(xy 103.824741 -216.782142) (xy 103.866757 -216.812668) (xy 103.90348 -216.849391) (xy 103.934006 -216.891407)
			(xy 103.957584 -216.937681) (xy 103.973632 -216.987074) (xy 103.981757 -217.038369) (xy 103.982266 -217.064336)
			(xy 103.981802 -217.089788) (xy 103.981722 -217.090303) (xy 104.261921 -217.090303) (xy 104.261921 -217.038369)
			(xy 104.270046 -216.987074) (xy 104.286094 -216.937681) (xy 104.309672 -216.891407) (xy 104.340198 -216.849391)
			(xy 104.376921 -216.812668) (xy 104.418937 -216.782142) (xy 104.465211 -216.758564) (xy 104.514604 -216.742516)
			(xy 104.565899 -216.734391) (xy 104.617833 -216.734391) (xy 104.669128 -216.742516) (xy 104.718521 -216.758564)
			(xy 104.764795 -216.782142) (xy 104.806811 -216.812668) (xy 104.843534 -216.849391) (xy 104.87406 -216.891407)
			(xy 104.897638 -216.937681) (xy 104.913686 -216.987074) (xy 104.921811 -217.038369) (xy 104.92232 -217.064336)
			(xy 104.921811 -217.090303) (xy 104.913686 -217.141598) (xy 104.897638 -217.190991) (xy 104.87406 -217.237265)
			(xy 104.843534 -217.279281) (xy 104.806811 -217.316004) (xy 104.764795 -217.34653) (xy 104.718521 -217.370108)
			(xy 104.669128 -217.386156) (xy 104.617833 -217.394281) (xy 104.565899 -217.394281) (xy 104.514604 -217.386156)
			(xy 104.465211 -217.370108) (xy 104.418937 -217.34653) (xy 104.376921 -217.316004) (xy 104.340198 -217.279281)
			(xy 104.309672 -217.237265) (xy 104.286094 -217.190991) (xy 104.270046 -217.141598) (xy 104.261921 -217.090303)
			(xy 103.981722 -217.090303) (xy 103.974019 -217.140092) (xy 103.958612 -217.188607) (xy 103.935946 -217.234184)
			(xy 103.906557 -217.275746) (xy 103.87114 -217.312307) (xy 103.830535 -217.343004) (xy 103.785701 -217.367108)
			(xy 103.737701 -217.384051) (xy 103.712772 -217.389202) (xy 103.689912 -217.39352) (xy 103.486204 -217.74658)
			(xy 103.493824 -217.768678) (xy 103.502557 -217.795268) (xy 103.512007 -217.850426) (xy 103.51262 -217.878406)
			(xy 103.791512 -217.878406) (xy 103.792021 -217.852439) (xy 103.800146 -217.801144) (xy 103.816194 -217.751751)
			(xy 103.839772 -217.705477) (xy 103.870298 -217.663461) (xy 103.907021 -217.626738) (xy 103.949037 -217.596212)
			(xy 103.995311 -217.572634) (xy 104.044704 -217.556586) (xy 104.095999 -217.548461) (xy 104.147933 -217.548461)
			(xy 104.199228 -217.556586) (xy 104.248621 -217.572634) (xy 104.294895 -217.596212) (xy 104.336911 -217.626738)
			(xy 104.373634 -217.663461) (xy 104.40416 -217.705477) (xy 104.427738 -217.751751) (xy 104.443786 -217.801144)
			(xy 104.451911 -217.852439) (xy 104.45242 -217.878406) (xy 104.731312 -217.878406) (xy 104.731833 -217.852957)
			(xy 104.739609 -217.802656) (xy 104.755009 -217.754143) (xy 104.777668 -217.708567) (xy 104.80705 -217.667006)
			(xy 104.842459 -217.630444) (xy 104.883058 -217.599746) (xy 104.927885 -217.575639) (xy 104.97588 -217.558693)
			(xy 105.000806 -217.55354) (xy 105.023666 -217.549222) (xy 105.227374 -217.196162) (xy 105.219754 -217.174064)
			(xy 105.211009 -217.147478) (xy 105.201566 -217.092317) (xy 105.200958 -217.064336) (xy 105.201467 -217.038369)
			(xy 105.209592 -216.987074) (xy 105.22564 -216.937681) (xy 105.249218 -216.891407) (xy 105.279744 -216.849391)
			(xy 105.316467 -216.812668) (xy 105.358483 -216.782142) (xy 105.404757 -216.758564) (xy 105.45415 -216.742516)
			(xy 105.505445 -216.734391) (xy 105.557379 -216.734391) (xy 105.608674 -216.742516) (xy 105.658067 -216.758564)
			(xy 105.704341 -216.782142) (xy 105.746357 -216.812668) (xy 105.78308 -216.849391) (xy 105.813606 -216.891407)
			(xy 105.837184 -216.937681) (xy 105.853232 -216.987074) (xy 105.861357 -217.038369) (xy 105.861866 -217.064336)
			(xy 105.861402 -217.089788) (xy 105.861322 -217.090303) (xy 106.141521 -217.090303) (xy 106.141521 -217.038369)
			(xy 106.149646 -216.987074) (xy 106.165694 -216.937681) (xy 106.189272 -216.891407) (xy 106.219798 -216.849391)
			(xy 106.256521 -216.812668) (xy 106.298537 -216.782142) (xy 106.344811 -216.758564) (xy 106.394204 -216.742516)
			(xy 106.445499 -216.734391) (xy 106.497433 -216.734391) (xy 106.548728 -216.742516) (xy 106.598121 -216.758564)
			(xy 106.644395 -216.782142) (xy 106.686411 -216.812668) (xy 106.723134 -216.849391) (xy 106.75366 -216.891407)
			(xy 106.777238 -216.937681) (xy 106.793286 -216.987074) (xy 106.801411 -217.038369) (xy 106.80192 -217.064336)
			(xy 106.801411 -217.090303) (xy 106.793286 -217.141598) (xy 106.777238 -217.190991) (xy 106.75366 -217.237265)
			(xy 106.723134 -217.279281) (xy 106.686411 -217.316004) (xy 106.644395 -217.34653) (xy 106.598121 -217.370108)
			(xy 106.548728 -217.386156) (xy 106.497433 -217.394281) (xy 106.445499 -217.394281) (xy 106.394204 -217.386156)
			(xy 106.344811 -217.370108) (xy 106.298537 -217.34653) (xy 106.256521 -217.316004) (xy 106.219798 -217.279281)
			(xy 106.189272 -217.237265) (xy 106.165694 -217.190991) (xy 106.149646 -217.141598) (xy 106.141521 -217.090303)
			(xy 105.861322 -217.090303) (xy 105.853619 -217.140092) (xy 105.838212 -217.188607) (xy 105.815546 -217.234184)
			(xy 105.786157 -217.275746) (xy 105.75074 -217.312307) (xy 105.710135 -217.343004) (xy 105.665301 -217.367108)
			(xy 105.617301 -217.384051) (xy 105.592372 -217.389202) (xy 105.569512 -217.39352) (xy 105.365804 -217.74658)
			(xy 105.373424 -217.768678) (xy 105.382157 -217.795268) (xy 105.391607 -217.850426) (xy 105.39222 -217.878406)
			(xy 105.671112 -217.878406) (xy 105.671621 -217.852439) (xy 105.679746 -217.801144) (xy 105.695794 -217.751751)
			(xy 105.719372 -217.705477) (xy 105.749898 -217.663461) (xy 105.786621 -217.626738) (xy 105.828637 -217.596212)
			(xy 105.874911 -217.572634) (xy 105.924304 -217.556586) (xy 105.975599 -217.548461) (xy 106.027533 -217.548461)
			(xy 106.078828 -217.556586) (xy 106.128221 -217.572634) (xy 106.174495 -217.596212) (xy 106.216511 -217.626738)
			(xy 106.253234 -217.663461) (xy 106.28376 -217.705477) (xy 106.307338 -217.751751) (xy 106.323386 -217.801144)
			(xy 106.331511 -217.852439) (xy 106.33202 -217.878406) (xy 106.610912 -217.878406) (xy 106.611433 -217.852957)
			(xy 106.619209 -217.802656) (xy 106.634609 -217.754143) (xy 106.657268 -217.708567) (xy 106.68665 -217.667006)
			(xy 106.722059 -217.630444) (xy 106.762658 -217.599746) (xy 106.807485 -217.575639) (xy 106.85548 -217.558693)
			(xy 106.880406 -217.55354) (xy 106.903266 -217.549222) (xy 107.106974 -217.196162) (xy 107.099354 -217.174064)
			(xy 107.090609 -217.147478) (xy 107.081166 -217.092317) (xy 107.080558 -217.064336) (xy 107.081067 -217.038369)
			(xy 107.089192 -216.987074) (xy 107.10524 -216.937681) (xy 107.128818 -216.891407) (xy 107.159344 -216.849391)
			(xy 107.196067 -216.812668) (xy 107.238083 -216.782142) (xy 107.284357 -216.758564) (xy 107.33375 -216.742516)
			(xy 107.385045 -216.734391) (xy 107.436979 -216.734391) (xy 107.488274 -216.742516) (xy 107.537667 -216.758564)
			(xy 107.583941 -216.782142) (xy 107.625957 -216.812668) (xy 107.66268 -216.849391) (xy 107.693206 -216.891407)
			(xy 107.716784 -216.937681) (xy 107.732832 -216.987074) (xy 107.740957 -217.038369) (xy 107.741466 -217.064336)
			(xy 107.741002 -217.089788) (xy 107.740922 -217.090303) (xy 108.021121 -217.090303) (xy 108.021121 -217.038369)
			(xy 108.029246 -216.987074) (xy 108.045294 -216.937681) (xy 108.068872 -216.891407) (xy 108.099398 -216.849391)
			(xy 108.136121 -216.812668) (xy 108.178137 -216.782142) (xy 108.224411 -216.758564) (xy 108.273804 -216.742516)
			(xy 108.325099 -216.734391) (xy 108.377033 -216.734391) (xy 108.428328 -216.742516) (xy 108.477721 -216.758564)
			(xy 108.523995 -216.782142) (xy 108.566011 -216.812668) (xy 108.602734 -216.849391) (xy 108.63326 -216.891407)
			(xy 108.656838 -216.937681) (xy 108.672886 -216.987074) (xy 108.681011 -217.038369) (xy 108.68152 -217.064336)
			(xy 108.681011 -217.090303) (xy 108.672886 -217.141598) (xy 108.656838 -217.190991) (xy 108.63326 -217.237265)
			(xy 108.602734 -217.279281) (xy 108.566011 -217.316004) (xy 108.523995 -217.34653) (xy 108.477721 -217.370108)
			(xy 108.428328 -217.386156) (xy 108.377033 -217.394281) (xy 108.325099 -217.394281) (xy 108.273804 -217.386156)
			(xy 108.224411 -217.370108) (xy 108.178137 -217.34653) (xy 108.136121 -217.316004) (xy 108.099398 -217.279281)
			(xy 108.068872 -217.237265) (xy 108.045294 -217.190991) (xy 108.029246 -217.141598) (xy 108.021121 -217.090303)
			(xy 107.740922 -217.090303) (xy 107.733219 -217.140092) (xy 107.717812 -217.188607) (xy 107.695146 -217.234184)
			(xy 107.665757 -217.275746) (xy 107.63034 -217.312307) (xy 107.589735 -217.343004) (xy 107.544901 -217.367108)
			(xy 107.496901 -217.384051) (xy 107.471972 -217.389202) (xy 107.449112 -217.39352) (xy 107.245404 -217.74658)
			(xy 107.253024 -217.768678) (xy 107.261757 -217.795268) (xy 107.271207 -217.850426) (xy 107.27182 -217.878406)
			(xy 107.550712 -217.878406) (xy 107.551221 -217.852439) (xy 107.559346 -217.801144) (xy 107.575394 -217.751751)
			(xy 107.598972 -217.705477) (xy 107.629498 -217.663461) (xy 107.666221 -217.626738) (xy 107.708237 -217.596212)
			(xy 107.754511 -217.572634) (xy 107.803904 -217.556586) (xy 107.855199 -217.548461) (xy 107.907133 -217.548461)
			(xy 107.958428 -217.556586) (xy 108.007821 -217.572634) (xy 108.054095 -217.596212) (xy 108.096111 -217.626738)
			(xy 108.132834 -217.663461) (xy 108.16336 -217.705477) (xy 108.186938 -217.751751) (xy 108.202986 -217.801144)
			(xy 108.211111 -217.852439) (xy 108.21162 -217.878406) (xy 108.490512 -217.878406) (xy 108.491033 -217.852957)
			(xy 108.498809 -217.802656) (xy 108.514209 -217.754143) (xy 108.536868 -217.708567) (xy 108.56625 -217.667006)
			(xy 108.601659 -217.630444) (xy 108.642258 -217.599746) (xy 108.687085 -217.575639) (xy 108.73508 -217.558693)
			(xy 108.760006 -217.55354) (xy 108.782866 -217.549222) (xy 108.986574 -217.196162) (xy 108.978954 -217.174064)
			(xy 108.970209 -217.147478) (xy 108.960766 -217.092317) (xy 108.960158 -217.064336) (xy 108.960667 -217.038369)
			(xy 108.968792 -216.987074) (xy 108.98484 -216.937681) (xy 109.008418 -216.891407) (xy 109.038944 -216.849391)
			(xy 109.075667 -216.812668) (xy 109.117683 -216.782142) (xy 109.163957 -216.758564) (xy 109.21335 -216.742516)
			(xy 109.264645 -216.734391) (xy 109.316579 -216.734391) (xy 109.367874 -216.742516) (xy 109.417267 -216.758564)
			(xy 109.463541 -216.782142) (xy 109.505557 -216.812668) (xy 109.54228 -216.849391) (xy 109.572806 -216.891407)
			(xy 109.596384 -216.937681) (xy 109.612432 -216.987074) (xy 109.620557 -217.038369) (xy 109.621066 -217.064336)
			(xy 109.620602 -217.089788) (xy 109.620522 -217.090303) (xy 109.900721 -217.090303) (xy 109.900721 -217.038369)
			(xy 109.908846 -216.987074) (xy 109.924894 -216.937681) (xy 109.948472 -216.891407) (xy 109.978998 -216.849391)
			(xy 110.015721 -216.812668) (xy 110.057737 -216.782142) (xy 110.104011 -216.758564) (xy 110.153404 -216.742516)
			(xy 110.204699 -216.734391) (xy 110.256633 -216.734391) (xy 110.307928 -216.742516) (xy 110.357321 -216.758564)
			(xy 110.403595 -216.782142) (xy 110.445611 -216.812668) (xy 110.482334 -216.849391) (xy 110.51286 -216.891407)
			(xy 110.536438 -216.937681) (xy 110.552486 -216.987074) (xy 110.560611 -217.038369) (xy 110.56112 -217.064336)
			(xy 110.560611 -217.090303) (xy 110.552486 -217.141598) (xy 110.536438 -217.190991) (xy 110.51286 -217.237265)
			(xy 110.482334 -217.279281) (xy 110.445611 -217.316004) (xy 110.403595 -217.34653) (xy 110.357321 -217.370108)
			(xy 110.307928 -217.386156) (xy 110.256633 -217.394281) (xy 110.204699 -217.394281) (xy 110.153404 -217.386156)
			(xy 110.104011 -217.370108) (xy 110.057737 -217.34653) (xy 110.015721 -217.316004) (xy 109.978998 -217.279281)
			(xy 109.948472 -217.237265) (xy 109.924894 -217.190991) (xy 109.908846 -217.141598) (xy 109.900721 -217.090303)
			(xy 109.620522 -217.090303) (xy 109.612819 -217.140092) (xy 109.597412 -217.188607) (xy 109.574746 -217.234184)
			(xy 109.545357 -217.275746) (xy 109.50994 -217.312307) (xy 109.469335 -217.343004) (xy 109.424501 -217.367108)
			(xy 109.376501 -217.384051) (xy 109.351572 -217.389202) (xy 109.328712 -217.39352) (xy 109.125004 -217.74658)
			(xy 109.132624 -217.768678) (xy 109.141357 -217.795268) (xy 109.150807 -217.850426) (xy 109.15142 -217.878406)
			(xy 109.430312 -217.878406) (xy 109.430821 -217.852439) (xy 109.438946 -217.801144) (xy 109.454994 -217.751751)
			(xy 109.478572 -217.705477) (xy 109.509098 -217.663461) (xy 109.545821 -217.626738) (xy 109.587837 -217.596212)
			(xy 109.634111 -217.572634) (xy 109.683504 -217.556586) (xy 109.734799 -217.548461) (xy 109.786733 -217.548461)
			(xy 109.838028 -217.556586) (xy 109.887421 -217.572634) (xy 109.933695 -217.596212) (xy 109.975711 -217.626738)
			(xy 110.012434 -217.663461) (xy 110.04296 -217.705477) (xy 110.066538 -217.751751) (xy 110.082586 -217.801144)
			(xy 110.090711 -217.852439) (xy 110.09122 -217.878406) (xy 110.090584 -217.906322) (xy 110.081141 -217.961352)
			(xy 110.072424 -217.98788) (xy 110.064804 -218.009978) (xy 110.268766 -218.363038) (xy 110.291626 -218.367356)
			(xy 110.316543 -218.372543) (xy 110.364527 -218.389505) (xy 110.409344 -218.41362) (xy 110.449937 -218.444318)
			(xy 110.485346 -218.480873) (xy 110.514735 -218.522423) (xy 110.53741 -218.567986) (xy 110.552835 -218.616485)
			(xy 110.560646 -218.666776) (xy 110.56112 -218.692222) (xy 110.560611 -218.718189) (xy 110.552486 -218.769484)
			(xy 110.536438 -218.818877) (xy 110.51286 -218.865151) (xy 110.482334 -218.907167) (xy 110.445611 -218.94389)
			(xy 110.403595 -218.974416) (xy 110.357321 -218.997994) (xy 110.307928 -219.014042) (xy 110.256633 -219.022167)
			(xy 110.204699 -219.022167) (xy 110.153404 -219.014042) (xy 110.104011 -218.997994) (xy 110.057737 -218.974416)
			(xy 110.015721 -218.94389) (xy 109.978998 -218.907167) (xy 109.948472 -218.865151) (xy 109.924894 -218.818877)
			(xy 109.908846 -218.769484) (xy 109.900721 -218.718189) (xy 109.900212 -218.692222) (xy 109.90077 -218.664236)
			(xy 109.910216 -218.609069) (xy 109.919008 -218.582494) (xy 109.926628 -218.560396) (xy 109.723174 -218.20759)
			(xy 109.70006 -218.203272) (xy 109.675122 -218.198118) (xy 109.627095 -218.181193) (xy 109.582233 -218.157101)
			(xy 109.541598 -218.126413) (xy 109.50615 -218.089856) (xy 109.476729 -218.048294) (xy 109.454031 -218.002711)
			(xy 109.438594 -217.954186) (xy 109.430782 -217.903867) (xy 109.430312 -217.878406) (xy 109.15142 -217.878406)
			(xy 109.150911 -217.904373) (xy 109.142786 -217.955668) (xy 109.126738 -218.005061) (xy 109.10316 -218.051335)
			(xy 109.072634 -218.093351) (xy 109.035911 -218.130074) (xy 108.993895 -218.1606) (xy 108.947621 -218.184178)
			(xy 108.898228 -218.200226) (xy 108.846933 -218.208351) (xy 108.794999 -218.208351) (xy 108.743704 -218.200226)
			(xy 108.694311 -218.184178) (xy 108.648037 -218.1606) (xy 108.606021 -218.130074) (xy 108.569298 -218.093351)
			(xy 108.538772 -218.051335) (xy 108.515194 -218.005061) (xy 108.499146 -217.955668) (xy 108.491021 -217.904373)
			(xy 108.490512 -217.878406) (xy 108.21162 -217.878406) (xy 108.211068 -217.906392) (xy 108.201617 -217.96156)
			(xy 108.192824 -217.988134) (xy 108.185204 -218.010232) (xy 108.388912 -218.363038) (xy 108.411772 -218.367356)
			(xy 108.436696 -218.37251) (xy 108.48468 -218.389479) (xy 108.529496 -218.413599) (xy 108.570088 -218.444302)
			(xy 108.605496 -218.480861) (xy 108.634884 -218.522415) (xy 108.657557 -218.56798) (xy 108.672982 -218.616482)
			(xy 108.680792 -218.666774) (xy 108.681266 -218.692222) (xy 108.680757 -218.718189) (xy 108.672632 -218.769484)
			(xy 108.656584 -218.818877) (xy 108.633006 -218.865151) (xy 108.60248 -218.907167) (xy 108.565757 -218.94389)
			(xy 108.523741 -218.974416) (xy 108.477467 -218.997994) (xy 108.428074 -219.014042) (xy 108.376779 -219.022167)
			(xy 108.324845 -219.022167) (xy 108.27355 -219.014042) (xy 108.224157 -218.997994) (xy 108.177883 -218.974416)
			(xy 108.135867 -218.94389) (xy 108.099144 -218.907167) (xy 108.068618 -218.865151) (xy 108.04504 -218.818877)
			(xy 108.028992 -218.769484) (xy 108.020867 -218.718189) (xy 108.020358 -218.692222) (xy 108.020913 -218.664236)
			(xy 108.030361 -218.609068) (xy 108.039154 -218.582494) (xy 108.046774 -218.560396) (xy 107.843066 -218.20759)
			(xy 107.820206 -218.203272) (xy 107.7953 -218.198035) (xy 107.747319 -218.18108) (xy 107.702502 -218.156972)
			(xy 107.661909 -218.12628) (xy 107.626499 -218.089731) (xy 107.597108 -218.048187) (xy 107.574431 -218.00263)
			(xy 107.559003 -217.954136) (xy 107.551188 -217.90385) (xy 107.550712 -217.878406) (xy 107.27182 -217.878406)
			(xy 107.271311 -217.904373) (xy 107.263186 -217.955668) (xy 107.247138 -218.005061) (xy 107.22356 -218.051335)
			(xy 107.193034 -218.093351) (xy 107.156311 -218.130074) (xy 107.114295 -218.1606) (xy 107.068021 -218.184178)
			(xy 107.018628 -218.200226) (xy 106.967333 -218.208351) (xy 106.915399 -218.208351) (xy 106.864104 -218.200226)
			(xy 106.814711 -218.184178) (xy 106.768437 -218.1606) (xy 106.726421 -218.130074) (xy 106.689698 -218.093351)
			(xy 106.659172 -218.051335) (xy 106.635594 -218.005061) (xy 106.619546 -217.955668) (xy 106.611421 -217.904373)
			(xy 106.610912 -217.878406) (xy 106.33202 -217.878406) (xy 106.331468 -217.906392) (xy 106.322017 -217.96156)
			(xy 106.313224 -217.988134) (xy 106.305604 -218.010232) (xy 106.509312 -218.363038) (xy 106.532172 -218.367356)
			(xy 106.557096 -218.37251) (xy 106.60508 -218.389479) (xy 106.649896 -218.413599) (xy 106.690488 -218.444302)
			(xy 106.725896 -218.480861) (xy 106.755284 -218.522415) (xy 106.777957 -218.56798) (xy 106.793382 -218.616482)
			(xy 106.801192 -218.666774) (xy 106.801666 -218.692222) (xy 106.801157 -218.718189) (xy 106.793032 -218.769484)
			(xy 106.776984 -218.818877) (xy 106.753406 -218.865151) (xy 106.72288 -218.907167) (xy 106.686157 -218.94389)
			(xy 106.644141 -218.974416) (xy 106.597867 -218.997994) (xy 106.548474 -219.014042) (xy 106.497179 -219.022167)
			(xy 106.445245 -219.022167) (xy 106.39395 -219.014042) (xy 106.344557 -218.997994) (xy 106.298283 -218.974416)
			(xy 106.256267 -218.94389) (xy 106.219544 -218.907167) (xy 106.189018 -218.865151) (xy 106.16544 -218.818877)
			(xy 106.149392 -218.769484) (xy 106.141267 -218.718189) (xy 106.140758 -218.692222) (xy 106.141313 -218.664236)
			(xy 106.150761 -218.609068) (xy 106.159554 -218.582494) (xy 106.167174 -218.560396) (xy 105.963466 -218.20759)
			(xy 105.940606 -218.203272) (xy 105.9157 -218.198035) (xy 105.867719 -218.18108) (xy 105.822902 -218.156972)
			(xy 105.782309 -218.12628) (xy 105.746899 -218.089731) (xy 105.717508 -218.048187) (xy 105.694831 -218.00263)
			(xy 105.679403 -217.954136) (xy 105.671588 -217.90385) (xy 105.671112 -217.878406) (xy 105.39222 -217.878406)
			(xy 105.391711 -217.904373) (xy 105.383586 -217.955668) (xy 105.367538 -218.005061) (xy 105.34396 -218.051335)
			(xy 105.313434 -218.093351) (xy 105.276711 -218.130074) (xy 105.234695 -218.1606) (xy 105.188421 -218.184178)
			(xy 105.139028 -218.200226) (xy 105.087733 -218.208351) (xy 105.035799 -218.208351) (xy 104.984504 -218.200226)
			(xy 104.935111 -218.184178) (xy 104.888837 -218.1606) (xy 104.846821 -218.130074) (xy 104.810098 -218.093351)
			(xy 104.779572 -218.051335) (xy 104.755994 -218.005061) (xy 104.739946 -217.955668) (xy 104.731821 -217.904373)
			(xy 104.731312 -217.878406) (xy 104.45242 -217.878406) (xy 104.451868 -217.906392) (xy 104.442417 -217.96156)
			(xy 104.433624 -217.988134) (xy 104.426004 -218.010232) (xy 104.629712 -218.363038) (xy 104.652572 -218.367356)
			(xy 104.677496 -218.37251) (xy 104.72548 -218.389479) (xy 104.770296 -218.413599) (xy 104.810888 -218.444302)
			(xy 104.846296 -218.480861) (xy 104.875684 -218.522415) (xy 104.898357 -218.56798) (xy 104.913782 -218.616482)
			(xy 104.921592 -218.666774) (xy 104.922066 -218.692222) (xy 104.921557 -218.718189) (xy 104.913432 -218.769484)
			(xy 104.897384 -218.818877) (xy 104.873806 -218.865151) (xy 104.84328 -218.907167) (xy 104.806557 -218.94389)
			(xy 104.764541 -218.974416) (xy 104.718267 -218.997994) (xy 104.668874 -219.014042) (xy 104.617579 -219.022167)
			(xy 104.565645 -219.022167) (xy 104.51435 -219.014042) (xy 104.464957 -218.997994) (xy 104.418683 -218.974416)
			(xy 104.376667 -218.94389) (xy 104.339944 -218.907167) (xy 104.309418 -218.865151) (xy 104.28584 -218.818877)
			(xy 104.269792 -218.769484) (xy 104.261667 -218.718189) (xy 104.261158 -218.692222) (xy 104.261713 -218.664236)
			(xy 104.271161 -218.609068) (xy 104.279954 -218.582494) (xy 104.287574 -218.560396) (xy 104.083866 -218.20759)
			(xy 104.061006 -218.203272) (xy 104.0361 -218.198035) (xy 103.988119 -218.18108) (xy 103.943302 -218.156972)
			(xy 103.902709 -218.12628) (xy 103.867299 -218.089731) (xy 103.837908 -218.048187) (xy 103.815231 -218.00263)
			(xy 103.799803 -217.954136) (xy 103.791988 -217.90385) (xy 103.791512 -217.878406) (xy 103.51262 -217.878406)
			(xy 103.512111 -217.904373) (xy 103.503986 -217.955668) (xy 103.487938 -218.005061) (xy 103.46436 -218.051335)
			(xy 103.433834 -218.093351) (xy 103.397111 -218.130074) (xy 103.355095 -218.1606) (xy 103.308821 -218.184178)
			(xy 103.259428 -218.200226) (xy 103.208133 -218.208351) (xy 103.156199 -218.208351) (xy 103.104904 -218.200226)
			(xy 103.055511 -218.184178) (xy 103.009237 -218.1606) (xy 102.967221 -218.130074) (xy 102.930498 -218.093351)
			(xy 102.899972 -218.051335) (xy 102.876394 -218.005061) (xy 102.860346 -217.955668) (xy 102.852221 -217.904373)
			(xy 102.851712 -217.878406) (xy 102.57282 -217.878406) (xy 102.572268 -217.906392) (xy 102.562817 -217.96156)
			(xy 102.554024 -217.988134) (xy 102.546404 -218.010232) (xy 102.750112 -218.363038) (xy 102.772972 -218.367356)
			(xy 102.797896 -218.37251) (xy 102.84588 -218.389479) (xy 102.890696 -218.413599) (xy 102.931288 -218.444302)
			(xy 102.966696 -218.480861) (xy 102.996084 -218.522415) (xy 103.018757 -218.56798) (xy 103.034182 -218.616482)
			(xy 103.041992 -218.666774) (xy 103.042466 -218.692222) (xy 103.041957 -218.718189) (xy 103.033832 -218.769484)
			(xy 103.017784 -218.818877) (xy 102.994206 -218.865151) (xy 102.96368 -218.907167) (xy 102.926957 -218.94389)
			(xy 102.884941 -218.974416) (xy 102.838667 -218.997994) (xy 102.789274 -219.014042) (xy 102.737979 -219.022167)
			(xy 102.686045 -219.022167) (xy 102.63475 -219.014042) (xy 102.585357 -218.997994) (xy 102.539083 -218.974416)
			(xy 102.497067 -218.94389) (xy 102.460344 -218.907167) (xy 102.429818 -218.865151) (xy 102.40624 -218.818877)
			(xy 102.390192 -218.769484) (xy 102.382067 -218.718189) (xy 102.381558 -218.692222) (xy 102.382113 -218.664236)
			(xy 102.391561 -218.609068) (xy 102.400354 -218.582494) (xy 102.407974 -218.560396) (xy 102.204266 -218.20759)
			(xy 102.181406 -218.203272) (xy 102.1565 -218.198035) (xy 102.108519 -218.18108) (xy 102.063702 -218.156972)
			(xy 102.023109 -218.12628) (xy 101.987699 -218.089731) (xy 101.958308 -218.048187) (xy 101.935631 -218.00263)
			(xy 101.920203 -217.954136) (xy 101.912388 -217.90385) (xy 101.911912 -217.878406) (xy 101.63302 -217.878406)
			(xy 101.632485 -217.904937) (xy 101.623993 -217.957317) (xy 101.607244 -218.007667) (xy 101.582668 -218.054696)
			(xy 101.550896 -218.097196) (xy 101.512744 -218.134075) (xy 101.469191 -218.164388) (xy 101.421356 -218.187355)
			(xy 101.370467 -218.202387) (xy 101.344222 -218.20632) (xy 101.299772 -218.211908) (xy 101.299772 -219.172536)
			(xy 101.344222 -219.178124) (xy 101.370329 -219.181959) (xy 101.420952 -219.19684) (xy 101.468566 -219.219578)
			(xy 101.511962 -219.249594) (xy 101.550035 -219.286125) (xy 101.581819 -219.328243) (xy 101.606505 -219.374877)
			(xy 101.623465 -219.424842) (xy 101.63227 -219.476867) (xy 101.63302 -219.503244) (xy 101.633579 -219.516471)
			(xy 101.640648 -219.541973) (xy 101.654038 -219.564799) (xy 101.672848 -219.583413) (xy 101.695813 -219.596563)
			(xy 101.721388 -219.603365) (xy 101.73462 -219.603828) (xy 101.75113 -219.603828) (xy 101.762925 -219.611759)
			(xy 101.789653 -219.621394) (xy 101.818001 -219.623296) (xy 101.845776 -219.617318) (xy 101.870831 -219.603922)
			(xy 101.891228 -219.584143) (xy 101.905389 -219.559513) (xy 101.91222 -219.531935) (xy 101.912166 -219.517722)
			(xy 101.911912 -219.506038) (xy 101.912392 -219.480065) (xy 101.920513 -219.428757) (xy 101.93656 -219.379352)
			(xy 101.960139 -219.333065) (xy 101.990669 -219.291037) (xy 102.027397 -219.254302) (xy 102.069421 -219.223766)
			(xy 102.115704 -219.20018) (xy 102.165106 -219.184125) (xy 102.216413 -219.175996) (xy 102.268359 -219.175994)
			(xy 102.319666 -219.184118) (xy 102.369071 -219.200169) (xy 102.415356 -219.223751) (xy 102.457381 -219.254284)
			(xy 102.494113 -219.291016) (xy 102.524646 -219.333041) (xy 102.548229 -219.379326) (xy 102.564281 -219.42873)
			(xy 102.572406 -219.480037) (xy 102.572404 -219.531983) (xy 102.572401 -219.532005) (xy 102.852221 -219.532005)
			(xy 102.852221 -219.480071) (xy 102.860346 -219.428776) (xy 102.876394 -219.379383) (xy 102.899972 -219.333109)
			(xy 102.930498 -219.291093) (xy 102.967221 -219.25437) (xy 103.009237 -219.223844) (xy 103.055511 -219.200266)
			(xy 103.104904 -219.184218) (xy 103.156199 -219.176093) (xy 103.208133 -219.176093) (xy 103.259428 -219.184218)
			(xy 103.308821 -219.200266) (xy 103.355095 -219.223844) (xy 103.397111 -219.25437) (xy 103.433834 -219.291093)
			(xy 103.46436 -219.333109) (xy 103.487938 -219.379383) (xy 103.503986 -219.428776) (xy 103.512111 -219.480071)
			(xy 103.51262 -219.506038) (xy 103.512111 -219.532005) (xy 103.792021 -219.532005) (xy 103.792021 -219.480071)
			(xy 103.800146 -219.428776) (xy 103.816194 -219.379383) (xy 103.839772 -219.333109) (xy 103.870298 -219.291093)
			(xy 103.907021 -219.25437) (xy 103.949037 -219.223844) (xy 103.995311 -219.200266) (xy 104.044704 -219.184218)
			(xy 104.095999 -219.176093) (xy 104.147933 -219.176093) (xy 104.199228 -219.184218) (xy 104.248621 -219.200266)
			(xy 104.294895 -219.223844) (xy 104.336911 -219.25437) (xy 104.373634 -219.291093) (xy 104.40416 -219.333109)
			(xy 104.427738 -219.379383) (xy 104.443786 -219.428776) (xy 104.451911 -219.480071) (xy 104.45242 -219.506038)
			(xy 104.451911 -219.532005) (xy 104.731821 -219.532005) (xy 104.731821 -219.480071) (xy 104.739946 -219.428776)
			(xy 104.755994 -219.379383) (xy 104.779572 -219.333109) (xy 104.810098 -219.291093) (xy 104.846821 -219.25437)
			(xy 104.888837 -219.223844) (xy 104.935111 -219.200266) (xy 104.984504 -219.184218) (xy 105.035799 -219.176093)
			(xy 105.087733 -219.176093) (xy 105.139028 -219.184218) (xy 105.188421 -219.200266) (xy 105.234695 -219.223844)
			(xy 105.276711 -219.25437) (xy 105.313434 -219.291093) (xy 105.34396 -219.333109) (xy 105.367538 -219.379383)
			(xy 105.383586 -219.428776) (xy 105.391711 -219.480071) (xy 105.39222 -219.506038) (xy 105.391711 -219.532005)
			(xy 105.671621 -219.532005) (xy 105.671621 -219.480071) (xy 105.679746 -219.428776) (xy 105.695794 -219.379383)
			(xy 105.719372 -219.333109) (xy 105.749898 -219.291093) (xy 105.786621 -219.25437) (xy 105.828637 -219.223844)
			(xy 105.874911 -219.200266) (xy 105.924304 -219.184218) (xy 105.975599 -219.176093) (xy 106.027533 -219.176093)
			(xy 106.078828 -219.184218) (xy 106.128221 -219.200266) (xy 106.174495 -219.223844) (xy 106.216511 -219.25437)
			(xy 106.253234 -219.291093) (xy 106.28376 -219.333109) (xy 106.307338 -219.379383) (xy 106.323386 -219.428776)
			(xy 106.331511 -219.480071) (xy 106.33202 -219.506038) (xy 106.331511 -219.532005) (xy 106.611421 -219.532005)
			(xy 106.611421 -219.480071) (xy 106.619546 -219.428776) (xy 106.635594 -219.379383) (xy 106.659172 -219.333109)
			(xy 106.689698 -219.291093) (xy 106.726421 -219.25437) (xy 106.768437 -219.223844) (xy 106.814711 -219.200266)
			(xy 106.864104 -219.184218) (xy 106.915399 -219.176093) (xy 106.967333 -219.176093) (xy 107.018628 -219.184218)
			(xy 107.068021 -219.200266) (xy 107.114295 -219.223844) (xy 107.156311 -219.25437) (xy 107.193034 -219.291093)
			(xy 107.22356 -219.333109) (xy 107.247138 -219.379383) (xy 107.263186 -219.428776) (xy 107.271311 -219.480071)
			(xy 107.27182 -219.506038) (xy 107.271311 -219.532005) (xy 107.551221 -219.532005) (xy 107.551221 -219.480071)
			(xy 107.559346 -219.428776) (xy 107.575394 -219.379383) (xy 107.598972 -219.333109) (xy 107.629498 -219.291093)
			(xy 107.666221 -219.25437) (xy 107.708237 -219.223844) (xy 107.754511 -219.200266) (xy 107.803904 -219.184218)
			(xy 107.855199 -219.176093) (xy 107.907133 -219.176093) (xy 107.958428 -219.184218) (xy 108.007821 -219.200266)
			(xy 108.054095 -219.223844) (xy 108.096111 -219.25437) (xy 108.132834 -219.291093) (xy 108.16336 -219.333109)
			(xy 108.186938 -219.379383) (xy 108.202986 -219.428776) (xy 108.211111 -219.480071) (xy 108.21162 -219.506038)
			(xy 108.211111 -219.532005) (xy 108.491021 -219.532005) (xy 108.491021 -219.480071) (xy 108.499146 -219.428776)
			(xy 108.515194 -219.379383) (xy 108.538772 -219.333109) (xy 108.569298 -219.291093) (xy 108.606021 -219.25437)
			(xy 108.648037 -219.223844) (xy 108.694311 -219.200266) (xy 108.743704 -219.184218) (xy 108.794999 -219.176093)
			(xy 108.846933 -219.176093) (xy 108.898228 -219.184218) (xy 108.947621 -219.200266) (xy 108.993895 -219.223844)
			(xy 109.035911 -219.25437) (xy 109.072634 -219.291093) (xy 109.10316 -219.333109) (xy 109.126738 -219.379383)
			(xy 109.142786 -219.428776) (xy 109.150911 -219.480071) (xy 109.15142 -219.506038) (xy 109.150911 -219.532005)
			(xy 109.430821 -219.532005) (xy 109.430821 -219.480071) (xy 109.438946 -219.428776) (xy 109.454994 -219.379383)
			(xy 109.478572 -219.333109) (xy 109.509098 -219.291093) (xy 109.545821 -219.25437) (xy 109.587837 -219.223844)
			(xy 109.634111 -219.200266) (xy 109.683504 -219.184218) (xy 109.734799 -219.176093) (xy 109.786733 -219.176093)
			(xy 109.838028 -219.184218) (xy 109.887421 -219.200266) (xy 109.933695 -219.223844) (xy 109.975711 -219.25437)
			(xy 110.012434 -219.291093) (xy 110.04296 -219.333109) (xy 110.066538 -219.379383) (xy 110.082586 -219.428776)
			(xy 110.090711 -219.480071) (xy 110.09122 -219.506038) (xy 110.090711 -219.532005) (xy 110.082586 -219.5833)
			(xy 110.066538 -219.632693) (xy 110.04296 -219.678967) (xy 110.012434 -219.720983) (xy 109.975711 -219.757706)
			(xy 109.933695 -219.788232) (xy 109.887421 -219.81181) (xy 109.838028 -219.827858) (xy 109.786733 -219.835983)
			(xy 109.734799 -219.835983) (xy 109.683504 -219.827858) (xy 109.634111 -219.81181) (xy 109.587837 -219.788232)
			(xy 109.545821 -219.757706) (xy 109.509098 -219.720983) (xy 109.478572 -219.678967) (xy 109.454994 -219.632693)
			(xy 109.438946 -219.5833) (xy 109.430821 -219.532005) (xy 109.150911 -219.532005) (xy 109.142786 -219.5833)
			(xy 109.126738 -219.632693) (xy 109.10316 -219.678967) (xy 109.072634 -219.720983) (xy 109.035911 -219.757706)
			(xy 108.993895 -219.788232) (xy 108.947621 -219.81181) (xy 108.898228 -219.827858) (xy 108.846933 -219.835983)
			(xy 108.794999 -219.835983) (xy 108.743704 -219.827858) (xy 108.694311 -219.81181) (xy 108.648037 -219.788232)
			(xy 108.606021 -219.757706) (xy 108.569298 -219.720983) (xy 108.538772 -219.678967) (xy 108.515194 -219.632693)
			(xy 108.499146 -219.5833) (xy 108.491021 -219.532005) (xy 108.211111 -219.532005) (xy 108.202986 -219.5833)
			(xy 108.186938 -219.632693) (xy 108.16336 -219.678967) (xy 108.132834 -219.720983) (xy 108.096111 -219.757706)
			(xy 108.054095 -219.788232) (xy 108.007821 -219.81181) (xy 107.958428 -219.827858) (xy 107.907133 -219.835983)
			(xy 107.855199 -219.835983) (xy 107.803904 -219.827858) (xy 107.754511 -219.81181) (xy 107.708237 -219.788232)
			(xy 107.666221 -219.757706) (xy 107.629498 -219.720983) (xy 107.598972 -219.678967) (xy 107.575394 -219.632693)
			(xy 107.559346 -219.5833) (xy 107.551221 -219.532005) (xy 107.271311 -219.532005) (xy 107.263186 -219.5833)
			(xy 107.247138 -219.632693) (xy 107.22356 -219.678967) (xy 107.193034 -219.720983) (xy 107.156311 -219.757706)
			(xy 107.114295 -219.788232) (xy 107.068021 -219.81181) (xy 107.018628 -219.827858) (xy 106.967333 -219.835983)
			(xy 106.915399 -219.835983) (xy 106.864104 -219.827858) (xy 106.814711 -219.81181) (xy 106.768437 -219.788232)
			(xy 106.726421 -219.757706) (xy 106.689698 -219.720983) (xy 106.659172 -219.678967) (xy 106.635594 -219.632693)
			(xy 106.619546 -219.5833) (xy 106.611421 -219.532005) (xy 106.331511 -219.532005) (xy 106.323386 -219.5833)
			(xy 106.307338 -219.632693) (xy 106.28376 -219.678967) (xy 106.253234 -219.720983) (xy 106.216511 -219.757706)
			(xy 106.174495 -219.788232) (xy 106.128221 -219.81181) (xy 106.078828 -219.827858) (xy 106.027533 -219.835983)
			(xy 105.975599 -219.835983) (xy 105.924304 -219.827858) (xy 105.874911 -219.81181) (xy 105.828637 -219.788232)
			(xy 105.786621 -219.757706) (xy 105.749898 -219.720983) (xy 105.719372 -219.678967) (xy 105.695794 -219.632693)
			(xy 105.679746 -219.5833) (xy 105.671621 -219.532005) (xy 105.391711 -219.532005) (xy 105.383586 -219.5833)
			(xy 105.367538 -219.632693) (xy 105.34396 -219.678967) (xy 105.313434 -219.720983) (xy 105.276711 -219.757706)
			(xy 105.234695 -219.788232) (xy 105.188421 -219.81181) (xy 105.139028 -219.827858) (xy 105.087733 -219.835983)
			(xy 105.035799 -219.835983) (xy 104.984504 -219.827858) (xy 104.935111 -219.81181) (xy 104.888837 -219.788232)
			(xy 104.846821 -219.757706) (xy 104.810098 -219.720983) (xy 104.779572 -219.678967) (xy 104.755994 -219.632693)
			(xy 104.739946 -219.5833) (xy 104.731821 -219.532005) (xy 104.451911 -219.532005) (xy 104.443786 -219.5833)
			(xy 104.427738 -219.632693) (xy 104.40416 -219.678967) (xy 104.373634 -219.720983) (xy 104.336911 -219.757706)
			(xy 104.294895 -219.788232) (xy 104.248621 -219.81181) (xy 104.199228 -219.827858) (xy 104.147933 -219.835983)
			(xy 104.095999 -219.835983) (xy 104.044704 -219.827858) (xy 103.995311 -219.81181) (xy 103.949037 -219.788232)
			(xy 103.907021 -219.757706) (xy 103.870298 -219.720983) (xy 103.839772 -219.678967) (xy 103.816194 -219.632693)
			(xy 103.800146 -219.5833) (xy 103.792021 -219.532005) (xy 103.512111 -219.532005) (xy 103.503986 -219.5833)
			(xy 103.487938 -219.632693) (xy 103.46436 -219.678967) (xy 103.433834 -219.720983) (xy 103.397111 -219.757706)
			(xy 103.355095 -219.788232) (xy 103.308821 -219.81181) (xy 103.259428 -219.827858) (xy 103.208133 -219.835983)
			(xy 103.156199 -219.835983) (xy 103.104904 -219.827858) (xy 103.055511 -219.81181) (xy 103.009237 -219.788232)
			(xy 102.967221 -219.757706) (xy 102.930498 -219.720983) (xy 102.899972 -219.678967) (xy 102.876394 -219.632693)
			(xy 102.860346 -219.5833) (xy 102.852221 -219.532005) (xy 102.572401 -219.532005) (xy 102.564276 -219.58329)
			(xy 102.548222 -219.632693) (xy 102.524636 -219.678976) (xy 102.4941 -219.721) (xy 102.457366 -219.757729)
			(xy 102.415338 -219.788259) (xy 102.369052 -219.811838) (xy 102.319647 -219.827886) (xy 102.268339 -219.836008)
			(xy 102.242366 -219.836492) (xy 102.230682 -219.836238) (xy 102.217127 -219.836146) (xy 102.190732 -219.842275)
			(xy 102.166883 -219.855137) (xy 102.14726 -219.873824) (xy 102.133249 -219.897017) (xy 102.125839 -219.923081)
			(xy 102.125552 -219.950177) (xy 102.132409 -219.976392) (xy 102.145925 -219.999877) (xy 102.155244 -220.00972)
			(xy 102.287832 -220.142308) (xy 102.298615 -220.152404) (xy 102.324583 -220.166453) (xy 102.353489 -220.172471)
			(xy 102.382907 -220.169955) (xy 102.410371 -220.159114) (xy 102.433576 -220.140859) (xy 102.442518 -220.1291)
			(xy 102.458117 -220.107893) (xy 102.49492 -220.070252) (xy 102.537229 -220.038928) (xy 102.583973 -220.014716)
			(xy 102.633967 -219.998229) (xy 102.685945 -219.989885) (xy 102.712266 -219.9894) (xy 102.738236 -219.989907)
			(xy 102.789538 -219.998026) (xy 102.838938 -220.014072) (xy 102.88522 -220.037647) (xy 102.927244 -220.068172)
			(xy 102.963976 -220.104895) (xy 102.994511 -220.146912) (xy 103.018098 -220.193188) (xy 103.034155 -220.242584)
			(xy 103.042287 -220.293884) (xy 103.04272 -220.319854) (xy 103.042205 -220.346172) (xy 103.033849 -220.39814)
			(xy 103.017358 -220.448126) (xy 102.993148 -220.494864) (xy 102.961832 -220.537171) (xy 102.924204 -220.573977)
			(xy 102.90302 -220.589602) (xy 102.891284 -220.598544) (xy 102.873114 -220.621773) (xy 102.86233 -220.649222)
			(xy 102.859828 -220.678607) (xy 102.865816 -220.707484) (xy 102.879796 -220.733452) (xy 102.889812 -220.744288)
			(xy 103.00081 -220.855286) (xy 103.033576 -220.838776) (xy 103.054485 -220.828671) (xy 103.098462 -220.813751)
			(xy 103.121206 -220.809058) (xy 103.144066 -220.80474) (xy 103.347774 -220.45168) (xy 103.340154 -220.429582)
			(xy 103.331363 -220.403007) (xy 103.321919 -220.347839) (xy 103.321358 -220.319854) (xy 103.321867 -220.293887)
			(xy 103.329992 -220.242592) (xy 103.34604 -220.193199) (xy 103.369618 -220.146925) (xy 103.400144 -220.104909)
			(xy 103.436867 -220.068186) (xy 103.478883 -220.03766) (xy 103.525157 -220.014082) (xy 103.57455 -219.998034)
			(xy 103.625845 -219.989909) (xy 103.677779 -219.989909) (xy 103.729074 -219.998034) (xy 103.778467 -220.014082)
			(xy 103.824741 -220.03766) (xy 103.866757 -220.068186) (xy 103.90348 -220.104909) (xy 103.934006 -220.146925)
			(xy 103.957584 -220.193199) (xy 103.973632 -220.242592) (xy 103.981757 -220.293887) (xy 103.982266 -220.319854)
			(xy 103.981794 -220.345303) (xy 103.981714 -220.345821) (xy 104.261921 -220.345821) (xy 104.261921 -220.293887)
			(xy 104.270046 -220.242592) (xy 104.286094 -220.193199) (xy 104.309672 -220.146925) (xy 104.340198 -220.104909)
			(xy 104.376921 -220.068186) (xy 104.418937 -220.03766) (xy 104.465211 -220.014082) (xy 104.514604 -219.998034)
			(xy 104.565899 -219.989909) (xy 104.617833 -219.989909) (xy 104.669128 -219.998034) (xy 104.718521 -220.014082)
			(xy 104.764795 -220.03766) (xy 104.806811 -220.068186) (xy 104.843534 -220.104909) (xy 104.87406 -220.146925)
			(xy 104.897638 -220.193199) (xy 104.913686 -220.242592) (xy 104.921811 -220.293887) (xy 104.92232 -220.319854)
			(xy 105.200958 -220.319854) (xy 105.201467 -220.293887) (xy 105.209592 -220.242592) (xy 105.22564 -220.193199)
			(xy 105.249218 -220.146925) (xy 105.279744 -220.104909) (xy 105.316467 -220.068186) (xy 105.358483 -220.03766)
			(xy 105.404757 -220.014082) (xy 105.45415 -219.998034) (xy 105.505445 -219.989909) (xy 105.557379 -219.989909)
			(xy 105.608674 -219.998034) (xy 105.658067 -220.014082) (xy 105.704341 -220.03766) (xy 105.746357 -220.068186)
			(xy 105.78308 -220.104909) (xy 105.813606 -220.146925) (xy 105.837184 -220.193199) (xy 105.853232 -220.242592)
			(xy 105.861357 -220.293887) (xy 105.861866 -220.319854) (xy 105.861369 -220.345821) (xy 106.141521 -220.345821)
			(xy 106.141521 -220.293887) (xy 106.149646 -220.242592) (xy 106.165694 -220.193199) (xy 106.189272 -220.146925)
			(xy 106.219798 -220.104909) (xy 106.256521 -220.068186) (xy 106.298537 -220.03766) (xy 106.344811 -220.014082)
			(xy 106.394204 -219.998034) (xy 106.445499 -219.989909) (xy 106.497433 -219.989909) (xy 106.548728 -219.998034)
			(xy 106.598121 -220.014082) (xy 106.644395 -220.03766) (xy 106.686411 -220.068186) (xy 106.723134 -220.104909)
			(xy 106.75366 -220.146925) (xy 106.777238 -220.193199) (xy 106.793286 -220.242592) (xy 106.801411 -220.293887)
			(xy 106.80192 -220.319854) (xy 107.080558 -220.319854) (xy 107.081067 -220.293887) (xy 107.089192 -220.242592)
			(xy 107.10524 -220.193199) (xy 107.128818 -220.146925) (xy 107.159344 -220.104909) (xy 107.196067 -220.068186)
			(xy 107.238083 -220.03766) (xy 107.284357 -220.014082) (xy 107.33375 -219.998034) (xy 107.385045 -219.989909)
			(xy 107.436979 -219.989909) (xy 107.488274 -219.998034) (xy 107.537667 -220.014082) (xy 107.583941 -220.03766)
			(xy 107.625957 -220.068186) (xy 107.66268 -220.104909) (xy 107.693206 -220.146925) (xy 107.716784 -220.193199)
			(xy 107.732832 -220.242592) (xy 107.740957 -220.293887) (xy 107.741466 -220.319854) (xy 107.740969 -220.345821)
			(xy 108.021121 -220.345821) (xy 108.021121 -220.293887) (xy 108.029246 -220.242592) (xy 108.045294 -220.193199)
			(xy 108.068872 -220.146925) (xy 108.099398 -220.104909) (xy 108.136121 -220.068186) (xy 108.178137 -220.03766)
			(xy 108.224411 -220.014082) (xy 108.273804 -219.998034) (xy 108.325099 -219.989909) (xy 108.377033 -219.989909)
			(xy 108.428328 -219.998034) (xy 108.477721 -220.014082) (xy 108.523995 -220.03766) (xy 108.566011 -220.068186)
			(xy 108.602734 -220.104909) (xy 108.63326 -220.146925) (xy 108.656838 -220.193199) (xy 108.672886 -220.242592)
			(xy 108.681011 -220.293887) (xy 108.68152 -220.319854) (xy 108.960158 -220.319854) (xy 108.960667 -220.293887)
			(xy 108.968792 -220.242592) (xy 108.98484 -220.193199) (xy 109.008418 -220.146925) (xy 109.038944 -220.104909)
			(xy 109.075667 -220.068186) (xy 109.117683 -220.03766) (xy 109.163957 -220.014082) (xy 109.21335 -219.998034)
			(xy 109.264645 -219.989909) (xy 109.316579 -219.989909) (xy 109.367874 -219.998034) (xy 109.417267 -220.014082)
			(xy 109.463541 -220.03766) (xy 109.505557 -220.068186) (xy 109.54228 -220.104909) (xy 109.572806 -220.146925)
			(xy 109.596384 -220.193199) (xy 109.612432 -220.242592) (xy 109.620557 -220.293887) (xy 109.621066 -220.319854)
			(xy 109.620569 -220.345821) (xy 109.900721 -220.345821) (xy 109.900721 -220.293887) (xy 109.908846 -220.242592)
			(xy 109.924894 -220.193199) (xy 109.948472 -220.146925) (xy 109.978998 -220.104909) (xy 110.015721 -220.068186)
			(xy 110.057737 -220.03766) (xy 110.104011 -220.014082) (xy 110.153404 -219.998034) (xy 110.204699 -219.989909)
			(xy 110.256633 -219.989909) (xy 110.307928 -219.998034) (xy 110.357321 -220.014082) (xy 110.403595 -220.03766)
			(xy 110.445611 -220.068186) (xy 110.482334 -220.104909) (xy 110.51286 -220.146925) (xy 110.536438 -220.193199)
			(xy 110.552486 -220.242592) (xy 110.560611 -220.293887) (xy 110.56112 -220.319854) (xy 110.560611 -220.345821)
			(xy 110.552486 -220.397116) (xy 110.536438 -220.446509) (xy 110.51286 -220.492783) (xy 110.482334 -220.534799)
			(xy 110.445611 -220.571522) (xy 110.403595 -220.602048) (xy 110.357321 -220.625626) (xy 110.307928 -220.641674)
			(xy 110.256633 -220.649799) (xy 110.204699 -220.649799) (xy 110.153404 -220.641674) (xy 110.104011 -220.625626)
			(xy 110.057737 -220.602048) (xy 110.015721 -220.571522) (xy 109.978998 -220.534799) (xy 109.948472 -220.492783)
			(xy 109.924894 -220.446509) (xy 109.908846 -220.397116) (xy 109.900721 -220.345821) (xy 109.620569 -220.345821)
			(xy 109.620532 -220.347764) (xy 109.611204 -220.402797) (xy 109.602524 -220.429328) (xy 109.59465 -220.451172)
			(xy 109.798866 -220.80474) (xy 109.821726 -220.809058) (xy 109.846644 -220.814243) (xy 109.894627 -220.831206)
			(xy 109.939445 -220.85532) (xy 109.980038 -220.886018) (xy 110.015447 -220.922574) (xy 110.044836 -220.964124)
			(xy 110.067511 -221.009687) (xy 110.082935 -221.058187) (xy 110.090746 -221.108477) (xy 110.09122 -221.133924)
			(xy 110.090711 -221.159891) (xy 110.082586 -221.211186) (xy 110.066538 -221.260579) (xy 110.04296 -221.306853)
			(xy 110.012434 -221.348869) (xy 109.975711 -221.385592) (xy 109.933695 -221.416118) (xy 109.887421 -221.439696)
			(xy 109.838028 -221.455744) (xy 109.786733 -221.463869) (xy 109.734799 -221.463869) (xy 109.683504 -221.455744)
			(xy 109.634111 -221.439696) (xy 109.587837 -221.416118) (xy 109.545821 -221.385592) (xy 109.509098 -221.348869)
			(xy 109.478572 -221.306853) (xy 109.454994 -221.260579) (xy 109.438946 -221.211186) (xy 109.430821 -221.159891)
			(xy 109.430312 -221.133924) (xy 109.43087 -221.105938) (xy 109.440316 -221.050771) (xy 109.449108 -221.024196)
			(xy 109.456728 -221.002098) (xy 109.25302 -220.649038) (xy 109.229906 -220.64472) (xy 109.20497 -220.63956)
			(xy 109.156947 -220.62263) (xy 109.112088 -220.598536) (xy 109.071455 -220.567848) (xy 109.036009 -220.531292)
			(xy 109.006589 -220.489732) (xy 108.983889 -220.444152) (xy 108.968449 -220.39563) (xy 108.960632 -220.345314)
			(xy 108.960158 -220.319854) (xy 108.68152 -220.319854) (xy 108.681011 -220.345821) (xy 108.672886 -220.397116)
			(xy 108.656838 -220.446509) (xy 108.63326 -220.492783) (xy 108.602734 -220.534799) (xy 108.566011 -220.571522)
			(xy 108.523995 -220.602048) (xy 108.477721 -220.625626) (xy 108.428328 -220.641674) (xy 108.377033 -220.649799)
			(xy 108.325099 -220.649799) (xy 108.273804 -220.641674) (xy 108.224411 -220.625626) (xy 108.178137 -220.602048)
			(xy 108.136121 -220.571522) (xy 108.099398 -220.534799) (xy 108.068872 -220.492783) (xy 108.045294 -220.446509)
			(xy 108.029246 -220.397116) (xy 108.021121 -220.345821) (xy 107.740969 -220.345821) (xy 107.740932 -220.347764)
			(xy 107.731604 -220.402797) (xy 107.722924 -220.429328) (xy 107.71505 -220.451172) (xy 107.919266 -220.80474)
			(xy 107.942126 -220.809058) (xy 107.967044 -220.814243) (xy 108.015027 -220.831206) (xy 108.059845 -220.85532)
			(xy 108.100438 -220.886018) (xy 108.135847 -220.922574) (xy 108.165236 -220.964124) (xy 108.187911 -221.009687)
			(xy 108.203335 -221.058187) (xy 108.211146 -221.108477) (xy 108.21162 -221.133924) (xy 108.211111 -221.159891)
			(xy 108.202986 -221.211186) (xy 108.186938 -221.260579) (xy 108.16336 -221.306853) (xy 108.132834 -221.348869)
			(xy 108.096111 -221.385592) (xy 108.054095 -221.416118) (xy 108.007821 -221.439696) (xy 107.958428 -221.455744)
			(xy 107.907133 -221.463869) (xy 107.855199 -221.463869) (xy 107.803904 -221.455744) (xy 107.754511 -221.439696)
			(xy 107.708237 -221.416118) (xy 107.666221 -221.385592) (xy 107.629498 -221.348869) (xy 107.598972 -221.306853)
			(xy 107.575394 -221.260579) (xy 107.559346 -221.211186) (xy 107.551221 -221.159891) (xy 107.550712 -221.133924)
			(xy 107.55127 -221.105938) (xy 107.560716 -221.050771) (xy 107.569508 -221.024196) (xy 107.577128 -221.002098)
			(xy 107.37342 -220.649038) (xy 107.350306 -220.64472) (xy 107.32537 -220.63956) (xy 107.277347 -220.62263)
			(xy 107.232488 -220.598536) (xy 107.191855 -220.567848) (xy 107.156409 -220.531292) (xy 107.126989 -220.489732)
			(xy 107.104289 -220.444152) (xy 107.088849 -220.39563) (xy 107.081032 -220.345314) (xy 107.080558 -220.319854)
			(xy 106.80192 -220.319854) (xy 106.801411 -220.345821) (xy 106.793286 -220.397116) (xy 106.777238 -220.446509)
			(xy 106.75366 -220.492783) (xy 106.723134 -220.534799) (xy 106.686411 -220.571522) (xy 106.644395 -220.602048)
			(xy 106.598121 -220.625626) (xy 106.548728 -220.641674) (xy 106.497433 -220.649799) (xy 106.445499 -220.649799)
			(xy 106.394204 -220.641674) (xy 106.344811 -220.625626) (xy 106.298537 -220.602048) (xy 106.256521 -220.571522)
			(xy 106.219798 -220.534799) (xy 106.189272 -220.492783) (xy 106.165694 -220.446509) (xy 106.149646 -220.397116)
			(xy 106.141521 -220.345821) (xy 105.861369 -220.345821) (xy 105.861332 -220.347764) (xy 105.852004 -220.402797)
			(xy 105.843324 -220.429328) (xy 105.83545 -220.451172) (xy 106.039666 -220.80474) (xy 106.062526 -220.809058)
			(xy 106.087444 -220.814243) (xy 106.135427 -220.831206) (xy 106.180245 -220.85532) (xy 106.220838 -220.886018)
			(xy 106.256247 -220.922574) (xy 106.285636 -220.964124) (xy 106.308311 -221.009687) (xy 106.323735 -221.058187)
			(xy 106.331546 -221.108477) (xy 106.33202 -221.133924) (xy 106.331511 -221.159891) (xy 106.323386 -221.211186)
			(xy 106.307338 -221.260579) (xy 106.28376 -221.306853) (xy 106.253234 -221.348869) (xy 106.216511 -221.385592)
			(xy 106.174495 -221.416118) (xy 106.128221 -221.439696) (xy 106.078828 -221.455744) (xy 106.027533 -221.463869)
			(xy 105.975599 -221.463869) (xy 105.924304 -221.455744) (xy 105.874911 -221.439696) (xy 105.828637 -221.416118)
			(xy 105.786621 -221.385592) (xy 105.749898 -221.348869) (xy 105.719372 -221.306853) (xy 105.695794 -221.260579)
			(xy 105.679746 -221.211186) (xy 105.671621 -221.159891) (xy 105.671112 -221.133924) (xy 105.67167 -221.105938)
			(xy 105.681116 -221.050771) (xy 105.689908 -221.024196) (xy 105.697528 -221.002098) (xy 105.49382 -220.649038)
			(xy 105.470706 -220.64472) (xy 105.44577 -220.63956) (xy 105.397747 -220.62263) (xy 105.352888 -220.598536)
			(xy 105.312255 -220.567848) (xy 105.276809 -220.531292) (xy 105.247389 -220.489732) (xy 105.224689 -220.444152)
			(xy 105.209249 -220.39563) (xy 105.201432 -220.345314) (xy 105.200958 -220.319854) (xy 104.92232 -220.319854)
			(xy 104.921811 -220.345821) (xy 104.913686 -220.397116) (xy 104.897638 -220.446509) (xy 104.87406 -220.492783)
			(xy 104.843534 -220.534799) (xy 104.806811 -220.571522) (xy 104.764795 -220.602048) (xy 104.718521 -220.625626)
			(xy 104.669128 -220.641674) (xy 104.617833 -220.649799) (xy 104.565899 -220.649799) (xy 104.514604 -220.641674)
			(xy 104.465211 -220.625626) (xy 104.418937 -220.602048) (xy 104.376921 -220.571522) (xy 104.340198 -220.534799)
			(xy 104.309672 -220.492783) (xy 104.286094 -220.446509) (xy 104.270046 -220.397116) (xy 104.261921 -220.345821)
			(xy 103.981714 -220.345821) (xy 103.973986 -220.395598) (xy 103.958564 -220.444102) (xy 103.935892 -220.489671)
			(xy 103.906505 -220.531228) (xy 103.871097 -220.56779) (xy 103.830505 -220.598496) (xy 103.785687 -220.622618)
			(xy 103.737702 -220.639589) (xy 103.712772 -220.64472) (xy 103.689912 -220.649038) (xy 103.486204 -221.002098)
			(xy 103.493824 -221.024196) (xy 103.502615 -221.050771) (xy 103.51206 -221.105938) (xy 103.51262 -221.133924)
			(xy 103.512129 -221.159624) (xy 103.512087 -221.159891) (xy 103.792021 -221.159891) (xy 103.792021 -221.107957)
			(xy 103.800146 -221.056662) (xy 103.816194 -221.007269) (xy 103.839772 -220.960995) (xy 103.870298 -220.918979)
			(xy 103.907021 -220.882256) (xy 103.949037 -220.85173) (xy 103.995311 -220.828152) (xy 104.044704 -220.812104)
			(xy 104.095999 -220.803979) (xy 104.147933 -220.803979) (xy 104.199228 -220.812104) (xy 104.248621 -220.828152)
			(xy 104.294895 -220.85173) (xy 104.336911 -220.882256) (xy 104.373634 -220.918979) (xy 104.40416 -220.960995)
			(xy 104.427738 -221.007269) (xy 104.443786 -221.056662) (xy 104.451911 -221.107957) (xy 104.45242 -221.133924)
			(xy 104.451911 -221.159891) (xy 104.443786 -221.211186) (xy 104.427738 -221.260579) (xy 104.40416 -221.306853)
			(xy 104.373634 -221.348869) (xy 104.336911 -221.385592) (xy 104.294895 -221.416118) (xy 104.248621 -221.439696)
			(xy 104.199228 -221.455744) (xy 104.147933 -221.463869) (xy 104.095999 -221.463869) (xy 104.044704 -221.455744)
			(xy 103.995311 -221.439696) (xy 103.949037 -221.416118) (xy 103.907021 -221.385592) (xy 103.870298 -221.348869)
			(xy 103.839772 -221.306853) (xy 103.816194 -221.260579) (xy 103.800146 -221.211186) (xy 103.792021 -221.159891)
			(xy 103.512087 -221.159891) (xy 103.504161 -221.210402) (xy 103.488422 -221.259333) (xy 103.477314 -221.282514)
			(xy 103.460804 -221.31528) (xy 103.795576 -221.650052) (xy 103.802688 -221.653862) (xy 103.825331 -221.66604)
			(xy 103.866872 -221.696325) (xy 103.903221 -221.732681) (xy 103.933497 -221.774229) (xy 103.94569 -221.796864)
			(xy 103.9495 -221.803976) (xy 104.093772 -221.948248) (xy 104.103924 -221.957809) (xy 104.12822 -221.971476)
			(xy 104.15531 -221.978054) (xy 104.183169 -221.97705) (xy 104.209715 -221.968538) (xy 104.232964 -221.953156)
			(xy 104.251179 -221.932053) (xy 104.262998 -221.906806) (xy 104.26573 -221.89313) (xy 104.270369 -221.868363)
			(xy 104.286154 -221.820512) (xy 104.309014 -221.775609) (xy 104.338421 -221.734693) (xy 104.373694 -221.698712)
			(xy 104.414017 -221.668497) (xy 104.458456 -221.644748) (xy 104.505984 -221.628014) (xy 104.530652 -221.622874)
			(xy 104.553512 -221.618556) (xy 104.757474 -221.264988) (xy 104.749854 -221.243144) (xy 104.741195 -221.216673)
			(xy 104.731879 -221.161769) (xy 104.731312 -221.133924) (xy 104.731821 -221.107957) (xy 104.739946 -221.056662)
			(xy 104.755994 -221.007269) (xy 104.779572 -220.960995) (xy 104.810098 -220.918979) (xy 104.846821 -220.882256)
			(xy 104.888837 -220.85173) (xy 104.935111 -220.828152) (xy 104.984504 -220.812104) (xy 105.035799 -220.803979)
			(xy 105.087733 -220.803979) (xy 105.139028 -220.812104) (xy 105.188421 -220.828152) (xy 105.234695 -220.85173)
			(xy 105.276711 -220.882256) (xy 105.313434 -220.918979) (xy 105.34396 -220.960995) (xy 105.367538 -221.007269)
			(xy 105.383586 -221.056662) (xy 105.391711 -221.107957) (xy 105.39222 -221.133924) (xy 105.391747 -221.159396)
			(xy 105.383924 -221.209737) (xy 105.368468 -221.25828) (xy 105.345743 -221.303875) (xy 105.31629 -221.345443)
			(xy 105.280805 -221.381997) (xy 105.240131 -221.412671) (xy 105.19523 -221.436739) (xy 105.147168 -221.453631)
			(xy 105.122218 -221.45879) (xy 105.099104 -221.463108) (xy 104.89565 -221.815914) (xy 104.90327 -221.838012)
			(xy 104.912061 -221.864587) (xy 104.921505 -221.919755) (xy 104.922066 -221.94774) (xy 104.921569 -221.973521)
			(xy 104.913556 -222.024458) (xy 104.897732 -222.073533) (xy 104.87448 -222.119555) (xy 104.859836 -222.14078)
			(xy 104.852022 -222.152358) (xy 104.842433 -222.178582) (xy 104.840307 -222.206423) (xy 104.845805 -222.233799)
			(xy 104.858515 -222.258661) (xy 104.877486 -222.279149) (xy 104.901298 -222.29373) (xy 104.928171 -222.301314)
			(xy 104.942132 -222.301816)
		)
		(stroke
			(width 0)
			(type solid)
		)
		(fill yes)
		(layer "In6.Cu")
		(net "PVCCD_HV_CPU1")
	)
	(gr_poly
		(pts
			(xy 53.623718 -118.425722) (xy 53.623718 -117.794786) (xy 53.623265 -117.78072) (xy 53.615587 -117.753656)
			(xy 53.600817 -117.729713) (xy 53.580075 -117.710708) (xy 53.554936 -117.698081) (xy 53.527305 -117.692792)
			(xy 53.49928 -117.695241) (xy 53.472986 -117.705243) (xy 53.461412 -117.713252) (xy 53.436525 -117.731099)
			(xy 53.382249 -117.759459) (xy 53.324137 -117.778779) (xy 53.263685 -117.788562) (xy 53.233066 -117.789198)
			(xy 53.205817 -117.788709) (xy 53.151875 -117.780949) (xy 53.099585 -117.765592) (xy 53.050014 -117.742949)
			(xy 53.004169 -117.713483) (xy 52.962984 -117.677792) (xy 52.927297 -117.636604) (xy 52.897835 -117.590756)
			(xy 52.875197 -117.541183) (xy 52.859844 -117.488892) (xy 52.852088 -117.434949) (xy 52.852088 -117.380451)
			(xy 52.859844 -117.326508) (xy 52.875197 -117.274217) (xy 52.897835 -117.224644) (xy 52.927297 -117.178796)
			(xy 52.962984 -117.137608) (xy 53.004169 -117.101917) (xy 53.050014 -117.072451) (xy 53.099585 -117.049808)
			(xy 53.151875 -117.034451) (xy 53.205817 -117.026691) (xy 53.233066 -117.026182) (xy 53.263687 -117.026789)
			(xy 53.324143 -117.036575) (xy 53.382256 -117.055899) (xy 53.436533 -117.084266) (xy 53.461412 -117.102128)
			(xy 53.472968 -117.110168) (xy 53.49927 -117.120175) (xy 53.527304 -117.122626) (xy 53.554943 -117.117335)
			(xy 53.58009 -117.104704) (xy 53.600837 -117.085691) (xy 53.615609 -117.061738) (xy 53.623286 -117.034665)
			(xy 53.623718 -117.020594) (xy 53.623718 -116.521484) (xy 53.623265 -116.507418) (xy 53.615587 -116.480355)
			(xy 53.600816 -116.456412) (xy 53.580075 -116.437407) (xy 53.554936 -116.424781) (xy 53.527305 -116.419492)
			(xy 53.49928 -116.421941) (xy 53.472986 -116.431943) (xy 53.461412 -116.43995) (xy 53.436525 -116.457797)
			(xy 53.382249 -116.486158) (xy 53.324138 -116.505478) (xy 53.263685 -116.515261) (xy 53.233066 -116.515896)
			(xy 53.205817 -116.515407) (xy 53.151875 -116.507647) (xy 53.099586 -116.49229) (xy 53.050015 -116.469647)
			(xy 53.00417 -116.440181) (xy 52.962985 -116.404491) (xy 52.927299 -116.363303) (xy 52.897836 -116.317455)
			(xy 52.875198 -116.267882) (xy 52.859846 -116.215592) (xy 52.85209 -116.161649) (xy 52.85209 -116.107151)
			(xy 52.859846 -116.053208) (xy 52.875198 -116.000918) (xy 52.897836 -115.951345) (xy 52.927299 -115.905497)
			(xy 52.962985 -115.864309) (xy 53.00417 -115.828619) (xy 53.050015 -115.799153) (xy 53.099586 -115.77651)
			(xy 53.151875 -115.761153) (xy 53.205817 -115.753393) (xy 53.233066 -115.75288) (xy 53.263687 -115.753487)
			(xy 53.324143 -115.763273) (xy 53.382256 -115.782597) (xy 53.436533 -115.810964) (xy 53.461412 -115.828826)
			(xy 53.472968 -115.836866) (xy 53.49927 -115.846873) (xy 53.527304 -115.849324) (xy 53.554943 -115.844033)
			(xy 53.58009 -115.831402) (xy 53.600837 -115.812389) (xy 53.615608 -115.788437) (xy 53.623284 -115.761363)
			(xy 53.623718 -115.747292) (xy 53.623718 -111.532162) (xy 51.476656 -109.3851) (xy 51.476656 -105.542842)
			(xy 50.629058 -104.695244) (xy 49.92497 -104.695244) (xy 49.916842 -104.736138) (xy 49.910629 -104.76463)
			(xy 49.890716 -104.819437) (xy 49.862697 -104.870577) (xy 49.827224 -104.916859) (xy 49.785123 -104.957207)
			(xy 49.737375 -104.990679) (xy 49.68509 -105.016499) (xy 49.629485 -105.034063) (xy 49.571856 -105.042965)
			(xy 49.5427 -105.043478) (xy 49.517181 -105.043052) (xy 49.466598 -105.03625) (xy 49.417373 -105.022767)
			(xy 49.370383 -105.002844) (xy 49.326468 -104.976837) (xy 49.286411 -104.945209) (xy 49.26838 -104.927146)
			(xy 49.258123 -104.917249) (xy 49.233415 -104.903066) (xy 49.205751 -104.896256) (xy 49.177282 -104.897349)
			(xy 49.150222 -104.906261) (xy 49.126675 -104.922299) (xy 49.11725 -104.932988) (xy 49.099037 -104.954134)
			(xy 49.057488 -104.991393) (xy 49.010956 -105.022203) (xy 48.960432 -105.045908) (xy 48.906995 -105.062002)
			(xy 48.851784 -105.070141) (xy 48.82388 -105.070656) (xy 48.796425 -105.070177) (xy 48.742082 -105.062303)
			(xy 48.68943 -105.046721) (xy 48.639555 -105.023751) (xy 48.593487 -104.99387) (xy 48.552179 -104.957693)
			(xy 48.516483 -104.915969) (xy 48.487137 -104.869559) (xy 48.464746 -104.819421) (xy 48.449774 -104.766591)
			(xy 48.445674 -104.73944) (xy 48.439832 -104.695244) (xy 37.633148 -104.695244) (xy 36.826444 -105.501948)
			(xy 41.273982 -105.501948) (xy 41.278053 -105.446326) (xy 41.290179 -105.391889) (xy 41.310102 -105.339798)
			(xy 41.337398 -105.291163) (xy 41.371484 -105.24702) (xy 41.411633 -105.208311) (xy 41.456991 -105.17586)
			(xy 41.506591 -105.150359) (xy 41.559375 -105.132352) (xy 41.614218 -105.122222) (xy 41.669952 -105.120185)
			(xy 41.725389 -105.126285) (xy 41.779346 -105.140391) (xy 41.830675 -105.162203) (xy 41.878281 -105.191257)
			(xy 41.921149 -105.226932) (xy 41.958366 -105.268469) (xy 41.989139 -105.314982) (xy 42.012811 -105.365479)
			(xy 42.028879 -105.418886) (xy 42.036999 -105.474062) (xy 42.037508 -105.501948) (xy 42.036999 -105.529834)
			(xy 42.028879 -105.58501) (xy 42.012811 -105.638417) (xy 41.989139 -105.688914) (xy 41.958366 -105.735427)
			(xy 41.921149 -105.776964) (xy 41.878281 -105.812639) (xy 41.830675 -105.841693) (xy 41.779346 -105.863505)
			(xy 41.725389 -105.877611) (xy 41.669952 -105.883711) (xy 41.614218 -105.881674) (xy 41.559375 -105.871544)
			(xy 41.506591 -105.853537) (xy 41.456991 -105.828036) (xy 41.411633 -105.795585) (xy 41.371484 -105.756876)
			(xy 41.337398 -105.712733) (xy 41.310102 -105.664098) (xy 41.290179 -105.612007) (xy 41.278053 -105.55757)
			(xy 41.273982 -105.501948) (xy 36.826444 -105.501948) (xy 36.358322 -105.97007) (xy 43.43476 -105.97007)
			(xy 43.438831 -105.914448) (xy 43.450957 -105.860011) (xy 43.47088 -105.80792) (xy 43.498176 -105.759285)
			(xy 43.532262 -105.715142) (xy 43.572411 -105.676433) (xy 43.617769 -105.643982) (xy 43.667369 -105.618481)
			(xy 43.720153 -105.600474) (xy 43.774996 -105.590344) (xy 43.83073 -105.588307) (xy 43.886167 -105.594407)
			(xy 43.940124 -105.608513) (xy 43.991453 -105.630325) (xy 44.039059 -105.659379) (xy 44.081927 -105.695054)
			(xy 44.119144 -105.736591) (xy 44.149917 -105.783104) (xy 44.173589 -105.833601) (xy 44.189657 -105.887008)
			(xy 44.197777 -105.942184) (xy 44.198286 -105.97007) (xy 44.197777 -105.997956) (xy 44.192162 -106.03611)
			(xy 49.160682 -106.03611) (xy 49.164753 -105.980488) (xy 49.176879 -105.926051) (xy 49.196802 -105.87396)
			(xy 49.224098 -105.825325) (xy 49.258184 -105.781182) (xy 49.298333 -105.742473) (xy 49.343691 -105.710022)
			(xy 49.393291 -105.684521) (xy 49.446075 -105.666514) (xy 49.500918 -105.656384) (xy 49.556652 -105.654347)
			(xy 49.612089 -105.660447) (xy 49.666046 -105.674553) (xy 49.717375 -105.696365) (xy 49.764981 -105.725419)
			(xy 49.807849 -105.761094) (xy 49.845066 -105.802631) (xy 49.875839 -105.849144) (xy 49.899511 -105.899641)
			(xy 49.915579 -105.953048) (xy 49.923699 -106.008224) (xy 49.924208 -106.03611) (xy 49.923699 -106.063996)
			(xy 49.915579 -106.119172) (xy 49.899511 -106.172579) (xy 49.875839 -106.223076) (xy 49.845066 -106.269589)
			(xy 49.807849 -106.311126) (xy 49.764981 -106.346801) (xy 49.717375 -106.375855) (xy 49.666046 -106.397667)
			(xy 49.612089 -106.411773) (xy 49.556652 -106.417873) (xy 49.500918 -106.415836) (xy 49.446075 -106.405706)
			(xy 49.393291 -106.387699) (xy 49.343691 -106.362198) (xy 49.298333 -106.329747) (xy 49.258184 -106.291038)
			(xy 49.224098 -106.246895) (xy 49.196802 -106.19826) (xy 49.176879 -106.146169) (xy 49.164753 -106.091732)
			(xy 49.160682 -106.03611) (xy 44.192162 -106.03611) (xy 44.189657 -106.053132) (xy 44.173589 -106.106539)
			(xy 44.149917 -106.157036) (xy 44.119144 -106.203549) (xy 44.081927 -106.245086) (xy 44.039059 -106.280761)
			(xy 43.991453 -106.309815) (xy 43.940124 -106.331627) (xy 43.886167 -106.345733) (xy 43.83073 -106.351833)
			(xy 43.774996 -106.349796) (xy 43.720153 -106.339666) (xy 43.667369 -106.321659) (xy 43.617769 -106.296158)
			(xy 43.572411 -106.263707) (xy 43.532262 -106.224998) (xy 43.498176 -106.180855) (xy 43.47088 -106.13222)
			(xy 43.450957 -106.080129) (xy 43.438831 -106.025692) (xy 43.43476 -105.97007) (xy 36.358322 -105.97007)
			(xy 35.80511 -106.523282) (xy 37.558216 -106.523282) (xy 37.562287 -106.46766) (xy 37.574413 -106.413223)
			(xy 37.594336 -106.361132) (xy 37.621632 -106.312497) (xy 37.655718 -106.268354) (xy 37.695867 -106.229645)
			(xy 37.741225 -106.197194) (xy 37.790825 -106.171693) (xy 37.843609 -106.153686) (xy 37.898452 -106.143556)
			(xy 37.954186 -106.141519) (xy 38.009623 -106.147619) (xy 38.06358 -106.161725) (xy 38.114909 -106.183537)
			(xy 38.162515 -106.212591) (xy 38.205383 -106.248266) (xy 38.2426 -106.289803) (xy 38.273373 -106.336316)
			(xy 38.297045 -106.386813) (xy 38.313113 -106.44022) (xy 38.321233 -106.495396) (xy 38.321742 -106.523282)
			(xy 38.321233 -106.551168) (xy 38.313113 -106.606344) (xy 38.297045 -106.659751) (xy 38.273373 -106.710248)
			(xy 38.2426 -106.756761) (xy 38.228993 -106.771948) (xy 41.273982 -106.771948) (xy 41.278053 -106.716326)
			(xy 41.290179 -106.661889) (xy 41.310102 -106.609798) (xy 41.337398 -106.561163) (xy 41.371484 -106.51702)
			(xy 41.411633 -106.478311) (xy 41.456991 -106.44586) (xy 41.506591 -106.420359) (xy 41.559375 -106.402352)
			(xy 41.614218 -106.392222) (xy 41.669952 -106.390185) (xy 41.725389 -106.396285) (xy 41.779346 -106.410391)
			(xy 41.830675 -106.432203) (xy 41.878281 -106.461257) (xy 41.921149 -106.496932) (xy 41.958366 -106.538469)
			(xy 41.989139 -106.584982) (xy 42.012811 -106.635479) (xy 42.028879 -106.688886) (xy 42.036999 -106.744062)
			(xy 42.037508 -106.771948) (xy 42.036999 -106.799834) (xy 42.028879 -106.85501) (xy 42.012811 -106.908417)
			(xy 41.989139 -106.958914) (xy 41.958366 -107.005427) (xy 41.9352 -107.031282) (xy 44.797216 -107.031282)
			(xy 44.801287 -106.97566) (xy 44.813413 -106.921223) (xy 44.833336 -106.869132) (xy 44.860632 -106.820497)
			(xy 44.894718 -106.776354) (xy 44.934867 -106.737645) (xy 44.980225 -106.705194) (xy 45.029825 -106.679693)
			(xy 45.082609 -106.661686) (xy 45.137452 -106.651556) (xy 45.193186 -106.649519) (xy 45.248623 -106.655619)
			(xy 45.30258 -106.669725) (xy 45.353909 -106.691537) (xy 45.401515 -106.720591) (xy 45.444383 -106.756266)
			(xy 45.4816 -106.797803) (xy 45.512373 -106.844316) (xy 45.536045 -106.894813) (xy 45.552113 -106.94822)
			(xy 45.560233 -107.003396) (xy 45.560742 -107.031282) (xy 45.560233 -107.059168) (xy 45.552113 -107.114344)
			(xy 45.536045 -107.167751) (xy 45.512373 -107.218248) (xy 45.4816 -107.264761) (xy 45.444383 -107.306298)
			(xy 45.401515 -107.341973) (xy 45.353909 -107.371027) (xy 45.30258 -107.392839) (xy 45.248623 -107.406945)
			(xy 45.202429 -107.412028) (xy 50.199288 -107.412028) (xy 50.203359 -107.356406) (xy 50.215485 -107.301969)
			(xy 50.235408 -107.249878) (xy 50.262704 -107.201243) (xy 50.29679 -107.1571) (xy 50.336939 -107.118391)
			(xy 50.382297 -107.08594) (xy 50.431897 -107.060439) (xy 50.484681 -107.042432) (xy 50.539524 -107.032302)
			(xy 50.595258 -107.030265) (xy 50.650695 -107.036365) (xy 50.704652 -107.050471) (xy 50.755981 -107.072283)
			(xy 50.803587 -107.101337) (xy 50.846455 -107.137012) (xy 50.883672 -107.178549) (xy 50.914445 -107.225062)
			(xy 50.938117 -107.275559) (xy 50.954185 -107.328966) (xy 50.962305 -107.384142) (xy 50.962814 -107.412028)
			(xy 50.962305 -107.439914) (xy 50.954185 -107.49509) (xy 50.938117 -107.548497) (xy 50.914445 -107.598994)
			(xy 50.883672 -107.645507) (xy 50.846455 -107.687044) (xy 50.803587 -107.722719) (xy 50.755981 -107.751773)
			(xy 50.704652 -107.773585) (xy 50.650695 -107.787691) (xy 50.595258 -107.793791) (xy 50.539524 -107.791754)
			(xy 50.484681 -107.781624) (xy 50.431897 -107.763617) (xy 50.382297 -107.738116) (xy 50.336939 -107.705665)
			(xy 50.29679 -107.666956) (xy 50.262704 -107.622813) (xy 50.235408 -107.574178) (xy 50.215485 -107.522087)
			(xy 50.203359 -107.46765) (xy 50.199288 -107.412028) (xy 45.202429 -107.412028) (xy 45.193186 -107.413045)
			(xy 45.137452 -107.411008) (xy 45.082609 -107.400878) (xy 45.029825 -107.382871) (xy 44.980225 -107.35737)
			(xy 44.934867 -107.324919) (xy 44.894718 -107.28621) (xy 44.860632 -107.242067) (xy 44.833336 -107.193432)
			(xy 44.813413 -107.141341) (xy 44.801287 -107.086904) (xy 44.797216 -107.031282) (xy 41.9352 -107.031282)
			(xy 41.921149 -107.046964) (xy 41.878281 -107.082639) (xy 41.830675 -107.111693) (xy 41.779346 -107.133505)
			(xy 41.725389 -107.147611) (xy 41.669952 -107.153711) (xy 41.614218 -107.151674) (xy 41.559375 -107.141544)
			(xy 41.506591 -107.123537) (xy 41.456991 -107.098036) (xy 41.411633 -107.065585) (xy 41.371484 -107.026876)
			(xy 41.337398 -106.982733) (xy 41.310102 -106.934098) (xy 41.290179 -106.882007) (xy 41.278053 -106.82757)
			(xy 41.273982 -106.771948) (xy 38.228993 -106.771948) (xy 38.205383 -106.798298) (xy 38.162515 -106.833973)
			(xy 38.114909 -106.863027) (xy 38.06358 -106.884839) (xy 38.009623 -106.898945) (xy 37.954186 -106.905045)
			(xy 37.898452 -106.903008) (xy 37.843609 -106.892878) (xy 37.790825 -106.874871) (xy 37.741225 -106.84937)
			(xy 37.695867 -106.816919) (xy 37.655718 -106.77821) (xy 37.621632 -106.734067) (xy 37.594336 -106.685432)
			(xy 37.574413 -106.633341) (xy 37.562287 -106.578904) (xy 37.558216 -106.523282) (xy 35.80511 -106.523282)
			(xy 35.316414 -107.011978) (xy 33.865566 -107.011978) (xy 33.841831 -107.027372) (xy 33.790778 -107.051745)
			(xy 33.736688 -107.06832) (xy 33.680745 -107.076733) (xy 33.65246 -107.077256) (xy 33.624174 -107.076723)
			(xy 33.568229 -107.068326) (xy 33.51414 -107.051753) (xy 33.463094 -107.027366) (xy 33.439354 -107.011978)
			(xy 28.874974 -107.011978) (xy 24.919686 -103.05669) (xy 24.919686 -91.812364) (xy 23.224744 -90.117422)
			(xy 12.40409 -90.117422) (xy 11.952224 -90.569288) (xy 11.952224 -91.279472) (xy 11.990324 -91.289378)
			(xy 12.017331 -91.296791) (xy 12.068978 -91.318443) (xy 12.116906 -91.347411) (xy 12.160086 -91.383073)
			(xy 12.19759 -91.424663) (xy 12.228613 -91.471288) (xy 12.252488 -91.521946) (xy 12.268703 -91.575549)
			(xy 12.27691 -91.630947) (xy 12.277344 -91.658948) (xy 13.636242 -91.658948) (xy 13.640313 -91.603326)
			(xy 13.652439 -91.548889) (xy 13.672362 -91.496798) (xy 13.699658 -91.448163) (xy 13.733744 -91.40402)
			(xy 13.773893 -91.365311) (xy 13.819251 -91.33286) (xy 13.868851 -91.307359) (xy 13.921635 -91.289352)
			(xy 13.976478 -91.279222) (xy 14.032212 -91.277185) (xy 14.087649 -91.283285) (xy 14.141606 -91.297391)
			(xy 14.192935 -91.319203) (xy 14.240541 -91.348257) (xy 14.283409 -91.383932) (xy 14.320626 -91.425469)
			(xy 14.351399 -91.471982) (xy 14.375071 -91.522479) (xy 14.391139 -91.575886) (xy 14.397382 -91.618308)
			(xy 16.808956 -91.618308) (xy 16.813027 -91.562686) (xy 16.825153 -91.508249) (xy 16.845076 -91.456158)
			(xy 16.872372 -91.407523) (xy 16.906458 -91.36338) (xy 16.946607 -91.324671) (xy 16.991965 -91.29222)
			(xy 17.041565 -91.266719) (xy 17.094349 -91.248712) (xy 17.149192 -91.238582) (xy 17.204926 -91.236545)
			(xy 17.260363 -91.242645) (xy 17.31432 -91.256751) (xy 17.365649 -91.278563) (xy 17.413255 -91.307617)
			(xy 17.456123 -91.343292) (xy 17.49334 -91.384829) (xy 17.524113 -91.431342) (xy 17.547785 -91.481839)
			(xy 17.563853 -91.535246) (xy 17.571973 -91.590422) (xy 17.572482 -91.618308) (xy 17.571973 -91.646194)
			(xy 17.563853 -91.70137) (xy 17.547785 -91.754777) (xy 17.524113 -91.805274) (xy 17.49334 -91.851787)
			(xy 17.456123 -91.893324) (xy 17.413255 -91.928999) (xy 17.365649 -91.958053) (xy 17.31432 -91.979865)
			(xy 17.260363 -91.993971) (xy 17.204926 -92.000071) (xy 17.149192 -91.998034) (xy 17.094349 -91.987904)
			(xy 17.041565 -91.969897) (xy 16.991965 -91.944396) (xy 16.946607 -91.911945) (xy 16.906458 -91.873236)
			(xy 16.872372 -91.829093) (xy 16.845076 -91.780458) (xy 16.825153 -91.728367) (xy 16.813027 -91.67393)
			(xy 16.808956 -91.618308) (xy 14.397382 -91.618308) (xy 14.399259 -91.631062) (xy 14.399768 -91.658948)
			(xy 14.399259 -91.686834) (xy 14.391139 -91.74201) (xy 14.375071 -91.795417) (xy 14.351399 -91.845914)
			(xy 14.320626 -91.892427) (xy 14.283409 -91.933964) (xy 14.240541 -91.969639) (xy 14.192935 -91.998693)
			(xy 14.141606 -92.020505) (xy 14.087649 -92.034611) (xy 14.032212 -92.040711) (xy 13.976478 -92.038674)
			(xy 13.921635 -92.028544) (xy 13.868851 -92.010537) (xy 13.819251 -91.985036) (xy 13.773893 -91.952585)
			(xy 13.733744 -91.913876) (xy 13.699658 -91.869733) (xy 13.672362 -91.821098) (xy 13.652439 -91.769007)
			(xy 13.640313 -91.71457) (xy 13.636242 -91.658948) (xy 12.277344 -91.658948) (xy 12.276846 -91.686964)
			(xy 12.268637 -91.742391) (xy 12.252405 -91.79602) (xy 12.228497 -91.846695) (xy 12.19743 -91.893325)
			(xy 12.179046 -91.914472) (xy 12.146788 -91.950286) (xy 12.60221 -92.405708) (xy 17.856962 -92.405708)
			(xy 19.015202 -93.563948) (xy 19.015202 -95.510604) (xy 21.882098 -95.510604) (xy 21.886169 -95.454982)
			(xy 21.898295 -95.400545) (xy 21.918218 -95.348454) (xy 21.945514 -95.299819) (xy 21.9796 -95.255676)
			(xy 22.019749 -95.216967) (xy 22.065107 -95.184516) (xy 22.114707 -95.159015) (xy 22.167491 -95.141008)
			(xy 22.222334 -95.130878) (xy 22.278068 -95.128841) (xy 22.333505 -95.134941) (xy 22.387462 -95.149047)
			(xy 22.438791 -95.170859) (xy 22.486397 -95.199913) (xy 22.529265 -95.235588) (xy 22.566482 -95.277125)
			(xy 22.597255 -95.323638) (xy 22.620927 -95.374135) (xy 22.636995 -95.427542) (xy 22.645115 -95.482718)
			(xy 22.645624 -95.510604) (xy 22.645115 -95.53849) (xy 22.636995 -95.593666) (xy 22.620927 -95.647073)
			(xy 22.597255 -95.69757) (xy 22.566482 -95.744083) (xy 22.529265 -95.78562) (xy 22.486397 -95.821295)
			(xy 22.438791 -95.850349) (xy 22.387462 -95.872161) (xy 22.333505 -95.886267) (xy 22.278068 -95.892367)
			(xy 22.222334 -95.89033) (xy 22.167491 -95.8802) (xy 22.114707 -95.862193) (xy 22.065107 -95.836692)
			(xy 22.019749 -95.804241) (xy 21.9796 -95.765532) (xy 21.945514 -95.721389) (xy 21.918218 -95.672754)
			(xy 21.898295 -95.620663) (xy 21.886169 -95.566226) (xy 21.882098 -95.510604) (xy 19.015202 -95.510604)
			(xy 19.015202 -98.171508) (xy 21.848062 -98.171508) (xy 21.852133 -98.115886) (xy 21.864259 -98.061449)
			(xy 21.884182 -98.009358) (xy 21.911478 -97.960723) (xy 21.945564 -97.91658) (xy 21.985713 -97.877871)
			(xy 22.031071 -97.84542) (xy 22.080671 -97.819919) (xy 22.133455 -97.801912) (xy 22.188298 -97.791782)
			(xy 22.244032 -97.789745) (xy 22.299469 -97.795845) (xy 22.353426 -97.809951) (xy 22.404755 -97.831763)
			(xy 22.452361 -97.860817) (xy 22.495229 -97.896492) (xy 22.532446 -97.938029) (xy 22.563219 -97.984542)
			(xy 22.586891 -98.035039) (xy 22.602959 -98.088446) (xy 22.611079 -98.143622) (xy 22.611588 -98.171508)
			(xy 22.611079 -98.199394) (xy 22.602959 -98.25457) (xy 22.586891 -98.307977) (xy 22.563219 -98.358474)
			(xy 22.532446 -98.404987) (xy 22.495229 -98.446524) (xy 22.452361 -98.482199) (xy 22.404755 -98.511253)
			(xy 22.353426 -98.533065) (xy 22.299469 -98.547171) (xy 22.244032 -98.553271) (xy 22.188298 -98.551234)
			(xy 22.133455 -98.541104) (xy 22.080671 -98.523097) (xy 22.031071 -98.497596) (xy 21.985713 -98.465145)
			(xy 21.945564 -98.426436) (xy 21.911478 -98.382293) (xy 21.884182 -98.333658) (xy 21.864259 -98.281567)
			(xy 21.852133 -98.22713) (xy 21.848062 -98.171508) (xy 19.015202 -98.171508) (xy 19.015202 -105.118916)
			(xy 17.010634 -107.123484) (xy 17.84807 -107.123484) (xy 17.852141 -107.067862) (xy 17.864267 -107.013425)
			(xy 17.88419 -106.961334) (xy 17.911486 -106.912699) (xy 17.945572 -106.868556) (xy 17.985721 -106.829847)
			(xy 18.031079 -106.797396) (xy 18.080679 -106.771895) (xy 18.133463 -106.753888) (xy 18.188306 -106.743758)
			(xy 18.24404 -106.741721) (xy 18.299477 -106.747821) (xy 18.349988 -106.761026) (xy 21.417786 -106.761026)
			(xy 21.421857 -106.705404) (xy 21.433983 -106.650967) (xy 21.453906 -106.598876) (xy 21.481202 -106.550241)
			(xy 21.515288 -106.506098) (xy 21.555437 -106.467389) (xy 21.600795 -106.434938) (xy 21.650395 -106.409437)
			(xy 21.703179 -106.39143) (xy 21.758022 -106.3813) (xy 21.813756 -106.379263) (xy 21.869193 -106.385363)
			(xy 21.92315 -106.399469) (xy 21.974479 -106.421281) (xy 22.022085 -106.450335) (xy 22.064953 -106.48601)
			(xy 22.10217 -106.527547) (xy 22.132943 -106.57406) (xy 22.156615 -106.624557) (xy 22.172683 -106.677964)
			(xy 22.180803 -106.73314) (xy 22.181312 -106.761026) (xy 22.180803 -106.788912) (xy 22.172683 -106.844088)
			(xy 22.156615 -106.897495) (xy 22.132943 -106.947992) (xy 22.10217 -106.994505) (xy 22.064953 -107.036042)
			(xy 22.022085 -107.071717) (xy 21.974479 -107.100771) (xy 21.92315 -107.122583) (xy 21.869193 -107.136689)
			(xy 21.813756 -107.142789) (xy 21.758022 -107.140752) (xy 21.703179 -107.130622) (xy 21.650395 -107.112615)
			(xy 21.600795 -107.087114) (xy 21.555437 -107.054663) (xy 21.515288 -107.015954) (xy 21.481202 -106.971811)
			(xy 21.453906 -106.923176) (xy 21.433983 -106.871085) (xy 21.421857 -106.816648) (xy 21.417786 -106.761026)
			(xy 18.349988 -106.761026) (xy 18.353434 -106.761927) (xy 18.404763 -106.783739) (xy 18.452369 -106.812793)
			(xy 18.495237 -106.848468) (xy 18.532454 -106.890005) (xy 18.563227 -106.936518) (xy 18.586899 -106.987015)
			(xy 18.602967 -107.040422) (xy 18.611087 -107.095598) (xy 18.611596 -107.123484) (xy 18.611087 -107.15137)
			(xy 18.602967 -107.206546) (xy 18.586899 -107.259953) (xy 18.563227 -107.31045) (xy 18.532454 -107.356963)
			(xy 18.495237 -107.3985) (xy 18.452369 -107.434175) (xy 18.404763 -107.463229) (xy 18.353434 -107.485041)
			(xy 18.299477 -107.499147) (xy 18.24404 -107.505247) (xy 18.188306 -107.50321) (xy 18.133463 -107.49308)
			(xy 18.080679 -107.475073) (xy 18.031079 -107.449572) (xy 17.985721 -107.417121) (xy 17.945572 -107.378412)
			(xy 17.911486 -107.334269) (xy 17.88419 -107.285634) (xy 17.864267 -107.233543) (xy 17.852141 -107.179106)
			(xy 17.84807 -107.123484) (xy 17.010634 -107.123484) (xy 16.357092 -107.777026) (xy 21.417786 -107.777026)
			(xy 21.421857 -107.721404) (xy 21.433983 -107.666967) (xy 21.453906 -107.614876) (xy 21.481202 -107.566241)
			(xy 21.515288 -107.522098) (xy 21.555437 -107.483389) (xy 21.600795 -107.450938) (xy 21.650395 -107.425437)
			(xy 21.703179 -107.40743) (xy 21.758022 -107.3973) (xy 21.813756 -107.395263) (xy 21.869193 -107.401363)
			(xy 21.92315 -107.415469) (xy 21.974479 -107.437281) (xy 22.022085 -107.466335) (xy 22.064953 -107.50201)
			(xy 22.098349 -107.539282) (xy 37.558216 -107.539282) (xy 37.562287 -107.48366) (xy 37.574413 -107.429223)
			(xy 37.594336 -107.377132) (xy 37.621632 -107.328497) (xy 37.655718 -107.284354) (xy 37.695867 -107.245645)
			(xy 37.741225 -107.213194) (xy 37.790825 -107.187693) (xy 37.843609 -107.169686) (xy 37.898452 -107.159556)
			(xy 37.954186 -107.157519) (xy 38.009623 -107.163619) (xy 38.06358 -107.177725) (xy 38.114909 -107.199537)
			(xy 38.162515 -107.228591) (xy 38.205383 -107.264266) (xy 38.2426 -107.305803) (xy 38.273373 -107.352316)
			(xy 38.297045 -107.402813) (xy 38.313113 -107.45622) (xy 38.321233 -107.511396) (xy 38.321742 -107.539282)
			(xy 38.321233 -107.567168) (xy 38.313113 -107.622344) (xy 38.297045 -107.675751) (xy 38.273373 -107.726248)
			(xy 38.2426 -107.772761) (xy 38.205383 -107.814298) (xy 38.162515 -107.849973) (xy 38.114909 -107.879027)
			(xy 38.06358 -107.900839) (xy 38.009623 -107.914945) (xy 37.954186 -107.921045) (xy 37.898452 -107.919008)
			(xy 37.843609 -107.908878) (xy 37.790825 -107.890871) (xy 37.741225 -107.86537) (xy 37.695867 -107.832919)
			(xy 37.655718 -107.79421) (xy 37.621632 -107.750067) (xy 37.594336 -107.701432) (xy 37.574413 -107.649341)
			(xy 37.562287 -107.594904) (xy 37.558216 -107.539282) (xy 22.098349 -107.539282) (xy 22.10217 -107.543547)
			(xy 22.132943 -107.59006) (xy 22.156615 -107.640557) (xy 22.172683 -107.693964) (xy 22.180803 -107.74914)
			(xy 22.181312 -107.777026) (xy 22.180803 -107.804912) (xy 22.172683 -107.860088) (xy 22.156615 -107.913495)
			(xy 22.132943 -107.963992) (xy 22.10217 -108.010505) (xy 22.069218 -108.047282) (xy 41.255186 -108.047282)
			(xy 41.259257 -107.99166) (xy 41.271383 -107.937223) (xy 41.291306 -107.885132) (xy 41.318602 -107.836497)
			(xy 41.352688 -107.792354) (xy 41.392837 -107.753645) (xy 41.438195 -107.721194) (xy 41.487795 -107.695693)
			(xy 41.540579 -107.677686) (xy 41.595422 -107.667556) (xy 41.651156 -107.665519) (xy 41.706593 -107.671619)
			(xy 41.76055 -107.685725) (xy 41.811879 -107.707537) (xy 41.859485 -107.736591) (xy 41.902353 -107.772266)
			(xy 41.93957 -107.813803) (xy 41.970343 -107.860316) (xy 41.994015 -107.910813) (xy 42.010083 -107.96422)
			(xy 42.018203 -108.019396) (xy 42.018712 -108.047282) (xy 44.797216 -108.047282) (xy 44.801287 -107.99166)
			(xy 44.813413 -107.937223) (xy 44.833336 -107.885132) (xy 44.860632 -107.836497) (xy 44.894718 -107.792354)
			(xy 44.934867 -107.753645) (xy 44.980225 -107.721194) (xy 45.029825 -107.695693) (xy 45.082609 -107.677686)
			(xy 45.137452 -107.667556) (xy 45.193186 -107.665519) (xy 45.248623 -107.671619) (xy 45.30258 -107.685725)
			(xy 45.353909 -107.707537) (xy 45.401515 -107.736591) (xy 45.444383 -107.772266) (xy 45.4816 -107.813803)
			(xy 45.512373 -107.860316) (xy 45.536045 -107.910813) (xy 45.552113 -107.96422) (xy 45.560233 -108.019396)
			(xy 45.560742 -108.047282) (xy 47.210216 -108.047282) (xy 47.214287 -107.99166) (xy 47.226413 -107.937223)
			(xy 47.246336 -107.885132) (xy 47.273632 -107.836497) (xy 47.307718 -107.792354) (xy 47.347867 -107.753645)
			(xy 47.393225 -107.721194) (xy 47.442825 -107.695693) (xy 47.495609 -107.677686) (xy 47.550452 -107.667556)
			(xy 47.606186 -107.665519) (xy 47.661623 -107.671619) (xy 47.71558 -107.685725) (xy 47.766909 -107.707537)
			(xy 47.814515 -107.736591) (xy 47.857383 -107.772266) (xy 47.8946 -107.813803) (xy 47.925373 -107.860316)
			(xy 47.949045 -107.910813) (xy 47.965113 -107.96422) (xy 47.973233 -108.019396) (xy 47.973742 -108.047282)
			(xy 47.973233 -108.075168) (xy 47.965113 -108.130344) (xy 47.949045 -108.183751) (xy 47.925373 -108.234248)
			(xy 47.8946 -108.280761) (xy 47.857383 -108.322298) (xy 47.814515 -108.357973) (xy 47.766909 -108.387027)
			(xy 47.71558 -108.408839) (xy 47.661623 -108.422945) (xy 47.606186 -108.429045) (xy 47.550452 -108.427008)
			(xy 47.495609 -108.416878) (xy 47.442825 -108.398871) (xy 47.393225 -108.37337) (xy 47.347867 -108.340919)
			(xy 47.307718 -108.30221) (xy 47.273632 -108.258067) (xy 47.246336 -108.209432) (xy 47.226413 -108.157341)
			(xy 47.214287 -108.102904) (xy 47.210216 -108.047282) (xy 45.560742 -108.047282) (xy 45.560233 -108.075168)
			(xy 45.552113 -108.130344) (xy 45.536045 -108.183751) (xy 45.512373 -108.234248) (xy 45.4816 -108.280761)
			(xy 45.444383 -108.322298) (xy 45.401515 -108.357973) (xy 45.353909 -108.387027) (xy 45.30258 -108.408839)
			(xy 45.248623 -108.422945) (xy 45.193186 -108.429045) (xy 45.137452 -108.427008) (xy 45.082609 -108.416878)
			(xy 45.029825 -108.398871) (xy 44.980225 -108.37337) (xy 44.934867 -108.340919) (xy 44.894718 -108.30221)
			(xy 44.860632 -108.258067) (xy 44.833336 -108.209432) (xy 44.813413 -108.157341) (xy 44.801287 -108.102904)
			(xy 44.797216 -108.047282) (xy 42.018712 -108.047282) (xy 42.018203 -108.075168) (xy 42.010083 -108.130344)
			(xy 41.994015 -108.183751) (xy 41.970343 -108.234248) (xy 41.93957 -108.280761) (xy 41.902353 -108.322298)
			(xy 41.859485 -108.357973) (xy 41.811879 -108.387027) (xy 41.76055 -108.408839) (xy 41.706593 -108.422945)
			(xy 41.651156 -108.429045) (xy 41.595422 -108.427008) (xy 41.540579 -108.416878) (xy 41.487795 -108.398871)
			(xy 41.438195 -108.37337) (xy 41.392837 -108.340919) (xy 41.352688 -108.30221) (xy 41.318602 -108.258067)
			(xy 41.291306 -108.209432) (xy 41.271383 -108.157341) (xy 41.259257 -108.102904) (xy 41.255186 -108.047282)
			(xy 22.069218 -108.047282) (xy 22.064953 -108.052042) (xy 22.022085 -108.087717) (xy 21.974479 -108.116771)
			(xy 21.92315 -108.138583) (xy 21.869193 -108.152689) (xy 21.813756 -108.158789) (xy 21.758022 -108.156752)
			(xy 21.703179 -108.146622) (xy 21.650395 -108.128615) (xy 21.600795 -108.103114) (xy 21.555437 -108.070663)
			(xy 21.515288 -108.031954) (xy 21.481202 -107.987811) (xy 21.453906 -107.939176) (xy 21.433983 -107.887085)
			(xy 21.421857 -107.832648) (xy 21.417786 -107.777026) (xy 16.357092 -107.777026) (xy 16.274542 -107.859576)
			(xy 15.700248 -107.859576) (xy 15.685639 -107.860088) (xy 15.657634 -107.868426) (xy 15.633133 -107.884349)
			(xy 15.614139 -107.906554) (xy 15.602205 -107.933226) (xy 15.598306 -107.962185) (xy 15.602762 -107.991064)
			(xy 15.615208 -108.017501) (xy 15.624556 -108.02874) (xy 15.642681 -108.04983) (xy 15.673266 -108.09627)
			(xy 15.696793 -108.146655) (xy 15.712762 -108.199919) (xy 15.720836 -108.254937) (xy 15.72133 -108.28274)
			(xy 15.720748 -108.313044) (xy 15.711182 -108.372893) (xy 15.70228 -108.401866) (xy 15.69842 -108.415048)
			(xy 15.697106 -108.442472) (xy 15.703149 -108.469254) (xy 15.716111 -108.493457) (xy 15.735054 -108.51333)
			(xy 15.75861 -108.527436) (xy 15.785072 -108.534753) (xy 15.7988 -108.535216) (xy 16.139668 -108.535216)
			(xy 16.153401 -108.53477) (xy 16.179874 -108.527457) (xy 16.20344 -108.513351) (xy 16.222393 -108.493474)
			(xy 16.235362 -108.469263) (xy 16.241407 -108.442472) (xy 16.240092 -108.415038) (xy 16.236188 -108.401866)
			(xy 16.227281 -108.372894) (xy 16.217715 -108.313045) (xy 16.217138 -108.28274) (xy 16.217624 -108.255489)
			(xy 16.22538 -108.201541) (xy 16.240735 -108.149246) (xy 16.263377 -108.099669) (xy 16.292843 -108.053819)
			(xy 16.328534 -108.012628) (xy 16.369725 -107.976937) (xy 16.415575 -107.947471) (xy 16.465152 -107.924829)
			(xy 16.517447 -107.909474) (xy 16.571395 -107.901718) (xy 16.625897 -107.901718) (xy 16.679845 -107.909474)
			(xy 16.73214 -107.924829) (xy 16.781717 -107.947471) (xy 16.827567 -107.976937) (xy 16.868758 -108.012628)
			(xy 16.904449 -108.053819) (xy 16.933915 -108.099669) (xy 16.956557 -108.149246) (xy 16.971912 -108.201541)
			(xy 16.979668 -108.255489) (xy 16.980154 -108.28274) (xy 16.979619 -108.311626) (xy 16.970904 -108.368736)
			(xy 16.953678 -108.42388) (xy 16.928336 -108.475797) (xy 16.895457 -108.5233) (xy 16.855792 -108.565303)
			(xy 16.810248 -108.600847) (xy 16.785336 -108.61548) (xy 16.772126 -108.623487) (xy 16.750912 -108.645919)
			(xy 16.737367 -108.673665) (xy 16.732728 -108.704189) (xy 16.73742 -108.734706) (xy 16.74368 -108.74883)
			(xy 16.755986 -108.775091) (xy 16.76163 -108.793026) (xy 21.417786 -108.793026) (xy 21.421857 -108.737404)
			(xy 21.433983 -108.682967) (xy 21.453906 -108.630876) (xy 21.481202 -108.582241) (xy 21.515288 -108.538098)
			(xy 21.555437 -108.499389) (xy 21.600795 -108.466938) (xy 21.650395 -108.441437) (xy 21.703179 -108.42343)
			(xy 21.758022 -108.4133) (xy 21.813756 -108.411263) (xy 21.869193 -108.417363) (xy 21.92315 -108.431469)
			(xy 21.974479 -108.453281) (xy 22.022085 -108.482335) (xy 22.064953 -108.51801) (xy 22.098349 -108.555282)
			(xy 37.558216 -108.555282) (xy 37.562287 -108.49966) (xy 37.574413 -108.445223) (xy 37.594336 -108.393132)
			(xy 37.621632 -108.344497) (xy 37.655718 -108.300354) (xy 37.695867 -108.261645) (xy 37.741225 -108.229194)
			(xy 37.790825 -108.203693) (xy 37.843609 -108.185686) (xy 37.898452 -108.175556) (xy 37.954186 -108.173519)
			(xy 38.009623 -108.179619) (xy 38.06358 -108.193725) (xy 38.114909 -108.215537) (xy 38.162515 -108.244591)
			(xy 38.205383 -108.280266) (xy 38.2426 -108.321803) (xy 38.273373 -108.368316) (xy 38.297045 -108.418813)
			(xy 38.313113 -108.47222) (xy 38.321233 -108.527396) (xy 38.321742 -108.555282) (xy 38.321233 -108.583168)
			(xy 38.313113 -108.638344) (xy 38.297045 -108.691751) (xy 38.273373 -108.742248) (xy 38.2426 -108.788761)
			(xy 38.205383 -108.830298) (xy 38.162515 -108.865973) (xy 38.154272 -108.871004) (xy 50.17592 -108.871004)
			(xy 50.179991 -108.815382) (xy 50.192117 -108.760945) (xy 50.21204 -108.708854) (xy 50.239336 -108.660219)
			(xy 50.273422 -108.616076) (xy 50.313571 -108.577367) (xy 50.358929 -108.544916) (xy 50.408529 -108.519415)
			(xy 50.461313 -108.501408) (xy 50.516156 -108.491278) (xy 50.57189 -108.489241) (xy 50.627327 -108.495341)
			(xy 50.681284 -108.509447) (xy 50.732613 -108.531259) (xy 50.780219 -108.560313) (xy 50.823087 -108.595988)
			(xy 50.860304 -108.637525) (xy 50.891077 -108.684038) (xy 50.914749 -108.734535) (xy 50.930817 -108.787942)
			(xy 50.938937 -108.843118) (xy 50.939446 -108.871004) (xy 50.938937 -108.89889) (xy 50.930817 -108.954066)
			(xy 50.914749 -109.007473) (xy 50.891077 -109.05797) (xy 50.860304 -109.104483) (xy 50.823087 -109.14602)
			(xy 50.780219 -109.181695) (xy 50.732613 -109.210749) (xy 50.681284 -109.232561) (xy 50.627327 -109.246667)
			(xy 50.57189 -109.252767) (xy 50.516156 -109.25073) (xy 50.461313 -109.2406) (xy 50.408529 -109.222593)
			(xy 50.358929 -109.197092) (xy 50.313571 -109.164641) (xy 50.273422 -109.125932) (xy 50.239336 -109.081789)
			(xy 50.21204 -109.033154) (xy 50.192117 -108.981063) (xy 50.179991 -108.926626) (xy 50.17592 -108.871004)
			(xy 38.154272 -108.871004) (xy 38.114909 -108.895027) (xy 38.06358 -108.916839) (xy 38.009623 -108.930945)
			(xy 37.954186 -108.937045) (xy 37.898452 -108.935008) (xy 37.843609 -108.924878) (xy 37.790825 -108.906871)
			(xy 37.741225 -108.88137) (xy 37.695867 -108.848919) (xy 37.655718 -108.81021) (xy 37.621632 -108.766067)
			(xy 37.594336 -108.717432) (xy 37.574413 -108.665341) (xy 37.562287 -108.610904) (xy 37.558216 -108.555282)
			(xy 22.098349 -108.555282) (xy 22.10217 -108.559547) (xy 22.132943 -108.60606) (xy 22.156615 -108.656557)
			(xy 22.172683 -108.709964) (xy 22.180803 -108.76514) (xy 22.181312 -108.793026) (xy 22.180803 -108.820912)
			(xy 22.172683 -108.876088) (xy 22.156615 -108.929495) (xy 22.132943 -108.979992) (xy 22.10217 -109.026505)
			(xy 22.064953 -109.068042) (xy 22.022085 -109.103717) (xy 21.974479 -109.132771) (xy 21.92315 -109.154583)
			(xy 21.869193 -109.168689) (xy 21.813756 -109.174789) (xy 21.758022 -109.172752) (xy 21.703179 -109.162622)
			(xy 21.650395 -109.144615) (xy 21.600795 -109.119114) (xy 21.555437 -109.086663) (xy 21.515288 -109.047954)
			(xy 21.481202 -109.003811) (xy 21.453906 -108.955176) (xy 21.433983 -108.903085) (xy 21.421857 -108.848648)
			(xy 21.417786 -108.793026) (xy 16.76163 -108.793026) (xy 16.773393 -108.83041) (xy 16.782219 -108.887728)
			(xy 16.782796 -108.916724) (xy 16.78233 -108.943987) (xy 16.774564 -108.997957) (xy 16.759193 -109.050272)
			(xy 16.73653 -109.099865) (xy 16.707038 -109.145726) (xy 16.671316 -109.186922) (xy 16.630094 -109.222612)
			(xy 16.58421 -109.252069) (xy 16.534599 -109.274694) (xy 16.482273 -109.290025) (xy 16.428297 -109.297751)
			(xy 16.401034 -109.298232) (xy 15.537434 -109.298232) (xy 15.510175 -109.297749) (xy 15.456212 -109.289997)
			(xy 15.4039 -109.274647) (xy 15.354305 -109.252011) (xy 15.308434 -109.22255) (xy 15.267221 -109.186861)
			(xy 15.231505 -109.145673) (xy 15.202012 -109.099822) (xy 15.179343 -109.050242) (xy 15.163958 -108.99794)
			(xy 15.15617 -108.943982) (xy 15.155672 -108.916724) (xy 15.156253 -108.887729) (xy 15.165097 -108.830416)
			(xy 15.182495 -108.775096) (xy 15.194788 -108.74883) (xy 15.201105 -108.734724) (xy 15.205801 -108.704191)
			(xy 15.201159 -108.673649) (xy 15.187604 -108.64589) (xy 15.166373 -108.623449) (xy 15.153132 -108.61548)
			(xy 15.128195 -108.600884) (xy 15.082638 -108.565344) (xy 15.042963 -108.523339) (xy 15.010077 -108.47583)
			(xy 14.984733 -108.423904) (xy 14.967511 -108.368751) (xy 14.958805 -108.31163) (xy 14.958314 -108.28274)
			(xy 14.958791 -108.254874) (xy 14.966903 -108.199735) (xy 14.982974 -108.14637) (xy 14.994382 -108.120942)
			(xy 15.009368 -108.088684) (xy 14.948408 -108.02747) (xy 14.777212 -108.198666) (xy 14.777212 -109.859826)
			(xy 18.792442 -109.859826) (xy 18.796513 -109.804204) (xy 18.808639 -109.749767) (xy 18.828562 -109.697676)
			(xy 18.855858 -109.649041) (xy 18.889944 -109.604898) (xy 18.930093 -109.566189) (xy 18.975451 -109.533738)
			(xy 19.025051 -109.508237) (xy 19.077835 -109.49023) (xy 19.132678 -109.4801) (xy 19.188412 -109.478063)
			(xy 19.243849 -109.484163) (xy 19.297806 -109.498269) (xy 19.349135 -109.520081) (xy 19.396741 -109.549135)
			(xy 19.439609 -109.58481) (xy 19.476826 -109.626347) (xy 19.498203 -109.658658) (xy 25.3525 -109.658658)
			(xy 25.356571 -109.603036) (xy 25.368697 -109.548599) (xy 25.38862 -109.496508) (xy 25.415916 -109.447873)
			(xy 25.450002 -109.40373) (xy 25.490151 -109.365021) (xy 25.535509 -109.33257) (xy 25.585109 -109.307069)
			(xy 25.637893 -109.289062) (xy 25.692736 -109.278932) (xy 25.74847 -109.276895) (xy 25.803907 -109.282995)
			(xy 25.857864 -109.297101) (xy 25.909193 -109.318913) (xy 25.956799 -109.347967) (xy 25.999667 -109.383642)
			(xy 26.036884 -109.425179) (xy 26.067657 -109.471692) (xy 26.091329 -109.522189) (xy 26.106099 -109.571282)
			(xy 37.558216 -109.571282) (xy 37.562287 -109.51566) (xy 37.574413 -109.461223) (xy 37.594336 -109.409132)
			(xy 37.621632 -109.360497) (xy 37.655718 -109.316354) (xy 37.695867 -109.277645) (xy 37.741225 -109.245194)
			(xy 37.790825 -109.219693) (xy 37.843609 -109.201686) (xy 37.898452 -109.191556) (xy 37.954186 -109.189519)
			(xy 38.009623 -109.195619) (xy 38.06358 -109.209725) (xy 38.114909 -109.231537) (xy 38.162515 -109.260591)
			(xy 38.205383 -109.296266) (xy 38.2426 -109.337803) (xy 38.273373 -109.384316) (xy 38.297045 -109.434813)
			(xy 38.299894 -109.444282) (xy 41.255186 -109.444282) (xy 41.259257 -109.38866) (xy 41.271383 -109.334223)
			(xy 41.291306 -109.282132) (xy 41.318602 -109.233497) (xy 41.352688 -109.189354) (xy 41.392837 -109.150645)
			(xy 41.438195 -109.118194) (xy 41.487795 -109.092693) (xy 41.540579 -109.074686) (xy 41.595422 -109.064556)
			(xy 41.651156 -109.062519) (xy 41.706593 -109.068619) (xy 41.76055 -109.082725) (xy 41.811879 -109.104537)
			(xy 41.859485 -109.133591) (xy 41.902353 -109.169266) (xy 41.93957 -109.210803) (xy 41.970343 -109.257316)
			(xy 41.994015 -109.307813) (xy 42.010083 -109.36122) (xy 42.018203 -109.416396) (xy 42.018712 -109.444282)
			(xy 44.797216 -109.444282) (xy 44.801287 -109.38866) (xy 44.813413 -109.334223) (xy 44.833336 -109.282132)
			(xy 44.860632 -109.233497) (xy 44.894718 -109.189354) (xy 44.934867 -109.150645) (xy 44.980225 -109.118194)
			(xy 45.029825 -109.092693) (xy 45.082609 -109.074686) (xy 45.137452 -109.064556) (xy 45.193186 -109.062519)
			(xy 45.248623 -109.068619) (xy 45.30258 -109.082725) (xy 45.353909 -109.104537) (xy 45.401515 -109.133591)
			(xy 45.444383 -109.169266) (xy 45.4816 -109.210803) (xy 45.512373 -109.257316) (xy 45.536045 -109.307813)
			(xy 45.552113 -109.36122) (xy 45.560233 -109.416396) (xy 45.560742 -109.444282) (xy 47.210216 -109.444282)
			(xy 47.214287 -109.38866) (xy 47.226413 -109.334223) (xy 47.246336 -109.282132) (xy 47.273632 -109.233497)
			(xy 47.307718 -109.189354) (xy 47.347867 -109.150645) (xy 47.393225 -109.118194) (xy 47.442825 -109.092693)
			(xy 47.495609 -109.074686) (xy 47.550452 -109.064556) (xy 47.606186 -109.062519) (xy 47.661623 -109.068619)
			(xy 47.71558 -109.082725) (xy 47.766909 -109.104537) (xy 47.814515 -109.133591) (xy 47.857383 -109.169266)
			(xy 47.8946 -109.210803) (xy 47.925373 -109.257316) (xy 47.933599 -109.274864) (xy 48.209452 -109.274864)
			(xy 48.213523 -109.219242) (xy 48.225649 -109.164805) (xy 48.245572 -109.112714) (xy 48.272868 -109.064079)
			(xy 48.306954 -109.019936) (xy 48.347103 -108.981227) (xy 48.392461 -108.948776) (xy 48.442061 -108.923275)
			(xy 48.494845 -108.905268) (xy 48.549688 -108.895138) (xy 48.605422 -108.893101) (xy 48.660859 -108.899201)
			(xy 48.714816 -108.913307) (xy 48.766145 -108.935119) (xy 48.813751 -108.964173) (xy 48.856619 -108.999848)
			(xy 48.893836 -109.041385) (xy 48.924609 -109.087898) (xy 48.948281 -109.138395) (xy 48.964349 -109.191802)
			(xy 48.972469 -109.246978) (xy 48.972978 -109.274864) (xy 48.972469 -109.30275) (xy 48.964349 -109.357926)
			(xy 48.948281 -109.411333) (xy 48.924609 -109.46183) (xy 48.893836 -109.508343) (xy 48.856619 -109.54988)
			(xy 48.813751 -109.585555) (xy 48.766145 -109.614609) (xy 48.714816 -109.636421) (xy 48.660859 -109.650527)
			(xy 48.605422 -109.656627) (xy 48.549688 -109.65459) (xy 48.494845 -109.64446) (xy 48.442061 -109.626453)
			(xy 48.392461 -109.600952) (xy 48.347103 -109.568501) (xy 48.306954 -109.529792) (xy 48.272868 -109.485649)
			(xy 48.245572 -109.437014) (xy 48.225649 -109.384923) (xy 48.213523 -109.330486) (xy 48.209452 -109.274864)
			(xy 47.933599 -109.274864) (xy 47.949045 -109.307813) (xy 47.965113 -109.36122) (xy 47.973233 -109.416396)
			(xy 47.973742 -109.444282) (xy 47.973233 -109.472168) (xy 47.965113 -109.527344) (xy 47.949045 -109.580751)
			(xy 47.925373 -109.631248) (xy 47.8946 -109.677761) (xy 47.857383 -109.719298) (xy 47.814515 -109.754973)
			(xy 47.766909 -109.784027) (xy 47.71558 -109.805839) (xy 47.661623 -109.819945) (xy 47.606186 -109.826045)
			(xy 47.550452 -109.824008) (xy 47.495609 -109.813878) (xy 47.442825 -109.795871) (xy 47.393225 -109.77037)
			(xy 47.347867 -109.737919) (xy 47.307718 -109.69921) (xy 47.273632 -109.655067) (xy 47.246336 -109.606432)
			(xy 47.226413 -109.554341) (xy 47.214287 -109.499904) (xy 47.210216 -109.444282) (xy 45.560742 -109.444282)
			(xy 45.560233 -109.472168) (xy 45.552113 -109.527344) (xy 45.536045 -109.580751) (xy 45.512373 -109.631248)
			(xy 45.4816 -109.677761) (xy 45.444383 -109.719298) (xy 45.401515 -109.754973) (xy 45.353909 -109.784027)
			(xy 45.30258 -109.805839) (xy 45.248623 -109.819945) (xy 45.193186 -109.826045) (xy 45.137452 -109.824008)
			(xy 45.082609 -109.813878) (xy 45.029825 -109.795871) (xy 44.980225 -109.77037) (xy 44.934867 -109.737919)
			(xy 44.894718 -109.69921) (xy 44.860632 -109.655067) (xy 44.833336 -109.606432) (xy 44.813413 -109.554341)
			(xy 44.801287 -109.499904) (xy 44.797216 -109.444282) (xy 42.018712 -109.444282) (xy 42.018203 -109.472168)
			(xy 42.010083 -109.527344) (xy 41.994015 -109.580751) (xy 41.970343 -109.631248) (xy 41.93957 -109.677761)
			(xy 41.902353 -109.719298) (xy 41.859485 -109.754973) (xy 41.811879 -109.784027) (xy 41.76055 -109.805839)
			(xy 41.706593 -109.819945) (xy 41.651156 -109.826045) (xy 41.595422 -109.824008) (xy 41.540579 -109.813878)
			(xy 41.487795 -109.795871) (xy 41.438195 -109.77037) (xy 41.392837 -109.737919) (xy 41.352688 -109.69921)
			(xy 41.318602 -109.655067) (xy 41.291306 -109.606432) (xy 41.271383 -109.554341) (xy 41.259257 -109.499904)
			(xy 41.255186 -109.444282) (xy 38.299894 -109.444282) (xy 38.313113 -109.48822) (xy 38.321233 -109.543396)
			(xy 38.321742 -109.571282) (xy 38.321233 -109.599168) (xy 38.313113 -109.654344) (xy 38.297045 -109.707751)
			(xy 38.273373 -109.758248) (xy 38.2426 -109.804761) (xy 38.205383 -109.846298) (xy 38.162515 -109.881973)
			(xy 38.114909 -109.911027) (xy 38.06358 -109.932839) (xy 38.009623 -109.946945) (xy 37.954186 -109.953045)
			(xy 37.898452 -109.951008) (xy 37.843609 -109.940878) (xy 37.790825 -109.922871) (xy 37.741225 -109.89737)
			(xy 37.695867 -109.864919) (xy 37.655718 -109.82621) (xy 37.621632 -109.782067) (xy 37.594336 -109.733432)
			(xy 37.574413 -109.681341) (xy 37.562287 -109.626904) (xy 37.558216 -109.571282) (xy 26.106099 -109.571282)
			(xy 26.107397 -109.575596) (xy 26.115517 -109.630772) (xy 26.116026 -109.658658) (xy 26.115517 -109.686544)
			(xy 26.107397 -109.74172) (xy 26.091329 -109.795127) (xy 26.067657 -109.845624) (xy 26.036884 -109.892137)
			(xy 25.999667 -109.933674) (xy 25.956799 -109.969349) (xy 25.909193 -109.998403) (xy 25.857864 -110.020215)
			(xy 25.803907 -110.034321) (xy 25.74847 -110.040421) (xy 25.692736 -110.038384) (xy 25.637893 -110.028254)
			(xy 25.585109 -110.010247) (xy 25.535509 -109.984746) (xy 25.490151 -109.952295) (xy 25.450002 -109.913586)
			(xy 25.415916 -109.869443) (xy 25.38862 -109.820808) (xy 25.368697 -109.768717) (xy 25.356571 -109.71428)
			(xy 25.3525 -109.658658) (xy 19.498203 -109.658658) (xy 19.507599 -109.67286) (xy 19.531271 -109.723357)
			(xy 19.547339 -109.776764) (xy 19.555459 -109.83194) (xy 19.555968 -109.859826) (xy 19.555459 -109.887712)
			(xy 19.547339 -109.942888) (xy 19.531271 -109.996295) (xy 19.507599 -110.046792) (xy 19.476826 -110.093305)
			(xy 19.439609 -110.134842) (xy 19.396741 -110.170517) (xy 19.349135 -110.199571) (xy 19.297806 -110.221383)
			(xy 19.243849 -110.235489) (xy 19.188412 -110.241589) (xy 19.132678 -110.239552) (xy 19.077835 -110.229422)
			(xy 19.025051 -110.211415) (xy 18.975451 -110.185914) (xy 18.930093 -110.153463) (xy 18.889944 -110.114754)
			(xy 18.855858 -110.070611) (xy 18.828562 -110.021976) (xy 18.808639 -109.969885) (xy 18.796513 -109.915448)
			(xy 18.792442 -109.859826) (xy 14.777212 -109.859826) (xy 14.777212 -110.482888) (xy 15.912082 -110.482888)
			(xy 15.916153 -110.427266) (xy 15.928279 -110.372829) (xy 15.948202 -110.320738) (xy 15.975498 -110.272103)
			(xy 16.009584 -110.22796) (xy 16.049733 -110.189251) (xy 16.095091 -110.1568) (xy 16.144691 -110.131299)
			(xy 16.197475 -110.113292) (xy 16.252318 -110.103162) (xy 16.308052 -110.101125) (xy 16.363489 -110.107225)
			(xy 16.417446 -110.121331) (xy 16.468775 -110.143143) (xy 16.516381 -110.172197) (xy 16.559249 -110.207872)
			(xy 16.596466 -110.249409) (xy 16.627239 -110.295922) (xy 16.650911 -110.346419) (xy 16.666979 -110.399826)
			(xy 16.675099 -110.455002) (xy 16.675608 -110.482888) (xy 16.675099 -110.510774) (xy 16.666979 -110.56595)
			(xy 16.650911 -110.619357) (xy 16.627239 -110.669854) (xy 16.596466 -110.716367) (xy 16.559249 -110.757904)
			(xy 16.516381 -110.793579) (xy 16.468775 -110.822633) (xy 16.417446 -110.844445) (xy 16.363489 -110.858551)
			(xy 16.308052 -110.864651) (xy 16.252318 -110.862614) (xy 16.197475 -110.852484) (xy 16.144691 -110.834477)
			(xy 16.095091 -110.808976) (xy 16.049733 -110.776525) (xy 16.009584 -110.737816) (xy 15.975498 -110.693673)
			(xy 15.948202 -110.645038) (xy 15.928279 -110.592947) (xy 15.916153 -110.53851) (xy 15.912082 -110.482888)
			(xy 14.777212 -110.482888) (xy 14.777212 -110.875826) (xy 18.799046 -110.875826) (xy 18.803117 -110.820204)
			(xy 18.815243 -110.765767) (xy 18.835166 -110.713676) (xy 18.862462 -110.665041) (xy 18.896548 -110.620898)
			(xy 18.936697 -110.582189) (xy 18.982055 -110.549738) (xy 19.031655 -110.524237) (xy 19.084439 -110.50623)
			(xy 19.139282 -110.4961) (xy 19.195016 -110.494063) (xy 19.250453 -110.500163) (xy 19.30441 -110.514269)
			(xy 19.355739 -110.536081) (xy 19.403345 -110.565135) (xy 19.429957 -110.587282) (xy 37.558216 -110.587282)
			(xy 37.562287 -110.53166) (xy 37.574413 -110.477223) (xy 37.594336 -110.425132) (xy 37.621632 -110.376497)
			(xy 37.655718 -110.332354) (xy 37.695867 -110.293645) (xy 37.741225 -110.261194) (xy 37.790825 -110.235693)
			(xy 37.843609 -110.217686) (xy 37.898452 -110.207556) (xy 37.954186 -110.205519) (xy 38.009623 -110.211619)
			(xy 38.06358 -110.225725) (xy 38.114909 -110.247537) (xy 38.162515 -110.276591) (xy 38.205383 -110.312266)
			(xy 38.219434 -110.327948) (xy 38.435786 -110.327948) (xy 38.439857 -110.272326) (xy 38.451983 -110.217889)
			(xy 38.471906 -110.165798) (xy 38.499202 -110.117163) (xy 38.533288 -110.07302) (xy 38.573437 -110.034311)
			(xy 38.618795 -110.00186) (xy 38.668395 -109.976359) (xy 38.721179 -109.958352) (xy 38.776022 -109.948222)
			(xy 38.831756 -109.946185) (xy 38.887193 -109.952285) (xy 38.94115 -109.966391) (xy 38.992479 -109.988203)
			(xy 39.040085 -110.017257) (xy 39.082953 -110.052932) (xy 39.12017 -110.094469) (xy 39.150943 -110.140982)
			(xy 39.174615 -110.191479) (xy 39.190683 -110.244886) (xy 39.198803 -110.300062) (xy 39.199312 -110.327948)
			(xy 39.198803 -110.355834) (xy 39.190683 -110.41101) (xy 39.174615 -110.464417) (xy 39.150943 -110.514914)
			(xy 39.12017 -110.561427) (xy 39.097004 -110.587282) (xy 41.255186 -110.587282) (xy 41.259257 -110.53166)
			(xy 41.271383 -110.477223) (xy 41.291306 -110.425132) (xy 41.318602 -110.376497) (xy 41.352688 -110.332354)
			(xy 41.392837 -110.293645) (xy 41.438195 -110.261194) (xy 41.487795 -110.235693) (xy 41.540579 -110.217686)
			(xy 41.595422 -110.207556) (xy 41.651156 -110.205519) (xy 41.68579 -110.20933) (xy 49.005742 -110.20933)
			(xy 49.009813 -110.153708) (xy 49.021939 -110.099271) (xy 49.041862 -110.04718) (xy 49.069158 -109.998545)
			(xy 49.103244 -109.954402) (xy 49.143393 -109.915693) (xy 49.188751 -109.883242) (xy 49.238351 -109.857741)
			(xy 49.291135 -109.839734) (xy 49.345978 -109.829604) (xy 49.401712 -109.827567) (xy 49.457149 -109.833667)
			(xy 49.511106 -109.847773) (xy 49.562435 -109.869585) (xy 49.610041 -109.898639) (xy 49.652909 -109.934314)
			(xy 49.690126 -109.975851) (xy 49.720899 -110.022364) (xy 49.744571 -110.072861) (xy 49.760639 -110.126268)
			(xy 49.768759 -110.181444) (xy 49.769268 -110.20933) (xy 49.768759 -110.237216) (xy 49.760639 -110.292392)
			(xy 49.744571 -110.345799) (xy 49.720899 -110.396296) (xy 49.690126 -110.442809) (xy 49.652909 -110.484346)
			(xy 49.610041 -110.520021) (xy 49.562435 -110.549075) (xy 49.511106 -110.570887) (xy 49.457149 -110.584993)
			(xy 49.401712 -110.591093) (xy 49.345978 -110.589056) (xy 49.291135 -110.578926) (xy 49.238351 -110.560919)
			(xy 49.188751 -110.535418) (xy 49.143393 -110.502967) (xy 49.103244 -110.464258) (xy 49.069158 -110.420115)
			(xy 49.041862 -110.37148) (xy 49.021939 -110.319389) (xy 49.009813 -110.264952) (xy 49.005742 -110.20933)
			(xy 41.68579 -110.20933) (xy 41.706593 -110.211619) (xy 41.76055 -110.225725) (xy 41.811879 -110.247537)
			(xy 41.859485 -110.276591) (xy 41.902353 -110.312266) (xy 41.93957 -110.353803) (xy 41.970343 -110.400316)
			(xy 41.994015 -110.450813) (xy 42.010083 -110.50422) (xy 42.018203 -110.559396) (xy 42.018712 -110.587282)
			(xy 42.018203 -110.615168) (xy 42.010083 -110.670344) (xy 42.009931 -110.670848) (xy 46.493682 -110.670848)
			(xy 46.497753 -110.615226) (xy 46.509879 -110.560789) (xy 46.529802 -110.508698) (xy 46.557098 -110.460063)
			(xy 46.591184 -110.41592) (xy 46.631333 -110.377211) (xy 46.676691 -110.34476) (xy 46.726291 -110.319259)
			(xy 46.779075 -110.301252) (xy 46.833918 -110.291122) (xy 46.889652 -110.289085) (xy 46.945089 -110.295185)
			(xy 46.999046 -110.309291) (xy 47.050375 -110.331103) (xy 47.097981 -110.360157) (xy 47.140849 -110.395832)
			(xy 47.178066 -110.437369) (xy 47.208839 -110.483882) (xy 47.232511 -110.534379) (xy 47.248579 -110.587786)
			(xy 47.256699 -110.642962) (xy 47.257208 -110.670848) (xy 47.256699 -110.698734) (xy 47.248579 -110.75391)
			(xy 47.232511 -110.807317) (xy 47.208839 -110.857814) (xy 47.178066 -110.904327) (xy 47.140849 -110.945864)
			(xy 47.097981 -110.981539) (xy 47.050375 -111.010593) (xy 46.999046 -111.032405) (xy 46.945089 -111.046511)
			(xy 46.889652 -111.052611) (xy 46.833918 -111.050574) (xy 46.779075 -111.040444) (xy 46.726291 -111.022437)
			(xy 46.676691 -110.996936) (xy 46.631333 -110.964485) (xy 46.591184 -110.925776) (xy 46.557098 -110.881633)
			(xy 46.529802 -110.832998) (xy 46.509879 -110.780907) (xy 46.497753 -110.72647) (xy 46.493682 -110.670848)
			(xy 42.009931 -110.670848) (xy 41.994015 -110.723751) (xy 41.970343 -110.774248) (xy 41.93957 -110.820761)
			(xy 41.902353 -110.862298) (xy 41.859485 -110.897973) (xy 41.811879 -110.927027) (xy 41.76055 -110.948839)
			(xy 41.706593 -110.962945) (xy 41.651156 -110.969045) (xy 41.595422 -110.967008) (xy 41.540579 -110.956878)
			(xy 41.487795 -110.938871) (xy 41.438195 -110.91337) (xy 41.392837 -110.880919) (xy 41.352688 -110.84221)
			(xy 41.318602 -110.798067) (xy 41.291306 -110.749432) (xy 41.271383 -110.697341) (xy 41.259257 -110.642904)
			(xy 41.255186 -110.587282) (xy 39.097004 -110.587282) (xy 39.082953 -110.602964) (xy 39.040085 -110.638639)
			(xy 38.992479 -110.667693) (xy 38.94115 -110.689505) (xy 38.887193 -110.703611) (xy 38.831756 -110.709711)
			(xy 38.776022 -110.707674) (xy 38.721179 -110.697544) (xy 38.668395 -110.679537) (xy 38.618795 -110.654036)
			(xy 38.573437 -110.621585) (xy 38.533288 -110.582876) (xy 38.499202 -110.538733) (xy 38.471906 -110.490098)
			(xy 38.451983 -110.438007) (xy 38.439857 -110.38357) (xy 38.435786 -110.327948) (xy 38.219434 -110.327948)
			(xy 38.2426 -110.353803) (xy 38.273373 -110.400316) (xy 38.297045 -110.450813) (xy 38.313113 -110.50422)
			(xy 38.321233 -110.559396) (xy 38.321742 -110.587282) (xy 38.321233 -110.615168) (xy 38.313113 -110.670344)
			(xy 38.297045 -110.723751) (xy 38.273373 -110.774248) (xy 38.2426 -110.820761) (xy 38.205383 -110.862298)
			(xy 38.162515 -110.897973) (xy 38.114909 -110.927027) (xy 38.06358 -110.948839) (xy 38.009623 -110.962945)
			(xy 37.954186 -110.969045) (xy 37.898452 -110.967008) (xy 37.843609 -110.956878) (xy 37.790825 -110.938871)
			(xy 37.741225 -110.91337) (xy 37.695867 -110.880919) (xy 37.655718 -110.84221) (xy 37.621632 -110.798067)
			(xy 37.594336 -110.749432) (xy 37.574413 -110.697341) (xy 37.562287 -110.642904) (xy 37.558216 -110.587282)
			(xy 19.429957 -110.587282) (xy 19.446213 -110.60081) (xy 19.48343 -110.642347) (xy 19.514203 -110.68886)
			(xy 19.537875 -110.739357) (xy 19.553943 -110.792764) (xy 19.562063 -110.84794) (xy 19.562572 -110.875826)
			(xy 19.562063 -110.903712) (xy 19.553943 -110.958888) (xy 19.537875 -111.012295) (xy 19.514203 -111.062792)
			(xy 19.48343 -111.109305) (xy 19.446213 -111.150842) (xy 19.403345 -111.186517) (xy 19.355739 -111.215571)
			(xy 19.30441 -111.237383) (xy 19.250453 -111.251489) (xy 19.195016 -111.257589) (xy 19.139282 -111.255552)
			(xy 19.084439 -111.245422) (xy 19.031655 -111.227415) (xy 18.982055 -111.201914) (xy 18.936697 -111.169463)
			(xy 18.896548 -111.130754) (xy 18.862462 -111.086611) (xy 18.835166 -111.037976) (xy 18.815243 -110.985885)
			(xy 18.803117 -110.931448) (xy 18.799046 -110.875826) (xy 14.777212 -110.875826) (xy 14.777212 -111.383826)
			(xy 21.058122 -111.383826) (xy 21.062193 -111.328204) (xy 21.074319 -111.273767) (xy 21.094242 -111.221676)
			(xy 21.121538 -111.173041) (xy 21.155624 -111.128898) (xy 21.195773 -111.090189) (xy 21.241131 -111.057738)
			(xy 21.290731 -111.032237) (xy 21.343515 -111.01423) (xy 21.398358 -111.0041) (xy 21.454092 -111.002063)
			(xy 21.509529 -111.008163) (xy 21.563486 -111.022269) (xy 21.614815 -111.044081) (xy 21.662421 -111.073135)
			(xy 21.705289 -111.10881) (xy 21.733905 -111.140748) (xy 45.525942 -111.140748) (xy 45.530013 -111.085126)
			(xy 45.542139 -111.030689) (xy 45.562062 -110.978598) (xy 45.589358 -110.929963) (xy 45.623444 -110.88582)
			(xy 45.663593 -110.847111) (xy 45.708951 -110.81466) (xy 45.758551 -110.789159) (xy 45.811335 -110.771152)
			(xy 45.866178 -110.761022) (xy 45.921912 -110.758985) (xy 45.977349 -110.765085) (xy 46.031306 -110.779191)
			(xy 46.082635 -110.801003) (xy 46.130241 -110.830057) (xy 46.173109 -110.865732) (xy 46.210326 -110.907269)
			(xy 46.241099 -110.953782) (xy 46.264771 -111.004279) (xy 46.280839 -111.057686) (xy 46.288959 -111.112862)
			(xy 46.289468 -111.140748) (xy 46.288959 -111.168634) (xy 46.280839 -111.22381) (xy 46.264771 -111.277217)
			(xy 46.241099 -111.327714) (xy 46.210326 -111.374227) (xy 46.173109 -111.415764) (xy 46.130241 -111.451439)
			(xy 46.082635 -111.480493) (xy 46.031306 -111.502305) (xy 45.977349 -111.516411) (xy 45.921912 -111.522511)
			(xy 45.866178 -111.520474) (xy 45.811335 -111.510344) (xy 45.758551 -111.492337) (xy 45.708951 -111.466836)
			(xy 45.663593 -111.434385) (xy 45.623444 -111.395676) (xy 45.589358 -111.351533) (xy 45.562062 -111.302898)
			(xy 45.542139 -111.250807) (xy 45.530013 -111.19637) (xy 45.525942 -111.140748) (xy 21.733905 -111.140748)
			(xy 21.742506 -111.150347) (xy 21.773279 -111.19686) (xy 21.796951 -111.247357) (xy 21.813019 -111.300764)
			(xy 21.821139 -111.35594) (xy 21.821648 -111.383826) (xy 21.821139 -111.411712) (xy 21.813019 -111.466888)
			(xy 21.796951 -111.520295) (xy 21.773279 -111.570792) (xy 21.751784 -111.603282) (xy 37.558216 -111.603282)
			(xy 37.562287 -111.54766) (xy 37.574413 -111.493223) (xy 37.594336 -111.441132) (xy 37.621632 -111.392497)
			(xy 37.655718 -111.348354) (xy 37.695867 -111.309645) (xy 37.741225 -111.277194) (xy 37.790825 -111.251693)
			(xy 37.843609 -111.233686) (xy 37.898452 -111.223556) (xy 37.954186 -111.221519) (xy 38.009623 -111.227619)
			(xy 38.06358 -111.241725) (xy 38.114909 -111.263537) (xy 38.162515 -111.292591) (xy 38.205383 -111.328266)
			(xy 38.2426 -111.369803) (xy 38.273373 -111.416316) (xy 38.297045 -111.466813) (xy 38.313113 -111.52022)
			(xy 38.321233 -111.575396) (xy 38.321742 -111.603282) (xy 38.321677 -111.606838) (xy 38.435786 -111.606838)
			(xy 38.439857 -111.551216) (xy 38.451983 -111.496779) (xy 38.471906 -111.444688) (xy 38.499202 -111.396053)
			(xy 38.533288 -111.35191) (xy 38.573437 -111.313201) (xy 38.618795 -111.28075) (xy 38.668395 -111.255249)
			(xy 38.721179 -111.237242) (xy 38.776022 -111.227112) (xy 38.831756 -111.225075) (xy 38.887193 -111.231175)
			(xy 38.94115 -111.245281) (xy 38.992479 -111.267093) (xy 39.040085 -111.296147) (xy 39.082953 -111.331822)
			(xy 39.12017 -111.373359) (xy 39.150943 -111.419872) (xy 39.174615 -111.470369) (xy 39.190683 -111.523776)
			(xy 39.198803 -111.578952) (xy 39.199312 -111.606838) (xy 41.255186 -111.606838) (xy 41.259257 -111.551216)
			(xy 41.271383 -111.496779) (xy 41.291306 -111.444688) (xy 41.318602 -111.396053) (xy 41.352688 -111.35191)
			(xy 41.392837 -111.313201) (xy 41.438195 -111.28075) (xy 41.487795 -111.255249) (xy 41.540579 -111.237242)
			(xy 41.595422 -111.227112) (xy 41.651156 -111.225075) (xy 41.706593 -111.231175) (xy 41.76055 -111.245281)
			(xy 41.811879 -111.267093) (xy 41.859485 -111.296147) (xy 41.902353 -111.331822) (xy 41.93957 -111.373359)
			(xy 41.970343 -111.419872) (xy 41.994015 -111.470369) (xy 42.010083 -111.523776) (xy 42.018203 -111.578952)
			(xy 42.018712 -111.606838) (xy 42.018203 -111.634724) (xy 42.010083 -111.6899) (xy 41.994015 -111.743307)
			(xy 41.970343 -111.793804) (xy 41.93957 -111.840317) (xy 41.902353 -111.881854) (xy 41.859485 -111.917529)
			(xy 41.811879 -111.946583) (xy 41.76055 -111.968395) (xy 41.706593 -111.982501) (xy 41.651156 -111.988601)
			(xy 41.595422 -111.986564) (xy 41.540579 -111.976434) (xy 41.487795 -111.958427) (xy 41.438195 -111.932926)
			(xy 41.392837 -111.900475) (xy 41.352688 -111.861766) (xy 41.318602 -111.817623) (xy 41.291306 -111.768988)
			(xy 41.271383 -111.716897) (xy 41.259257 -111.66246) (xy 41.255186 -111.606838) (xy 39.199312 -111.606838)
			(xy 39.198803 -111.634724) (xy 39.190683 -111.6899) (xy 39.174615 -111.743307) (xy 39.150943 -111.793804)
			(xy 39.12017 -111.840317) (xy 39.082953 -111.881854) (xy 39.040085 -111.917529) (xy 38.992479 -111.946583)
			(xy 38.94115 -111.968395) (xy 38.887193 -111.982501) (xy 38.831756 -111.988601) (xy 38.776022 -111.986564)
			(xy 38.721179 -111.976434) (xy 38.668395 -111.958427) (xy 38.618795 -111.932926) (xy 38.573437 -111.900475)
			(xy 38.533288 -111.861766) (xy 38.499202 -111.817623) (xy 38.471906 -111.768988) (xy 38.451983 -111.716897)
			(xy 38.439857 -111.66246) (xy 38.435786 -111.606838) (xy 38.321677 -111.606838) (xy 38.321233 -111.631168)
			(xy 38.313113 -111.686344) (xy 38.297045 -111.739751) (xy 38.273373 -111.790248) (xy 38.2426 -111.836761)
			(xy 38.205383 -111.878298) (xy 38.162515 -111.913973) (xy 38.114909 -111.943027) (xy 38.06358 -111.964839)
			(xy 38.009623 -111.978945) (xy 37.954186 -111.985045) (xy 37.898452 -111.983008) (xy 37.843609 -111.972878)
			(xy 37.790825 -111.954871) (xy 37.741225 -111.92937) (xy 37.695867 -111.896919) (xy 37.655718 -111.85821)
			(xy 37.621632 -111.814067) (xy 37.594336 -111.765432) (xy 37.574413 -111.713341) (xy 37.562287 -111.658904)
			(xy 37.558216 -111.603282) (xy 21.751784 -111.603282) (xy 21.742506 -111.617305) (xy 21.705289 -111.658842)
			(xy 21.662421 -111.694517) (xy 21.614815 -111.723571) (xy 21.563486 -111.745383) (xy 21.509529 -111.759489)
			(xy 21.454092 -111.765589) (xy 21.398358 -111.763552) (xy 21.343515 -111.753422) (xy 21.290731 -111.735415)
			(xy 21.241131 -111.709914) (xy 21.195773 -111.677463) (xy 21.155624 -111.638754) (xy 21.121538 -111.594611)
			(xy 21.094242 -111.545976) (xy 21.074319 -111.493885) (xy 21.062193 -111.439448) (xy 21.058122 -111.383826)
			(xy 14.777212 -111.383826) (xy 14.777212 -112.693958) (xy 16.982692 -112.693958) (xy 16.986763 -112.638336)
			(xy 16.998889 -112.583899) (xy 17.018812 -112.531808) (xy 17.046108 -112.483173) (xy 17.080194 -112.43903)
			(xy 17.120343 -112.400321) (xy 17.165701 -112.36787) (xy 17.215301 -112.342369) (xy 17.268085 -112.324362)
			(xy 17.322928 -112.314232) (xy 17.378662 -112.312195) (xy 17.434099 -112.318295) (xy 17.488056 -112.332401)
			(xy 17.539385 -112.354213) (xy 17.586991 -112.383267) (xy 17.629859 -112.418942) (xy 17.667076 -112.460479)
			(xy 17.697849 -112.506992) (xy 17.721521 -112.557489) (xy 17.737589 -112.610896) (xy 17.738823 -112.619282)
			(xy 37.558216 -112.619282) (xy 37.562287 -112.56366) (xy 37.574413 -112.509223) (xy 37.594336 -112.457132)
			(xy 37.621632 -112.408497) (xy 37.655718 -112.364354) (xy 37.695867 -112.325645) (xy 37.741225 -112.293194)
			(xy 37.790825 -112.267693) (xy 37.843609 -112.249686) (xy 37.898452 -112.239556) (xy 37.954186 -112.237519)
			(xy 38.009623 -112.243619) (xy 38.06358 -112.257725) (xy 38.114909 -112.279537) (xy 38.162515 -112.308591)
			(xy 38.205383 -112.344266) (xy 38.2426 -112.385803) (xy 38.273373 -112.432316) (xy 38.297045 -112.482813)
			(xy 38.313113 -112.53622) (xy 38.321233 -112.591396) (xy 38.321445 -112.603026) (xy 41.255186 -112.603026)
			(xy 41.259257 -112.547404) (xy 41.271383 -112.492967) (xy 41.291306 -112.440876) (xy 41.318602 -112.392241)
			(xy 41.352688 -112.348098) (xy 41.392837 -112.309389) (xy 41.438195 -112.276938) (xy 41.487795 -112.251437)
			(xy 41.540579 -112.23343) (xy 41.595422 -112.2233) (xy 41.651156 -112.221263) (xy 41.706593 -112.227363)
			(xy 41.76055 -112.241469) (xy 41.811879 -112.263281) (xy 41.859485 -112.292335) (xy 41.902353 -112.32801)
			(xy 41.93957 -112.369547) (xy 41.970343 -112.41606) (xy 41.994015 -112.466557) (xy 42.010083 -112.519964)
			(xy 42.018203 -112.57514) (xy 42.018712 -112.603026) (xy 42.018415 -112.619282) (xy 44.797216 -112.619282)
			(xy 44.801287 -112.56366) (xy 44.813413 -112.509223) (xy 44.833336 -112.457132) (xy 44.860632 -112.408497)
			(xy 44.894718 -112.364354) (xy 44.934867 -112.325645) (xy 44.980225 -112.293194) (xy 45.029825 -112.267693)
			(xy 45.082609 -112.249686) (xy 45.137452 -112.239556) (xy 45.193186 -112.237519) (xy 45.248623 -112.243619)
			(xy 45.30258 -112.257725) (xy 45.353909 -112.279537) (xy 45.401515 -112.308591) (xy 45.444383 -112.344266)
			(xy 45.4816 -112.385803) (xy 45.512373 -112.432316) (xy 45.536045 -112.482813) (xy 45.552113 -112.53622)
			(xy 45.560233 -112.591396) (xy 45.560742 -112.619282) (xy 47.210726 -112.619282) (xy 47.211213 -112.58998)
			(xy 47.220166 -112.532066) (xy 47.237875 -112.476202) (xy 47.263923 -112.423706) (xy 47.297695 -112.375813)
			(xy 47.31766 -112.35436) (xy 47.328137 -112.342754) (xy 47.342042 -112.314766) (xy 47.346824 -112.283882)
			(xy 47.342031 -112.252999) (xy 47.328116 -112.225016) (xy 47.31766 -112.21339) (xy 47.297714 -112.191924)
			(xy 47.263966 -112.144023) (xy 47.237934 -112.091528) (xy 47.220228 -112.035671) (xy 47.211265 -111.977766)
			(xy 47.210726 -111.948468) (xy 47.211212 -111.921217) (xy 47.218968 -111.867269) (xy 47.234323 -111.814974)
			(xy 47.256965 -111.765397) (xy 47.286431 -111.719547) (xy 47.322122 -111.678356) (xy 47.363313 -111.642665)
			(xy 47.409163 -111.613199) (xy 47.45874 -111.590557) (xy 47.511035 -111.575202) (xy 47.564983 -111.567446)
			(xy 47.619485 -111.567446) (xy 47.673433 -111.575202) (xy 47.725728 -111.590557) (xy 47.775305 -111.613199)
			(xy 47.821155 -111.642665) (xy 47.829055 -111.64951) (xy 49.005742 -111.64951) (xy 49.009813 -111.593888)
			(xy 49.021939 -111.539451) (xy 49.041862 -111.48736) (xy 49.069158 -111.438725) (xy 49.103244 -111.394582)
			(xy 49.143393 -111.355873) (xy 49.188751 -111.323422) (xy 49.238351 -111.297921) (xy 49.291135 -111.279914)
			(xy 49.345978 -111.269784) (xy 49.401712 -111.267747) (xy 49.457149 -111.273847) (xy 49.511106 -111.287953)
			(xy 49.562435 -111.309765) (xy 49.610041 -111.338819) (xy 49.652909 -111.374494) (xy 49.690126 -111.416031)
			(xy 49.720899 -111.462544) (xy 49.744571 -111.513041) (xy 49.760639 -111.566448) (xy 49.768759 -111.621624)
			(xy 49.769268 -111.64951) (xy 49.768759 -111.677396) (xy 49.760639 -111.732572) (xy 49.744571 -111.785979)
			(xy 49.720899 -111.836476) (xy 49.690126 -111.882989) (xy 49.652909 -111.924526) (xy 49.610041 -111.960201)
			(xy 49.562435 -111.989255) (xy 49.511106 -112.011067) (xy 49.457149 -112.025173) (xy 49.401712 -112.031273)
			(xy 49.345978 -112.029236) (xy 49.291135 -112.019106) (xy 49.238351 -112.001099) (xy 49.188751 -111.975598)
			(xy 49.143393 -111.943147) (xy 49.103244 -111.904438) (xy 49.069158 -111.860295) (xy 49.041862 -111.81166)
			(xy 49.021939 -111.759569) (xy 49.009813 -111.705132) (xy 49.005742 -111.64951) (xy 47.829055 -111.64951)
			(xy 47.862346 -111.678356) (xy 47.898037 -111.719547) (xy 47.927503 -111.765397) (xy 47.950145 -111.814974)
			(xy 47.9655 -111.867269) (xy 47.973256 -111.921217) (xy 47.973742 -111.948468) (xy 47.973205 -111.977767)
			(xy 47.964261 -112.035679) (xy 47.946563 -112.091541) (xy 47.920527 -112.144038) (xy 47.886767 -112.191934)
			(xy 47.866808 -112.21339) (xy 47.856435 -112.225062) (xy 47.842612 -112.25304) (xy 47.837853 -112.283882)
			(xy 47.842601 -112.314725) (xy 47.856414 -112.342709) (xy 47.866808 -112.35436) (xy 47.886772 -112.37581)
			(xy 47.920518 -112.423715) (xy 47.946548 -112.476214) (xy 47.964249 -112.532074) (xy 47.973206 -112.589983)
			(xy 47.973742 -112.619282) (xy 47.973256 -112.646533) (xy 47.9655 -112.700481) (xy 47.950145 -112.752776)
			(xy 47.927503 -112.802353) (xy 47.898037 -112.848203) (xy 47.862346 -112.889394) (xy 47.821155 -112.925085)
			(xy 47.775305 -112.954551) (xy 47.725728 -112.977193) (xy 47.673433 -112.992548) (xy 47.619485 -113.000304)
			(xy 47.564983 -113.000304) (xy 47.511035 -112.992548) (xy 47.45874 -112.977193) (xy 47.409163 -112.954551)
			(xy 47.363313 -112.925085) (xy 47.322122 -112.889394) (xy 47.286431 -112.848203) (xy 47.256965 -112.802353)
			(xy 47.234323 -112.752776) (xy 47.218968 -112.700481) (xy 47.211212 -112.646533) (xy 47.210726 -112.619282)
			(xy 45.560742 -112.619282) (xy 45.560233 -112.647168) (xy 45.552113 -112.702344) (xy 45.536045 -112.755751)
			(xy 45.512373 -112.806248) (xy 45.4816 -112.852761) (xy 45.444383 -112.894298) (xy 45.401515 -112.929973)
			(xy 45.353909 -112.959027) (xy 45.30258 -112.980839) (xy 45.248623 -112.994945) (xy 45.193186 -113.001045)
			(xy 45.137452 -112.999008) (xy 45.082609 -112.988878) (xy 45.029825 -112.970871) (xy 44.980225 -112.94537)
			(xy 44.934867 -112.912919) (xy 44.894718 -112.87421) (xy 44.860632 -112.830067) (xy 44.833336 -112.781432)
			(xy 44.813413 -112.729341) (xy 44.801287 -112.674904) (xy 44.797216 -112.619282) (xy 42.018415 -112.619282)
			(xy 42.018203 -112.630912) (xy 42.010083 -112.686088) (xy 41.994015 -112.739495) (xy 41.970343 -112.789992)
			(xy 41.93957 -112.836505) (xy 41.902353 -112.878042) (xy 41.859485 -112.913717) (xy 41.811879 -112.942771)
			(xy 41.76055 -112.964583) (xy 41.706593 -112.978689) (xy 41.651156 -112.984789) (xy 41.595422 -112.982752)
			(xy 41.540579 -112.972622) (xy 41.487795 -112.954615) (xy 41.438195 -112.929114) (xy 41.392837 -112.896663)
			(xy 41.352688 -112.857954) (xy 41.318602 -112.813811) (xy 41.291306 -112.765176) (xy 41.271383 -112.713085)
			(xy 41.259257 -112.658648) (xy 41.255186 -112.603026) (xy 38.321445 -112.603026) (xy 38.321742 -112.619282)
			(xy 38.321233 -112.647168) (xy 38.313113 -112.702344) (xy 38.297045 -112.755751) (xy 38.273373 -112.806248)
			(xy 38.2426 -112.852761) (xy 38.205383 -112.894298) (xy 38.162515 -112.929973) (xy 38.114909 -112.959027)
			(xy 38.06358 -112.980839) (xy 38.009623 -112.994945) (xy 37.954186 -113.001045) (xy 37.898452 -112.999008)
			(xy 37.843609 -112.988878) (xy 37.790825 -112.970871) (xy 37.741225 -112.94537) (xy 37.695867 -112.912919)
			(xy 37.655718 -112.87421) (xy 37.621632 -112.830067) (xy 37.594336 -112.781432) (xy 37.574413 -112.729341)
			(xy 37.562287 -112.674904) (xy 37.558216 -112.619282) (xy 17.738823 -112.619282) (xy 17.745709 -112.666072)
			(xy 17.746218 -112.693958) (xy 17.745709 -112.721844) (xy 17.737589 -112.77702) (xy 17.721521 -112.830427)
			(xy 17.697849 -112.880924) (xy 17.667076 -112.927437) (xy 17.629859 -112.968974) (xy 17.586991 -113.004649)
			(xy 17.539385 -113.033703) (xy 17.488056 -113.055515) (xy 17.434099 -113.069621) (xy 17.378662 -113.075721)
			(xy 17.322928 -113.073684) (xy 17.268085 -113.063554) (xy 17.215301 -113.045547) (xy 17.165701 -113.020046)
			(xy 17.120343 -112.987595) (xy 17.080194 -112.948886) (xy 17.046108 -112.904743) (xy 17.018812 -112.856108)
			(xy 16.998889 -112.804017) (xy 16.986763 -112.74958) (xy 16.982692 -112.693958) (xy 14.777212 -112.693958)
			(xy 14.777212 -113.633758) (xy 20.320762 -113.633758) (xy 20.321222 -113.607132) (xy 20.328633 -113.554398)
			(xy 20.343306 -113.503207) (xy 20.364955 -113.454553) (xy 20.393159 -113.409383) (xy 20.42737 -113.368574)
			(xy 20.466924 -113.332919) (xy 20.511052 -113.30311) (xy 20.558897 -113.279728) (xy 20.609528 -113.263226)
			(xy 20.661962 -113.253926) (xy 20.688554 -113.252504) (xy 20.702729 -113.251584) (xy 20.729727 -113.242771)
			(xy 20.753259 -113.226874) (xy 20.771513 -113.205118) (xy 20.78308 -113.179181) (xy 20.787068 -113.151063)
			(xy 20.785582 -113.136934) (xy 20.783825 -113.123732) (xy 20.781916 -113.097165) (xy 20.781772 -113.083848)
			(xy 20.782258 -113.056597) (xy 20.790014 -113.002649) (xy 20.805369 -112.950354) (xy 20.828011 -112.900777)
			(xy 20.857477 -112.854927) (xy 20.893168 -112.813736) (xy 20.934359 -112.778045) (xy 20.980209 -112.748579)
			(xy 21.029786 -112.725937) (xy 21.082081 -112.710582) (xy 21.136029 -112.702826) (xy 21.190531 -112.702826)
			(xy 21.244479 -112.710582) (xy 21.296774 -112.725937) (xy 21.346351 -112.748579) (xy 21.392201 -112.778045)
			(xy 21.433392 -112.813736) (xy 21.469083 -112.854927) (xy 21.498549 -112.900777) (xy 21.521191 -112.950354)
			(xy 21.536546 -113.002649) (xy 21.544302 -113.056597) (xy 21.544788 -113.083848) (xy 21.544381 -113.110476)
			(xy 21.536968 -113.163215) (xy 21.522293 -113.21441) (xy 21.50064 -113.263067) (xy 21.472431 -113.308239)
			(xy 21.438213 -113.349049) (xy 21.398653 -113.384705) (xy 21.354519 -113.414511) (xy 21.306668 -113.437891)
			(xy 21.25603 -113.454388) (xy 21.203591 -113.463683) (xy 21.176996 -113.465102) (xy 21.162837 -113.466167)
			(xy 21.135856 -113.474957) (xy 21.112332 -113.490827) (xy 21.094079 -113.512553) (xy 21.082502 -113.538461)
			(xy 21.078495 -113.566553) (xy 21.079968 -113.580672) (xy 21.081726 -113.593874) (xy 21.083634 -113.620441)
			(xy 21.083778 -113.633758) (xy 21.08341 -113.656788) (xy 21.077803 -113.702506) (xy 21.072602 -113.724944)
			(xy 21.06956 -113.739327) (xy 21.070981 -113.76868) (xy 21.080672 -113.796424) (xy 21.097836 -113.820279)
			(xy 21.121063 -113.838283) (xy 21.134578 -113.84407) (xy 21.161014 -113.854984) (xy 21.210601 -113.883475)
			(xy 21.255376 -113.919052) (xy 21.294337 -113.960917) (xy 21.326608 -114.008131) (xy 21.351466 -114.059635)
			(xy 21.368354 -114.114273) (xy 21.376892 -114.170821) (xy 21.377402 -114.199416) (xy 21.376916 -114.226667)
			(xy 21.36916 -114.280615) (xy 21.357427 -114.320574) (xy 23.605488 -114.320574) (xy 23.609559 -114.264952)
			(xy 23.621685 -114.210515) (xy 23.641608 -114.158424) (xy 23.668904 -114.109789) (xy 23.70299 -114.065646)
			(xy 23.743139 -114.026937) (xy 23.788497 -113.994486) (xy 23.838097 -113.968985) (xy 23.890881 -113.950978)
			(xy 23.945724 -113.940848) (xy 24.001458 -113.938811) (xy 24.056895 -113.944911) (xy 24.110852 -113.959017)
			(xy 24.162181 -113.980829) (xy 24.209787 -114.009883) (xy 24.252655 -114.045558) (xy 24.289872 -114.087095)
			(xy 24.299502 -114.101651) (xy 38.572403 -114.101651) (xy 38.572403 -114.047149) (xy 38.58016 -113.993201)
			(xy 38.595516 -113.940907) (xy 38.618159 -113.89133) (xy 38.647627 -113.845481) (xy 38.683321 -113.804292)
			(xy 38.724513 -113.768603) (xy 38.770365 -113.73914) (xy 38.819944 -113.716502) (xy 38.87224 -113.701152)
			(xy 38.926189 -113.6934) (xy 38.95344 -113.69294) (xy 38.980909 -113.693451) (xy 39.035279 -113.70133)
			(xy 39.087958 -113.71692) (xy 39.13786 -113.739899) (xy 39.183953 -113.769793) (xy 39.225286 -113.805984)
			(xy 39.243508 -113.826544) (xy 39.253723 -113.83756) (xy 39.279041 -113.853696) (xy 39.307956 -113.861777)
			(xy 39.337971 -113.861104) (xy 39.366495 -113.851737) (xy 39.391065 -113.834484) (xy 39.400734 -113.822988)
			(xy 39.418903 -113.800486) (xy 39.460928 -113.760752) (xy 39.508467 -113.727816) (xy 39.560433 -113.702431)
			(xy 39.615634 -113.685179) (xy 39.672807 -113.676454) (xy 39.701724 -113.675922) (xy 39.728847 -113.676396)
			(xy 39.782549 -113.684052) (xy 39.834626 -113.699234) (xy 39.884029 -113.721637) (xy 39.929763 -113.750809)
			(xy 39.950644 -113.768124) (xy 39.961777 -113.77714) (xy 39.987813 -113.789066) (xy 40.01614 -113.793275)
			(xy 40.044519 -113.789434) (xy 40.070707 -113.777846) (xy 40.092636 -113.759428) (xy 40.101012 -113.747804)
			(xy 40.11625 -113.725879) (xy 40.151941 -113.686165) (xy 40.192818 -113.651812) (xy 40.238084 -113.623491)
			(xy 40.286854 -113.601753) (xy 40.338177 -113.587024) (xy 40.391052 -113.57959) (xy 40.41775 -113.579148)
			(xy 40.445002 -113.579696) (xy 40.498952 -113.587446) (xy 40.55125 -113.602796) (xy 40.56474 -113.608955)
			(xy 44.798143 -113.608955) (xy 44.798143 -113.554445) (xy 44.805901 -113.500489) (xy 44.821259 -113.448187)
			(xy 44.843905 -113.398603) (xy 44.873377 -113.352747) (xy 44.909076 -113.311552) (xy 44.950274 -113.275857)
			(xy 44.996133 -113.246389) (xy 45.045719 -113.223747) (xy 45.098022 -113.208394) (xy 45.151979 -113.200641)
			(xy 45.179234 -113.20018) (xy 45.205155 -113.200631) (xy 45.256516 -113.207665) (xy 45.306454 -113.221586)
			(xy 45.354047 -113.242138) (xy 45.398422 -113.268941) (xy 45.43876 -113.301504) (xy 45.456856 -113.320068)
			(xy 45.466692 -113.329815) (xy 45.490392 -113.344112) (xy 45.517058 -113.351533) (xy 45.544736 -113.351533)
			(xy 45.571402 -113.344112) (xy 45.595102 -113.329815) (xy 45.604938 -113.320068) (xy 45.623012 -113.30148)
			(xy 45.663346 -113.268903) (xy 45.707722 -113.242092) (xy 45.755322 -113.221541) (xy 45.805267 -113.207628)
			(xy 45.856637 -113.200612) (xy 45.88256 -113.20018) (xy 45.909814 -113.200665) (xy 45.963767 -113.208417)
			(xy 46.016068 -113.223769) (xy 46.065652 -113.246408) (xy 46.111509 -113.275874) (xy 46.152705 -113.311567)
			(xy 46.188402 -113.352759) (xy 46.217873 -113.398613) (xy 46.240517 -113.448194) (xy 46.255875 -113.500493)
			(xy 46.263633 -113.554446) (xy 46.263633 -113.585054) (xy 46.392267 -113.585054) (xy 46.392267 -113.530546)
			(xy 46.400025 -113.476594) (xy 46.415383 -113.424294) (xy 46.438027 -113.374713) (xy 46.467498 -113.32886)
			(xy 46.503194 -113.287668) (xy 46.54439 -113.251975) (xy 46.590247 -113.222509) (xy 46.63983 -113.199869)
			(xy 46.692131 -113.184517) (xy 46.746084 -113.176765) (xy 46.773338 -113.176304) (xy 46.801716 -113.176864)
			(xy 46.857846 -113.185277) (xy 46.912111 -113.201912) (xy 46.963312 -113.226401) (xy 47.010321 -113.258205)
			(xy 47.0521 -113.296622) (xy 47.087728 -113.340803) (xy 47.102522 -113.365026) (xy 47.110355 -113.377503)
			(xy 47.131848 -113.397635) (xy 47.158192 -113.410798) (xy 47.187196 -113.415899) (xy 47.216449 -113.412513)
			(xy 47.243521 -113.400921) (xy 47.266161 -113.382087) (xy 47.274734 -113.370106) (xy 47.290007 -113.34808)
			(xy 47.325682 -113.308083) (xy 47.366603 -113.273471) (xy 47.411964 -113.244924) (xy 47.460874 -113.223006)
			(xy 47.512369 -113.208146) (xy 47.565436 -113.200638) (xy 47.592234 -113.20018) (xy 47.619483 -113.200693)
			(xy 47.673425 -113.208453) (xy 47.725714 -113.22381) (xy 47.775285 -113.246453) (xy 47.82113 -113.275919)
			(xy 47.862315 -113.311609) (xy 47.898001 -113.352797) (xy 47.927464 -113.398645) (xy 47.950102 -113.448218)
			(xy 47.965454 -113.500508) (xy 47.97321 -113.554451) (xy 47.97321 -113.608949) (xy 47.965454 -113.662892)
			(xy 47.959988 -113.68151) (xy 49.456592 -113.68151) (xy 49.460663 -113.625888) (xy 49.472789 -113.571451)
			(xy 49.492712 -113.51936) (xy 49.520008 -113.470725) (xy 49.554094 -113.426582) (xy 49.594243 -113.387873)
			(xy 49.639601 -113.355422) (xy 49.689201 -113.329921) (xy 49.741985 -113.311914) (xy 49.796828 -113.301784)
			(xy 49.852562 -113.299747) (xy 49.907999 -113.305847) (xy 49.961956 -113.319953) (xy 50.013285 -113.341765)
			(xy 50.060891 -113.370819) (xy 50.103759 -113.406494) (xy 50.140976 -113.448031) (xy 50.171749 -113.494544)
			(xy 50.195421 -113.545041) (xy 50.211489 -113.598448) (xy 50.219609 -113.653624) (xy 50.220118 -113.68151)
			(xy 50.219609 -113.709396) (xy 50.211489 -113.764572) (xy 50.195421 -113.817979) (xy 50.171749 -113.868476)
			(xy 50.140976 -113.914989) (xy 50.103759 -113.956526) (xy 50.060891 -113.992201) (xy 50.013285 -114.021255)
			(xy 49.961956 -114.043067) (xy 49.907999 -114.057173) (xy 49.852562 -114.063273) (xy 49.796828 -114.061236)
			(xy 49.741985 -114.051106) (xy 49.689201 -114.033099) (xy 49.639601 -114.007598) (xy 49.594243 -113.975147)
			(xy 49.554094 -113.936438) (xy 49.520008 -113.892295) (xy 49.492712 -113.84366) (xy 49.472789 -113.791569)
			(xy 49.460663 -113.737132) (xy 49.456592 -113.68151) (xy 47.959988 -113.68151) (xy 47.950102 -113.715182)
			(xy 47.927464 -113.764755) (xy 47.898001 -113.810603) (xy 47.862315 -113.851791) (xy 47.82113 -113.887481)
			(xy 47.775285 -113.916947) (xy 47.725714 -113.93959) (xy 47.673425 -113.954947) (xy 47.619483 -113.962707)
			(xy 47.592234 -113.963196) (xy 47.563855 -113.962658) (xy 47.507724 -113.954241) (xy 47.453459 -113.937602)
			(xy 47.402258 -113.913109) (xy 47.355249 -113.881302) (xy 47.31347 -113.842882) (xy 47.277843 -113.798698)
			(xy 47.26305 -113.774474) (xy 47.255254 -113.761971) (xy 47.233753 -113.741837) (xy 47.207402 -113.728675)
			(xy 47.17839 -113.723577) (xy 47.14913 -113.726968) (xy 47.122053 -113.738567) (xy 47.099411 -113.757408)
			(xy 47.090838 -113.769394) (xy 47.075583 -113.791433) (xy 47.039905 -113.83143) (xy 46.998981 -113.866041)
			(xy 46.953616 -113.894586) (xy 46.904704 -113.916502) (xy 46.853207 -113.931359) (xy 46.800137 -113.938864)
			(xy 46.773338 -113.93932) (xy 46.746084 -113.938835) (xy 46.692131 -113.931083) (xy 46.63983 -113.915731)
			(xy 46.590247 -113.893091) (xy 46.54439 -113.863625) (xy 46.503194 -113.827932) (xy 46.467498 -113.78674)
			(xy 46.438027 -113.740887) (xy 46.415383 -113.691306) (xy 46.400025 -113.639006) (xy 46.392267 -113.585054)
			(xy 46.263633 -113.585054) (xy 46.263633 -113.608954) (xy 46.255875 -113.662907) (xy 46.240517 -113.715206)
			(xy 46.217873 -113.764787) (xy 46.188402 -113.810641) (xy 46.152705 -113.851833) (xy 46.111509 -113.887526)
			(xy 46.065652 -113.916992) (xy 46.016068 -113.939631) (xy 45.963767 -113.954983) (xy 45.909814 -113.962735)
			(xy 45.88256 -113.963196) (xy 45.856639 -113.962757) (xy 45.805276 -113.955721) (xy 45.755339 -113.941798)
			(xy 45.707745 -113.921245) (xy 45.663371 -113.894438) (xy 45.623033 -113.861873) (xy 45.604938 -113.843308)
			(xy 45.595127 -113.833513) (xy 45.571439 -113.819133) (xy 45.544753 -113.811666) (xy 45.517041 -113.811666)
			(xy 45.490355 -113.819133) (xy 45.466667 -113.833513) (xy 45.456856 -113.843308) (xy 45.43878 -113.861894)
			(xy 45.398447 -113.894472) (xy 45.354071 -113.921284) (xy 45.306472 -113.941836) (xy 45.256527 -113.955748)
			(xy 45.205157 -113.962765) (xy 45.179234 -113.963196) (xy 45.151979 -113.962759) (xy 45.098022 -113.955006)
			(xy 45.045719 -113.939653) (xy 44.996133 -113.917011) (xy 44.950274 -113.887543) (xy 44.909076 -113.851848)
			(xy 44.873377 -113.810653) (xy 44.843905 -113.764797) (xy 44.821259 -113.715213) (xy 44.805901 -113.662911)
			(xy 44.798143 -113.608955) (xy 40.56474 -113.608955) (xy 40.600831 -113.625433) (xy 40.646685 -113.654896)
			(xy 40.687879 -113.690586) (xy 40.723574 -113.731775) (xy 40.753043 -113.777625) (xy 40.775686 -113.827203)
			(xy 40.791043 -113.879499) (xy 40.798801 -113.933448) (xy 40.798801 -113.987952) (xy 40.791043 -114.041901)
			(xy 40.775686 -114.094197) (xy 40.753043 -114.143775) (xy 40.723574 -114.189625) (xy 40.687879 -114.230814)
			(xy 40.646685 -114.266504) (xy 40.600831 -114.295967) (xy 40.55125 -114.318604) (xy 40.498952 -114.333954)
			(xy 40.445002 -114.341704) (xy 40.41775 -114.342164) (xy 40.390627 -114.341708) (xy 40.336923 -114.334048)
			(xy 40.284846 -114.318862) (xy 40.235443 -114.296455) (xy 40.189711 -114.267279) (xy 40.16883 -114.249962)
			(xy 40.157635 -114.241031) (xy 40.131619 -114.229099) (xy 40.10331 -114.224879) (xy 40.074945 -114.228704)
			(xy 40.048765 -114.240272) (xy 40.026839 -114.258669) (xy 40.018462 -114.270282) (xy 40.003172 -114.29217)
			(xy 39.96749 -114.331885) (xy 39.926622 -114.366241) (xy 39.881366 -114.394567) (xy 39.832604 -114.416311)
			(xy 39.781288 -114.431048) (xy 39.728419 -114.43849) (xy 39.701724 -114.438938) (xy 39.674254 -114.438459)
			(xy 39.619882 -114.430575) (xy 39.567202 -114.414979) (xy 39.5173 -114.391993) (xy 39.471208 -114.362094)
			(xy 39.429877 -114.325897) (xy 39.411656 -114.305334) (xy 39.401477 -114.294284) (xy 39.376148 -114.278153)
			(xy 39.347224 -114.270078) (xy 39.317202 -114.270758) (xy 39.288674 -114.280132) (xy 39.2641 -114.297391)
			(xy 39.25443 -114.30889) (xy 39.23622 -114.331357) (xy 39.194204 -114.371094) (xy 39.146673 -114.404035)
			(xy 39.094716 -114.429426) (xy 39.039522 -114.446686) (xy 38.982355 -114.455419) (xy 38.95344 -114.455956)
			(xy 38.926189 -114.4554) (xy 38.87224 -114.447648) (xy 38.819944 -114.432298) (xy 38.770365 -114.40966)
			(xy 38.724513 -114.380197) (xy 38.683321 -114.344508) (xy 38.647627 -114.303319) (xy 38.618159 -114.25747)
			(xy 38.595516 -114.207893) (xy 38.58016 -114.155599) (xy 38.572403 -114.101651) (xy 24.299502 -114.101651)
			(xy 24.320645 -114.133608) (xy 24.344317 -114.184105) (xy 24.360385 -114.237512) (xy 24.368505 -114.292688)
			(xy 24.369014 -114.320574) (xy 24.368505 -114.34846) (xy 24.360385 -114.403636) (xy 24.344317 -114.457043)
			(xy 24.320645 -114.50754) (xy 24.289872 -114.554053) (xy 24.252655 -114.59559) (xy 24.209787 -114.631265)
			(xy 24.162181 -114.660319) (xy 24.110852 -114.682131) (xy 24.056895 -114.696237) (xy 24.001458 -114.702337)
			(xy 23.945724 -114.7003) (xy 23.890881 -114.69017) (xy 23.838097 -114.672163) (xy 23.788497 -114.646662)
			(xy 23.743139 -114.614211) (xy 23.70299 -114.575502) (xy 23.668904 -114.531359) (xy 23.641608 -114.482724)
			(xy 23.621685 -114.430633) (xy 23.609559 -114.376196) (xy 23.605488 -114.320574) (xy 21.357427 -114.320574)
			(xy 21.353805 -114.33291) (xy 21.331163 -114.382487) (xy 21.301697 -114.428337) (xy 21.266006 -114.469528)
			(xy 21.224815 -114.505219) (xy 21.178965 -114.534685) (xy 21.129388 -114.557327) (xy 21.077093 -114.572682)
			(xy 21.023145 -114.580438) (xy 20.968643 -114.580438) (xy 20.914695 -114.572682) (xy 20.8624 -114.557327)
			(xy 20.812823 -114.534685) (xy 20.766973 -114.505219) (xy 20.725782 -114.469528) (xy 20.690091 -114.428337)
			(xy 20.660625 -114.382487) (xy 20.637983 -114.33291) (xy 20.622628 -114.280615) (xy 20.614872 -114.226667)
			(xy 20.614386 -114.199416) (xy 20.614752 -114.176386) (xy 20.620351 -114.130666) (xy 20.625562 -114.10823)
			(xy 20.628551 -114.093837) (xy 20.627148 -114.064489) (xy 20.617472 -114.036746) (xy 20.600318 -114.012892)
			(xy 20.577098 -113.99489) (xy 20.563586 -113.989104) (xy 20.537133 -113.978231) (xy 20.487546 -113.949733)
			(xy 20.442771 -113.914149) (xy 20.403813 -113.872278) (xy 20.371544 -113.825058) (xy 20.346689 -113.773549)
			(xy 20.329805 -113.718906) (xy 20.32127 -113.662354) (xy 20.320762 -113.633758) (xy 14.777212 -113.633758)
			(xy 14.777212 -115.26139) (xy 14.883174 -115.367352) (xy 43.467485 -115.367352) (xy 43.467485 -115.312848)
			(xy 43.475242 -115.258899) (xy 43.490599 -115.206603) (xy 43.513241 -115.157025) (xy 43.54271 -115.111174)
			(xy 43.578404 -115.069984) (xy 43.619596 -115.034293) (xy 43.665449 -115.004828) (xy 43.715029 -114.982189)
			(xy 43.767326 -114.966836) (xy 43.821276 -114.959083) (xy 43.848528 -114.958622) (xy 43.87444 -114.959052)
			(xy 43.925788 -114.966052) (xy 43.975717 -114.979934) (xy 44.023309 -115.000443) (xy 44.06769 -115.027201)
			(xy 44.108043 -115.059716) (xy 44.12615 -115.078256) (xy 44.135585 -115.087711) (xy 44.158321 -115.101716)
			(xy 44.183912 -115.109342) (xy 44.210605 -115.110066) (xy 44.236572 -115.103838) (xy 44.260034 -115.091085)
			(xy 44.279382 -115.072681) (xy 44.286678 -115.061492) (xy 44.301629 -115.03791) (xy 44.337303 -114.994958)
			(xy 44.378856 -114.957664) (xy 44.425401 -114.926824) (xy 44.475944 -114.903098) (xy 44.529405 -114.886991)
			(xy 44.584643 -114.878847) (xy 44.61256 -114.878358) (xy 44.640508 -114.878837) (xy 44.695802 -114.887019)
			(xy 44.74931 -114.903186) (xy 44.799884 -114.926989) (xy 44.846442 -114.95792) (xy 44.887987 -114.995316)
			(xy 44.906184 -115.016534) (xy 44.91595 -115.027648) (xy 44.940544 -115.044076) (xy 44.968813 -115.052772)
			(xy 44.998389 -115.053006) (xy 45.026792 -115.044758) (xy 45.051643 -115.02872) (xy 45.061632 -115.017804)
			(xy 45.079813 -114.997368) (xy 45.121058 -114.96144) (xy 45.167011 -114.931771) (xy 45.21673 -114.908969)
			(xy 45.269197 -114.893502) (xy 45.323335 -114.885687) (xy 45.350684 -114.885216) (xy 45.377939 -114.88563)
			(xy 45.431895 -114.893385) (xy 45.484199 -114.908741) (xy 45.533784 -114.931384) (xy 45.579642 -114.960854)
			(xy 45.620839 -114.996549) (xy 45.656537 -115.037745) (xy 45.686008 -115.083602) (xy 45.708653 -115.133186)
			(xy 45.724011 -115.185489) (xy 45.731769 -115.239445) (xy 45.731769 -115.293955) (xy 45.727169 -115.325948)
			(xy 45.845506 -115.325948) (xy 45.845506 -115.271452) (xy 45.853261 -115.21751) (xy 45.868614 -115.165221)
			(xy 45.891252 -115.115649) (xy 45.920714 -115.069804) (xy 45.9564 -115.028617) (xy 45.997584 -114.992928)
			(xy 46.043428 -114.963463) (xy 46.092999 -114.940823) (xy 46.145287 -114.925467) (xy 46.199228 -114.917708)
			(xy 46.226476 -114.91722) (xy 46.254037 -114.917738) (xy 46.308586 -114.925663) (xy 46.361428 -114.94135)
			(xy 46.411464 -114.964475) (xy 46.457654 -114.994555) (xy 46.499038 -115.030966) (xy 46.534754 -115.072951)
			(xy 46.549818 -115.096036) (xy 46.557979 -115.108209) (xy 46.579925 -115.127615) (xy 46.606478 -115.139992)
			(xy 46.635452 -115.144321) (xy 46.664464 -115.140246) (xy 46.691124 -115.128102) (xy 46.71324 -115.108889)
			(xy 46.721522 -115.096798) (xy 46.736626 -115.073928) (xy 46.772313 -115.032334) (xy 46.813585 -114.996275)
			(xy 46.859593 -114.966495) (xy 46.90939 -114.943606) (xy 46.96195 -114.928079) (xy 47.016191 -114.920235)
			(xy 47.043594 -114.91976) (xy 47.069468 -114.920162) (xy 47.120743 -114.927145) (xy 47.170603 -114.940998)
			(xy 47.218132 -114.961466) (xy 47.262456 -114.988173) (xy 47.302762 -115.020628) (xy 47.338309 -115.058235)
			(xy 47.353728 -115.079018) (xy 47.361849 -115.089534) (xy 47.382371 -115.106388) (xy 47.406548 -115.117374)
			(xy 47.432741 -115.121747) (xy 47.459176 -115.119211) (xy 47.48406 -115.109938) (xy 47.505707 -115.094556)
			(xy 47.51451 -115.084606) (xy 47.532703 -115.063399) (xy 47.574272 -115.026062) (xy 47.620843 -114.995187)
			(xy 47.671418 -114.971435) (xy 47.724918 -114.955314) (xy 47.780196 -114.947169) (xy 47.808134 -114.946684)
			(xy 47.835383 -114.947188) (xy 47.889326 -114.954948) (xy 47.941616 -114.970306) (xy 47.991187 -114.992949)
			(xy 48.037033 -115.022415) (xy 48.078218 -115.058106) (xy 48.113905 -115.099295) (xy 48.143368 -115.145142)
			(xy 48.166006 -115.194716) (xy 48.181359 -115.247007) (xy 48.189114 -115.300951) (xy 48.189114 -115.355449)
			(xy 48.181359 -115.409393) (xy 48.166006 -115.461684) (xy 48.143368 -115.511258) (xy 48.113905 -115.557105)
			(xy 48.078218 -115.598294) (xy 48.037033 -115.633985) (xy 47.991187 -115.663451) (xy 47.941616 -115.686094)
			(xy 47.889326 -115.701452) (xy 47.835383 -115.709212) (xy 47.808134 -115.7097) (xy 47.782261 -115.709252)
			(xy 47.730989 -115.702274) (xy 47.681132 -115.688427) (xy 47.633604 -115.667966) (xy 47.589279 -115.641267)
			(xy 47.548972 -115.60882) (xy 47.513421 -115.571221) (xy 47.498 -115.550442) (xy 47.489964 -115.539854)
			(xy 47.469426 -115.52299) (xy 47.44523 -115.512001) (xy 47.419017 -115.507634) (xy 47.392565 -115.510185)
			(xy 47.367669 -115.51948) (xy 47.346018 -115.534889) (xy 47.337218 -115.544854) (xy 47.319001 -115.566039)
			(xy 47.277438 -115.60338) (xy 47.230873 -115.634258) (xy 47.180301 -115.658014) (xy 47.126806 -115.674139)
			(xy 47.07153 -115.682289) (xy 47.043594 -115.682776) (xy 47.016032 -115.682283) (xy 46.961482 -115.674354)
			(xy 46.90864 -115.658662) (xy 46.858603 -115.635534) (xy 46.812413 -115.605449) (xy 46.77103 -115.569035)
			(xy 46.735315 -115.527047) (xy 46.720252 -115.50396) (xy 46.71213 -115.491759) (xy 46.690175 -115.472352)
			(xy 46.663613 -115.459977) (xy 46.634631 -115.455652) (xy 46.605614 -115.459732) (xy 46.578949 -115.471882)
			(xy 46.556831 -115.491103) (xy 46.548548 -115.503198) (xy 46.533463 -115.526081) (xy 46.497773 -115.567675)
			(xy 46.456497 -115.603733) (xy 46.410486 -115.633512) (xy 46.360686 -115.656399) (xy 46.308123 -115.671922)
			(xy 46.25388 -115.679763) (xy 46.226476 -115.680236) (xy 46.199228 -115.679692) (xy 46.145287 -115.671933)
			(xy 46.092999 -115.656577) (xy 46.043428 -115.633937) (xy 45.997584 -115.604472) (xy 45.9564 -115.568783)
			(xy 45.920714 -115.527596) (xy 45.891252 -115.481751) (xy 45.868614 -115.432179) (xy 45.853261 -115.37989)
			(xy 45.845506 -115.325948) (xy 45.727169 -115.325948) (xy 45.724011 -115.347911) (xy 45.708653 -115.400214)
			(xy 45.686008 -115.449798) (xy 45.656537 -115.495655) (xy 45.620839 -115.536851) (xy 45.579642 -115.572546)
			(xy 45.533784 -115.602016) (xy 45.484199 -115.624659) (xy 45.431895 -115.640015) (xy 45.377939 -115.64777)
			(xy 45.350684 -115.648232) (xy 45.322737 -115.647726) (xy 45.267444 -115.63955) (xy 45.213937 -115.623389)
			(xy 45.163362 -115.599591) (xy 45.116803 -115.568664) (xy 45.075258 -115.531272) (xy 45.05706 -115.510056)
			(xy 45.047248 -115.498987) (xy 45.022666 -115.482559) (xy 44.994409 -115.473859) (xy 44.964844 -115.473617)
			(xy 44.936449 -115.481854) (xy 44.911602 -115.497878) (xy 44.901612 -115.508786) (xy 44.883406 -115.529199)
			(xy 44.842167 -115.565129) (xy 44.796219 -115.594802) (xy 44.746504 -115.617607) (xy 44.694042 -115.633079)
			(xy 44.639908 -115.640899) (xy 44.61256 -115.641374) (xy 44.586648 -115.640953) (xy 44.5353 -115.633951)
			(xy 44.48537 -115.620067) (xy 44.437778 -115.599557) (xy 44.393397 -115.572798) (xy 44.353045 -115.540281)
			(xy 44.334938 -115.52174) (xy 44.325515 -115.512273) (xy 44.302776 -115.498269) (xy 44.277182 -115.490644)
			(xy 44.250486 -115.489922) (xy 44.224518 -115.496152) (xy 44.201055 -115.508908) (xy 44.181706 -115.527314)
			(xy 44.17441 -115.538504) (xy 44.159466 -115.562091) (xy 44.123791 -115.605043) (xy 44.082237 -115.642337)
			(xy 44.03569 -115.673176) (xy 43.985147 -115.696902) (xy 43.931684 -115.713008) (xy 43.876446 -115.72115)
			(xy 43.848528 -115.721638) (xy 43.821276 -115.721117) (xy 43.767326 -115.713364) (xy 43.715029 -115.698011)
			(xy 43.665449 -115.675372) (xy 43.619596 -115.645907) (xy 43.578404 -115.610216) (xy 43.54271 -115.569026)
			(xy 43.513241 -115.523175) (xy 43.490599 -115.473597) (xy 43.475242 -115.421301) (xy 43.467485 -115.367352)
			(xy 14.883174 -115.367352) (xy 15.26667 -115.750848) (xy 49.821082 -115.750848) (xy 49.825153 -115.695226)
			(xy 49.837279 -115.640789) (xy 49.857202 -115.588698) (xy 49.884498 -115.540063) (xy 49.918584 -115.49592)
			(xy 49.958733 -115.457211) (xy 50.004091 -115.42476) (xy 50.053691 -115.399259) (xy 50.106475 -115.381252)
			(xy 50.161318 -115.371122) (xy 50.217052 -115.369085) (xy 50.272489 -115.375185) (xy 50.326446 -115.389291)
			(xy 50.377775 -115.411103) (xy 50.425381 -115.440157) (xy 50.468249 -115.475832) (xy 50.505466 -115.517369)
			(xy 50.536239 -115.563882) (xy 50.559911 -115.614379) (xy 50.575979 -115.667786) (xy 50.584099 -115.722962)
			(xy 50.584608 -115.750848) (xy 50.584099 -115.778734) (xy 50.575979 -115.83391) (xy 50.559911 -115.887317)
			(xy 50.536239 -115.937814) (xy 50.505466 -115.984327) (xy 50.468249 -116.025864) (xy 50.425381 -116.061539)
			(xy 50.377775 -116.090593) (xy 50.326446 -116.112405) (xy 50.272489 -116.126511) (xy 50.217052 -116.132611)
			(xy 50.161318 -116.130574) (xy 50.106475 -116.120444) (xy 50.053691 -116.102437) (xy 50.004091 -116.076936)
			(xy 49.958733 -116.044485) (xy 49.918584 -116.005776) (xy 49.884498 -115.961633) (xy 49.857202 -115.912998)
			(xy 49.837279 -115.860907) (xy 49.825153 -115.80647) (xy 49.821082 -115.750848) (xy 15.26667 -115.750848)
			(xy 15.342362 -115.82654) (xy 46.278292 -115.82654) (xy 50.00752 -119.555768) (xy 52.493672 -119.555768)
		)
		(stroke
			(width 0)
			(type solid)
		)
		(fill yes)
		(layer "In6.Cu")
		(net "P3V3_AUX")
	)
	(gr_poly
		(pts
			(xy 20.44446 -421.02532) (xy 20.44446 -409.910026) (xy 20.441666 -409.901898) (xy 20.432025 -409.871888)
			(xy 20.421683 -409.809715) (xy 20.421092 -409.7782) (xy 20.421741 -409.74669) (xy 20.432079 -409.684525)
			(xy 20.441666 -409.654502) (xy 20.44446 -409.646374) (xy 20.44446 -408.4955) (xy 21.8186 -407.12136)
			(xy 26.18232 -407.12136) (xy 26.198847 -407.098192) (xy 26.237651 -407.056564) (xy 26.28221 -407.021166)
			(xy 26.331536 -406.992784) (xy 26.384532 -406.972049) (xy 26.440022 -406.95942) (xy 26.496772 -406.95518)
			(xy 26.553522 -406.95942) (xy 26.609012 -406.972049) (xy 26.662008 -406.992784) (xy 26.711334 -407.021166)
			(xy 26.755893 -407.056564) (xy 26.794697 -407.098192) (xy 26.811224 -407.12136) (xy 32.0675 -407.12136)
			(xy 36.78174 -402.40712) (xy 40.00246 -402.40712) (xy 41.49598 -400.9136) (xy 41.49598 -397.85036)
			(xy 43.0276 -396.31874) (xy 48.64608 -396.31874) (xy 50.33264 -394.63218) (xy 50.33264 -390.62406)
			(xy 47.66056 -387.95198) (xy 25.382728 -387.95198) (xy 25.372822 -387.956552) (xy 25.348005 -387.967241)
			(xy 25.296112 -387.982302) (xy 25.242613 -387.989887) (xy 25.215596 -387.990334) (xy 25.18858 -387.989879)
			(xy 25.135084 -387.982286) (xy 25.083194 -387.967223) (xy 25.05837 -387.956552) (xy 25.048464 -387.95198)
			(xy 19.65452 -387.95198) (xy 16.70812 -385.00558) (xy 13.48994 -385.00558) (xy 11.375644 -387.119876)
			(xy 14.044928 -387.119876) (xy 14.048999 -387.064254) (xy 14.061125 -387.009817) (xy 14.081048 -386.957726)
			(xy 14.108344 -386.909091) (xy 14.14243 -386.864948) (xy 14.182579 -386.826239) (xy 14.227937 -386.793788)
			(xy 14.277537 -386.768287) (xy 14.330321 -386.75028) (xy 14.385164 -386.74015) (xy 14.440898 -386.738113)
			(xy 14.496335 -386.744213) (xy 14.550292 -386.758319) (xy 14.601621 -386.780131) (xy 14.649227 -386.809185)
			(xy 14.692095 -386.84486) (xy 14.729312 -386.886397) (xy 14.760085 -386.93291) (xy 14.783757 -386.983407)
			(xy 14.799825 -387.036814) (xy 14.807945 -387.09199) (xy 14.808454 -387.119876) (xy 14.807945 -387.147762)
			(xy 14.799825 -387.202938) (xy 14.783757 -387.256345) (xy 14.760085 -387.306842) (xy 14.729312 -387.353355)
			(xy 14.692095 -387.394892) (xy 14.649227 -387.430567) (xy 14.601621 -387.459621) (xy 14.550292 -387.481433)
			(xy 14.496335 -387.495539) (xy 14.440898 -387.501639) (xy 14.385164 -387.499602) (xy 14.330321 -387.489472)
			(xy 14.277537 -387.471465) (xy 14.227937 -387.445964) (xy 14.182579 -387.413513) (xy 14.14243 -387.374804)
			(xy 14.108344 -387.330661) (xy 14.081048 -387.282026) (xy 14.061125 -387.229935) (xy 14.048999 -387.175498)
			(xy 14.044928 -387.119876) (xy 11.375644 -387.119876) (xy 10.359644 -388.135876) (xy 14.044928 -388.135876)
			(xy 14.048999 -388.080254) (xy 14.061125 -388.025817) (xy 14.081048 -387.973726) (xy 14.108344 -387.925091)
			(xy 14.14243 -387.880948) (xy 14.182579 -387.842239) (xy 14.227937 -387.809788) (xy 14.277537 -387.784287)
			(xy 14.330321 -387.76628) (xy 14.385164 -387.75615) (xy 14.440898 -387.754113) (xy 14.496335 -387.760213)
			(xy 14.550292 -387.774319) (xy 14.601621 -387.796131) (xy 14.649227 -387.825185) (xy 14.692095 -387.86086)
			(xy 14.729312 -387.902397) (xy 14.760085 -387.94891) (xy 14.783757 -387.999407) (xy 14.799825 -388.052814)
			(xy 14.807945 -388.10799) (xy 14.808454 -388.135876) (xy 14.807945 -388.163762) (xy 14.799825 -388.218938)
			(xy 14.783757 -388.272345) (xy 14.760085 -388.322842) (xy 14.729312 -388.369355) (xy 14.692095 -388.410892)
			(xy 14.649227 -388.446567) (xy 14.601621 -388.475621) (xy 14.550292 -388.497433) (xy 14.496335 -388.511539)
			(xy 14.440898 -388.517639) (xy 14.385164 -388.515602) (xy 14.330321 -388.505472) (xy 14.277537 -388.487465)
			(xy 14.227937 -388.461964) (xy 14.182579 -388.429513) (xy 14.14243 -388.390804) (xy 14.108344 -388.346661)
			(xy 14.081048 -388.298026) (xy 14.061125 -388.245935) (xy 14.048999 -388.191498) (xy 14.044928 -388.135876)
			(xy 10.359644 -388.135876) (xy 9.343644 -389.151876) (xy 14.044928 -389.151876) (xy 14.048999 -389.096254)
			(xy 14.061125 -389.041817) (xy 14.081048 -388.989726) (xy 14.108344 -388.941091) (xy 14.14243 -388.896948)
			(xy 14.182579 -388.858239) (xy 14.227937 -388.825788) (xy 14.277537 -388.800287) (xy 14.330321 -388.78228)
			(xy 14.385164 -388.77215) (xy 14.440898 -388.770113) (xy 14.496335 -388.776213) (xy 14.550292 -388.790319)
			(xy 14.601621 -388.812131) (xy 14.649227 -388.841185) (xy 14.692095 -388.87686) (xy 14.729312 -388.918397)
			(xy 14.760085 -388.96491) (xy 14.783757 -389.015407) (xy 14.799825 -389.068814) (xy 14.807945 -389.12399)
			(xy 14.808454 -389.151876) (xy 14.807945 -389.179762) (xy 14.799825 -389.234938) (xy 14.783757 -389.288345)
			(xy 14.760085 -389.338842) (xy 14.729312 -389.385355) (xy 14.692095 -389.426892) (xy 14.649227 -389.462567)
			(xy 14.601621 -389.491621) (xy 14.550292 -389.513433) (xy 14.496335 -389.527539) (xy 14.440898 -389.533639)
			(xy 14.385164 -389.531602) (xy 14.330321 -389.521472) (xy 14.277537 -389.503465) (xy 14.227937 -389.477964)
			(xy 14.182579 -389.445513) (xy 14.14243 -389.406804) (xy 14.108344 -389.362661) (xy 14.081048 -389.314026)
			(xy 14.061125 -389.261935) (xy 14.048999 -389.207498) (xy 14.044928 -389.151876) (xy 9.343644 -389.151876)
			(xy 8.85444 -389.64108) (xy 8.85444 -390.372346) (xy 20.201634 -390.372346) (xy 20.205705 -390.316724)
			(xy 20.217831 -390.262287) (xy 20.237754 -390.210196) (xy 20.26505 -390.161561) (xy 20.299136 -390.117418)
			(xy 20.339285 -390.078709) (xy 20.384643 -390.046258) (xy 20.434243 -390.020757) (xy 20.487027 -390.00275)
			(xy 20.54187 -389.99262) (xy 20.597604 -389.990583) (xy 20.653041 -389.996683) (xy 20.706998 -390.010789)
			(xy 20.758327 -390.032601) (xy 20.805933 -390.061655) (xy 20.848801 -390.09733) (xy 20.886018 -390.138867)
			(xy 20.916791 -390.18538) (xy 20.940463 -390.235877) (xy 20.956531 -390.289284) (xy 20.957354 -390.294876)
			(xy 28.256228 -390.294876) (xy 28.260299 -390.239254) (xy 28.272425 -390.184817) (xy 28.292348 -390.132726)
			(xy 28.319644 -390.084091) (xy 28.35373 -390.039948) (xy 28.393879 -390.001239) (xy 28.439237 -389.968788)
			(xy 28.488837 -389.943287) (xy 28.541621 -389.92528) (xy 28.596464 -389.91515) (xy 28.652198 -389.913113)
			(xy 28.707635 -389.919213) (xy 28.761592 -389.933319) (xy 28.812921 -389.955131) (xy 28.860527 -389.984185)
			(xy 28.903395 -390.01986) (xy 28.940612 -390.061397) (xy 28.970895 -390.10717) (xy 31.968946 -390.10717)
			(xy 31.973017 -390.051548) (xy 31.985143 -389.997111) (xy 32.005066 -389.94502) (xy 32.032362 -389.896385)
			(xy 32.066448 -389.852242) (xy 32.106597 -389.813533) (xy 32.151955 -389.781082) (xy 32.201555 -389.755581)
			(xy 32.254339 -389.737574) (xy 32.309182 -389.727444) (xy 32.364916 -389.725407) (xy 32.420353 -389.731507)
			(xy 32.47431 -389.745613) (xy 32.525639 -389.767425) (xy 32.573245 -389.796479) (xy 32.616113 -389.832154)
			(xy 32.65333 -389.873691) (xy 32.684103 -389.920204) (xy 32.707775 -389.970701) (xy 32.718801 -390.007348)
			(xy 46.835312 -390.007348) (xy 46.839383 -389.951726) (xy 46.851509 -389.897289) (xy 46.871432 -389.845198)
			(xy 46.898728 -389.796563) (xy 46.932814 -389.75242) (xy 46.972963 -389.713711) (xy 47.018321 -389.68126)
			(xy 47.067921 -389.655759) (xy 47.120705 -389.637752) (xy 47.175548 -389.627622) (xy 47.231282 -389.625585)
			(xy 47.286719 -389.631685) (xy 47.340676 -389.645791) (xy 47.392005 -389.667603) (xy 47.439611 -389.696657)
			(xy 47.482479 -389.732332) (xy 47.519696 -389.773869) (xy 47.550469 -389.820382) (xy 47.574141 -389.870879)
			(xy 47.590209 -389.924286) (xy 47.598329 -389.979462) (xy 47.598838 -390.007348) (xy 47.598329 -390.035234)
			(xy 47.590209 -390.09041) (xy 47.574141 -390.143817) (xy 47.550469 -390.194314) (xy 47.519696 -390.240827)
			(xy 47.482479 -390.282364) (xy 47.439611 -390.318039) (xy 47.392005 -390.347093) (xy 47.340676 -390.368905)
			(xy 47.286719 -390.383011) (xy 47.231282 -390.389111) (xy 47.175548 -390.387074) (xy 47.120705 -390.376944)
			(xy 47.067921 -390.358937) (xy 47.018321 -390.333436) (xy 46.972963 -390.300985) (xy 46.932814 -390.262276)
			(xy 46.898728 -390.218133) (xy 46.871432 -390.169498) (xy 46.851509 -390.117407) (xy 46.839383 -390.06297)
			(xy 46.835312 -390.007348) (xy 32.718801 -390.007348) (xy 32.723843 -390.024108) (xy 32.731963 -390.079284)
			(xy 32.732472 -390.10717) (xy 32.731963 -390.135056) (xy 32.723843 -390.190232) (xy 32.707775 -390.243639)
			(xy 32.684103 -390.294136) (xy 32.65333 -390.340649) (xy 32.616113 -390.382186) (xy 32.573245 -390.417861)
			(xy 32.525639 -390.446915) (xy 32.47431 -390.468727) (xy 32.420353 -390.482833) (xy 32.364916 -390.488933)
			(xy 32.309182 -390.486896) (xy 32.254339 -390.476766) (xy 32.201555 -390.458759) (xy 32.151955 -390.433258)
			(xy 32.106597 -390.400807) (xy 32.066448 -390.362098) (xy 32.032362 -390.317955) (xy 32.005066 -390.26932)
			(xy 31.985143 -390.217229) (xy 31.973017 -390.162792) (xy 31.968946 -390.10717) (xy 28.970895 -390.10717)
			(xy 28.971385 -390.10791) (xy 28.995057 -390.158407) (xy 29.011125 -390.211814) (xy 29.019245 -390.26699)
			(xy 29.019754 -390.294876) (xy 29.019245 -390.322762) (xy 29.011125 -390.377938) (xy 28.995057 -390.431345)
			(xy 28.971385 -390.481842) (xy 28.940612 -390.528355) (xy 28.903395 -390.569892) (xy 28.860527 -390.605567)
			(xy 28.812921 -390.634621) (xy 28.761592 -390.656433) (xy 28.707635 -390.670539) (xy 28.652198 -390.676639)
			(xy 28.596464 -390.674602) (xy 28.541621 -390.664472) (xy 28.488837 -390.646465) (xy 28.439237 -390.620964)
			(xy 28.393879 -390.588513) (xy 28.35373 -390.549804) (xy 28.319644 -390.505661) (xy 28.292348 -390.457026)
			(xy 28.272425 -390.404935) (xy 28.260299 -390.350498) (xy 28.256228 -390.294876) (xy 20.957354 -390.294876)
			(xy 20.964651 -390.34446) (xy 20.96516 -390.372346) (xy 20.964651 -390.400232) (xy 20.956531 -390.455408)
			(xy 20.940463 -390.508815) (xy 20.916791 -390.559312) (xy 20.886018 -390.605825) (xy 20.848801 -390.647362)
			(xy 20.805933 -390.683037) (xy 20.758327 -390.712091) (xy 20.706998 -390.733903) (xy 20.653041 -390.748009)
			(xy 20.597604 -390.754109) (xy 20.54187 -390.752072) (xy 20.487027 -390.741942) (xy 20.434243 -390.723935)
			(xy 20.384643 -390.698434) (xy 20.339285 -390.665983) (xy 20.299136 -390.627274) (xy 20.26505 -390.583131)
			(xy 20.237754 -390.534496) (xy 20.217831 -390.482405) (xy 20.205705 -390.427968) (xy 20.201634 -390.372346)
			(xy 8.85444 -390.372346) (xy 8.85444 -391.007346) (xy 22.868634 -391.007346) (xy 22.872705 -390.951724)
			(xy 22.884831 -390.897287) (xy 22.904754 -390.845196) (xy 22.93205 -390.796561) (xy 22.966136 -390.752418)
			(xy 23.006285 -390.713709) (xy 23.051643 -390.681258) (xy 23.101243 -390.655757) (xy 23.154027 -390.63775)
			(xy 23.20887 -390.62762) (xy 23.264604 -390.625583) (xy 23.320041 -390.631683) (xy 23.373998 -390.645789)
			(xy 23.425327 -390.667601) (xy 23.472933 -390.696655) (xy 23.515801 -390.73233) (xy 23.553018 -390.773867)
			(xy 23.583791 -390.82038) (xy 23.607463 -390.870877) (xy 23.623531 -390.924284) (xy 23.631651 -390.97946)
			(xy 23.63216 -391.007346) (xy 23.631651 -391.035232) (xy 23.623531 -391.090408) (xy 23.607463 -391.143815)
			(xy 23.583791 -391.194312) (xy 23.553018 -391.240825) (xy 23.515801 -391.282362) (xy 23.481538 -391.310876)
			(xy 28.256228 -391.310876) (xy 28.260299 -391.255254) (xy 28.272425 -391.200817) (xy 28.292348 -391.148726)
			(xy 28.319644 -391.100091) (xy 28.35373 -391.055948) (xy 28.393879 -391.017239) (xy 28.439237 -390.984788)
			(xy 28.488837 -390.959287) (xy 28.541621 -390.94128) (xy 28.596464 -390.93115) (xy 28.652198 -390.929113)
			(xy 28.707635 -390.935213) (xy 28.761592 -390.949319) (xy 28.812921 -390.971131) (xy 28.860527 -391.000185)
			(xy 28.903395 -391.03586) (xy 28.940612 -391.077397) (xy 28.971385 -391.12391) (xy 28.995057 -391.174407)
			(xy 29.011125 -391.227814) (xy 29.019245 -391.28299) (xy 29.019754 -391.310876) (xy 29.019245 -391.338762)
			(xy 29.011125 -391.393938) (xy 28.995057 -391.447345) (xy 28.971385 -391.497842) (xy 28.940612 -391.544355)
			(xy 28.903395 -391.585892) (xy 28.860527 -391.621567) (xy 28.836885 -391.635996) (xy 31.968946 -391.635996)
			(xy 31.973017 -391.580374) (xy 31.985143 -391.525937) (xy 32.005066 -391.473846) (xy 32.032362 -391.425211)
			(xy 32.066448 -391.381068) (xy 32.106597 -391.342359) (xy 32.151955 -391.309908) (xy 32.201555 -391.284407)
			(xy 32.254339 -391.2664) (xy 32.309182 -391.25627) (xy 32.364916 -391.254233) (xy 32.420353 -391.260333)
			(xy 32.47431 -391.274439) (xy 32.525639 -391.296251) (xy 32.573245 -391.325305) (xy 32.616113 -391.36098)
			(xy 32.65333 -391.402517) (xy 32.654373 -391.404094) (xy 38.548816 -391.404094) (xy 38.552887 -391.348472)
			(xy 38.565013 -391.294035) (xy 38.584936 -391.241944) (xy 38.612232 -391.193309) (xy 38.646318 -391.149166)
			(xy 38.686467 -391.110457) (xy 38.731825 -391.078006) (xy 38.781425 -391.052505) (xy 38.834209 -391.034498)
			(xy 38.889052 -391.024368) (xy 38.944786 -391.022331) (xy 39.000223 -391.028431) (xy 39.05418 -391.042537)
			(xy 39.105509 -391.064349) (xy 39.153115 -391.093403) (xy 39.195983 -391.129078) (xy 39.2332 -391.170615)
			(xy 39.263973 -391.217128) (xy 39.287645 -391.267625) (xy 39.303713 -391.321032) (xy 39.311833 -391.376208)
			(xy 39.311864 -391.377932) (xy 40.593516 -391.377932) (xy 40.597587 -391.32231) (xy 40.609713 -391.267873)
			(xy 40.629636 -391.215782) (xy 40.656932 -391.167147) (xy 40.691018 -391.123004) (xy 40.731167 -391.084295)
			(xy 40.776525 -391.051844) (xy 40.826125 -391.026343) (xy 40.878909 -391.008336) (xy 40.933752 -390.998206)
			(xy 40.989486 -390.996169) (xy 41.044923 -391.002269) (xy 41.09888 -391.016375) (xy 41.150209 -391.038187)
			(xy 41.197815 -391.067241) (xy 41.224733 -391.089642) (xy 46.835312 -391.089642) (xy 46.839383 -391.03402)
			(xy 46.851509 -390.979583) (xy 46.871432 -390.927492) (xy 46.898728 -390.878857) (xy 46.932814 -390.834714)
			(xy 46.972963 -390.796005) (xy 47.018321 -390.763554) (xy 47.067921 -390.738053) (xy 47.120705 -390.720046)
			(xy 47.175548 -390.709916) (xy 47.231282 -390.707879) (xy 47.286719 -390.713979) (xy 47.340676 -390.728085)
			(xy 47.392005 -390.749897) (xy 47.439611 -390.778951) (xy 47.482479 -390.814626) (xy 47.519696 -390.856163)
			(xy 47.550469 -390.902676) (xy 47.574141 -390.953173) (xy 47.590209 -391.00658) (xy 47.598329 -391.061756)
			(xy 47.598838 -391.089642) (xy 47.598329 -391.117528) (xy 47.590209 -391.172704) (xy 47.574141 -391.226111)
			(xy 47.550469 -391.276608) (xy 47.519696 -391.323121) (xy 47.482479 -391.364658) (xy 47.439611 -391.400333)
			(xy 47.392005 -391.429387) (xy 47.340676 -391.451199) (xy 47.286719 -391.465305) (xy 47.231282 -391.471405)
			(xy 47.175548 -391.469368) (xy 47.120705 -391.459238) (xy 47.067921 -391.441231) (xy 47.018321 -391.41573)
			(xy 46.972963 -391.383279) (xy 46.932814 -391.34457) (xy 46.898728 -391.300427) (xy 46.871432 -391.251792)
			(xy 46.851509 -391.199701) (xy 46.839383 -391.145264) (xy 46.835312 -391.089642) (xy 41.224733 -391.089642)
			(xy 41.240683 -391.102916) (xy 41.2779 -391.144453) (xy 41.308673 -391.190966) (xy 41.332345 -391.241463)
			(xy 41.348413 -391.29487) (xy 41.356533 -391.350046) (xy 41.357042 -391.377932) (xy 41.356533 -391.405818)
			(xy 41.348413 -391.460994) (xy 41.332345 -391.514401) (xy 41.308673 -391.564898) (xy 41.2779 -391.611411)
			(xy 41.240683 -391.652948) (xy 41.197815 -391.688623) (xy 41.150209 -391.717677) (xy 41.09888 -391.739489)
			(xy 41.044923 -391.753595) (xy 40.989486 -391.759695) (xy 40.933752 -391.757658) (xy 40.878909 -391.747528)
			(xy 40.826125 -391.729521) (xy 40.776525 -391.70402) (xy 40.731167 -391.671569) (xy 40.691018 -391.63286)
			(xy 40.656932 -391.588717) (xy 40.629636 -391.540082) (xy 40.609713 -391.487991) (xy 40.597587 -391.433554)
			(xy 40.593516 -391.377932) (xy 39.311864 -391.377932) (xy 39.312342 -391.404094) (xy 39.311833 -391.43198)
			(xy 39.303713 -391.487156) (xy 39.287645 -391.540563) (xy 39.263973 -391.59106) (xy 39.2332 -391.637573)
			(xy 39.195983 -391.67911) (xy 39.153115 -391.714785) (xy 39.105509 -391.743839) (xy 39.05418 -391.765651)
			(xy 39.000223 -391.779757) (xy 38.944786 -391.785857) (xy 38.889052 -391.78382) (xy 38.834209 -391.77369)
			(xy 38.781425 -391.755683) (xy 38.731825 -391.730182) (xy 38.686467 -391.697731) (xy 38.646318 -391.659022)
			(xy 38.612232 -391.614879) (xy 38.584936 -391.566244) (xy 38.565013 -391.514153) (xy 38.552887 -391.459716)
			(xy 38.548816 -391.404094) (xy 32.654373 -391.404094) (xy 32.684103 -391.44903) (xy 32.707775 -391.499527)
			(xy 32.723843 -391.552934) (xy 32.731963 -391.60811) (xy 32.732472 -391.635996) (xy 32.731963 -391.663882)
			(xy 32.723843 -391.719058) (xy 32.707775 -391.772465) (xy 32.684103 -391.822962) (xy 32.65333 -391.869475)
			(xy 32.616113 -391.911012) (xy 32.573245 -391.946687) (xy 32.525639 -391.975741) (xy 32.47431 -391.997553)
			(xy 32.420353 -392.011659) (xy 32.364916 -392.017759) (xy 32.309182 -392.015722) (xy 32.254339 -392.005592)
			(xy 32.201555 -391.987585) (xy 32.151955 -391.962084) (xy 32.106597 -391.929633) (xy 32.066448 -391.890924)
			(xy 32.032362 -391.846781) (xy 32.005066 -391.798146) (xy 31.985143 -391.746055) (xy 31.973017 -391.691618)
			(xy 31.968946 -391.635996) (xy 28.836885 -391.635996) (xy 28.812921 -391.650621) (xy 28.761592 -391.672433)
			(xy 28.707635 -391.686539) (xy 28.652198 -391.692639) (xy 28.596464 -391.690602) (xy 28.541621 -391.680472)
			(xy 28.488837 -391.662465) (xy 28.439237 -391.636964) (xy 28.393879 -391.604513) (xy 28.35373 -391.565804)
			(xy 28.319644 -391.521661) (xy 28.292348 -391.473026) (xy 28.272425 -391.420935) (xy 28.260299 -391.366498)
			(xy 28.256228 -391.310876) (xy 23.481538 -391.310876) (xy 23.472933 -391.318037) (xy 23.425327 -391.347091)
			(xy 23.373998 -391.368903) (xy 23.320041 -391.383009) (xy 23.264604 -391.389109) (xy 23.20887 -391.387072)
			(xy 23.154027 -391.376942) (xy 23.101243 -391.358935) (xy 23.051643 -391.333434) (xy 23.006285 -391.300983)
			(xy 22.966136 -391.262274) (xy 22.93205 -391.218131) (xy 22.904754 -391.169496) (xy 22.884831 -391.117405)
			(xy 22.872705 -391.062968) (xy 22.868634 -391.007346) (xy 8.85444 -391.007346) (xy 8.85444 -392.199876)
			(xy 14.044928 -392.199876) (xy 14.048999 -392.144254) (xy 14.061125 -392.089817) (xy 14.081048 -392.037726)
			(xy 14.108344 -391.989091) (xy 14.14243 -391.944948) (xy 14.182579 -391.906239) (xy 14.227937 -391.873788)
			(xy 14.277537 -391.848287) (xy 14.330321 -391.83028) (xy 14.385164 -391.82015) (xy 14.440898 -391.818113)
			(xy 14.496335 -391.824213) (xy 14.550292 -391.838319) (xy 14.601621 -391.860131) (xy 14.649227 -391.889185)
			(xy 14.692095 -391.92486) (xy 14.729312 -391.966397) (xy 14.760085 -392.01291) (xy 14.783757 -392.063407)
			(xy 14.799825 -392.116814) (xy 14.807945 -392.17199) (xy 14.808454 -392.199876) (xy 14.807945 -392.227762)
			(xy 14.799825 -392.282938) (xy 14.786606 -392.326876) (xy 28.256228 -392.326876) (xy 28.260299 -392.271254)
			(xy 28.272425 -392.216817) (xy 28.292348 -392.164726) (xy 28.319644 -392.116091) (xy 28.35373 -392.071948)
			(xy 28.393879 -392.033239) (xy 28.439237 -392.000788) (xy 28.488837 -391.975287) (xy 28.541621 -391.95728)
			(xy 28.596464 -391.94715) (xy 28.652198 -391.945113) (xy 28.707635 -391.951213) (xy 28.761592 -391.965319)
			(xy 28.812921 -391.987131) (xy 28.860527 -392.016185) (xy 28.903395 -392.05186) (xy 28.940612 -392.093397)
			(xy 28.971385 -392.13991) (xy 28.991756 -392.183366) (xy 46.835312 -392.183366) (xy 46.839383 -392.127744)
			(xy 46.851509 -392.073307) (xy 46.871432 -392.021216) (xy 46.898728 -391.972581) (xy 46.932814 -391.928438)
			(xy 46.972963 -391.889729) (xy 47.018321 -391.857278) (xy 47.067921 -391.831777) (xy 47.120705 -391.81377)
			(xy 47.175548 -391.80364) (xy 47.231282 -391.801603) (xy 47.286719 -391.807703) (xy 47.340676 -391.821809)
			(xy 47.392005 -391.843621) (xy 47.439611 -391.872675) (xy 47.482479 -391.90835) (xy 47.519696 -391.949887)
			(xy 47.550469 -391.9964) (xy 47.574141 -392.046897) (xy 47.590209 -392.100304) (xy 47.598329 -392.15548)
			(xy 47.598838 -392.183366) (xy 47.598329 -392.211252) (xy 47.590209 -392.266428) (xy 47.574141 -392.319835)
			(xy 47.550469 -392.370332) (xy 47.519696 -392.416845) (xy 47.482479 -392.458382) (xy 47.439611 -392.494057)
			(xy 47.392005 -392.523111) (xy 47.340676 -392.544923) (xy 47.286719 -392.559029) (xy 47.231282 -392.565129)
			(xy 47.175548 -392.563092) (xy 47.120705 -392.552962) (xy 47.067921 -392.534955) (xy 47.018321 -392.509454)
			(xy 46.972963 -392.477003) (xy 46.932814 -392.438294) (xy 46.898728 -392.394151) (xy 46.871432 -392.345516)
			(xy 46.851509 -392.293425) (xy 46.839383 -392.238988) (xy 46.835312 -392.183366) (xy 28.991756 -392.183366)
			(xy 28.995057 -392.190407) (xy 29.011125 -392.243814) (xy 29.019245 -392.29899) (xy 29.019754 -392.326876)
			(xy 29.019245 -392.354762) (xy 29.011125 -392.409938) (xy 28.995057 -392.463345) (xy 28.971385 -392.513842)
			(xy 28.940612 -392.560355) (xy 28.903395 -392.601892) (xy 28.860527 -392.637567) (xy 28.812921 -392.666621)
			(xy 28.761592 -392.688433) (xy 28.707635 -392.702539) (xy 28.652198 -392.708639) (xy 28.596464 -392.706602)
			(xy 28.541621 -392.696472) (xy 28.488837 -392.678465) (xy 28.439237 -392.652964) (xy 28.393879 -392.620513)
			(xy 28.35373 -392.581804) (xy 28.319644 -392.537661) (xy 28.292348 -392.489026) (xy 28.272425 -392.436935)
			(xy 28.260299 -392.382498) (xy 28.256228 -392.326876) (xy 14.786606 -392.326876) (xy 14.783757 -392.336345)
			(xy 14.760085 -392.386842) (xy 14.729312 -392.433355) (xy 14.692095 -392.474892) (xy 14.649227 -392.510567)
			(xy 14.601621 -392.539621) (xy 14.550292 -392.561433) (xy 14.496335 -392.575539) (xy 14.440898 -392.581639)
			(xy 14.385164 -392.579602) (xy 14.330321 -392.569472) (xy 14.277537 -392.551465) (xy 14.227937 -392.525964)
			(xy 14.182579 -392.493513) (xy 14.14243 -392.454804) (xy 14.108344 -392.410661) (xy 14.081048 -392.362026)
			(xy 14.061125 -392.309935) (xy 14.048999 -392.255498) (xy 14.044928 -392.199876) (xy 8.85444 -392.199876)
			(xy 8.85444 -393.215876) (xy 14.044928 -393.215876) (xy 14.048999 -393.160254) (xy 14.061125 -393.105817)
			(xy 14.081048 -393.053726) (xy 14.108344 -393.005091) (xy 14.14243 -392.960948) (xy 14.182579 -392.922239)
			(xy 14.227937 -392.889788) (xy 14.277537 -392.864287) (xy 14.330321 -392.84628) (xy 14.385164 -392.83615)
			(xy 14.440898 -392.834113) (xy 14.496335 -392.840213) (xy 14.550292 -392.854319) (xy 14.601621 -392.876131)
			(xy 14.649227 -392.905185) (xy 14.692095 -392.94086) (xy 14.729312 -392.982397) (xy 14.760085 -393.02891)
			(xy 14.783757 -393.079407) (xy 14.799825 -393.132814) (xy 14.807945 -393.18799) (xy 14.808454 -393.215876)
			(xy 14.807945 -393.243762) (xy 14.799825 -393.298938) (xy 14.783757 -393.352345) (xy 14.760085 -393.402842)
			(xy 14.729312 -393.449355) (xy 14.692095 -393.490892) (xy 14.649227 -393.526567) (xy 14.601621 -393.555621)
			(xy 14.550292 -393.577433) (xy 14.496335 -393.591539) (xy 14.440898 -393.597639) (xy 14.385164 -393.595602)
			(xy 14.330321 -393.585472) (xy 14.277537 -393.567465) (xy 14.227937 -393.541964) (xy 14.182579 -393.509513)
			(xy 14.14243 -393.470804) (xy 14.108344 -393.426661) (xy 14.081048 -393.378026) (xy 14.061125 -393.325935)
			(xy 14.048999 -393.271498) (xy 14.044928 -393.215876) (xy 8.85444 -393.215876) (xy 8.85444 -393.615926)
			(xy 18.102578 -393.615926) (xy 18.106649 -393.560304) (xy 18.118775 -393.505867) (xy 18.138698 -393.453776)
			(xy 18.165994 -393.405141) (xy 18.20008 -393.360998) (xy 18.240229 -393.322289) (xy 18.285587 -393.289838)
			(xy 18.335187 -393.264337) (xy 18.387971 -393.24633) (xy 18.442814 -393.2362) (xy 18.498548 -393.234163)
			(xy 18.553985 -393.240263) (xy 18.607942 -393.254369) (xy 18.659271 -393.276181) (xy 18.706877 -393.305235)
			(xy 18.749745 -393.34091) (xy 18.751507 -393.342876) (xy 28.256228 -393.342876) (xy 28.260299 -393.287254)
			(xy 28.272425 -393.232817) (xy 28.292348 -393.180726) (xy 28.319644 -393.132091) (xy 28.35373 -393.087948)
			(xy 28.393879 -393.049239) (xy 28.439237 -393.016788) (xy 28.488837 -392.991287) (xy 28.541621 -392.97328)
			(xy 28.596464 -392.96315) (xy 28.652198 -392.961113) (xy 28.707635 -392.967213) (xy 28.761592 -392.981319)
			(xy 28.812921 -393.003131) (xy 28.860527 -393.032185) (xy 28.903395 -393.06786) (xy 28.940612 -393.109397)
			(xy 28.971385 -393.15591) (xy 28.980564 -393.17549) (xy 31.968946 -393.17549) (xy 31.973017 -393.119868)
			(xy 31.985143 -393.065431) (xy 32.005066 -393.01334) (xy 32.032362 -392.964705) (xy 32.066448 -392.920562)
			(xy 32.106597 -392.881853) (xy 32.151955 -392.849402) (xy 32.201555 -392.823901) (xy 32.254339 -392.805894)
			(xy 32.309182 -392.795764) (xy 32.364916 -392.793727) (xy 32.420353 -392.799827) (xy 32.47431 -392.813933)
			(xy 32.525639 -392.835745) (xy 32.573245 -392.864799) (xy 32.616113 -392.900474) (xy 32.65333 -392.942011)
			(xy 32.684103 -392.988524) (xy 32.707775 -393.039021) (xy 32.723843 -393.092428) (xy 32.731963 -393.147604)
			(xy 32.732472 -393.17549) (xy 32.731963 -393.203376) (xy 32.723843 -393.258552) (xy 32.707775 -393.311959)
			(xy 32.684103 -393.362456) (xy 32.65333 -393.408969) (xy 32.616113 -393.450506) (xy 32.611761 -393.454128)
			(xy 38.515034 -393.454128) (xy 38.519105 -393.398506) (xy 38.531231 -393.344069) (xy 38.551154 -393.291978)
			(xy 38.57845 -393.243343) (xy 38.612536 -393.1992) (xy 38.652685 -393.160491) (xy 38.698043 -393.12804)
			(xy 38.747643 -393.102539) (xy 38.800427 -393.084532) (xy 38.85527 -393.074402) (xy 38.911004 -393.072365)
			(xy 38.966441 -393.078465) (xy 39.020398 -393.092571) (xy 39.071727 -393.114383) (xy 39.119333 -393.143437)
			(xy 39.162201 -393.179112) (xy 39.199418 -393.220649) (xy 39.230191 -393.267162) (xy 39.253863 -393.317659)
			(xy 39.269931 -393.371066) (xy 39.278051 -393.426242) (xy 39.27856 -393.454128) (xy 39.27837 -393.464542)
			(xy 40.606978 -393.464542) (xy 40.611049 -393.40892) (xy 40.623175 -393.354483) (xy 40.643098 -393.302392)
			(xy 40.670394 -393.253757) (xy 40.70448 -393.209614) (xy 40.744629 -393.170905) (xy 40.789987 -393.138454)
			(xy 40.839587 -393.112953) (xy 40.892371 -393.094946) (xy 40.947214 -393.084816) (xy 41.002948 -393.082779)
			(xy 41.058385 -393.088879) (xy 41.112342 -393.102985) (xy 41.163671 -393.124797) (xy 41.211277 -393.153851)
			(xy 41.254145 -393.189526) (xy 41.291362 -393.231063) (xy 41.322135 -393.277576) (xy 41.340006 -393.315698)
			(xy 46.835312 -393.315698) (xy 46.839383 -393.260076) (xy 46.851509 -393.205639) (xy 46.871432 -393.153548)
			(xy 46.898728 -393.104913) (xy 46.932814 -393.06077) (xy 46.972963 -393.022061) (xy 47.018321 -392.98961)
			(xy 47.067921 -392.964109) (xy 47.120705 -392.946102) (xy 47.175548 -392.935972) (xy 47.231282 -392.933935)
			(xy 47.286719 -392.940035) (xy 47.340676 -392.954141) (xy 47.392005 -392.975953) (xy 47.439611 -393.005007)
			(xy 47.482479 -393.040682) (xy 47.519696 -393.082219) (xy 47.550469 -393.128732) (xy 47.574141 -393.179229)
			(xy 47.590209 -393.232636) (xy 47.598329 -393.287812) (xy 47.598838 -393.315698) (xy 47.598329 -393.343584)
			(xy 47.590209 -393.39876) (xy 47.574141 -393.452167) (xy 47.550469 -393.502664) (xy 47.519696 -393.549177)
			(xy 47.482479 -393.590714) (xy 47.439611 -393.626389) (xy 47.392005 -393.655443) (xy 47.340676 -393.677255)
			(xy 47.286719 -393.691361) (xy 47.231282 -393.697461) (xy 47.175548 -393.695424) (xy 47.120705 -393.685294)
			(xy 47.067921 -393.667287) (xy 47.018321 -393.641786) (xy 46.972963 -393.609335) (xy 46.932814 -393.570626)
			(xy 46.898728 -393.526483) (xy 46.871432 -393.477848) (xy 46.851509 -393.425757) (xy 46.839383 -393.37132)
			(xy 46.835312 -393.315698) (xy 41.340006 -393.315698) (xy 41.345807 -393.328073) (xy 41.361875 -393.38148)
			(xy 41.369995 -393.436656) (xy 41.370504 -393.464542) (xy 41.369995 -393.492428) (xy 41.361875 -393.547604)
			(xy 41.345807 -393.601011) (xy 41.322135 -393.651508) (xy 41.291362 -393.698021) (xy 41.254145 -393.739558)
			(xy 41.211277 -393.775233) (xy 41.163671 -393.804287) (xy 41.112342 -393.826099) (xy 41.058385 -393.840205)
			(xy 41.002948 -393.846305) (xy 40.947214 -393.844268) (xy 40.892371 -393.834138) (xy 40.839587 -393.816131)
			(xy 40.789987 -393.79063) (xy 40.744629 -393.758179) (xy 40.70448 -393.71947) (xy 40.670394 -393.675327)
			(xy 40.643098 -393.626692) (xy 40.623175 -393.574601) (xy 40.611049 -393.520164) (xy 40.606978 -393.464542)
			(xy 39.27837 -393.464542) (xy 39.278051 -393.482014) (xy 39.269931 -393.53719) (xy 39.253863 -393.590597)
			(xy 39.230191 -393.641094) (xy 39.199418 -393.687607) (xy 39.162201 -393.729144) (xy 39.119333 -393.764819)
			(xy 39.071727 -393.793873) (xy 39.020398 -393.815685) (xy 38.966441 -393.829791) (xy 38.911004 -393.835891)
			(xy 38.85527 -393.833854) (xy 38.800427 -393.823724) (xy 38.747643 -393.805717) (xy 38.698043 -393.780216)
			(xy 38.652685 -393.747765) (xy 38.612536 -393.709056) (xy 38.57845 -393.664913) (xy 38.551154 -393.616278)
			(xy 38.531231 -393.564187) (xy 38.519105 -393.50975) (xy 38.515034 -393.454128) (xy 32.611761 -393.454128)
			(xy 32.573245 -393.486181) (xy 32.525639 -393.515235) (xy 32.47431 -393.537047) (xy 32.420353 -393.551153)
			(xy 32.364916 -393.557253) (xy 32.309182 -393.555216) (xy 32.254339 -393.545086) (xy 32.201555 -393.527079)
			(xy 32.151955 -393.501578) (xy 32.106597 -393.469127) (xy 32.066448 -393.430418) (xy 32.032362 -393.386275)
			(xy 32.005066 -393.33764) (xy 31.985143 -393.285549) (xy 31.973017 -393.231112) (xy 31.968946 -393.17549)
			(xy 28.980564 -393.17549) (xy 28.995057 -393.206407) (xy 29.011125 -393.259814) (xy 29.019245 -393.31499)
			(xy 29.019754 -393.342876) (xy 29.019245 -393.370762) (xy 29.011125 -393.425938) (xy 28.995057 -393.479345)
			(xy 28.971385 -393.529842) (xy 28.940612 -393.576355) (xy 28.903395 -393.617892) (xy 28.860527 -393.653567)
			(xy 28.812921 -393.682621) (xy 28.761592 -393.704433) (xy 28.707635 -393.718539) (xy 28.652198 -393.724639)
			(xy 28.596464 -393.722602) (xy 28.541621 -393.712472) (xy 28.488837 -393.694465) (xy 28.439237 -393.668964)
			(xy 28.393879 -393.636513) (xy 28.35373 -393.597804) (xy 28.319644 -393.553661) (xy 28.292348 -393.505026)
			(xy 28.272425 -393.452935) (xy 28.260299 -393.398498) (xy 28.256228 -393.342876) (xy 18.751507 -393.342876)
			(xy 18.786962 -393.382447) (xy 18.817735 -393.42896) (xy 18.841407 -393.479457) (xy 18.857475 -393.532864)
			(xy 18.865595 -393.58804) (xy 18.866104 -393.615926) (xy 18.865595 -393.643812) (xy 18.857475 -393.698988)
			(xy 18.841407 -393.752395) (xy 18.817735 -393.802892) (xy 18.786962 -393.849405) (xy 18.749745 -393.890942)
			(xy 18.706877 -393.926617) (xy 18.659271 -393.955671) (xy 18.607942 -393.977483) (xy 18.553985 -393.991589)
			(xy 18.498548 -393.997689) (xy 18.442814 -393.995652) (xy 18.387971 -393.985522) (xy 18.335187 -393.967515)
			(xy 18.285587 -393.942014) (xy 18.240229 -393.909563) (xy 18.20008 -393.870854) (xy 18.165994 -393.826711)
			(xy 18.138698 -393.778076) (xy 18.118775 -393.725985) (xy 18.106649 -393.671548) (xy 18.102578 -393.615926)
			(xy 8.85444 -393.615926) (xy 8.85444 -394.231876) (xy 14.044928 -394.231876) (xy 14.048999 -394.176254)
			(xy 14.061125 -394.121817) (xy 14.081048 -394.069726) (xy 14.108344 -394.021091) (xy 14.14243 -393.976948)
			(xy 14.182579 -393.938239) (xy 14.227937 -393.905788) (xy 14.277537 -393.880287) (xy 14.330321 -393.86228)
			(xy 14.385164 -393.85215) (xy 14.440898 -393.850113) (xy 14.496335 -393.856213) (xy 14.550292 -393.870319)
			(xy 14.601621 -393.892131) (xy 14.649227 -393.921185) (xy 14.692095 -393.95686) (xy 14.729312 -393.998397)
			(xy 14.760085 -394.04491) (xy 14.783757 -394.095407) (xy 14.799825 -394.148814) (xy 14.807945 -394.20399)
			(xy 14.808454 -394.231876) (xy 14.807945 -394.259762) (xy 14.799825 -394.314938) (xy 14.783757 -394.368345)
			(xy 14.760085 -394.418842) (xy 14.752537 -394.43025) (xy 46.835312 -394.43025) (xy 46.839383 -394.374628)
			(xy 46.851509 -394.320191) (xy 46.871432 -394.2681) (xy 46.898728 -394.219465) (xy 46.932814 -394.175322)
			(xy 46.972963 -394.136613) (xy 47.018321 -394.104162) (xy 47.067921 -394.078661) (xy 47.120705 -394.060654)
			(xy 47.175548 -394.050524) (xy 47.231282 -394.048487) (xy 47.286719 -394.054587) (xy 47.340676 -394.068693)
			(xy 47.392005 -394.090505) (xy 47.439611 -394.119559) (xy 47.482479 -394.155234) (xy 47.519696 -394.196771)
			(xy 47.550469 -394.243284) (xy 47.574141 -394.293781) (xy 47.590209 -394.347188) (xy 47.598329 -394.402364)
			(xy 47.598838 -394.43025) (xy 47.598329 -394.458136) (xy 47.590209 -394.513312) (xy 47.574141 -394.566719)
			(xy 47.550469 -394.617216) (xy 47.519696 -394.663729) (xy 47.482479 -394.705266) (xy 47.439611 -394.740941)
			(xy 47.392005 -394.769995) (xy 47.340676 -394.791807) (xy 47.286719 -394.805913) (xy 47.231282 -394.812013)
			(xy 47.175548 -394.809976) (xy 47.120705 -394.799846) (xy 47.067921 -394.781839) (xy 47.018321 -394.756338)
			(xy 46.972963 -394.723887) (xy 46.932814 -394.685178) (xy 46.898728 -394.641035) (xy 46.871432 -394.5924)
			(xy 46.851509 -394.540309) (xy 46.839383 -394.485872) (xy 46.835312 -394.43025) (xy 14.752537 -394.43025)
			(xy 14.729312 -394.465355) (xy 14.692095 -394.506892) (xy 14.649227 -394.542567) (xy 14.601621 -394.571621)
			(xy 14.550292 -394.593433) (xy 14.496335 -394.607539) (xy 14.440898 -394.613639) (xy 14.385164 -394.611602)
			(xy 14.330321 -394.601472) (xy 14.277537 -394.583465) (xy 14.227937 -394.557964) (xy 14.182579 -394.525513)
			(xy 14.14243 -394.486804) (xy 14.108344 -394.442661) (xy 14.081048 -394.394026) (xy 14.061125 -394.341935)
			(xy 14.048999 -394.287498) (xy 14.044928 -394.231876) (xy 8.85444 -394.231876) (xy 8.85444 -395.247876)
			(xy 14.044928 -395.247876) (xy 14.048999 -395.192254) (xy 14.061125 -395.137817) (xy 14.081048 -395.085726)
			(xy 14.108344 -395.037091) (xy 14.14243 -394.992948) (xy 14.182579 -394.954239) (xy 14.227937 -394.921788)
			(xy 14.277537 -394.896287) (xy 14.330321 -394.87828) (xy 14.385164 -394.86815) (xy 14.440898 -394.866113)
			(xy 14.496335 -394.872213) (xy 14.550292 -394.886319) (xy 14.601621 -394.908131) (xy 14.649227 -394.937185)
			(xy 14.692095 -394.97286) (xy 14.729312 -395.014397) (xy 14.760085 -395.06091) (xy 14.783757 -395.111407)
			(xy 14.799825 -395.164814) (xy 14.807945 -395.21999) (xy 14.808454 -395.247876) (xy 14.807945 -395.275762)
			(xy 14.799825 -395.330938) (xy 14.783757 -395.384345) (xy 14.760085 -395.434842) (xy 14.729312 -395.481355)
			(xy 14.692095 -395.522892) (xy 14.649227 -395.558567) (xy 14.601621 -395.587621) (xy 14.550292 -395.609433)
			(xy 14.496335 -395.623539) (xy 14.440898 -395.629639) (xy 14.385164 -395.627602) (xy 14.330321 -395.617472)
			(xy 14.277537 -395.599465) (xy 14.227937 -395.573964) (xy 14.182579 -395.541513) (xy 14.14243 -395.502804)
			(xy 14.108344 -395.458661) (xy 14.081048 -395.410026) (xy 14.061125 -395.357935) (xy 14.048999 -395.303498)
			(xy 14.044928 -395.247876) (xy 8.85444 -395.247876) (xy 8.85444 -397.477996) (xy 18.90268 -397.477996)
			(xy 18.903124 -397.450625) (xy 18.910944 -397.396444) (xy 18.926437 -397.34394) (xy 18.949285 -397.294193)
			(xy 18.979015 -397.248228) (xy 18.99666 -397.227298) (xy 19.005872 -397.215982) (xy 19.018052 -397.189482)
			(xy 19.02223 -397.160617) (xy 19.018062 -397.131751) (xy 19.005891 -397.105247) (xy 18.99666 -397.093948)
			(xy 18.979008 -397.072993) (xy 18.949266 -397.026978) (xy 18.926417 -396.97718) (xy 18.910933 -396.924623)
			(xy 18.903132 -396.870391) (xy 18.90268 -396.842996) (xy 18.90268 -395.979396) (xy 18.903129 -395.952002)
			(xy 18.910948 -395.897774) (xy 18.926439 -395.845222) (xy 18.949284 -395.795424) (xy 18.979014 -395.749403)
			(xy 18.99666 -395.728444) (xy 19.005924 -395.717167) (xy 19.018098 -395.690653) (xy 19.022265 -395.661777)
			(xy 19.018085 -395.632902) (xy 19.005898 -395.606394) (xy 18.99666 -395.595094) (xy 18.978998 -395.57418)
			(xy 18.949291 -395.528202) (xy 18.92646 -395.47845) (xy 18.910974 -395.425945) (xy 18.903151 -395.371766)
			(xy 18.90268 -395.344396) (xy 18.903166 -395.317145) (xy 18.910922 -395.263197) (xy 18.926277 -395.210902)
			(xy 18.948919 -395.161325) (xy 18.978385 -395.115475) (xy 19.014076 -395.074284) (xy 19.055267 -395.038593)
			(xy 19.101117 -395.009127) (xy 19.150694 -394.986485) (xy 19.202989 -394.97113) (xy 19.256937 -394.963374)
			(xy 19.311439 -394.963374) (xy 19.365387 -394.97113) (xy 19.417682 -394.986485) (xy 19.467259 -395.009127)
			(xy 19.513109 -395.038593) (xy 19.5543 -395.074284) (xy 19.589991 -395.115475) (xy 19.619457 -395.161325)
			(xy 19.642099 -395.210902) (xy 19.657454 -395.263197) (xy 19.66521 -395.317145) (xy 19.665696 -395.344396)
			(xy 19.665229 -395.371766) (xy 19.657411 -395.425945) (xy 19.641923 -395.478448) (xy 19.619081 -395.528195)
			(xy 19.589357 -395.574162) (xy 19.571716 -395.595094) (xy 19.56261 -395.606467) (xy 19.550523 -395.632956)
			(xy 19.546377 -395.661776) (xy 19.550509 -395.690599) (xy 19.554908 -395.70025) (xy 46.835312 -395.70025)
			(xy 46.839383 -395.644628) (xy 46.851509 -395.590191) (xy 46.871432 -395.5381) (xy 46.898728 -395.489465)
			(xy 46.932814 -395.445322) (xy 46.972963 -395.406613) (xy 47.018321 -395.374162) (xy 47.067921 -395.348661)
			(xy 47.120705 -395.330654) (xy 47.175548 -395.320524) (xy 47.231282 -395.318487) (xy 47.286719 -395.324587)
			(xy 47.340676 -395.338693) (xy 47.392005 -395.360505) (xy 47.439611 -395.389559) (xy 47.482479 -395.425234)
			(xy 47.519696 -395.466771) (xy 47.550469 -395.513284) (xy 47.574141 -395.563781) (xy 47.590209 -395.617188)
			(xy 47.598329 -395.672364) (xy 47.598838 -395.70025) (xy 47.598329 -395.728136) (xy 47.590209 -395.783312)
			(xy 47.574141 -395.836719) (xy 47.550469 -395.887216) (xy 47.519696 -395.933729) (xy 47.482479 -395.975266)
			(xy 47.439611 -396.010941) (xy 47.392005 -396.039995) (xy 47.340676 -396.061807) (xy 47.286719 -396.075913)
			(xy 47.231282 -396.082013) (xy 47.175548 -396.079976) (xy 47.120705 -396.069846) (xy 47.067921 -396.051839)
			(xy 47.018321 -396.026338) (xy 46.972963 -395.993887) (xy 46.932814 -395.955178) (xy 46.898728 -395.911035)
			(xy 46.871432 -395.8624) (xy 46.851509 -395.810309) (xy 46.839383 -395.755872) (xy 46.835312 -395.70025)
			(xy 19.554908 -395.70025) (xy 19.562585 -395.717093) (xy 19.571716 -395.728444) (xy 19.589361 -395.749405)
			(xy 19.619105 -395.795418) (xy 19.641955 -395.845215) (xy 19.657441 -395.89777) (xy 19.665243 -395.952001)
			(xy 19.665696 -395.979396) (xy 19.665696 -396.842996) (xy 19.665224 -396.870389) (xy 19.657408 -396.924615)
			(xy 19.641921 -396.977167) (xy 19.619081 -397.026965) (xy 19.589358 -397.072987) (xy 19.571716 -397.093948)
			(xy 19.562558 -397.105282) (xy 19.550477 -397.131786) (xy 19.546342 -397.160617) (xy 19.550487 -397.189448)
			(xy 19.562577 -397.215947) (xy 19.571716 -397.227298) (xy 19.58937 -397.248218) (xy 19.619079 -397.294194)
			(xy 19.641912 -397.343945) (xy 19.6574 -397.396448) (xy 19.665224 -397.450626) (xy 19.665696 -397.477996)
			(xy 19.66521 -397.505247) (xy 19.657454 -397.559195) (xy 19.642099 -397.61149) (xy 19.619457 -397.661067)
			(xy 19.589991 -397.706917) (xy 19.5543 -397.748108) (xy 19.513109 -397.783799) (xy 19.467259 -397.813265)
			(xy 19.417682 -397.835907) (xy 19.365387 -397.851262) (xy 19.311439 -397.859018) (xy 19.256937 -397.859018)
			(xy 19.202989 -397.851262) (xy 19.150694 -397.835907) (xy 19.101117 -397.813265) (xy 19.055267 -397.783799)
			(xy 19.014076 -397.748108) (xy 18.978385 -397.706917) (xy 18.948919 -397.661067) (xy 18.926277 -397.61149)
			(xy 18.910922 -397.559195) (xy 18.903166 -397.505247) (xy 18.90268 -397.477996) (xy 8.85444 -397.477996)
			(xy 8.85444 -398.241012) (xy 24.946356 -398.241012) (xy 24.946842 -398.213137) (xy 24.954955 -398.15798)
			(xy 24.971011 -398.104592) (xy 24.994667 -398.054109) (xy 25.02542 -398.007608) (xy 25.043638 -397.986504)
			(xy 25.053055 -397.975318) (xy 25.065605 -397.948919) (xy 25.070167 -397.920047) (xy 25.066367 -397.891065)
			(xy 25.054518 -397.864345) (xy 25.045416 -397.8529) (xy 25.028431 -397.832095) (xy 24.999802 -397.786655)
			(xy 24.977827 -397.737649) (xy 24.96294 -397.686046) (xy 24.955436 -397.632866) (xy 24.954992 -397.606012)
			(xy 24.954992 -396.742412) (xy 24.955447 -396.715018) (xy 24.963264 -396.660791) (xy 24.978754 -396.608238)
			(xy 25.001598 -396.55844) (xy 25.031327 -396.512419) (xy 25.048972 -396.49146) (xy 25.05822 -396.480171)
			(xy 25.070394 -396.453661) (xy 25.074564 -396.424789) (xy 25.070388 -396.395917) (xy 25.058207 -396.36941)
			(xy 25.048972 -396.35811) (xy 25.03132 -396.337189) (xy 25.001611 -396.291212) (xy 24.978778 -396.241462)
			(xy 24.96329 -396.188959) (xy 24.955465 -396.134782) (xy 24.954992 -396.107412) (xy 24.955478 -396.080161)
			(xy 24.963234 -396.026213) (xy 24.978589 -395.973918) (xy 25.001231 -395.924341) (xy 25.030697 -395.878491)
			(xy 25.066388 -395.8373) (xy 25.107579 -395.801609) (xy 25.153429 -395.772143) (xy 25.203006 -395.749501)
			(xy 25.255301 -395.734146) (xy 25.309249 -395.72639) (xy 25.363751 -395.72639) (xy 25.417699 -395.734146)
			(xy 25.469994 -395.749501) (xy 25.519571 -395.772143) (xy 25.565421 -395.801609) (xy 25.606612 -395.8373)
			(xy 25.642303 -395.878491) (xy 25.671769 -395.924341) (xy 25.694411 -395.973918) (xy 25.709766 -396.026213)
			(xy 25.717522 -396.080161) (xy 25.718008 -396.107412) (xy 25.717547 -396.134782) (xy 25.709728 -396.188962)
			(xy 25.694237 -396.241465) (xy 25.671395 -396.291211) (xy 25.641669 -396.337178) (xy 25.624028 -396.35811)
			(xy 25.614906 -396.369471) (xy 25.60514 -396.390876) (xy 28.256228 -396.390876) (xy 28.260299 -396.335254)
			(xy 28.272425 -396.280817) (xy 28.292348 -396.228726) (xy 28.319644 -396.180091) (xy 28.35373 -396.135948)
			(xy 28.393879 -396.097239) (xy 28.439237 -396.064788) (xy 28.488837 -396.039287) (xy 28.541621 -396.02128)
			(xy 28.596464 -396.01115) (xy 28.652198 -396.009113) (xy 28.707635 -396.015213) (xy 28.761592 -396.029319)
			(xy 28.812921 -396.051131) (xy 28.860527 -396.080185) (xy 28.903395 -396.11586) (xy 28.940612 -396.157397)
			(xy 28.971385 -396.20391) (xy 28.995057 -396.254407) (xy 29.001115 -396.274544) (xy 35.204398 -396.274544)
			(xy 35.208469 -396.218922) (xy 35.220595 -396.164485) (xy 35.240518 -396.112394) (xy 35.267814 -396.063759)
			(xy 35.3019 -396.019616) (xy 35.342049 -395.980907) (xy 35.387407 -395.948456) (xy 35.437007 -395.922955)
			(xy 35.489791 -395.904948) (xy 35.544634 -395.894818) (xy 35.600368 -395.892781) (xy 35.655805 -395.898881)
			(xy 35.709762 -395.912987) (xy 35.761091 -395.934799) (xy 35.808697 -395.963853) (xy 35.851565 -395.999528)
			(xy 35.888782 -396.041065) (xy 35.919555 -396.087578) (xy 35.943227 -396.138075) (xy 35.959295 -396.191482)
			(xy 35.967415 -396.246658) (xy 35.967924 -396.274544) (xy 35.967415 -396.30243) (xy 35.959295 -396.357606)
			(xy 35.943227 -396.411013) (xy 35.919555 -396.46151) (xy 35.888782 -396.508023) (xy 35.851565 -396.54956)
			(xy 35.808697 -396.585235) (xy 35.761091 -396.614289) (xy 35.709762 -396.636101) (xy 35.655805 -396.650207)
			(xy 35.600368 -396.656307) (xy 35.544634 -396.65427) (xy 35.489791 -396.64414) (xy 35.437007 -396.626133)
			(xy 35.387407 -396.600632) (xy 35.342049 -396.568181) (xy 35.3019 -396.529472) (xy 35.267814 -396.485329)
			(xy 35.240518 -396.436694) (xy 35.220595 -396.384603) (xy 35.208469 -396.330166) (xy 35.204398 -396.274544)
			(xy 29.001115 -396.274544) (xy 29.011125 -396.307814) (xy 29.019245 -396.36299) (xy 29.019754 -396.390876)
			(xy 29.019245 -396.418762) (xy 29.011125 -396.473938) (xy 28.995057 -396.527345) (xy 28.971385 -396.577842)
			(xy 28.940612 -396.624355) (xy 28.903395 -396.665892) (xy 28.860527 -396.701567) (xy 28.812921 -396.730621)
			(xy 28.761592 -396.752433) (xy 28.707635 -396.766539) (xy 28.652198 -396.772639) (xy 28.596464 -396.770602)
			(xy 28.541621 -396.760472) (xy 28.488837 -396.742465) (xy 28.439237 -396.716964) (xy 28.393879 -396.684513)
			(xy 28.35373 -396.645804) (xy 28.319644 -396.601661) (xy 28.292348 -396.553026) (xy 28.272425 -396.500935)
			(xy 28.260299 -396.446498) (xy 28.256228 -396.390876) (xy 25.60514 -396.390876) (xy 25.602819 -396.395964)
			(xy 25.598676 -396.424789) (xy 25.602812 -396.453614) (xy 25.614894 -396.48011) (xy 25.624028 -396.49146)
			(xy 25.641682 -396.512414) (xy 25.671424 -396.558428) (xy 25.694273 -396.608227) (xy 25.709756 -396.660784)
			(xy 25.717556 -396.715016) (xy 25.718008 -396.742412) (xy 25.718008 -397.406876) (xy 28.256228 -397.406876)
			(xy 28.260299 -397.351254) (xy 28.272425 -397.296817) (xy 28.292348 -397.244726) (xy 28.319644 -397.196091)
			(xy 28.35373 -397.151948) (xy 28.393879 -397.113239) (xy 28.439237 -397.080788) (xy 28.488837 -397.055287)
			(xy 28.541621 -397.03728) (xy 28.596464 -397.02715) (xy 28.652198 -397.025113) (xy 28.707635 -397.031213)
			(xy 28.751345 -397.04264) (xy 32.554162 -397.04264) (xy 32.558233 -396.987018) (xy 32.570359 -396.932581)
			(xy 32.590282 -396.88049) (xy 32.617578 -396.831855) (xy 32.651664 -396.787712) (xy 32.691813 -396.749003)
			(xy 32.737171 -396.716552) (xy 32.786771 -396.691051) (xy 32.839555 -396.673044) (xy 32.894398 -396.662914)
			(xy 32.950132 -396.660877) (xy 33.005569 -396.666977) (xy 33.059526 -396.681083) (xy 33.110855 -396.702895)
			(xy 33.158461 -396.731949) (xy 33.201329 -396.767624) (xy 33.238546 -396.809161) (xy 33.269319 -396.855674)
			(xy 33.292991 -396.906171) (xy 33.309059 -396.959578) (xy 33.317179 -397.014754) (xy 33.317688 -397.04264)
			(xy 33.317179 -397.070526) (xy 33.309059 -397.125702) (xy 33.292991 -397.179109) (xy 33.269319 -397.229606)
			(xy 33.238546 -397.276119) (xy 33.201329 -397.317656) (xy 33.158461 -397.353331) (xy 33.110855 -397.382385)
			(xy 33.059526 -397.404197) (xy 33.005569 -397.418303) (xy 32.950132 -397.424403) (xy 32.894398 -397.422366)
			(xy 32.839555 -397.412236) (xy 32.786771 -397.394229) (xy 32.737171 -397.368728) (xy 32.691813 -397.336277)
			(xy 32.651664 -397.297568) (xy 32.617578 -397.253425) (xy 32.590282 -397.20479) (xy 32.570359 -397.152699)
			(xy 32.558233 -397.098262) (xy 32.554162 -397.04264) (xy 28.751345 -397.04264) (xy 28.761592 -397.045319)
			(xy 28.812921 -397.067131) (xy 28.860527 -397.096185) (xy 28.903395 -397.13186) (xy 28.940612 -397.173397)
			(xy 28.971385 -397.21991) (xy 28.995057 -397.270407) (xy 29.011125 -397.323814) (xy 29.019245 -397.37899)
			(xy 29.019754 -397.406876) (xy 29.019245 -397.434762) (xy 29.011125 -397.489938) (xy 28.995057 -397.543345)
			(xy 28.971385 -397.593842) (xy 28.940612 -397.640355) (xy 28.903395 -397.681892) (xy 28.860527 -397.717567)
			(xy 28.812921 -397.746621) (xy 28.761592 -397.768433) (xy 28.707635 -397.782539) (xy 28.652198 -397.788639)
			(xy 28.596464 -397.786602) (xy 28.541621 -397.776472) (xy 28.488837 -397.758465) (xy 28.439237 -397.732964)
			(xy 28.393879 -397.700513) (xy 28.35373 -397.661804) (xy 28.319644 -397.617661) (xy 28.292348 -397.569026)
			(xy 28.272425 -397.516935) (xy 28.260299 -397.462498) (xy 28.256228 -397.406876) (xy 25.718008 -397.406876)
			(xy 25.718008 -397.606012) (xy 25.71756 -397.633915) (xy 25.70947 -397.68913) (xy 25.693422 -397.742577)
			(xy 25.669756 -397.793115) (xy 25.63898 -397.839665) (xy 25.620726 -397.860774) (xy 25.611333 -397.871977)
			(xy 25.598785 -397.898371) (xy 25.59422 -397.927236) (xy 25.598013 -397.956213) (xy 25.609852 -397.982932)
			(xy 25.618948 -397.994378) (xy 25.635949 -398.015138) (xy 25.664554 -398.060538) (xy 25.686515 -398.109498)
			(xy 25.701401 -398.161052) (xy 25.708917 -398.214182) (xy 25.709372 -398.241012) (xy 25.708886 -398.268263)
			(xy 25.70113 -398.322211) (xy 25.685775 -398.374506) (xy 25.663133 -398.424083) (xy 25.633667 -398.469933)
			(xy 25.597976 -398.511124) (xy 25.556785 -398.546815) (xy 25.510935 -398.576281) (xy 25.461358 -398.598923)
			(xy 25.409063 -398.614278) (xy 25.355115 -398.622034) (xy 25.300613 -398.622034) (xy 25.246665 -398.614278)
			(xy 25.19437 -398.598923) (xy 25.144793 -398.576281) (xy 25.098943 -398.546815) (xy 25.057752 -398.511124)
			(xy 25.022061 -398.469933) (xy 24.992595 -398.424083) (xy 24.969953 -398.374506) (xy 24.954598 -398.322211)
			(xy 24.946842 -398.268263) (xy 24.946356 -398.241012) (xy 8.85444 -398.241012) (xy 8.85444 -398.782032)
			(xy 18.269458 -398.782032) (xy 18.269944 -398.754781) (xy 18.2777 -398.700833) (xy 18.293055 -398.648538)
			(xy 18.315697 -398.598961) (xy 18.345163 -398.553111) (xy 18.380854 -398.51192) (xy 18.422045 -398.476229)
			(xy 18.467895 -398.446763) (xy 18.517472 -398.424121) (xy 18.569767 -398.408766) (xy 18.623715 -398.40101)
			(xy 18.678217 -398.40101) (xy 18.732165 -398.408766) (xy 18.78446 -398.424121) (xy 18.834037 -398.446763)
			(xy 18.879887 -398.476229) (xy 18.921078 -398.51192) (xy 18.956769 -398.553111) (xy 18.986235 -398.598961)
			(xy 19.008877 -398.648538) (xy 19.024232 -398.700833) (xy 19.031988 -398.754781) (xy 19.032474 -398.782032)
			(xy 19.031895 -398.812337) (xy 19.022331 -398.872186) (xy 19.013424 -398.901158) (xy 19.009518 -398.91433)
			(xy 19.0082 -398.941765) (xy 19.014244 -398.968558) (xy 19.027213 -398.992769) (xy 19.046168 -399.012647)
			(xy 19.069735 -399.026752) (xy 19.096211 -399.034063) (xy 19.109944 -399.034508) (xy 19.458432 -399.034508)
			(xy 19.472162 -399.034082) (xy 19.498626 -399.026757) (xy 19.522182 -399.012644) (xy 19.541125 -398.992765)
			(xy 19.554086 -398.968556) (xy 19.560128 -398.94177) (xy 19.558813 -398.914341) (xy 19.554952 -398.901158)
			(xy 19.546049 -398.872185) (xy 19.536483 -398.812336) (xy 19.535902 -398.782032) (xy 19.536388 -398.754781)
			(xy 19.544144 -398.700833) (xy 19.559499 -398.648538) (xy 19.582141 -398.598961) (xy 19.611607 -398.553111)
			(xy 19.647298 -398.51192) (xy 19.688489 -398.476229) (xy 19.734339 -398.446763) (xy 19.783916 -398.424121)
			(xy 19.836211 -398.408766) (xy 19.890159 -398.40101) (xy 19.944661 -398.40101) (xy 19.998609 -398.408766)
			(xy 20.050904 -398.424121) (xy 20.100481 -398.446763) (xy 20.146331 -398.476229) (xy 20.187522 -398.51192)
			(xy 20.223213 -398.553111) (xy 20.252679 -398.598961) (xy 20.275321 -398.648538) (xy 20.290676 -398.700833)
			(xy 20.298432 -398.754781) (xy 20.298918 -398.782032) (xy 20.298336 -398.811171) (xy 20.289474 -398.868772)
			(xy 20.271961 -398.924356) (xy 20.246204 -398.976634) (xy 20.212801 -399.024389) (xy 20.172528 -399.066514)
			(xy 20.126321 -399.102028) (xy 20.101052 -399.11655) (xy 20.08779 -399.124479) (xy 20.066418 -399.146774)
			(xy 20.052662 -399.174425) (xy 20.047774 -399.20492) (xy 20.052197 -399.235486) (xy 20.05838 -399.249646)
			(xy 20.070423 -399.275708) (xy 20.075884 -399.293334) (xy 36.58108 -399.293334) (xy 36.581607 -399.264285)
			(xy 36.590404 -399.206857) (xy 36.607816 -399.15143) (xy 36.633438 -399.099287) (xy 36.666676 -399.051637)
			(xy 36.706762 -399.009583) (xy 36.752766 -398.974101) (xy 36.77793 -398.959578) (xy 36.791213 -398.951644)
			(xy 36.812551 -398.929256) (xy 36.826221 -398.901514) (xy 36.830973 -398.870954) (xy 36.826372 -398.84037)
			(xy 36.820094 -398.826228) (xy 36.807968 -398.800101) (xy 36.790865 -398.7451) (xy 36.782242 -398.68815)
			(xy 36.78174 -398.65935) (xy 36.782177 -398.632091) (xy 36.789939 -398.578128) (xy 36.805298 -398.525817)
			(xy 36.827942 -398.476224) (xy 36.857409 -398.430355) (xy 36.893102 -398.389145) (xy 36.934293 -398.353431)
			(xy 36.980146 -398.323939) (xy 37.029728 -398.301269) (xy 37.08203 -398.285882) (xy 37.135989 -398.278092)
			(xy 37.163248 -398.277588) (xy 38.026848 -398.277588) (xy 38.054113 -398.278011) (xy 38.108088 -398.285781)
			(xy 38.160407 -398.301156) (xy 38.210004 -398.323822) (xy 38.255869 -398.353318) (xy 38.297067 -398.389044)
			(xy 38.33276 -398.43027) (xy 38.362221 -398.476158) (xy 38.384849 -398.525773) (xy 38.400182 -398.578104)
			(xy 38.40791 -398.632084) (xy 38.408356 -398.65935) (xy 38.407848 -398.688148) (xy 38.3992 -398.745091)
			(xy 38.382108 -398.800093) (xy 38.370002 -398.826228) (xy 38.363697 -398.840354) (xy 38.359127 -398.870937)
			(xy 38.363898 -398.901489) (xy 38.377573 -398.929223) (xy 38.398906 -398.951608) (xy 38.412166 -398.959578)
			(xy 38.437306 -398.974135) (xy 38.483293 -399.009626) (xy 38.523367 -399.05168) (xy 38.5566 -399.099325)
			(xy 38.569936 -399.126456) (xy 40.03116 -399.126456) (xy 40.035231 -399.070834) (xy 40.047357 -399.016397)
			(xy 40.06728 -398.964306) (xy 40.094576 -398.915671) (xy 40.128662 -398.871528) (xy 40.168811 -398.832819)
			(xy 40.214169 -398.800368) (xy 40.263769 -398.774867) (xy 40.316553 -398.75686) (xy 40.371396 -398.74673)
			(xy 40.42713 -398.744693) (xy 40.482567 -398.750793) (xy 40.536524 -398.764899) (xy 40.587853 -398.786711)
			(xy 40.635459 -398.815765) (xy 40.678327 -398.85144) (xy 40.715544 -398.892977) (xy 40.746317 -398.93949)
			(xy 40.769989 -398.989987) (xy 40.786057 -399.043394) (xy 40.794177 -399.09857) (xy 40.794686 -399.126456)
			(xy 40.794177 -399.154342) (xy 40.786057 -399.209518) (xy 40.769989 -399.262925) (xy 40.746317 -399.313422)
			(xy 40.715544 -399.359935) (xy 40.678327 -399.401472) (xy 40.635459 -399.437147) (xy 40.587853 -399.466201)
			(xy 40.536524 -399.488013) (xy 40.482567 -399.502119) (xy 40.42713 -399.508219) (xy 40.371396 -399.506182)
			(xy 40.316553 -399.496052) (xy 40.263769 -399.478045) (xy 40.214169 -399.452544) (xy 40.168811 -399.420093)
			(xy 40.128662 -399.381384) (xy 40.094576 -399.337241) (xy 40.06728 -399.288606) (xy 40.047357 -399.236515)
			(xy 40.035231 -399.182078) (xy 40.03116 -399.126456) (xy 38.569936 -399.126456) (xy 38.582225 -399.151457)
			(xy 38.599648 -399.206873) (xy 38.608466 -399.264289) (xy 38.609016 -399.293334) (xy 38.60853 -399.320585)
			(xy 38.600774 -399.374533) (xy 38.585419 -399.426828) (xy 38.562777 -399.476405) (xy 38.533311 -399.522255)
			(xy 38.49762 -399.563446) (xy 38.456429 -399.599137) (xy 38.410579 -399.628603) (xy 38.361002 -399.651245)
			(xy 38.308707 -399.6666) (xy 38.254759 -399.674356) (xy 38.200257 -399.674356) (xy 38.146309 -399.6666)
			(xy 38.094014 -399.651245) (xy 38.044437 -399.628603) (xy 37.998587 -399.599137) (xy 37.957396 -399.563446)
			(xy 37.921705 -399.522255) (xy 37.892239 -399.476405) (xy 37.869597 -399.426828) (xy 37.854242 -399.374533)
			(xy 37.846486 -399.320585) (xy 37.846 -399.293334) (xy 37.846572 -399.263029) (xy 37.856141 -399.20318)
			(xy 37.86505 -399.174208) (xy 37.868884 -399.161037) (xy 37.870171 -399.133646) (xy 37.864112 -399.106904)
			(xy 37.851146 -399.082742) (xy 37.832211 -399.06291) (xy 37.808675 -399.04884) (xy 37.782241 -399.041551)
			(xy 37.76853 -399.041112) (xy 37.421566 -399.041112) (xy 37.407859 -399.041504) (xy 37.38144 -399.048831)
			(xy 37.357923 -399.062921) (xy 37.339 -399.082759) (xy 37.326036 -399.106916) (xy 37.319964 -399.13365)
			(xy 37.321222 -399.161037) (xy 37.325046 -399.174208) (xy 37.333941 -399.203183) (xy 37.343512 -399.26303)
			(xy 37.344096 -399.293334) (xy 37.34361 -399.320585) (xy 37.335854 -399.374533) (xy 37.320499 -399.426828)
			(xy 37.297857 -399.476405) (xy 37.268391 -399.522255) (xy 37.2327 -399.563446) (xy 37.191509 -399.599137)
			(xy 37.145659 -399.628603) (xy 37.096082 -399.651245) (xy 37.043787 -399.6666) (xy 36.989839 -399.674356)
			(xy 36.935337 -399.674356) (xy 36.881389 -399.6666) (xy 36.829094 -399.651245) (xy 36.779517 -399.628603)
			(xy 36.733667 -399.599137) (xy 36.692476 -399.563446) (xy 36.656785 -399.522255) (xy 36.627319 -399.476405)
			(xy 36.604677 -399.426828) (xy 36.589322 -399.374533) (xy 36.581566 -399.320585) (xy 36.58108 -399.293334)
			(xy 20.075884 -399.293334) (xy 20.087414 -399.330545) (xy 20.095983 -399.387311) (xy 20.09648 -399.416016)
			(xy 20.09606 -399.443271) (xy 20.0883 -399.497225) (xy 20.072941 -399.549525) (xy 20.050294 -399.599107)
			(xy 20.020822 -399.644962) (xy 19.985124 -399.686155) (xy 19.943926 -399.721848) (xy 19.898068 -399.751315)
			(xy 19.848484 -399.773956) (xy 19.796181 -399.789309) (xy 19.742227 -399.797063) (xy 19.714972 -399.797524)
			(xy 18.851372 -399.797524) (xy 18.824121 -399.797048) (xy 18.770174 -399.789288) (xy 18.71788 -399.773931)
			(xy 18.668303 -399.751287) (xy 18.622454 -399.72182) (xy 18.581264 -399.686127) (xy 18.545573 -399.644937)
			(xy 18.516107 -399.599086) (xy 18.493465 -399.549509) (xy 18.478109 -399.497215) (xy 18.470351 -399.443267)
			(xy 18.469864 -399.416016) (xy 18.470394 -399.387219) (xy 18.479032 -399.330276) (xy 18.496116 -399.275274)
			(xy 18.508218 -399.249138) (xy 18.514442 -399.234981) (xy 18.519025 -399.204414) (xy 18.514272 -399.173874)
			(xy 18.500616 -399.146146) (xy 18.479304 -399.12376) (xy 18.466054 -399.115788) (xy 18.440928 -399.101229)
			(xy 18.394995 -399.065707) (xy 18.354972 -399.023636) (xy 18.321785 -398.975988) (xy 18.296199 -398.923862)
			(xy 18.278804 -398.868461) (xy 18.270003 -398.811065) (xy 18.269458 -398.782032) (xy 8.85444 -398.782032)
			(xy 8.85444 -399.974816) (xy 25.133046 -399.974816) (xy 25.133532 -399.947565) (xy 25.141288 -399.893617)
			(xy 25.156643 -399.841322) (xy 25.179285 -399.791745) (xy 25.208751 -399.745895) (xy 25.244442 -399.704704)
			(xy 25.285633 -399.669013) (xy 25.331483 -399.639547) (xy 25.38106 -399.616905) (xy 25.433355 -399.60155)
			(xy 25.487303 -399.593794) (xy 25.541805 -399.593794) (xy 25.595753 -399.60155) (xy 25.648048 -399.616905)
			(xy 25.697625 -399.639547) (xy 25.743475 -399.669013) (xy 25.784666 -399.704704) (xy 25.820357 -399.745895)
			(xy 25.849823 -399.791745) (xy 25.872465 -399.841322) (xy 25.88782 -399.893617) (xy 25.895576 -399.947565)
			(xy 25.896062 -399.974816) (xy 25.8953 -399.997422) (xy 25.895165 -400.008213) (xy 25.902896 -400.028344)
			(xy 25.918185 -400.043552) (xy 25.938356 -400.051177) (xy 25.949148 -400.051016) (xy 25.971754 -400.050508)
			(xy 26.835354 -400.050508) (xy 26.85796 -400.051016) (xy 26.868747 -400.051153) (xy 26.888907 -400.043529)
			(xy 26.904186 -400.028329) (xy 26.911912 -400.008209) (xy 26.911808 -399.997422) (xy 26.911046 -399.974816)
			(xy 26.911532 -399.947565) (xy 26.919288 -399.893617) (xy 26.934643 -399.841322) (xy 26.957285 -399.791745)
			(xy 26.986751 -399.745895) (xy 27.022442 -399.704704) (xy 27.063633 -399.669013) (xy 27.109483 -399.639547)
			(xy 27.15906 -399.616905) (xy 27.211355 -399.60155) (xy 27.265303 -399.593794) (xy 27.319805 -399.593794)
			(xy 27.373753 -399.60155) (xy 27.426048 -399.616905) (xy 27.475625 -399.639547) (xy 27.521475 -399.669013)
			(xy 27.562666 -399.704704) (xy 27.598357 -399.745895) (xy 27.627823 -399.791745) (xy 27.650465 -399.841322)
			(xy 27.66582 -399.893617) (xy 27.673576 -399.947565) (xy 27.674062 -399.974816) (xy 27.673509 -400.003792)
			(xy 27.664755 -400.061079) (xy 27.647437 -400.116382) (xy 27.621952 -400.16843) (xy 27.588887 -400.216023)
			(xy 27.549004 -400.258067) (xy 27.503219 -400.293594) (xy 27.452587 -400.321787) (xy 27.398273 -400.341996)
			(xy 27.341528 -400.353757) (xy 27.31262 -400.355816) (xy 27.297748 -400.357132) (xy 27.269664 -400.367216)
			(xy 27.245686 -400.384978) (xy 27.227856 -400.408904) (xy 27.21769 -400.436959) (xy 27.216354 -400.451828)
			(xy 27.214264 -400.480744) (xy 27.202528 -400.537514) (xy 27.182339 -400.591855) (xy 27.154161 -400.642516)
			(xy 27.118643 -400.688332) (xy 27.076603 -400.728246) (xy 27.029009 -400.761342) (xy 26.976955 -400.786856)
			(xy 26.921641 -400.804202) (xy 26.864339 -400.81298) (xy 26.835354 -400.813524) (xy 25.971754 -400.813524)
			(xy 25.942768 -400.812926) (xy 25.885464 -400.804163) (xy 25.830144 -400.786829) (xy 25.778085 -400.761325)
			(xy 25.730484 -400.728237) (xy 25.688438 -400.688328) (xy 25.652914 -400.642516) (xy 25.624731 -400.591857)
			(xy 25.604538 -400.537517) (xy 25.5928 -400.480746) (xy 25.590754 -400.451828) (xy 25.58934 -400.436969)
			(xy 25.579186 -400.408923) (xy 25.561374 -400.384998) (xy 25.537417 -400.367228) (xy 25.509353 -400.357124)
			(xy 25.494488 -400.355816) (xy 25.465581 -400.353758) (xy 25.408839 -400.341988) (xy 25.354529 -400.321772)
			(xy 25.303901 -400.293576) (xy 25.258119 -400.258049) (xy 25.218236 -400.216006) (xy 25.185169 -400.168416)
			(xy 25.159679 -400.116374) (xy 25.142351 -400.061074) (xy 25.133586 -400.003791) (xy 25.133046 -399.974816)
			(xy 8.85444 -399.974816) (xy 8.85444 -400.814032) (xy 20.966174 -400.814032) (xy 20.970245 -400.75841)
			(xy 20.982371 -400.703973) (xy 21.002294 -400.651882) (xy 21.02959 -400.603247) (xy 21.063676 -400.559104)
			(xy 21.103825 -400.520395) (xy 21.149183 -400.487944) (xy 21.198783 -400.462443) (xy 21.251567 -400.444436)
			(xy 21.30641 -400.434306) (xy 21.362144 -400.432269) (xy 21.417581 -400.438369) (xy 21.471538 -400.452475)
			(xy 21.522867 -400.474287) (xy 21.570473 -400.503341) (xy 21.613341 -400.539016) (xy 21.650558 -400.580553)
			(xy 21.681331 -400.627066) (xy 21.705003 -400.677563) (xy 21.709686 -400.693128) (xy 24.065736 -400.693128)
			(xy 24.069807 -400.637506) (xy 24.081933 -400.583069) (xy 24.101856 -400.530978) (xy 24.129152 -400.482343)
			(xy 24.163238 -400.4382) (xy 24.203387 -400.399491) (xy 24.248745 -400.36704) (xy 24.298345 -400.341539)
			(xy 24.351129 -400.323532) (xy 24.405972 -400.313402) (xy 24.461706 -400.311365) (xy 24.517143 -400.317465)
			(xy 24.5711 -400.331571) (xy 24.622429 -400.353383) (xy 24.670035 -400.382437) (xy 24.712903 -400.418112)
			(xy 24.75012 -400.459649) (xy 24.780893 -400.506162) (xy 24.804565 -400.556659) (xy 24.820633 -400.610066)
			(xy 24.828753 -400.665242) (xy 24.829262 -400.693128) (xy 24.828753 -400.721014) (xy 24.820633 -400.77619)
			(xy 24.804565 -400.829597) (xy 24.780893 -400.880094) (xy 24.75012 -400.926607) (xy 24.712903 -400.968144)
			(xy 24.670035 -401.003819) (xy 24.622429 -401.032873) (xy 24.5711 -401.054685) (xy 24.517143 -401.068791)
			(xy 24.461706 -401.074891) (xy 24.405972 -401.072854) (xy 24.351129 -401.062724) (xy 24.298345 -401.044717)
			(xy 24.248745 -401.019216) (xy 24.203387 -400.986765) (xy 24.163238 -400.948056) (xy 24.129152 -400.903913)
			(xy 24.101856 -400.855278) (xy 24.081933 -400.803187) (xy 24.069807 -400.74875) (xy 24.065736 -400.693128)
			(xy 21.709686 -400.693128) (xy 21.721071 -400.73097) (xy 21.729191 -400.786146) (xy 21.7297 -400.814032)
			(xy 21.729191 -400.841918) (xy 21.721071 -400.897094) (xy 21.705003 -400.950501) (xy 21.681331 -401.000998)
			(xy 21.650558 -401.047511) (xy 21.613341 -401.089048) (xy 21.570473 -401.124723) (xy 21.522867 -401.153777)
			(xy 21.471538 -401.175589) (xy 21.417581 -401.189695) (xy 21.362144 -401.195795) (xy 21.30641 -401.193758)
			(xy 21.251567 -401.183628) (xy 21.198783 -401.165621) (xy 21.149183 -401.14012) (xy 21.103825 -401.107669)
			(xy 21.063676 -401.06896) (xy 21.02959 -401.024817) (xy 21.002294 -400.976182) (xy 20.982371 -400.924091)
			(xy 20.970245 -400.869654) (xy 20.966174 -400.814032) (xy 8.85444 -400.814032) (xy 8.85444 -402.421598)
			(xy 26.00909 -402.421598) (xy 26.013161 -402.365976) (xy 26.025287 -402.311539) (xy 26.04521 -402.259448)
			(xy 26.072506 -402.210813) (xy 26.106592 -402.16667) (xy 26.146741 -402.127961) (xy 26.192099 -402.09551)
			(xy 26.241699 -402.070009) (xy 26.294483 -402.052002) (xy 26.349326 -402.041872) (xy 26.40506 -402.039835)
			(xy 26.460497 -402.045935) (xy 26.514454 -402.060041) (xy 26.565783 -402.081853) (xy 26.613389 -402.110907)
			(xy 26.656257 -402.146582) (xy 26.693474 -402.188119) (xy 26.724247 -402.234632) (xy 26.747919 -402.285129)
			(xy 26.763987 -402.338536) (xy 26.772107 -402.393712) (xy 26.772616 -402.421598) (xy 26.772107 -402.449484)
			(xy 26.763987 -402.50466) (xy 26.747919 -402.558067) (xy 26.724247 -402.608564) (xy 26.693474 -402.655077)
			(xy 26.656257 -402.696614) (xy 26.613389 -402.732289) (xy 26.565783 -402.761343) (xy 26.514454 -402.783155)
			(xy 26.460497 -402.797261) (xy 26.40506 -402.803361) (xy 26.349326 -402.801324) (xy 26.294483 -402.791194)
			(xy 26.241699 -402.773187) (xy 26.192099 -402.747686) (xy 26.146741 -402.715235) (xy 26.106592 -402.676526)
			(xy 26.072506 -402.632383) (xy 26.04521 -402.583748) (xy 26.025287 -402.531657) (xy 26.013161 -402.47722)
			(xy 26.00909 -402.421598) (xy 8.85444 -402.421598) (xy 8.85444 -402.806408) (xy 22.659084 -402.806408)
			(xy 22.663155 -402.750786) (xy 22.675281 -402.696349) (xy 22.695204 -402.644258) (xy 22.7225 -402.595623)
			(xy 22.756586 -402.55148) (xy 22.796735 -402.512771) (xy 22.842093 -402.48032) (xy 22.891693 -402.454819)
			(xy 22.944477 -402.436812) (xy 22.99932 -402.426682) (xy 23.055054 -402.424645) (xy 23.110491 -402.430745)
			(xy 23.164448 -402.444851) (xy 23.215777 -402.466663) (xy 23.263383 -402.495717) (xy 23.306251 -402.531392)
			(xy 23.343468 -402.572929) (xy 23.374241 -402.619442) (xy 23.397913 -402.669939) (xy 23.413981 -402.723346)
			(xy 23.422101 -402.778522) (xy 23.42261 -402.806408) (xy 23.422101 -402.834294) (xy 23.413981 -402.88947)
			(xy 23.397913 -402.942877) (xy 23.374241 -402.993374) (xy 23.343468 -403.039887) (xy 23.306251 -403.081424)
			(xy 23.263383 -403.117099) (xy 23.215777 -403.146153) (xy 23.164448 -403.167965) (xy 23.110491 -403.182071)
			(xy 23.055054 -403.188171) (xy 22.99932 -403.186134) (xy 22.944477 -403.176004) (xy 22.891693 -403.157997)
			(xy 22.842093 -403.132496) (xy 22.796735 -403.100045) (xy 22.756586 -403.061336) (xy 22.7225 -403.017193)
			(xy 22.695204 -402.968558) (xy 22.675281 -402.916467) (xy 22.663155 -402.86203) (xy 22.659084 -402.806408)
			(xy 8.85444 -402.806408) (xy 8.85444 -403.822408) (xy 22.659084 -403.822408) (xy 22.663155 -403.766786)
			(xy 22.675281 -403.712349) (xy 22.695204 -403.660258) (xy 22.7225 -403.611623) (xy 22.756586 -403.56748)
			(xy 22.796735 -403.528771) (xy 22.842093 -403.49632) (xy 22.891693 -403.470819) (xy 22.944477 -403.452812)
			(xy 22.99932 -403.442682) (xy 23.055054 -403.440645) (xy 23.110491 -403.446745) (xy 23.164448 -403.460851)
			(xy 23.215777 -403.482663) (xy 23.263383 -403.511717) (xy 23.306251 -403.547392) (xy 23.343468 -403.588929)
			(xy 23.374241 -403.635442) (xy 23.397913 -403.685939) (xy 23.413981 -403.739346) (xy 23.422101 -403.794522)
			(xy 23.42261 -403.822408) (xy 23.422101 -403.850294) (xy 23.413981 -403.90547) (xy 23.397913 -403.958877)
			(xy 23.374241 -404.009374) (xy 23.343468 -404.055887) (xy 23.306251 -404.097424) (xy 23.263383 -404.133099)
			(xy 23.215777 -404.162153) (xy 23.164448 -404.183965) (xy 23.110491 -404.198071) (xy 23.055054 -404.204171)
			(xy 22.99932 -404.202134) (xy 22.944477 -404.192004) (xy 22.891693 -404.173997) (xy 22.842093 -404.148496)
			(xy 22.796735 -404.116045) (xy 22.756586 -404.077336) (xy 22.7225 -404.033193) (xy 22.695204 -403.984558)
			(xy 22.675281 -403.932467) (xy 22.663155 -403.87803) (xy 22.659084 -403.822408) (xy 8.85444 -403.822408)
			(xy 8.85444 -404.445216) (xy 26.115264 -404.445216) (xy 26.115765 -404.416947) (xy 26.124095 -404.361026)
			(xy 26.140591 -404.306948) (xy 26.164891 -404.255898) (xy 26.196462 -404.208996) (xy 26.234611 -404.167269)
			(xy 26.256234 -404.149052) (xy 26.267538 -404.139112) (xy 26.284304 -404.114131) (xy 26.293067 -404.08535)
			(xy 26.293069 -404.055265) (xy 26.28431 -404.026483) (xy 26.267548 -404.001499) (xy 26.256234 -403.991572)
			(xy 26.234612 -403.973356) (xy 26.196476 -403.93162) (xy 26.164914 -403.884715) (xy 26.140618 -403.833667)
			(xy 26.124118 -403.779592) (xy 26.115776 -403.723676) (xy 26.115264 -403.695408) (xy 26.11575 -403.668157)
			(xy 26.123506 -403.614209) (xy 26.138861 -403.561914) (xy 26.161503 -403.512337) (xy 26.190969 -403.466487)
			(xy 26.22666 -403.425296) (xy 26.267851 -403.389605) (xy 26.313701 -403.360139) (xy 26.363278 -403.337497)
			(xy 26.415573 -403.322142) (xy 26.469521 -403.314386) (xy 26.524023 -403.314386) (xy 26.577971 -403.322142)
			(xy 26.630266 -403.337497) (xy 26.679843 -403.360139) (xy 26.725693 -403.389605) (xy 26.766884 -403.425296)
			(xy 26.802575 -403.466487) (xy 26.832041 -403.512337) (xy 26.854683 -403.561914) (xy 26.870038 -403.614209)
			(xy 26.877794 -403.668157) (xy 26.87828 -403.695408) (xy 29.285184 -403.695408) (xy 29.285709 -403.665612)
			(xy 29.294975 -403.606745) (xy 29.313282 -403.550035) (xy 29.340184 -403.496861) (xy 29.375028 -403.448517)
			(xy 29.416966 -403.40618) (xy 29.440632 -403.388068) (xy 29.45135 -403.379674) (xy 29.468218 -403.358317)
			(xy 29.478842 -403.333261) (xy 29.482467 -403.306288) (xy 29.478836 -403.279316) (xy 29.468206 -403.254263)
			(xy 29.451333 -403.232909) (xy 29.440632 -403.224492) (xy 29.416983 -403.206363) (xy 29.375061 -403.164021)
			(xy 29.340229 -403.115677) (xy 29.313334 -403.062507) (xy 29.29503 -403.005804) (xy 29.285761 -402.946944)
			(xy 29.285184 -402.917152) (xy 29.28567 -402.889901) (xy 29.293426 -402.835953) (xy 29.308781 -402.783658)
			(xy 29.331423 -402.734081) (xy 29.360889 -402.688231) (xy 29.39658 -402.64704) (xy 29.437771 -402.611349)
			(xy 29.483621 -402.581883) (xy 29.533198 -402.559241) (xy 29.585493 -402.543886) (xy 29.639441 -402.53613)
			(xy 29.693943 -402.53613) (xy 29.747891 -402.543886) (xy 29.800186 -402.559241) (xy 29.849763 -402.581883)
			(xy 29.895613 -402.611349) (xy 29.936804 -402.64704) (xy 29.972495 -402.688231) (xy 30.001961 -402.734081)
			(xy 30.024603 -402.783658) (xy 30.039958 -402.835953) (xy 30.047714 -402.889901) (xy 30.0482 -402.917152)
			(xy 30.047651 -402.946947) (xy 30.038392 -403.005814) (xy 30.02009 -403.062524) (xy 29.993192 -403.115698)
			(xy 29.958351 -403.164041) (xy 29.916416 -403.206379) (xy 29.892752 -403.224492) (xy 29.882075 -403.232933)
			(xy 29.86521 -403.254281) (xy 29.854585 -403.279326) (xy 29.850956 -403.306288) (xy 29.854579 -403.333251)
			(xy 29.865198 -403.358299) (xy 29.882058 -403.37965) (xy 29.892752 -403.388068) (xy 29.916426 -403.406166)
			(xy 29.958348 -403.448514) (xy 29.993177 -403.496864) (xy 30.020068 -403.55004) (xy 30.038366 -403.606749)
			(xy 30.047628 -403.665614) (xy 30.0482 -403.695408) (xy 30.047714 -403.722659) (xy 30.039958 -403.776607)
			(xy 30.024603 -403.828902) (xy 30.001961 -403.878479) (xy 29.972495 -403.924329) (xy 29.936804 -403.96552)
			(xy 29.895613 -404.001211) (xy 29.849763 -404.030677) (xy 29.800186 -404.053319) (xy 29.747891 -404.068674)
			(xy 29.693943 -404.07643) (xy 29.639441 -404.07643) (xy 29.585493 -404.068674) (xy 29.533198 -404.053319)
			(xy 29.483621 -404.030677) (xy 29.437771 -404.001211) (xy 29.39658 -403.96552) (xy 29.360889 -403.924329)
			(xy 29.331423 -403.878479) (xy 29.308781 -403.828902) (xy 29.293426 -403.776607) (xy 29.28567 -403.722659)
			(xy 29.285184 -403.695408) (xy 26.87828 -403.695408) (xy 26.87778 -403.723677) (xy 26.869447 -403.779597)
			(xy 26.85295 -403.833674) (xy 26.82865 -403.884724) (xy 26.79708 -403.931626) (xy 26.758932 -403.973354)
			(xy 26.73731 -403.991572) (xy 26.725987 -404.00149) (xy 26.709232 -404.02648) (xy 26.700476 -404.055264)
			(xy 26.700478 -404.085351) (xy 26.709238 -404.114134) (xy 26.725997 -404.139121) (xy 26.73731 -404.149052)
			(xy 26.758904 -404.167299) (xy 26.79704 -404.209029) (xy 26.828604 -404.255929) (xy 26.852905 -404.306971)
			(xy 26.869411 -404.361039) (xy 26.877762 -404.41695) (xy 26.87828 -404.445216) (xy 26.877794 -404.472467)
			(xy 26.870038 -404.526415) (xy 26.854683 -404.57871) (xy 26.832041 -404.628287) (xy 26.802575 -404.674137)
			(xy 26.766884 -404.715328) (xy 26.725693 -404.751019) (xy 26.679843 -404.780485) (xy 26.630266 -404.803127)
			(xy 26.577971 -404.818482) (xy 26.524023 -404.826238) (xy 26.469521 -404.826238) (xy 26.415573 -404.818482)
			(xy 26.363278 -404.803127) (xy 26.313701 -404.780485) (xy 26.267851 -404.751019) (xy 26.22666 -404.715328)
			(xy 26.190969 -404.674137) (xy 26.161503 -404.628287) (xy 26.138861 -404.57871) (xy 26.123506 -404.526415)
			(xy 26.11575 -404.472467) (xy 26.115264 -404.445216) (xy 8.85444 -404.445216) (xy 8.85444 -404.842218)
			(xy 22.659084 -404.842218) (xy 22.663155 -404.786596) (xy 22.675281 -404.732159) (xy 22.695204 -404.680068)
			(xy 22.7225 -404.631433) (xy 22.756586 -404.58729) (xy 22.796735 -404.548581) (xy 22.842093 -404.51613)
			(xy 22.891693 -404.490629) (xy 22.944477 -404.472622) (xy 22.99932 -404.462492) (xy 23.055054 -404.460455)
			(xy 23.110491 -404.466555) (xy 23.164448 -404.480661) (xy 23.215777 -404.502473) (xy 23.263383 -404.531527)
			(xy 23.306251 -404.567202) (xy 23.343468 -404.608739) (xy 23.374241 -404.655252) (xy 23.397913 -404.705749)
			(xy 23.413981 -404.759156) (xy 23.422101 -404.814332) (xy 23.42261 -404.842218) (xy 23.422101 -404.870104)
			(xy 23.413981 -404.92528) (xy 23.397913 -404.978687) (xy 23.374241 -405.029184) (xy 23.343468 -405.075697)
			(xy 23.306251 -405.117234) (xy 23.263383 -405.152909) (xy 23.215777 -405.181963) (xy 23.164448 -405.203775)
			(xy 23.110491 -405.217881) (xy 23.055054 -405.223981) (xy 22.99932 -405.221944) (xy 22.944477 -405.211814)
			(xy 22.891693 -405.193807) (xy 22.842093 -405.168306) (xy 22.796735 -405.135855) (xy 22.756586 -405.097146)
			(xy 22.7225 -405.053003) (xy 22.695204 -405.004368) (xy 22.675281 -404.952277) (xy 22.663155 -404.89784)
			(xy 22.659084 -404.842218) (xy 8.85444 -404.842218) (xy 8.85444 -405.477218) (xy 25.175462 -405.477218)
			(xy 25.179533 -405.421596) (xy 25.191659 -405.367159) (xy 25.211582 -405.315068) (xy 25.238878 -405.266433)
			(xy 25.272964 -405.22229) (xy 25.313113 -405.183581) (xy 25.358471 -405.15113) (xy 25.408071 -405.125629)
			(xy 25.460855 -405.107622) (xy 25.515698 -405.097492) (xy 25.571432 -405.095455) (xy 25.626869 -405.101555)
			(xy 25.680826 -405.115661) (xy 25.732155 -405.137473) (xy 25.779761 -405.166527) (xy 25.822629 -405.202202)
			(xy 25.859846 -405.243739) (xy 25.890619 -405.290252) (xy 25.914291 -405.340749) (xy 25.930359 -405.394156)
			(xy 25.938479 -405.449332) (xy 25.938988 -405.477218) (xy 25.938479 -405.505104) (xy 25.930359 -405.56028)
			(xy 25.914291 -405.613687) (xy 25.890619 -405.664184) (xy 25.859846 -405.710697) (xy 25.822629 -405.752234)
			(xy 25.779761 -405.787909) (xy 25.732155 -405.816963) (xy 25.680826 -405.838775) (xy 25.626869 -405.852881)
			(xy 25.571432 -405.858981) (xy 25.515698 -405.856944) (xy 25.460855 -405.846814) (xy 25.408071 -405.828807)
			(xy 25.358471 -405.803306) (xy 25.313113 -405.770855) (xy 25.272964 -405.732146) (xy 25.238878 -405.688003)
			(xy 25.211582 -405.639368) (xy 25.191659 -405.587277) (xy 25.179533 -405.53284) (xy 25.175462 -405.477218)
			(xy 8.85444 -405.477218) (xy 8.85444 -407.035508) (xy 15.978632 -407.035508) (xy 15.978632 -406.171908)
			(xy 15.979063 -406.144654) (xy 15.98682 -406.090699) (xy 16.002177 -406.038398) (xy 16.024821 -405.988816)
			(xy 16.054292 -405.942961) (xy 16.089989 -405.901767) (xy 16.131186 -405.866073) (xy 16.177044 -405.836606)
			(xy 16.226628 -405.813966) (xy 16.278931 -405.798613) (xy 16.332885 -405.790861) (xy 16.36014 -405.7904)
			(xy 16.389125 -405.790961) (xy 16.44643 -405.799715) (xy 16.501757 -405.817017) (xy 16.528034 -405.829262)
			(xy 16.542121 -405.835617) (xy 16.572658 -405.840299) (xy 16.603198 -405.835643) (xy 16.630952 -405.822073)
			(xy 16.653382 -405.80083) (xy 16.661384 -405.787606) (xy 16.675949 -405.762653) (xy 16.711506 -405.717112)
			(xy 16.753522 -405.677451) (xy 16.801036 -405.644577) (xy 16.852964 -405.619242) (xy 16.908117 -405.602025)
			(xy 16.965235 -405.593318) (xy 16.994124 -405.592788) (xy 17.021374 -405.593283) (xy 17.075318 -405.601043)
			(xy 17.12761 -405.6164) (xy 17.177183 -405.639042) (xy 17.22303 -405.668509) (xy 17.264217 -405.7042)
			(xy 17.299906 -405.745389) (xy 17.32937 -405.791238) (xy 17.352009 -405.840813) (xy 17.367362 -405.893105)
			(xy 17.375118 -405.94705) (xy 17.375118 -406.00155) (xy 17.36998 -406.037288) (xy 29.284674 -406.037288)
			(xy 29.288745 -405.981666) (xy 29.300871 -405.927229) (xy 29.320794 -405.875138) (xy 29.34809 -405.826503)
			(xy 29.382176 -405.78236) (xy 29.422325 -405.743651) (xy 29.467683 -405.7112) (xy 29.517283 -405.685699)
			(xy 29.570067 -405.667692) (xy 29.62491 -405.657562) (xy 29.680644 -405.655525) (xy 29.736081 -405.661625)
			(xy 29.790038 -405.675731) (xy 29.841367 -405.697543) (xy 29.888973 -405.726597) (xy 29.889337 -405.7269)
			(xy 30.918402 -405.7269) (xy 30.922473 -405.671278) (xy 30.934599 -405.616841) (xy 30.954522 -405.56475)
			(xy 30.981818 -405.516115) (xy 31.015904 -405.471972) (xy 31.056053 -405.433263) (xy 31.101411 -405.400812)
			(xy 31.151011 -405.375311) (xy 31.203795 -405.357304) (xy 31.258638 -405.347174) (xy 31.314372 -405.345137)
			(xy 31.369809 -405.351237) (xy 31.423766 -405.365343) (xy 31.475095 -405.387155) (xy 31.522701 -405.416209)
			(xy 31.565569 -405.451884) (xy 31.602786 -405.493421) (xy 31.633559 -405.539934) (xy 31.657231 -405.590431)
			(xy 31.673299 -405.643838) (xy 31.681419 -405.699014) (xy 31.681928 -405.7269) (xy 31.681419 -405.754786)
			(xy 31.673299 -405.809962) (xy 31.657231 -405.863369) (xy 31.633559 -405.913866) (xy 31.602786 -405.960379)
			(xy 31.565569 -406.001916) (xy 31.522701 -406.037591) (xy 31.475095 -406.066645) (xy 31.423766 -406.088457)
			(xy 31.369809 -406.102563) (xy 31.314372 -406.108663) (xy 31.258638 -406.106626) (xy 31.203795 -406.096496)
			(xy 31.151011 -406.078489) (xy 31.101411 -406.052988) (xy 31.056053 -406.020537) (xy 31.015904 -405.981828)
			(xy 30.981818 -405.937685) (xy 30.954522 -405.88905) (xy 30.934599 -405.836959) (xy 30.922473 -405.782522)
			(xy 30.918402 -405.7269) (xy 29.889337 -405.7269) (xy 29.931841 -405.762272) (xy 29.969058 -405.803809)
			(xy 29.999831 -405.850322) (xy 30.023503 -405.900819) (xy 30.039571 -405.954226) (xy 30.047691 -406.009402)
			(xy 30.0482 -406.037288) (xy 30.047691 -406.065174) (xy 30.039571 -406.12035) (xy 30.023503 -406.173757)
			(xy 29.999831 -406.224254) (xy 29.969058 -406.270767) (xy 29.931841 -406.312304) (xy 29.888973 -406.347979)
			(xy 29.841367 -406.377033) (xy 29.790038 -406.398845) (xy 29.736081 -406.412951) (xy 29.680644 -406.419051)
			(xy 29.62491 -406.417014) (xy 29.570067 -406.406884) (xy 29.517283 -406.388877) (xy 29.467683 -406.363376)
			(xy 29.422325 -406.330925) (xy 29.382176 -406.292216) (xy 29.34809 -406.248073) (xy 29.320794 -406.199438)
			(xy 29.300871 -406.147347) (xy 29.288745 -406.09291) (xy 29.284674 -406.037288) (xy 17.36998 -406.037288)
			(xy 17.367362 -406.055495) (xy 17.352009 -406.107787) (xy 17.32937 -406.157362) (xy 17.299906 -406.203211)
			(xy 17.264217 -406.2444) (xy 17.22303 -406.280091) (xy 17.177183 -406.309558) (xy 17.12761 -406.3322)
			(xy 17.075318 -406.347557) (xy 17.021374 -406.355317) (xy 16.994124 -406.355804) (xy 16.963819 -406.355234)
			(xy 16.90397 -406.345663) (xy 16.874998 -406.336754) (xy 16.861824 -406.332864) (xy 16.834396 -406.331559)
			(xy 16.807612 -406.337608) (xy 16.783407 -406.350575) (xy 16.763532 -406.369522) (xy 16.749423 -406.39308)
			(xy 16.742101 -406.419545) (xy 16.741648 -406.433274) (xy 16.741648 -406.679908) (xy 19.186142 -406.679908)
			(xy 19.190213 -406.624286) (xy 19.202339 -406.569849) (xy 19.222262 -406.517758) (xy 19.249558 -406.469123)
			(xy 19.283644 -406.42498) (xy 19.323793 -406.386271) (xy 19.369151 -406.35382) (xy 19.418751 -406.328319)
			(xy 19.471535 -406.310312) (xy 19.526378 -406.300182) (xy 19.582112 -406.298145) (xy 19.637549 -406.304245)
			(xy 19.691506 -406.318351) (xy 19.742835 -406.340163) (xy 19.790441 -406.369217) (xy 19.833309 -406.404892)
			(xy 19.870526 -406.446429) (xy 19.901299 -406.492942) (xy 19.924971 -406.543439) (xy 19.941039 -406.596846)
			(xy 19.949159 -406.652022) (xy 19.949668 -406.679908) (xy 19.949159 -406.707794) (xy 19.941039 -406.76297)
			(xy 19.924971 -406.816377) (xy 19.901299 -406.866874) (xy 19.870526 -406.913387) (xy 19.833309 -406.954924)
			(xy 19.790441 -406.990599) (xy 19.742835 -407.019653) (xy 19.691506 -407.041465) (xy 19.637549 -407.055571)
			(xy 19.582112 -407.061671) (xy 19.526378 -407.059634) (xy 19.471535 -407.049504) (xy 19.418751 -407.031497)
			(xy 19.369151 -407.005996) (xy 19.323793 -406.973545) (xy 19.283644 -406.934836) (xy 19.249558 -406.890693)
			(xy 19.222262 -406.842058) (xy 19.202339 -406.789967) (xy 19.190213 -406.73553) (xy 19.186142 -406.679908)
			(xy 16.741648 -406.679908) (xy 16.741648 -406.774142) (xy 16.742075 -406.787875) (xy 16.749385 -406.81435)
			(xy 16.763491 -406.837916) (xy 16.783372 -406.856867) (xy 16.807586 -406.869829) (xy 16.834381 -406.875864)
			(xy 16.861814 -406.874533) (xy 16.874998 -406.870662) (xy 16.903973 -406.861769) (xy 16.96382 -406.852197)
			(xy 16.994124 -406.851612) (xy 17.021376 -406.852059) (xy 17.075324 -406.859819) (xy 17.127618 -406.875177)
			(xy 17.177195 -406.897821) (xy 17.223045 -406.927289) (xy 17.264234 -406.962983) (xy 17.299925 -407.004175)
			(xy 17.329391 -407.050026) (xy 17.352031 -407.099604) (xy 17.367386 -407.1519) (xy 17.375142 -407.205848)
			(xy 17.375142 -407.260352) (xy 17.367386 -407.3143) (xy 17.352031 -407.366596) (xy 17.329391 -407.416174)
			(xy 17.299925 -407.462025) (xy 17.264234 -407.503217) (xy 17.223045 -407.538911) (xy 17.177195 -407.568379)
			(xy 17.127618 -407.591023) (xy 17.075324 -407.606381) (xy 17.021376 -407.614141) (xy 16.994124 -407.614628)
			(xy 16.965237 -407.614064) (xy 16.908121 -407.605369) (xy 16.852969 -407.588158) (xy 16.801045 -407.562826)
			(xy 16.753535 -407.529952) (xy 16.711528 -407.490288) (xy 16.675983 -407.444742) (xy 16.661384 -407.41981)
			(xy 16.653339 -407.406619) (xy 16.630921 -407.385385) (xy 16.603182 -407.37182) (xy 16.572657 -407.367166)
			(xy 16.542136 -407.371846) (xy 16.528034 -407.378154) (xy 16.501766 -407.390425) (xy 16.446442 -407.407759)
			(xy 16.389128 -407.416499) (xy 16.36014 -407.417016) (xy 16.332888 -407.416508) (xy 16.27894 -407.408756)
			(xy 16.226643 -407.393406) (xy 16.177064 -407.370768) (xy 16.131211 -407.341305) (xy 16.090018 -407.305616)
			(xy 16.054324 -407.264428) (xy 16.024855 -407.218579) (xy 16.002211 -407.169002) (xy 15.986854 -407.116707)
			(xy 15.979096 -407.062759) (xy 15.978632 -407.035508) (xy 8.85444 -407.035508) (xy 8.85444 -407.507186)
			(xy 13.418564 -407.507186) (xy 13.422635 -407.451564) (xy 13.434761 -407.397127) (xy 13.454684 -407.345036)
			(xy 13.48198 -407.296401) (xy 13.516066 -407.252258) (xy 13.556215 -407.213549) (xy 13.601573 -407.181098)
			(xy 13.651173 -407.155597) (xy 13.703957 -407.13759) (xy 13.7588 -407.12746) (xy 13.814534 -407.125423)
			(xy 13.869971 -407.131523) (xy 13.923928 -407.145629) (xy 13.975257 -407.167441) (xy 14.022863 -407.196495)
			(xy 14.065731 -407.23217) (xy 14.102948 -407.273707) (xy 14.133721 -407.32022) (xy 14.157393 -407.370717)
			(xy 14.173461 -407.424124) (xy 14.181581 -407.4793) (xy 14.18209 -407.507186) (xy 14.181581 -407.535072)
			(xy 14.173461 -407.590248) (xy 14.157393 -407.643655) (xy 14.133721 -407.694152) (xy 14.102948 -407.740665)
			(xy 14.065731 -407.782202) (xy 14.022863 -407.817877) (xy 13.975257 -407.846931) (xy 13.923928 -407.868743)
			(xy 13.869971 -407.882849) (xy 13.814534 -407.888949) (xy 13.7588 -407.886912) (xy 13.703957 -407.876782)
			(xy 13.651173 -407.858775) (xy 13.601573 -407.833274) (xy 13.556215 -407.800823) (xy 13.516066 -407.762114)
			(xy 13.48198 -407.717971) (xy 13.454684 -407.669336) (xy 13.434761 -407.617245) (xy 13.422635 -407.562808)
			(xy 13.418564 -407.507186) (xy 8.85444 -407.507186) (xy 8.85444 -408.916886) (xy 16.158462 -408.916886)
			(xy 16.162533 -408.861264) (xy 16.174659 -408.806827) (xy 16.194582 -408.754736) (xy 16.221878 -408.706101)
			(xy 16.255964 -408.661958) (xy 16.296113 -408.623249) (xy 16.341471 -408.590798) (xy 16.391071 -408.565297)
			(xy 16.443855 -408.54729) (xy 16.498698 -408.53716) (xy 16.554432 -408.535123) (xy 16.609869 -408.541223)
			(xy 16.663826 -408.555329) (xy 16.715155 -408.577141) (xy 16.762761 -408.606195) (xy 16.805629 -408.64187)
			(xy 16.842846 -408.683407) (xy 16.873619 -408.72992) (xy 16.897291 -408.780417) (xy 16.913359 -408.833824)
			(xy 16.921479 -408.889) (xy 16.921988 -408.916886) (xy 16.921479 -408.944772) (xy 16.913359 -408.999948)
			(xy 16.897291 -409.053355) (xy 16.873619 -409.103852) (xy 16.842846 -409.150365) (xy 16.805629 -409.191902)
			(xy 16.762761 -409.227577) (xy 16.715155 -409.256631) (xy 16.663826 -409.278443) (xy 16.609869 -409.292549)
			(xy 16.554432 -409.298649) (xy 16.498698 -409.296612) (xy 16.443855 -409.286482) (xy 16.391071 -409.268475)
			(xy 16.341471 -409.242974) (xy 16.296113 -409.210523) (xy 16.255964 -409.171814) (xy 16.221878 -409.127671)
			(xy 16.194582 -409.079036) (xy 16.174659 -409.026945) (xy 16.162533 -408.972508) (xy 16.158462 -408.916886)
			(xy 8.85444 -408.916886) (xy 8.85444 -409.7782) (xy 18.439382 -409.7782) (xy 18.443453 -409.722578)
			(xy 18.455579 -409.668141) (xy 18.475502 -409.61605) (xy 18.502798 -409.567415) (xy 18.536884 -409.523272)
			(xy 18.577033 -409.484563) (xy 18.622391 -409.452112) (xy 18.671991 -409.426611) (xy 18.724775 -409.408604)
			(xy 18.779618 -409.398474) (xy 18.835352 -409.396437) (xy 18.890789 -409.402537) (xy 18.944746 -409.416643)
			(xy 18.996075 -409.438455) (xy 19.043681 -409.467509) (xy 19.086549 -409.503184) (xy 19.123766 -409.544721)
			(xy 19.154539 -409.591234) (xy 19.178211 -409.641731) (xy 19.194279 -409.695138) (xy 19.202399 -409.750314)
			(xy 19.202908 -409.7782) (xy 19.202399 -409.806086) (xy 19.194279 -409.861262) (xy 19.178211 -409.914669)
			(xy 19.154539 -409.965166) (xy 19.123766 -410.011679) (xy 19.086549 -410.053216) (xy 19.043681 -410.088891)
			(xy 18.996075 -410.117945) (xy 18.944746 -410.139757) (xy 18.890789 -410.153863) (xy 18.835352 -410.159963)
			(xy 18.779618 -410.157926) (xy 18.724775 -410.147796) (xy 18.671991 -410.129789) (xy 18.622391 -410.104288)
			(xy 18.577033 -410.071837) (xy 18.536884 -410.033128) (xy 18.502798 -409.988985) (xy 18.475502 -409.94035)
			(xy 18.455579 -409.888259) (xy 18.443453 -409.833822) (xy 18.439382 -409.7782) (xy 8.85444 -409.7782)
			(xy 8.85444 -410.456888) (xy 16.260062 -410.456888) (xy 16.264133 -410.401266) (xy 16.276259 -410.346829)
			(xy 16.296182 -410.294738) (xy 16.323478 -410.246103) (xy 16.357564 -410.20196) (xy 16.397713 -410.163251)
			(xy 16.443071 -410.1308) (xy 16.492671 -410.105299) (xy 16.545455 -410.087292) (xy 16.600298 -410.077162)
			(xy 16.656032 -410.075125) (xy 16.711469 -410.081225) (xy 16.765426 -410.095331) (xy 16.816755 -410.117143)
			(xy 16.864361 -410.146197) (xy 16.907229 -410.181872) (xy 16.944446 -410.223409) (xy 16.975219 -410.269922)
			(xy 16.998891 -410.320419) (xy 17.014959 -410.373826) (xy 17.023079 -410.429002) (xy 17.023588 -410.456888)
			(xy 17.023079 -410.484774) (xy 17.014959 -410.53995) (xy 16.998891 -410.593357) (xy 16.975219 -410.643854)
			(xy 16.944446 -410.690367) (xy 16.907229 -410.731904) (xy 16.864361 -410.767579) (xy 16.816755 -410.796633)
			(xy 16.765426 -410.818445) (xy 16.711469 -410.832551) (xy 16.656032 -410.838651) (xy 16.600298 -410.836614)
			(xy 16.545455 -410.826484) (xy 16.492671 -410.808477) (xy 16.443071 -410.782976) (xy 16.397713 -410.750525)
			(xy 16.357564 -410.711816) (xy 16.323478 -410.667673) (xy 16.296182 -410.619038) (xy 16.276259 -410.566947)
			(xy 16.264133 -410.51251) (xy 16.260062 -410.456888) (xy 8.85444 -410.456888) (xy 8.85444 -421.616886)
			(xy 11.005564 -421.616886) (xy 11.009635 -421.561264) (xy 11.021761 -421.506827) (xy 11.041684 -421.454736)
			(xy 11.06898 -421.406101) (xy 11.103066 -421.361958) (xy 11.143215 -421.323249) (xy 11.188573 -421.290798)
			(xy 11.238173 -421.265297) (xy 11.290957 -421.24729) (xy 11.3458 -421.23716) (xy 11.401534 -421.235123)
			(xy 11.456971 -421.241223) (xy 11.473476 -421.245538) (xy 13.469872 -421.245538) (xy 13.473943 -421.189916)
			(xy 13.486069 -421.135479) (xy 13.505992 -421.083388) (xy 13.533288 -421.034753) (xy 13.567374 -420.99061)
			(xy 13.607523 -420.951901) (xy 13.652881 -420.91945) (xy 13.702481 -420.893949) (xy 13.755265 -420.875942)
			(xy 13.810108 -420.865812) (xy 13.865842 -420.863775) (xy 13.921279 -420.869875) (xy 13.975236 -420.883981)
			(xy 14.026565 -420.905793) (xy 14.074171 -420.934847) (xy 14.117039 -420.970522) (xy 14.154256 -421.012059)
			(xy 14.185029 -421.058572) (xy 14.208701 -421.109069) (xy 14.224769 -421.162476) (xy 14.232889 -421.217652)
			(xy 14.233398 -421.245538) (xy 14.232889 -421.273424) (xy 14.224769 -421.3286) (xy 14.208701 -421.382007)
			(xy 14.185029 -421.432504) (xy 14.154256 -421.479017) (xy 14.117039 -421.520554) (xy 14.074171 -421.556229)
			(xy 14.026565 -421.585283) (xy 13.975236 -421.607095) (xy 13.921279 -421.621201) (xy 13.865842 -421.627301)
			(xy 13.810108 -421.625264) (xy 13.755265 -421.615134) (xy 13.702481 -421.597127) (xy 13.652881 -421.571626)
			(xy 13.607523 -421.539175) (xy 13.567374 -421.500466) (xy 13.533288 -421.456323) (xy 13.505992 -421.407688)
			(xy 13.486069 -421.355597) (xy 13.473943 -421.30116) (xy 13.469872 -421.245538) (xy 11.473476 -421.245538)
			(xy 11.510928 -421.255329) (xy 11.562257 -421.277141) (xy 11.609863 -421.306195) (xy 11.652731 -421.34187)
			(xy 11.689948 -421.383407) (xy 11.720721 -421.42992) (xy 11.744393 -421.480417) (xy 11.760461 -421.533824)
			(xy 11.768581 -421.589) (xy 11.76909 -421.616886) (xy 11.768581 -421.644772) (xy 11.760461 -421.699948)
			(xy 11.744393 -421.753355) (xy 11.720721 -421.803852) (xy 11.689948 -421.850365) (xy 11.652731 -421.891902)
			(xy 11.609863 -421.927577) (xy 11.562257 -421.956631) (xy 11.510928 -421.978443) (xy 11.456971 -421.992549)
			(xy 11.401534 -421.998649) (xy 11.3458 -421.996612) (xy 11.290957 -421.986482) (xy 11.238173 -421.968475)
			(xy 11.188573 -421.942974) (xy 11.143215 -421.910523) (xy 11.103066 -421.871814) (xy 11.06898 -421.827671)
			(xy 11.041684 -421.779036) (xy 11.021761 -421.726945) (xy 11.009635 -421.672508) (xy 11.005564 -421.616886)
			(xy 8.85444 -421.616886) (xy 8.85444 -422.44391) (xy 11.554458 -422.44391) (xy 11.558529 -422.388288)
			(xy 11.570655 -422.333851) (xy 11.590578 -422.28176) (xy 11.617874 -422.233125) (xy 11.65196 -422.188982)
			(xy 11.692109 -422.150273) (xy 11.737467 -422.117822) (xy 11.787067 -422.092321) (xy 11.839851 -422.074314)
			(xy 11.894694 -422.064184) (xy 11.950428 -422.062147) (xy 12.005865 -422.068247) (xy 12.059822 -422.082353)
			(xy 12.111151 -422.104165) (xy 12.158757 -422.133219) (xy 12.201625 -422.168894) (xy 12.238842 -422.210431)
			(xy 12.269615 -422.256944) (xy 12.293287 -422.307441) (xy 12.309355 -422.360848) (xy 12.317475 -422.416024)
			(xy 12.317984 -422.44391) (xy 12.317475 -422.471796) (xy 12.309355 -422.526972) (xy 12.29583 -422.571926)
			(xy 13.455394 -422.571926) (xy 13.459465 -422.516304) (xy 13.471591 -422.461867) (xy 13.491514 -422.409776)
			(xy 13.51881 -422.361141) (xy 13.552896 -422.316998) (xy 13.593045 -422.278289) (xy 13.638403 -422.245838)
			(xy 13.688003 -422.220337) (xy 13.740787 -422.20233) (xy 13.79563 -422.1922) (xy 13.851364 -422.190163)
			(xy 13.906801 -422.196263) (xy 13.960758 -422.210369) (xy 14.012087 -422.232181) (xy 14.059693 -422.261235)
			(xy 14.102561 -422.29691) (xy 14.139778 -422.338447) (xy 14.170551 -422.38496) (xy 14.194223 -422.435457)
			(xy 14.210291 -422.488864) (xy 14.218411 -422.54404) (xy 14.21892 -422.571926) (xy 14.218411 -422.599812)
			(xy 14.210291 -422.654988) (xy 14.194223 -422.708395) (xy 14.170551 -422.758892) (xy 14.139778 -422.805405)
			(xy 14.102561 -422.846942) (xy 14.059693 -422.882617) (xy 14.012087 -422.911671) (xy 13.960758 -422.933483)
			(xy 13.906801 -422.947589) (xy 13.851364 -422.953689) (xy 13.79563 -422.951652) (xy 13.740787 -422.941522)
			(xy 13.688003 -422.923515) (xy 13.638403 -422.898014) (xy 13.593045 -422.865563) (xy 13.552896 -422.826854)
			(xy 13.51881 -422.782711) (xy 13.491514 -422.734076) (xy 13.471591 -422.681985) (xy 13.459465 -422.627548)
			(xy 13.455394 -422.571926) (xy 12.29583 -422.571926) (xy 12.293287 -422.580379) (xy 12.269615 -422.630876)
			(xy 12.238842 -422.677389) (xy 12.201625 -422.718926) (xy 12.158757 -422.754601) (xy 12.111151 -422.783655)
			(xy 12.059822 -422.805467) (xy 12.005865 -422.819573) (xy 11.950428 -422.825673) (xy 11.894694 -422.823636)
			(xy 11.839851 -422.813506) (xy 11.787067 -422.795499) (xy 11.737467 -422.769998) (xy 11.692109 -422.737547)
			(xy 11.65196 -422.698838) (xy 11.617874 -422.654695) (xy 11.590578 -422.60606) (xy 11.570655 -422.553969)
			(xy 11.558529 -422.499532) (xy 11.554458 -422.44391) (xy 8.85444 -422.44391) (xy 8.85444 -424.36542)
			(xy 9.372854 -424.883834) (xy 11.878308 -424.883834) (xy 11.882379 -424.828212) (xy 11.894505 -424.773775)
			(xy 11.914428 -424.721684) (xy 11.941724 -424.673049) (xy 11.97581 -424.628906) (xy 12.015959 -424.590197)
			(xy 12.061317 -424.557746) (xy 12.110917 -424.532245) (xy 12.163701 -424.514238) (xy 12.218544 -424.504108)
			(xy 12.274278 -424.502071) (xy 12.329715 -424.508171) (xy 12.383672 -424.522277) (xy 12.435001 -424.544089)
			(xy 12.482607 -424.573143) (xy 12.525475 -424.608818) (xy 12.562692 -424.650355) (xy 12.564408 -424.652948)
			(xy 13.164564 -424.652948) (xy 13.168635 -424.597326) (xy 13.180761 -424.542889) (xy 13.200684 -424.490798)
			(xy 13.22798 -424.442163) (xy 13.262066 -424.39802) (xy 13.302215 -424.359311) (xy 13.347573 -424.32686)
			(xy 13.397173 -424.301359) (xy 13.449957 -424.283352) (xy 13.5048 -424.273222) (xy 13.560534 -424.271185)
			(xy 13.615971 -424.277285) (xy 13.669928 -424.291391) (xy 13.721257 -424.313203) (xy 13.768863 -424.342257)
			(xy 13.811731 -424.377932) (xy 13.848948 -424.419469) (xy 13.879721 -424.465982) (xy 13.903393 -424.516479)
			(xy 13.919461 -424.569886) (xy 13.927581 -424.625062) (xy 13.92809 -424.652948) (xy 13.927581 -424.680834)
			(xy 13.919461 -424.73601) (xy 13.903393 -424.789417) (xy 13.879721 -424.839914) (xy 13.848948 -424.886427)
			(xy 13.811731 -424.927964) (xy 13.768863 -424.963639) (xy 13.721257 -424.992693) (xy 13.669928 -425.014505)
			(xy 13.615971 -425.028611) (xy 13.560534 -425.034711) (xy 13.5048 -425.032674) (xy 13.449957 -425.022544)
			(xy 13.397173 -425.004537) (xy 13.347573 -424.979036) (xy 13.302215 -424.946585) (xy 13.262066 -424.907876)
			(xy 13.22798 -424.863733) (xy 13.200684 -424.815098) (xy 13.180761 -424.763007) (xy 13.168635 -424.70857)
			(xy 13.164564 -424.652948) (xy 12.564408 -424.652948) (xy 12.593465 -424.696868) (xy 12.617137 -424.747365)
			(xy 12.633205 -424.800772) (xy 12.641325 -424.855948) (xy 12.641834 -424.883834) (xy 12.641325 -424.91172)
			(xy 12.633205 -424.966896) (xy 12.617137 -425.020303) (xy 12.593465 -425.0708) (xy 12.562692 -425.117313)
			(xy 12.525475 -425.15885) (xy 12.482607 -425.194525) (xy 12.435001 -425.223579) (xy 12.383672 -425.245391)
			(xy 12.329715 -425.259497) (xy 12.274278 -425.265597) (xy 12.218544 -425.26356) (xy 12.163701 -425.25343)
			(xy 12.110917 -425.235423) (xy 12.061317 -425.209922) (xy 12.015959 -425.177471) (xy 11.97581 -425.138762)
			(xy 11.941724 -425.094619) (xy 11.914428 -425.045984) (xy 11.894505 -424.993893) (xy 11.882379 -424.939456)
			(xy 11.878308 -424.883834) (xy 9.372854 -424.883834) (xy 10.14984 -425.66082) (xy 15.80896 -425.66082)
		)
		(stroke
			(width 0)
			(type solid)
		)
		(fill yes)
		(layer "In6.Cu")
		(net "P3V3_AUX")
	)
	(gr_poly
		(pts
			(xy 469.65108 -76.647548) (xy 469.65108 -55.926228) (xy 460.8322 -47.107348) (xy 441.005214 -47.107348)
			(xy 440.990736 -47.134272) (xy 440.977411 -47.158418) (xy 440.944869 -47.202943) (xy 440.906253 -47.242315)
			(xy 440.862367 -47.275714) (xy 440.814127 -47.302442) (xy 440.762541 -47.321942) (xy 440.708683 -47.333807)
			(xy 440.653678 -47.33779) (xy 440.598673 -47.333807) (xy 440.544815 -47.321942) (xy 440.493229 -47.302442)
			(xy 440.444989 -47.275714) (xy 440.401103 -47.242315) (xy 440.362487 -47.202943) (xy 440.329945 -47.158418)
			(xy 440.31662 -47.134272) (xy 440.302142 -47.107348) (xy 438.084976 -47.107348) (xy 438.07987 -47.133992)
			(xy 438.063196 -47.185614) (xy 438.039492 -47.234411) (xy 438.009221 -47.279429) (xy 437.972973 -47.319791)
			(xy 437.931456 -47.354709) (xy 437.885479 -47.383503) (xy 437.835938 -47.40561) (xy 437.783801 -47.4206)
			(xy 437.730084 -47.42818) (xy 437.70296 -47.428658) (xy 437.675832 -47.428208) (xy 437.622104 -47.420651)
			(xy 437.569954 -47.405675) (xy 437.520403 -47.383575) (xy 437.474417 -47.354781) (xy 437.432895 -47.319855)
			(xy 437.39665 -47.279481) (xy 437.366388 -47.234448) (xy 437.342701 -47.185635) (xy 437.326052 -47.133995)
			(xy 437.320944 -47.107348) (xy 435.4322 -47.107348) (xy 433.96154 -48.578008) (xy 436.577232 -48.578008)
			(xy 436.577787 -48.549327) (xy 436.586396 -48.492615) (xy 436.603391 -48.437828) (xy 436.62839 -48.3862)
			(xy 436.66083 -48.338892) (xy 436.699982 -48.296969) (xy 436.744964 -48.261374) (xy 436.794764 -48.232907)
			(xy 436.848262 -48.212211) (xy 436.904254 -48.199749) (xy 436.932832 -48.197262) (xy 436.947352 -48.195752)
			(xy 436.974693 -48.18556) (xy 436.998039 -48.168055) (xy 437.015484 -48.144666) (xy 437.025607 -48.117298)
			(xy 437.027066 -48.102774) (xy 437.029521 -48.074186) (xy 437.041948 -48.018171) (xy 437.062623 -47.964649)
			(xy 437.091079 -47.914826) (xy 437.126675 -47.869826) (xy 437.168609 -47.830663) (xy 437.215933 -47.798221)
			(xy 437.267582 -47.773231) (xy 437.322391 -47.756258) (xy 437.379123 -47.747683) (xy 437.407812 -47.747174)
			(xy 437.435063 -47.747667) (xy 437.489009 -47.755424) (xy 437.541303 -47.77078) (xy 437.590879 -47.793421)
			(xy 437.636728 -47.822887) (xy 437.677918 -47.858578) (xy 437.713609 -47.899767) (xy 437.743076 -47.945616)
			(xy 437.765718 -47.995192) (xy 437.781074 -48.047485) (xy 437.788833 -48.101431) (xy 437.78932 -48.128682)
			(xy 437.7888 -48.157365) (xy 437.780192 -48.214081) (xy 437.763195 -48.268871) (xy 437.738194 -48.320502)
			(xy 437.70575 -48.367812) (xy 437.666594 -48.409736) (xy 437.621606 -48.445331) (xy 437.574339 -48.472344)
			(xy 445.193418 -48.472344) (xy 445.197489 -48.416722) (xy 445.209615 -48.362285) (xy 445.229538 -48.310194)
			(xy 445.256834 -48.261559) (xy 445.29092 -48.217416) (xy 445.331069 -48.178707) (xy 445.376427 -48.146256)
			(xy 445.426027 -48.120755) (xy 445.478811 -48.102748) (xy 445.533654 -48.092618) (xy 445.589388 -48.090581)
			(xy 445.644825 -48.096681) (xy 445.698782 -48.110787) (xy 445.750111 -48.132599) (xy 445.797717 -48.161653)
			(xy 445.840585 -48.197328) (xy 445.877802 -48.238865) (xy 445.908575 -48.285378) (xy 445.932247 -48.335875)
			(xy 445.948315 -48.389282) (xy 445.956435 -48.444458) (xy 445.956944 -48.472344) (xy 445.956435 -48.50023)
			(xy 445.948315 -48.555406) (xy 445.932247 -48.608813) (xy 445.908575 -48.65931) (xy 445.877802 -48.705823)
			(xy 445.840585 -48.74736) (xy 445.797717 -48.783035) (xy 445.750111 -48.812089) (xy 445.698782 -48.833901)
			(xy 445.644825 -48.848007) (xy 445.589388 -48.854107) (xy 445.533654 -48.85207) (xy 445.478811 -48.84194)
			(xy 445.426027 -48.823933) (xy 445.376427 -48.798432) (xy 445.331069 -48.765981) (xy 445.29092 -48.727272)
			(xy 445.256834 -48.683129) (xy 445.229538 -48.634494) (xy 445.209615 -48.582403) (xy 445.197489 -48.527966)
			(xy 445.193418 -48.472344) (xy 437.574339 -48.472344) (xy 437.5718 -48.473795) (xy 437.518297 -48.494488)
			(xy 437.4623 -48.506944) (xy 437.43372 -48.509428) (xy 437.419197 -48.510909) (xy 437.391856 -48.521112)
			(xy 437.368513 -48.538625) (xy 437.351069 -48.56202) (xy 437.340946 -48.58939) (xy 437.339486 -48.603916)
			(xy 437.336971 -48.632497) (xy 437.324548 -48.688507) (xy 437.303878 -48.742026) (xy 437.275428 -48.791846)
			(xy 437.239838 -48.836845) (xy 437.197912 -48.876008) (xy 437.150595 -48.908451) (xy 437.098954 -48.933444)
			(xy 437.044152 -48.950422) (xy 436.987426 -48.959004) (xy 436.95874 -48.959516) (xy 436.931488 -48.959008)
			(xy 436.87754 -48.951256) (xy 436.825243 -48.935906) (xy 436.775664 -48.913268) (xy 436.729811 -48.883805)
			(xy 436.688618 -48.848116) (xy 436.652924 -48.806928) (xy 436.623455 -48.761079) (xy 436.600811 -48.711502)
			(xy 436.585454 -48.659207) (xy 436.577696 -48.605259) (xy 436.577232 -48.578008) (xy 433.96154 -48.578008)
			(xy 433.063142 -49.476406) (xy 448.662047 -49.476406) (xy 448.666083 -49.392959) (xy 448.678155 -49.310291)
			(xy 448.698148 -49.229174) (xy 448.725877 -49.150365) (xy 448.761083 -49.0746) (xy 448.803437 -49.002587)
			(xy 448.852543 -48.934998) (xy 448.907944 -48.872464) (xy 448.969121 -48.815569) (xy 449.035504 -48.764843)
			(xy 449.106472 -48.720762) (xy 449.181364 -48.683736) (xy 449.25948 -48.65411) (xy 449.34009 -48.632162)
			(xy 449.422442 -48.618097) (xy 449.505768 -48.612045) (xy 449.589288 -48.614064) (xy 449.672224 -48.624134)
			(xy 449.7538 -48.642162) (xy 449.833256 -48.667979) (xy 449.909849 -48.701344) (xy 449.982865 -48.741945)
			(xy 450.051621 -48.789404) (xy 450.115475 -48.843277) (xy 450.173832 -48.903062) (xy 450.226147 -48.968199)
			(xy 450.27193 -49.038082) (xy 450.310755 -49.112057) (xy 450.34226 -49.189434) (xy 450.366149 -49.269491)
			(xy 450.3822 -49.351479) (xy 450.390263 -49.434634) (xy 450.390768 -49.476406) (xy 456.170287 -49.476406)
			(xy 456.174323 -49.392959) (xy 456.186395 -49.310291) (xy 456.206388 -49.229174) (xy 456.234117 -49.150365)
			(xy 456.269323 -49.0746) (xy 456.311677 -49.002587) (xy 456.360783 -48.934998) (xy 456.416184 -48.872464)
			(xy 456.477361 -48.815569) (xy 456.543744 -48.764843) (xy 456.614712 -48.720762) (xy 456.689604 -48.683736)
			(xy 456.76772 -48.65411) (xy 456.84833 -48.632162) (xy 456.930682 -48.618097) (xy 457.014008 -48.612045)
			(xy 457.097528 -48.614064) (xy 457.180464 -48.624134) (xy 457.26204 -48.642162) (xy 457.341496 -48.667979)
			(xy 457.418089 -48.701344) (xy 457.491105 -48.741945) (xy 457.559861 -48.789404) (xy 457.623715 -48.843277)
			(xy 457.682072 -48.903062) (xy 457.734387 -48.968199) (xy 457.78017 -49.038082) (xy 457.818995 -49.112057)
			(xy 457.8505 -49.189434) (xy 457.874389 -49.269491) (xy 457.89044 -49.351479) (xy 457.898503 -49.434634)
			(xy 457.899008 -49.476406) (xy 457.898503 -49.518178) (xy 457.89044 -49.601333) (xy 457.874389 -49.683321)
			(xy 457.8505 -49.763378) (xy 457.818995 -49.840755) (xy 457.78017 -49.91473) (xy 457.734387 -49.984613)
			(xy 457.682072 -50.04975) (xy 457.623715 -50.109535) (xy 457.559861 -50.163408) (xy 457.491105 -50.210867)
			(xy 457.418089 -50.251468) (xy 457.341496 -50.284833) (xy 457.26204 -50.31065) (xy 457.180464 -50.328678)
			(xy 457.097528 -50.338748) (xy 457.014008 -50.340767) (xy 456.930682 -50.334715) (xy 456.84833 -50.32065)
			(xy 456.76772 -50.298702) (xy 456.689604 -50.269076) (xy 456.614712 -50.23205) (xy 456.543744 -50.187969)
			(xy 456.477361 -50.137243) (xy 456.416184 -50.080348) (xy 456.360783 -50.017814) (xy 456.311677 -49.950225)
			(xy 456.269323 -49.878212) (xy 456.234117 -49.802447) (xy 456.206388 -49.723638) (xy 456.186395 -49.642521)
			(xy 456.174323 -49.559853) (xy 456.170287 -49.476406) (xy 450.390768 -49.476406) (xy 450.390263 -49.518178)
			(xy 450.3822 -49.601333) (xy 450.366149 -49.683321) (xy 450.34226 -49.763378) (xy 450.310755 -49.840755)
			(xy 450.27193 -49.91473) (xy 450.226147 -49.984613) (xy 450.173832 -50.04975) (xy 450.115475 -50.109535)
			(xy 450.051621 -50.163408) (xy 449.982865 -50.210867) (xy 449.909849 -50.251468) (xy 449.833256 -50.284833)
			(xy 449.7538 -50.31065) (xy 449.672224 -50.328678) (xy 449.589288 -50.338748) (xy 449.505768 -50.340767)
			(xy 449.422442 -50.334715) (xy 449.34009 -50.32065) (xy 449.25948 -50.298702) (xy 449.181364 -50.269076)
			(xy 449.106472 -50.23205) (xy 449.035504 -50.187969) (xy 448.969121 -50.137243) (xy 448.907944 -50.080348)
			(xy 448.852543 -50.017814) (xy 448.803437 -49.950225) (xy 448.761083 -49.878212) (xy 448.725877 -49.802447)
			(xy 448.698148 -49.723638) (xy 448.678155 -49.642521) (xy 448.666083 -49.559853) (xy 448.662047 -49.476406)
			(xy 433.063142 -49.476406) (xy 430.525428 -52.01412) (xy 432.050442 -52.01412) (xy 432.054513 -51.958498)
			(xy 432.066639 -51.904061) (xy 432.086562 -51.85197) (xy 432.113858 -51.803335) (xy 432.147944 -51.759192)
			(xy 432.188093 -51.720483) (xy 432.233451 -51.688032) (xy 432.283051 -51.662531) (xy 432.335835 -51.644524)
			(xy 432.390678 -51.634394) (xy 432.446412 -51.632357) (xy 432.501849 -51.638457) (xy 432.555806 -51.652563)
			(xy 432.607135 -51.674375) (xy 432.654741 -51.703429) (xy 432.697609 -51.739104) (xy 432.734826 -51.780641)
			(xy 432.765599 -51.827154) (xy 432.789271 -51.877651) (xy 432.805339 -51.931058) (xy 432.813459 -51.986234)
			(xy 432.813968 -52.01412) (xy 432.813881 -52.018876) (xy 448.637656 -52.018876) (xy 448.637656 -51.93418)
			(xy 448.645707 -51.849866) (xy 448.661736 -51.7667) (xy 448.685597 -51.685433) (xy 448.717076 -51.606803)
			(xy 448.755887 -51.531522) (xy 448.801677 -51.46027) (xy 448.854033 -51.393694) (xy 448.912481 -51.332396)
			(xy 448.976491 -51.276931) (xy 449.045483 -51.227802) (xy 449.118833 -51.185453) (xy 449.195876 -51.150269)
			(xy 449.275915 -51.122567) (xy 449.358224 -51.102599) (xy 449.442059 -51.090546) (xy 449.52666 -51.086516)
			(xy 449.611261 -51.090546) (xy 449.695096 -51.102599) (xy 449.777405 -51.122567) (xy 449.857444 -51.150269)
			(xy 449.934487 -51.185453) (xy 450.007837 -51.227802) (xy 450.076829 -51.276931) (xy 450.140839 -51.332396)
			(xy 450.199287 -51.393694) (xy 450.251643 -51.46027) (xy 450.297433 -51.531522) (xy 450.336244 -51.606803)
			(xy 450.367723 -51.685433) (xy 450.391584 -51.7667) (xy 450.407613 -51.849866) (xy 450.415664 -51.93418)
			(xy 450.416168 -51.976528) (xy 450.415664 -52.018876) (xy 456.145896 -52.018876) (xy 456.145896 -51.93418)
			(xy 456.153947 -51.849866) (xy 456.169976 -51.7667) (xy 456.193837 -51.685433) (xy 456.225316 -51.606803)
			(xy 456.264127 -51.531522) (xy 456.309917 -51.46027) (xy 456.362273 -51.393694) (xy 456.420721 -51.332396)
			(xy 456.484731 -51.276931) (xy 456.553723 -51.227802) (xy 456.627073 -51.185453) (xy 456.704116 -51.150269)
			(xy 456.784155 -51.122567) (xy 456.866464 -51.102599) (xy 456.950299 -51.090546) (xy 457.0349 -51.086516)
			(xy 457.119501 -51.090546) (xy 457.203336 -51.102599) (xy 457.285645 -51.122567) (xy 457.365684 -51.150269)
			(xy 457.442727 -51.185453) (xy 457.516077 -51.227802) (xy 457.585069 -51.276931) (xy 457.649079 -51.332396)
			(xy 457.707527 -51.393694) (xy 457.759883 -51.46027) (xy 457.805673 -51.531522) (xy 457.844484 -51.606803)
			(xy 457.875963 -51.685433) (xy 457.899824 -51.7667) (xy 457.915853 -51.849866) (xy 457.923904 -51.93418)
			(xy 457.924408 -51.976528) (xy 457.923904 -52.018876) (xy 457.915853 -52.10319) (xy 457.899824 -52.186356)
			(xy 457.875963 -52.267623) (xy 457.844484 -52.346253) (xy 457.805673 -52.421534) (xy 457.759883 -52.492786)
			(xy 457.707527 -52.559362) (xy 457.649079 -52.62066) (xy 457.585069 -52.676125) (xy 457.516077 -52.725254)
			(xy 457.442727 -52.767603) (xy 457.365684 -52.802787) (xy 457.285645 -52.830489) (xy 457.203336 -52.850457)
			(xy 457.119501 -52.86251) (xy 457.0349 -52.866541) (xy 456.950299 -52.86251) (xy 456.866464 -52.850457)
			(xy 456.784155 -52.830489) (xy 456.704116 -52.802787) (xy 456.627073 -52.767603) (xy 456.553723 -52.725254)
			(xy 456.484731 -52.676125) (xy 456.420721 -52.62066) (xy 456.362273 -52.559362) (xy 456.309917 -52.492786)
			(xy 456.264127 -52.421534) (xy 456.225316 -52.346253) (xy 456.193837 -52.267623) (xy 456.169976 -52.186356)
			(xy 456.153947 -52.10319) (xy 456.145896 -52.018876) (xy 450.415664 -52.018876) (xy 450.407613 -52.10319)
			(xy 450.391584 -52.186356) (xy 450.367723 -52.267623) (xy 450.336244 -52.346253) (xy 450.297433 -52.421534)
			(xy 450.251643 -52.492786) (xy 450.199287 -52.559362) (xy 450.140839 -52.62066) (xy 450.076829 -52.676125)
			(xy 450.007837 -52.725254) (xy 449.934487 -52.767603) (xy 449.857444 -52.802787) (xy 449.777405 -52.830489)
			(xy 449.695096 -52.850457) (xy 449.611261 -52.86251) (xy 449.52666 -52.866541) (xy 449.442059 -52.86251)
			(xy 449.358224 -52.850457) (xy 449.275915 -52.830489) (xy 449.195876 -52.802787) (xy 449.118833 -52.767603)
			(xy 449.045483 -52.725254) (xy 448.976491 -52.676125) (xy 448.912481 -52.62066) (xy 448.854033 -52.559362)
			(xy 448.801677 -52.492786) (xy 448.755887 -52.421534) (xy 448.717076 -52.346253) (xy 448.685597 -52.267623)
			(xy 448.661736 -52.186356) (xy 448.645707 -52.10319) (xy 448.637656 -52.018876) (xy 432.813881 -52.018876)
			(xy 432.813459 -52.042006) (xy 432.805339 -52.097182) (xy 432.789271 -52.150589) (xy 432.765599 -52.201086)
			(xy 432.734826 -52.247599) (xy 432.697609 -52.289136) (xy 432.654741 -52.324811) (xy 432.607135 -52.353865)
			(xy 432.555806 -52.375677) (xy 432.501849 -52.389783) (xy 432.446412 -52.395883) (xy 432.390678 -52.393846)
			(xy 432.335835 -52.383716) (xy 432.283051 -52.365709) (xy 432.233451 -52.340208) (xy 432.188093 -52.307757)
			(xy 432.147944 -52.269048) (xy 432.113858 -52.224905) (xy 432.086562 -52.17627) (xy 432.066639 -52.124179)
			(xy 432.054513 -52.069742) (xy 432.050442 -52.01412) (xy 430.525428 -52.01412) (xy 430.022 -52.517548)
			(xy 444.575182 -52.517548) (xy 444.579253 -52.461926) (xy 444.591379 -52.407489) (xy 444.611302 -52.355398)
			(xy 444.638598 -52.306763) (xy 444.672684 -52.26262) (xy 444.712833 -52.223911) (xy 444.758191 -52.19146)
			(xy 444.807791 -52.165959) (xy 444.860575 -52.147952) (xy 444.915418 -52.137822) (xy 444.971152 -52.135785)
			(xy 445.026589 -52.141885) (xy 445.080546 -52.155991) (xy 445.131875 -52.177803) (xy 445.179481 -52.206857)
			(xy 445.222349 -52.242532) (xy 445.259566 -52.284069) (xy 445.290339 -52.330582) (xy 445.314011 -52.381079)
			(xy 445.330079 -52.434486) (xy 445.338199 -52.489662) (xy 445.338708 -52.517548) (xy 445.338199 -52.545434)
			(xy 445.330079 -52.60061) (xy 445.314011 -52.654017) (xy 445.290339 -52.704514) (xy 445.259566 -52.751027)
			(xy 445.222349 -52.792564) (xy 445.179481 -52.828239) (xy 445.131875 -52.857293) (xy 445.080546 -52.879105)
			(xy 445.026589 -52.893211) (xy 444.971152 -52.899311) (xy 444.915418 -52.897274) (xy 444.860575 -52.887144)
			(xy 444.807791 -52.869137) (xy 444.758191 -52.843636) (xy 444.712833 -52.811185) (xy 444.672684 -52.772476)
			(xy 444.638598 -52.728333) (xy 444.611302 -52.679698) (xy 444.591379 -52.627607) (xy 444.579253 -52.57317)
			(xy 444.575182 -52.517548) (xy 430.022 -52.517548) (xy 429.38446 -53.155088) (xy 429.38446 -54.534816)
			(xy 429.758856 -54.534816) (xy 429.759318 -54.507445) (xy 429.767135 -54.453266) (xy 429.782624 -54.400762)
			(xy 429.805467 -54.351015) (xy 429.835194 -54.305049) (xy 429.852836 -54.284118) (xy 429.862055 -54.272778)
			(xy 429.874229 -54.246224) (xy 429.878403 -54.217312) (xy 429.874236 -54.188399) (xy 429.862068 -54.161842)
			(xy 429.852836 -54.150514) (xy 429.835196 -54.129583) (xy 429.805483 -54.08361) (xy 429.782646 -54.033863)
			(xy 429.767156 -53.981362) (xy 429.759329 -53.927185) (xy 429.758856 -53.899816) (xy 429.759435 -53.869693)
			(xy 429.768914 -53.810197) (xy 429.787623 -53.752929) (xy 429.815097 -53.699312) (xy 429.850654 -53.650677)
			(xy 429.871632 -53.629052) (xy 429.880834 -53.619316) (xy 429.89428 -53.596158) (xy 429.901244 -53.570301)
			(xy 429.901247 -53.543522) (xy 429.894288 -53.517663) (xy 429.880847 -53.494502) (xy 429.871632 -53.48478)
			(xy 429.850671 -53.463138) (xy 429.815099 -53.414514) (xy 429.787614 -53.360902) (xy 429.768902 -53.303636)
			(xy 429.759426 -53.244139) (xy 429.758856 -53.214016) (xy 429.759393 -53.186767) (xy 429.767146 -53.132823)
			(xy 429.782498 -53.080531) (xy 429.805134 -53.030957) (xy 429.834596 -52.985108) (xy 429.870282 -52.943918)
			(xy 429.911466 -52.908227) (xy 429.957311 -52.878759) (xy 430.006883 -52.856116) (xy 430.059172 -52.840757)
			(xy 430.113115 -52.832997) (xy 430.140364 -52.832508) (xy 430.166824 -52.832931) (xy 430.219233 -52.840271)
			(xy 430.270124 -52.854787) (xy 430.318518 -52.876201) (xy 430.363487 -52.904102) (xy 430.404166 -52.937952)
			(xy 430.422304 -52.957222) (xy 430.433109 -52.968182) (xy 430.459663 -52.983704) (xy 430.489627 -52.990644)
			(xy 430.520301 -52.988377) (xy 430.54892 -52.977108) (xy 430.561242 -52.96789) (xy 430.581659 -52.951937)
			(xy 430.62602 -52.925161) (xy 430.673598 -52.904638) (xy 430.723516 -52.890745) (xy 430.774856 -52.883738)
			(xy 430.800764 -52.883308) (xy 430.828134 -52.883793) (xy 430.882312 -52.891606) (xy 430.934815 -52.907091)
			(xy 430.984562 -52.929928) (xy 431.03053 -52.959649) (xy 431.051462 -52.977288) (xy 431.06279 -52.986524)
			(xy 431.089347 -52.9987) (xy 431.118264 -53.002873) (xy 431.147181 -52.9987) (xy 431.173738 -52.986524)
			(xy 431.185066 -52.977288) (xy 431.205999 -52.95965) (xy 431.251971 -52.929938) (xy 431.301719 -52.907102)
			(xy 431.354219 -52.891611) (xy 431.408395 -52.883782) (xy 431.435764 -52.883308) (xy 431.465276 -52.883875)
			(xy 431.523597 -52.892961) (xy 431.579823 -52.910922) (xy 431.632611 -52.937328) (xy 431.680702 -52.97155)
			(xy 431.70221 -52.991766) (xy 431.713589 -53.002006) (xy 431.740854 -53.015882) (xy 431.771003 -53.021076)
			(xy 431.801339 -53.017123) (xy 431.82915 -53.004375) (xy 431.840894 -52.99456) (xy 431.861973 -52.976257)
			(xy 431.908518 -52.945435) (xy 431.959057 -52.921725) (xy 432.012513 -52.905634) (xy 432.067743 -52.897506)
			(xy 432.095656 -52.897024) (xy 432.124842 -52.897613) (xy 432.182533 -52.906505) (xy 432.238198 -52.924075)
			(xy 432.29054 -52.949912) (xy 432.338341 -52.983414) (xy 432.380485 -53.023801) (xy 432.398678 -53.04663)
			(xy 432.407273 -53.057141) (xy 432.428869 -53.073581) (xy 432.454033 -53.083755) (xy 432.480987 -53.086942)
			(xy 432.507829 -53.082919) (xy 432.532664 -53.071969) (xy 432.553739 -53.054866) (xy 432.562 -53.04409)
			(xy 432.577449 -53.023253) (xy 432.613004 -52.985486) (xy 432.653348 -52.952885) (xy 432.697737 -52.926051)
			(xy 432.745353 -52.905477) (xy 432.795316 -52.891545) (xy 432.846707 -52.884509) (xy 432.872642 -52.88407)
			(xy 432.900387 -52.884563) (xy 432.955291 -52.892607) (xy 433.008451 -52.90852) (xy 433.058744 -52.931966)
			(xy 433.105111 -52.96245) (xy 433.146573 -52.999329) (xy 433.182255 -53.041825) (xy 433.197254 -53.065172)
			(xy 433.205615 -53.077809) (xy 433.228365 -53.097807) (xy 433.255973 -53.110268) (xy 433.286019 -53.1141)
			(xy 433.315871 -53.108968) (xy 433.342913 -53.095322) (xy 433.354226 -53.085238) (xy 433.375661 -53.065403)
			(xy 433.423454 -53.031843) (xy 433.475799 -53.00595) (xy 433.531476 -52.988329) (xy 433.589187 -52.97939)
			(xy 433.618386 -52.978812) (xy 433.645641 -52.979234) (xy 433.699596 -52.98699) (xy 433.751899 -53.002345)
			(xy 433.801483 -53.024988) (xy 433.847341 -53.054457) (xy 433.888537 -53.090153) (xy 433.924234 -53.131348)
			(xy 433.953705 -53.177205) (xy 433.97635 -53.226788) (xy 433.991707 -53.27909) (xy 433.999465 -53.333045)
			(xy 433.999465 -53.387555) (xy 433.991707 -53.44151) (xy 433.97635 -53.493812) (xy 433.953705 -53.543395)
			(xy 433.924234 -53.589252) (xy 433.888537 -53.630447) (xy 433.847341 -53.666143) (xy 433.801483 -53.695612)
			(xy 433.751899 -53.718255) (xy 433.699596 -53.73361) (xy 433.645641 -53.741366) (xy 433.618386 -53.741828)
			(xy 433.590229 -53.741343) (xy 433.534526 -53.733076) (xy 433.480643 -53.716709) (xy 433.429753 -53.692597)
			(xy 433.38296 -53.661266) (xy 433.341282 -53.623395) (xy 433.305626 -53.579808) (xy 433.276765 -53.531453)
			(xy 433.26558 -53.505608) (xy 433.261051 -53.495825) (xy 433.245429 -53.480995) (xy 433.225106 -53.473859)
			(xy 433.203641 -53.475669) (xy 433.184799 -53.486106) (xy 433.17795 -53.494432) (xy 433.16017 -53.516276)
			(xy 433.150957 -53.52762) (xy 433.13878 -53.554172) (xy 433.134605 -53.583083) (xy 433.138771 -53.611996)
			(xy 433.150939 -53.638552) (xy 433.16017 -53.64988) (xy 433.177809 -53.670813) (xy 433.207521 -53.716785)
			(xy 433.230358 -53.766532) (xy 433.245849 -53.819033) (xy 433.253677 -53.873209) (xy 433.25415 -53.900578)
			(xy 433.253591 -53.930883) (xy 433.243998 -53.990728) (xy 433.225064 -54.048304) (xy 433.197268 -54.102163)
			(xy 433.161306 -54.150952) (xy 433.140104 -54.172612) (xy 433.130665 -54.182541) (xy 433.11702 -54.206286)
			(xy 433.110167 -54.232801) (xy 433.110597 -54.260184) (xy 433.11828 -54.28647) (xy 433.132664 -54.309775)
			(xy 433.14239 -54.319424) (xy 433.15353 -54.329979) (xy 433.174256 -54.352613) (xy 433.183792 -54.364636)
			(xy 433.193277 -54.375863) (xy 433.217199 -54.392905) (xy 433.244978 -54.402451) (xy 433.274324 -54.403712)
			(xy 433.302819 -54.396586) (xy 433.328116 -54.381659) (xy 433.338478 -54.37124) (xy 433.356615 -54.352319)
			(xy 433.397123 -54.319063) (xy 433.441807 -54.291672) (xy 433.489823 -54.270663) (xy 433.540265 -54.256433)
			(xy 433.592181 -54.249248) (xy 433.618386 -54.248812) (xy 433.645639 -54.249268) (xy 433.699592 -54.257024)
			(xy 433.751891 -54.272379) (xy 433.801472 -54.295022) (xy 433.847326 -54.32449) (xy 433.88852 -54.360185)
			(xy 433.924214 -54.401378) (xy 433.953681 -54.447233) (xy 433.976323 -54.496815) (xy 433.991677 -54.549114)
			(xy 433.999432 -54.603067) (xy 433.999894 -54.63032) (xy 433.999441 -54.657691) (xy 433.99162 -54.71187)
			(xy 433.976128 -54.764374) (xy 433.953284 -54.81412) (xy 433.923556 -54.860087) (xy 433.905914 -54.881018)
			(xy 433.896657 -54.89233) (xy 433.88448 -54.918893) (xy 433.880311 -54.947815) (xy 433.884489 -54.976736)
			(xy 433.896673 -55.003295) (xy 433.905914 -55.014622) (xy 433.923573 -55.03554) (xy 433.953293 -55.081511)
			(xy 433.976135 -55.13126) (xy 433.991628 -55.183764) (xy 433.999454 -55.237944) (xy 433.999452 -55.292686)
			(xy 433.991622 -55.346865) (xy 433.976125 -55.399368) (xy 433.953279 -55.449115) (xy 433.923554 -55.495084)
			(xy 433.905914 -55.516018) (xy 433.896657 -55.52733) (xy 433.88448 -55.553893) (xy 433.880311 -55.582815)
			(xy 433.884489 -55.611736) (xy 433.896673 -55.638295) (xy 433.905914 -55.649622) (xy 433.923573 -55.67054)
			(xy 433.953293 -55.716511) (xy 433.976135 -55.76626) (xy 433.991628 -55.818764) (xy 433.999454 -55.872944)
			(xy 433.999452 -55.927686) (xy 433.991622 -55.981865) (xy 433.976125 -56.034368) (xy 433.953279 -56.084115)
			(xy 433.923554 -56.130084) (xy 433.905914 -56.151018) (xy 433.896657 -56.16233) (xy 433.88448 -56.188893)
			(xy 433.880311 -56.217815) (xy 433.884489 -56.246736) (xy 433.896673 -56.273295) (xy 433.905914 -56.284622)
			(xy 433.923573 -56.30554) (xy 433.953293 -56.351511) (xy 433.976135 -56.40126) (xy 433.991628 -56.453764)
			(xy 433.999454 -56.507944) (xy 433.999452 -56.562686) (xy 433.991622 -56.616865) (xy 433.976125 -56.669368)
			(xy 433.953279 -56.719115) (xy 433.923554 -56.765084) (xy 433.905914 -56.786018) (xy 433.896657 -56.79733)
			(xy 433.88448 -56.823893) (xy 433.880311 -56.852815) (xy 433.884489 -56.881736) (xy 433.886597 -56.88633)
			(xy 440.94303 -56.88633) (xy 440.946755 -56.833083) (xy 440.957867 -56.780876) (xy 440.976147 -56.730727)
			(xy 441.00124 -56.683617) (xy 441.032655 -56.640464) (xy 441.069779 -56.602112) (xy 441.090558 -56.585358)
			(xy 441.102318 -56.57541) (xy 441.119841 -56.550102) (xy 441.129025 -56.520721) (xy 441.129034 -56.489938)
			(xy 441.119868 -56.460552) (xy 441.102359 -56.435234) (xy 441.090558 -56.425338) (xy 441.069823 -56.408528)
			(xy 441.032693 -56.370181) (xy 441.001272 -56.327033) (xy 440.976172 -56.279927) (xy 440.957883 -56.229781)
			(xy 440.946764 -56.177575) (xy 440.94303 -56.12433) (xy 440.946755 -56.071083) (xy 440.957867 -56.018876)
			(xy 440.976147 -55.968727) (xy 441.00124 -55.921617) (xy 441.032655 -55.878464) (xy 441.069779 -55.840112)
			(xy 441.090558 -55.823358) (xy 441.102318 -55.81341) (xy 441.119841 -55.788102) (xy 441.129025 -55.758721)
			(xy 441.129034 -55.727938) (xy 441.119868 -55.698552) (xy 441.102359 -55.673234) (xy 441.090558 -55.663338)
			(xy 441.069823 -55.646528) (xy 441.032693 -55.608181) (xy 441.001272 -55.565033) (xy 440.976172 -55.517927)
			(xy 440.957883 -55.467781) (xy 440.946764 -55.415575) (xy 440.94303 -55.36233) (xy 440.946755 -55.309083)
			(xy 440.957867 -55.256876) (xy 440.976147 -55.206727) (xy 441.00124 -55.159617) (xy 441.032655 -55.116464)
			(xy 441.069779 -55.078112) (xy 441.090558 -55.061358) (xy 441.102318 -55.05141) (xy 441.119841 -55.026102)
			(xy 441.129025 -54.996721) (xy 441.129034 -54.965938) (xy 441.119868 -54.936552) (xy 441.102359 -54.911234)
			(xy 441.090558 -54.901338) (xy 441.069823 -54.884528) (xy 441.032693 -54.846181) (xy 441.001272 -54.803033)
			(xy 440.976172 -54.755927) (xy 440.957883 -54.705781) (xy 440.946764 -54.653575) (xy 440.94303 -54.60033)
			(xy 440.946755 -54.547083) (xy 440.957867 -54.494876) (xy 440.976147 -54.444727) (xy 441.00124 -54.397617)
			(xy 441.032655 -54.354464) (xy 441.069779 -54.316112) (xy 441.090558 -54.299358) (xy 441.102318 -54.28941)
			(xy 441.119841 -54.264102) (xy 441.129025 -54.234721) (xy 441.129034 -54.203938) (xy 441.119868 -54.174552)
			(xy 441.102359 -54.149234) (xy 441.090558 -54.139338) (xy 441.069823 -54.122528) (xy 441.032693 -54.084181)
			(xy 441.001272 -54.041033) (xy 440.976172 -53.993927) (xy 440.957883 -53.943781) (xy 440.946764 -53.891575)
			(xy 440.94303 -53.83833) (xy 440.946755 -53.785083) (xy 440.957867 -53.732876) (xy 440.976147 -53.682727)
			(xy 441.00124 -53.635617) (xy 441.032655 -53.592464) (xy 441.069779 -53.554112) (xy 441.090558 -53.537358)
			(xy 441.102318 -53.52741) (xy 441.119841 -53.502102) (xy 441.129025 -53.472721) (xy 441.129034 -53.441938)
			(xy 441.119868 -53.412552) (xy 441.102359 -53.387234) (xy 441.090558 -53.377338) (xy 441.068084 -53.359136)
			(xy 441.02835 -53.317117) (xy 440.995411 -53.269584) (xy 440.970022 -53.217625) (xy 440.952763 -53.16243)
			(xy 440.94403 -53.105263) (xy 440.943492 -53.076348) (xy 440.944 -53.049096) (xy 440.95175 -52.995147)
			(xy 440.9671 -52.94285) (xy 440.989737 -52.89327) (xy 441.0192 -52.847417) (xy 441.054889 -52.806223)
			(xy 441.096078 -52.770529) (xy 441.141928 -52.74106) (xy 441.191505 -52.718417) (xy 441.2438 -52.703061)
			(xy 441.297748 -52.695303) (xy 441.325 -52.69484) (xy 441.353918 -52.695343) (xy 441.41109 -52.704073)
			(xy 441.46629 -52.721333) (xy 441.518252 -52.746728) (xy 441.565785 -52.779675) (xy 441.607801 -52.819419)
			(xy 441.62599 -52.841906) (xy 441.635887 -52.853711) (xy 441.661211 -52.87123) (xy 441.690604 -52.880406)
			(xy 441.721396 -52.880406) (xy 441.750789 -52.87123) (xy 441.776113 -52.853711) (xy 441.78601 -52.841906)
			(xy 441.804197 -52.819419) (xy 441.846217 -52.779684) (xy 441.893753 -52.746745) (xy 441.945715 -52.721357)
			(xy 442.000914 -52.704102) (xy 442.058084 -52.695374) (xy 442.087 -52.69484) (xy 442.114255 -52.695255)
			(xy 442.16821 -52.703014) (xy 442.220512 -52.718372) (xy 442.270095 -52.741018) (xy 442.315951 -52.770491)
			(xy 442.357145 -52.806189) (xy 442.392838 -52.847388) (xy 442.422305 -52.893247) (xy 442.444945 -52.942833)
			(xy 442.460297 -52.995137) (xy 442.468048 -53.049093) (xy 442.468508 -53.076348) (xy 442.467987 -53.105265)
			(xy 442.464373 -53.128948) (xy 442.747426 -53.128948) (xy 442.747426 -53.074452) (xy 442.755182 -53.020511)
			(xy 442.770535 -52.968223) (xy 442.793173 -52.918652) (xy 442.822636 -52.872808) (xy 442.858323 -52.831623)
			(xy 442.899508 -52.795936) (xy 442.945352 -52.766473) (xy 442.994923 -52.743835) (xy 443.047211 -52.728482)
			(xy 443.101152 -52.720726) (xy 443.1284 -52.72024) (xy 443.157318 -52.720743) (xy 443.21449 -52.729473)
			(xy 443.26969 -52.746733) (xy 443.321652 -52.772128) (xy 443.369185 -52.805075) (xy 443.411201 -52.844819)
			(xy 443.42939 -52.867306) (xy 443.439287 -52.879111) (xy 443.464611 -52.89663) (xy 443.494004 -52.905806)
			(xy 443.524796 -52.905806) (xy 443.554189 -52.89663) (xy 443.579513 -52.879111) (xy 443.58941 -52.867306)
			(xy 443.607597 -52.844819) (xy 443.649617 -52.805084) (xy 443.697153 -52.772145) (xy 443.749115 -52.746757)
			(xy 443.804314 -52.729502) (xy 443.861484 -52.720774) (xy 443.8904 -52.72024) (xy 443.917655 -52.72063)
			(xy 443.971609 -52.728387) (xy 444.023911 -52.743744) (xy 444.073494 -52.766388) (xy 444.11935 -52.795858)
			(xy 444.160546 -52.831554) (xy 444.196242 -52.87275) (xy 444.225712 -52.918606) (xy 444.248356 -52.968189)
			(xy 444.263713 -53.020491) (xy 444.27147 -53.074445) (xy 444.27147 -53.128955) (xy 444.263713 -53.182909)
			(xy 444.248356 -53.235211) (xy 444.225712 -53.284794) (xy 444.196242 -53.33065) (xy 444.160546 -53.371846)
			(xy 444.11935 -53.407542) (xy 444.073494 -53.437012) (xy 444.023911 -53.459656) (xy 443.971609 -53.475013)
			(xy 443.917655 -53.48277) (xy 443.8904 -53.483256) (xy 443.861482 -53.482754) (xy 443.80431 -53.474024)
			(xy 443.74911 -53.456764) (xy 443.697148 -53.431369) (xy 443.649614 -53.398422) (xy 443.607599 -53.358677)
			(xy 443.58941 -53.33619) (xy 443.579513 -53.324385) (xy 443.554189 -53.306866) (xy 443.524796 -53.29769)
			(xy 443.494004 -53.29769) (xy 443.464611 -53.306866) (xy 443.439287 -53.324385) (xy 443.42939 -53.33619)
			(xy 443.411202 -53.358676) (xy 443.369182 -53.398412) (xy 443.321647 -53.431351) (xy 443.269685 -53.456739)
			(xy 443.214486 -53.473994) (xy 443.157316 -53.482722) (xy 443.1284 -53.483256) (xy 443.101152 -53.482674)
			(xy 443.047211 -53.474918) (xy 442.994923 -53.459565) (xy 442.945352 -53.436927) (xy 442.899508 -53.407464)
			(xy 442.858323 -53.371777) (xy 442.822636 -53.330592) (xy 442.793173 -53.284748) (xy 442.770535 -53.235177)
			(xy 442.755182 -53.182889) (xy 442.747426 -53.128948) (xy 442.464373 -53.128948) (xy 442.459263 -53.162438)
			(xy 442.442008 -53.217638) (xy 442.416617 -53.269601) (xy 442.383672 -53.317134) (xy 442.343929 -53.359149)
			(xy 442.321442 -53.377338) (xy 442.309586 -53.387181) (xy 442.292064 -53.412518) (xy 442.282891 -53.441927)
			(xy 442.2829 -53.472732) (xy 442.29209 -53.502135) (xy 442.309627 -53.527462) (xy 442.321442 -53.537358)
			(xy 442.342272 -53.554055) (xy 442.379403 -53.592415) (xy 442.410824 -53.635576) (xy 442.435922 -53.682696)
			(xy 442.454206 -53.732855) (xy 442.46532 -53.785073) (xy 442.469046 -53.83833) (xy 442.465312 -53.891586)
			(xy 442.45419 -53.943802) (xy 442.435898 -53.993958) (xy 442.410793 -54.041074) (xy 442.379365 -54.08423)
			(xy 442.342228 -54.122585) (xy 442.321442 -54.139338) (xy 442.309586 -54.149181) (xy 442.292064 -54.174518)
			(xy 442.282891 -54.203927) (xy 442.2829 -54.234732) (xy 442.29209 -54.264135) (xy 442.309627 -54.289462)
			(xy 442.321442 -54.299358) (xy 442.342272 -54.316055) (xy 442.379403 -54.354415) (xy 442.392021 -54.371748)
			(xy 447.038982 -54.371748) (xy 447.043053 -54.316126) (xy 447.055179 -54.261689) (xy 447.075102 -54.209598)
			(xy 447.102398 -54.160963) (xy 447.136484 -54.11682) (xy 447.176633 -54.078111) (xy 447.221991 -54.04566)
			(xy 447.271591 -54.020159) (xy 447.324375 -54.002152) (xy 447.379218 -53.992022) (xy 447.434952 -53.989985)
			(xy 447.490389 -53.996085) (xy 447.544346 -54.010191) (xy 447.595675 -54.032003) (xy 447.643281 -54.061057)
			(xy 447.686149 -54.096732) (xy 447.723366 -54.138269) (xy 447.754139 -54.184782) (xy 447.777811 -54.235279)
			(xy 447.793879 -54.288686) (xy 447.801999 -54.343862) (xy 447.802508 -54.371748) (xy 447.927982 -54.371748)
			(xy 447.932053 -54.316126) (xy 447.944179 -54.261689) (xy 447.964102 -54.209598) (xy 447.991398 -54.160963)
			(xy 448.025484 -54.11682) (xy 448.065633 -54.078111) (xy 448.110991 -54.04566) (xy 448.160591 -54.020159)
			(xy 448.213375 -54.002152) (xy 448.268218 -53.992022) (xy 448.323952 -53.989985) (xy 448.379389 -53.996085)
			(xy 448.433346 -54.010191) (xy 448.484675 -54.032003) (xy 448.532281 -54.061057) (xy 448.575149 -54.096732)
			(xy 448.612366 -54.138269) (xy 448.643139 -54.184782) (xy 448.666811 -54.235279) (xy 448.682879 -54.288686)
			(xy 448.690999 -54.343862) (xy 448.691508 -54.371748) (xy 448.816982 -54.371748) (xy 448.821053 -54.316126)
			(xy 448.833179 -54.261689) (xy 448.853102 -54.209598) (xy 448.880398 -54.160963) (xy 448.914484 -54.11682)
			(xy 448.954633 -54.078111) (xy 448.999991 -54.04566) (xy 449.049591 -54.020159) (xy 449.102375 -54.002152)
			(xy 449.157218 -53.992022) (xy 449.212952 -53.989985) (xy 449.268389 -53.996085) (xy 449.322346 -54.010191)
			(xy 449.373675 -54.032003) (xy 449.421281 -54.061057) (xy 449.464149 -54.096732) (xy 449.501366 -54.138269)
			(xy 449.532139 -54.184782) (xy 449.555811 -54.235279) (xy 449.571879 -54.288686) (xy 449.579999 -54.343862)
			(xy 449.580508 -54.371748) (xy 449.705982 -54.371748) (xy 449.710053 -54.316126) (xy 449.722179 -54.261689)
			(xy 449.742102 -54.209598) (xy 449.769398 -54.160963) (xy 449.803484 -54.11682) (xy 449.843633 -54.078111)
			(xy 449.888991 -54.04566) (xy 449.938591 -54.020159) (xy 449.991375 -54.002152) (xy 450.046218 -53.992022)
			(xy 450.101952 -53.989985) (xy 450.157389 -53.996085) (xy 450.211346 -54.010191) (xy 450.262675 -54.032003)
			(xy 450.310281 -54.061057) (xy 450.353149 -54.096732) (xy 450.390366 -54.138269) (xy 450.421139 -54.184782)
			(xy 450.444811 -54.235279) (xy 450.460879 -54.288686) (xy 450.468999 -54.343862) (xy 450.469508 -54.371748)
			(xy 450.468999 -54.399634) (xy 450.460879 -54.45481) (xy 450.444811 -54.508217) (xy 450.421139 -54.558714)
			(xy 450.390366 -54.605227) (xy 450.353149 -54.646764) (xy 450.310281 -54.682439) (xy 450.262675 -54.711493)
			(xy 450.211346 -54.733305) (xy 450.157389 -54.747411) (xy 450.101952 -54.753511) (xy 450.046218 -54.751474)
			(xy 449.991375 -54.741344) (xy 449.938591 -54.723337) (xy 449.888991 -54.697836) (xy 449.843633 -54.665385)
			(xy 449.803484 -54.626676) (xy 449.769398 -54.582533) (xy 449.742102 -54.533898) (xy 449.722179 -54.481807)
			(xy 449.710053 -54.42737) (xy 449.705982 -54.371748) (xy 449.580508 -54.371748) (xy 449.579999 -54.399634)
			(xy 449.571879 -54.45481) (xy 449.555811 -54.508217) (xy 449.532139 -54.558714) (xy 449.501366 -54.605227)
			(xy 449.464149 -54.646764) (xy 449.421281 -54.682439) (xy 449.373675 -54.711493) (xy 449.322346 -54.733305)
			(xy 449.268389 -54.747411) (xy 449.212952 -54.753511) (xy 449.157218 -54.751474) (xy 449.102375 -54.741344)
			(xy 449.049591 -54.723337) (xy 448.999991 -54.697836) (xy 448.954633 -54.665385) (xy 448.914484 -54.626676)
			(xy 448.880398 -54.582533) (xy 448.853102 -54.533898) (xy 448.833179 -54.481807) (xy 448.821053 -54.42737)
			(xy 448.816982 -54.371748) (xy 448.691508 -54.371748) (xy 448.690999 -54.399634) (xy 448.682879 -54.45481)
			(xy 448.666811 -54.508217) (xy 448.643139 -54.558714) (xy 448.612366 -54.605227) (xy 448.575149 -54.646764)
			(xy 448.532281 -54.682439) (xy 448.484675 -54.711493) (xy 448.433346 -54.733305) (xy 448.379389 -54.747411)
			(xy 448.323952 -54.753511) (xy 448.268218 -54.751474) (xy 448.213375 -54.741344) (xy 448.160591 -54.723337)
			(xy 448.110991 -54.697836) (xy 448.065633 -54.665385) (xy 448.025484 -54.626676) (xy 447.991398 -54.582533)
			(xy 447.964102 -54.533898) (xy 447.944179 -54.481807) (xy 447.932053 -54.42737) (xy 447.927982 -54.371748)
			(xy 447.802508 -54.371748) (xy 447.801999 -54.399634) (xy 447.793879 -54.45481) (xy 447.777811 -54.508217)
			(xy 447.754139 -54.558714) (xy 447.723366 -54.605227) (xy 447.686149 -54.646764) (xy 447.643281 -54.682439)
			(xy 447.595675 -54.711493) (xy 447.544346 -54.733305) (xy 447.490389 -54.747411) (xy 447.434952 -54.753511)
			(xy 447.379218 -54.751474) (xy 447.324375 -54.741344) (xy 447.271591 -54.723337) (xy 447.221991 -54.697836)
			(xy 447.176633 -54.665385) (xy 447.136484 -54.626676) (xy 447.102398 -54.582533) (xy 447.075102 -54.533898)
			(xy 447.055179 -54.481807) (xy 447.043053 -54.42737) (xy 447.038982 -54.371748) (xy 442.392021 -54.371748)
			(xy 442.410824 -54.397576) (xy 442.435922 -54.444696) (xy 442.454206 -54.494855) (xy 442.46532 -54.547073)
			(xy 442.469046 -54.60033) (xy 442.465312 -54.653586) (xy 442.45419 -54.705802) (xy 442.435898 -54.755958)
			(xy 442.410793 -54.803074) (xy 442.379365 -54.84623) (xy 442.342228 -54.884585) (xy 442.321442 -54.901338)
			(xy 442.309586 -54.911181) (xy 442.292064 -54.936518) (xy 442.282891 -54.965927) (xy 442.2829 -54.996732)
			(xy 442.29209 -55.026135) (xy 442.309627 -55.051462) (xy 442.321442 -55.061358) (xy 442.342272 -55.078055)
			(xy 442.379403 -55.116415) (xy 442.410824 -55.159576) (xy 442.435922 -55.206696) (xy 442.454206 -55.256855)
			(xy 442.46532 -55.309073) (xy 442.469046 -55.36233) (xy 442.465312 -55.415586) (xy 442.45419 -55.467802)
			(xy 442.435898 -55.517958) (xy 442.410793 -55.565074) (xy 442.379365 -55.60823) (xy 442.342228 -55.646585)
			(xy 442.321442 -55.663338) (xy 442.309586 -55.673181) (xy 442.292064 -55.698518) (xy 442.282891 -55.727927)
			(xy 442.2829 -55.758732) (xy 442.29209 -55.788135) (xy 442.309627 -55.813462) (xy 442.321442 -55.823358)
			(xy 442.342272 -55.840055) (xy 442.379403 -55.878415) (xy 442.410824 -55.921576) (xy 442.435922 -55.968696)
			(xy 442.454206 -56.018855) (xy 442.46532 -56.071073) (xy 442.469046 -56.12433) (xy 442.465312 -56.177586)
			(xy 442.45419 -56.229802) (xy 442.435898 -56.279958) (xy 442.410793 -56.327074) (xy 442.379365 -56.37023)
			(xy 442.342228 -56.408585) (xy 442.321442 -56.425338) (xy 442.309586 -56.435181) (xy 442.292064 -56.460518)
			(xy 442.282891 -56.489927) (xy 442.2829 -56.520732) (xy 442.29209 -56.550135) (xy 442.309627 -56.575462)
			(xy 442.321442 -56.585358) (xy 442.342272 -56.602055) (xy 442.379403 -56.640415) (xy 442.410824 -56.683576)
			(xy 442.435922 -56.730696) (xy 442.454206 -56.780855) (xy 442.46532 -56.833073) (xy 442.469046 -56.88633)
			(xy 442.465312 -56.939586) (xy 442.45419 -56.991802) (xy 442.435898 -57.041958) (xy 442.410793 -57.089074)
			(xy 442.379365 -57.13223) (xy 442.342228 -57.170585) (xy 442.321442 -57.187338) (xy 442.309586 -57.197181)
			(xy 442.292064 -57.222518) (xy 442.282891 -57.251927) (xy 442.2829 -57.282732) (xy 442.29209 -57.312135)
			(xy 442.309627 -57.337462) (xy 442.321442 -57.347358) (xy 442.343914 -57.365562) (xy 442.383648 -57.40758)
			(xy 442.416587 -57.455113) (xy 442.441977 -57.507071) (xy 442.459237 -57.562266) (xy 442.463308 -57.588912)
			(xy 444.646304 -57.588912) (xy 444.646776 -57.561542) (xy 444.654592 -57.507363) (xy 444.67008 -57.45486)
			(xy 444.69292 -57.405113) (xy 444.722643 -57.359146) (xy 444.740284 -57.338214) (xy 444.749511 -57.326879)
			(xy 444.761691 -57.300324) (xy 444.765867 -57.271409) (xy 444.761696 -57.242493) (xy 444.74952 -57.215937)
			(xy 444.740284 -57.20461) (xy 444.722657 -57.183667) (xy 444.692935 -57.1377) (xy 444.670091 -57.087955)
			(xy 444.654596 -57.035455) (xy 444.646767 -56.981279) (xy 444.646766 -56.926539) (xy 444.654592 -56.872363)
			(xy 444.670085 -56.819862) (xy 444.692926 -56.770116) (xy 444.722646 -56.724148) (xy 444.740284 -56.703214)
			(xy 444.749511 -56.691879) (xy 444.761691 -56.665324) (xy 444.765867 -56.636409) (xy 444.761696 -56.607493)
			(xy 444.74952 -56.580937) (xy 444.740284 -56.56961) (xy 444.722657 -56.548667) (xy 444.692935 -56.5027)
			(xy 444.670091 -56.452955) (xy 444.654596 -56.400455) (xy 444.646767 -56.346279) (xy 444.646766 -56.291539)
			(xy 444.654592 -56.237363) (xy 444.670085 -56.184862) (xy 444.692926 -56.135116) (xy 444.722646 -56.089148)
			(xy 444.740284 -56.068214) (xy 444.749511 -56.056879) (xy 444.761691 -56.030324) (xy 444.765867 -56.001409)
			(xy 444.761696 -55.972493) (xy 444.74952 -55.945937) (xy 444.740284 -55.93461) (xy 444.722657 -55.913667)
			(xy 444.692935 -55.8677) (xy 444.670091 -55.817955) (xy 444.654596 -55.765455) (xy 444.646767 -55.711279)
			(xy 444.646766 -55.656539) (xy 444.654592 -55.602363) (xy 444.670085 -55.549862) (xy 444.692926 -55.500116)
			(xy 444.722646 -55.454148) (xy 444.740284 -55.433214) (xy 444.749511 -55.421879) (xy 444.761691 -55.395324)
			(xy 444.765867 -55.366409) (xy 444.761696 -55.337493) (xy 444.74952 -55.310937) (xy 444.740284 -55.29961)
			(xy 444.722634 -55.278687) (xy 444.692924 -55.232711) (xy 444.670091 -55.182962) (xy 444.654602 -55.130459)
			(xy 444.646777 -55.076282) (xy 444.646304 -55.048912) (xy 444.646767 -55.021659) (xy 444.654522 -54.967707)
			(xy 444.669877 -54.915409) (xy 444.692519 -54.865828) (xy 444.721987 -54.819974) (xy 444.757681 -54.778781)
			(xy 444.798874 -54.743087) (xy 444.844728 -54.713619) (xy 444.894309 -54.690977) (xy 444.946607 -54.675622)
			(xy 445.000559 -54.667867) (xy 445.027812 -54.667404) (xy 445.054483 -54.66783) (xy 445.107306 -54.67525)
			(xy 445.158579 -54.689958) (xy 445.207304 -54.711667) (xy 445.252528 -54.739952) (xy 445.29337 -54.774263)
			(xy 445.329032 -54.81393) (xy 445.344296 -54.835806) (xy 445.35343 -54.848302) (xy 445.377599 -54.867612)
			(xy 445.406436 -54.87881) (xy 445.437302 -54.88087) (xy 445.467372 -54.873605) (xy 445.493892 -54.857678)
			(xy 445.50457 -54.846474) (xy 445.522735 -54.826673) (xy 445.563685 -54.791879) (xy 445.609115 -54.76318)
			(xy 445.658124 -54.741143) (xy 445.709741 -54.726205) (xy 445.762944 -54.718663) (xy 445.789812 -54.718204)
			(xy 445.817064 -54.718667) (xy 445.871013 -54.726425) (xy 445.923309 -54.741782) (xy 445.972887 -54.764426)
			(xy 446.018738 -54.793894) (xy 446.059929 -54.829588) (xy 446.09562 -54.870781) (xy 446.125086 -54.916634)
			(xy 446.147726 -54.966213) (xy 446.16308 -55.01851) (xy 446.170835 -55.07246) (xy 446.17132 -55.099712)
			(xy 446.17088 -55.127083) (xy 446.163059 -55.181264) (xy 446.147565 -55.233769) (xy 446.124717 -55.283515)
			(xy 446.094985 -55.32948) (xy 446.07734 -55.35041) (xy 446.068088 -55.361727) (xy 446.055908 -55.388288)
			(xy 446.051735 -55.417209) (xy 446.055913 -55.44613) (xy 446.068098 -55.472688) (xy 446.07734 -55.484014)
			(xy 446.094994 -55.504937) (xy 446.124721 -55.550905) (xy 446.147567 -55.600653) (xy 446.163064 -55.653157)
			(xy 446.170892 -55.707337) (xy 446.170891 -55.762081) (xy 446.16306 -55.816261) (xy 446.147561 -55.868764)
			(xy 446.124712 -55.918511) (xy 446.094983 -55.964478) (xy 446.07734 -55.98541) (xy 446.068088 -55.996727)
			(xy 446.055908 -56.023288) (xy 446.051735 -56.052209) (xy 446.055913 -56.08113) (xy 446.068098 -56.107688)
			(xy 446.07734 -56.119014) (xy 446.094994 -56.139937) (xy 446.124721 -56.185905) (xy 446.147567 -56.235653)
			(xy 446.163064 -56.288157) (xy 446.170892 -56.342337) (xy 446.170891 -56.369712) (xy 451.428104 -56.369712)
			(xy 451.428576 -56.342342) (xy 451.436392 -56.288163) (xy 451.45188 -56.23566) (xy 451.47472 -56.185913)
			(xy 451.504443 -56.139946) (xy 451.522084 -56.119014) (xy 451.531311 -56.107679) (xy 451.543491 -56.081124)
			(xy 451.547667 -56.052209) (xy 451.543496 -56.023293) (xy 451.53132 -55.996737) (xy 451.522084 -55.98541)
			(xy 451.504457 -55.964467) (xy 451.474735 -55.9185) (xy 451.451891 -55.868755) (xy 451.436396 -55.816255)
			(xy 451.428567 -55.762079) (xy 451.428566 -55.707339) (xy 451.436392 -55.653163) (xy 451.451885 -55.600662)
			(xy 451.474726 -55.550916) (xy 451.504446 -55.504948) (xy 451.522084 -55.484014) (xy 451.531311 -55.472679)
			(xy 451.543491 -55.446124) (xy 451.547667 -55.417209) (xy 451.543496 -55.388293) (xy 451.53132 -55.361737)
			(xy 451.522084 -55.35041) (xy 451.504434 -55.329487) (xy 451.474724 -55.283511) (xy 451.451891 -55.233762)
			(xy 451.436402 -55.181259) (xy 451.428577 -55.127082) (xy 451.428104 -55.099712) (xy 451.42859 -55.072461)
			(xy 451.436346 -55.018513) (xy 451.451701 -54.966218) (xy 451.474343 -54.916641) (xy 451.503809 -54.870791)
			(xy 451.5395 -54.8296) (xy 451.580691 -54.793909) (xy 451.626541 -54.764443) (xy 451.676118 -54.741801)
			(xy 451.728413 -54.726446) (xy 451.782361 -54.71869) (xy 451.836863 -54.71869) (xy 451.890811 -54.726446)
			(xy 451.943106 -54.741801) (xy 451.992683 -54.764443) (xy 452.038533 -54.793909) (xy 452.079724 -54.8296)
			(xy 452.115415 -54.870791) (xy 452.144881 -54.916641) (xy 452.167523 -54.966218) (xy 452.182878 -55.018513)
			(xy 452.190634 -55.072461) (xy 452.19112 -55.099712) (xy 452.19068 -55.127083) (xy 452.182859 -55.181264)
			(xy 452.167365 -55.233769) (xy 452.144517 -55.283515) (xy 452.114785 -55.32948) (xy 452.09714 -55.35041)
			(xy 452.087888 -55.361727) (xy 452.075708 -55.388288) (xy 452.071535 -55.417209) (xy 452.075713 -55.44613)
			(xy 452.087898 -55.472688) (xy 452.09714 -55.484014) (xy 452.114794 -55.504937) (xy 452.144521 -55.550905)
			(xy 452.167367 -55.600653) (xy 452.182864 -55.653157) (xy 452.190692 -55.707337) (xy 452.190691 -55.762081)
			(xy 452.18286 -55.816261) (xy 452.167361 -55.868764) (xy 452.144512 -55.918511) (xy 452.114783 -55.964478)
			(xy 452.09714 -55.98541) (xy 452.087888 -55.996727) (xy 452.075708 -56.023288) (xy 452.071535 -56.052209)
			(xy 452.075713 -56.08113) (xy 452.087898 -56.107688) (xy 452.09714 -56.119014) (xy 452.114759 -56.139962)
			(xy 452.144472 -56.185931) (xy 452.167312 -56.235675) (xy 452.182808 -56.288172) (xy 452.190643 -56.342344)
			(xy 452.19112 -56.369712) (xy 452.190634 -56.396963) (xy 452.182878 -56.450911) (xy 452.167523 -56.503206)
			(xy 452.144881 -56.552783) (xy 452.115415 -56.598633) (xy 452.079724 -56.639824) (xy 452.038533 -56.675515)
			(xy 451.992683 -56.704981) (xy 451.943106 -56.727623) (xy 451.890811 -56.742978) (xy 451.836863 -56.750734)
			(xy 451.782361 -56.750734) (xy 451.728413 -56.742978) (xy 451.676118 -56.727623) (xy 451.626541 -56.704981)
			(xy 451.580691 -56.675515) (xy 451.5395 -56.639824) (xy 451.503809 -56.598633) (xy 451.474343 -56.552783)
			(xy 451.451701 -56.503206) (xy 451.436346 -56.450911) (xy 451.42859 -56.396963) (xy 451.428104 -56.369712)
			(xy 446.170891 -56.369712) (xy 446.170891 -56.397081) (xy 446.16306 -56.451261) (xy 446.147561 -56.503764)
			(xy 446.124712 -56.553511) (xy 446.094983 -56.599478) (xy 446.07734 -56.62041) (xy 446.068088 -56.631727)
			(xy 446.055908 -56.658288) (xy 446.051735 -56.687209) (xy 446.055913 -56.71613) (xy 446.068098 -56.742688)
			(xy 446.07734 -56.754014) (xy 446.094959 -56.774962) (xy 446.124672 -56.820931) (xy 446.147512 -56.870675)
			(xy 446.163008 -56.923172) (xy 446.170843 -56.977344) (xy 446.17132 -57.004712) (xy 446.170833 -57.031963)
			(xy 446.163076 -57.08591) (xy 446.14772 -57.138204) (xy 446.125078 -57.187781) (xy 446.095611 -57.23363)
			(xy 446.05992 -57.27482) (xy 446.01873 -57.310511) (xy 445.972881 -57.339978) (xy 445.923304 -57.36262)
			(xy 445.87101 -57.377976) (xy 445.817063 -57.385733) (xy 445.789812 -57.38622) (xy 445.762381 -57.385755)
			(xy 445.708084 -57.377911) (xy 445.65547 -57.362369) (xy 445.605626 -57.339449) (xy 445.55958 -57.309624)
			(xy 445.518282 -57.27351) (xy 445.482584 -57.231852) (xy 445.453222 -57.185509) (xy 445.441578 -57.160668)
			(xy 445.436517 -57.15084) (xy 445.419862 -57.13635) (xy 445.398659 -57.130199) (xy 445.376835 -57.133527)
			(xy 445.358428 -57.145717) (xy 445.35217 -57.154826) (xy 445.343856 -57.167909) (xy 445.325419 -57.192833)
			(xy 445.31534 -57.20461) (xy 445.306088 -57.215927) (xy 445.293908 -57.242488) (xy 445.289735 -57.271409)
			(xy 445.293913 -57.30033) (xy 445.306098 -57.326888) (xy 445.31534 -57.338214) (xy 445.332959 -57.359162)
			(xy 445.362672 -57.405131) (xy 445.385512 -57.454875) (xy 445.401008 -57.507372) (xy 445.408843 -57.561544)
			(xy 445.40932 -57.588912) (xy 445.408834 -57.616163) (xy 445.405448 -57.639712) (xy 452.723504 -57.639712)
			(xy 452.723976 -57.612342) (xy 452.731792 -57.558163) (xy 452.74728 -57.50566) (xy 452.77012 -57.455913)
			(xy 452.799843 -57.409946) (xy 452.817484 -57.389014) (xy 452.826711 -57.377679) (xy 452.838891 -57.351124)
			(xy 452.843067 -57.322209) (xy 452.838896 -57.293293) (xy 452.82672 -57.266737) (xy 452.817484 -57.25541)
			(xy 452.799857 -57.234467) (xy 452.770135 -57.1885) (xy 452.747291 -57.138755) (xy 452.731796 -57.086255)
			(xy 452.723967 -57.032079) (xy 452.723966 -56.977339) (xy 452.731792 -56.923163) (xy 452.747285 -56.870662)
			(xy 452.770126 -56.820916) (xy 452.799846 -56.774948) (xy 452.817484 -56.754014) (xy 452.826711 -56.742679)
			(xy 452.838891 -56.716124) (xy 452.843067 -56.687209) (xy 452.838896 -56.658293) (xy 452.82672 -56.631737)
			(xy 452.817484 -56.62041) (xy 452.799857 -56.599467) (xy 452.770135 -56.5535) (xy 452.747291 -56.503755)
			(xy 452.731796 -56.451255) (xy 452.723967 -56.397079) (xy 452.723966 -56.342339) (xy 452.731792 -56.288163)
			(xy 452.747285 -56.235662) (xy 452.770126 -56.185916) (xy 452.799846 -56.139948) (xy 452.817484 -56.119014)
			(xy 452.826711 -56.107679) (xy 452.838891 -56.081124) (xy 452.843067 -56.052209) (xy 452.838896 -56.023293)
			(xy 452.82672 -55.996737) (xy 452.817484 -55.98541) (xy 452.799857 -55.964467) (xy 452.770135 -55.9185)
			(xy 452.747291 -55.868755) (xy 452.731796 -55.816255) (xy 452.723967 -55.762079) (xy 452.723966 -55.707339)
			(xy 452.731792 -55.653163) (xy 452.747285 -55.600662) (xy 452.770126 -55.550916) (xy 452.799846 -55.504948)
			(xy 452.817484 -55.484014) (xy 452.826711 -55.472679) (xy 452.838891 -55.446124) (xy 452.843067 -55.417209)
			(xy 452.838896 -55.388293) (xy 452.82672 -55.361737) (xy 452.817484 -55.35041) (xy 452.799834 -55.329487)
			(xy 452.770124 -55.283511) (xy 452.747291 -55.233762) (xy 452.731802 -55.181259) (xy 452.723977 -55.127082)
			(xy 452.723504 -55.099712) (xy 452.72399 -55.072461) (xy 452.731746 -55.018513) (xy 452.747101 -54.966218)
			(xy 452.769743 -54.916641) (xy 452.799209 -54.870791) (xy 452.8349 -54.8296) (xy 452.876091 -54.793909)
			(xy 452.921941 -54.764443) (xy 452.971518 -54.741801) (xy 453.023813 -54.726446) (xy 453.077761 -54.71869)
			(xy 453.132263 -54.71869) (xy 453.186211 -54.726446) (xy 453.238506 -54.741801) (xy 453.288083 -54.764443)
			(xy 453.333933 -54.793909) (xy 453.375124 -54.8296) (xy 453.410815 -54.870791) (xy 453.440281 -54.916641)
			(xy 453.462923 -54.966218) (xy 453.478278 -55.018513) (xy 453.486034 -55.072461) (xy 453.48652 -55.099712)
			(xy 453.48608 -55.127083) (xy 453.478259 -55.181264) (xy 453.462765 -55.233769) (xy 453.439917 -55.283515)
			(xy 453.410185 -55.32948) (xy 453.39254 -55.35041) (xy 453.383288 -55.361727) (xy 453.371108 -55.388288)
			(xy 453.366935 -55.417209) (xy 453.371113 -55.44613) (xy 453.383298 -55.472688) (xy 453.39254 -55.484014)
			(xy 453.410194 -55.504937) (xy 453.439921 -55.550905) (xy 453.462767 -55.600653) (xy 453.478264 -55.653157)
			(xy 453.486092 -55.707337) (xy 453.486091 -55.762081) (xy 453.47826 -55.816261) (xy 453.462761 -55.868764)
			(xy 453.439912 -55.918511) (xy 453.410183 -55.964478) (xy 453.39254 -55.98541) (xy 453.383288 -55.996727)
			(xy 453.371108 -56.023288) (xy 453.366935 -56.052209) (xy 453.371113 -56.08113) (xy 453.383298 -56.107688)
			(xy 453.39254 -56.119014) (xy 453.410194 -56.139937) (xy 453.439921 -56.185905) (xy 453.462767 -56.235653)
			(xy 453.478264 -56.288157) (xy 453.486092 -56.342337) (xy 453.486091 -56.397081) (xy 453.47826 -56.451261)
			(xy 453.462761 -56.503764) (xy 453.439912 -56.553511) (xy 453.410183 -56.599478) (xy 453.39254 -56.62041)
			(xy 453.383288 -56.631727) (xy 453.371108 -56.658288) (xy 453.366935 -56.687209) (xy 453.371113 -56.71613)
			(xy 453.383298 -56.742688) (xy 453.39254 -56.754014) (xy 453.410194 -56.774937) (xy 453.439921 -56.820905)
			(xy 453.462767 -56.870653) (xy 453.478264 -56.923157) (xy 453.486092 -56.977337) (xy 453.486091 -57.032081)
			(xy 453.47826 -57.086261) (xy 453.462761 -57.138764) (xy 453.439912 -57.188511) (xy 453.410183 -57.234478)
			(xy 453.39254 -57.25541) (xy 453.383288 -57.266727) (xy 453.371108 -57.293288) (xy 453.366935 -57.322209)
			(xy 453.371113 -57.35113) (xy 453.383298 -57.377688) (xy 453.39254 -57.389014) (xy 453.410159 -57.409962)
			(xy 453.439872 -57.455931) (xy 453.462712 -57.505675) (xy 453.478208 -57.558172) (xy 453.486043 -57.612344)
			(xy 453.48652 -57.639712) (xy 453.486034 -57.666963) (xy 453.478278 -57.720911) (xy 453.462923 -57.773206)
			(xy 453.440281 -57.822783) (xy 453.410815 -57.868633) (xy 453.375124 -57.909824) (xy 453.333933 -57.945515)
			(xy 453.288083 -57.974981) (xy 453.238506 -57.997623) (xy 453.186211 -58.012978) (xy 453.132263 -58.020734)
			(xy 453.077761 -58.020734) (xy 453.023813 -58.012978) (xy 452.971518 -57.997623) (xy 452.921941 -57.974981)
			(xy 452.876091 -57.945515) (xy 452.8349 -57.909824) (xy 452.799209 -57.868633) (xy 452.769743 -57.822783)
			(xy 452.747101 -57.773206) (xy 452.731746 -57.720911) (xy 452.72399 -57.666963) (xy 452.723504 -57.639712)
			(xy 445.405448 -57.639712) (xy 445.401078 -57.670111) (xy 445.385723 -57.722406) (xy 445.363081 -57.771983)
			(xy 445.333615 -57.817833) (xy 445.297924 -57.859024) (xy 445.256733 -57.894715) (xy 445.210883 -57.924181)
			(xy 445.161306 -57.946823) (xy 445.109011 -57.962178) (xy 445.055063 -57.969934) (xy 445.000561 -57.969934)
			(xy 444.946613 -57.962178) (xy 444.894318 -57.946823) (xy 444.844741 -57.924181) (xy 444.798891 -57.894715)
			(xy 444.7577 -57.859024) (xy 444.722009 -57.817833) (xy 444.692543 -57.771983) (xy 444.669901 -57.722406)
			(xy 444.654546 -57.670111) (xy 444.64679 -57.616163) (xy 444.646304 -57.588912) (xy 442.463308 -57.588912)
			(xy 442.46797 -57.619433) (xy 442.468508 -57.648348) (xy 442.468067 -57.6756) (xy 442.460304 -57.72955)
			(xy 442.444943 -57.781845) (xy 442.422296 -57.831423) (xy 442.392825 -57.877273) (xy 442.357129 -57.918463)
			(xy 442.315934 -57.954153) (xy 442.270081 -57.983619) (xy 442.2205 -58.006259) (xy 442.168203 -58.021614)
			(xy 442.114252 -58.02937) (xy 442.087 -58.029856) (xy 442.058082 -58.029354) (xy 442.00091 -58.020624)
			(xy 441.94571 -58.003364) (xy 441.893748 -57.977969) (xy 441.846214 -57.945022) (xy 441.804199 -57.905277)
			(xy 441.78601 -57.88279) (xy 441.776113 -57.870985) (xy 441.750789 -57.853466) (xy 441.721396 -57.84429)
			(xy 441.690604 -57.84429) (xy 441.661211 -57.853466) (xy 441.635887 -57.870985) (xy 441.62599 -57.88279)
			(xy 441.607802 -57.905276) (xy 441.565782 -57.945012) (xy 441.518247 -57.977951) (xy 441.466285 -58.003339)
			(xy 441.411086 -58.020594) (xy 441.353916 -58.029322) (xy 441.325 -58.029856) (xy 441.297751 -58.029322)
			(xy 441.243807 -58.021567) (xy 441.191516 -58.006214) (xy 441.141942 -57.983577) (xy 441.096094 -57.954115)
			(xy 441.054905 -57.918429) (xy 441.019214 -57.877244) (xy 440.989746 -57.8314) (xy 440.967102 -57.781829)
			(xy 440.951743 -57.72954) (xy 440.943981 -57.675597) (xy 440.943492 -57.648348) (xy 440.94401 -57.619431)
			(xy 440.952734 -57.562258) (xy 440.96999 -57.507058) (xy 440.995382 -57.455095) (xy 441.028327 -57.407562)
			(xy 441.068071 -57.365547) (xy 441.090558 -57.347358) (xy 441.102318 -57.33741) (xy 441.119841 -57.312102)
			(xy 441.129025 -57.282721) (xy 441.129034 -57.251938) (xy 441.119868 -57.222552) (xy 441.102359 -57.197234)
			(xy 441.090558 -57.187338) (xy 441.069823 -57.170528) (xy 441.032693 -57.132181) (xy 441.001272 -57.089033)
			(xy 440.976172 -57.041927) (xy 440.957883 -56.991781) (xy 440.946764 -56.939575) (xy 440.94303 -56.88633)
			(xy 433.886597 -56.88633) (xy 433.896673 -56.908295) (xy 433.905914 -56.919622) (xy 433.923532 -56.940571)
			(xy 433.953247 -56.986539) (xy 433.976086 -57.036283) (xy 433.991582 -57.088779) (xy 433.999417 -57.142952)
			(xy 433.999894 -57.17032) (xy 433.999408 -57.197571) (xy 433.991652 -57.251519) (xy 433.976297 -57.303814)
			(xy 433.953655 -57.353391) (xy 433.924189 -57.399241) (xy 433.888498 -57.440432) (xy 433.847307 -57.476123)
			(xy 433.801457 -57.505589) (xy 433.75188 -57.528231) (xy 433.699585 -57.543586) (xy 433.645637 -57.551342)
			(xy 433.591135 -57.551342) (xy 433.537187 -57.543586) (xy 433.484892 -57.528231) (xy 433.435315 -57.505589)
			(xy 433.389465 -57.476123) (xy 433.348274 -57.440432) (xy 433.312583 -57.399241) (xy 433.283117 -57.353391)
			(xy 433.260475 -57.303814) (xy 433.24512 -57.251519) (xy 433.237364 -57.197571) (xy 433.236878 -57.17032)
			(xy 433.237337 -57.142949) (xy 433.245153 -57.088769) (xy 433.260643 -57.036265) (xy 433.283487 -56.986518)
			(xy 433.313215 -56.940553) (xy 433.330858 -56.919622) (xy 433.340071 -56.908278) (xy 433.352244 -56.881726)
			(xy 433.356417 -56.852815) (xy 433.352252 -56.823904) (xy 433.340087 -56.797347) (xy 433.330858 -56.786018)
			(xy 433.330604 -56.785764) (xy 433.320196 -56.774568) (xy 433.294269 -56.758405) (xy 433.264722 -56.750633)
			(xy 433.234198 -56.751946) (xy 433.205427 -56.762227) (xy 433.180983 -56.780556) (xy 433.1716 -56.792622)
			(xy 433.156153 -56.813153) (xy 433.120646 -56.850289) (xy 433.080475 -56.882323) (xy 433.036368 -56.908674)
			(xy 432.989122 -56.928866) (xy 432.939594 -56.942534) (xy 432.88868 -56.949429) (xy 432.86299 -56.949848)
			(xy 432.83574 -56.949332) (xy 432.781796 -56.941575) (xy 432.729504 -56.92622) (xy 432.679929 -56.903581)
			(xy 432.634081 -56.874117) (xy 432.592892 -56.838429) (xy 432.557201 -56.797243) (xy 432.527733 -56.751397)
			(xy 432.50509 -56.701824) (xy 432.489732 -56.649534) (xy 432.481971 -56.59559) (xy 432.481482 -56.56834)
			(xy 432.481903 -56.541695) (xy 432.489309 -56.488921) (xy 432.503997 -56.437695) (xy 432.525678 -56.389015)
			(xy 432.553931 -56.34383) (xy 432.588205 -56.303023) (xy 432.60772 -56.284876) (xy 432.617643 -56.275375)
			(xy 432.632425 -56.252231) (xy 432.64051 -56.225985) (xy 432.641313 -56.198534) (xy 432.634776 -56.171861)
			(xy 432.621371 -56.147892) (xy 432.612038 -56.13781) (xy 432.604111 -56.129693) (xy 432.589114 -56.112665)
			(xy 432.582066 -56.103774) (xy 432.572169 -56.091969) (xy 432.546845 -56.07445) (xy 432.517452 -56.065274)
			(xy 432.48666 -56.065274) (xy 432.457267 -56.07445) (xy 432.431943 -56.091969) (xy 432.422046 -56.103774)
			(xy 432.403822 -56.12623) (xy 432.36181 -56.165968) (xy 432.314282 -56.198911) (xy 432.262327 -56.224304)
			(xy 432.207135 -56.241566) (xy 432.14997 -56.250302) (xy 432.121056 -56.25084) (xy 432.092423 -56.250308)
			(xy 432.035799 -56.241768) (xy 431.981088 -56.224857) (xy 431.929522 -56.199954) (xy 431.882259 -56.167621)
			(xy 431.86096 -56.148478) (xy 431.849747 -56.13867) (xy 431.823058 -56.125462) (xy 431.793693 -56.120517)
			(xy 431.76415 -56.124254) (xy 431.736942 -56.136357) (xy 431.725324 -56.145684) (xy 431.704466 -56.1631)
			(xy 431.658712 -56.192416) (xy 431.609259 -56.214937) (xy 431.55711 -56.230207) (xy 431.50332 -56.237916)
			(xy 431.47615 -56.238394) (xy 431.448781 -56.2379) (xy 431.394603 -56.230089) (xy 431.3421 -56.214607)
			(xy 431.292353 -56.191771) (xy 431.246385 -56.162052) (xy 431.225452 -56.144414) (xy 431.214124 -56.135178)
			(xy 431.187567 -56.123002) (xy 431.15865 -56.118829) (xy 431.129733 -56.123002) (xy 431.103176 -56.135178)
			(xy 431.091848 -56.144414) (xy 431.070915 -56.162055) (xy 431.024947 -56.191779) (xy 430.975201 -56.214625)
			(xy 430.922699 -56.230121) (xy 430.868521 -56.23795) (xy 430.813779 -56.23795) (xy 430.759601 -56.230121)
			(xy 430.707099 -56.214625) (xy 430.657353 -56.191779) (xy 430.611385 -56.162055) (xy 430.590452 -56.144414)
			(xy 430.579124 -56.135178) (xy 430.552567 -56.123002) (xy 430.52365 -56.118829) (xy 430.494733 -56.123002)
			(xy 430.468176 -56.135178) (xy 430.456848 -56.144414) (xy 430.43591 -56.162046) (xy 430.389939 -56.191759)
			(xy 430.340193 -56.214596) (xy 430.287693 -56.230088) (xy 430.233519 -56.237919) (xy 430.20615 -56.238394)
			(xy 430.178898 -56.237898) (xy 430.124947 -56.230148) (xy 430.072649 -56.214797) (xy 430.023068 -56.19216)
			(xy 429.977214 -56.162695) (xy 429.936021 -56.127005) (xy 429.900326 -56.085815) (xy 429.870858 -56.039963)
			(xy 429.848215 -55.990385) (xy 429.83286 -55.938088) (xy 429.825104 -55.884138) (xy 429.824642 -55.856886)
			(xy 429.82509 -55.829515) (xy 429.83291 -55.775335) (xy 429.848403 -55.722831) (xy 429.871249 -55.673084)
			(xy 429.900978 -55.627119) (xy 429.918622 -55.606188) (xy 429.927871 -55.59487) (xy 429.940044 -55.568309)
			(xy 429.944213 -55.539389) (xy 429.940038 -55.510471) (xy 429.927859 -55.483912) (xy 429.918622 -55.472584)
			(xy 429.901012 -55.451628) (xy 429.871295 -55.405662) (xy 429.848453 -55.355921) (xy 429.832955 -55.303425)
			(xy 429.82512 -55.249254) (xy 429.824642 -55.221886) (xy 429.825083 -55.195161) (xy 429.832537 -55.142234)
			(xy 429.847296 -55.090863) (xy 429.869073 -55.042052) (xy 429.897442 -54.996753) (xy 429.914304 -54.976014)
			(xy 429.922662 -54.9654) (xy 429.934098 -54.940939) (xy 429.938707 -54.914332) (xy 429.936164 -54.88745)
			(xy 429.926649 -54.862179) (xy 429.910829 -54.840296) (xy 429.900588 -54.831488) (xy 429.878857 -54.813288)
			(xy 429.840524 -54.771532) (xy 429.808792 -54.724563) (xy 429.78436 -54.673416) (xy 429.767766 -54.619216)
			(xy 429.759375 -54.563158) (xy 429.758856 -54.534816) (xy 429.38446 -54.534816) (xy 429.38446 -59.210448)
			(xy 429.592994 -59.418982) (xy 462.938622 -59.418982) (xy 462.939072 -59.391611) (xy 462.946893 -59.337431)
			(xy 462.962386 -59.284928) (xy 462.985231 -59.235181) (xy 463.014959 -59.189215) (xy 463.032602 -59.168284)
			(xy 463.041856 -59.15697) (xy 463.054031 -59.130407) (xy 463.0582 -59.101486) (xy 463.054023 -59.072567)
			(xy 463.041841 -59.046007) (xy 463.032602 -59.03468) (xy 463.014945 -59.013761) (xy 462.985223 -58.96779)
			(xy 462.96238 -58.918042) (xy 462.946886 -58.865538) (xy 462.93906 -58.811358) (xy 462.939062 -58.756615)
			(xy 462.946892 -58.702436) (xy 462.962389 -58.649933) (xy 462.985236 -58.600186) (xy 463.014961 -58.554217)
			(xy 463.032602 -58.533284) (xy 463.041856 -58.52197) (xy 463.054031 -58.495407) (xy 463.0582 -58.466486)
			(xy 463.054023 -58.437567) (xy 463.041841 -58.411007) (xy 463.032602 -58.39968) (xy 463.014987 -58.378728)
			(xy 462.985272 -58.332761) (xy 462.962431 -58.283018) (xy 462.946934 -58.230522) (xy 462.9391 -58.17635)
			(xy 462.938622 -58.148982) (xy 462.939156 -58.120244) (xy 462.947779 -58.063418) (xy 462.964828 -58.008528)
			(xy 462.989917 -57.956816) (xy 463.022478 -57.909452) (xy 463.041746 -57.888124) (xy 463.051837 -57.876605)
			(xy 463.065181 -57.849054) (xy 463.069763 -57.818787) (xy 463.065173 -57.788521) (xy 463.051822 -57.760973)
			(xy 463.041746 -57.74944) (xy 463.022456 -57.728129) (xy 462.98989 -57.680765) (xy 462.964798 -57.62905)
			(xy 462.947748 -57.574157) (xy 462.939127 -57.517327) (xy 462.939129 -57.459847) (xy 462.947754 -57.403017)
			(xy 462.964807 -57.348125) (xy 462.989903 -57.296413) (xy 463.022473 -57.24905) (xy 463.041746 -57.227724)
			(xy 463.051837 -57.216205) (xy 463.065181 -57.188654) (xy 463.069763 -57.158387) (xy 463.065173 -57.128121)
			(xy 463.051822 -57.100573) (xy 463.041746 -57.08904) (xy 463.022468 -57.067719) (xy 462.989902 -57.020356)
			(xy 462.964811 -56.968642) (xy 462.947762 -56.91375) (xy 462.939142 -56.856921) (xy 462.938622 -56.828182)
			(xy 462.939038 -56.800927) (xy 462.946798 -56.746973) (xy 462.962158 -56.694672) (xy 462.984805 -56.64509)
			(xy 463.014278 -56.599236) (xy 463.049976 -56.558042) (xy 463.091174 -56.522349) (xy 463.137032 -56.492882)
			(xy 463.186618 -56.470241) (xy 463.23892 -56.454888) (xy 463.292875 -56.447135) (xy 463.32013 -56.446674)
			(xy 463.349046 -56.447215) (xy 463.406218 -56.455935) (xy 463.461417 -56.473187) (xy 463.51338 -56.498574)
			(xy 463.560914 -56.531515) (xy 463.60293 -56.571255) (xy 463.62112 -56.59374) (xy 463.631017 -56.605545)
			(xy 463.656341 -56.623064) (xy 463.685734 -56.63224) (xy 463.716526 -56.63224) (xy 463.745919 -56.623064)
			(xy 463.771243 -56.605545) (xy 463.78114 -56.59374) (xy 463.799319 -56.571246) (xy 463.84134 -56.531509)
			(xy 463.888877 -56.49857) (xy 463.940841 -56.473184) (xy 463.996041 -56.45593) (xy 464.053213 -56.447206)
			(xy 464.08213 -56.446674) (xy 464.110869 -56.447186) (xy 464.167697 -56.455813) (xy 464.222587 -56.472866)
			(xy 464.274299 -56.49796) (xy 464.321661 -56.530527) (xy 464.342988 -56.549798) (xy 464.354522 -56.55987)
			(xy 464.382068 -56.573212) (xy 464.41233 -56.577797) (xy 464.442592 -56.573212) (xy 464.470138 -56.55987)
			(xy 464.481672 -56.549798) (xy 464.502999 -56.530528) (xy 464.550362 -56.497963) (xy 464.602073 -56.472872)
			(xy 464.656964 -56.455822) (xy 464.713791 -56.4472) (xy 464.771269 -56.4472) (xy 464.828096 -56.455822)
			(xy 464.882987 -56.472872) (xy 464.934698 -56.497963) (xy 464.982061 -56.530528) (xy 465.003388 -56.549798)
			(xy 465.014922 -56.55987) (xy 465.042468 -56.573212) (xy 465.07273 -56.577797) (xy 465.102992 -56.573212)
			(xy 465.130538 -56.55987) (xy 465.142072 -56.549798) (xy 465.163399 -56.530528) (xy 465.210762 -56.497963)
			(xy 465.262473 -56.472872) (xy 465.317364 -56.455822) (xy 465.374191 -56.4472) (xy 465.431669 -56.4472)
			(xy 465.488496 -56.455822) (xy 465.543387 -56.472872) (xy 465.595098 -56.497963) (xy 465.642461 -56.530528)
			(xy 465.663788 -56.549798) (xy 465.675322 -56.55987) (xy 465.702868 -56.573212) (xy 465.73313 -56.577797)
			(xy 465.763392 -56.573212) (xy 465.790938 -56.55987) (xy 465.802472 -56.549798) (xy 465.823796 -56.530523)
			(xy 465.871158 -56.497955) (xy 465.92287 -56.472863) (xy 465.977762 -56.455813) (xy 466.034591 -56.447193)
			(xy 466.06333 -56.446674) (xy 466.092246 -56.447215) (xy 466.149418 -56.455935) (xy 466.204617 -56.473187)
			(xy 466.25658 -56.498574) (xy 466.304114 -56.531515) (xy 466.34613 -56.571255) (xy 466.36432 -56.59374)
			(xy 466.374217 -56.605545) (xy 466.399541 -56.623064) (xy 466.428934 -56.63224) (xy 466.459726 -56.63224)
			(xy 466.489119 -56.623064) (xy 466.514443 -56.605545) (xy 466.52434 -56.59374) (xy 466.542519 -56.571246)
			(xy 466.58454 -56.531509) (xy 466.632077 -56.49857) (xy 466.684041 -56.473184) (xy 466.739241 -56.45593)
			(xy 466.796413 -56.447206) (xy 466.82533 -56.446674) (xy 466.852581 -56.44715) (xy 466.906528 -56.45491)
			(xy 466.958822 -56.470268) (xy 467.008398 -56.492911) (xy 467.054248 -56.522379) (xy 467.095437 -56.558071)
			(xy 467.131128 -56.599262) (xy 467.160594 -56.645112) (xy 467.183236 -56.694689) (xy 467.198593 -56.746983)
			(xy 467.206351 -56.800931) (xy 467.206838 -56.828182) (xy 467.206293 -56.85692) (xy 467.197674 -56.913746)
			(xy 467.180628 -56.968636) (xy 467.155542 -57.020348) (xy 467.122982 -57.067712) (xy 467.103714 -57.08904)
			(xy 467.093661 -57.100589) (xy 467.080319 -57.12813) (xy 467.075732 -57.158387) (xy 467.080311 -57.188645)
			(xy 467.093646 -57.21619) (xy 467.103714 -57.227724) (xy 467.122965 -57.249067) (xy 467.155528 -57.296428)
			(xy 467.180618 -57.348137) (xy 467.197667 -57.403025) (xy 467.206291 -57.459849) (xy 467.206293 -57.517324)
			(xy 467.197673 -57.574149) (xy 467.180628 -57.629038) (xy 467.155541 -57.680749) (xy 467.122982 -57.728112)
			(xy 467.103714 -57.74944) (xy 467.093661 -57.760989) (xy 467.080319 -57.78853) (xy 467.075732 -57.818787)
			(xy 467.080311 -57.849045) (xy 467.093646 -57.87659) (xy 467.103714 -57.888124) (xy 467.122968 -57.909465)
			(xy 467.155539 -57.956823) (xy 467.180635 -58.008531) (xy 467.197689 -58.063418) (xy 467.206316 -58.120244)
			(xy 467.206838 -58.148982) (xy 467.206376 -58.176353) (xy 467.19856 -58.230532) (xy 467.183071 -58.283036)
			(xy 467.160227 -58.332783) (xy 467.130501 -58.378749) (xy 467.112858 -58.39968) (xy 467.103642 -58.411022)
			(xy 467.091467 -58.437575) (xy 467.087293 -58.466486) (xy 467.09146 -58.495399) (xy 467.103627 -58.521955)
			(xy 467.112858 -58.533284) (xy 467.130482 -58.554231) (xy 467.160208 -58.600196) (xy 467.183056 -58.64994)
			(xy 467.198554 -58.70244) (xy 467.206385 -58.756617) (xy 467.206387 -58.811356) (xy 467.19856 -58.865534)
			(xy 467.183065 -58.918035) (xy 467.160221 -58.96778) (xy 467.130498 -59.013748) (xy 467.112858 -59.03468)
			(xy 467.103642 -59.046022) (xy 467.091467 -59.072575) (xy 467.087293 -59.101486) (xy 467.09146 -59.130399)
			(xy 467.103627 -59.156955) (xy 467.112858 -59.168284) (xy 467.130497 -59.189217) (xy 467.16021 -59.235189)
			(xy 467.183047 -59.284936) (xy 467.198538 -59.337437) (xy 467.206365 -59.391613) (xy 467.206838 -59.418982)
			(xy 467.206305 -59.446231) (xy 467.198552 -59.500176) (xy 467.1832 -59.552468) (xy 467.160564 -59.602043)
			(xy 467.131102 -59.647892) (xy 467.095416 -59.689082) (xy 467.05423 -59.724773) (xy 467.008385 -59.754241)
			(xy 466.958813 -59.776884) (xy 466.906523 -59.792242) (xy 466.852579 -59.800002) (xy 466.82533 -59.80049)
			(xy 466.796414 -59.799954) (xy 466.739243 -59.791229) (xy 466.684045 -59.773975) (xy 466.632083 -59.748587)
			(xy 466.584548 -59.715646) (xy 466.542531 -59.675908) (xy 466.52434 -59.653424) (xy 466.514443 -59.641619)
			(xy 466.489119 -59.6241) (xy 466.459726 -59.614924) (xy 466.428934 -59.614924) (xy 466.399541 -59.6241)
			(xy 466.374217 -59.641619) (xy 466.36432 -59.653424) (xy 466.346124 -59.675903) (xy 466.304104 -59.715637)
			(xy 466.25657 -59.748576) (xy 466.20461 -59.773965) (xy 466.149414 -59.791223) (xy 466.092246 -59.799954)
			(xy 466.06333 -59.80049) (xy 466.034592 -59.799951) (xy 465.977765 -59.791332) (xy 465.922874 -59.774286)
			(xy 465.871162 -59.749198) (xy 465.823799 -59.716636) (xy 465.802472 -59.697366) (xy 465.790938 -59.687294)
			(xy 465.763392 -59.673952) (xy 465.73313 -59.669367) (xy 465.702868 -59.673952) (xy 465.675322 -59.687294)
			(xy 465.663788 -59.697366) (xy 465.642461 -59.716636) (xy 465.595098 -59.749201) (xy 465.543387 -59.774292)
			(xy 465.488496 -59.791342) (xy 465.431669 -59.799964) (xy 465.374191 -59.799964) (xy 465.317364 -59.791342)
			(xy 465.262473 -59.774292) (xy 465.210762 -59.749201) (xy 465.163399 -59.716636) (xy 465.142072 -59.697366)
			(xy 465.130538 -59.687294) (xy 465.102992 -59.673952) (xy 465.07273 -59.669367) (xy 465.042468 -59.673952)
			(xy 465.014922 -59.687294) (xy 465.003388 -59.697366) (xy 464.982061 -59.716636) (xy 464.934698 -59.749201)
			(xy 464.882987 -59.774292) (xy 464.828096 -59.791342) (xy 464.771269 -59.799964) (xy 464.713791 -59.799964)
			(xy 464.656964 -59.791342) (xy 464.602073 -59.774292) (xy 464.550362 -59.749201) (xy 464.502999 -59.716636)
			(xy 464.481672 -59.697366) (xy 464.470138 -59.687294) (xy 464.442592 -59.673952) (xy 464.41233 -59.669367)
			(xy 464.382068 -59.673952) (xy 464.354522 -59.687294) (xy 464.342988 -59.697366) (xy 464.321649 -59.716623)
			(xy 464.27429 -59.749191) (xy 464.222582 -59.774286) (xy 464.167694 -59.79134) (xy 464.110868 -59.799967)
			(xy 464.08213 -59.80049) (xy 464.053214 -59.799954) (xy 463.996043 -59.791229) (xy 463.940845 -59.773975)
			(xy 463.888883 -59.748587) (xy 463.841348 -59.715646) (xy 463.799331 -59.675908) (xy 463.78114 -59.653424)
			(xy 463.771243 -59.641619) (xy 463.745919 -59.6241) (xy 463.716526 -59.614924) (xy 463.685734 -59.614924)
			(xy 463.656341 -59.6241) (xy 463.631017 -59.641619) (xy 463.62112 -59.653424) (xy 463.602924 -59.675903)
			(xy 463.560904 -59.715637) (xy 463.51337 -59.748576) (xy 463.46141 -59.773965) (xy 463.406214 -59.791223)
			(xy 463.349046 -59.799954) (xy 463.32013 -59.80049) (xy 463.292877 -59.800017) (xy 463.238926 -59.792263)
			(xy 463.186627 -59.77691) (xy 463.137046 -59.75427) (xy 463.091191 -59.724803) (xy 463.049998 -59.689111)
			(xy 463.014304 -59.647918) (xy 462.984836 -59.602065) (xy 462.962194 -59.552484) (xy 462.946839 -59.500186)
			(xy 462.939084 -59.446235) (xy 462.938622 -59.418982) (xy 429.592994 -59.418982) (xy 434.1749 -64.000888)
			(xy 434.1749 -68.56215) (xy 463.017866 -68.56215) (xy 463.017866 -68.477454) (xy 463.025917 -68.39314)
			(xy 463.041946 -68.309974) (xy 463.065807 -68.228707) (xy 463.097286 -68.150077) (xy 463.136097 -68.074796)
			(xy 463.181887 -68.003544) (xy 463.234243 -67.936968) (xy 463.292691 -67.87567) (xy 463.356701 -67.820205)
			(xy 463.425693 -67.771076) (xy 463.499043 -67.728727) (xy 463.576086 -67.693543) (xy 463.656125 -67.665841)
			(xy 463.738434 -67.645873) (xy 463.822269 -67.63382) (xy 463.90687 -67.62979) (xy 463.991471 -67.63382)
			(xy 464.075306 -67.645873) (xy 464.157615 -67.665841) (xy 464.237654 -67.693543) (xy 464.314697 -67.728727)
			(xy 464.388047 -67.771076) (xy 464.457039 -67.820205) (xy 464.521049 -67.87567) (xy 464.579497 -67.936968)
			(xy 464.631853 -68.003544) (xy 464.677643 -68.074796) (xy 464.716454 -68.150077) (xy 464.747933 -68.228707)
			(xy 464.771794 -68.309974) (xy 464.787823 -68.39314) (xy 464.795874 -68.477454) (xy 464.796378 -68.519802)
			(xy 465.542379 -68.519802) (xy 465.546415 -68.436355) (xy 465.558487 -68.353687) (xy 465.57848 -68.27257)
			(xy 465.606209 -68.193761) (xy 465.641415 -68.117996) (xy 465.683769 -68.045983) (xy 465.732875 -67.978394)
			(xy 465.788276 -67.91586) (xy 465.849453 -67.858965) (xy 465.915836 -67.808239) (xy 465.986804 -67.764158)
			(xy 466.061696 -67.727132) (xy 466.139812 -67.697506) (xy 466.220422 -67.675558) (xy 466.302774 -67.661493)
			(xy 466.3861 -67.655441) (xy 466.46962 -67.65746) (xy 466.552556 -67.66753) (xy 466.634132 -67.685558)
			(xy 466.713588 -67.711375) (xy 466.790181 -67.74474) (xy 466.863197 -67.785341) (xy 466.931953 -67.8328)
			(xy 466.995807 -67.886673) (xy 467.054164 -67.946458) (xy 467.106479 -68.011595) (xy 467.152262 -68.081478)
			(xy 467.191087 -68.155453) (xy 467.222592 -68.23283) (xy 467.246481 -68.312887) (xy 467.262532 -68.394875)
			(xy 467.270595 -68.47803) (xy 467.2711 -68.519802) (xy 467.270595 -68.561574) (xy 467.262532 -68.644729)
			(xy 467.246481 -68.726717) (xy 467.222592 -68.806774) (xy 467.191087 -68.884151) (xy 467.152262 -68.958126)
			(xy 467.106479 -69.028009) (xy 467.054164 -69.093146) (xy 466.995807 -69.152931) (xy 466.931953 -69.206804)
			(xy 466.863197 -69.254263) (xy 466.790181 -69.294864) (xy 466.713588 -69.328229) (xy 466.634132 -69.354046)
			(xy 466.552556 -69.372074) (xy 466.46962 -69.382144) (xy 466.3861 -69.384163) (xy 466.302774 -69.378111)
			(xy 466.220422 -69.364046) (xy 466.139812 -69.342098) (xy 466.061696 -69.312472) (xy 465.986804 -69.275446)
			(xy 465.915836 -69.231365) (xy 465.849453 -69.180639) (xy 465.788276 -69.123744) (xy 465.732875 -69.06121)
			(xy 465.683769 -68.993621) (xy 465.641415 -68.921608) (xy 465.606209 -68.845843) (xy 465.57848 -68.767034)
			(xy 465.558487 -68.685917) (xy 465.546415 -68.603249) (xy 465.542379 -68.519802) (xy 464.796378 -68.519802)
			(xy 464.795874 -68.56215) (xy 464.787823 -68.646464) (xy 464.771794 -68.72963) (xy 464.747933 -68.810897)
			(xy 464.716454 -68.889527) (xy 464.677643 -68.964808) (xy 464.631853 -69.03606) (xy 464.579497 -69.102636)
			(xy 464.521049 -69.163934) (xy 464.457039 -69.219399) (xy 464.388047 -69.268528) (xy 464.314697 -69.310877)
			(xy 464.237654 -69.346061) (xy 464.157615 -69.373763) (xy 464.075306 -69.393731) (xy 463.991471 -69.405784)
			(xy 463.90687 -69.409815) (xy 463.822269 -69.405784) (xy 463.738434 -69.393731) (xy 463.656125 -69.373763)
			(xy 463.576086 -69.346061) (xy 463.499043 -69.310877) (xy 463.425693 -69.268528) (xy 463.356701 -69.219399)
			(xy 463.292691 -69.163934) (xy 463.234243 -69.102636) (xy 463.181887 -69.03606) (xy 463.136097 -68.964808)
			(xy 463.097286 -68.889527) (xy 463.065807 -68.810897) (xy 463.041946 -68.72963) (xy 463.025917 -68.646464)
			(xy 463.017866 -68.56215) (xy 434.1749 -68.56215) (xy 434.1749 -71.039228) (xy 443.224918 -71.039228)
			(xy 443.228989 -70.983606) (xy 443.241115 -70.929169) (xy 443.261038 -70.877078) (xy 443.288334 -70.828443)
			(xy 443.32242 -70.7843) (xy 443.362569 -70.745591) (xy 443.407927 -70.71314) (xy 443.457527 -70.687639)
			(xy 443.510311 -70.669632) (xy 443.565154 -70.659502) (xy 443.620888 -70.657465) (xy 443.676325 -70.663565)
			(xy 443.730282 -70.677671) (xy 443.781611 -70.699483) (xy 443.829217 -70.728537) (xy 443.872085 -70.764212)
			(xy 443.909302 -70.805749) (xy 443.940075 -70.852262) (xy 443.963747 -70.902759) (xy 443.979815 -70.956166)
			(xy 443.987935 -71.011342) (xy 443.988444 -71.039228) (xy 443.987935 -71.067114) (xy 443.979815 -71.12229)
			(xy 443.963747 -71.175697) (xy 443.940075 -71.226194) (xy 443.909302 -71.272707) (xy 443.872085 -71.314244)
			(xy 443.829217 -71.349919) (xy 443.781611 -71.378973) (xy 443.730282 -71.400785) (xy 443.676325 -71.414891)
			(xy 443.620888 -71.420991) (xy 443.565154 -71.418954) (xy 443.510311 -71.408824) (xy 443.457527 -71.390817)
			(xy 443.407927 -71.365316) (xy 443.362569 -71.332865) (xy 443.32242 -71.294156) (xy 443.288334 -71.250013)
			(xy 443.261038 -71.201378) (xy 443.241115 -71.149287) (xy 443.228989 -71.09485) (xy 443.224918 -71.039228)
			(xy 434.1749 -71.039228) (xy 434.1749 -73.088052) (xy 452.643969 -73.088052) (xy 452.643969 -73.033548)
			(xy 452.651726 -72.979599) (xy 452.667082 -72.927303) (xy 452.689723 -72.877724) (xy 452.719191 -72.831873)
			(xy 452.754883 -72.790682) (xy 452.796074 -72.754989) (xy 452.841926 -72.725522) (xy 452.891505 -72.702881)
			(xy 452.943801 -72.687526) (xy 452.99775 -72.679769) (xy 453.025002 -72.679306) (xy 453.052711 -72.679821)
			(xy 453.107544 -72.687844) (xy 453.160639 -72.703721) (xy 453.210876 -72.727117) (xy 453.257196 -72.75754)
			(xy 453.27824 -72.775572) (xy 453.289642 -72.78504) (xy 453.316492 -72.797557) (xy 453.345804 -72.80185)
			(xy 453.375116 -72.797557) (xy 453.401966 -72.78504) (xy 453.413368 -72.775572) (xy 453.434411 -72.757537)
			(xy 453.480729 -72.727108) (xy 453.530966 -72.703707) (xy 453.584061 -72.687827) (xy 453.638896 -72.679803)
			(xy 453.666606 -72.679306) (xy 453.693858 -72.679764) (xy 453.747807 -72.687522) (xy 453.800103 -72.702878)
			(xy 453.849681 -72.72552) (xy 453.895533 -72.754988) (xy 453.936724 -72.790681) (xy 453.972416 -72.831872)
			(xy 454.001883 -72.877724) (xy 454.024524 -72.927303) (xy 454.03988 -72.979599) (xy 454.047636 -73.033548)
			(xy 454.047636 -73.088052) (xy 454.047636 -73.088053) (xy 454.467669 -73.088053) (xy 454.467669 -73.033547)
			(xy 454.475427 -72.979596) (xy 454.490783 -72.927299) (xy 454.513426 -72.877719) (xy 454.542895 -72.831866)
			(xy 454.57859 -72.790675) (xy 454.619784 -72.754982) (xy 454.665638 -72.725516) (xy 454.715219 -72.702876)
			(xy 454.767518 -72.687522) (xy 454.821469 -72.679768) (xy 454.848722 -72.679306) (xy 454.876431 -72.679809)
			(xy 454.931265 -72.687835) (xy 454.98436 -72.703715) (xy 455.034596 -72.727113) (xy 455.080916 -72.757538)
			(xy 455.10196 -72.775572) (xy 455.113362 -72.78504) (xy 455.140212 -72.797557) (xy 455.169524 -72.80185)
			(xy 455.198836 -72.797557) (xy 455.225686 -72.78504) (xy 455.237088 -72.775572) (xy 455.258124 -72.757528)
			(xy 455.304444 -72.7271) (xy 455.354682 -72.703701) (xy 455.407779 -72.687823) (xy 455.462616 -72.679801)
			(xy 455.490326 -72.679306) (xy 455.517577 -72.679766) (xy 455.571524 -72.687525) (xy 455.623817 -72.702883)
			(xy 455.673393 -72.725527) (xy 455.719242 -72.754995) (xy 455.760431 -72.790688) (xy 455.796121 -72.831879)
			(xy 455.825586 -72.87773) (xy 455.848226 -72.927307) (xy 455.86358 -72.979602) (xy 455.871336 -73.033549)
			(xy 455.871336 -73.088051) (xy 455.86358 -73.141998) (xy 455.848226 -73.194293) (xy 455.825586 -73.24387)
			(xy 455.796121 -73.289721) (xy 455.760431 -73.330912) (xy 455.719242 -73.366605) (xy 455.673393 -73.396073)
			(xy 455.623817 -73.418717) (xy 455.571524 -73.434075) (xy 455.517577 -73.441834) (xy 455.490326 -73.442322)
			(xy 455.462616 -73.441843) (xy 455.407781 -73.43381) (xy 455.354686 -73.417924) (xy 455.30445 -73.39452)
			(xy 455.258131 -73.364091) (xy 455.237088 -73.346056) (xy 455.225686 -73.336588) (xy 455.198836 -73.324071)
			(xy 455.169524 -73.319778) (xy 455.140212 -73.324071) (xy 455.113362 -73.336588) (xy 455.10196 -73.346056)
			(xy 455.08091 -73.364082) (xy 455.034593 -73.394511) (xy 454.984358 -73.417914) (xy 454.931265 -73.433796)
			(xy 454.876431 -73.441823) (xy 454.848722 -73.442322) (xy 454.821469 -73.441832) (xy 454.767518 -73.434078)
			(xy 454.715219 -73.418724) (xy 454.665638 -73.396084) (xy 454.619784 -73.366618) (xy 454.57859 -73.330925)
			(xy 454.542895 -73.289734) (xy 454.513426 -73.243881) (xy 454.490783 -73.194301) (xy 454.475427 -73.142004)
			(xy 454.467669 -73.088053) (xy 454.047636 -73.088053) (xy 454.03988 -73.142001) (xy 454.024524 -73.194297)
			(xy 454.001883 -73.243876) (xy 453.972416 -73.289728) (xy 453.936724 -73.330919) (xy 453.895533 -73.366612)
			(xy 453.849681 -73.39608) (xy 453.800103 -73.418722) (xy 453.747807 -73.434078) (xy 453.693858 -73.441836)
			(xy 453.666606 -73.442322) (xy 453.638898 -73.441795) (xy 453.584065 -73.433774) (xy 453.530971 -73.4179)
			(xy 453.480734 -73.394506) (xy 453.434413 -73.364087) (xy 453.413368 -73.346056) (xy 453.401966 -73.336588)
			(xy 453.375116 -73.324071) (xy 453.345804 -73.319778) (xy 453.316492 -73.324071) (xy 453.289642 -73.336588)
			(xy 453.27824 -73.346056) (xy 453.257197 -73.364091) (xy 453.210879 -73.394519) (xy 453.160642 -73.41792)
			(xy 453.107547 -73.4338) (xy 453.052712 -73.441825) (xy 453.025002 -73.442322) (xy 452.99775 -73.441831)
			(xy 452.943801 -73.434074) (xy 452.891505 -73.418719) (xy 452.841926 -73.396078) (xy 452.796074 -73.366611)
			(xy 452.754883 -73.330918) (xy 452.719191 -73.289727) (xy 452.689723 -73.243876) (xy 452.667082 -73.194297)
			(xy 452.651726 -73.142001) (xy 452.643969 -73.088052) (xy 434.1749 -73.088052) (xy 434.1749 -74.640948)
			(xy 443.978282 -74.640948) (xy 443.982353 -74.585326) (xy 443.994479 -74.530889) (xy 444.014402 -74.478798)
			(xy 444.041698 -74.430163) (xy 444.075784 -74.38602) (xy 444.115933 -74.347311) (xy 444.161291 -74.31486)
			(xy 444.210891 -74.289359) (xy 444.263675 -74.271352) (xy 444.318518 -74.261222) (xy 444.374252 -74.259185)
			(xy 444.429689 -74.265285) (xy 444.483646 -74.279391) (xy 444.534975 -74.301203) (xy 444.582581 -74.330257)
			(xy 444.625449 -74.365932) (xy 444.662666 -74.407469) (xy 444.693439 -74.453982) (xy 444.717111 -74.504479)
			(xy 444.733179 -74.557886) (xy 444.741299 -74.613062) (xy 444.741808 -74.640948) (xy 444.741299 -74.668834)
			(xy 444.733179 -74.72401) (xy 444.717111 -74.777417) (xy 444.693439 -74.827914) (xy 444.662666 -74.874427)
			(xy 444.625449 -74.915964) (xy 444.582581 -74.951639) (xy 444.534975 -74.980693) (xy 444.483646 -75.002505)
			(xy 444.429689 -75.016611) (xy 444.374252 -75.022711) (xy 444.318518 -75.020674) (xy 444.263675 -75.010544)
			(xy 444.210891 -74.992537) (xy 444.161291 -74.967036) (xy 444.115933 -74.934585) (xy 444.075784 -74.895876)
			(xy 444.041698 -74.851733) (xy 444.014402 -74.803098) (xy 443.994479 -74.751007) (xy 443.982353 -74.69657)
			(xy 443.978282 -74.640948) (xy 434.1749 -74.640948) (xy 434.1749 -75.054206) (xy 451.065898 -75.054206)
			(xy 451.069969 -74.998584) (xy 451.082095 -74.944147) (xy 451.102018 -74.892056) (xy 451.129314 -74.843421)
			(xy 451.1634 -74.799278) (xy 451.203549 -74.760569) (xy 451.248907 -74.728118) (xy 451.298507 -74.702617)
			(xy 451.351291 -74.68461) (xy 451.406134 -74.67448) (xy 451.461868 -74.672443) (xy 451.517305 -74.678543)
			(xy 451.571262 -74.692649) (xy 451.622591 -74.714461) (xy 451.670197 -74.743515) (xy 451.713065 -74.77919)
			(xy 451.745377 -74.815253) (xy 454.048569 -74.815253) (xy 454.048569 -74.760747) (xy 454.056327 -74.706796)
			(xy 454.071683 -74.654499) (xy 454.094326 -74.604919) (xy 454.123795 -74.559066) (xy 454.15949 -74.517875)
			(xy 454.200684 -74.482182) (xy 454.246538 -74.452716) (xy 454.296119 -74.430076) (xy 454.348418 -74.414722)
			(xy 454.402369 -74.406968) (xy 454.429622 -74.406506) (xy 454.457331 -74.407009) (xy 454.512165 -74.415035)
			(xy 454.56526 -74.430915) (xy 454.615496 -74.454313) (xy 454.661816 -74.484738) (xy 454.68286 -74.502772)
			(xy 454.694262 -74.51224) (xy 454.721112 -74.524757) (xy 454.750424 -74.52905) (xy 454.779736 -74.524757)
			(xy 454.806586 -74.51224) (xy 454.817988 -74.502772) (xy 454.839024 -74.484728) (xy 454.885344 -74.4543)
			(xy 454.935582 -74.430901) (xy 454.988679 -74.415023) (xy 455.043516 -74.407001) (xy 455.071226 -74.406506)
			(xy 455.098477 -74.406966) (xy 455.152424 -74.414725) (xy 455.204717 -74.430083) (xy 455.254293 -74.452727)
			(xy 455.300142 -74.482195) (xy 455.341331 -74.517888) (xy 455.377021 -74.559079) (xy 455.406486 -74.60493)
			(xy 455.429126 -74.654507) (xy 455.44448 -74.706802) (xy 455.452236 -74.760749) (xy 455.452236 -74.815251)
			(xy 455.44448 -74.869198) (xy 455.429126 -74.921493) (xy 455.406486 -74.97107) (xy 455.377021 -75.016921)
			(xy 455.341331 -75.058112) (xy 455.300142 -75.093805) (xy 455.254293 -75.123273) (xy 455.204717 -75.145917)
			(xy 455.152424 -75.161275) (xy 455.098477 -75.169034) (xy 455.071226 -75.169522) (xy 455.043516 -75.169043)
			(xy 454.988681 -75.16101) (xy 454.935586 -75.145124) (xy 454.88535 -75.12172) (xy 454.839031 -75.091291)
			(xy 454.817988 -75.073256) (xy 454.806586 -75.063788) (xy 454.779736 -75.051271) (xy 454.750424 -75.046978)
			(xy 454.721112 -75.051271) (xy 454.694262 -75.063788) (xy 454.68286 -75.073256) (xy 454.66181 -75.091282)
			(xy 454.615493 -75.121711) (xy 454.565258 -75.145114) (xy 454.512165 -75.160996) (xy 454.457331 -75.169023)
			(xy 454.429622 -75.169522) (xy 454.402369 -75.169032) (xy 454.348418 -75.161278) (xy 454.296119 -75.145924)
			(xy 454.246538 -75.123284) (xy 454.200684 -75.093818) (xy 454.15949 -75.058125) (xy 454.123795 -75.016934)
			(xy 454.094326 -74.971081) (xy 454.071683 -74.921501) (xy 454.056327 -74.869204) (xy 454.048569 -74.815253)
			(xy 451.745377 -74.815253) (xy 451.750282 -74.820727) (xy 451.781055 -74.86724) (xy 451.804727 -74.917737)
			(xy 451.820795 -74.971144) (xy 451.828915 -75.02632) (xy 451.829424 -75.054206) (xy 451.828915 -75.082092)
			(xy 451.820795 -75.137268) (xy 451.804727 -75.190675) (xy 451.781055 -75.241172) (xy 451.750282 -75.287685)
			(xy 451.713065 -75.329222) (xy 451.670197 -75.364897) (xy 451.622591 -75.393951) (xy 451.571262 -75.415763)
			(xy 451.517305 -75.429869) (xy 451.461868 -75.435969) (xy 451.406134 -75.433932) (xy 451.351291 -75.423802)
			(xy 451.298507 -75.405795) (xy 451.248907 -75.380294) (xy 451.203549 -75.347843) (xy 451.1634 -75.309134)
			(xy 451.129314 -75.264991) (xy 451.102018 -75.216356) (xy 451.082095 -75.164265) (xy 451.069969 -75.109828)
			(xy 451.065898 -75.054206) (xy 434.1749 -75.054206) (xy 434.1749 -76.002572) (xy 463.017866 -76.002572)
			(xy 463.017866 -75.917876) (xy 463.025917 -75.833562) (xy 463.041946 -75.750396) (xy 463.065807 -75.669129)
			(xy 463.097286 -75.590499) (xy 463.136097 -75.515218) (xy 463.181887 -75.443966) (xy 463.234243 -75.37739)
			(xy 463.292691 -75.316092) (xy 463.356701 -75.260627) (xy 463.425693 -75.211498) (xy 463.499043 -75.169149)
			(xy 463.576086 -75.133965) (xy 463.656125 -75.106263) (xy 463.738434 -75.086295) (xy 463.822269 -75.074242)
			(xy 463.90687 -75.070212) (xy 463.991471 -75.074242) (xy 464.075306 -75.086295) (xy 464.157615 -75.106263)
			(xy 464.237654 -75.133965) (xy 464.314697 -75.169149) (xy 464.388047 -75.211498) (xy 464.457039 -75.260627)
			(xy 464.521049 -75.316092) (xy 464.579497 -75.37739) (xy 464.631853 -75.443966) (xy 464.677643 -75.515218)
			(xy 464.716454 -75.590499) (xy 464.747933 -75.669129) (xy 464.771794 -75.750396) (xy 464.787823 -75.833562)
			(xy 464.795874 -75.917876) (xy 464.796378 -75.960224) (xy 465.542379 -75.960224) (xy 465.546415 -75.876777)
			(xy 465.558487 -75.794109) (xy 465.57848 -75.712992) (xy 465.606209 -75.634183) (xy 465.641415 -75.558418)
			(xy 465.683769 -75.486405) (xy 465.732875 -75.418816) (xy 465.788276 -75.356282) (xy 465.849453 -75.299387)
			(xy 465.915836 -75.248661) (xy 465.986804 -75.20458) (xy 466.061696 -75.167554) (xy 466.139812 -75.137928)
			(xy 466.220422 -75.11598) (xy 466.302774 -75.101915) (xy 466.3861 -75.095863) (xy 466.46962 -75.097882)
			(xy 466.552556 -75.107952) (xy 466.634132 -75.12598) (xy 466.713588 -75.151797) (xy 466.790181 -75.185162)
			(xy 466.863197 -75.225763) (xy 466.931953 -75.273222) (xy 466.995807 -75.327095) (xy 467.054164 -75.38688)
			(xy 467.106479 -75.452017) (xy 467.152262 -75.5219) (xy 467.191087 -75.595875) (xy 467.222592 -75.673252)
			(xy 467.246481 -75.753309) (xy 467.262532 -75.835297) (xy 467.270595 -75.918452) (xy 467.2711 -75.960224)
			(xy 467.270595 -76.001996) (xy 467.262532 -76.085151) (xy 467.246481 -76.167139) (xy 467.222592 -76.247196)
			(xy 467.191087 -76.324573) (xy 467.152262 -76.398548) (xy 467.106479 -76.468431) (xy 467.054164 -76.533568)
			(xy 466.995807 -76.593353) (xy 466.931953 -76.647226) (xy 466.863197 -76.694685) (xy 466.790181 -76.735286)
			(xy 466.713588 -76.768651) (xy 466.634132 -76.794468) (xy 466.552556 -76.812496) (xy 466.46962 -76.822566)
			(xy 466.3861 -76.824585) (xy 466.302774 -76.818533) (xy 466.220422 -76.804468) (xy 466.139812 -76.78252)
			(xy 466.061696 -76.752894) (xy 465.986804 -76.715868) (xy 465.915836 -76.671787) (xy 465.849453 -76.621061)
			(xy 465.788276 -76.564166) (xy 465.732875 -76.501632) (xy 465.683769 -76.434043) (xy 465.641415 -76.36203)
			(xy 465.606209 -76.286265) (xy 465.57848 -76.207456) (xy 465.558487 -76.126339) (xy 465.546415 -76.043671)
			(xy 465.542379 -75.960224) (xy 464.796378 -75.960224) (xy 464.795874 -76.002572) (xy 464.787823 -76.086886)
			(xy 464.771794 -76.170052) (xy 464.747933 -76.251319) (xy 464.716454 -76.329949) (xy 464.677643 -76.40523)
			(xy 464.631853 -76.476482) (xy 464.579497 -76.543058) (xy 464.521049 -76.604356) (xy 464.457039 -76.659821)
			(xy 464.388047 -76.70895) (xy 464.314697 -76.751299) (xy 464.237654 -76.786483) (xy 464.157615 -76.814185)
			(xy 464.075306 -76.834153) (xy 463.991471 -76.846206) (xy 463.90687 -76.850237) (xy 463.822269 -76.846206)
			(xy 463.738434 -76.834153) (xy 463.656125 -76.814185) (xy 463.576086 -76.786483) (xy 463.499043 -76.751299)
			(xy 463.425693 -76.70895) (xy 463.356701 -76.659821) (xy 463.292691 -76.604356) (xy 463.234243 -76.543058)
			(xy 463.181887 -76.476482) (xy 463.136097 -76.40523) (xy 463.097286 -76.329949) (xy 463.065807 -76.251319)
			(xy 463.041946 -76.170052) (xy 463.025917 -76.086886) (xy 463.017866 -76.002572) (xy 434.1749 -76.002572)
			(xy 434.1749 -76.63053) (xy 445.693798 -76.63053) (xy 445.697869 -76.574908) (xy 445.709995 -76.520471)
			(xy 445.729918 -76.46838) (xy 445.757214 -76.419745) (xy 445.7913 -76.375602) (xy 445.831449 -76.336893)
			(xy 445.876807 -76.304442) (xy 445.926407 -76.278941) (xy 445.979191 -76.260934) (xy 446.034034 -76.250804)
			(xy 446.089768 -76.248767) (xy 446.145205 -76.254867) (xy 446.199162 -76.268973) (xy 446.250491 -76.290785)
			(xy 446.298097 -76.319839) (xy 446.340965 -76.355514) (xy 446.378182 -76.397051) (xy 446.408955 -76.443564)
			(xy 446.432627 -76.494061) (xy 446.448695 -76.547468) (xy 446.456815 -76.602644) (xy 446.457106 -76.618592)
			(xy 446.684398 -76.618592) (xy 446.688469 -76.56297) (xy 446.700595 -76.508533) (xy 446.720518 -76.456442)
			(xy 446.747814 -76.407807) (xy 446.7819 -76.363664) (xy 446.822049 -76.324955) (xy 446.867407 -76.292504)
			(xy 446.917007 -76.267003) (xy 446.969791 -76.248996) (xy 447.024634 -76.238866) (xy 447.080368 -76.236829)
			(xy 447.135805 -76.242929) (xy 447.189762 -76.257035) (xy 447.241091 -76.278847) (xy 447.288697 -76.307901)
			(xy 447.331565 -76.343576) (xy 447.368782 -76.385113) (xy 447.399555 -76.431626) (xy 447.423227 -76.482123)
			(xy 447.439295 -76.53553) (xy 447.447415 -76.590706) (xy 447.447924 -76.618592) (xy 447.447548 -76.639166)
			(xy 452.504554 -76.639166) (xy 452.508625 -76.583544) (xy 452.520751 -76.529107) (xy 452.540674 -76.477016)
			(xy 452.56797 -76.428381) (xy 452.602056 -76.384238) (xy 452.642205 -76.345529) (xy 452.687563 -76.313078)
			(xy 452.737163 -76.287577) (xy 452.789947 -76.26957) (xy 452.84479 -76.25944) (xy 452.900524 -76.257403)
			(xy 452.955961 -76.263503) (xy 453.009918 -76.277609) (xy 453.061247 -76.299421) (xy 453.108853 -76.328475)
			(xy 453.151721 -76.36415) (xy 453.188938 -76.405687) (xy 453.219711 -76.4522) (xy 453.243383 -76.502697)
			(xy 453.259451 -76.556104) (xy 453.267571 -76.61128) (xy 453.26808 -76.639166) (xy 453.267571 -76.667052)
			(xy 453.259451 -76.722228) (xy 453.243383 -76.775635) (xy 453.219711 -76.826132) (xy 453.188938 -76.872645)
			(xy 453.151721 -76.914182) (xy 453.108853 -76.949857) (xy 453.061247 -76.978911) (xy 453.009918 -77.000723)
			(xy 452.955961 -77.014829) (xy 452.900524 -77.020929) (xy 452.84479 -77.018892) (xy 452.789947 -77.008762)
			(xy 452.737163 -76.990755) (xy 452.687563 -76.965254) (xy 452.642205 -76.932803) (xy 452.602056 -76.894094)
			(xy 452.56797 -76.849951) (xy 452.540674 -76.801316) (xy 452.520751 -76.749225) (xy 452.508625 -76.694788)
			(xy 452.504554 -76.639166) (xy 447.447548 -76.639166) (xy 447.447415 -76.646478) (xy 447.439295 -76.701654)
			(xy 447.423227 -76.755061) (xy 447.399555 -76.805558) (xy 447.368782 -76.852071) (xy 447.331565 -76.893608)
			(xy 447.288697 -76.929283) (xy 447.241091 -76.958337) (xy 447.189762 -76.980149) (xy 447.135805 -76.994255)
			(xy 447.080368 -77.000355) (xy 447.024634 -76.998318) (xy 446.969791 -76.988188) (xy 446.917007 -76.970181)
			(xy 446.867407 -76.94468) (xy 446.822049 -76.912229) (xy 446.7819 -76.87352) (xy 446.747814 -76.829377)
			(xy 446.720518 -76.780742) (xy 446.700595 -76.728651) (xy 446.688469 -76.674214) (xy 446.684398 -76.618592)
			(xy 446.457106 -76.618592) (xy 446.457324 -76.63053) (xy 446.456815 -76.658416) (xy 446.448695 -76.713592)
			(xy 446.432627 -76.766999) (xy 446.408955 -76.817496) (xy 446.378182 -76.864009) (xy 446.340965 -76.905546)
			(xy 446.298097 -76.941221) (xy 446.250491 -76.970275) (xy 446.199162 -76.992087) (xy 446.145205 -77.006193)
			(xy 446.089768 -77.012293) (xy 446.034034 -77.010256) (xy 445.979191 -77.000126) (xy 445.926407 -76.982119)
			(xy 445.876807 -76.956618) (xy 445.831449 -76.924167) (xy 445.7913 -76.885458) (xy 445.757214 -76.841315)
			(xy 445.729918 -76.79268) (xy 445.709995 -76.740589) (xy 445.697869 -76.686152) (xy 445.693798 -76.63053)
			(xy 434.1749 -76.63053) (xy 434.1749 -77.518768) (xy 434.52288 -77.866748) (xy 444.625982 -77.866748)
			(xy 444.630053 -77.811126) (xy 444.642179 -77.756689) (xy 444.662102 -77.704598) (xy 444.689398 -77.655963)
			(xy 444.723484 -77.61182) (xy 444.763633 -77.573111) (xy 444.808991 -77.54066) (xy 444.858591 -77.515159)
			(xy 444.911375 -77.497152) (xy 444.966218 -77.487022) (xy 445.021952 -77.484985) (xy 445.077389 -77.491085)
			(xy 445.131346 -77.505191) (xy 445.182675 -77.527003) (xy 445.230281 -77.556057) (xy 445.273149 -77.591732)
			(xy 445.310366 -77.633269) (xy 445.341139 -77.679782) (xy 445.364811 -77.730279) (xy 445.380879 -77.783686)
			(xy 445.388999 -77.838862) (xy 445.389508 -77.866748) (xy 445.388999 -77.894634) (xy 445.380879 -77.94981)
			(xy 445.364811 -78.003217) (xy 445.341139 -78.053714) (xy 445.310366 -78.100227) (xy 445.273149 -78.141764)
			(xy 445.230281 -78.177439) (xy 445.182675 -78.206493) (xy 445.131346 -78.228305) (xy 445.077389 -78.242411)
			(xy 445.021952 -78.248511) (xy 444.966218 -78.246474) (xy 444.911375 -78.236344) (xy 444.858591 -78.218337)
			(xy 444.808991 -78.192836) (xy 444.763633 -78.160385) (xy 444.723484 -78.121676) (xy 444.689398 -78.077533)
			(xy 444.662102 -78.028898) (xy 444.642179 -77.976807) (xy 444.630053 -77.92237) (xy 444.625982 -77.866748)
			(xy 434.52288 -77.866748) (xy 435.576218 -78.920086) (xy 447.149726 -78.920086) (xy 447.153797 -78.864464)
			(xy 447.165923 -78.810027) (xy 447.185846 -78.757936) (xy 447.213142 -78.709301) (xy 447.247228 -78.665158)
			(xy 447.287377 -78.626449) (xy 447.332735 -78.593998) (xy 447.382335 -78.568497) (xy 447.435119 -78.55049)
			(xy 447.489962 -78.54036) (xy 447.545696 -78.538323) (xy 447.601133 -78.544423) (xy 447.65509 -78.558529)
			(xy 447.706419 -78.580341) (xy 447.754025 -78.609395) (xy 447.796893 -78.64507) (xy 447.83411 -78.686607)
			(xy 447.864883 -78.73312) (xy 447.888555 -78.783617) (xy 447.904623 -78.837024) (xy 447.908212 -78.861412)
			(xy 449.002402 -78.861412) (xy 449.006473 -78.80579) (xy 449.018599 -78.751353) (xy 449.038522 -78.699262)
			(xy 449.065818 -78.650627) (xy 449.099904 -78.606484) (xy 449.140053 -78.567775) (xy 449.185411 -78.535324)
			(xy 449.235011 -78.509823) (xy 449.287795 -78.491816) (xy 449.342638 -78.481686) (xy 449.398372 -78.479649)
			(xy 449.453809 -78.485749) (xy 449.507766 -78.499855) (xy 449.559095 -78.521667) (xy 449.606701 -78.550721)
			(xy 449.649569 -78.586396) (xy 449.686786 -78.627933) (xy 449.717559 -78.674446) (xy 449.741231 -78.724943)
			(xy 449.757299 -78.77835) (xy 449.765419 -78.833526) (xy 449.765928 -78.861412) (xy 449.765419 -78.889298)
			(xy 449.757299 -78.944474) (xy 449.741231 -78.997881) (xy 449.717559 -79.048378) (xy 449.686786 -79.094891)
			(xy 449.649569 -79.136428) (xy 449.606701 -79.172103) (xy 449.559095 -79.201157) (xy 449.507766 -79.222969)
			(xy 449.453809 -79.237075) (xy 449.398372 -79.243175) (xy 449.342638 -79.241138) (xy 449.287795 -79.231008)
			(xy 449.235011 -79.213001) (xy 449.185411 -79.1875) (xy 449.140053 -79.155049) (xy 449.099904 -79.11634)
			(xy 449.065818 -79.072197) (xy 449.038522 -79.023562) (xy 449.018599 -78.971471) (xy 449.006473 -78.917034)
			(xy 449.002402 -78.861412) (xy 447.908212 -78.861412) (xy 447.912743 -78.8922) (xy 447.913252 -78.920086)
			(xy 447.912743 -78.947972) (xy 447.904623 -79.003148) (xy 447.888555 -79.056555) (xy 447.864883 -79.107052)
			(xy 447.83411 -79.153565) (xy 447.796893 -79.195102) (xy 447.754025 -79.230777) (xy 447.706419 -79.259831)
			(xy 447.65509 -79.281643) (xy 447.601133 -79.295749) (xy 447.545696 -79.301849) (xy 447.489962 -79.299812)
			(xy 447.435119 -79.289682) (xy 447.382335 -79.271675) (xy 447.332735 -79.246174) (xy 447.287377 -79.213723)
			(xy 447.247228 -79.175014) (xy 447.213142 -79.130871) (xy 447.185846 -79.082236) (xy 447.165923 -79.030145)
			(xy 447.153797 -78.975708) (xy 447.149726 -78.920086) (xy 435.576218 -78.920086) (xy 436.78094 -80.124808)
			(xy 442.31306 -80.124808) (xy 442.3156 -80.127348) (xy 466.17128 -80.127348)
		)
		(stroke
			(width 0)
			(type solid)
		)
		(fill yes)
		(layer "In6.Cu")
		(net "GND")
	)
	(gr_poly
		(pts
			(xy 410.79166 -40.091868) (xy 410.79166 -20.241514) (xy 410.791197 -20.22769) (xy 410.783771 -20.201058)
			(xy 410.769462 -20.177401) (xy 410.749321 -20.158459) (xy 410.724832 -20.145626) (xy 410.697794 -20.139846)
			(xy 410.683964 -20.140168) (xy 410.660596 -20.14093) (xy 410.633344 -20.140444) (xy 410.579396 -20.132687)
			(xy 410.5271 -20.117332) (xy 410.477522 -20.094691) (xy 410.431671 -20.065225) (xy 410.390479 -20.029534)
			(xy 410.354786 -19.988344) (xy 410.325318 -19.942494) (xy 410.302674 -19.892917) (xy 410.287317 -19.840622)
			(xy 410.279557 -19.786674) (xy 410.279088 -19.759422) (xy 410.279673 -19.729118) (xy 410.289245 -19.669271)
			(xy 410.298138 -19.640296) (xy 410.301961 -19.627127) (xy 410.303217 -19.599744) (xy 410.297143 -19.573013)
			(xy 410.284178 -19.548861) (xy 410.265255 -19.529028) (xy 410.241739 -19.514943) (xy 410.215323 -19.507621)
			(xy 410.201618 -19.5072) (xy 409.86075 -19.5072) (xy 409.847041 -19.507642) (xy 409.82061 -19.514934)
			(xy 409.797077 -19.529004) (xy 409.778143 -19.548836) (xy 409.765178 -19.572995) (xy 409.759118 -19.599736)
			(xy 409.760401 -19.627124) (xy 409.76423 -19.640296) (xy 409.77314 -19.669267) (xy 409.782711 -19.729117)
			(xy 409.78328 -19.759422) (xy 409.782794 -19.786673) (xy 409.775038 -19.840621) (xy 409.759683 -19.892916)
			(xy 409.737041 -19.942493) (xy 409.707575 -19.988343) (xy 409.671884 -20.029534) (xy 409.630693 -20.065225)
			(xy 409.584843 -20.094691) (xy 409.535266 -20.117333) (xy 409.482971 -20.132688) (xy 409.429023 -20.140444)
			(xy 409.374521 -20.140444) (xy 409.320573 -20.132688) (xy 409.268278 -20.117333) (xy 409.218701 -20.094691)
			(xy 409.172851 -20.065225) (xy 409.13166 -20.029534) (xy 409.095969 -19.988343) (xy 409.066503 -19.942493)
			(xy 409.043861 -19.892916) (xy 409.028506 -19.840621) (xy 409.02075 -19.786673) (xy 409.020264 -19.759422)
			(xy 409.020876 -19.728577) (xy 409.030824 -19.667695) (xy 409.040076 -19.638264) (xy 409.044199 -19.624323)
			(xy 409.045292 -19.595285) (xy 409.038165 -19.567115) (xy 409.023396 -19.542091) (xy 409.002177 -19.522237)
			(xy 408.976228 -19.509161) (xy 408.947646 -19.503921) (xy 408.933142 -19.504914) (xy 408.923328 -19.505869)
			(xy 408.903633 -19.506885) (xy 408.893772 -19.506946) (xy 408.866519 -19.506458) (xy 408.812569 -19.498698)
			(xy 408.760273 -19.483339) (xy 408.710694 -19.460694) (xy 408.664843 -19.431224) (xy 408.623652 -19.395529)
			(xy 408.58796 -19.354335) (xy 408.558493 -19.308481) (xy 408.535852 -19.258901) (xy 408.520496 -19.206603)
			(xy 408.51274 -19.152653) (xy 408.51274 -19.098147) (xy 408.520496 -19.044197) (xy 408.535852 -18.991899)
			(xy 408.558493 -18.942319) (xy 408.58796 -18.896465) (xy 408.623652 -18.855271) (xy 408.664843 -18.819576)
			(xy 408.710694 -18.790106) (xy 408.760273 -18.767461) (xy 408.812569 -18.752102) (xy 408.866519 -18.744342)
			(xy 408.893772 -18.74393) (xy 408.903632 -18.743995) (xy 408.923327 -18.745012) (xy 408.933142 -18.745962)
			(xy 408.94766 -18.747038) (xy 408.976291 -18.741833) (xy 409.002291 -18.728764) (xy 409.023548 -18.708891)
			(xy 409.038336 -18.683829) (xy 409.045454 -18.655613) (xy 409.044323 -18.626535) (xy 409.040076 -18.612612)
			(xy 409.030822 -18.583182) (xy 409.020867 -18.522299) (xy 409.020264 -18.491454) (xy 409.02075 -18.464203)
			(xy 409.028506 -18.410255) (xy 409.043861 -18.35796) (xy 409.066503 -18.308383) (xy 409.095969 -18.262533)
			(xy 409.13166 -18.221342) (xy 409.172851 -18.185651) (xy 409.218701 -18.156185) (xy 409.268278 -18.133543)
			(xy 409.320573 -18.118188) (xy 409.374521 -18.110432) (xy 409.429023 -18.110432) (xy 409.482971 -18.118188)
			(xy 409.535266 -18.133543) (xy 409.584843 -18.156185) (xy 409.630693 -18.185651) (xy 409.671884 -18.221342)
			(xy 409.707575 -18.262533) (xy 409.737041 -18.308383) (xy 409.759683 -18.35796) (xy 409.775038 -18.410255)
			(xy 409.782794 -18.464203) (xy 409.78328 -18.491454) (xy 409.782697 -18.521758) (xy 409.77313 -18.581607)
			(xy 409.76423 -18.61058) (xy 409.760402 -18.623748) (xy 409.759139 -18.651131) (xy 409.76521 -18.677863)
			(xy 409.778176 -18.702015) (xy 409.797103 -18.721844) (xy 409.820624 -18.735921) (xy 409.847044 -18.74323)
			(xy 409.86075 -18.743676) (xy 410.201618 -18.743676) (xy 410.215329 -18.743238) (xy 410.241764 -18.735951)
			(xy 410.265301 -18.721882) (xy 410.284238 -18.702049) (xy 410.297203 -18.677887) (xy 410.30326 -18.651143)
			(xy 410.30197 -18.623752) (xy 410.298138 -18.61058) (xy 410.289231 -18.581608) (xy 410.279664 -18.521759)
			(xy 410.279088 -18.491454) (xy 410.279577 -18.464205) (xy 410.287339 -18.410262) (xy 410.302698 -18.357972)
			(xy 410.325342 -18.308401) (xy 410.354809 -18.262556) (xy 410.3905 -18.221371) (xy 410.431689 -18.185684)
			(xy 410.477538 -18.156221) (xy 410.527112 -18.133583) (xy 410.579403 -18.11823) (xy 410.633347 -18.110474)
			(xy 410.660596 -18.109946) (xy 410.683964 -18.110708) (xy 410.69779 -18.111068) (xy 410.724817 -18.10525)
			(xy 410.749294 -18.092398) (xy 410.76943 -18.073455) (xy 410.783749 -18.049806) (xy 410.791204 -18.023184)
			(xy 410.79166 -18.009362) (xy 410.79166 -12.870688) (xy 411.47492 -12.187428) (xy 412.624524 -12.187428)
			(xy 412.639147 -12.162588) (xy 412.674701 -12.117221) (xy 412.716674 -12.077717) (xy 412.76411 -12.044973)
			(xy 412.81593 -12.019735) (xy 412.870956 -12.002576) (xy 412.927937 -11.993887) (xy 412.956756 -11.993372)
			(xy 412.984011 -11.993832) (xy 413.037968 -12.001584) (xy 413.090273 -12.016936) (xy 413.13986 -12.039575)
			(xy 413.18572 -12.069042) (xy 413.226919 -12.104735) (xy 413.26262 -12.145929) (xy 413.292094 -12.191784)
			(xy 413.314742 -12.241367) (xy 413.330103 -12.293669) (xy 413.337864 -12.347625) (xy 413.338264 -12.37488)
			(xy 414.374836 -12.37488) (xy 414.378907 -12.319258) (xy 414.391033 -12.264821) (xy 414.410956 -12.21273)
			(xy 414.438252 -12.164095) (xy 414.472338 -12.119952) (xy 414.512487 -12.081243) (xy 414.557845 -12.048792)
			(xy 414.607445 -12.023291) (xy 414.660229 -12.005284) (xy 414.715072 -11.995154) (xy 414.770806 -11.993117)
			(xy 414.826243 -11.999217) (xy 414.8802 -12.013323) (xy 414.931529 -12.035135) (xy 414.979135 -12.064189)
			(xy 415.022003 -12.099864) (xy 415.05922 -12.141401) (xy 415.089993 -12.187914) (xy 415.113665 -12.238411)
			(xy 415.129733 -12.291818) (xy 415.137853 -12.346994) (xy 415.138362 -12.37488) (xy 416.174934 -12.37488)
			(xy 416.179005 -12.319258) (xy 416.191131 -12.264821) (xy 416.211054 -12.21273) (xy 416.23835 -12.164095)
			(xy 416.272436 -12.119952) (xy 416.312585 -12.081243) (xy 416.357943 -12.048792) (xy 416.407543 -12.023291)
			(xy 416.460327 -12.005284) (xy 416.51517 -11.995154) (xy 416.570904 -11.993117) (xy 416.626341 -11.999217)
			(xy 416.680298 -12.013323) (xy 416.731627 -12.035135) (xy 416.779233 -12.064189) (xy 416.822101 -12.099864)
			(xy 416.859318 -12.141401) (xy 416.890091 -12.187914) (xy 416.913763 -12.238411) (xy 416.929831 -12.291818)
			(xy 416.937951 -12.346994) (xy 416.93846 -12.37488) (xy 417.974778 -12.37488) (xy 417.978849 -12.319258)
			(xy 417.990975 -12.264821) (xy 418.010898 -12.21273) (xy 418.038194 -12.164095) (xy 418.07228 -12.119952)
			(xy 418.112429 -12.081243) (xy 418.157787 -12.048792) (xy 418.207387 -12.023291) (xy 418.260171 -12.005284)
			(xy 418.315014 -11.995154) (xy 418.370748 -11.993117) (xy 418.426185 -11.999217) (xy 418.480142 -12.013323)
			(xy 418.531471 -12.035135) (xy 418.579077 -12.064189) (xy 418.621945 -12.099864) (xy 418.659162 -12.141401)
			(xy 418.689935 -12.187914) (xy 418.713607 -12.238411) (xy 418.729675 -12.291818) (xy 418.737795 -12.346994)
			(xy 418.738304 -12.37488) (xy 419.774876 -12.37488) (xy 419.778947 -12.319258) (xy 419.791073 -12.264821)
			(xy 419.810996 -12.21273) (xy 419.838292 -12.164095) (xy 419.872378 -12.119952) (xy 419.912527 -12.081243)
			(xy 419.957885 -12.048792) (xy 420.007485 -12.023291) (xy 420.060269 -12.005284) (xy 420.115112 -11.995154)
			(xy 420.170846 -11.993117) (xy 420.226283 -11.999217) (xy 420.28024 -12.013323) (xy 420.331569 -12.035135)
			(xy 420.379175 -12.064189) (xy 420.422043 -12.099864) (xy 420.45926 -12.141401) (xy 420.490033 -12.187914)
			(xy 420.513705 -12.238411) (xy 420.529773 -12.291818) (xy 420.537893 -12.346994) (xy 420.538402 -12.37488)
			(xy 423.784774 -12.37488) (xy 423.788845 -12.319258) (xy 423.800971 -12.264821) (xy 423.820894 -12.21273)
			(xy 423.84819 -12.164095) (xy 423.882276 -12.119952) (xy 423.922425 -12.081243) (xy 423.967783 -12.048792)
			(xy 424.017383 -12.023291) (xy 424.070167 -12.005284) (xy 424.12501 -11.995154) (xy 424.180744 -11.993117)
			(xy 424.236181 -11.999217) (xy 424.290138 -12.013323) (xy 424.341467 -12.035135) (xy 424.389073 -12.064189)
			(xy 424.431941 -12.099864) (xy 424.469158 -12.141401) (xy 424.499931 -12.187914) (xy 424.523603 -12.238411)
			(xy 424.539671 -12.291818) (xy 424.547791 -12.346994) (xy 424.5483 -12.37488) (xy 425.584872 -12.37488)
			(xy 425.588943 -12.319258) (xy 425.601069 -12.264821) (xy 425.620992 -12.21273) (xy 425.648288 -12.164095)
			(xy 425.682374 -12.119952) (xy 425.722523 -12.081243) (xy 425.767881 -12.048792) (xy 425.817481 -12.023291)
			(xy 425.870265 -12.005284) (xy 425.925108 -11.995154) (xy 425.980842 -11.993117) (xy 426.036279 -11.999217)
			(xy 426.090236 -12.013323) (xy 426.141565 -12.035135) (xy 426.189171 -12.064189) (xy 426.232039 -12.099864)
			(xy 426.269256 -12.141401) (xy 426.300029 -12.187914) (xy 426.323701 -12.238411) (xy 426.339769 -12.291818)
			(xy 426.347889 -12.346994) (xy 426.348398 -12.37488) (xy 427.38497 -12.37488) (xy 427.389041 -12.319258)
			(xy 427.401167 -12.264821) (xy 427.42109 -12.21273) (xy 427.448386 -12.164095) (xy 427.482472 -12.119952)
			(xy 427.522621 -12.081243) (xy 427.567979 -12.048792) (xy 427.617579 -12.023291) (xy 427.670363 -12.005284)
			(xy 427.725206 -11.995154) (xy 427.78094 -11.993117) (xy 427.836377 -11.999217) (xy 427.890334 -12.013323)
			(xy 427.941663 -12.035135) (xy 427.989269 -12.064189) (xy 428.032137 -12.099864) (xy 428.069354 -12.141401)
			(xy 428.100127 -12.187914) (xy 428.123799 -12.238411) (xy 428.139867 -12.291818) (xy 428.147987 -12.346994)
			(xy 428.148496 -12.37488) (xy 429.184814 -12.37488) (xy 429.188885 -12.319258) (xy 429.201011 -12.264821)
			(xy 429.220934 -12.21273) (xy 429.24823 -12.164095) (xy 429.282316 -12.119952) (xy 429.322465 -12.081243)
			(xy 429.367823 -12.048792) (xy 429.417423 -12.023291) (xy 429.470207 -12.005284) (xy 429.52505 -11.995154)
			(xy 429.580784 -11.993117) (xy 429.636221 -11.999217) (xy 429.690178 -12.013323) (xy 429.741507 -12.035135)
			(xy 429.789113 -12.064189) (xy 429.831981 -12.099864) (xy 429.869198 -12.141401) (xy 429.899971 -12.187914)
			(xy 429.923643 -12.238411) (xy 429.939711 -12.291818) (xy 429.947831 -12.346994) (xy 429.94834 -12.37488)
			(xy 430.985422 -12.37488) (xy 430.985908 -12.347629) (xy 430.993664 -12.293681) (xy 431.009019 -12.241386)
			(xy 431.031661 -12.191809) (xy 431.061127 -12.145959) (xy 431.096818 -12.104768) (xy 431.138009 -12.069077)
			(xy 431.183859 -12.039611) (xy 431.233436 -12.016969) (xy 431.285731 -12.001614) (xy 431.339679 -11.993858)
			(xy 431.394181 -11.993858) (xy 431.448129 -12.001614) (xy 431.500424 -12.016969) (xy 431.550001 -12.039611)
			(xy 431.595851 -12.069077) (xy 431.637042 -12.104768) (xy 431.672733 -12.145959) (xy 431.702199 -12.191809)
			(xy 431.724841 -12.241386) (xy 431.740196 -12.293681) (xy 431.747952 -12.347629) (xy 431.748438 -12.37488)
			(xy 431.748302 -12.388198) (xy 431.746396 -12.414765) (xy 431.744628 -12.427966) (xy 431.743738 -12.437249)
			(xy 431.747858 -12.455418) (xy 431.758205 -12.470911) (xy 431.773411 -12.481675) (xy 431.791461 -12.486287)
			(xy 431.800762 -12.485624) (xy 431.811329 -12.484473) (xy 431.832551 -12.4832) (xy 431.84318 -12.483084)
			(xy 432.70678 -12.483084) (xy 432.73472 -12.484354) (xy 432.746097 -12.484542) (xy 432.767255 -12.476251)
			(xy 432.782804 -12.45968) (xy 432.789734 -12.438038) (xy 432.788822 -12.426696) (xy 432.787168 -12.413806)
			(xy 432.785386 -12.387876) (xy 432.785266 -12.37488) (xy 432.785752 -12.347629) (xy 432.793508 -12.293681)
			(xy 432.808863 -12.241386) (xy 432.831505 -12.191809) (xy 432.860971 -12.145959) (xy 432.896662 -12.104768)
			(xy 432.937853 -12.069077) (xy 432.983703 -12.039611) (xy 433.03328 -12.016969) (xy 433.085575 -12.001614)
			(xy 433.139523 -11.993858) (xy 433.194025 -11.993858) (xy 433.247973 -12.001614) (xy 433.300268 -12.016969)
			(xy 433.349845 -12.039611) (xy 433.395695 -12.069077) (xy 433.436886 -12.104768) (xy 433.472577 -12.145959)
			(xy 433.502043 -12.191809) (xy 433.524685 -12.241386) (xy 433.54004 -12.293681) (xy 433.547796 -12.347629)
			(xy 433.548282 -12.37488) (xy 433.547768 -12.401293) (xy 433.540469 -12.453613) (xy 433.526022 -12.504425)
			(xy 433.504703 -12.552758) (xy 433.476919 -12.597688) (xy 433.443202 -12.638355) (xy 433.404198 -12.673982)
			(xy 433.360651 -12.703887) (xy 433.313395 -12.727498) (xy 433.263333 -12.744363) (xy 433.211423 -12.754161)
			(xy 433.185062 -12.75588) (xy 433.169444 -12.757248) (xy 433.140082 -12.768183) (xy 433.115397 -12.787481)
			(xy 433.097699 -12.813336) (xy 433.088642 -12.843331) (xy 433.088288 -12.859004) (xy 433.088288 -12.864846)
			(xy 433.087819 -12.892104) (xy 433.080059 -12.946064) (xy 433.064702 -12.998372) (xy 433.042061 -13.047964)
			(xy 433.012596 -13.093831) (xy 432.976907 -13.135041) (xy 432.935719 -13.170755) (xy 432.88987 -13.200248)
			(xy 432.840292 -13.22292) (xy 432.787993 -13.238309) (xy 432.734037 -13.246103) (xy 432.70678 -13.246608)
			(xy 431.84318 -13.246608) (xy 431.815915 -13.246163) (xy 431.761941 -13.238397) (xy 431.709623 -13.223025)
			(xy 431.660025 -13.200362) (xy 431.61416 -13.170868) (xy 431.572961 -13.135145) (xy 431.537267 -13.09392)
			(xy 431.507807 -13.048034) (xy 431.485179 -12.99842) (xy 431.469845 -12.946091) (xy 431.462117 -12.892111)
			(xy 431.461672 -12.864846) (xy 431.461672 -12.859258) (xy 431.461481 -12.845927) (xy 431.454901 -12.820096)
			(xy 431.441858 -12.79685) (xy 431.423244 -12.777771) (xy 431.400325 -12.764161) (xy 431.374664 -12.756947)
			(xy 431.361342 -12.756388) (xy 431.334351 -12.755568) (xy 431.281009 -12.747163) (xy 431.229384 -12.731321)
			(xy 431.180509 -12.708359) (xy 431.135359 -12.678736) (xy 431.094836 -12.643043) (xy 431.05975 -12.601994)
			(xy 431.030802 -12.556408) (xy 431.00857 -12.507196) (xy 430.993499 -12.455342) (xy 430.985888 -12.40188)
			(xy 430.985422 -12.37488) (xy 429.94834 -12.37488) (xy 429.947831 -12.402766) (xy 429.939711 -12.457942)
			(xy 429.923643 -12.511349) (xy 429.899971 -12.561846) (xy 429.869198 -12.608359) (xy 429.831981 -12.649896)
			(xy 429.789113 -12.685571) (xy 429.741507 -12.714625) (xy 429.690178 -12.736437) (xy 429.636221 -12.750543)
			(xy 429.580784 -12.756643) (xy 429.52505 -12.754606) (xy 429.470207 -12.744476) (xy 429.417423 -12.726469)
			(xy 429.367823 -12.700968) (xy 429.322465 -12.668517) (xy 429.282316 -12.629808) (xy 429.24823 -12.585665)
			(xy 429.220934 -12.53703) (xy 429.201011 -12.484939) (xy 429.188885 -12.430502) (xy 429.184814 -12.37488)
			(xy 428.148496 -12.37488) (xy 428.147987 -12.402766) (xy 428.139867 -12.457942) (xy 428.123799 -12.511349)
			(xy 428.100127 -12.561846) (xy 428.069354 -12.608359) (xy 428.032137 -12.649896) (xy 427.989269 -12.685571)
			(xy 427.941663 -12.714625) (xy 427.890334 -12.736437) (xy 427.836377 -12.750543) (xy 427.78094 -12.756643)
			(xy 427.725206 -12.754606) (xy 427.670363 -12.744476) (xy 427.617579 -12.726469) (xy 427.567979 -12.700968)
			(xy 427.522621 -12.668517) (xy 427.482472 -12.629808) (xy 427.448386 -12.585665) (xy 427.42109 -12.53703)
			(xy 427.401167 -12.484939) (xy 427.389041 -12.430502) (xy 427.38497 -12.37488) (xy 426.348398 -12.37488)
			(xy 426.347889 -12.402766) (xy 426.339769 -12.457942) (xy 426.323701 -12.511349) (xy 426.300029 -12.561846)
			(xy 426.269256 -12.608359) (xy 426.232039 -12.649896) (xy 426.189171 -12.685571) (xy 426.141565 -12.714625)
			(xy 426.090236 -12.736437) (xy 426.036279 -12.750543) (xy 425.980842 -12.756643) (xy 425.925108 -12.754606)
			(xy 425.870265 -12.744476) (xy 425.817481 -12.726469) (xy 425.767881 -12.700968) (xy 425.722523 -12.668517)
			(xy 425.682374 -12.629808) (xy 425.648288 -12.585665) (xy 425.620992 -12.53703) (xy 425.601069 -12.484939)
			(xy 425.588943 -12.430502) (xy 425.584872 -12.37488) (xy 424.5483 -12.37488) (xy 424.547791 -12.402766)
			(xy 424.539671 -12.457942) (xy 424.523603 -12.511349) (xy 424.499931 -12.561846) (xy 424.469158 -12.608359)
			(xy 424.431941 -12.649896) (xy 424.389073 -12.685571) (xy 424.341467 -12.714625) (xy 424.290138 -12.736437)
			(xy 424.236181 -12.750543) (xy 424.180744 -12.756643) (xy 424.12501 -12.754606) (xy 424.070167 -12.744476)
			(xy 424.017383 -12.726469) (xy 423.967783 -12.700968) (xy 423.922425 -12.668517) (xy 423.882276 -12.629808)
			(xy 423.84819 -12.585665) (xy 423.820894 -12.53703) (xy 423.800971 -12.484939) (xy 423.788845 -12.430502)
			(xy 423.784774 -12.37488) (xy 420.538402 -12.37488) (xy 420.537893 -12.402766) (xy 420.529773 -12.457942)
			(xy 420.513705 -12.511349) (xy 420.490033 -12.561846) (xy 420.45926 -12.608359) (xy 420.422043 -12.649896)
			(xy 420.379175 -12.685571) (xy 420.331569 -12.714625) (xy 420.28024 -12.736437) (xy 420.226283 -12.750543)
			(xy 420.170846 -12.756643) (xy 420.115112 -12.754606) (xy 420.060269 -12.744476) (xy 420.007485 -12.726469)
			(xy 419.957885 -12.700968) (xy 419.912527 -12.668517) (xy 419.872378 -12.629808) (xy 419.838292 -12.585665)
			(xy 419.810996 -12.53703) (xy 419.791073 -12.484939) (xy 419.778947 -12.430502) (xy 419.774876 -12.37488)
			(xy 418.738304 -12.37488) (xy 418.737795 -12.402766) (xy 418.729675 -12.457942) (xy 418.713607 -12.511349)
			(xy 418.689935 -12.561846) (xy 418.659162 -12.608359) (xy 418.621945 -12.649896) (xy 418.579077 -12.685571)
			(xy 418.531471 -12.714625) (xy 418.480142 -12.736437) (xy 418.426185 -12.750543) (xy 418.370748 -12.756643)
			(xy 418.315014 -12.754606) (xy 418.260171 -12.744476) (xy 418.207387 -12.726469) (xy 418.157787 -12.700968)
			(xy 418.112429 -12.668517) (xy 418.07228 -12.629808) (xy 418.038194 -12.585665) (xy 418.010898 -12.53703)
			(xy 417.990975 -12.484939) (xy 417.978849 -12.430502) (xy 417.974778 -12.37488) (xy 416.93846 -12.37488)
			(xy 416.937951 -12.402766) (xy 416.929831 -12.457942) (xy 416.913763 -12.511349) (xy 416.890091 -12.561846)
			(xy 416.859318 -12.608359) (xy 416.822101 -12.649896) (xy 416.779233 -12.685571) (xy 416.731627 -12.714625)
			(xy 416.680298 -12.736437) (xy 416.626341 -12.750543) (xy 416.570904 -12.756643) (xy 416.51517 -12.754606)
			(xy 416.460327 -12.744476) (xy 416.407543 -12.726469) (xy 416.357943 -12.700968) (xy 416.312585 -12.668517)
			(xy 416.272436 -12.629808) (xy 416.23835 -12.585665) (xy 416.211054 -12.53703) (xy 416.191131 -12.484939)
			(xy 416.179005 -12.430502) (xy 416.174934 -12.37488) (xy 415.138362 -12.37488) (xy 415.137853 -12.402766)
			(xy 415.129733 -12.457942) (xy 415.113665 -12.511349) (xy 415.089993 -12.561846) (xy 415.05922 -12.608359)
			(xy 415.022003 -12.649896) (xy 414.979135 -12.685571) (xy 414.931529 -12.714625) (xy 414.8802 -12.736437)
			(xy 414.826243 -12.750543) (xy 414.770806 -12.756643) (xy 414.715072 -12.754606) (xy 414.660229 -12.744476)
			(xy 414.607445 -12.726469) (xy 414.557845 -12.700968) (xy 414.512487 -12.668517) (xy 414.472338 -12.629808)
			(xy 414.438252 -12.585665) (xy 414.410956 -12.53703) (xy 414.391033 -12.484939) (xy 414.378907 -12.430502)
			(xy 414.374836 -12.37488) (xy 413.338264 -12.37488) (xy 413.33768 -12.404486) (xy 413.328496 -12.462983)
			(xy 413.310406 -12.519365) (xy 413.297624 -12.546076) (xy 413.281114 -12.578842) (xy 414.06826 -13.365988)
			(xy 434.35778 -13.365988) (xy 435.01818 -12.705588) (xy 435.01818 -8.837168) (xy 434.16982 -7.988808)
			(xy 395.859 -7.988808) (xy 394.946378 -8.90143) (xy 394.936484 -8.912041) (xy 394.922561 -8.937477)
			(xy 394.916348 -8.965801) (xy 394.918345 -8.994729) (xy 394.928393 -9.02193) (xy 394.945681 -9.04521)
			(xy 394.968815 -9.062694) (xy 394.982192 -9.068308) (xy 395.008944 -9.07903) (xy 395.059132 -9.107358)
			(xy 395.104491 -9.14291) (xy 395.143989 -9.184877) (xy 395.176728 -9.232307) (xy 395.201963 -9.284119)
			(xy 395.219122 -9.339137) (xy 395.227813 -9.396109) (xy 395.228318 -9.424924) (xy 395.227816 -9.452693)
			(xy 395.21976 -9.507644) (xy 395.203822 -9.560846) (xy 395.180338 -9.611175) (xy 395.149805 -9.657567)
			(xy 395.112868 -9.699042) (xy 395.09192 -9.717278) (xy 395.080949 -9.727188) (xy 395.064755 -9.751907)
			(xy 395.056305 -9.780225) (xy 395.056306 -9.809777) (xy 395.064756 -9.838095) (xy 395.08095 -9.862814)
			(xy 395.09192 -9.872726) (xy 395.112879 -9.890951) (xy 395.149817 -9.932427) (xy 395.180351 -9.978821)
			(xy 395.203836 -10.029153) (xy 395.219774 -10.082357) (xy 395.22783 -10.13731) (xy 395.228318 -10.16508)
			(xy 396.2654 -10.16508) (xy 396.265882 -10.13731) (xy 396.273938 -10.082356) (xy 396.289877 -10.029151)
			(xy 396.313363 -9.97882) (xy 396.343898 -9.932426) (xy 396.380838 -9.89095) (xy 396.401798 -9.872726)
			(xy 396.412775 -9.862818) (xy 396.428982 -9.838101) (xy 396.43744 -9.80978) (xy 396.43744 -9.780223)
			(xy 396.428983 -9.751901) (xy 396.412777 -9.727184) (xy 396.401798 -9.717278) (xy 396.380854 -9.699037)
			(xy 396.343916 -9.657564) (xy 396.313382 -9.611173) (xy 396.289898 -9.560845) (xy 396.273959 -9.507643)
			(xy 396.265902 -9.452693) (xy 396.2654 -9.424924) (xy 396.265886 -9.397673) (xy 396.273642 -9.343725)
			(xy 396.288997 -9.29143) (xy 396.311639 -9.241853) (xy 396.341105 -9.196003) (xy 396.376796 -9.154812)
			(xy 396.417987 -9.119121) (xy 396.463837 -9.089655) (xy 396.513414 -9.067013) (xy 396.565709 -9.051658)
			(xy 396.619657 -9.043902) (xy 396.674159 -9.043902) (xy 396.728107 -9.051658) (xy 396.780402 -9.067013)
			(xy 396.829979 -9.089655) (xy 396.875829 -9.119121) (xy 396.91702 -9.154812) (xy 396.952711 -9.196003)
			(xy 396.982177 -9.241853) (xy 397.004819 -9.29143) (xy 397.020174 -9.343725) (xy 397.02793 -9.397673)
			(xy 397.028416 -9.424924) (xy 397.027932 -9.452694) (xy 397.019875 -9.507648) (xy 397.003936 -9.560852)
			(xy 396.980451 -9.611183) (xy 396.949916 -9.657577) (xy 396.912978 -9.699054) (xy 396.892018 -9.717278)
			(xy 396.881045 -9.727186) (xy 396.864851 -9.751906) (xy 396.856401 -9.780225) (xy 396.856402 -9.809777)
			(xy 396.864852 -9.838096) (xy 396.881046 -9.862816) (xy 396.892018 -9.872726) (xy 396.912967 -9.890961)
			(xy 396.949904 -9.932436) (xy 396.980437 -9.978829) (xy 397.00392 -10.029158) (xy 397.019858 -10.08236)
			(xy 397.027914 -10.137311) (xy 397.028416 -10.16508) (xy 398.065244 -10.16508) (xy 398.06571 -10.137309)
			(xy 398.073768 -10.082354) (xy 398.089709 -10.029148) (xy 398.113197 -9.978817) (xy 398.143736 -9.932424)
			(xy 398.18068 -9.890949) (xy 398.201642 -9.872726) (xy 398.212615 -9.862816) (xy 398.228815 -9.838098)
			(xy 398.237269 -9.809778) (xy 398.237269 -9.780224) (xy 398.228816 -9.751905) (xy 398.212617 -9.727186)
			(xy 398.201642 -9.717278) (xy 398.180686 -9.69905) (xy 398.143752 -9.657573) (xy 398.113221 -9.611178)
			(xy 398.089738 -9.560848) (xy 398.073801 -9.507645) (xy 398.065746 -9.452693) (xy 398.065244 -9.424924)
			(xy 398.06573 -9.397673) (xy 398.073486 -9.343725) (xy 398.088841 -9.29143) (xy 398.111483 -9.241853)
			(xy 398.140949 -9.196003) (xy 398.17664 -9.154812) (xy 398.217831 -9.119121) (xy 398.263681 -9.089655)
			(xy 398.313258 -9.067013) (xy 398.365553 -9.051658) (xy 398.419501 -9.043902) (xy 398.474003 -9.043902)
			(xy 398.527951 -9.051658) (xy 398.580246 -9.067013) (xy 398.629823 -9.089655) (xy 398.675673 -9.119121)
			(xy 398.716864 -9.154812) (xy 398.752555 -9.196003) (xy 398.782021 -9.241853) (xy 398.804663 -9.29143)
			(xy 398.820018 -9.343725) (xy 398.827774 -9.397673) (xy 398.82826 -9.424924) (xy 398.827795 -9.452695)
			(xy 398.819737 -9.50765) (xy 398.803795 -9.560856) (xy 398.780307 -9.611187) (xy 398.749768 -9.65758)
			(xy 398.712824 -9.699055) (xy 398.691862 -9.717278) (xy 398.680885 -9.727184) (xy 398.664684 -9.751903)
			(xy 398.656231 -9.780224) (xy 398.656231 -9.809779) (xy 398.664685 -9.838099) (xy 398.680887 -9.862818)
			(xy 398.691862 -9.872726) (xy 398.71282 -9.890951) (xy 398.749755 -9.932429) (xy 398.780285 -9.978824)
			(xy 398.803767 -10.029155) (xy 398.819704 -10.082359) (xy 398.827759 -10.13731) (xy 398.82826 -10.16508)
			(xy 399.865342 -10.16508) (xy 399.865809 -10.137309) (xy 399.873866 -10.082354) (xy 399.889808 -10.029148)
			(xy 399.913296 -9.978817) (xy 399.943835 -9.932424) (xy 399.980778 -9.890949) (xy 400.00174 -9.872726)
			(xy 400.012713 -9.862816) (xy 400.028914 -9.838098) (xy 400.037367 -9.809778) (xy 400.037368 -9.780224)
			(xy 400.028915 -9.751905) (xy 400.012715 -9.727186) (xy 400.00174 -9.717278) (xy 399.980784 -9.699051)
			(xy 399.943849 -9.657573) (xy 399.913318 -9.611179) (xy 399.889836 -9.560848) (xy 399.873899 -9.507645)
			(xy 399.865844 -9.452693) (xy 399.865342 -9.424924) (xy 399.865828 -9.397673) (xy 399.873584 -9.343725)
			(xy 399.888939 -9.29143) (xy 399.911581 -9.241853) (xy 399.941047 -9.196003) (xy 399.976738 -9.154812)
			(xy 400.017929 -9.119121) (xy 400.063779 -9.089655) (xy 400.113356 -9.067013) (xy 400.165651 -9.051658)
			(xy 400.219599 -9.043902) (xy 400.274101 -9.043902) (xy 400.328049 -9.051658) (xy 400.380344 -9.067013)
			(xy 400.429921 -9.089655) (xy 400.475771 -9.119121) (xy 400.516962 -9.154812) (xy 400.552653 -9.196003)
			(xy 400.582119 -9.241853) (xy 400.604761 -9.29143) (xy 400.620116 -9.343725) (xy 400.627872 -9.397673)
			(xy 400.628358 -9.424924) (xy 400.627894 -9.452695) (xy 400.619836 -9.50765) (xy 400.603894 -9.560856)
			(xy 400.580405 -9.611187) (xy 400.549866 -9.657581) (xy 400.512922 -9.699055) (xy 400.49196 -9.717278)
			(xy 400.480983 -9.727184) (xy 400.464782 -9.751903) (xy 400.456329 -9.780224) (xy 400.45633 -9.809779)
			(xy 400.464784 -9.838099) (xy 400.480985 -9.862818) (xy 400.49196 -9.872726) (xy 400.512918 -9.890951)
			(xy 400.549852 -9.932429) (xy 400.580383 -9.978824) (xy 400.603865 -10.029155) (xy 400.619802 -10.082359)
			(xy 400.627857 -10.13731) (xy 400.628358 -10.16508) (xy 401.66544 -10.16508) (xy 401.665908 -10.137309)
			(xy 401.673965 -10.082354) (xy 401.689906 -10.029149) (xy 401.713394 -9.978817) (xy 401.743933 -9.932424)
			(xy 401.780876 -9.890949) (xy 401.801838 -9.872726) (xy 401.812811 -9.862816) (xy 401.829012 -9.838098)
			(xy 401.837466 -9.809778) (xy 401.837466 -9.780224) (xy 401.829013 -9.751904) (xy 401.812813 -9.727186)
			(xy 401.801838 -9.717278) (xy 401.780882 -9.699051) (xy 401.743947 -9.657573) (xy 401.713416 -9.611179)
			(xy 401.689934 -9.560848) (xy 401.673997 -9.507645) (xy 401.665942 -9.452693) (xy 401.66544 -9.424924)
			(xy 401.665926 -9.397673) (xy 401.673682 -9.343725) (xy 401.689037 -9.29143) (xy 401.711679 -9.241853)
			(xy 401.741145 -9.196003) (xy 401.776836 -9.154812) (xy 401.818027 -9.119121) (xy 401.863877 -9.089655)
			(xy 401.913454 -9.067013) (xy 401.965749 -9.051658) (xy 402.019697 -9.043902) (xy 402.074199 -9.043902)
			(xy 402.128147 -9.051658) (xy 402.180442 -9.067013) (xy 402.230019 -9.089655) (xy 402.275869 -9.119121)
			(xy 402.31706 -9.154812) (xy 402.352751 -9.196003) (xy 402.382217 -9.241853) (xy 402.404859 -9.29143)
			(xy 402.420214 -9.343725) (xy 402.42797 -9.397673) (xy 402.428456 -9.424924) (xy 402.427992 -9.452695)
			(xy 402.419934 -9.50765) (xy 402.403993 -9.560856) (xy 402.380504 -9.611187) (xy 402.349964 -9.657581)
			(xy 402.31302 -9.699055) (xy 402.292058 -9.717278) (xy 402.281081 -9.727184) (xy 402.264881 -9.751903)
			(xy 402.256428 -9.780224) (xy 402.256428 -9.809779) (xy 402.264882 -9.838099) (xy 402.281083 -9.862818)
			(xy 402.292058 -9.872726) (xy 402.313016 -9.890952) (xy 402.34995 -9.93243) (xy 402.380481 -9.978824)
			(xy 402.403963 -10.029155) (xy 402.4199 -10.082359) (xy 402.427955 -10.13731) (xy 402.428456 -10.16508)
			(xy 403.465284 -10.16508) (xy 403.465771 -10.13731) (xy 403.473827 -10.082357) (xy 403.489766 -10.029152)
			(xy 403.51325 -9.978821) (xy 403.543784 -9.932427) (xy 403.580722 -9.890951) (xy 403.601682 -9.872726)
			(xy 403.612651 -9.862814) (xy 403.628845 -9.838095) (xy 403.637295 -9.809777) (xy 403.637296 -9.780226)
			(xy 403.628847 -9.751908) (xy 403.612653 -9.727188) (xy 403.601682 -9.717278) (xy 403.580735 -9.699041)
			(xy 403.543798 -9.657566) (xy 403.513265 -9.611174) (xy 403.489781 -9.560846) (xy 403.473842 -9.507644)
			(xy 403.465786 -9.452693) (xy 403.465284 -9.424924) (xy 403.46577 -9.397673) (xy 403.473526 -9.343725)
			(xy 403.488881 -9.29143) (xy 403.511523 -9.241853) (xy 403.540989 -9.196003) (xy 403.57668 -9.154812)
			(xy 403.617871 -9.119121) (xy 403.663721 -9.089655) (xy 403.713298 -9.067013) (xy 403.765593 -9.051658)
			(xy 403.819541 -9.043902) (xy 403.874043 -9.043902) (xy 403.927991 -9.051658) (xy 403.980286 -9.067013)
			(xy 404.029863 -9.089655) (xy 404.075713 -9.119121) (xy 404.116904 -9.154812) (xy 404.152595 -9.196003)
			(xy 404.182061 -9.241853) (xy 404.204703 -9.29143) (xy 404.220058 -9.343725) (xy 404.227814 -9.397673)
			(xy 404.2283 -9.424924) (xy 404.227821 -9.452695) (xy 404.219764 -9.507648) (xy 404.203824 -9.560853)
			(xy 404.180338 -9.611184) (xy 404.149803 -9.657578) (xy 404.112863 -9.699054) (xy 404.091902 -9.717278)
			(xy 404.080921 -9.727182) (xy 404.064714 -9.7519) (xy 404.056257 -9.780222) (xy 404.056257 -9.80978)
			(xy 404.064715 -9.838102) (xy 404.080923 -9.86282) (xy 404.091902 -9.872726) (xy 404.112848 -9.890965)
			(xy 404.149786 -9.932439) (xy 404.180319 -9.97883) (xy 404.203804 -10.029159) (xy 404.219742 -10.08236)
			(xy 404.227798 -10.137311) (xy 404.2283 -10.16508) (xy 405.265382 -10.16508) (xy 405.26587 -10.13731)
			(xy 405.273926 -10.082357) (xy 405.289864 -10.029153) (xy 405.313349 -9.978821) (xy 405.343883 -9.932427)
			(xy 405.380821 -9.890951) (xy 405.40178 -9.872726) (xy 405.41275 -9.862814) (xy 405.428944 -9.838095)
			(xy 405.437394 -9.809777) (xy 405.437395 -9.780225) (xy 405.428945 -9.751907) (xy 405.412751 -9.727188)
			(xy 405.40178 -9.717278) (xy 405.380832 -9.699042) (xy 405.343895 -9.657567) (xy 405.313362 -9.611175)
			(xy 405.289878 -9.560846) (xy 405.27394 -9.507644) (xy 405.265884 -9.452693) (xy 405.265382 -9.424924)
			(xy 405.265868 -9.397673) (xy 405.273624 -9.343725) (xy 405.288979 -9.29143) (xy 405.311621 -9.241853)
			(xy 405.341087 -9.196003) (xy 405.376778 -9.154812) (xy 405.417969 -9.119121) (xy 405.463819 -9.089655)
			(xy 405.513396 -9.067013) (xy 405.565691 -9.051658) (xy 405.619639 -9.043902) (xy 405.674141 -9.043902)
			(xy 405.728089 -9.051658) (xy 405.780384 -9.067013) (xy 405.829961 -9.089655) (xy 405.875811 -9.119121)
			(xy 405.917002 -9.154812) (xy 405.952693 -9.196003) (xy 405.982159 -9.241853) (xy 406.004801 -9.29143)
			(xy 406.020156 -9.343725) (xy 406.027912 -9.397673) (xy 406.028398 -9.424924) (xy 406.02792 -9.452695)
			(xy 406.019863 -9.507648) (xy 406.003923 -9.560853) (xy 405.980437 -9.611184) (xy 405.949901 -9.657578)
			(xy 405.912961 -9.699054) (xy 405.892 -9.717278) (xy 405.881019 -9.727182) (xy 405.864812 -9.7519)
			(xy 405.856355 -9.780222) (xy 405.856356 -9.80978) (xy 405.864813 -9.838102) (xy 405.881021 -9.86282)
			(xy 405.892 -9.872726) (xy 405.912946 -9.890965) (xy 405.949883 -9.932439) (xy 405.980417 -9.97883)
			(xy 406.003901 -10.029159) (xy 406.01984 -10.08236) (xy 406.027896 -10.137311) (xy 406.028398 -10.16508)
			(xy 407.06548 -10.16508) (xy 407.065969 -10.13731) (xy 407.074024 -10.082357) (xy 407.089963 -10.029153)
			(xy 407.113447 -9.978822) (xy 407.143981 -9.932427) (xy 407.180919 -9.890951) (xy 407.201878 -9.872726)
			(xy 407.212848 -9.862814) (xy 407.229043 -9.838095) (xy 407.237493 -9.809777) (xy 407.237493 -9.780225)
			(xy 407.229044 -9.751907) (xy 407.21285 -9.727188) (xy 407.201878 -9.717278) (xy 407.18093 -9.699042)
			(xy 407.143993 -9.657567) (xy 407.11346 -9.611175) (xy 407.089976 -9.560846) (xy 407.074038 -9.507644)
			(xy 407.065982 -9.452693) (xy 407.06548 -9.424924) (xy 407.065966 -9.397673) (xy 407.073722 -9.343725)
			(xy 407.089077 -9.29143) (xy 407.111719 -9.241853) (xy 407.141185 -9.196003) (xy 407.176876 -9.154812)
			(xy 407.218067 -9.119121) (xy 407.263917 -9.089655) (xy 407.313494 -9.067013) (xy 407.365789 -9.051658)
			(xy 407.419737 -9.043902) (xy 407.474239 -9.043902) (xy 407.528187 -9.051658) (xy 407.580482 -9.067013)
			(xy 407.630059 -9.089655) (xy 407.675909 -9.119121) (xy 407.7171 -9.154812) (xy 407.752791 -9.196003)
			(xy 407.782257 -9.241853) (xy 407.804899 -9.29143) (xy 407.820254 -9.343725) (xy 407.82801 -9.397673)
			(xy 407.828496 -9.424924) (xy 407.828019 -9.452695) (xy 407.819962 -9.507648) (xy 407.804022 -9.560853)
			(xy 407.780535 -9.611185) (xy 407.749999 -9.657578) (xy 407.713059 -9.699054) (xy 407.692098 -9.717278)
			(xy 407.681117 -9.727182) (xy 407.664911 -9.7519) (xy 407.656454 -9.780222) (xy 407.656455 -9.80978)
			(xy 407.664912 -9.838102) (xy 407.681119 -9.86282) (xy 407.692098 -9.872726) (xy 407.713043 -9.890966)
			(xy 407.749981 -9.932439) (xy 407.780515 -9.97883) (xy 407.803999 -10.029159) (xy 407.819938 -10.082361)
			(xy 407.827994 -10.137311) (xy 407.828496 -10.16508) (xy 412.575248 -10.16508) (xy 412.575748 -10.13731)
			(xy 412.583803 -10.082358) (xy 412.59974 -10.029155) (xy 412.623222 -9.978824) (xy 412.653753 -9.932429)
			(xy 412.690688 -9.890952) (xy 412.711646 -9.872726) (xy 412.722618 -9.862816) (xy 412.738818 -9.838097)
			(xy 412.747271 -9.809778) (xy 412.747272 -9.780224) (xy 412.738819 -9.751905) (xy 412.72262 -9.727186)
			(xy 412.711646 -9.717278) (xy 412.690691 -9.699049) (xy 412.653756 -9.657572) (xy 412.623225 -9.611178)
			(xy 412.599743 -9.560848) (xy 412.583805 -9.507645) (xy 412.57575 -9.452693) (xy 412.575248 -9.424924)
			(xy 412.575734 -9.397673) (xy 412.58349 -9.343725) (xy 412.598845 -9.29143) (xy 412.621487 -9.241853)
			(xy 412.650953 -9.196003) (xy 412.686644 -9.154812) (xy 412.727835 -9.119121) (xy 412.773685 -9.089655)
			(xy 412.823262 -9.067013) (xy 412.875557 -9.051658) (xy 412.929505 -9.043902) (xy 412.984007 -9.043902)
			(xy 413.037955 -9.051658) (xy 413.09025 -9.067013) (xy 413.139827 -9.089655) (xy 413.185677 -9.119121)
			(xy 413.226868 -9.154812) (xy 413.262559 -9.196003) (xy 413.292025 -9.241853) (xy 413.314667 -9.29143)
			(xy 413.330022 -9.343725) (xy 413.337778 -9.397673) (xy 413.338264 -9.424924) (xy 413.337797 -9.452695)
			(xy 413.32974 -9.50765) (xy 413.313798 -9.560855) (xy 413.29031 -9.611187) (xy 413.259771 -9.65758)
			(xy 413.222828 -9.699055) (xy 413.201866 -9.717278) (xy 413.190888 -9.727184) (xy 413.174687 -9.751903)
			(xy 413.166233 -9.780224) (xy 413.166234 -9.809779) (xy 413.174688 -9.8381) (xy 413.19089 -9.862818)
			(xy 413.201866 -9.872726) (xy 413.222825 -9.89095) (xy 413.259759 -9.932429) (xy 413.29029 -9.978824)
			(xy 413.313771 -10.029155) (xy 413.329708 -10.082358) (xy 413.337763 -10.13731) (xy 413.338264 -10.16508)
			(xy 414.375346 -10.16508) (xy 414.375812 -10.137309) (xy 414.383869 -10.082354) (xy 414.399811 -10.029148)
			(xy 414.423299 -9.978817) (xy 414.453838 -9.932423) (xy 414.490782 -9.890949) (xy 414.511744 -9.872726)
			(xy 414.522717 -9.862816) (xy 414.538917 -9.838097) (xy 414.54737 -9.809778) (xy 414.54737 -9.780224)
			(xy 414.538918 -9.751905) (xy 414.522718 -9.727186) (xy 414.511744 -9.717278) (xy 414.490789 -9.69905)
			(xy 414.453854 -9.657572) (xy 414.423323 -9.611178) (xy 414.399841 -9.560848) (xy 414.383903 -9.507645)
			(xy 414.375848 -9.452693) (xy 414.375346 -9.424924) (xy 414.375832 -9.397673) (xy 414.383588 -9.343725)
			(xy 414.398943 -9.29143) (xy 414.421585 -9.241853) (xy 414.451051 -9.196003) (xy 414.486742 -9.154812)
			(xy 414.527933 -9.119121) (xy 414.573783 -9.089655) (xy 414.62336 -9.067013) (xy 414.675655 -9.051658)
			(xy 414.729603 -9.043902) (xy 414.784105 -9.043902) (xy 414.838053 -9.051658) (xy 414.890348 -9.067013)
			(xy 414.939925 -9.089655) (xy 414.985775 -9.119121) (xy 415.026966 -9.154812) (xy 415.062657 -9.196003)
			(xy 415.092123 -9.241853) (xy 415.114765 -9.29143) (xy 415.13012 -9.343725) (xy 415.137876 -9.397673)
			(xy 415.138362 -9.424924) (xy 415.137896 -9.452695) (xy 415.129838 -9.50765) (xy 415.113897 -9.560856)
			(xy 415.090408 -9.611187) (xy 415.05987 -9.65758) (xy 415.022926 -9.699055) (xy 415.001964 -9.717278)
			(xy 414.990987 -9.727184) (xy 414.974785 -9.751903) (xy 414.966332 -9.780224) (xy 414.966332 -9.809779)
			(xy 414.974787 -9.838099) (xy 414.990988 -9.862818) (xy 415.001964 -9.872726) (xy 415.022923 -9.89095)
			(xy 415.059857 -9.932429) (xy 415.090387 -9.978824) (xy 415.113869 -10.029155) (xy 415.129806 -10.082358)
			(xy 415.137861 -10.13731) (xy 415.138362 -10.16508) (xy 416.175444 -10.16508) (xy 416.17591 -10.137309)
			(xy 416.183968 -10.082354) (xy 416.199909 -10.029148) (xy 416.223397 -9.978817) (xy 416.253936 -9.932424)
			(xy 416.29088 -9.890949) (xy 416.311842 -9.872726) (xy 416.322815 -9.862816) (xy 416.339015 -9.838098)
			(xy 416.347469 -9.809778) (xy 416.347469 -9.780224) (xy 416.339016 -9.751905) (xy 416.322817 -9.727186)
			(xy 416.311842 -9.717278) (xy 416.290886 -9.69905) (xy 416.253952 -9.657573) (xy 416.223421 -9.611178)
			(xy 416.199938 -9.560848) (xy 416.184001 -9.507645) (xy 416.175946 -9.452693) (xy 416.175444 -9.424924)
			(xy 416.17593 -9.397673) (xy 416.183686 -9.343725) (xy 416.199041 -9.29143) (xy 416.221683 -9.241853)
			(xy 416.251149 -9.196003) (xy 416.28684 -9.154812) (xy 416.328031 -9.119121) (xy 416.373881 -9.089655)
			(xy 416.423458 -9.067013) (xy 416.475753 -9.051658) (xy 416.529701 -9.043902) (xy 416.584203 -9.043902)
			(xy 416.638151 -9.051658) (xy 416.690446 -9.067013) (xy 416.740023 -9.089655) (xy 416.785873 -9.119121)
			(xy 416.827064 -9.154812) (xy 416.862755 -9.196003) (xy 416.892221 -9.241853) (xy 416.914863 -9.29143)
			(xy 416.930218 -9.343725) (xy 416.937974 -9.397673) (xy 416.93846 -9.424924) (xy 416.937995 -9.452695)
			(xy 416.929937 -9.50765) (xy 416.913995 -9.560856) (xy 416.890507 -9.611187) (xy 416.859968 -9.65758)
			(xy 416.823024 -9.699055) (xy 416.802062 -9.717278) (xy 416.791085 -9.727184) (xy 416.774884 -9.751903)
			(xy 416.766431 -9.780224) (xy 416.766431 -9.809779) (xy 416.774885 -9.838099) (xy 416.791087 -9.862818)
			(xy 416.802062 -9.872726) (xy 416.82302 -9.890951) (xy 416.859955 -9.932429) (xy 416.890485 -9.978824)
			(xy 416.913967 -10.029155) (xy 416.929904 -10.082359) (xy 416.937959 -10.13731) (xy 416.93846 -10.16508)
			(xy 417.975288 -10.16508) (xy 417.975774 -10.13731) (xy 417.98383 -10.082357) (xy 417.999769 -10.029152)
			(xy 418.023253 -9.978821) (xy 418.053788 -9.932427) (xy 418.090726 -9.89095) (xy 418.111686 -9.872726)
			(xy 418.122664 -9.862819) (xy 418.138873 -9.838102) (xy 418.147332 -9.80978) (xy 418.147332 -9.780222)
			(xy 418.138874 -9.7519) (xy 418.122666 -9.727183) (xy 418.111686 -9.717278) (xy 418.09074 -9.69904)
			(xy 418.053802 -9.657566) (xy 418.023269 -9.611174) (xy 417.999785 -9.560845) (xy 417.983846 -9.507644)
			(xy 417.97579 -9.452693) (xy 417.975288 -9.424924) (xy 417.975774 -9.397673) (xy 417.98353 -9.343725)
			(xy 417.998885 -9.29143) (xy 418.021527 -9.241853) (xy 418.050993 -9.196003) (xy 418.086684 -9.154812)
			(xy 418.127875 -9.119121) (xy 418.173725 -9.089655) (xy 418.223302 -9.067013) (xy 418.275597 -9.051658)
			(xy 418.329545 -9.043902) (xy 418.384047 -9.043902) (xy 418.437995 -9.051658) (xy 418.49029 -9.067013)
			(xy 418.539867 -9.089655) (xy 418.585717 -9.119121) (xy 418.626908 -9.154812) (xy 418.662599 -9.196003)
			(xy 418.692065 -9.241853) (xy 418.714707 -9.29143) (xy 418.730062 -9.343725) (xy 418.737818 -9.397673)
			(xy 418.738304 -9.424924) (xy 418.737824 -9.452694) (xy 418.729767 -9.507648) (xy 418.713827 -9.560853)
			(xy 418.690342 -9.611184) (xy 418.659806 -9.657578) (xy 418.622866 -9.699054) (xy 418.601906 -9.717278)
			(xy 418.590925 -9.727182) (xy 418.574717 -9.7519) (xy 418.566259 -9.780222) (xy 418.56626 -9.80978)
			(xy 418.574718 -9.838103) (xy 418.590926 -9.86282) (xy 418.601906 -9.872726) (xy 418.622853 -9.890964)
			(xy 418.65979 -9.932438) (xy 418.690324 -9.97883) (xy 418.713808 -10.029158) (xy 418.729746 -10.08236)
			(xy 418.737802 -10.137311) (xy 418.738304 -10.16508) (xy 419.775386 -10.16508) (xy 419.775873 -10.13731)
			(xy 419.783928 -10.082357) (xy 419.799867 -10.029152) (xy 419.823352 -9.978821) (xy 419.853886 -9.932427)
			(xy 419.890824 -9.89095) (xy 419.911784 -9.872726) (xy 419.922762 -9.862819) (xy 419.938972 -9.838102)
			(xy 419.947431 -9.80978) (xy 419.947431 -9.780222) (xy 419.938973 -9.7519) (xy 419.922764 -9.727183)
			(xy 419.911784 -9.717278) (xy 419.890837 -9.69904) (xy 419.8539 -9.657566) (xy 419.823367 -9.611174)
			(xy 419.799883 -9.560845) (xy 419.783944 -9.507644) (xy 419.775888 -9.452693) (xy 419.775386 -9.424924)
			(xy 419.775872 -9.397673) (xy 419.783628 -9.343725) (xy 419.798983 -9.29143) (xy 419.821625 -9.241853)
			(xy 419.851091 -9.196003) (xy 419.886782 -9.154812) (xy 419.927973 -9.119121) (xy 419.973823 -9.089655)
			(xy 420.0234 -9.067013) (xy 420.075695 -9.051658) (xy 420.129643 -9.043902) (xy 420.184145 -9.043902)
			(xy 420.238093 -9.051658) (xy 420.290388 -9.067013) (xy 420.339965 -9.089655) (xy 420.385815 -9.119121)
			(xy 420.427006 -9.154812) (xy 420.462697 -9.196003) (xy 420.492163 -9.241853) (xy 420.514805 -9.29143)
			(xy 420.53016 -9.343725) (xy 420.537916 -9.397673) (xy 420.538402 -9.424924) (xy 420.537922 -9.452695)
			(xy 420.529866 -9.507648) (xy 420.513926 -9.560853) (xy 420.49044 -9.611184) (xy 420.459904 -9.657578)
			(xy 420.422964 -9.699054) (xy 420.402004 -9.717278) (xy 420.391023 -9.727182) (xy 420.374815 -9.7519)
			(xy 420.366358 -9.780222) (xy 420.366358 -9.80978) (xy 420.374816 -9.838102) (xy 420.391025 -9.86282)
			(xy 420.402004 -9.872726) (xy 420.42295 -9.890964) (xy 420.459888 -9.932438) (xy 420.490422 -9.97883)
			(xy 420.513906 -10.029158) (xy 420.529844 -10.08236) (xy 420.5379 -10.137311) (xy 420.538402 -10.16508)
			(xy 423.785284 -10.16508) (xy 423.785771 -10.13731) (xy 423.793827 -10.082357) (xy 423.809766 -10.029152)
			(xy 423.83325 -9.978821) (xy 423.863784 -9.932427) (xy 423.900722 -9.890951) (xy 423.921682 -9.872726)
			(xy 423.932651 -9.862814) (xy 423.948845 -9.838095) (xy 423.957295 -9.809777) (xy 423.957296 -9.780226)
			(xy 423.948847 -9.751908) (xy 423.932653 -9.727188) (xy 423.921682 -9.717278) (xy 423.900735 -9.699041)
			(xy 423.863798 -9.657566) (xy 423.833265 -9.611174) (xy 423.809781 -9.560846) (xy 423.793842 -9.507644)
			(xy 423.785786 -9.452693) (xy 423.785284 -9.424924) (xy 423.78577 -9.397673) (xy 423.793526 -9.343725)
			(xy 423.808881 -9.29143) (xy 423.831523 -9.241853) (xy 423.860989 -9.196003) (xy 423.89668 -9.154812)
			(xy 423.937871 -9.119121) (xy 423.983721 -9.089655) (xy 424.033298 -9.067013) (xy 424.085593 -9.051658)
			(xy 424.139541 -9.043902) (xy 424.194043 -9.043902) (xy 424.247991 -9.051658) (xy 424.300286 -9.067013)
			(xy 424.349863 -9.089655) (xy 424.395713 -9.119121) (xy 424.436904 -9.154812) (xy 424.472595 -9.196003)
			(xy 424.502061 -9.241853) (xy 424.524703 -9.29143) (xy 424.540058 -9.343725) (xy 424.547814 -9.397673)
			(xy 424.5483 -9.424924) (xy 424.547821 -9.452695) (xy 424.539764 -9.507648) (xy 424.523824 -9.560853)
			(xy 424.500338 -9.611184) (xy 424.469803 -9.657578) (xy 424.432863 -9.699054) (xy 424.411902 -9.717278)
			(xy 424.400921 -9.727182) (xy 424.384714 -9.7519) (xy 424.376257 -9.780222) (xy 424.376257 -9.80978)
			(xy 424.384715 -9.838102) (xy 424.400923 -9.86282) (xy 424.411902 -9.872726) (xy 424.432848 -9.890965)
			(xy 424.469786 -9.932439) (xy 424.500319 -9.97883) (xy 424.523804 -10.029159) (xy 424.539742 -10.08236)
			(xy 424.547798 -10.137311) (xy 424.5483 -10.16508) (xy 425.585382 -10.16508) (xy 425.58587 -10.13731)
			(xy 425.593926 -10.082357) (xy 425.609864 -10.029153) (xy 425.633349 -9.978821) (xy 425.663883 -9.932427)
			(xy 425.700821 -9.890951) (xy 425.72178 -9.872726) (xy 425.73275 -9.862814) (xy 425.748944 -9.838095)
			(xy 425.757394 -9.809777) (xy 425.757395 -9.780225) (xy 425.748945 -9.751907) (xy 425.732751 -9.727188)
			(xy 425.72178 -9.717278) (xy 425.700832 -9.699042) (xy 425.663895 -9.657567) (xy 425.633362 -9.611175)
			(xy 425.609878 -9.560846) (xy 425.59394 -9.507644) (xy 425.585884 -9.452693) (xy 425.585382 -9.424924)
			(xy 425.585868 -9.397673) (xy 425.593624 -9.343725) (xy 425.608979 -9.29143) (xy 425.631621 -9.241853)
			(xy 425.661087 -9.196003) (xy 425.696778 -9.154812) (xy 425.737969 -9.119121) (xy 425.783819 -9.089655)
			(xy 425.833396 -9.067013) (xy 425.885691 -9.051658) (xy 425.939639 -9.043902) (xy 425.994141 -9.043902)
			(xy 426.048089 -9.051658) (xy 426.100384 -9.067013) (xy 426.149961 -9.089655) (xy 426.195811 -9.119121)
			(xy 426.237002 -9.154812) (xy 426.272693 -9.196003) (xy 426.302159 -9.241853) (xy 426.324801 -9.29143)
			(xy 426.340156 -9.343725) (xy 426.347912 -9.397673) (xy 426.348398 -9.424924) (xy 426.34792 -9.452695)
			(xy 426.339863 -9.507648) (xy 426.323923 -9.560853) (xy 426.300437 -9.611184) (xy 426.269901 -9.657578)
			(xy 426.232961 -9.699054) (xy 426.212 -9.717278) (xy 426.201019 -9.727182) (xy 426.184812 -9.7519)
			(xy 426.176355 -9.780222) (xy 426.176356 -9.80978) (xy 426.184813 -9.838102) (xy 426.201021 -9.86282)
			(xy 426.212 -9.872726) (xy 426.232946 -9.890965) (xy 426.269883 -9.932439) (xy 426.300417 -9.97883)
			(xy 426.323901 -10.029159) (xy 426.33984 -10.08236) (xy 426.347896 -10.137311) (xy 426.348398 -10.16508)
			(xy 427.38548 -10.16508) (xy 427.385969 -10.13731) (xy 427.394024 -10.082357) (xy 427.409963 -10.029153)
			(xy 427.433447 -9.978822) (xy 427.463981 -9.932427) (xy 427.500919 -9.890951) (xy 427.521878 -9.872726)
			(xy 427.532848 -9.862814) (xy 427.549043 -9.838095) (xy 427.557493 -9.809777) (xy 427.557493 -9.780225)
			(xy 427.549044 -9.751907) (xy 427.53285 -9.727188) (xy 427.521878 -9.717278) (xy 427.50093 -9.699042)
			(xy 427.463993 -9.657567) (xy 427.43346 -9.611175) (xy 427.409976 -9.560846) (xy 427.394038 -9.507644)
			(xy 427.385982 -9.452693) (xy 427.38548 -9.424924) (xy 427.385966 -9.397673) (xy 427.393722 -9.343725)
			(xy 427.409077 -9.29143) (xy 427.431719 -9.241853) (xy 427.461185 -9.196003) (xy 427.496876 -9.154812)
			(xy 427.538067 -9.119121) (xy 427.583917 -9.089655) (xy 427.633494 -9.067013) (xy 427.685789 -9.051658)
			(xy 427.739737 -9.043902) (xy 427.794239 -9.043902) (xy 427.848187 -9.051658) (xy 427.900482 -9.067013)
			(xy 427.950059 -9.089655) (xy 427.995909 -9.119121) (xy 428.0371 -9.154812) (xy 428.072791 -9.196003)
			(xy 428.102257 -9.241853) (xy 428.124899 -9.29143) (xy 428.140254 -9.343725) (xy 428.14801 -9.397673)
			(xy 428.148496 -9.424924) (xy 428.148019 -9.452695) (xy 428.139962 -9.507648) (xy 428.124022 -9.560853)
			(xy 428.100535 -9.611185) (xy 428.069999 -9.657578) (xy 428.033059 -9.699054) (xy 428.012098 -9.717278)
			(xy 428.001117 -9.727182) (xy 427.984911 -9.7519) (xy 427.976454 -9.780222) (xy 427.976455 -9.80978)
			(xy 427.984912 -9.838102) (xy 428.001119 -9.86282) (xy 428.012098 -9.872726) (xy 428.033043 -9.890966)
			(xy 428.069981 -9.932439) (xy 428.100515 -9.97883) (xy 428.123999 -10.029159) (xy 428.139938 -10.082361)
			(xy 428.147994 -10.137311) (xy 428.148496 -10.16508) (xy 429.185324 -10.16508) (xy 429.185798 -10.137309)
			(xy 429.193854 -10.082355) (xy 429.209795 -10.02915) (xy 429.233282 -9.978818) (xy 429.263819 -9.932425)
			(xy 429.300761 -9.89095) (xy 429.321722 -9.872726) (xy 429.332697 -9.862817) (xy 429.3489 -9.838099)
			(xy 429.357356 -9.809779) (xy 429.357356 -9.780224) (xy 429.348901 -9.751903) (xy 429.332698 -9.727185)
			(xy 429.321722 -9.717278) (xy 429.300783 -9.699032) (xy 429.263844 -9.65756) (xy 429.233308 -9.61117)
			(xy 429.209823 -9.560843) (xy 429.193883 -9.507642) (xy 429.185826 -9.452693) (xy 429.185324 -9.424924)
			(xy 429.18581 -9.397673) (xy 429.193566 -9.343725) (xy 429.208921 -9.29143) (xy 429.231563 -9.241853)
			(xy 429.261029 -9.196003) (xy 429.29672 -9.154812) (xy 429.337911 -9.119121) (xy 429.383761 -9.089655)
			(xy 429.433338 -9.067013) (xy 429.485633 -9.051658) (xy 429.539581 -9.043902) (xy 429.594083 -9.043902)
			(xy 429.648031 -9.051658) (xy 429.700326 -9.067013) (xy 429.749903 -9.089655) (xy 429.795753 -9.119121)
			(xy 429.836944 -9.154812) (xy 429.872635 -9.196003) (xy 429.902101 -9.241853) (xy 429.924743 -9.29143)
			(xy 429.940098 -9.343725) (xy 429.947854 -9.397673) (xy 429.94834 -9.424924) (xy 429.947847 -9.452694)
			(xy 429.939791 -9.507646) (xy 429.923853 -9.56085) (xy 429.90037 -9.611181) (xy 429.869837 -9.657575)
			(xy 429.832901 -9.699053) (xy 429.811942 -9.717278) (xy 429.800966 -9.727185) (xy 429.784769 -9.751904)
			(xy 429.776317 -9.780224) (xy 429.776317 -9.809778) (xy 429.78477 -9.838098) (xy 429.800968 -9.862817)
			(xy 429.811942 -9.872726) (xy 429.832896 -9.890955) (xy 429.869832 -9.932432) (xy 429.900363 -9.978826)
			(xy 429.923846 -10.029156) (xy 429.939783 -10.082359) (xy 429.947838 -10.137311) (xy 429.948129 -10.153396)
			(xy 430.865788 -10.153396) (xy 430.866327 -10.125256) (xy 430.874601 -10.069587) (xy 430.890968 -10.01574)
			(xy 430.915073 -9.964883) (xy 430.946393 -9.918123) (xy 430.984246 -9.876475) (xy 431.02781 -9.840843)
			(xy 431.051716 -9.82599) (xy 431.064173 -9.818024) (xy 431.084145 -9.796233) (xy 431.097057 -9.769643)
			(xy 431.101832 -9.740472) (xy 431.09807 -9.711153) (xy 431.086087 -9.684132) (xy 431.076862 -9.672574)
			(xy 431.059704 -9.651764) (xy 431.030809 -9.606223) (xy 431.008607 -9.55707) (xy 430.993541 -9.505283)
			(xy 430.985909 -9.451891) (xy 430.985422 -9.424924) (xy 430.985908 -9.397673) (xy 430.993664 -9.343725)
			(xy 431.009019 -9.29143) (xy 431.031661 -9.241853) (xy 431.061127 -9.196003) (xy 431.096818 -9.154812)
			(xy 431.138009 -9.119121) (xy 431.183859 -9.089655) (xy 431.233436 -9.067013) (xy 431.285731 -9.051658)
			(xy 431.339679 -9.043902) (xy 431.394181 -9.043902) (xy 431.448129 -9.051658) (xy 431.500424 -9.067013)
			(xy 431.550001 -9.089655) (xy 431.595851 -9.119121) (xy 431.637042 -9.154812) (xy 431.672733 -9.196003)
			(xy 431.702199 -9.241853) (xy 431.724841 -9.29143) (xy 431.740196 -9.343725) (xy 431.747952 -9.397673)
			(xy 431.748438 -9.424924) (xy 432.784756 -9.424924) (xy 432.788827 -9.369302) (xy 432.800953 -9.314865)
			(xy 432.820876 -9.262774) (xy 432.848172 -9.214139) (xy 432.882258 -9.169996) (xy 432.922407 -9.131287)
			(xy 432.967765 -9.098836) (xy 433.017365 -9.073335) (xy 433.070149 -9.055328) (xy 433.124992 -9.045198)
			(xy 433.180726 -9.043161) (xy 433.236163 -9.049261) (xy 433.29012 -9.063367) (xy 433.341449 -9.085179)
			(xy 433.389055 -9.114233) (xy 433.431923 -9.149908) (xy 433.46914 -9.191445) (xy 433.499913 -9.237958)
			(xy 433.523585 -9.288455) (xy 433.539653 -9.341862) (xy 433.547773 -9.397038) (xy 433.548282 -9.424924)
			(xy 433.547773 -9.45281) (xy 433.539653 -9.507986) (xy 433.523585 -9.561393) (xy 433.499913 -9.61189)
			(xy 433.46914 -9.658403) (xy 433.431923 -9.69994) (xy 433.389055 -9.735615) (xy 433.341449 -9.764669)
			(xy 433.29012 -9.786481) (xy 433.236163 -9.800587) (xy 433.180726 -9.806687) (xy 433.124992 -9.80465)
			(xy 433.070149 -9.79452) (xy 433.017365 -9.776513) (xy 432.967765 -9.751012) (xy 432.922407 -9.718561)
			(xy 432.882258 -9.679852) (xy 432.848172 -9.635709) (xy 432.820876 -9.587074) (xy 432.800953 -9.534983)
			(xy 432.788827 -9.480546) (xy 432.784756 -9.424924) (xy 431.748438 -9.424924) (xy 431.74795 -9.453066)
			(xy 431.739672 -9.508739) (xy 431.723298 -9.562589) (xy 431.699185 -9.613447) (xy 431.667857 -9.660207)
			(xy 431.629995 -9.701853) (xy 431.586421 -9.73748) (xy 431.56251 -9.75233) (xy 431.550121 -9.760393)
			(xy 431.530147 -9.782159) (xy 431.517228 -9.808726) (xy 431.512442 -9.837877) (xy 431.516186 -9.86718)
			(xy 431.52815 -9.894191) (xy 431.537364 -9.905746) (xy 431.554535 -9.926545) (xy 431.583427 -9.97209)
			(xy 431.605626 -10.021246) (xy 431.62069 -10.073035) (xy 431.628319 -10.126429) (xy 431.628804 -10.153396)
			(xy 431.628318 -10.180647) (xy 431.620562 -10.234595) (xy 431.605207 -10.28689) (xy 431.582565 -10.336467)
			(xy 431.553099 -10.382317) (xy 431.517408 -10.423508) (xy 431.476217 -10.459199) (xy 431.430367 -10.488665)
			(xy 431.38079 -10.511307) (xy 431.328495 -10.526662) (xy 431.274547 -10.534418) (xy 431.220045 -10.534418)
			(xy 431.166097 -10.526662) (xy 431.113802 -10.511307) (xy 431.064225 -10.488665) (xy 431.018375 -10.459199)
			(xy 430.977184 -10.423508) (xy 430.941493 -10.382317) (xy 430.912027 -10.336467) (xy 430.889385 -10.28689)
			(xy 430.87403 -10.234595) (xy 430.866274 -10.180647) (xy 430.865788 -10.153396) (xy 429.948129 -10.153396)
			(xy 429.94834 -10.16508) (xy 429.947854 -10.192331) (xy 429.940098 -10.246279) (xy 429.924743 -10.298574)
			(xy 429.902101 -10.348151) (xy 429.872635 -10.394001) (xy 429.836944 -10.435192) (xy 429.795753 -10.470883)
			(xy 429.749903 -10.500349) (xy 429.700326 -10.522991) (xy 429.648031 -10.538346) (xy 429.594083 -10.546102)
			(xy 429.539581 -10.546102) (xy 429.485633 -10.538346) (xy 429.433338 -10.522991) (xy 429.383761 -10.500349)
			(xy 429.337911 -10.470883) (xy 429.29672 -10.435192) (xy 429.261029 -10.394001) (xy 429.231563 -10.348151)
			(xy 429.208921 -10.298574) (xy 429.193566 -10.246279) (xy 429.18581 -10.192331) (xy 429.185324 -10.16508)
			(xy 428.148496 -10.16508) (xy 428.14801 -10.192331) (xy 428.140254 -10.246279) (xy 428.124899 -10.298574)
			(xy 428.102257 -10.348151) (xy 428.072791 -10.394001) (xy 428.0371 -10.435192) (xy 427.995909 -10.470883)
			(xy 427.950059 -10.500349) (xy 427.900482 -10.522991) (xy 427.848187 -10.538346) (xy 427.794239 -10.546102)
			(xy 427.739737 -10.546102) (xy 427.685789 -10.538346) (xy 427.633494 -10.522991) (xy 427.583917 -10.500349)
			(xy 427.538067 -10.470883) (xy 427.496876 -10.435192) (xy 427.461185 -10.394001) (xy 427.431719 -10.348151)
			(xy 427.409077 -10.298574) (xy 427.393722 -10.246279) (xy 427.385966 -10.192331) (xy 427.38548 -10.16508)
			(xy 426.348398 -10.16508) (xy 426.347912 -10.192331) (xy 426.340156 -10.246279) (xy 426.324801 -10.298574)
			(xy 426.302159 -10.348151) (xy 426.272693 -10.394001) (xy 426.237002 -10.435192) (xy 426.195811 -10.470883)
			(xy 426.149961 -10.500349) (xy 426.100384 -10.522991) (xy 426.048089 -10.538346) (xy 425.994141 -10.546102)
			(xy 425.939639 -10.546102) (xy 425.885691 -10.538346) (xy 425.833396 -10.522991) (xy 425.783819 -10.500349)
			(xy 425.737969 -10.470883) (xy 425.696778 -10.435192) (xy 425.661087 -10.394001) (xy 425.631621 -10.348151)
			(xy 425.608979 -10.298574) (xy 425.593624 -10.246279) (xy 425.585868 -10.192331) (xy 425.585382 -10.16508)
			(xy 424.5483 -10.16508) (xy 424.547814 -10.192331) (xy 424.540058 -10.246279) (xy 424.524703 -10.298574)
			(xy 424.502061 -10.348151) (xy 424.472595 -10.394001) (xy 424.436904 -10.435192) (xy 424.395713 -10.470883)
			(xy 424.349863 -10.500349) (xy 424.300286 -10.522991) (xy 424.247991 -10.538346) (xy 424.194043 -10.546102)
			(xy 424.139541 -10.546102) (xy 424.085593 -10.538346) (xy 424.033298 -10.522991) (xy 423.983721 -10.500349)
			(xy 423.937871 -10.470883) (xy 423.89668 -10.435192) (xy 423.860989 -10.394001) (xy 423.831523 -10.348151)
			(xy 423.808881 -10.298574) (xy 423.793526 -10.246279) (xy 423.78577 -10.192331) (xy 423.785284 -10.16508)
			(xy 420.538402 -10.16508) (xy 420.537916 -10.192331) (xy 420.53016 -10.246279) (xy 420.514805 -10.298574)
			(xy 420.492163 -10.348151) (xy 420.462697 -10.394001) (xy 420.427006 -10.435192) (xy 420.385815 -10.470883)
			(xy 420.339965 -10.500349) (xy 420.290388 -10.522991) (xy 420.238093 -10.538346) (xy 420.184145 -10.546102)
			(xy 420.129643 -10.546102) (xy 420.075695 -10.538346) (xy 420.0234 -10.522991) (xy 419.973823 -10.500349)
			(xy 419.927973 -10.470883) (xy 419.886782 -10.435192) (xy 419.851091 -10.394001) (xy 419.821625 -10.348151)
			(xy 419.798983 -10.298574) (xy 419.783628 -10.246279) (xy 419.775872 -10.192331) (xy 419.775386 -10.16508)
			(xy 418.738304 -10.16508) (xy 418.737818 -10.192331) (xy 418.730062 -10.246279) (xy 418.714707 -10.298574)
			(xy 418.692065 -10.348151) (xy 418.662599 -10.394001) (xy 418.626908 -10.435192) (xy 418.585717 -10.470883)
			(xy 418.539867 -10.500349) (xy 418.49029 -10.522991) (xy 418.437995 -10.538346) (xy 418.384047 -10.546102)
			(xy 418.329545 -10.546102) (xy 418.275597 -10.538346) (xy 418.223302 -10.522991) (xy 418.173725 -10.500349)
			(xy 418.127875 -10.470883) (xy 418.086684 -10.435192) (xy 418.050993 -10.394001) (xy 418.021527 -10.348151)
			(xy 417.998885 -10.298574) (xy 417.98353 -10.246279) (xy 417.975774 -10.192331) (xy 417.975288 -10.16508)
			(xy 416.93846 -10.16508) (xy 416.937974 -10.192331) (xy 416.930218 -10.246279) (xy 416.914863 -10.298574)
			(xy 416.892221 -10.348151) (xy 416.862755 -10.394001) (xy 416.827064 -10.435192) (xy 416.785873 -10.470883)
			(xy 416.740023 -10.500349) (xy 416.690446 -10.522991) (xy 416.638151 -10.538346) (xy 416.584203 -10.546102)
			(xy 416.529701 -10.546102) (xy 416.475753 -10.538346) (xy 416.423458 -10.522991) (xy 416.373881 -10.500349)
			(xy 416.328031 -10.470883) (xy 416.28684 -10.435192) (xy 416.251149 -10.394001) (xy 416.221683 -10.348151)
			(xy 416.199041 -10.298574) (xy 416.183686 -10.246279) (xy 416.17593 -10.192331) (xy 416.175444 -10.16508)
			(xy 415.138362 -10.16508) (xy 415.137876 -10.192331) (xy 415.13012 -10.246279) (xy 415.114765 -10.298574)
			(xy 415.092123 -10.348151) (xy 415.062657 -10.394001) (xy 415.026966 -10.435192) (xy 414.985775 -10.470883)
			(xy 414.939925 -10.500349) (xy 414.890348 -10.522991) (xy 414.838053 -10.538346) (xy 414.784105 -10.546102)
			(xy 414.729603 -10.546102) (xy 414.675655 -10.538346) (xy 414.62336 -10.522991) (xy 414.573783 -10.500349)
			(xy 414.527933 -10.470883) (xy 414.486742 -10.435192) (xy 414.451051 -10.394001) (xy 414.421585 -10.348151)
			(xy 414.398943 -10.298574) (xy 414.383588 -10.246279) (xy 414.375832 -10.192331) (xy 414.375346 -10.16508)
			(xy 413.338264 -10.16508) (xy 413.337778 -10.192331) (xy 413.330022 -10.246279) (xy 413.314667 -10.298574)
			(xy 413.292025 -10.348151) (xy 413.262559 -10.394001) (xy 413.226868 -10.435192) (xy 413.185677 -10.470883)
			(xy 413.139827 -10.500349) (xy 413.09025 -10.522991) (xy 413.037955 -10.538346) (xy 412.984007 -10.546102)
			(xy 412.929505 -10.546102) (xy 412.875557 -10.538346) (xy 412.823262 -10.522991) (xy 412.773685 -10.500349)
			(xy 412.727835 -10.470883) (xy 412.686644 -10.435192) (xy 412.650953 -10.394001) (xy 412.621487 -10.348151)
			(xy 412.598845 -10.298574) (xy 412.58349 -10.246279) (xy 412.575734 -10.192331) (xy 412.575248 -10.16508)
			(xy 407.828496 -10.16508) (xy 407.82801 -10.192331) (xy 407.820254 -10.246279) (xy 407.804899 -10.298574)
			(xy 407.782257 -10.348151) (xy 407.752791 -10.394001) (xy 407.7171 -10.435192) (xy 407.675909 -10.470883)
			(xy 407.630059 -10.500349) (xy 407.580482 -10.522991) (xy 407.528187 -10.538346) (xy 407.474239 -10.546102)
			(xy 407.419737 -10.546102) (xy 407.365789 -10.538346) (xy 407.313494 -10.522991) (xy 407.263917 -10.500349)
			(xy 407.218067 -10.470883) (xy 407.176876 -10.435192) (xy 407.141185 -10.394001) (xy 407.111719 -10.348151)
			(xy 407.089077 -10.298574) (xy 407.073722 -10.246279) (xy 407.065966 -10.192331) (xy 407.06548 -10.16508)
			(xy 406.028398 -10.16508) (xy 406.027912 -10.192331) (xy 406.020156 -10.246279) (xy 406.004801 -10.298574)
			(xy 405.982159 -10.348151) (xy 405.952693 -10.394001) (xy 405.917002 -10.435192) (xy 405.875811 -10.470883)
			(xy 405.829961 -10.500349) (xy 405.780384 -10.522991) (xy 405.728089 -10.538346) (xy 405.674141 -10.546102)
			(xy 405.619639 -10.546102) (xy 405.565691 -10.538346) (xy 405.513396 -10.522991) (xy 405.463819 -10.500349)
			(xy 405.417969 -10.470883) (xy 405.376778 -10.435192) (xy 405.341087 -10.394001) (xy 405.311621 -10.348151)
			(xy 405.288979 -10.298574) (xy 405.273624 -10.246279) (xy 405.265868 -10.192331) (xy 405.265382 -10.16508)
			(xy 404.2283 -10.16508) (xy 404.227814 -10.192331) (xy 404.220058 -10.246279) (xy 404.204703 -10.298574)
			(xy 404.182061 -10.348151) (xy 404.152595 -10.394001) (xy 404.116904 -10.435192) (xy 404.075713 -10.470883)
			(xy 404.029863 -10.500349) (xy 403.980286 -10.522991) (xy 403.927991 -10.538346) (xy 403.874043 -10.546102)
			(xy 403.819541 -10.546102) (xy 403.765593 -10.538346) (xy 403.713298 -10.522991) (xy 403.663721 -10.500349)
			(xy 403.617871 -10.470883) (xy 403.57668 -10.435192) (xy 403.540989 -10.394001) (xy 403.511523 -10.348151)
			(xy 403.488881 -10.298574) (xy 403.473526 -10.246279) (xy 403.46577 -10.192331) (xy 403.465284 -10.16508)
			(xy 402.428456 -10.16508) (xy 402.42797 -10.192331) (xy 402.420214 -10.246279) (xy 402.404859 -10.298574)
			(xy 402.382217 -10.348151) (xy 402.352751 -10.394001) (xy 402.31706 -10.435192) (xy 402.275869 -10.470883)
			(xy 402.230019 -10.500349) (xy 402.180442 -10.522991) (xy 402.128147 -10.538346) (xy 402.074199 -10.546102)
			(xy 402.019697 -10.546102) (xy 401.965749 -10.538346) (xy 401.913454 -10.522991) (xy 401.863877 -10.500349)
			(xy 401.818027 -10.470883) (xy 401.776836 -10.435192) (xy 401.741145 -10.394001) (xy 401.711679 -10.348151)
			(xy 401.689037 -10.298574) (xy 401.673682 -10.246279) (xy 401.665926 -10.192331) (xy 401.66544 -10.16508)
			(xy 400.628358 -10.16508) (xy 400.627872 -10.192331) (xy 400.620116 -10.246279) (xy 400.604761 -10.298574)
			(xy 400.582119 -10.348151) (xy 400.552653 -10.394001) (xy 400.516962 -10.435192) (xy 400.475771 -10.470883)
			(xy 400.429921 -10.500349) (xy 400.380344 -10.522991) (xy 400.328049 -10.538346) (xy 400.274101 -10.546102)
			(xy 400.219599 -10.546102) (xy 400.165651 -10.538346) (xy 400.113356 -10.522991) (xy 400.063779 -10.500349)
			(xy 400.017929 -10.470883) (xy 399.976738 -10.435192) (xy 399.941047 -10.394001) (xy 399.911581 -10.348151)
			(xy 399.888939 -10.298574) (xy 399.873584 -10.246279) (xy 399.865828 -10.192331) (xy 399.865342 -10.16508)
			(xy 398.82826 -10.16508) (xy 398.827774 -10.192331) (xy 398.820018 -10.246279) (xy 398.804663 -10.298574)
			(xy 398.782021 -10.348151) (xy 398.752555 -10.394001) (xy 398.716864 -10.435192) (xy 398.675673 -10.470883)
			(xy 398.629823 -10.500349) (xy 398.580246 -10.522991) (xy 398.527951 -10.538346) (xy 398.474003 -10.546102)
			(xy 398.419501 -10.546102) (xy 398.365553 -10.538346) (xy 398.313258 -10.522991) (xy 398.263681 -10.500349)
			(xy 398.217831 -10.470883) (xy 398.17664 -10.435192) (xy 398.140949 -10.394001) (xy 398.111483 -10.348151)
			(xy 398.088841 -10.298574) (xy 398.073486 -10.246279) (xy 398.06573 -10.192331) (xy 398.065244 -10.16508)
			(xy 397.028416 -10.16508) (xy 397.02793 -10.192331) (xy 397.020174 -10.246279) (xy 397.004819 -10.298574)
			(xy 396.982177 -10.348151) (xy 396.952711 -10.394001) (xy 396.91702 -10.435192) (xy 396.875829 -10.470883)
			(xy 396.829979 -10.500349) (xy 396.780402 -10.522991) (xy 396.728107 -10.538346) (xy 396.674159 -10.546102)
			(xy 396.619657 -10.546102) (xy 396.565709 -10.538346) (xy 396.513414 -10.522991) (xy 396.463837 -10.500349)
			(xy 396.417987 -10.470883) (xy 396.376796 -10.435192) (xy 396.341105 -10.394001) (xy 396.311639 -10.348151)
			(xy 396.288997 -10.298574) (xy 396.273642 -10.246279) (xy 396.265886 -10.192331) (xy 396.2654 -10.16508)
			(xy 395.228318 -10.16508) (xy 395.227832 -10.192331) (xy 395.220076 -10.246279) (xy 395.204721 -10.298574)
			(xy 395.182079 -10.348151) (xy 395.152613 -10.394001) (xy 395.116922 -10.435192) (xy 395.075731 -10.470883)
			(xy 395.029881 -10.500349) (xy 394.980304 -10.522991) (xy 394.928009 -10.538346) (xy 394.874061 -10.546102)
			(xy 394.819559 -10.546102) (xy 394.765611 -10.538346) (xy 394.713316 -10.522991) (xy 394.663739 -10.500349)
			(xy 394.617889 -10.470883) (xy 394.576698 -10.435192) (xy 394.541007 -10.394001) (xy 394.511541 -10.348151)
			(xy 394.488899 -10.298574) (xy 394.473544 -10.246279) (xy 394.465788 -10.192331) (xy 394.465302 -10.16508)
			(xy 394.465804 -10.137311) (xy 394.47386 -10.08236) (xy 394.489799 -10.029159) (xy 394.513283 -9.97883)
			(xy 394.543817 -9.932439) (xy 394.580754 -9.890965) (xy 394.6017 -9.872726) (xy 394.612679 -9.86282)
			(xy 394.628887 -9.838102) (xy 394.637344 -9.80978) (xy 394.637345 -9.780222) (xy 394.628888 -9.7519)
			(xy 394.612681 -9.727182) (xy 394.6017 -9.717278) (xy 394.583292 -9.701348) (xy 394.55027 -9.665579)
			(xy 394.522079 -9.62589) (xy 394.499181 -9.58293) (xy 394.490194 -9.560306) (xy 394.48457 -9.546941)
			(xy 394.467081 -9.523831) (xy 394.443804 -9.506563) (xy 394.416615 -9.496528) (xy 394.387702 -9.494533)
			(xy 394.359392 -9.50074) (xy 394.333965 -9.514648) (xy 394.323316 -9.524492) (xy 394.27658 -9.571228)
			(xy 394.27658 -12.37488) (xy 394.464792 -12.37488) (xy 394.468863 -12.319258) (xy 394.480989 -12.264821)
			(xy 394.500912 -12.21273) (xy 394.528208 -12.164095) (xy 394.562294 -12.119952) (xy 394.602443 -12.081243)
			(xy 394.647801 -12.048792) (xy 394.697401 -12.023291) (xy 394.750185 -12.005284) (xy 394.805028 -11.995154)
			(xy 394.860762 -11.993117) (xy 394.916199 -11.999217) (xy 394.970156 -12.013323) (xy 395.021485 -12.035135)
			(xy 395.069091 -12.064189) (xy 395.111959 -12.099864) (xy 395.149176 -12.141401) (xy 395.179949 -12.187914)
			(xy 395.203621 -12.238411) (xy 395.219689 -12.291818) (xy 395.227809 -12.346994) (xy 395.228318 -12.37488)
			(xy 396.26489 -12.37488) (xy 396.268961 -12.319258) (xy 396.281087 -12.264821) (xy 396.30101 -12.21273)
			(xy 396.328306 -12.164095) (xy 396.362392 -12.119952) (xy 396.402541 -12.081243) (xy 396.447899 -12.048792)
			(xy 396.497499 -12.023291) (xy 396.550283 -12.005284) (xy 396.605126 -11.995154) (xy 396.66086 -11.993117)
			(xy 396.716297 -11.999217) (xy 396.770254 -12.013323) (xy 396.821583 -12.035135) (xy 396.869189 -12.064189)
			(xy 396.912057 -12.099864) (xy 396.949274 -12.141401) (xy 396.980047 -12.187914) (xy 397.003719 -12.238411)
			(xy 397.019787 -12.291818) (xy 397.027907 -12.346994) (xy 397.028416 -12.37488) (xy 398.064734 -12.37488)
			(xy 398.068805 -12.319258) (xy 398.080931 -12.264821) (xy 398.100854 -12.21273) (xy 398.12815 -12.164095)
			(xy 398.162236 -12.119952) (xy 398.202385 -12.081243) (xy 398.247743 -12.048792) (xy 398.297343 -12.023291)
			(xy 398.350127 -12.005284) (xy 398.40497 -11.995154) (xy 398.460704 -11.993117) (xy 398.516141 -11.999217)
			(xy 398.570098 -12.013323) (xy 398.621427 -12.035135) (xy 398.669033 -12.064189) (xy 398.711901 -12.099864)
			(xy 398.749118 -12.141401) (xy 398.779891 -12.187914) (xy 398.803563 -12.238411) (xy 398.819631 -12.291818)
			(xy 398.827751 -12.346994) (xy 398.82826 -12.37488) (xy 399.864832 -12.37488) (xy 399.868903 -12.319258)
			(xy 399.881029 -12.264821) (xy 399.900952 -12.21273) (xy 399.928248 -12.164095) (xy 399.962334 -12.119952)
			(xy 400.002483 -12.081243) (xy 400.047841 -12.048792) (xy 400.097441 -12.023291) (xy 400.150225 -12.005284)
			(xy 400.205068 -11.995154) (xy 400.260802 -11.993117) (xy 400.316239 -11.999217) (xy 400.370196 -12.013323)
			(xy 400.421525 -12.035135) (xy 400.469131 -12.064189) (xy 400.511999 -12.099864) (xy 400.549216 -12.141401)
			(xy 400.579989 -12.187914) (xy 400.603661 -12.238411) (xy 400.619729 -12.291818) (xy 400.627849 -12.346994)
			(xy 400.628358 -12.37488) (xy 401.66493 -12.37488) (xy 401.669001 -12.319258) (xy 401.681127 -12.264821)
			(xy 401.70105 -12.21273) (xy 401.728346 -12.164095) (xy 401.762432 -12.119952) (xy 401.802581 -12.081243)
			(xy 401.847939 -12.048792) (xy 401.897539 -12.023291) (xy 401.950323 -12.005284) (xy 402.005166 -11.995154)
			(xy 402.0609 -11.993117) (xy 402.116337 -11.999217) (xy 402.170294 -12.013323) (xy 402.221623 -12.035135)
			(xy 402.269229 -12.064189) (xy 402.312097 -12.099864) (xy 402.349314 -12.141401) (xy 402.380087 -12.187914)
			(xy 402.403759 -12.238411) (xy 402.419827 -12.291818) (xy 402.427947 -12.346994) (xy 402.428456 -12.37488)
			(xy 403.464774 -12.37488) (xy 403.468845 -12.319258) (xy 403.480971 -12.264821) (xy 403.500894 -12.21273)
			(xy 403.52819 -12.164095) (xy 403.562276 -12.119952) (xy 403.602425 -12.081243) (xy 403.647783 -12.048792)
			(xy 403.697383 -12.023291) (xy 403.750167 -12.005284) (xy 403.80501 -11.995154) (xy 403.860744 -11.993117)
			(xy 403.916181 -11.999217) (xy 403.970138 -12.013323) (xy 404.021467 -12.035135) (xy 404.069073 -12.064189)
			(xy 404.111941 -12.099864) (xy 404.149158 -12.141401) (xy 404.179931 -12.187914) (xy 404.203603 -12.238411)
			(xy 404.219671 -12.291818) (xy 404.227791 -12.346994) (xy 404.2283 -12.37488) (xy 405.264872 -12.37488)
			(xy 405.268943 -12.319258) (xy 405.281069 -12.264821) (xy 405.300992 -12.21273) (xy 405.328288 -12.164095)
			(xy 405.362374 -12.119952) (xy 405.402523 -12.081243) (xy 405.447881 -12.048792) (xy 405.497481 -12.023291)
			(xy 405.550265 -12.005284) (xy 405.605108 -11.995154) (xy 405.660842 -11.993117) (xy 405.716279 -11.999217)
			(xy 405.770236 -12.013323) (xy 405.821565 -12.035135) (xy 405.869171 -12.064189) (xy 405.912039 -12.099864)
			(xy 405.949256 -12.141401) (xy 405.980029 -12.187914) (xy 406.003701 -12.238411) (xy 406.019769 -12.291818)
			(xy 406.027889 -12.346994) (xy 406.028398 -12.37488) (xy 407.06497 -12.37488) (xy 407.069041 -12.319258)
			(xy 407.081167 -12.264821) (xy 407.10109 -12.21273) (xy 407.128386 -12.164095) (xy 407.162472 -12.119952)
			(xy 407.202621 -12.081243) (xy 407.247979 -12.048792) (xy 407.297579 -12.023291) (xy 407.350363 -12.005284)
			(xy 407.405206 -11.995154) (xy 407.46094 -11.993117) (xy 407.516377 -11.999217) (xy 407.570334 -12.013323)
			(xy 407.621663 -12.035135) (xy 407.669269 -12.064189) (xy 407.712137 -12.099864) (xy 407.749354 -12.141401)
			(xy 407.780127 -12.187914) (xy 407.803799 -12.238411) (xy 407.819867 -12.291818) (xy 407.827987 -12.346994)
			(xy 407.828496 -12.37488) (xy 407.827987 -12.402766) (xy 407.819867 -12.457942) (xy 407.803799 -12.511349)
			(xy 407.780127 -12.561846) (xy 407.749354 -12.608359) (xy 407.712137 -12.649896) (xy 407.669269 -12.685571)
			(xy 407.621663 -12.714625) (xy 407.570334 -12.736437) (xy 407.516377 -12.750543) (xy 407.46094 -12.756643)
			(xy 407.405206 -12.754606) (xy 407.350363 -12.744476) (xy 407.297579 -12.726469) (xy 407.247979 -12.700968)
			(xy 407.202621 -12.668517) (xy 407.162472 -12.629808) (xy 407.128386 -12.585665) (xy 407.10109 -12.53703)
			(xy 407.081167 -12.484939) (xy 407.069041 -12.430502) (xy 407.06497 -12.37488) (xy 406.028398 -12.37488)
			(xy 406.027889 -12.402766) (xy 406.019769 -12.457942) (xy 406.003701 -12.511349) (xy 405.980029 -12.561846)
			(xy 405.949256 -12.608359) (xy 405.912039 -12.649896) (xy 405.869171 -12.685571) (xy 405.821565 -12.714625)
			(xy 405.770236 -12.736437) (xy 405.716279 -12.750543) (xy 405.660842 -12.756643) (xy 405.605108 -12.754606)
			(xy 405.550265 -12.744476) (xy 405.497481 -12.726469) (xy 405.447881 -12.700968) (xy 405.402523 -12.668517)
			(xy 405.362374 -12.629808) (xy 405.328288 -12.585665) (xy 405.300992 -12.53703) (xy 405.281069 -12.484939)
			(xy 405.268943 -12.430502) (xy 405.264872 -12.37488) (xy 404.2283 -12.37488) (xy 404.227791 -12.402766)
			(xy 404.219671 -12.457942) (xy 404.203603 -12.511349) (xy 404.179931 -12.561846) (xy 404.149158 -12.608359)
			(xy 404.111941 -12.649896) (xy 404.069073 -12.685571) (xy 404.021467 -12.714625) (xy 403.970138 -12.736437)
			(xy 403.916181 -12.750543) (xy 403.860744 -12.756643) (xy 403.80501 -12.754606) (xy 403.750167 -12.744476)
			(xy 403.697383 -12.726469) (xy 403.647783 -12.700968) (xy 403.602425 -12.668517) (xy 403.562276 -12.629808)
			(xy 403.52819 -12.585665) (xy 403.500894 -12.53703) (xy 403.480971 -12.484939) (xy 403.468845 -12.430502)
			(xy 403.464774 -12.37488) (xy 402.428456 -12.37488) (xy 402.427947 -12.402766) (xy 402.419827 -12.457942)
			(xy 402.403759 -12.511349) (xy 402.380087 -12.561846) (xy 402.349314 -12.608359) (xy 402.312097 -12.649896)
			(xy 402.269229 -12.685571) (xy 402.221623 -12.714625) (xy 402.170294 -12.736437) (xy 402.116337 -12.750543)
			(xy 402.0609 -12.756643) (xy 402.005166 -12.754606) (xy 401.950323 -12.744476) (xy 401.897539 -12.726469)
			(xy 401.847939 -12.700968) (xy 401.802581 -12.668517) (xy 401.762432 -12.629808) (xy 401.728346 -12.585665)
			(xy 401.70105 -12.53703) (xy 401.681127 -12.484939) (xy 401.669001 -12.430502) (xy 401.66493 -12.37488)
			(xy 400.628358 -12.37488) (xy 400.627849 -12.402766) (xy 400.619729 -12.457942) (xy 400.603661 -12.511349)
			(xy 400.579989 -12.561846) (xy 400.549216 -12.608359) (xy 400.511999 -12.649896) (xy 400.469131 -12.685571)
			(xy 400.421525 -12.714625) (xy 400.370196 -12.736437) (xy 400.316239 -12.750543) (xy 400.260802 -12.756643)
			(xy 400.205068 -12.754606) (xy 400.150225 -12.744476) (xy 400.097441 -12.726469) (xy 400.047841 -12.700968)
			(xy 400.002483 -12.668517) (xy 399.962334 -12.629808) (xy 399.928248 -12.585665) (xy 399.900952 -12.53703)
			(xy 399.881029 -12.484939) (xy 399.868903 -12.430502) (xy 399.864832 -12.37488) (xy 398.82826 -12.37488)
			(xy 398.827751 -12.402766) (xy 398.819631 -12.457942) (xy 398.803563 -12.511349) (xy 398.779891 -12.561846)
			(xy 398.749118 -12.608359) (xy 398.711901 -12.649896) (xy 398.669033 -12.685571) (xy 398.621427 -12.714625)
			(xy 398.570098 -12.736437) (xy 398.516141 -12.750543) (xy 398.460704 -12.756643) (xy 398.40497 -12.754606)
			(xy 398.350127 -12.744476) (xy 398.297343 -12.726469) (xy 398.247743 -12.700968) (xy 398.202385 -12.668517)
			(xy 398.162236 -12.629808) (xy 398.12815 -12.585665) (xy 398.100854 -12.53703) (xy 398.080931 -12.484939)
			(xy 398.068805 -12.430502) (xy 398.064734 -12.37488) (xy 397.028416 -12.37488) (xy 397.027907 -12.402766)
			(xy 397.019787 -12.457942) (xy 397.003719 -12.511349) (xy 396.980047 -12.561846) (xy 396.949274 -12.608359)
			(xy 396.912057 -12.649896) (xy 396.869189 -12.685571) (xy 396.821583 -12.714625) (xy 396.770254 -12.736437)
			(xy 396.716297 -12.750543) (xy 396.66086 -12.756643) (xy 396.605126 -12.754606) (xy 396.550283 -12.744476)
			(xy 396.497499 -12.726469) (xy 396.447899 -12.700968) (xy 396.402541 -12.668517) (xy 396.362392 -12.629808)
			(xy 396.328306 -12.585665) (xy 396.30101 -12.53703) (xy 396.281087 -12.484939) (xy 396.268961 -12.430502)
			(xy 396.26489 -12.37488) (xy 395.228318 -12.37488) (xy 395.227809 -12.402766) (xy 395.219689 -12.457942)
			(xy 395.203621 -12.511349) (xy 395.179949 -12.561846) (xy 395.149176 -12.608359) (xy 395.111959 -12.649896)
			(xy 395.069091 -12.685571) (xy 395.021485 -12.714625) (xy 394.970156 -12.736437) (xy 394.916199 -12.750543)
			(xy 394.860762 -12.756643) (xy 394.805028 -12.754606) (xy 394.750185 -12.744476) (xy 394.697401 -12.726469)
			(xy 394.647801 -12.700968) (xy 394.602443 -12.668517) (xy 394.562294 -12.629808) (xy 394.528208 -12.585665)
			(xy 394.500912 -12.53703) (xy 394.480989 -12.484939) (xy 394.468863 -12.430502) (xy 394.464792 -12.37488)
			(xy 394.27658 -12.37488) (xy 394.27658 -17.628647) (xy 394.542816 -17.628647) (xy 394.542816 -17.574153)
			(xy 394.550571 -17.520213) (xy 394.565923 -17.467926) (xy 394.58856 -17.418355) (xy 394.618021 -17.372511)
			(xy 394.653706 -17.331326) (xy 394.694888 -17.295638) (xy 394.740731 -17.266174) (xy 394.790299 -17.243533)
			(xy 394.842586 -17.228177) (xy 394.896525 -17.220418) (xy 394.923772 -17.21993) (xy 394.933633 -17.219991)
			(xy 394.953328 -17.221007) (xy 394.963142 -17.221962) (xy 394.977648 -17.222855) (xy 395.006211 -17.217619)
			(xy 395.032146 -17.204555) (xy 395.053357 -17.184719) (xy 395.068127 -17.159716) (xy 395.075262 -17.131567)
			(xy 395.074187 -17.102547) (xy 395.070076 -17.088612) (xy 395.060842 -17.059176) (xy 395.050882 -16.998298)
			(xy 395.050264 -16.967454) (xy 395.05075 -16.940203) (xy 395.058506 -16.886255) (xy 395.073861 -16.83396)
			(xy 395.096503 -16.784383) (xy 395.125969 -16.738533) (xy 395.16166 -16.697342) (xy 395.202851 -16.661651)
			(xy 395.248701 -16.632185) (xy 395.298278 -16.609543) (xy 395.350573 -16.594188) (xy 395.404521 -16.586432)
			(xy 395.459023 -16.586432) (xy 395.512971 -16.594188) (xy 395.565266 -16.609543) (xy 395.614843 -16.632185)
			(xy 395.660693 -16.661651) (xy 395.701884 -16.697342) (xy 395.737575 -16.738533) (xy 395.767041 -16.784383)
			(xy 395.789683 -16.83396) (xy 395.805038 -16.886255) (xy 395.812794 -16.940203) (xy 395.81328 -16.967454)
			(xy 395.812706 -16.997759) (xy 395.803138 -17.057608) (xy 395.79423 -17.08658) (xy 395.790429 -17.099759)
			(xy 395.78914 -17.127144) (xy 395.795195 -17.153882) (xy 395.808156 -17.178041) (xy 395.827085 -17.197872)
			(xy 395.850614 -17.211942) (xy 395.877042 -17.219234) (xy 395.89075 -17.219676) (xy 396.231618 -17.219676)
			(xy 396.245326 -17.219286) (xy 396.271747 -17.211962) (xy 396.295267 -17.197872) (xy 396.314191 -17.178034)
			(xy 396.327155 -17.153876) (xy 396.333226 -17.127139) (xy 396.331965 -17.099751) (xy 396.328138 -17.08658)
			(xy 396.319239 -17.057606) (xy 396.309671 -16.997758) (xy 396.309088 -16.967454) (xy 396.309574 -16.940203)
			(xy 396.31733 -16.886255) (xy 396.332685 -16.83396) (xy 396.355327 -16.784383) (xy 396.384793 -16.738533)
			(xy 396.420484 -16.697342) (xy 396.461675 -16.661651) (xy 396.507525 -16.632185) (xy 396.557102 -16.609543)
			(xy 396.609397 -16.594188) (xy 396.663345 -16.586432) (xy 396.717847 -16.586432) (xy 396.771795 -16.594188)
			(xy 396.82409 -16.609543) (xy 396.873667 -16.632185) (xy 396.919517 -16.661651) (xy 396.960708 -16.697342)
			(xy 396.996399 -16.738533) (xy 397.025865 -16.784383) (xy 397.048507 -16.83396) (xy 397.063862 -16.886255)
			(xy 397.071618 -16.940203) (xy 397.072104 -16.967454) (xy 397.071502 -16.998299) (xy 397.061547 -17.059182)
			(xy 397.052292 -17.088612) (xy 397.048079 -17.102542) (xy 397.046949 -17.131613) (xy 397.054065 -17.159823)
			(xy 397.068848 -17.18488) (xy 397.090098 -17.204751) (xy 397.116089 -17.217823) (xy 397.144711 -17.223033)
			(xy 397.159226 -17.221962) (xy 397.169041 -17.221014) (xy 397.188736 -17.219996) (xy 397.198596 -17.21993)
			(xy 397.225852 -17.220317) (xy 397.279809 -17.228074) (xy 397.332112 -17.243431) (xy 397.381698 -17.266076)
			(xy 397.427556 -17.295547) (xy 397.468753 -17.331244) (xy 397.504451 -17.372441) (xy 397.533922 -17.418299)
			(xy 397.556567 -17.467884) (xy 397.571925 -17.520188) (xy 397.579683 -17.574144) (xy 397.579683 -17.628647)
			(xy 400.130816 -17.628647) (xy 400.130816 -17.574153) (xy 400.138571 -17.520213) (xy 400.153923 -17.467926)
			(xy 400.17656 -17.418355) (xy 400.206021 -17.372511) (xy 400.241706 -17.331326) (xy 400.282888 -17.295638)
			(xy 400.328731 -17.266174) (xy 400.378299 -17.243533) (xy 400.430586 -17.228177) (xy 400.484525 -17.220418)
			(xy 400.511772 -17.21993) (xy 400.521633 -17.219991) (xy 400.541328 -17.221007) (xy 400.551142 -17.221962)
			(xy 400.565648 -17.222855) (xy 400.594211 -17.217619) (xy 400.620146 -17.204555) (xy 400.641357 -17.184719)
			(xy 400.656127 -17.159716) (xy 400.663262 -17.131567) (xy 400.662187 -17.102547) (xy 400.658076 -17.088612)
			(xy 400.648842 -17.059176) (xy 400.638882 -16.998298) (xy 400.638264 -16.967454) (xy 400.63875 -16.940203)
			(xy 400.646506 -16.886255) (xy 400.661861 -16.83396) (xy 400.684503 -16.784383) (xy 400.713969 -16.738533)
			(xy 400.74966 -16.697342) (xy 400.790851 -16.661651) (xy 400.836701 -16.632185) (xy 400.886278 -16.609543)
			(xy 400.938573 -16.594188) (xy 400.992521 -16.586432) (xy 401.047023 -16.586432) (xy 401.100971 -16.594188)
			(xy 401.153266 -16.609543) (xy 401.202843 -16.632185) (xy 401.248693 -16.661651) (xy 401.289884 -16.697342)
			(xy 401.325575 -16.738533) (xy 401.355041 -16.784383) (xy 401.377683 -16.83396) (xy 401.393038 -16.886255)
			(xy 401.400794 -16.940203) (xy 401.40128 -16.967454) (xy 401.400706 -16.997759) (xy 401.391138 -17.057608)
			(xy 401.38223 -17.08658) (xy 401.378429 -17.099759) (xy 401.37714 -17.127144) (xy 401.383195 -17.153882)
			(xy 401.396156 -17.178041) (xy 401.415085 -17.197872) (xy 401.438614 -17.211942) (xy 401.465042 -17.219234)
			(xy 401.47875 -17.219676) (xy 401.819618 -17.219676) (xy 401.833326 -17.219286) (xy 401.859747 -17.211962)
			(xy 401.883267 -17.197872) (xy 401.902191 -17.178034) (xy 401.915155 -17.153876) (xy 401.921226 -17.127139)
			(xy 401.919965 -17.099751) (xy 401.916138 -17.08658) (xy 401.907239 -17.057606) (xy 401.897671 -16.997758)
			(xy 401.897088 -16.967454) (xy 401.897574 -16.940203) (xy 401.90533 -16.886255) (xy 401.920685 -16.83396)
			(xy 401.943327 -16.784383) (xy 401.972793 -16.738533) (xy 402.008484 -16.697342) (xy 402.049675 -16.661651)
			(xy 402.095525 -16.632185) (xy 402.145102 -16.609543) (xy 402.197397 -16.594188) (xy 402.251345 -16.586432)
			(xy 402.305847 -16.586432) (xy 402.359795 -16.594188) (xy 402.41209 -16.609543) (xy 402.461667 -16.632185)
			(xy 402.507517 -16.661651) (xy 402.548708 -16.697342) (xy 402.584399 -16.738533) (xy 402.613865 -16.784383)
			(xy 402.636507 -16.83396) (xy 402.651862 -16.886255) (xy 402.659618 -16.940203) (xy 402.660104 -16.967454)
			(xy 402.659502 -16.998299) (xy 402.649547 -17.059182) (xy 402.640292 -17.088612) (xy 402.636079 -17.102542)
			(xy 402.634949 -17.131613) (xy 402.642065 -17.159823) (xy 402.656848 -17.18488) (xy 402.678098 -17.204751)
			(xy 402.704089 -17.217823) (xy 402.732711 -17.223033) (xy 402.747226 -17.221962) (xy 402.757041 -17.221014)
			(xy 402.776736 -17.219996) (xy 402.786596 -17.21993) (xy 402.813852 -17.220317) (xy 402.867809 -17.228074)
			(xy 402.920112 -17.243431) (xy 402.969698 -17.266076) (xy 403.015556 -17.295547) (xy 403.056753 -17.331244)
			(xy 403.092451 -17.372441) (xy 403.121922 -17.418299) (xy 403.144567 -17.467884) (xy 403.159925 -17.520188)
			(xy 403.167683 -17.574144) (xy 403.167683 -17.628647) (xy 405.718816 -17.628647) (xy 405.718816 -17.574153)
			(xy 405.726571 -17.520213) (xy 405.741923 -17.467926) (xy 405.76456 -17.418355) (xy 405.794021 -17.372511)
			(xy 405.829706 -17.331326) (xy 405.870888 -17.295638) (xy 405.916731 -17.266174) (xy 405.966299 -17.243533)
			(xy 406.018586 -17.228177) (xy 406.072525 -17.220418) (xy 406.099772 -17.21993) (xy 406.109633 -17.219991)
			(xy 406.129328 -17.221007) (xy 406.139142 -17.221962) (xy 406.153648 -17.222855) (xy 406.182211 -17.217619)
			(xy 406.208146 -17.204555) (xy 406.229357 -17.184719) (xy 406.244127 -17.159716) (xy 406.251262 -17.131567)
			(xy 406.250187 -17.102547) (xy 406.246076 -17.088612) (xy 406.236842 -17.059176) (xy 406.226882 -16.998298)
			(xy 406.226264 -16.967454) (xy 406.22675 -16.940203) (xy 406.234506 -16.886255) (xy 406.249861 -16.83396)
			(xy 406.272503 -16.784383) (xy 406.301969 -16.738533) (xy 406.33766 -16.697342) (xy 406.378851 -16.661651)
			(xy 406.424701 -16.632185) (xy 406.474278 -16.609543) (xy 406.526573 -16.594188) (xy 406.580521 -16.586432)
			(xy 406.635023 -16.586432) (xy 406.688971 -16.594188) (xy 406.741266 -16.609543) (xy 406.790843 -16.632185)
			(xy 406.836693 -16.661651) (xy 406.877884 -16.697342) (xy 406.913575 -16.738533) (xy 406.943041 -16.784383)
			(xy 406.965683 -16.83396) (xy 406.981038 -16.886255) (xy 406.988794 -16.940203) (xy 406.98928 -16.967454)
			(xy 406.988706 -16.997759) (xy 406.979138 -17.057608) (xy 406.97023 -17.08658) (xy 406.966429 -17.099759)
			(xy 406.96514 -17.127144) (xy 406.971195 -17.153882) (xy 406.984156 -17.178041) (xy 407.003085 -17.197872)
			(xy 407.026614 -17.211942) (xy 407.053042 -17.219234) (xy 407.06675 -17.219676) (xy 407.407618 -17.219676)
			(xy 407.421326 -17.219286) (xy 407.447747 -17.211962) (xy 407.471267 -17.197872) (xy 407.490191 -17.178034)
			(xy 407.503155 -17.153876) (xy 407.509226 -17.127139) (xy 407.507965 -17.099751) (xy 407.504138 -17.08658)
			(xy 407.495239 -17.057606) (xy 407.485671 -16.997758) (xy 407.485088 -16.967454) (xy 407.485574 -16.940203)
			(xy 407.49333 -16.886255) (xy 407.508685 -16.83396) (xy 407.531327 -16.784383) (xy 407.560793 -16.738533)
			(xy 407.596484 -16.697342) (xy 407.637675 -16.661651) (xy 407.683525 -16.632185) (xy 407.733102 -16.609543)
			(xy 407.785397 -16.594188) (xy 407.839345 -16.586432) (xy 407.893847 -16.586432) (xy 407.947795 -16.594188)
			(xy 408.00009 -16.609543) (xy 408.049667 -16.632185) (xy 408.095517 -16.661651) (xy 408.136708 -16.697342)
			(xy 408.172399 -16.738533) (xy 408.201865 -16.784383) (xy 408.224507 -16.83396) (xy 408.239862 -16.886255)
			(xy 408.247618 -16.940203) (xy 408.248104 -16.967454) (xy 408.247502 -16.998299) (xy 408.237547 -17.059182)
			(xy 408.228292 -17.088612) (xy 408.224079 -17.102542) (xy 408.222949 -17.131613) (xy 408.230065 -17.159823)
			(xy 408.244848 -17.18488) (xy 408.266098 -17.204751) (xy 408.292089 -17.217823) (xy 408.320711 -17.223033)
			(xy 408.335226 -17.221962) (xy 408.345041 -17.221014) (xy 408.364736 -17.219996) (xy 408.374596 -17.21993)
			(xy 408.401852 -17.220317) (xy 408.455809 -17.228074) (xy 408.508112 -17.243431) (xy 408.557698 -17.266076)
			(xy 408.603556 -17.295547) (xy 408.644753 -17.331244) (xy 408.680451 -17.372441) (xy 408.709922 -17.418299)
			(xy 408.732567 -17.467884) (xy 408.747925 -17.520188) (xy 408.755683 -17.574144) (xy 408.755683 -17.628656)
			(xy 408.747925 -17.682612) (xy 408.732567 -17.734916) (xy 408.709922 -17.784501) (xy 408.680451 -17.830359)
			(xy 408.644753 -17.871556) (xy 408.603556 -17.907253) (xy 408.557698 -17.936724) (xy 408.508112 -17.959369)
			(xy 408.455809 -17.974726) (xy 408.401852 -17.982483) (xy 408.374596 -17.982946) (xy 408.364735 -17.982888)
			(xy 408.34504 -17.98187) (xy 408.335226 -17.980914) (xy 408.320724 -17.979891) (xy 408.292141 -17.98514)
			(xy 408.266191 -17.998222) (xy 408.244974 -18.01808) (xy 408.230205 -18.043108) (xy 408.223078 -18.071281)
			(xy 408.22417 -18.100321) (xy 408.228292 -18.114264) (xy 408.237543 -18.143695) (xy 408.247492 -18.204577)
			(xy 408.248104 -18.235422) (xy 408.247618 -18.262673) (xy 408.239862 -18.316621) (xy 408.224507 -18.368916)
			(xy 408.201865 -18.418493) (xy 408.172399 -18.464343) (xy 408.136708 -18.505534) (xy 408.095517 -18.541225)
			(xy 408.049667 -18.570691) (xy 408.00009 -18.593333) (xy 407.947795 -18.608688) (xy 407.893847 -18.616444)
			(xy 407.839345 -18.616444) (xy 407.785397 -18.608688) (xy 407.733102 -18.593333) (xy 407.683525 -18.570691)
			(xy 407.637675 -18.541225) (xy 407.596484 -18.505534) (xy 407.560793 -18.464343) (xy 407.531327 -18.418493)
			(xy 407.508685 -18.368916) (xy 407.49333 -18.316621) (xy 407.485574 -18.262673) (xy 407.485088 -18.235422)
			(xy 407.485658 -18.205117) (xy 407.495229 -18.145268) (xy 407.504138 -18.116296) (xy 407.507998 -18.103131)
			(xy 407.509282 -18.075737) (xy 407.50322 -18.048991) (xy 407.49025 -18.024827) (xy 407.47131 -18.004994)
			(xy 407.447769 -17.990925) (xy 407.421331 -17.983638) (xy 407.407618 -17.9832) (xy 407.06675 -17.9832)
			(xy 407.053047 -17.983677) (xy 407.026632 -17.990984) (xy 407.003114 -18.005056) (xy 406.984189 -18.02488)
			(xy 406.971222 -18.049026) (xy 406.965148 -18.075751) (xy 406.966406 -18.103129) (xy 406.97023 -18.116296)
			(xy 406.979125 -18.145271) (xy 406.988695 -18.205118) (xy 406.98928 -18.235422) (xy 406.988794 -18.262673)
			(xy 406.981038 -18.316621) (xy 406.965683 -18.368916) (xy 406.943041 -18.418493) (xy 406.913575 -18.464343)
			(xy 406.877884 -18.505534) (xy 406.836693 -18.541225) (xy 406.790843 -18.570691) (xy 406.741266 -18.593333)
			(xy 406.688971 -18.608688) (xy 406.635023 -18.616444) (xy 406.580521 -18.616444) (xy 406.526573 -18.608688)
			(xy 406.474278 -18.593333) (xy 406.424701 -18.570691) (xy 406.378851 -18.541225) (xy 406.33766 -18.505534)
			(xy 406.301969 -18.464343) (xy 406.272503 -18.418493) (xy 406.249861 -18.368916) (xy 406.234506 -18.316621)
			(xy 406.22675 -18.262673) (xy 406.226264 -18.235422) (xy 406.226861 -18.204576) (xy 406.23682 -18.143694)
			(xy 406.246076 -18.114264) (xy 406.250351 -18.100349) (xy 406.251476 -18.071268) (xy 406.244353 -18.04305)
			(xy 406.22956 -18.017986) (xy 406.208299 -17.998113) (xy 406.182295 -17.985043) (xy 406.153661 -17.979838)
			(xy 406.139142 -17.980914) (xy 406.129327 -17.981864) (xy 406.109632 -17.982881) (xy 406.099772 -17.982946)
			(xy 406.072525 -17.982382) (xy 406.018586 -17.974623) (xy 405.966299 -17.959267) (xy 405.916731 -17.936626)
			(xy 405.870888 -17.907162) (xy 405.829706 -17.871474) (xy 405.794021 -17.830289) (xy 405.76456 -17.784445)
			(xy 405.741923 -17.734874) (xy 405.726571 -17.682587) (xy 405.718816 -17.628647) (xy 403.167683 -17.628647)
			(xy 403.167683 -17.628656) (xy 403.159925 -17.682612) (xy 403.144567 -17.734916) (xy 403.121922 -17.784501)
			(xy 403.092451 -17.830359) (xy 403.056753 -17.871556) (xy 403.015556 -17.907253) (xy 402.969698 -17.936724)
			(xy 402.920112 -17.959369) (xy 402.867809 -17.974726) (xy 402.813852 -17.982483) (xy 402.786596 -17.982946)
			(xy 402.776735 -17.982888) (xy 402.75704 -17.98187) (xy 402.747226 -17.980914) (xy 402.732724 -17.979891)
			(xy 402.704141 -17.98514) (xy 402.678191 -17.998222) (xy 402.656974 -18.01808) (xy 402.642205 -18.043108)
			(xy 402.635078 -18.071281) (xy 402.63617 -18.100321) (xy 402.640292 -18.114264) (xy 402.649543 -18.143695)
			(xy 402.659492 -18.204577) (xy 402.660104 -18.235422) (xy 402.659618 -18.262673) (xy 402.651862 -18.316621)
			(xy 402.636507 -18.368916) (xy 402.613865 -18.418493) (xy 402.584399 -18.464343) (xy 402.548708 -18.505534)
			(xy 402.507517 -18.541225) (xy 402.461667 -18.570691) (xy 402.41209 -18.593333) (xy 402.359795 -18.608688)
			(xy 402.305847 -18.616444) (xy 402.251345 -18.616444) (xy 402.197397 -18.608688) (xy 402.145102 -18.593333)
			(xy 402.095525 -18.570691) (xy 402.049675 -18.541225) (xy 402.008484 -18.505534) (xy 401.972793 -18.464343)
			(xy 401.943327 -18.418493) (xy 401.920685 -18.368916) (xy 401.90533 -18.316621) (xy 401.897574 -18.262673)
			(xy 401.897088 -18.235422) (xy 401.897658 -18.205117) (xy 401.907229 -18.145268) (xy 401.916138 -18.116296)
			(xy 401.919998 -18.103131) (xy 401.921282 -18.075737) (xy 401.91522 -18.048991) (xy 401.90225 -18.024827)
			(xy 401.88331 -18.004994) (xy 401.859769 -17.990925) (xy 401.833331 -17.983638) (xy 401.819618 -17.9832)
			(xy 401.47875 -17.9832) (xy 401.465047 -17.983677) (xy 401.438632 -17.990984) (xy 401.415114 -18.005056)
			(xy 401.396189 -18.02488) (xy 401.383222 -18.049026) (xy 401.377148 -18.075751) (xy 401.378406 -18.103129)
			(xy 401.38223 -18.116296) (xy 401.391125 -18.145271) (xy 401.400695 -18.205118) (xy 401.40128 -18.235422)
			(xy 401.400794 -18.262673) (xy 401.393038 -18.316621) (xy 401.377683 -18.368916) (xy 401.355041 -18.418493)
			(xy 401.325575 -18.464343) (xy 401.289884 -18.505534) (xy 401.248693 -18.541225) (xy 401.202843 -18.570691)
			(xy 401.153266 -18.593333) (xy 401.100971 -18.608688) (xy 401.047023 -18.616444) (xy 400.992521 -18.616444)
			(xy 400.938573 -18.608688) (xy 400.886278 -18.593333) (xy 400.836701 -18.570691) (xy 400.790851 -18.541225)
			(xy 400.74966 -18.505534) (xy 400.713969 -18.464343) (xy 400.684503 -18.418493) (xy 400.661861 -18.368916)
			(xy 400.646506 -18.316621) (xy 400.63875 -18.262673) (xy 400.638264 -18.235422) (xy 400.638861 -18.204576)
			(xy 400.64882 -18.143694) (xy 400.658076 -18.114264) (xy 400.662351 -18.100349) (xy 400.663476 -18.071268)
			(xy 400.656353 -18.04305) (xy 400.64156 -18.017986) (xy 400.620299 -17.998113) (xy 400.594295 -17.985043)
			(xy 400.565661 -17.979838) (xy 400.551142 -17.980914) (xy 400.541327 -17.981864) (xy 400.521632 -17.982881)
			(xy 400.511772 -17.982946) (xy 400.484525 -17.982382) (xy 400.430586 -17.974623) (xy 400.378299 -17.959267)
			(xy 400.328731 -17.936626) (xy 400.282888 -17.907162) (xy 400.241706 -17.871474) (xy 400.206021 -17.830289)
			(xy 400.17656 -17.784445) (xy 400.153923 -17.734874) (xy 400.138571 -17.682587) (xy 400.130816 -17.628647)
			(xy 397.579683 -17.628647) (xy 397.579683 -17.628656) (xy 397.571925 -17.682612) (xy 397.556567 -17.734916)
			(xy 397.533922 -17.784501) (xy 397.504451 -17.830359) (xy 397.468753 -17.871556) (xy 397.427556 -17.907253)
			(xy 397.381698 -17.936724) (xy 397.332112 -17.959369) (xy 397.279809 -17.974726) (xy 397.225852 -17.982483)
			(xy 397.198596 -17.982946) (xy 397.188735 -17.982888) (xy 397.16904 -17.98187) (xy 397.159226 -17.980914)
			(xy 397.144724 -17.979891) (xy 397.116141 -17.98514) (xy 397.090191 -17.998222) (xy 397.068974 -18.01808)
			(xy 397.054205 -18.043108) (xy 397.047078 -18.071281) (xy 397.04817 -18.100321) (xy 397.052292 -18.114264)
			(xy 397.061543 -18.143695) (xy 397.071492 -18.204577) (xy 397.072104 -18.235422) (xy 397.071618 -18.262673)
			(xy 397.063862 -18.316621) (xy 397.048507 -18.368916) (xy 397.025865 -18.418493) (xy 396.996399 -18.464343)
			(xy 396.960708 -18.505534) (xy 396.919517 -18.541225) (xy 396.873667 -18.570691) (xy 396.82409 -18.593333)
			(xy 396.771795 -18.608688) (xy 396.717847 -18.616444) (xy 396.663345 -18.616444) (xy 396.609397 -18.608688)
			(xy 396.557102 -18.593333) (xy 396.507525 -18.570691) (xy 396.461675 -18.541225) (xy 396.420484 -18.505534)
			(xy 396.384793 -18.464343) (xy 396.355327 -18.418493) (xy 396.332685 -18.368916) (xy 396.31733 -18.316621)
			(xy 396.309574 -18.262673) (xy 396.309088 -18.235422) (xy 396.309658 -18.205117) (xy 396.319229 -18.145268)
			(xy 396.328138 -18.116296) (xy 396.331998 -18.103131) (xy 396.333282 -18.075737) (xy 396.32722 -18.048991)
			(xy 396.31425 -18.024827) (xy 396.29531 -18.004994) (xy 396.271769 -17.990925) (xy 396.245331 -17.983638)
			(xy 396.231618 -17.9832) (xy 395.89075 -17.9832) (xy 395.877047 -17.983677) (xy 395.850632 -17.990984)
			(xy 395.827114 -18.005056) (xy 395.808189 -18.02488) (xy 395.795222 -18.049026) (xy 395.789148 -18.075751)
			(xy 395.790406 -18.103129) (xy 395.79423 -18.116296) (xy 395.803125 -18.145271) (xy 395.812695 -18.205118)
			(xy 395.81328 -18.235422) (xy 395.812794 -18.262673) (xy 395.805038 -18.316621) (xy 395.789683 -18.368916)
			(xy 395.767041 -18.418493) (xy 395.737575 -18.464343) (xy 395.701884 -18.505534) (xy 395.660693 -18.541225)
			(xy 395.614843 -18.570691) (xy 395.565266 -18.593333) (xy 395.512971 -18.608688) (xy 395.459023 -18.616444)
			(xy 395.404521 -18.616444) (xy 395.350573 -18.608688) (xy 395.298278 -18.593333) (xy 395.248701 -18.570691)
			(xy 395.202851 -18.541225) (xy 395.16166 -18.505534) (xy 395.125969 -18.464343) (xy 395.096503 -18.418493)
			(xy 395.073861 -18.368916) (xy 395.058506 -18.316621) (xy 395.05075 -18.262673) (xy 395.050264 -18.235422)
			(xy 395.050861 -18.204576) (xy 395.06082 -18.143694) (xy 395.070076 -18.114264) (xy 395.074351 -18.100349)
			(xy 395.075476 -18.071268) (xy 395.068353 -18.04305) (xy 395.05356 -18.017986) (xy 395.032299 -17.998113)
			(xy 395.006295 -17.985043) (xy 394.977661 -17.979838) (xy 394.963142 -17.980914) (xy 394.953327 -17.981864)
			(xy 394.933632 -17.982881) (xy 394.923772 -17.982946) (xy 394.896525 -17.982382) (xy 394.842586 -17.974623)
			(xy 394.790299 -17.959267) (xy 394.740731 -17.936626) (xy 394.694888 -17.907162) (xy 394.653706 -17.871474)
			(xy 394.618021 -17.830289) (xy 394.58856 -17.784445) (xy 394.565923 -17.734874) (xy 394.550571 -17.682587)
			(xy 394.542816 -17.628647) (xy 394.27658 -17.628647) (xy 394.27658 -18.457418) (xy 394.276834 -18.45945)
			(xy 394.278104 -18.491454) (xy 394.276834 -18.523458) (xy 394.27658 -18.52549) (xy 394.27658 -18.643092)
			(xy 394.277025 -18.656881) (xy 394.284392 -18.683455) (xy 394.298614 -18.707081) (xy 394.31865 -18.726029)
			(xy 394.343033 -18.73891) (xy 394.369977 -18.744781) (xy 394.383768 -18.744438) (xy 394.404596 -18.74393)
			(xy 394.431846 -18.744393) (xy 394.485792 -18.752149) (xy 394.538085 -18.767503) (xy 394.587661 -18.790143)
			(xy 394.63351 -18.819608) (xy 394.674699 -18.855298) (xy 394.71039 -18.896487) (xy 394.739855 -18.942335)
			(xy 394.762496 -18.991911) (xy 394.77785 -19.044204) (xy 394.785607 -19.09815) (xy 394.785607 -19.152647)
			(xy 397.336816 -19.152647) (xy 397.336816 -19.098153) (xy 397.344571 -19.044213) (xy 397.359923 -18.991926)
			(xy 397.38256 -18.942355) (xy 397.412021 -18.896511) (xy 397.447706 -18.855326) (xy 397.488888 -18.819638)
			(xy 397.534731 -18.790174) (xy 397.584299 -18.767533) (xy 397.636586 -18.752177) (xy 397.690525 -18.744418)
			(xy 397.717772 -18.74393) (xy 397.727633 -18.743991) (xy 397.747328 -18.745007) (xy 397.757142 -18.745962)
			(xy 397.771648 -18.746855) (xy 397.800211 -18.741619) (xy 397.826146 -18.728555) (xy 397.847357 -18.708719)
			(xy 397.862127 -18.683716) (xy 397.869262 -18.655567) (xy 397.868187 -18.626547) (xy 397.864076 -18.612612)
			(xy 397.854842 -18.583176) (xy 397.844882 -18.522298) (xy 397.844264 -18.491454) (xy 397.84475 -18.464203)
			(xy 397.852506 -18.410255) (xy 397.867861 -18.35796) (xy 397.890503 -18.308383) (xy 397.919969 -18.262533)
			(xy 397.95566 -18.221342) (xy 397.996851 -18.185651) (xy 398.042701 -18.156185) (xy 398.092278 -18.133543)
			(xy 398.144573 -18.118188) (xy 398.198521 -18.110432) (xy 398.253023 -18.110432) (xy 398.306971 -18.118188)
			(xy 398.359266 -18.133543) (xy 398.408843 -18.156185) (xy 398.454693 -18.185651) (xy 398.495884 -18.221342)
			(xy 398.531575 -18.262533) (xy 398.561041 -18.308383) (xy 398.583683 -18.35796) (xy 398.599038 -18.410255)
			(xy 398.606794 -18.464203) (xy 398.60728 -18.491454) (xy 398.606706 -18.521759) (xy 398.597138 -18.581608)
			(xy 398.58823 -18.61058) (xy 398.584429 -18.623759) (xy 398.58314 -18.651144) (xy 398.589195 -18.677882)
			(xy 398.602156 -18.702041) (xy 398.621085 -18.721872) (xy 398.644614 -18.735942) (xy 398.671042 -18.743234)
			(xy 398.68475 -18.743676) (xy 399.025618 -18.743676) (xy 399.039326 -18.743286) (xy 399.065747 -18.735962)
			(xy 399.089267 -18.721872) (xy 399.108191 -18.702034) (xy 399.121155 -18.677876) (xy 399.127226 -18.651139)
			(xy 399.125965 -18.623751) (xy 399.122138 -18.61058) (xy 399.113239 -18.581606) (xy 399.103671 -18.521758)
			(xy 399.103088 -18.491454) (xy 399.103574 -18.464203) (xy 399.11133 -18.410255) (xy 399.126685 -18.35796)
			(xy 399.149327 -18.308383) (xy 399.178793 -18.262533) (xy 399.214484 -18.221342) (xy 399.255675 -18.185651)
			(xy 399.301525 -18.156185) (xy 399.351102 -18.133543) (xy 399.403397 -18.118188) (xy 399.457345 -18.110432)
			(xy 399.511847 -18.110432) (xy 399.565795 -18.118188) (xy 399.61809 -18.133543) (xy 399.667667 -18.156185)
			(xy 399.713517 -18.185651) (xy 399.754708 -18.221342) (xy 399.790399 -18.262533) (xy 399.819865 -18.308383)
			(xy 399.842507 -18.35796) (xy 399.857862 -18.410255) (xy 399.865618 -18.464203) (xy 399.866104 -18.491454)
			(xy 399.865502 -18.522299) (xy 399.855547 -18.583182) (xy 399.846292 -18.612612) (xy 399.842079 -18.626542)
			(xy 399.840949 -18.655613) (xy 399.848065 -18.683823) (xy 399.862848 -18.70888) (xy 399.884098 -18.728751)
			(xy 399.910089 -18.741823) (xy 399.938711 -18.747033) (xy 399.953226 -18.745962) (xy 399.963041 -18.745014)
			(xy 399.982736 -18.743996) (xy 399.992596 -18.74393) (xy 400.019852 -18.744317) (xy 400.073809 -18.752074)
			(xy 400.126112 -18.767431) (xy 400.175698 -18.790076) (xy 400.221556 -18.819547) (xy 400.262753 -18.855244)
			(xy 400.298451 -18.896441) (xy 400.327922 -18.942299) (xy 400.350567 -18.991884) (xy 400.365925 -19.044188)
			(xy 400.373683 -19.098144) (xy 400.373683 -19.152647) (xy 402.924816 -19.152647) (xy 402.924816 -19.098153)
			(xy 402.932571 -19.044213) (xy 402.947923 -18.991926) (xy 402.97056 -18.942355) (xy 403.000021 -18.896511)
			(xy 403.035706 -18.855326) (xy 403.076888 -18.819638) (xy 403.122731 -18.790174) (xy 403.172299 -18.767533)
			(xy 403.224586 -18.752177) (xy 403.278525 -18.744418) (xy 403.305772 -18.74393) (xy 403.315633 -18.743991)
			(xy 403.335328 -18.745007) (xy 403.345142 -18.745962) (xy 403.359648 -18.746855) (xy 403.388211 -18.741619)
			(xy 403.414146 -18.728555) (xy 403.435357 -18.708719) (xy 403.450127 -18.683716) (xy 403.457262 -18.655567)
			(xy 403.456187 -18.626547) (xy 403.452076 -18.612612) (xy 403.442842 -18.583176) (xy 403.432882 -18.522298)
			(xy 403.432264 -18.491454) (xy 403.43275 -18.464203) (xy 403.440506 -18.410255) (xy 403.455861 -18.35796)
			(xy 403.478503 -18.308383) (xy 403.507969 -18.262533) (xy 403.54366 -18.221342) (xy 403.584851 -18.185651)
			(xy 403.630701 -18.156185) (xy 403.680278 -18.133543) (xy 403.732573 -18.118188) (xy 403.786521 -18.110432)
			(xy 403.841023 -18.110432) (xy 403.894971 -18.118188) (xy 403.947266 -18.133543) (xy 403.996843 -18.156185)
			(xy 404.042693 -18.185651) (xy 404.083884 -18.221342) (xy 404.119575 -18.262533) (xy 404.149041 -18.308383)
			(xy 404.171683 -18.35796) (xy 404.187038 -18.410255) (xy 404.194794 -18.464203) (xy 404.19528 -18.491454)
			(xy 404.194706 -18.521759) (xy 404.185138 -18.581608) (xy 404.17623 -18.61058) (xy 404.172429 -18.623759)
			(xy 404.17114 -18.651144) (xy 404.177195 -18.677882) (xy 404.190156 -18.702041) (xy 404.209085 -18.721872)
			(xy 404.232614 -18.735942) (xy 404.259042 -18.743234) (xy 404.27275 -18.743676) (xy 404.613618 -18.743676)
			(xy 404.627326 -18.743286) (xy 404.653747 -18.735962) (xy 404.677267 -18.721872) (xy 404.696191 -18.702034)
			(xy 404.709155 -18.677876) (xy 404.715226 -18.651139) (xy 404.713965 -18.623751) (xy 404.710138 -18.61058)
			(xy 404.701239 -18.581606) (xy 404.691671 -18.521758) (xy 404.691088 -18.491454) (xy 404.691574 -18.464203)
			(xy 404.69933 -18.410255) (xy 404.714685 -18.35796) (xy 404.737327 -18.308383) (xy 404.766793 -18.262533)
			(xy 404.802484 -18.221342) (xy 404.843675 -18.185651) (xy 404.889525 -18.156185) (xy 404.939102 -18.133543)
			(xy 404.991397 -18.118188) (xy 405.045345 -18.110432) (xy 405.099847 -18.110432) (xy 405.153795 -18.118188)
			(xy 405.20609 -18.133543) (xy 405.255667 -18.156185) (xy 405.301517 -18.185651) (xy 405.342708 -18.221342)
			(xy 405.378399 -18.262533) (xy 405.407865 -18.308383) (xy 405.430507 -18.35796) (xy 405.445862 -18.410255)
			(xy 405.453618 -18.464203) (xy 405.454104 -18.491454) (xy 405.453502 -18.522299) (xy 405.443547 -18.583182)
			(xy 405.434292 -18.612612) (xy 405.430079 -18.626542) (xy 405.428949 -18.655613) (xy 405.436065 -18.683823)
			(xy 405.450848 -18.70888) (xy 405.472098 -18.728751) (xy 405.498089 -18.741823) (xy 405.526711 -18.747033)
			(xy 405.541226 -18.745962) (xy 405.551041 -18.745014) (xy 405.570736 -18.743996) (xy 405.580596 -18.74393)
			(xy 405.607852 -18.744317) (xy 405.661809 -18.752074) (xy 405.714112 -18.767431) (xy 405.763698 -18.790076)
			(xy 405.809556 -18.819547) (xy 405.850753 -18.855244) (xy 405.886451 -18.896441) (xy 405.915922 -18.942299)
			(xy 405.938567 -18.991884) (xy 405.953925 -19.044188) (xy 405.961683 -19.098144) (xy 405.961683 -19.152656)
			(xy 405.953925 -19.206612) (xy 405.938567 -19.258916) (xy 405.915922 -19.308501) (xy 405.886451 -19.354359)
			(xy 405.850753 -19.395556) (xy 405.809556 -19.431253) (xy 405.763698 -19.460724) (xy 405.714112 -19.483369)
			(xy 405.661809 -19.498726) (xy 405.607852 -19.506483) (xy 405.580596 -19.506946) (xy 405.570735 -19.506888)
			(xy 405.55104 -19.50587) (xy 405.541226 -19.504914) (xy 405.526724 -19.503891) (xy 405.498141 -19.50914)
			(xy 405.472191 -19.522222) (xy 405.450974 -19.54208) (xy 405.436205 -19.567108) (xy 405.429078 -19.595281)
			(xy 405.43017 -19.624321) (xy 405.434292 -19.638264) (xy 405.443543 -19.667695) (xy 405.453492 -19.728577)
			(xy 405.454104 -19.759422) (xy 405.453618 -19.786673) (xy 405.445862 -19.840621) (xy 405.430507 -19.892916)
			(xy 405.407865 -19.942493) (xy 405.378399 -19.988343) (xy 405.342708 -20.029534) (xy 405.301517 -20.065225)
			(xy 405.255667 -20.094691) (xy 405.20609 -20.117333) (xy 405.153795 -20.132688) (xy 405.099847 -20.140444)
			(xy 405.045345 -20.140444) (xy 404.991397 -20.132688) (xy 404.939102 -20.117333) (xy 404.889525 -20.094691)
			(xy 404.843675 -20.065225) (xy 404.802484 -20.029534) (xy 404.766793 -19.988343) (xy 404.737327 -19.942493)
			(xy 404.714685 -19.892916) (xy 404.69933 -19.840621) (xy 404.691574 -19.786673) (xy 404.691088 -19.759422)
			(xy 404.691658 -19.729117) (xy 404.701229 -19.669268) (xy 404.710138 -19.640296) (xy 404.713998 -19.627131)
			(xy 404.715282 -19.599737) (xy 404.70922 -19.572991) (xy 404.69625 -19.548827) (xy 404.67731 -19.528994)
			(xy 404.653769 -19.514925) (xy 404.627331 -19.507638) (xy 404.613618 -19.5072) (xy 404.27275 -19.5072)
			(xy 404.259047 -19.507677) (xy 404.232632 -19.514984) (xy 404.209114 -19.529056) (xy 404.190189 -19.54888)
			(xy 404.177222 -19.573026) (xy 404.171148 -19.599751) (xy 404.172406 -19.627129) (xy 404.17623 -19.640296)
			(xy 404.185125 -19.669271) (xy 404.194695 -19.729118) (xy 404.19528 -19.759422) (xy 404.194794 -19.786673)
			(xy 404.187038 -19.840621) (xy 404.171683 -19.892916) (xy 404.149041 -19.942493) (xy 404.119575 -19.988343)
			(xy 404.083884 -20.029534) (xy 404.042693 -20.065225) (xy 403.996843 -20.094691) (xy 403.947266 -20.117333)
			(xy 403.894971 -20.132688) (xy 403.841023 -20.140444) (xy 403.786521 -20.140444) (xy 403.732573 -20.132688)
			(xy 403.680278 -20.117333) (xy 403.630701 -20.094691) (xy 403.584851 -20.065225) (xy 403.54366 -20.029534)
			(xy 403.507969 -19.988343) (xy 403.478503 -19.942493) (xy 403.455861 -19.892916) (xy 403.440506 -19.840621)
			(xy 403.43275 -19.786673) (xy 403.432264 -19.759422) (xy 403.432861 -19.728576) (xy 403.44282 -19.667694)
			(xy 403.452076 -19.638264) (xy 403.456351 -19.624349) (xy 403.457476 -19.595268) (xy 403.450353 -19.56705)
			(xy 403.43556 -19.541986) (xy 403.414299 -19.522113) (xy 403.388295 -19.509043) (xy 403.359661 -19.503838)
			(xy 403.345142 -19.504914) (xy 403.335327 -19.505864) (xy 403.315632 -19.506881) (xy 403.305772 -19.506946)
			(xy 403.278525 -19.506382) (xy 403.224586 -19.498623) (xy 403.172299 -19.483267) (xy 403.122731 -19.460626)
			(xy 403.076888 -19.431162) (xy 403.035706 -19.395474) (xy 403.000021 -19.354289) (xy 402.97056 -19.308445)
			(xy 402.947923 -19.258874) (xy 402.932571 -19.206587) (xy 402.924816 -19.152647) (xy 400.373683 -19.152647)
			(xy 400.373683 -19.152656) (xy 400.365925 -19.206612) (xy 400.350567 -19.258916) (xy 400.327922 -19.308501)
			(xy 400.298451 -19.354359) (xy 400.262753 -19.395556) (xy 400.221556 -19.431253) (xy 400.175698 -19.460724)
			(xy 400.126112 -19.483369) (xy 400.073809 -19.498726) (xy 400.019852 -19.506483) (xy 399.992596 -19.506946)
			(xy 399.982735 -19.506888) (xy 399.96304 -19.50587) (xy 399.953226 -19.504914) (xy 399.938724 -19.503891)
			(xy 399.910141 -19.50914) (xy 399.884191 -19.522222) (xy 399.862974 -19.54208) (xy 399.848205 -19.567108)
			(xy 399.841078 -19.595281) (xy 399.84217 -19.624321) (xy 399.846292 -19.638264) (xy 399.855543 -19.667695)
			(xy 399.865492 -19.728577) (xy 399.866104 -19.759422) (xy 399.865618 -19.786673) (xy 399.857862 -19.840621)
			(xy 399.842507 -19.892916) (xy 399.819865 -19.942493) (xy 399.790399 -19.988343) (xy 399.754708 -20.029534)
			(xy 399.713517 -20.065225) (xy 399.667667 -20.094691) (xy 399.61809 -20.117333) (xy 399.565795 -20.132688)
			(xy 399.511847 -20.140444) (xy 399.457345 -20.140444) (xy 399.403397 -20.132688) (xy 399.351102 -20.117333)
			(xy 399.301525 -20.094691) (xy 399.255675 -20.065225) (xy 399.214484 -20.029534) (xy 399.178793 -19.988343)
			(xy 399.149327 -19.942493) (xy 399.126685 -19.892916) (xy 399.11133 -19.840621) (xy 399.103574 -19.786673)
			(xy 399.103088 -19.759422) (xy 399.103658 -19.729117) (xy 399.113229 -19.669268) (xy 399.122138 -19.640296)
			(xy 399.125998 -19.627131) (xy 399.127282 -19.599737) (xy 399.12122 -19.572991) (xy 399.10825 -19.548827)
			(xy 399.08931 -19.528994) (xy 399.065769 -19.514925) (xy 399.039331 -19.507638) (xy 399.025618 -19.5072)
			(xy 398.68475 -19.5072) (xy 398.671047 -19.507677) (xy 398.644632 -19.514984) (xy 398.621114 -19.529056)
			(xy 398.602189 -19.54888) (xy 398.589222 -19.573026) (xy 398.583148 -19.599751) (xy 398.584406 -19.627129)
			(xy 398.58823 -19.640296) (xy 398.597125 -19.669271) (xy 398.606695 -19.729118) (xy 398.60728 -19.759422)
			(xy 398.606794 -19.786673) (xy 398.599038 -19.840621) (xy 398.583683 -19.892916) (xy 398.561041 -19.942493)
			(xy 398.531575 -19.988343) (xy 398.495884 -20.029534) (xy 398.454693 -20.065225) (xy 398.408843 -20.094691)
			(xy 398.359266 -20.117333) (xy 398.306971 -20.132688) (xy 398.253023 -20.140444) (xy 398.198521 -20.140444)
			(xy 398.144573 -20.132688) (xy 398.092278 -20.117333) (xy 398.042701 -20.094691) (xy 397.996851 -20.065225)
			(xy 397.95566 -20.029534) (xy 397.919969 -19.988343) (xy 397.890503 -19.942493) (xy 397.867861 -19.892916)
			(xy 397.852506 -19.840621) (xy 397.84475 -19.786673) (xy 397.844264 -19.759422) (xy 397.844861 -19.728576)
			(xy 397.85482 -19.667694) (xy 397.864076 -19.638264) (xy 397.868351 -19.624349) (xy 397.869476 -19.595268)
			(xy 397.862353 -19.56705) (xy 397.84756 -19.541986) (xy 397.826299 -19.522113) (xy 397.800295 -19.509043)
			(xy 397.771661 -19.503838) (xy 397.757142 -19.504914) (xy 397.747327 -19.505864) (xy 397.727632 -19.506881)
			(xy 397.717772 -19.506946) (xy 397.690525 -19.506382) (xy 397.636586 -19.498623) (xy 397.584299 -19.483267)
			(xy 397.534731 -19.460626) (xy 397.488888 -19.431162) (xy 397.447706 -19.395474) (xy 397.412021 -19.354289)
			(xy 397.38256 -19.308445) (xy 397.359923 -19.258874) (xy 397.344571 -19.206587) (xy 397.336816 -19.152647)
			(xy 394.785607 -19.152647) (xy 394.785607 -19.15265) (xy 394.77785 -19.206596) (xy 394.762496 -19.258889)
			(xy 394.739855 -19.308465) (xy 394.71039 -19.354313) (xy 394.674699 -19.395502) (xy 394.63351 -19.431192)
			(xy 394.587661 -19.460657) (xy 394.538085 -19.483297) (xy 394.485792 -19.498651) (xy 394.431846 -19.506407)
			(xy 394.404596 -19.506946) (xy 394.383768 -19.506438) (xy 394.369985 -19.506139) (xy 394.343068 -19.512043)
			(xy 394.318711 -19.524931) (xy 394.298688 -19.543863) (xy 394.284458 -19.567462) (xy 394.277058 -19.594006)
			(xy 394.27658 -19.607784) (xy 394.27658 -19.725386) (xy 394.276834 -19.727418) (xy 394.278104 -19.759422)
			(xy 394.276834 -19.791426) (xy 394.27658 -19.793458) (xy 394.27658 -30.962346) (xy 394.527024 -31.21279)
			(xy 394.540994 -31.216346) (xy 394.568401 -31.223443) (xy 394.620899 -31.24463) (xy 394.669685 -31.27335)
			(xy 394.713687 -31.30897) (xy 394.751936 -31.350706) (xy 394.783591 -31.397642) (xy 394.807955 -31.448743)
			(xy 394.824492 -31.502886) (xy 394.832839 -31.55888) (xy 394.833348 -31.587186) (xy 394.832863 -31.614439)
			(xy 394.825109 -31.66839) (xy 394.809755 -31.720689) (xy 394.787115 -31.770271) (xy 394.75765 -31.816126)
			(xy 394.721959 -31.857321) (xy 394.680769 -31.893018) (xy 394.634918 -31.922489) (xy 394.58534 -31.945136)
			(xy 394.533043 -31.960497) (xy 394.479093 -31.968259) (xy 394.45184 -31.968694) (xy 394.423998 -31.968151)
			(xy 394.368915 -31.959991) (xy 394.342112 -31.952438) (xy 394.334746 -31.950406) (xy 394.27658 -31.950406)
			(xy 394.27658 -32.115252) (xy 394.338556 -32.115252) (xy 394.348716 -32.11068) (xy 394.374093 -32.099395)
			(xy 394.427292 -32.083453) (xy 394.482238 -32.075376) (xy 394.510006 -32.074866) (xy 394.537259 -32.075352)
			(xy 394.59121 -32.08311) (xy 394.643507 -32.098467) (xy 394.693087 -32.12111) (xy 394.73894 -32.150578)
			(xy 394.780132 -32.186272) (xy 394.815825 -32.227465) (xy 394.845293 -32.273318) (xy 394.867935 -32.322898)
			(xy 394.883291 -32.375196) (xy 394.891048 -32.429147) (xy 394.891048 -32.483653) (xy 394.883291 -32.537604)
			(xy 394.867935 -32.589902) (xy 394.845293 -32.639482) (xy 394.815825 -32.685335) (xy 394.780132 -32.726528)
			(xy 394.73894 -32.762222) (xy 394.693087 -32.79169) (xy 394.643507 -32.814333) (xy 394.59121 -32.82969)
			(xy 394.537259 -32.837448) (xy 394.510006 -32.837882) (xy 394.479789 -32.837302) (xy 394.420109 -32.827775)
			(xy 394.362672 -32.808975) (xy 394.30891 -32.78137) (xy 394.2842 -32.763968) (xy 394.249148 -32.73806)
			(xy 393.56792 -33.419288) (xy 387.48208 -33.419288) (xy 386.63372 -34.267648) (xy 386.63372 -35.118802)
			(xy 394.394688 -35.118802) (xy 394.398759 -35.06318) (xy 394.410885 -35.008743) (xy 394.430808 -34.956652)
			(xy 394.458104 -34.908017) (xy 394.49219 -34.863874) (xy 394.532339 -34.825165) (xy 394.577697 -34.792714)
			(xy 394.627297 -34.767213) (xy 394.680081 -34.749206) (xy 394.734924 -34.739076) (xy 394.790658 -34.737039)
			(xy 394.846095 -34.743139) (xy 394.900052 -34.757245) (xy 394.951381 -34.779057) (xy 394.998987 -34.808111)
			(xy 395.041855 -34.843786) (xy 395.079072 -34.885323) (xy 395.109845 -34.931836) (xy 395.133517 -34.982333)
			(xy 395.149585 -35.03574) (xy 395.157705 -35.090916) (xy 395.158214 -35.118802) (xy 395.157705 -35.146688)
			(xy 395.149585 -35.201864) (xy 395.133517 -35.255271) (xy 395.109845 -35.305768) (xy 395.079072 -35.352281)
			(xy 395.041855 -35.393818) (xy 394.998987 -35.429493) (xy 394.951381 -35.458547) (xy 394.900052 -35.480359)
			(xy 394.846095 -35.494465) (xy 394.790658 -35.500565) (xy 394.734924 -35.498528) (xy 394.680081 -35.488398)
			(xy 394.627297 -35.470391) (xy 394.577697 -35.44489) (xy 394.532339 -35.412439) (xy 394.49219 -35.37373)
			(xy 394.458104 -35.329587) (xy 394.430808 -35.280952) (xy 394.410885 -35.228861) (xy 394.398759 -35.174424)
			(xy 394.394688 -35.118802) (xy 386.63372 -35.118802) (xy 386.63372 -35.589718) (xy 387.393432 -35.589718)
			(xy 387.397503 -35.534096) (xy 387.409629 -35.479659) (xy 387.429552 -35.427568) (xy 387.456848 -35.378933)
			(xy 387.490934 -35.33479) (xy 387.531083 -35.296081) (xy 387.576441 -35.26363) (xy 387.626041 -35.238129)
			(xy 387.678825 -35.220122) (xy 387.733668 -35.209992) (xy 387.789402 -35.207955) (xy 387.844839 -35.214055)
			(xy 387.898796 -35.228161) (xy 387.950125 -35.249973) (xy 387.997731 -35.279027) (xy 388.040599 -35.314702)
			(xy 388.077816 -35.356239) (xy 388.108589 -35.402752) (xy 388.132261 -35.453249) (xy 388.148329 -35.506656)
			(xy 388.156449 -35.561832) (xy 388.156958 -35.589718) (xy 388.156449 -35.617604) (xy 388.148329 -35.67278)
			(xy 388.132261 -35.726187) (xy 388.108589 -35.776684) (xy 388.077816 -35.823197) (xy 388.040599 -35.864734)
			(xy 387.997731 -35.900409) (xy 387.950125 -35.929463) (xy 387.898796 -35.951275) (xy 387.878833 -35.956494)
			(xy 391.387836 -35.956494) (xy 391.391907 -35.900872) (xy 391.404033 -35.846435) (xy 391.423956 -35.794344)
			(xy 391.451252 -35.745709) (xy 391.485338 -35.701566) (xy 391.525487 -35.662857) (xy 391.570845 -35.630406)
			(xy 391.620445 -35.604905) (xy 391.673229 -35.586898) (xy 391.728072 -35.576768) (xy 391.783806 -35.574731)
			(xy 391.839243 -35.580831) (xy 391.8932 -35.594937) (xy 391.944529 -35.616749) (xy 391.992135 -35.645803)
			(xy 392.035003 -35.681478) (xy 392.07222 -35.723015) (xy 392.102993 -35.769528) (xy 392.126665 -35.820025)
			(xy 392.142733 -35.873432) (xy 392.150853 -35.928608) (xy 392.151362 -35.956494) (xy 392.150853 -35.98438)
			(xy 392.142733 -36.039556) (xy 392.126665 -36.092963) (xy 392.102993 -36.14346) (xy 392.07222 -36.189973)
			(xy 392.035003 -36.23151) (xy 391.992135 -36.267185) (xy 391.944529 -36.296239) (xy 391.8932 -36.318051)
			(xy 391.839243 -36.332157) (xy 391.783806 -36.338257) (xy 391.728072 -36.33622) (xy 391.673229 -36.32609)
			(xy 391.620445 -36.308083) (xy 391.570845 -36.282582) (xy 391.525487 -36.250131) (xy 391.485338 -36.211422)
			(xy 391.451252 -36.167279) (xy 391.423956 -36.118644) (xy 391.404033 -36.066553) (xy 391.391907 -36.012116)
			(xy 391.387836 -35.956494) (xy 387.878833 -35.956494) (xy 387.844839 -35.965381) (xy 387.789402 -35.971481)
			(xy 387.733668 -35.969444) (xy 387.678825 -35.959314) (xy 387.626041 -35.941307) (xy 387.576441 -35.915806)
			(xy 387.531083 -35.883355) (xy 387.490934 -35.844646) (xy 387.456848 -35.800503) (xy 387.429552 -35.751868)
			(xy 387.409629 -35.699777) (xy 387.397503 -35.64534) (xy 387.393432 -35.589718) (xy 386.63372 -35.589718)
			(xy 386.63372 -37.14115) (xy 387.243064 -37.14115) (xy 387.247135 -37.085528) (xy 387.259261 -37.031091)
			(xy 387.279184 -36.979) (xy 387.30648 -36.930365) (xy 387.340566 -36.886222) (xy 387.380715 -36.847513)
			(xy 387.426073 -36.815062) (xy 387.475673 -36.789561) (xy 387.528457 -36.771554) (xy 387.5833 -36.761424)
			(xy 387.639034 -36.759387) (xy 387.694471 -36.765487) (xy 387.748428 -36.779593) (xy 387.799757 -36.801405)
			(xy 387.847363 -36.830459) (xy 387.890231 -36.866134) (xy 387.927448 -36.907671) (xy 387.958221 -36.954184)
			(xy 387.981893 -37.004681) (xy 387.997961 -37.058088) (xy 388.006081 -37.113264) (xy 388.00659 -37.14115)
			(xy 388.006081 -37.169036) (xy 387.997961 -37.224212) (xy 387.981893 -37.277619) (xy 387.958221 -37.328116)
			(xy 387.927448 -37.374629) (xy 387.890231 -37.416166) (xy 387.847363 -37.451841) (xy 387.799757 -37.480895)
			(xy 387.748428 -37.502707) (xy 387.694471 -37.516813) (xy 387.678285 -37.518594) (xy 394.854428 -37.518594)
			(xy 394.858499 -37.462972) (xy 394.870625 -37.408535) (xy 394.890548 -37.356444) (xy 394.917844 -37.307809)
			(xy 394.95193 -37.263666) (xy 394.992079 -37.224957) (xy 395.037437 -37.192506) (xy 395.087037 -37.167005)
			(xy 395.139821 -37.148998) (xy 395.194664 -37.138868) (xy 395.250398 -37.136831) (xy 395.305835 -37.142931)
			(xy 395.359792 -37.157037) (xy 395.411121 -37.178849) (xy 395.458727 -37.207903) (xy 395.501595 -37.243578)
			(xy 395.538812 -37.285115) (xy 395.569585 -37.331628) (xy 395.593257 -37.382125) (xy 395.609325 -37.435532)
			(xy 395.617445 -37.490708) (xy 395.617954 -37.518594) (xy 395.617445 -37.54648) (xy 395.609325 -37.601656)
			(xy 395.593257 -37.655063) (xy 395.569585 -37.70556) (xy 395.538812 -37.752073) (xy 395.501595 -37.79361)
			(xy 395.458727 -37.829285) (xy 395.411121 -37.858339) (xy 395.359792 -37.880151) (xy 395.305835 -37.894257)
			(xy 395.250398 -37.900357) (xy 395.194664 -37.89832) (xy 395.139821 -37.88819) (xy 395.087037 -37.870183)
			(xy 395.037437 -37.844682) (xy 394.992079 -37.812231) (xy 394.95193 -37.773522) (xy 394.917844 -37.729379)
			(xy 394.890548 -37.680744) (xy 394.870625 -37.628653) (xy 394.858499 -37.574216) (xy 394.854428 -37.518594)
			(xy 387.678285 -37.518594) (xy 387.639034 -37.522913) (xy 387.5833 -37.520876) (xy 387.528457 -37.510746)
			(xy 387.475673 -37.492739) (xy 387.426073 -37.467238) (xy 387.380715 -37.434787) (xy 387.340566 -37.396078)
			(xy 387.30648 -37.351935) (xy 387.279184 -37.3033) (xy 387.259261 -37.251209) (xy 387.247135 -37.196772)
			(xy 387.243064 -37.14115) (xy 386.63372 -37.14115) (xy 386.63372 -38.496748) (xy 389.640062 -38.496748)
			(xy 389.644133 -38.441126) (xy 389.656259 -38.386689) (xy 389.676182 -38.334598) (xy 389.703478 -38.285963)
			(xy 389.737564 -38.24182) (xy 389.777713 -38.203111) (xy 389.823071 -38.17066) (xy 389.872671 -38.145159)
			(xy 389.925455 -38.127152) (xy 389.980298 -38.117022) (xy 390.036032 -38.114985) (xy 390.091469 -38.121085)
			(xy 390.145426 -38.135191) (xy 390.196755 -38.157003) (xy 390.244361 -38.186057) (xy 390.287229 -38.221732)
			(xy 390.324446 -38.263269) (xy 390.355219 -38.309782) (xy 390.378891 -38.360279) (xy 390.394959 -38.413686)
			(xy 390.403079 -38.468862) (xy 390.403588 -38.496748) (xy 390.403079 -38.524634) (xy 390.394959 -38.57981)
			(xy 390.378891 -38.633217) (xy 390.355219 -38.683714) (xy 390.324446 -38.730227) (xy 390.287229 -38.771764)
			(xy 390.244361 -38.807439) (xy 390.196755 -38.836493) (xy 390.145426 -38.858305) (xy 390.091469 -38.872411)
			(xy 390.036032 -38.878511) (xy 389.980298 -38.876474) (xy 389.925455 -38.866344) (xy 389.872671 -38.848337)
			(xy 389.823071 -38.822836) (xy 389.777713 -38.790385) (xy 389.737564 -38.751676) (xy 389.703478 -38.707533)
			(xy 389.676182 -38.658898) (xy 389.656259 -38.606807) (xy 389.644133 -38.55237) (xy 389.640062 -38.496748)
			(xy 386.63372 -38.496748) (xy 386.63372 -39.436548) (xy 389.622282 -39.436548) (xy 389.626353 -39.380926)
			(xy 389.638479 -39.326489) (xy 389.658402 -39.274398) (xy 389.685698 -39.225763) (xy 389.719784 -39.18162)
			(xy 389.759933 -39.142911) (xy 389.805291 -39.11046) (xy 389.854891 -39.084959) (xy 389.907675 -39.066952)
			(xy 389.962518 -39.056822) (xy 390.018252 -39.054785) (xy 390.073689 -39.060885) (xy 390.127646 -39.074991)
			(xy 390.178975 -39.096803) (xy 390.226581 -39.125857) (xy 390.269449 -39.161532) (xy 390.306666 -39.203069)
			(xy 390.337439 -39.249582) (xy 390.361111 -39.300079) (xy 390.377179 -39.353486) (xy 390.385299 -39.408662)
			(xy 390.385808 -39.436548) (xy 390.385299 -39.464434) (xy 390.377179 -39.51961) (xy 390.361111 -39.573017)
			(xy 390.337439 -39.623514) (xy 390.331236 -39.63289) (xy 392.16203 -39.63289) (xy 392.162516 -39.605639)
			(xy 392.170272 -39.551691) (xy 392.185627 -39.499396) (xy 392.208269 -39.449819) (xy 392.237735 -39.403969)
			(xy 392.273426 -39.362778) (xy 392.314617 -39.327087) (xy 392.360467 -39.297621) (xy 392.410044 -39.274979)
			(xy 392.462339 -39.259624) (xy 392.516287 -39.251868) (xy 392.570789 -39.251868) (xy 392.624737 -39.259624)
			(xy 392.677032 -39.274979) (xy 392.726609 -39.297621) (xy 392.772459 -39.327087) (xy 392.81365 -39.362778)
			(xy 392.849341 -39.403969) (xy 392.878807 -39.449819) (xy 392.901449 -39.499396) (xy 392.916804 -39.551691)
			(xy 392.92456 -39.605639) (xy 392.925046 -39.63289) (xy 392.924619 -39.658681) (xy 392.917653 -39.709792)
			(xy 392.903862 -39.759497) (xy 392.883497 -39.806889) (xy 392.856929 -39.851104) (xy 392.824644 -39.891333)
			(xy 392.78723 -39.926844) (xy 392.76655 -39.942262) (xy 392.754555 -39.951581) (xy 392.736203 -39.975765)
			(xy 392.725775 -40.004276) (xy 392.724191 -40.034593) (xy 392.731593 -40.064036) (xy 392.747326 -40.089999)
			(xy 392.769998 -40.110189) (xy 392.783568 -40.117014) (xy 392.808018 -40.128857) (xy 392.853625 -40.158373)
			(xy 392.894584 -40.19406) (xy 392.930067 -40.235196) (xy 392.959355 -40.28095) (xy 392.981858 -40.330395)
			(xy 392.997118 -40.382533) (xy 393.004828 -40.436308) (xy 393.00531 -40.46347) (xy 393.004824 -40.490721)
			(xy 392.997068 -40.544669) (xy 392.981713 -40.596964) (xy 392.959071 -40.646541) (xy 392.929605 -40.692391)
			(xy 392.893914 -40.733582) (xy 392.852723 -40.769273) (xy 392.806873 -40.798739) (xy 392.757296 -40.821381)
			(xy 392.705001 -40.836736) (xy 392.651053 -40.844492) (xy 392.596551 -40.844492) (xy 392.542603 -40.836736)
			(xy 392.490308 -40.821381) (xy 392.440731 -40.798739) (xy 392.394881 -40.769273) (xy 392.35369 -40.733582)
			(xy 392.317999 -40.692391) (xy 392.288533 -40.646541) (xy 392.265891 -40.596964) (xy 392.250536 -40.544669)
			(xy 392.24278 -40.490721) (xy 392.242294 -40.46347) (xy 392.242716 -40.437679) (xy 392.249686 -40.386569)
			(xy 392.26348 -40.336865) (xy 392.283846 -40.289474) (xy 392.310414 -40.245259) (xy 392.342699 -40.205029)
			(xy 392.380111 -40.169517) (xy 392.40079 -40.154098) (xy 392.412818 -40.144821) (xy 392.431162 -40.120625)
			(xy 392.441583 -40.092106) (xy 392.44316 -40.061783) (xy 392.435753 -40.032337) (xy 392.420017 -40.006369)
			(xy 392.397343 -39.986175) (xy 392.383772 -39.979346) (xy 392.359292 -39.967562) (xy 392.313686 -39.938035)
			(xy 392.27273 -39.902339) (xy 392.237251 -39.861194) (xy 392.207966 -39.815432) (xy 392.185469 -39.765979)
			(xy 392.170214 -39.713835) (xy 392.162509 -39.660055) (xy 392.16203 -39.63289) (xy 390.331236 -39.63289)
			(xy 390.306666 -39.670027) (xy 390.269449 -39.711564) (xy 390.226581 -39.747239) (xy 390.178975 -39.776293)
			(xy 390.127646 -39.798105) (xy 390.073689 -39.812211) (xy 390.018252 -39.818311) (xy 389.962518 -39.816274)
			(xy 389.907675 -39.806144) (xy 389.854891 -39.788137) (xy 389.805291 -39.762636) (xy 389.759933 -39.730185)
			(xy 389.719784 -39.691476) (xy 389.685698 -39.647333) (xy 389.658402 -39.598698) (xy 389.638479 -39.546607)
			(xy 389.626353 -39.49217) (xy 389.622282 -39.436548) (xy 386.63372 -39.436548) (xy 386.63372 -40.495728)
			(xy 387.9088 -41.770808) (xy 409.11272 -41.770808)
		)
		(stroke
			(width 0)
			(type solid)
		)
		(fill yes)
		(layer "In6.Cu")
		(net "P3V3_OCP_SFF")
	)
	(gr_poly
		(pts
			(xy 57.846722 -371.886226) (xy 57.846722 -365.853726) (xy 57.861708 -365.83874) (xy 57.861708 -361.060746)
			(xy 57.860946 -361.049062) (xy 57.77992 -360.853228) (xy 57.58434 -360.38155) (xy 57.58434 -360.381296)
			(xy 57.521856 -360.23042) (xy 56.643778 -358.110536) (xy 56.090566 -356.77475) (xy 56.085994 -356.763066)
			(xy 56.074785 -356.731069) (xy 56.06265 -356.664373) (xy 56.061864 -356.630478) (xy 56.061864 -352.546412)
			(xy 55.626 -352.110548) (xy 55.626 -336.48269) (xy 49.511458 -330.368148) (xy 35.8648 -330.368148)
			(xy 34.910014 -331.322934) (xy 34.910014 -334.679036) (xy 34.902394 -334.697832) (xy 34.902394 -335.51361)
			(xy 39.617392 -335.51361) (xy 39.617392 -335.428914) (xy 39.625443 -335.3446) (xy 39.641472 -335.261434)
			(xy 39.665333 -335.180167) (xy 39.696812 -335.101537) (xy 39.735623 -335.026256) (xy 39.781413 -334.955004)
			(xy 39.833769 -334.888428) (xy 39.892217 -334.82713) (xy 39.956227 -334.771665) (xy 40.025219 -334.722536)
			(xy 40.098569 -334.680187) (xy 40.175612 -334.645003) (xy 40.255651 -334.617301) (xy 40.33796 -334.597333)
			(xy 40.421795 -334.58528) (xy 40.506396 -334.58125) (xy 40.590997 -334.58528) (xy 40.674832 -334.597333)
			(xy 40.757141 -334.617301) (xy 40.83718 -334.645003) (xy 40.914223 -334.680187) (xy 40.987573 -334.722536)
			(xy 41.056565 -334.771665) (xy 41.120575 -334.82713) (xy 41.179023 -334.888428) (xy 41.231379 -334.955004)
			(xy 41.277169 -335.026256) (xy 41.31598 -335.101537) (xy 41.347459 -335.180167) (xy 41.37132 -335.261434)
			(xy 41.387349 -335.3446) (xy 41.3954 -335.428914) (xy 41.395904 -335.471262) (xy 41.3954 -335.51361)
			(xy 41.394794 -335.51996) (xy 45.808134 -335.51996) (xy 45.808134 -335.435264) (xy 45.816185 -335.35095)
			(xy 45.832214 -335.267784) (xy 45.856075 -335.186517) (xy 45.887554 -335.107887) (xy 45.926365 -335.032606)
			(xy 45.972155 -334.961354) (xy 46.024511 -334.894778) (xy 46.082959 -334.83348) (xy 46.146969 -334.778015)
			(xy 46.215961 -334.728886) (xy 46.289311 -334.686537) (xy 46.366354 -334.651353) (xy 46.446393 -334.623651)
			(xy 46.528702 -334.603683) (xy 46.612537 -334.59163) (xy 46.697138 -334.5876) (xy 46.781739 -334.59163)
			(xy 46.865574 -334.603683) (xy 46.947883 -334.623651) (xy 47.027922 -334.651353) (xy 47.104965 -334.686537)
			(xy 47.178315 -334.728886) (xy 47.247307 -334.778015) (xy 47.311317 -334.83348) (xy 47.369765 -334.894778)
			(xy 47.422121 -334.961354) (xy 47.467911 -335.032606) (xy 47.506722 -335.107887) (xy 47.538201 -335.186517)
			(xy 47.562062 -335.267784) (xy 47.578091 -335.35095) (xy 47.586142 -335.435264) (xy 47.586646 -335.477612)
			(xy 47.586142 -335.51996) (xy 52.005734 -335.51996) (xy 52.005734 -335.435264) (xy 52.013785 -335.35095)
			(xy 52.029814 -335.267784) (xy 52.053675 -335.186517) (xy 52.085154 -335.107887) (xy 52.123965 -335.032606)
			(xy 52.169755 -334.961354) (xy 52.222111 -334.894778) (xy 52.280559 -334.83348) (xy 52.344569 -334.778015)
			(xy 52.413561 -334.728886) (xy 52.486911 -334.686537) (xy 52.563954 -334.651353) (xy 52.643993 -334.623651)
			(xy 52.726302 -334.603683) (xy 52.810137 -334.59163) (xy 52.894738 -334.5876) (xy 52.979339 -334.59163)
			(xy 53.063174 -334.603683) (xy 53.145483 -334.623651) (xy 53.225522 -334.651353) (xy 53.302565 -334.686537)
			(xy 53.375915 -334.728886) (xy 53.444907 -334.778015) (xy 53.508917 -334.83348) (xy 53.567365 -334.894778)
			(xy 53.619721 -334.961354) (xy 53.665511 -335.032606) (xy 53.704322 -335.107887) (xy 53.735801 -335.186517)
			(xy 53.759662 -335.267784) (xy 53.775691 -335.35095) (xy 53.783742 -335.435264) (xy 53.784246 -335.477612)
			(xy 53.783742 -335.51996) (xy 53.775691 -335.604274) (xy 53.759662 -335.68744) (xy 53.735801 -335.768707)
			(xy 53.704322 -335.847337) (xy 53.665511 -335.922618) (xy 53.619721 -335.99387) (xy 53.567365 -336.060446)
			(xy 53.508917 -336.121744) (xy 53.444907 -336.177209) (xy 53.375915 -336.226338) (xy 53.302565 -336.268687)
			(xy 53.225522 -336.303871) (xy 53.145483 -336.331573) (xy 53.063174 -336.351541) (xy 52.979339 -336.363594)
			(xy 52.894738 -336.367625) (xy 52.810137 -336.363594) (xy 52.726302 -336.351541) (xy 52.643993 -336.331573)
			(xy 52.563954 -336.303871) (xy 52.486911 -336.268687) (xy 52.413561 -336.226338) (xy 52.344569 -336.177209)
			(xy 52.280559 -336.121744) (xy 52.222111 -336.060446) (xy 52.169755 -335.99387) (xy 52.123965 -335.922618)
			(xy 52.085154 -335.847337) (xy 52.053675 -335.768707) (xy 52.029814 -335.68744) (xy 52.013785 -335.604274)
			(xy 52.005734 -335.51996) (xy 47.586142 -335.51996) (xy 47.578091 -335.604274) (xy 47.562062 -335.68744)
			(xy 47.538201 -335.768707) (xy 47.506722 -335.847337) (xy 47.467911 -335.922618) (xy 47.422121 -335.99387)
			(xy 47.369765 -336.060446) (xy 47.311317 -336.121744) (xy 47.247307 -336.177209) (xy 47.178315 -336.226338)
			(xy 47.104965 -336.268687) (xy 47.027922 -336.303871) (xy 46.947883 -336.331573) (xy 46.865574 -336.351541)
			(xy 46.781739 -336.363594) (xy 46.697138 -336.367625) (xy 46.612537 -336.363594) (xy 46.528702 -336.351541)
			(xy 46.446393 -336.331573) (xy 46.366354 -336.303871) (xy 46.289311 -336.268687) (xy 46.215961 -336.226338)
			(xy 46.146969 -336.177209) (xy 46.082959 -336.121744) (xy 46.024511 -336.060446) (xy 45.972155 -335.99387)
			(xy 45.926365 -335.922618) (xy 45.887554 -335.847337) (xy 45.856075 -335.768707) (xy 45.832214 -335.68744)
			(xy 45.816185 -335.604274) (xy 45.808134 -335.51996) (xy 41.394794 -335.51996) (xy 41.387349 -335.597924)
			(xy 41.37132 -335.68109) (xy 41.347459 -335.762357) (xy 41.31598 -335.840987) (xy 41.277169 -335.916268)
			(xy 41.231379 -335.98752) (xy 41.179023 -336.054096) (xy 41.120575 -336.115394) (xy 41.056565 -336.170859)
			(xy 40.987573 -336.219988) (xy 40.914223 -336.262337) (xy 40.83718 -336.297521) (xy 40.757141 -336.325223)
			(xy 40.674832 -336.345191) (xy 40.590997 -336.357244) (xy 40.506396 -336.361275) (xy 40.421795 -336.357244)
			(xy 40.33796 -336.345191) (xy 40.255651 -336.325223) (xy 40.175612 -336.297521) (xy 40.098569 -336.262337)
			(xy 40.025219 -336.219988) (xy 39.956227 -336.170859) (xy 39.892217 -336.115394) (xy 39.833769 -336.054096)
			(xy 39.781413 -335.98752) (xy 39.735623 -335.916268) (xy 39.696812 -335.840987) (xy 39.665333 -335.762357)
			(xy 39.641472 -335.68109) (xy 39.625443 -335.597924) (xy 39.617392 -335.51361) (xy 34.902394 -335.51361)
			(xy 34.902394 -337.471258) (xy 39.590985 -337.471258) (xy 39.595007 -337.385538) (xy 39.607038 -337.30057)
			(xy 39.626974 -337.217103) (xy 39.654637 -337.135869) (xy 39.689786 -337.057583) (xy 39.732112 -336.982932)
			(xy 39.781241 -336.912573) (xy 39.836744 -336.847123) (xy 39.898131 -336.787159) (xy 39.964864 -336.733206)
			(xy 40.036356 -336.685739) (xy 40.111978 -336.645175) (xy 40.191067 -336.611871) (xy 40.272927 -336.586119)
			(xy 40.356838 -336.568146) (xy 40.442064 -336.55811) (xy 40.527856 -336.556098) (xy 40.613458 -336.562129)
			(xy 40.69812 -336.576149) (xy 40.781097 -336.598035) (xy 40.86166 -336.627596) (xy 40.9391 -336.66457)
			(xy 41.012739 -336.708634) (xy 41.081927 -336.7594) (xy 41.146058 -336.816421) (xy 41.204567 -336.879197)
			(xy 41.25694 -336.947177) (xy 41.302718 -337.019762) (xy 41.341498 -337.096314) (xy 41.372939 -337.176162)
			(xy 41.396765 -337.258603) (xy 41.412766 -337.342913) (xy 41.420801 -337.428351) (xy 41.421304 -337.471258)
			(xy 41.42123 -337.477608) (xy 45.781727 -337.477608) (xy 45.785749 -337.391888) (xy 45.79778 -337.30692)
			(xy 45.817716 -337.223453) (xy 45.845379 -337.142219) (xy 45.880528 -337.063933) (xy 45.922854 -336.989282)
			(xy 45.971983 -336.918923) (xy 46.027486 -336.853473) (xy 46.088873 -336.793509) (xy 46.155606 -336.739556)
			(xy 46.227098 -336.692089) (xy 46.30272 -336.651525) (xy 46.381809 -336.618221) (xy 46.463669 -336.592469)
			(xy 46.54758 -336.574496) (xy 46.632806 -336.56446) (xy 46.718598 -336.562448) (xy 46.8042 -336.568479)
			(xy 46.888862 -336.582499) (xy 46.971839 -336.604385) (xy 47.052402 -336.633946) (xy 47.129842 -336.67092)
			(xy 47.203481 -336.714984) (xy 47.272669 -336.76575) (xy 47.3368 -336.822771) (xy 47.395309 -336.885547)
			(xy 47.447682 -336.953527) (xy 47.49346 -337.026112) (xy 47.53224 -337.102664) (xy 47.563681 -337.182512)
			(xy 47.587507 -337.264953) (xy 47.603508 -337.349263) (xy 47.611543 -337.434701) (xy 47.612046 -337.477608)
			(xy 51.97983 -337.477608) (xy 51.980318 -337.435332) (xy 51.98812 -337.35114) (xy 52.003656 -337.268027)
			(xy 52.026795 -337.186703) (xy 52.057339 -337.10786) (xy 52.095027 -337.032172) (xy 52.139538 -336.960284)
			(xy 52.190492 -336.89281) (xy 52.247455 -336.830325) (xy 52.30994 -336.773362) (xy 52.377414 -336.722408)
			(xy 52.449302 -336.677897) (xy 52.52499 -336.640209) (xy 52.603833 -336.609665) (xy 52.685157 -336.586526)
			(xy 52.76827 -336.57099) (xy 52.852462 -336.563188) (xy 52.937014 -336.563188) (xy 53.021206 -336.57099)
			(xy 53.104319 -336.586526) (xy 53.185643 -336.609665) (xy 53.264486 -336.640209) (xy 53.340174 -336.677897)
			(xy 53.412062 -336.722408) (xy 53.479536 -336.773362) (xy 53.542021 -336.830325) (xy 53.598984 -336.89281)
			(xy 53.649938 -336.960284) (xy 53.694449 -337.032172) (xy 53.732137 -337.10786) (xy 53.762681 -337.186703)
			(xy 53.78582 -337.268027) (xy 53.801356 -337.35114) (xy 53.809158 -337.435332) (xy 53.809646 -337.477608)
			(xy 53.809142 -337.519569) (xy 53.801456 -337.603139) (xy 53.786148 -337.685654) (xy 53.763347 -337.766421)
			(xy 53.733246 -337.844759) (xy 53.696097 -337.920012) (xy 53.652212 -337.991547) (xy 53.60196 -338.058761)
			(xy 53.545764 -338.121091) (xy 53.484096 -338.178013) (xy 53.417474 -338.229047) (xy 53.346458 -338.273766)
			(xy 53.309266 -338.293202) (xy 53.296167 -338.300524) (xy 53.274558 -338.321321) (xy 53.259912 -338.347494)
			(xy 53.25349 -338.37679) (xy 53.255844 -338.406689) (xy 53.266772 -338.434619) (xy 53.285333 -338.458177)
			(xy 53.297328 -338.467192) (xy 53.308811 -338.475301) (xy 53.330676 -338.492974) (xy 53.341016 -338.502498)
			(xy 53.35255 -338.51257) (xy 53.380096 -338.525912) (xy 53.410358 -338.530497) (xy 53.44062 -338.525912)
			(xy 53.468166 -338.51257) (xy 53.4797 -338.502498) (xy 53.501027 -338.483228) (xy 53.54839 -338.450663)
			(xy 53.600101 -338.425572) (xy 53.654992 -338.408522) (xy 53.711819 -338.3999) (xy 53.769297 -338.3999)
			(xy 53.826124 -338.408522) (xy 53.881015 -338.425572) (xy 53.932726 -338.450663) (xy 53.980089 -338.483228)
			(xy 54.001416 -338.502498) (xy 54.01295 -338.51257) (xy 54.040496 -338.525912) (xy 54.070758 -338.530497)
			(xy 54.10102 -338.525912) (xy 54.128566 -338.51257) (xy 54.1401 -338.502498) (xy 54.161412 -338.48321)
			(xy 54.208777 -338.450644) (xy 54.260493 -338.425554) (xy 54.315387 -338.408508) (xy 54.372218 -338.399891)
			(xy 54.400958 -338.399374) (xy 54.428209 -338.399894) (xy 54.482157 -338.407645) (xy 54.534453 -338.422995)
			(xy 54.584031 -338.445631) (xy 54.629884 -338.475093) (xy 54.671077 -338.510781) (xy 54.706771 -338.551968)
			(xy 54.73624 -338.597816) (xy 54.758884 -338.647391) (xy 54.774242 -338.699684) (xy 54.782001 -338.753631)
			(xy 54.782466 -338.780882) (xy 54.781914 -338.80962) (xy 54.773295 -338.866445) (xy 54.756251 -338.921335)
			(xy 54.731166 -338.973047) (xy 54.698609 -339.020411) (xy 54.679342 -339.04174) (xy 54.669287 -339.053288)
			(xy 54.655941 -339.080829) (xy 54.651353 -339.111087) (xy 54.655934 -339.141346) (xy 54.669272 -339.16889)
			(xy 54.679342 -339.180424) (xy 54.698601 -339.201761) (xy 54.73117 -339.24912) (xy 54.756265 -339.300829)
			(xy 54.773318 -339.355718) (xy 54.781944 -339.412544) (xy 54.782466 -339.441282) (xy 54.782015 -339.468272)
			(xy 54.774408 -339.521712) (xy 54.759344 -339.573547) (xy 54.737124 -339.622741) (xy 54.70819 -339.668311)
			(xy 54.673122 -339.709347) (xy 54.65318 -339.72754) (xy 54.642465 -339.737466) (xy 54.626852 -339.762143)
			(xy 54.618868 -339.790231) (xy 54.619166 -339.819431) (xy 54.627722 -339.84735) (xy 54.643835 -339.871703)
			(xy 54.654704 -339.881464) (xy 54.675503 -339.899686) (xy 54.712176 -339.941068) (xy 54.742483 -339.987316)
			(xy 54.765788 -340.037458) (xy 54.781602 -340.090442) (xy 54.789593 -340.145155) (xy 54.790086 -340.172802)
			(xy 54.789559 -340.202244) (xy 54.780511 -340.26043) (xy 54.76263 -340.316534) (xy 54.736341 -340.369224)
			(xy 54.702268 -340.417249) (xy 54.682136 -340.43874) (xy 54.671747 -340.450216) (xy 54.657858 -340.477865)
			(xy 54.652857 -340.508401) (xy 54.657201 -340.539036) (xy 54.670494 -340.566978) (xy 54.680612 -340.578694)
			(xy 54.699625 -340.600011) (xy 54.731799 -340.647204) (xy 54.75658 -340.698665) (xy 54.773417 -340.753245)
			(xy 54.781931 -340.809723) (xy 54.782466 -340.838282) (xy 54.781998 -340.865652) (xy 54.774182 -340.919832)
			(xy 54.758694 -340.972335) (xy 54.735852 -341.022082) (xy 54.706127 -341.068049) (xy 54.688486 -341.08898)
			(xy 54.679268 -341.100321) (xy 54.66709 -341.126874) (xy 54.662914 -341.155786) (xy 54.667082 -341.1847)
			(xy 54.679253 -341.211256) (xy 54.688486 -341.222584) (xy 54.706109 -341.243531) (xy 54.735833 -341.289497)
			(xy 54.758679 -341.339241) (xy 54.774176 -341.391741) (xy 54.782006 -341.445917) (xy 54.782008 -341.500656)
			(xy 54.774182 -341.554833) (xy 54.758688 -341.607334) (xy 54.735846 -341.657079) (xy 54.706125 -341.703047)
			(xy 54.688486 -341.72398) (xy 54.679268 -341.735321) (xy 54.66709 -341.761874) (xy 54.662914 -341.790786)
			(xy 54.667082 -341.8197) (xy 54.679253 -341.846256) (xy 54.688486 -341.857584) (xy 54.706109 -341.878531)
			(xy 54.735833 -341.924497) (xy 54.758679 -341.974241) (xy 54.774176 -342.026741) (xy 54.782006 -342.080917)
			(xy 54.782008 -342.135656) (xy 54.774182 -342.189833) (xy 54.758688 -342.242334) (xy 54.735846 -342.292079)
			(xy 54.706125 -342.338047) (xy 54.688486 -342.35898) (xy 54.679268 -342.370321) (xy 54.66709 -342.396874)
			(xy 54.662914 -342.425786) (xy 54.667082 -342.4547) (xy 54.679253 -342.481256) (xy 54.688486 -342.492584)
			(xy 54.706129 -342.513513) (xy 54.735841 -342.559486) (xy 54.758676 -342.609235) (xy 54.774166 -342.661736)
			(xy 54.781993 -342.715913) (xy 54.782466 -342.743282) (xy 54.782028 -342.770536) (xy 54.774272 -342.82449)
			(xy 54.758916 -342.876791) (xy 54.736273 -342.926374) (xy 54.706803 -342.972229) (xy 54.671106 -343.013423)
			(xy 54.62991 -343.049117) (xy 54.584053 -343.078584) (xy 54.534469 -343.101225) (xy 54.482167 -343.116577)
			(xy 54.428212 -343.12433) (xy 54.400958 -343.12479) (xy 54.372218 -343.124294) (xy 54.315389 -343.115665)
			(xy 54.260498 -343.098609) (xy 54.208787 -343.073511) (xy 54.161426 -343.04094) (xy 54.1401 -343.021666)
			(xy 54.128566 -343.011594) (xy 54.10102 -342.998252) (xy 54.070758 -342.993667) (xy 54.040496 -342.998252)
			(xy 54.01295 -343.011594) (xy 54.001416 -343.021666) (xy 53.980089 -343.040936) (xy 53.932726 -343.073501)
			(xy 53.881015 -343.098592) (xy 53.826124 -343.115642) (xy 53.769297 -343.124264) (xy 53.711819 -343.124264)
			(xy 53.654992 -343.115642) (xy 53.600101 -343.098592) (xy 53.54839 -343.073501) (xy 53.501027 -343.040936)
			(xy 53.4797 -343.021666) (xy 53.468166 -343.011594) (xy 53.44062 -342.998252) (xy 53.410358 -342.993667)
			(xy 53.380096 -342.998252) (xy 53.35255 -343.011594) (xy 53.341016 -343.021666) (xy 53.319707 -343.040957)
			(xy 53.27234 -343.073521) (xy 53.220624 -343.098609) (xy 53.165729 -343.115655) (xy 53.108898 -343.124272)
			(xy 53.080158 -343.12479) (xy 53.052905 -343.124361) (xy 52.998954 -343.116599) (xy 52.946657 -343.101237)
			(xy 52.897079 -343.07859) (xy 52.851228 -343.049117) (xy 52.810037 -343.01342) (xy 52.774347 -342.972224)
			(xy 52.744881 -342.926369) (xy 52.722242 -342.876786) (xy 52.706889 -342.824487) (xy 52.699135 -342.770535)
			(xy 52.69865 -342.743282) (xy 52.699093 -342.715911) (xy 52.706915 -342.66173) (xy 52.722408 -342.609226)
			(xy 52.745256 -342.55948) (xy 52.774986 -342.513514) (xy 52.79263 -342.492584) (xy 52.801882 -342.481269)
			(xy 52.814053 -342.454706) (xy 52.818221 -342.425786) (xy 52.814046 -342.396868) (xy 52.801867 -342.370308)
			(xy 52.79263 -342.35898) (xy 52.774972 -342.338062) (xy 52.745247 -342.292091) (xy 52.722403 -342.242343)
			(xy 52.706908 -342.189839) (xy 52.699081 -342.135658) (xy 52.699083 -342.080915) (xy 52.706914 -342.026735)
			(xy 52.722412 -341.974232) (xy 52.74526 -341.924485) (xy 52.774988 -341.878517) (xy 52.79263 -341.857584)
			(xy 52.801882 -341.846269) (xy 52.814053 -341.819706) (xy 52.818221 -341.790786) (xy 52.814046 -341.761868)
			(xy 52.801867 -341.735308) (xy 52.79263 -341.72398) (xy 52.774972 -341.703062) (xy 52.745247 -341.657091)
			(xy 52.722403 -341.607343) (xy 52.706908 -341.554839) (xy 52.699081 -341.500658) (xy 52.699083 -341.445915)
			(xy 52.706914 -341.391735) (xy 52.722412 -341.339232) (xy 52.74526 -341.289485) (xy 52.774988 -341.243517)
			(xy 52.79263 -341.222584) (xy 52.801882 -341.211269) (xy 52.814053 -341.184706) (xy 52.818221 -341.155786)
			(xy 52.814046 -341.126868) (xy 52.801867 -341.100308) (xy 52.79263 -341.08898) (xy 52.77502 -341.068025)
			(xy 52.745302 -341.022059) (xy 52.72246 -340.972317) (xy 52.706963 -340.919822) (xy 52.699128 -340.86565)
			(xy 52.69865 -340.838282) (xy 52.69922 -340.808841) (xy 52.708256 -340.750657) (xy 52.726126 -340.694554)
			(xy 52.752406 -340.641862) (xy 52.786471 -340.593836) (xy 52.8066 -340.572344) (xy 52.817009 -340.560883)
			(xy 52.830906 -340.53323) (xy 52.835907 -340.502688) (xy 52.831556 -340.472046) (xy 52.81825 -340.444104)
			(xy 52.808124 -340.43239) (xy 52.789093 -340.411088) (xy 52.756924 -340.36389) (xy 52.732147 -340.312425)
			(xy 52.715315 -340.257843) (xy 52.706803 -340.201361) (xy 52.70627 -340.172802) (xy 52.706698 -340.145811)
			(xy 52.714308 -340.092369) (xy 52.729376 -340.040533) (xy 52.7516 -339.99134) (xy 52.780538 -339.94577)
			(xy 52.815611 -339.904735) (xy 52.835556 -339.886544) (xy 52.846182 -339.876532) (xy 52.861793 -339.851879)
			(xy 52.869785 -339.823814) (xy 52.869503 -339.794635) (xy 52.86097 -339.766729) (xy 52.844886 -339.742382)
			(xy 52.834032 -339.73262) (xy 52.813233 -339.714399) (xy 52.776559 -339.673017) (xy 52.74625 -339.62677)
			(xy 52.722945 -339.576627) (xy 52.707131 -339.523643) (xy 52.699142 -339.468929) (xy 52.69865 -339.441282)
			(xy 52.699176 -339.412543) (xy 52.7078 -339.355717) (xy 52.72485 -339.300827) (xy 52.749941 -339.249115)
			(xy 52.782504 -339.201752) (xy 52.801774 -339.180424) (xy 52.811863 -339.168904) (xy 52.825203 -339.141353)
			(xy 52.829784 -339.111087) (xy 52.825195 -339.080822) (xy 52.811848 -339.053274) (xy 52.801774 -339.04174)
			(xy 52.782501 -339.020415) (xy 52.749933 -338.973053) (xy 52.724841 -338.921341) (xy 52.707791 -338.86645)
			(xy 52.69917 -338.809621) (xy 52.69865 -338.780882) (xy 52.699093 -338.754848) (xy 52.706182 -338.703265)
			(xy 52.720212 -338.653124) (xy 52.740924 -338.605353) (xy 52.767933 -338.560838) (xy 52.783994 -338.540344)
			(xy 52.792995 -338.528305) (xy 52.804369 -338.500505) (xy 52.807153 -338.470597) (xy 52.801105 -338.441174)
			(xy 52.78675 -338.414789) (xy 52.765333 -338.393729) (xy 52.73871 -338.37982) (xy 52.72405 -338.376514)
			(xy 52.682679 -338.368223) (xy 52.601583 -338.344902) (xy 52.522979 -338.314214) (xy 52.447534 -338.276419)
			(xy 52.375889 -338.231838) (xy 52.308653 -338.180851) (xy 52.246397 -338.12389) (xy 52.189649 -338.061439)
			(xy 52.138892 -337.994029) (xy 52.094557 -337.922232) (xy 52.05702 -337.846659) (xy 52.0266 -337.76795)
			(xy 52.003557 -337.686775) (xy 51.988084 -337.603823) (xy 51.980315 -337.519799) (xy 51.97983 -337.477608)
			(xy 47.612046 -337.477608) (xy 47.611543 -337.520515) (xy 47.603508 -337.605953) (xy 47.587507 -337.690263)
			(xy 47.563681 -337.772704) (xy 47.53224 -337.852552) (xy 47.49346 -337.929104) (xy 47.447682 -338.001689)
			(xy 47.395309 -338.069669) (xy 47.3368 -338.132445) (xy 47.272669 -338.189466) (xy 47.203481 -338.240232)
			(xy 47.129842 -338.284296) (xy 47.052402 -338.32127) (xy 46.971839 -338.350831) (xy 46.888862 -338.372717)
			(xy 46.8042 -338.386737) (xy 46.718598 -338.392768) (xy 46.632806 -338.390756) (xy 46.54758 -338.38072)
			(xy 46.463669 -338.362747) (xy 46.381809 -338.336995) (xy 46.30272 -338.303691) (xy 46.227098 -338.263127)
			(xy 46.155606 -338.21566) (xy 46.088873 -338.161707) (xy 46.027486 -338.101743) (xy 45.971983 -338.036293)
			(xy 45.922854 -337.965934) (xy 45.880528 -337.891283) (xy 45.845379 -337.812997) (xy 45.817716 -337.731763)
			(xy 45.79778 -337.648296) (xy 45.785749 -337.563328) (xy 45.781727 -337.477608) (xy 41.42123 -337.477608)
			(xy 41.420801 -337.514165) (xy 41.412766 -337.599603) (xy 41.396765 -337.683913) (xy 41.372939 -337.766354)
			(xy 41.341498 -337.846202) (xy 41.302718 -337.922754) (xy 41.25694 -337.995339) (xy 41.204567 -338.063319)
			(xy 41.146058 -338.126095) (xy 41.081927 -338.183116) (xy 41.012739 -338.233882) (xy 40.9391 -338.277946)
			(xy 40.86166 -338.31492) (xy 40.781097 -338.344481) (xy 40.69812 -338.366367) (xy 40.613458 -338.380387)
			(xy 40.527856 -338.386418) (xy 40.442064 -338.384406) (xy 40.356838 -338.37437) (xy 40.272927 -338.356397)
			(xy 40.191067 -338.330645) (xy 40.111978 -338.297341) (xy 40.036356 -338.256777) (xy 39.964864 -338.20931)
			(xy 39.898131 -338.155357) (xy 39.836744 -338.095393) (xy 39.781241 -338.029943) (xy 39.732112 -337.959584)
			(xy 39.689786 -337.884933) (xy 39.654637 -337.806647) (xy 39.626974 -337.725413) (xy 39.607038 -337.641946)
			(xy 39.595007 -337.556978) (xy 39.590985 -337.471258) (xy 34.902394 -337.471258) (xy 34.902394 -339.102954)
			(xy 34.561526 -339.443822) (xy 38.02761 -339.443822) (xy 38.028087 -339.416452) (xy 38.035901 -339.362273)
			(xy 38.051388 -339.30977) (xy 38.074227 -339.260023) (xy 38.10395 -339.214056) (xy 38.12159 -339.193124)
			(xy 38.130806 -339.181781) (xy 38.142988 -339.155229) (xy 38.147165 -339.126317) (xy 38.142997 -339.097403)
			(xy 38.130825 -339.070847) (xy 38.12159 -339.05952) (xy 38.103945 -339.038593) (xy 38.074235 -338.992618)
			(xy 38.0514 -338.94287) (xy 38.03591 -338.890368) (xy 38.028083 -338.836191) (xy 38.02761 -338.808822)
			(xy 38.028076 -338.781569) (xy 38.03583 -338.727617) (xy 38.051184 -338.675318) (xy 38.073826 -338.625737)
			(xy 38.103293 -338.579883) (xy 38.138987 -338.538689) (xy 38.18018 -338.502995) (xy 38.226033 -338.473528)
			(xy 38.275614 -338.450886) (xy 38.327913 -338.435531) (xy 38.381865 -338.427776) (xy 38.409118 -338.427314)
			(xy 38.437856 -338.42785) (xy 38.494682 -338.436473) (xy 38.549572 -338.453521) (xy 38.601284 -338.47861)
			(xy 38.648648 -338.51117) (xy 38.669976 -338.530438) (xy 38.68151 -338.54051) (xy 38.709056 -338.553852)
			(xy 38.739318 -338.558437) (xy 38.76958 -338.553852) (xy 38.797126 -338.54051) (xy 38.80866 -338.530438)
			(xy 38.829987 -338.511168) (xy 38.87735 -338.478603) (xy 38.929061 -338.453512) (xy 38.983952 -338.436462)
			(xy 39.040779 -338.42784) (xy 39.098257 -338.42784) (xy 39.155084 -338.436462) (xy 39.209975 -338.453512)
			(xy 39.261686 -338.478603) (xy 39.309049 -338.511168) (xy 39.330376 -338.530438) (xy 39.341283 -338.539936)
			(xy 39.367057 -338.553021) (xy 39.395469 -338.558337) (xy 39.42423 -338.555455) (xy 39.437818 -338.550504)
			(xy 39.456048 -338.52959) (xy 39.497498 -338.492717) (xy 39.543854 -338.462239) (xy 39.594137 -338.4388)
			(xy 39.647286 -338.422894) (xy 39.702179 -338.414858) (xy 39.729918 -338.41436) (xy 39.75719 -338.414785)
			(xy 39.81118 -338.42255) (xy 39.863515 -338.43792) (xy 39.913129 -338.460581) (xy 39.959014 -338.490072)
			(xy 40.000234 -338.525794) (xy 40.035952 -338.567018) (xy 40.065438 -338.612906) (xy 40.088094 -338.662523)
			(xy 40.103459 -338.714859) (xy 40.111218 -338.768849) (xy 40.11168 -338.796122) (xy 40.111426 -338.810092)
			(xy 40.110907 -338.837335) (xy 40.102977 -338.891244) (xy 40.087449 -338.943474) (xy 40.06464 -338.99296)
			(xy 40.035015 -339.038692) (xy 40.017446 -339.05952) (xy 40.009031 -339.069826) (xy 39.997353 -339.093722)
			(xy 39.992231 -339.119822) (xy 39.994012 -339.146359) (xy 39.997888 -339.159088) (xy 40.019063 -339.180757)
			(xy 40.054942 -339.229573) (xy 40.082668 -339.283439) (xy 40.101546 -339.341006) (xy 40.111103 -339.40083)
			(xy 40.11168 -339.431122) (xy 40.111426 -339.445092) (xy 40.110952 -339.470505) (xy 40.104043 -339.520863)
			(xy 40.090504 -339.569857) (xy 40.070578 -339.616618) (xy 40.044616 -339.660317) (xy 40.013079 -339.70018)
			(xy 39.995094 -339.718142) (xy 39.985339 -339.728135) (xy 39.971307 -339.752272) (xy 39.964343 -339.779309)
			(xy 39.964969 -339.807221) (xy 39.973137 -339.833919) (xy 39.988236 -339.857403) (xy 39.998396 -339.866986)
			(xy 40.018206 -339.885169) (xy 40.052996 -339.926171) (xy 40.081692 -339.971647) (xy 40.103726 -340.020698)
			(xy 40.118662 -340.072355) (xy 40.126207 -340.125596) (xy 40.126666 -340.152482) (xy 40.126079 -340.182605)
			(xy 40.116601 -340.2421) (xy 40.097894 -340.299368) (xy 40.070422 -340.352985) (xy 40.034867 -340.40162)
			(xy 40.01389 -340.423246) (xy 40.004689 -340.432983) (xy 39.99124 -340.45614) (xy 39.984274 -340.481998)
			(xy 39.984271 -340.508777) (xy 39.99123 -340.534636) (xy 40.004673 -340.557797) (xy 40.01389 -340.567518)
			(xy 40.034854 -340.589158) (xy 40.070425 -340.637782) (xy 40.097908 -340.691395) (xy 40.11662 -340.748662)
			(xy 40.126095 -340.808159) (xy 40.126666 -340.838282) (xy 40.126198 -340.865652) (xy 40.118382 -340.919832)
			(xy 40.102894 -340.972335) (xy 40.080052 -341.022082) (xy 40.050327 -341.068049) (xy 40.032686 -341.08898)
			(xy 40.023468 -341.100321) (xy 40.01129 -341.126874) (xy 40.007114 -341.155786) (xy 40.011282 -341.1847)
			(xy 40.023453 -341.211256) (xy 40.032686 -341.222584) (xy 40.050309 -341.243531) (xy 40.080033 -341.289497)
			(xy 40.102879 -341.339241) (xy 40.118376 -341.391741) (xy 40.126206 -341.445917) (xy 40.126208 -341.500656)
			(xy 40.118382 -341.554833) (xy 40.102888 -341.607334) (xy 40.080046 -341.657079) (xy 40.050325 -341.703047)
			(xy 40.032686 -341.72398) (xy 40.023468 -341.735321) (xy 40.01129 -341.761874) (xy 40.007114 -341.790786)
			(xy 40.011282 -341.8197) (xy 40.023453 -341.846256) (xy 40.032686 -341.857584) (xy 40.050309 -341.878531)
			(xy 40.080033 -341.924497) (xy 40.102879 -341.974241) (xy 40.118376 -342.026741) (xy 40.126206 -342.080917)
			(xy 40.126208 -342.135656) (xy 40.118382 -342.189833) (xy 40.102888 -342.242334) (xy 40.080046 -342.292079)
			(xy 40.050325 -342.338047) (xy 40.032686 -342.35898) (xy 40.023468 -342.370321) (xy 40.01129 -342.396874)
			(xy 40.007114 -342.425786) (xy 40.011282 -342.4547) (xy 40.023453 -342.481256) (xy 40.032686 -342.492584)
			(xy 40.050329 -342.513513) (xy 40.080041 -342.559486) (xy 40.102876 -342.609235) (xy 40.118366 -342.661736)
			(xy 40.126193 -342.715913) (xy 40.126666 -342.743282) (xy 43.02125 -342.743282) (xy 43.021693 -342.715911)
			(xy 43.029515 -342.66173) (xy 43.045008 -342.609226) (xy 43.067856 -342.55948) (xy 43.097586 -342.513514)
			(xy 43.11523 -342.492584) (xy 43.124482 -342.481269) (xy 43.136653 -342.454706) (xy 43.140821 -342.425786)
			(xy 43.136646 -342.396868) (xy 43.124467 -342.370308) (xy 43.11523 -342.35898) (xy 43.097572 -342.338062)
			(xy 43.067847 -342.292091) (xy 43.045003 -342.242343) (xy 43.029508 -342.189839) (xy 43.021681 -342.135658)
			(xy 43.021683 -342.080915) (xy 43.029514 -342.026735) (xy 43.045012 -341.974232) (xy 43.06786 -341.924485)
			(xy 43.097588 -341.878517) (xy 43.11523 -341.857584) (xy 43.124482 -341.846269) (xy 43.136653 -341.819706)
			(xy 43.140821 -341.790786) (xy 43.136646 -341.761868) (xy 43.124467 -341.735308) (xy 43.11523 -341.72398)
			(xy 43.097572 -341.703062) (xy 43.067847 -341.657091) (xy 43.045003 -341.607343) (xy 43.029508 -341.554839)
			(xy 43.021681 -341.500658) (xy 43.021683 -341.445915) (xy 43.029514 -341.391735) (xy 43.045012 -341.339232)
			(xy 43.06786 -341.289485) (xy 43.097588 -341.243517) (xy 43.11523 -341.222584) (xy 43.124482 -341.211269)
			(xy 43.136653 -341.184706) (xy 43.140821 -341.155786) (xy 43.136646 -341.126868) (xy 43.124467 -341.100308)
			(xy 43.11523 -341.08898) (xy 43.09762 -341.068025) (xy 43.067902 -341.022059) (xy 43.04506 -340.972317)
			(xy 43.029563 -340.919822) (xy 43.021728 -340.86565) (xy 43.02125 -340.838282) (xy 43.02125 -340.838028)
			(xy 43.021846 -340.808195) (xy 43.031143 -340.749256) (xy 43.049499 -340.692483) (xy 43.076467 -340.639258)
			(xy 43.11139 -340.590879) (xy 43.131994 -340.569296) (xy 43.142625 -340.557741) (xy 43.157002 -340.529852)
			(xy 43.162226 -340.498914) (xy 43.157801 -340.467851) (xy 43.144146 -340.439601) (xy 43.133772 -340.427818)
			(xy 43.114184 -340.406442) (xy 43.081067 -340.358854) (xy 43.055538 -340.3068) (xy 43.038186 -340.25148)
			(xy 43.02941 -340.194171) (xy 43.02887 -340.165182) (xy 43.029319 -340.138581) (xy 43.036697 -340.085893)
			(xy 43.051322 -340.034741) (xy 43.07291 -339.986116) (xy 43.101043 -339.940961) (xy 43.135174 -339.900151)
			(xy 43.1546 -339.881972) (xy 43.164941 -339.872005) (xy 43.180033 -339.847581) (xy 43.187736 -339.819924)
			(xy 43.187444 -339.791215) (xy 43.179179 -339.76372) (xy 43.163593 -339.739609) (xy 43.153076 -339.729826)
			(xy 43.132762 -339.711618) (xy 43.097025 -339.670401) (xy 43.067521 -339.624515) (xy 43.044852 -339.574896)
			(xy 43.029478 -339.522555) (xy 43.021713 -339.468558) (xy 43.02125 -339.441282) (xy 43.021776 -339.412543)
			(xy 43.0304 -339.355717) (xy 43.04745 -339.300827) (xy 43.072541 -339.249115) (xy 43.105104 -339.201752)
			(xy 43.124374 -339.180424) (xy 43.134463 -339.168904) (xy 43.147803 -339.141353) (xy 43.152384 -339.111087)
			(xy 43.147795 -339.080822) (xy 43.134448 -339.053274) (xy 43.124374 -339.04174) (xy 43.105101 -339.020415)
			(xy 43.072533 -338.973053) (xy 43.047441 -338.921341) (xy 43.030391 -338.86645) (xy 43.02177 -338.809621)
			(xy 43.02125 -338.780882) (xy 43.021761 -338.753632) (xy 43.029519 -338.699688) (xy 43.044874 -338.647396)
			(xy 43.067514 -338.597821) (xy 43.096979 -338.551973) (xy 43.132667 -338.510784) (xy 43.173854 -338.475093)
			(xy 43.2197 -338.445626) (xy 43.269273 -338.422982) (xy 43.321564 -338.407624) (xy 43.375508 -338.399863)
			(xy 43.402758 -338.399374) (xy 43.431498 -338.399869) (xy 43.488326 -338.4085) (xy 43.543217 -338.425557)
			(xy 43.594928 -338.450655) (xy 43.64229 -338.483225) (xy 43.663616 -338.502498) (xy 43.67515 -338.51257)
			(xy 43.702696 -338.525912) (xy 43.732958 -338.530497) (xy 43.76322 -338.525912) (xy 43.790766 -338.51257)
			(xy 43.8023 -338.502498) (xy 43.823627 -338.483228) (xy 43.87099 -338.450663) (xy 43.922701 -338.425572)
			(xy 43.977592 -338.408522) (xy 44.034419 -338.3999) (xy 44.091897 -338.3999) (xy 44.148724 -338.408522)
			(xy 44.203615 -338.425572) (xy 44.255326 -338.450663) (xy 44.302689 -338.483228) (xy 44.324016 -338.502498)
			(xy 44.33555 -338.51257) (xy 44.363096 -338.525912) (xy 44.393358 -338.530497) (xy 44.42362 -338.525912)
			(xy 44.451166 -338.51257) (xy 44.4627 -338.502498) (xy 44.484012 -338.48321) (xy 44.531377 -338.450644)
			(xy 44.583093 -338.425554) (xy 44.637987 -338.408508) (xy 44.694818 -338.399891) (xy 44.723558 -338.399374)
			(xy 44.750809 -338.399894) (xy 44.804757 -338.407645) (xy 44.857053 -338.422995) (xy 44.906631 -338.445631)
			(xy 44.952484 -338.475093) (xy 44.993677 -338.510781) (xy 45.029371 -338.551968) (xy 45.05884 -338.597816)
			(xy 45.081484 -338.647391) (xy 45.096842 -338.699684) (xy 45.104601 -338.753631) (xy 45.105066 -338.780882)
			(xy 45.104514 -338.80962) (xy 45.095895 -338.866445) (xy 45.078851 -338.921335) (xy 45.053766 -338.973047)
			(xy 45.021209 -339.020411) (xy 45.001942 -339.04174) (xy 44.991887 -339.053288) (xy 44.978541 -339.080829)
			(xy 44.973953 -339.111087) (xy 44.978534 -339.141346) (xy 44.991872 -339.16889) (xy 45.001942 -339.180424)
			(xy 45.021201 -339.201761) (xy 45.05377 -339.24912) (xy 45.078865 -339.300829) (xy 45.095918 -339.355718)
			(xy 45.104544 -339.412544) (xy 45.105066 -339.441282) (xy 45.104581 -339.467882) (xy 45.097208 -339.520567)
			(xy 45.08259 -339.571718) (xy 45.061009 -339.620343) (xy 45.032883 -339.665499) (xy 44.998758 -339.706312)
			(xy 44.979336 -339.724492) (xy 44.969028 -339.734492) (xy 44.953929 -339.758905) (xy 44.946218 -339.786555)
			(xy 44.946504 -339.815258) (xy 44.954764 -339.842749) (xy 44.970345 -339.866857) (xy 44.98086 -339.876638)
			(xy 45.001164 -339.894857) (xy 45.0369 -339.936073) (xy 45.066404 -339.981956) (xy 45.089075 -340.031573)
			(xy 45.104452 -340.083912) (xy 45.112221 -340.137907) (xy 45.112686 -340.165182) (xy 45.112686 -340.165436)
			(xy 45.112546 -340.172802) (xy 47.71263 -340.172802) (xy 47.713127 -340.145156) (xy 47.721126 -340.090444)
			(xy 47.736942 -340.037461) (xy 47.760243 -339.987318) (xy 47.790542 -339.941065) (xy 47.827203 -339.899672)
			(xy 47.848012 -339.881464) (xy 47.858786 -339.871635) (xy 47.874807 -339.847284) (xy 47.883311 -339.819404)
			(xy 47.883608 -339.790257) (xy 47.875673 -339.762209) (xy 47.860151 -339.737538) (xy 47.849536 -339.72754)
			(xy 47.829588 -339.709355) (xy 47.794526 -339.668314) (xy 47.765598 -339.622741) (xy 47.743382 -339.573546)
			(xy 47.728321 -339.521712) (xy 47.720716 -339.468271) (xy 47.72025 -339.441282) (xy 47.720776 -339.412543)
			(xy 47.7294 -339.355717) (xy 47.74645 -339.300827) (xy 47.771541 -339.249115) (xy 47.804104 -339.201752)
			(xy 47.823374 -339.180424) (xy 47.833463 -339.168904) (xy 47.846803 -339.141353) (xy 47.851384 -339.111087)
			(xy 47.846795 -339.080822) (xy 47.833448 -339.053274) (xy 47.823374 -339.04174) (xy 47.804101 -339.020415)
			(xy 47.771533 -338.973053) (xy 47.746441 -338.921341) (xy 47.729391 -338.86645) (xy 47.72077 -338.809621)
			(xy 47.72025 -338.780882) (xy 47.720761 -338.753632) (xy 47.728519 -338.699688) (xy 47.743874 -338.647396)
			(xy 47.766514 -338.597821) (xy 47.795979 -338.551973) (xy 47.831667 -338.510784) (xy 47.872854 -338.475093)
			(xy 47.9187 -338.445626) (xy 47.968273 -338.422982) (xy 48.020564 -338.407624) (xy 48.074508 -338.399863)
			(xy 48.101758 -338.399374) (xy 48.130498 -338.399869) (xy 48.187326 -338.4085) (xy 48.242217 -338.425557)
			(xy 48.293928 -338.450655) (xy 48.34129 -338.483225) (xy 48.362616 -338.502498) (xy 48.37415 -338.51257)
			(xy 48.401696 -338.525912) (xy 48.431958 -338.530497) (xy 48.46222 -338.525912) (xy 48.489766 -338.51257)
			(xy 48.5013 -338.502498) (xy 48.522627 -338.483228) (xy 48.56999 -338.450663) (xy 48.621701 -338.425572)
			(xy 48.676592 -338.408522) (xy 48.733419 -338.3999) (xy 48.790897 -338.3999) (xy 48.847724 -338.408522)
			(xy 48.902615 -338.425572) (xy 48.954326 -338.450663) (xy 49.001689 -338.483228) (xy 49.023016 -338.502498)
			(xy 49.03455 -338.51257) (xy 49.062096 -338.525912) (xy 49.092358 -338.530497) (xy 49.12262 -338.525912)
			(xy 49.150166 -338.51257) (xy 49.1617 -338.502498) (xy 49.183012 -338.48321) (xy 49.230377 -338.450644)
			(xy 49.282093 -338.425554) (xy 49.336987 -338.408508) (xy 49.393818 -338.399891) (xy 49.422558 -338.399374)
			(xy 49.449809 -338.399894) (xy 49.503757 -338.407645) (xy 49.556053 -338.422995) (xy 49.605631 -338.445631)
			(xy 49.651484 -338.475093) (xy 49.692677 -338.510781) (xy 49.728371 -338.551968) (xy 49.75784 -338.597816)
			(xy 49.780484 -338.647391) (xy 49.795842 -338.699684) (xy 49.803601 -338.753631) (xy 49.804066 -338.780882)
			(xy 49.803514 -338.80962) (xy 49.794895 -338.866445) (xy 49.777851 -338.921335) (xy 49.752766 -338.973047)
			(xy 49.720209 -339.020411) (xy 49.700942 -339.04174) (xy 49.690887 -339.053288) (xy 49.677541 -339.080829)
			(xy 49.672953 -339.111087) (xy 49.677534 -339.141346) (xy 49.690872 -339.16889) (xy 49.700942 -339.180424)
			(xy 49.720201 -339.201761) (xy 49.75277 -339.24912) (xy 49.777865 -339.300829) (xy 49.794918 -339.355718)
			(xy 49.803544 -339.412544) (xy 49.804066 -339.441282) (xy 49.80356 -339.468928) (xy 49.795563 -339.523639)
			(xy 49.779749 -339.576622) (xy 49.756449 -339.626766) (xy 49.726152 -339.673019) (xy 49.689493 -339.714412)
			(xy 49.668684 -339.73262) (xy 49.657819 -339.742361) (xy 49.641786 -339.766732) (xy 49.633283 -339.794638)
			(xy 49.633002 -339.823809) (xy 49.640965 -339.851874) (xy 49.656525 -339.87655) (xy 49.66716 -339.886544)
			(xy 49.687099 -339.904738) (xy 49.722162 -339.945777) (xy 49.751091 -339.991348) (xy 49.773309 -340.040541)
			(xy 49.788372 -340.092374) (xy 49.795979 -340.145813) (xy 49.796446 -340.172802) (xy 49.795882 -340.20136)
			(xy 49.787374 -340.257838) (xy 49.770547 -340.312419) (xy 49.745777 -340.363885) (xy 49.713618 -340.411086)
			(xy 49.694592 -340.43239) (xy 49.684469 -340.444114) (xy 49.671114 -340.472041) (xy 49.666746 -340.502687)
			(xy 49.671766 -340.533234) (xy 49.685713 -340.56087) (xy 49.696116 -340.572344) (xy 49.71624 -340.593841)
			(xy 49.750307 -340.641867) (xy 49.776592 -340.694557) (xy 49.794471 -340.750658) (xy 49.803519 -340.808841)
			(xy 49.804066 -340.838282) (xy 49.803598 -340.865652) (xy 49.795782 -340.919832) (xy 49.780294 -340.972335)
			(xy 49.757452 -341.022082) (xy 49.727727 -341.068049) (xy 49.710086 -341.08898) (xy 49.700868 -341.100321)
			(xy 49.68869 -341.126874) (xy 49.684514 -341.155786) (xy 49.688682 -341.1847) (xy 49.700853 -341.211256)
			(xy 49.710086 -341.222584) (xy 49.727709 -341.243531) (xy 49.757433 -341.289497) (xy 49.780279 -341.339241)
			(xy 49.795776 -341.391741) (xy 49.803606 -341.445917) (xy 49.803608 -341.500656) (xy 49.795782 -341.554833)
			(xy 49.780288 -341.607334) (xy 49.757446 -341.657079) (xy 49.727725 -341.703047) (xy 49.710086 -341.72398)
			(xy 49.700868 -341.735321) (xy 49.68869 -341.761874) (xy 49.684514 -341.790786) (xy 49.688682 -341.8197)
			(xy 49.700853 -341.846256) (xy 49.710086 -341.857584) (xy 49.727709 -341.878531) (xy 49.757433 -341.924497)
			(xy 49.780279 -341.974241) (xy 49.795776 -342.026741) (xy 49.803606 -342.080917) (xy 49.803608 -342.135656)
			(xy 49.795782 -342.189833) (xy 49.780288 -342.242334) (xy 49.757446 -342.292079) (xy 49.727725 -342.338047)
			(xy 49.710086 -342.35898) (xy 49.700868 -342.370321) (xy 49.68869 -342.396874) (xy 49.684514 -342.425786)
			(xy 49.688682 -342.4547) (xy 49.700853 -342.481256) (xy 49.710086 -342.492584) (xy 49.727729 -342.513513)
			(xy 49.757441 -342.559486) (xy 49.780276 -342.609235) (xy 49.795766 -342.661736) (xy 49.803593 -342.715913)
			(xy 49.804066 -342.743282) (xy 49.803628 -342.770536) (xy 49.795872 -342.82449) (xy 49.780516 -342.876791)
			(xy 49.757873 -342.926374) (xy 49.728403 -342.972229) (xy 49.692706 -343.013423) (xy 49.65151 -343.049117)
			(xy 49.605653 -343.078584) (xy 49.556069 -343.101225) (xy 49.503767 -343.116577) (xy 49.449812 -343.12433)
			(xy 49.422558 -343.12479) (xy 49.393818 -343.124294) (xy 49.336989 -343.115665) (xy 49.282098 -343.098609)
			(xy 49.230387 -343.073511) (xy 49.183026 -343.04094) (xy 49.1617 -343.021666) (xy 49.150166 -343.011594)
			(xy 49.12262 -342.998252) (xy 49.092358 -342.993667) (xy 49.062096 -342.998252) (xy 49.03455 -343.011594)
			(xy 49.023016 -343.021666) (xy 49.001689 -343.040936) (xy 48.954326 -343.073501) (xy 48.902615 -343.098592)
			(xy 48.847724 -343.115642) (xy 48.790897 -343.124264) (xy 48.733419 -343.124264) (xy 48.676592 -343.115642)
			(xy 48.621701 -343.098592) (xy 48.56999 -343.073501) (xy 48.522627 -343.040936) (xy 48.5013 -343.021666)
			(xy 48.489766 -343.011594) (xy 48.46222 -342.998252) (xy 48.431958 -342.993667) (xy 48.401696 -342.998252)
			(xy 48.37415 -343.011594) (xy 48.362616 -343.021666) (xy 48.341307 -343.040957) (xy 48.29394 -343.073521)
			(xy 48.242224 -343.098609) (xy 48.187329 -343.115655) (xy 48.130498 -343.124272) (xy 48.101758 -343.12479)
			(xy 48.074505 -343.124361) (xy 48.020554 -343.116599) (xy 47.968257 -343.101237) (xy 47.918679 -343.07859)
			(xy 47.872828 -343.049117) (xy 47.831637 -343.01342) (xy 47.795947 -342.972224) (xy 47.766481 -342.926369)
			(xy 47.743842 -342.876786) (xy 47.728489 -342.824487) (xy 47.720735 -342.770535) (xy 47.72025 -342.743282)
			(xy 47.720693 -342.715911) (xy 47.728515 -342.66173) (xy 47.744008 -342.609226) (xy 47.766856 -342.55948)
			(xy 47.796586 -342.513514) (xy 47.81423 -342.492584) (xy 47.823482 -342.481269) (xy 47.835653 -342.454706)
			(xy 47.839821 -342.425786) (xy 47.835646 -342.396868) (xy 47.823467 -342.370308) (xy 47.81423 -342.35898)
			(xy 47.796572 -342.338062) (xy 47.766847 -342.292091) (xy 47.744003 -342.242343) (xy 47.728508 -342.189839)
			(xy 47.720681 -342.135658) (xy 47.720683 -342.080915) (xy 47.728514 -342.026735) (xy 47.744012 -341.974232)
			(xy 47.76686 -341.924485) (xy 47.796588 -341.878517) (xy 47.81423 -341.857584) (xy 47.823482 -341.846269)
			(xy 47.835653 -341.819706) (xy 47.839821 -341.790786) (xy 47.835646 -341.761868) (xy 47.823467 -341.735308)
			(xy 47.81423 -341.72398) (xy 47.796572 -341.703062) (xy 47.766847 -341.657091) (xy 47.744003 -341.607343)
			(xy 47.728508 -341.554839) (xy 47.720681 -341.500658) (xy 47.720683 -341.445915) (xy 47.728514 -341.391735)
			(xy 47.744012 -341.339232) (xy 47.76686 -341.289485) (xy 47.796588 -341.243517) (xy 47.81423 -341.222584)
			(xy 47.823482 -341.211269) (xy 47.835653 -341.184706) (xy 47.839821 -341.155786) (xy 47.835646 -341.126868)
			(xy 47.823467 -341.100308) (xy 47.81423 -341.08898) (xy 47.79662 -341.068025) (xy 47.766902 -341.022059)
			(xy 47.74406 -340.972317) (xy 47.728563 -340.919822) (xy 47.720728 -340.86565) (xy 47.72025 -340.838282)
			(xy 47.720805 -340.809724) (xy 47.729316 -340.753245) (xy 47.746145 -340.698664) (xy 47.770916 -340.647199)
			(xy 47.803078 -340.599998) (xy 47.822104 -340.578694) (xy 47.832243 -340.566983) (xy 47.845597 -340.539051)
			(xy 47.849963 -340.508401) (xy 47.844938 -340.477852) (xy 47.830985 -340.450214) (xy 47.82058 -340.43874)
			(xy 47.800448 -340.417251) (xy 47.766382 -340.369222) (xy 47.740099 -340.316531) (xy 47.722222 -340.260427)
			(xy 47.713176 -340.202243) (xy 47.71263 -340.172802) (xy 45.112546 -340.172802) (xy 45.11212 -340.19527)
			(xy 45.102814 -340.254209) (xy 45.08445 -340.310983) (xy 45.057476 -340.364207) (xy 45.022548 -340.412585)
			(xy 45.001942 -340.434168) (xy 44.991253 -340.445671) (xy 44.976891 -340.47358) (xy 44.971683 -340.504532)
			(xy 44.976121 -340.535604) (xy 44.989785 -340.56386) (xy 45.000164 -340.575646) (xy 45.019724 -340.597046)
			(xy 45.052847 -340.644627) (xy 45.078382 -340.696675) (xy 45.095741 -340.751989) (xy 45.104523 -340.809295)
			(xy 45.105066 -340.838282) (xy 45.104598 -340.865652) (xy 45.096782 -340.919832) (xy 45.081294 -340.972335)
			(xy 45.058452 -341.022082) (xy 45.028727 -341.068049) (xy 45.011086 -341.08898) (xy 45.001868 -341.100321)
			(xy 44.98969 -341.126874) (xy 44.985514 -341.155786) (xy 44.989682 -341.1847) (xy 45.001853 -341.211256)
			(xy 45.011086 -341.222584) (xy 45.028709 -341.243531) (xy 45.058433 -341.289497) (xy 45.081279 -341.339241)
			(xy 45.096776 -341.391741) (xy 45.104606 -341.445917) (xy 45.104608 -341.500656) (xy 45.096782 -341.554833)
			(xy 45.081288 -341.607334) (xy 45.058446 -341.657079) (xy 45.028725 -341.703047) (xy 45.011086 -341.72398)
			(xy 45.001868 -341.735321) (xy 44.98969 -341.761874) (xy 44.985514 -341.790786) (xy 44.989682 -341.8197)
			(xy 45.001853 -341.846256) (xy 45.011086 -341.857584) (xy 45.028709 -341.878531) (xy 45.058433 -341.924497)
			(xy 45.081279 -341.974241) (xy 45.096776 -342.026741) (xy 45.104606 -342.080917) (xy 45.104608 -342.135656)
			(xy 45.096782 -342.189833) (xy 45.081288 -342.242334) (xy 45.058446 -342.292079) (xy 45.028725 -342.338047)
			(xy 45.011086 -342.35898) (xy 45.001868 -342.370321) (xy 44.98969 -342.396874) (xy 44.985514 -342.425786)
			(xy 44.989682 -342.4547) (xy 45.001853 -342.481256) (xy 45.011086 -342.492584) (xy 45.028729 -342.513513)
			(xy 45.058441 -342.559486) (xy 45.081276 -342.609235) (xy 45.096766 -342.661736) (xy 45.104593 -342.715913)
			(xy 45.105066 -342.743282) (xy 45.104628 -342.770536) (xy 45.096872 -342.82449) (xy 45.081516 -342.876791)
			(xy 45.058873 -342.926374) (xy 45.029403 -342.972229) (xy 44.993706 -343.013423) (xy 44.95251 -343.049117)
			(xy 44.906653 -343.078584) (xy 44.857069 -343.101225) (xy 44.804767 -343.116577) (xy 44.750812 -343.12433)
			(xy 44.723558 -343.12479) (xy 44.694818 -343.124294) (xy 44.637989 -343.115665) (xy 44.583098 -343.098609)
			(xy 44.531387 -343.073511) (xy 44.484026 -343.04094) (xy 44.4627 -343.021666) (xy 44.451166 -343.011594)
			(xy 44.42362 -342.998252) (xy 44.393358 -342.993667) (xy 44.363096 -342.998252) (xy 44.33555 -343.011594)
			(xy 44.324016 -343.021666) (xy 44.302689 -343.040936) (xy 44.255326 -343.073501) (xy 44.203615 -343.098592)
			(xy 44.148724 -343.115642) (xy 44.091897 -343.124264) (xy 44.034419 -343.124264) (xy 43.977592 -343.115642)
			(xy 43.922701 -343.098592) (xy 43.87099 -343.073501) (xy 43.823627 -343.040936) (xy 43.8023 -343.021666)
			(xy 43.790766 -343.011594) (xy 43.76322 -342.998252) (xy 43.732958 -342.993667) (xy 43.702696 -342.998252)
			(xy 43.67515 -343.011594) (xy 43.663616 -343.021666) (xy 43.642307 -343.040957) (xy 43.59494 -343.073521)
			(xy 43.543224 -343.098609) (xy 43.488329 -343.115655) (xy 43.431498 -343.124272) (xy 43.402758 -343.12479)
			(xy 43.375505 -343.124361) (xy 43.321554 -343.116599) (xy 43.269257 -343.101237) (xy 43.219679 -343.07859)
			(xy 43.173828 -343.049117) (xy 43.132637 -343.01342) (xy 43.096947 -342.972224) (xy 43.067481 -342.926369)
			(xy 43.044842 -342.876786) (xy 43.029489 -342.824487) (xy 43.021735 -342.770535) (xy 43.02125 -342.743282)
			(xy 40.126666 -342.743282) (xy 40.126228 -342.770536) (xy 40.118472 -342.82449) (xy 40.103116 -342.876791)
			(xy 40.080473 -342.926374) (xy 40.051003 -342.972229) (xy 40.015306 -343.013423) (xy 39.97411 -343.049117)
			(xy 39.928253 -343.078584) (xy 39.878669 -343.101225) (xy 39.826367 -343.116577) (xy 39.772412 -343.12433)
			(xy 39.745158 -343.12479) (xy 39.716418 -343.124294) (xy 39.659589 -343.115665) (xy 39.604698 -343.098609)
			(xy 39.552987 -343.073511) (xy 39.505626 -343.04094) (xy 39.4843 -343.021666) (xy 39.472766 -343.011594)
			(xy 39.44522 -342.998252) (xy 39.414958 -342.993667) (xy 39.384696 -342.998252) (xy 39.35715 -343.011594)
			(xy 39.345616 -343.021666) (xy 39.324289 -343.040936) (xy 39.276926 -343.073501) (xy 39.225215 -343.098592)
			(xy 39.170324 -343.115642) (xy 39.113497 -343.124264) (xy 39.056019 -343.124264) (xy 38.999192 -343.115642)
			(xy 38.944301 -343.098592) (xy 38.89259 -343.073501) (xy 38.845227 -343.040936) (xy 38.8239 -343.021666)
			(xy 38.812366 -343.011594) (xy 38.78482 -342.998252) (xy 38.754558 -342.993667) (xy 38.724296 -342.998252)
			(xy 38.69675 -343.011594) (xy 38.685216 -343.021666) (xy 38.663907 -343.040957) (xy 38.61654 -343.073521)
			(xy 38.564824 -343.098609) (xy 38.509929 -343.115655) (xy 38.453098 -343.124272) (xy 38.424358 -343.12479)
			(xy 38.397105 -343.124361) (xy 38.343154 -343.116599) (xy 38.290857 -343.101237) (xy 38.241279 -343.07859)
			(xy 38.195428 -343.049117) (xy 38.154237 -343.01342) (xy 38.118547 -342.972224) (xy 38.089081 -342.926369)
			(xy 38.066442 -342.876786) (xy 38.051089 -342.824487) (xy 38.043335 -342.770535) (xy 38.04285 -342.743282)
			(xy 38.043293 -342.715911) (xy 38.051115 -342.66173) (xy 38.066608 -342.609226) (xy 38.089456 -342.55948)
			(xy 38.119186 -342.513514) (xy 38.13683 -342.492584) (xy 38.146082 -342.481269) (xy 38.158253 -342.454706)
			(xy 38.162421 -342.425786) (xy 38.158246 -342.396868) (xy 38.146067 -342.370308) (xy 38.13683 -342.35898)
			(xy 38.119172 -342.338062) (xy 38.089447 -342.292091) (xy 38.066603 -342.242343) (xy 38.051108 -342.189839)
			(xy 38.043281 -342.135658) (xy 38.043283 -342.080915) (xy 38.051114 -342.026735) (xy 38.066612 -341.974232)
			(xy 38.08946 -341.924485) (xy 38.119188 -341.878517) (xy 38.13683 -341.857584) (xy 38.146082 -341.846269)
			(xy 38.158253 -341.819706) (xy 38.162421 -341.790786) (xy 38.158246 -341.761868) (xy 38.146067 -341.735308)
			(xy 38.13683 -341.72398) (xy 38.119172 -341.703062) (xy 38.089447 -341.657091) (xy 38.066603 -341.607343)
			(xy 38.051108 -341.554839) (xy 38.043281 -341.500658) (xy 38.043283 -341.445915) (xy 38.051114 -341.391735)
			(xy 38.066612 -341.339232) (xy 38.08946 -341.289485) (xy 38.119188 -341.243517) (xy 38.13683 -341.222584)
			(xy 38.146082 -341.211269) (xy 38.158253 -341.184706) (xy 38.162421 -341.155786) (xy 38.158246 -341.126868)
			(xy 38.146067 -341.100308) (xy 38.13683 -341.08898) (xy 38.11922 -341.068025) (xy 38.089502 -341.022059)
			(xy 38.06666 -340.972317) (xy 38.051163 -340.919822) (xy 38.043328 -340.86565) (xy 38.04285 -340.838282)
			(xy 38.043409 -340.808158) (xy 38.052893 -340.748661) (xy 38.071607 -340.691393) (xy 38.099085 -340.637776)
			(xy 38.134646 -340.589142) (xy 38.155626 -340.567518) (xy 38.164862 -340.557812) (xy 38.178306 -340.534645)
			(xy 38.185266 -340.50878) (xy 38.185263 -340.481995) (xy 38.178297 -340.456131) (xy 38.164846 -340.432968)
			(xy 38.155626 -340.423246) (xy 38.134647 -340.40162) (xy 38.099078 -340.352992) (xy 38.071597 -340.299376)
			(xy 38.052888 -340.242106) (xy 38.043418 -340.182606) (xy 38.04285 -340.152482) (xy 38.043236 -340.126961)
			(xy 38.050033 -340.076373) (xy 38.063518 -340.027143) (xy 38.083448 -339.980152) (xy 38.109469 -339.93624)
			(xy 38.141114 -339.896191) (xy 38.159182 -339.878162) (xy 38.168936 -339.868167) (xy 38.182971 -339.844031)
			(xy 38.189938 -339.816994) (xy 38.189313 -339.789081) (xy 38.181143 -339.762383) (xy 38.166041 -339.7389)
			(xy 38.15588 -339.729318) (xy 38.136067 -339.711138) (xy 38.101279 -339.670134) (xy 38.072584 -339.624658)
			(xy 38.05055 -339.575606) (xy 38.035614 -339.523949) (xy 38.02807 -339.470708) (xy 38.02761 -339.443822)
			(xy 34.561526 -339.443822) (xy 33.401 -340.604348) (xy 33.401 -353.70643) (xy 35.21405 -353.70643)
			(xy 35.218121 -353.650808) (xy 35.230247 -353.596371) (xy 35.25017 -353.54428) (xy 35.277466 -353.495645)
			(xy 35.311552 -353.451502) (xy 35.351701 -353.412793) (xy 35.397059 -353.380342) (xy 35.446659 -353.354841)
			(xy 35.499443 -353.336834) (xy 35.554286 -353.326704) (xy 35.61002 -353.324667) (xy 35.665457 -353.330767)
			(xy 35.719414 -353.344873) (xy 35.770743 -353.366685) (xy 35.818349 -353.395739) (xy 35.861217 -353.431414)
			(xy 35.898434 -353.472951) (xy 35.929207 -353.519464) (xy 35.952879 -353.569961) (xy 35.968947 -353.623368)
			(xy 35.977067 -353.678544) (xy 35.977576 -353.70643) (xy 35.977067 -353.734316) (xy 35.968947 -353.789492)
			(xy 35.952879 -353.842899) (xy 35.929207 -353.893396) (xy 35.898434 -353.939909) (xy 35.861217 -353.981446)
			(xy 35.818349 -354.017121) (xy 35.770743 -354.046175) (xy 35.719414 -354.067987) (xy 35.665457 -354.082093)
			(xy 35.61002 -354.088193) (xy 35.554286 -354.086156) (xy 35.499443 -354.076026) (xy 35.446659 -354.058019)
			(xy 35.397059 -354.032518) (xy 35.351701 -354.000067) (xy 35.311552 -353.961358) (xy 35.277466 -353.917215)
			(xy 35.25017 -353.86858) (xy 35.230247 -353.816489) (xy 35.218121 -353.762052) (xy 35.21405 -353.70643)
			(xy 33.401 -353.70643) (xy 33.401 -354.65385) (xy 35.21405 -354.65385) (xy 35.218121 -354.598228)
			(xy 35.230247 -354.543791) (xy 35.25017 -354.4917) (xy 35.277466 -354.443065) (xy 35.311552 -354.398922)
			(xy 35.351701 -354.360213) (xy 35.397059 -354.327762) (xy 35.446659 -354.302261) (xy 35.499443 -354.284254)
			(xy 35.554286 -354.274124) (xy 35.61002 -354.272087) (xy 35.665457 -354.278187) (xy 35.719414 -354.292293)
			(xy 35.770743 -354.314105) (xy 35.818349 -354.343159) (xy 35.861217 -354.378834) (xy 35.898434 -354.420371)
			(xy 35.929207 -354.466884) (xy 35.952879 -354.517381) (xy 35.968947 -354.570788) (xy 35.977067 -354.625964)
			(xy 35.977576 -354.65385) (xy 35.977067 -354.681736) (xy 35.968947 -354.736912) (xy 35.952879 -354.790319)
			(xy 35.929207 -354.840816) (xy 35.898434 -354.887329) (xy 35.861217 -354.928866) (xy 35.818349 -354.964541)
			(xy 35.770743 -354.993595) (xy 35.721478 -355.01453) (xy 37.608764 -355.01453) (xy 37.608764 -355.014276)
			(xy 37.609295 -354.986262) (xy 37.617514 -354.93084) (xy 37.633742 -354.877213) (xy 37.657631 -354.826533)
			(xy 37.688668 -354.779887) (xy 37.707062 -354.758752) (xy 37.716729 -354.747326) (xy 37.729509 -354.720278)
			(xy 37.733892 -354.690685) (xy 37.7295 -354.661093) (xy 37.716712 -354.634049) (xy 37.707062 -354.622608)
			(xy 37.688634 -354.601497) (xy 37.657566 -354.55486) (xy 37.633664 -354.504176) (xy 37.617442 -354.450538)
			(xy 37.609252 -354.395103) (xy 37.608764 -354.367084) (xy 37.608764 -354.36683) (xy 37.60925 -354.339579)
			(xy 37.617006 -354.285631) (xy 37.632361 -354.233336) (xy 37.655003 -354.183759) (xy 37.684469 -354.137909)
			(xy 37.72016 -354.096718) (xy 37.761351 -354.061027) (xy 37.807201 -354.031561) (xy 37.856778 -354.008919)
			(xy 37.909073 -353.993564) (xy 37.963021 -353.985808) (xy 38.017523 -353.985808) (xy 38.071471 -353.993564)
			(xy 38.123766 -354.008919) (xy 38.173343 -354.031561) (xy 38.219193 -354.061027) (xy 38.260384 -354.096718)
			(xy 38.296075 -354.137909) (xy 38.325541 -354.183759) (xy 38.348183 -354.233336) (xy 38.363538 -354.285631)
			(xy 38.371294 -354.339579) (xy 38.37178 -354.36683) (xy 38.37178 -354.367084) (xy 38.371299 -354.3951)
			(xy 38.36307 -354.450525) (xy 38.346831 -354.504153) (xy 38.322931 -354.554832) (xy 38.291882 -354.601475)
			(xy 38.273482 -354.622608) (xy 38.269002 -354.627942) (xy 45.58614 -354.627942) (xy 45.590211 -354.57232)
			(xy 45.602337 -354.517883) (xy 45.62226 -354.465792) (xy 45.649556 -354.417157) (xy 45.683642 -354.373014)
			(xy 45.723791 -354.334305) (xy 45.769149 -354.301854) (xy 45.818749 -354.276353) (xy 45.871533 -354.258346)
			(xy 45.926376 -354.248216) (xy 45.98211 -354.246179) (xy 46.037547 -354.252279) (xy 46.091504 -354.266385)
			(xy 46.142833 -354.288197) (xy 46.190439 -354.317251) (xy 46.233307 -354.352926) (xy 46.270524 -354.394463)
			(xy 46.301297 -354.440976) (xy 46.324969 -354.491473) (xy 46.341037 -354.54488) (xy 46.349157 -354.600056)
			(xy 46.349666 -354.627942) (xy 46.349157 -354.655828) (xy 46.341037 -354.711004) (xy 46.324969 -354.764411)
			(xy 46.301297 -354.814908) (xy 46.270524 -354.861421) (xy 46.233307 -354.902958) (xy 46.190439 -354.938633)
			(xy 46.142833 -354.967687) (xy 46.091504 -354.989499) (xy 46.037547 -355.003605) (xy 45.995969 -355.00818)
			(xy 47.297086 -355.00818) (xy 47.297544 -354.98081) (xy 47.305364 -354.92663) (xy 47.320855 -354.874127)
			(xy 47.343699 -354.82438) (xy 47.373424 -354.778414) (xy 47.391066 -354.757482) (xy 47.400325 -354.74617)
			(xy 47.412504 -354.719608) (xy 47.416674 -354.690685) (xy 47.412495 -354.661763) (xy 47.400308 -354.635204)
			(xy 47.391066 -354.623878) (xy 47.373445 -354.602932) (xy 47.343731 -354.556962) (xy 47.320893 -354.507218)
			(xy 47.305397 -354.454721) (xy 47.297563 -354.400548) (xy 47.297086 -354.37318) (xy 47.297572 -354.345929)
			(xy 47.305328 -354.291981) (xy 47.320683 -354.239686) (xy 47.343325 -354.190109) (xy 47.372791 -354.144259)
			(xy 47.408482 -354.103068) (xy 47.449673 -354.067377) (xy 47.495523 -354.037911) (xy 47.5451 -354.015269)
			(xy 47.597395 -353.999914) (xy 47.651343 -353.992158) (xy 47.705845 -353.992158) (xy 47.759793 -353.999914)
			(xy 47.812088 -354.015269) (xy 47.861665 -354.037911) (xy 47.907515 -354.067377) (xy 47.948706 -354.103068)
			(xy 47.984397 -354.144259) (xy 48.013863 -354.190109) (xy 48.036505 -354.239686) (xy 48.05186 -354.291981)
			(xy 48.059616 -354.345929) (xy 48.060102 -354.37318) (xy 48.059624 -354.40055) (xy 48.051809 -354.454728)
			(xy 48.036323 -354.507231) (xy 48.013484 -354.556978) (xy 47.983762 -354.602946) (xy 47.966122 -354.623878)
			(xy 47.956903 -354.635219) (xy 47.94472 -354.661771) (xy 47.940543 -354.690685) (xy 47.944712 -354.7196)
			(xy 47.956886 -354.746156) (xy 47.966122 -354.757482) (xy 47.98377 -354.778407) (xy 48.013479 -354.824382)
			(xy 48.036313 -354.874132) (xy 48.051802 -354.926634) (xy 48.059629 -354.98081) (xy 48.060102 -355.00818)
			(xy 48.059616 -355.035431) (xy 48.05186 -355.089379) (xy 48.036505 -355.141674) (xy 48.013863 -355.191251)
			(xy 47.984397 -355.237101) (xy 47.948706 -355.278292) (xy 47.907515 -355.313983) (xy 47.861665 -355.343449)
			(xy 47.812088 -355.366091) (xy 47.759793 -355.381446) (xy 47.705845 -355.389202) (xy 47.651343 -355.389202)
			(xy 47.597395 -355.381446) (xy 47.5451 -355.366091) (xy 47.495523 -355.343449) (xy 47.449673 -355.313983)
			(xy 47.408482 -355.278292) (xy 47.372791 -355.237101) (xy 47.343325 -355.191251) (xy 47.320683 -355.141674)
			(xy 47.305328 -355.089379) (xy 47.297572 -355.035431) (xy 47.297086 -355.00818) (xy 45.995969 -355.00818)
			(xy 45.98211 -355.009705) (xy 45.926376 -355.007668) (xy 45.871533 -354.997538) (xy 45.818749 -354.979531)
			(xy 45.769149 -354.95403) (xy 45.723791 -354.921579) (xy 45.683642 -354.88287) (xy 45.649556 -354.838727)
			(xy 45.62226 -354.790092) (xy 45.602337 -354.738001) (xy 45.590211 -354.683564) (xy 45.58614 -354.627942)
			(xy 38.269002 -354.627942) (xy 38.263859 -354.634066) (xy 38.251081 -354.661104) (xy 38.246693 -354.690685)
			(xy 38.251072 -354.720268) (xy 38.263843 -354.747309) (xy 38.273482 -354.758752) (xy 38.291898 -354.779873)
			(xy 38.322967 -354.826507) (xy 38.346871 -354.877189) (xy 38.363095 -354.930825) (xy 38.37129 -354.986258)
			(xy 38.37178 -355.014276) (xy 38.37178 -355.01453) (xy 38.371294 -355.041781) (xy 38.363538 -355.095729)
			(xy 38.348183 -355.148024) (xy 38.325541 -355.197601) (xy 38.296075 -355.243451) (xy 38.260384 -355.284642)
			(xy 38.219193 -355.320333) (xy 38.173343 -355.349799) (xy 38.123766 -355.372441) (xy 38.071471 -355.387796)
			(xy 38.017523 -355.395552) (xy 37.963021 -355.395552) (xy 37.909073 -355.387796) (xy 37.856778 -355.372441)
			(xy 37.807201 -355.349799) (xy 37.761351 -355.320333) (xy 37.72016 -355.284642) (xy 37.684469 -355.243451)
			(xy 37.655003 -355.197601) (xy 37.632361 -355.148024) (xy 37.617006 -355.095729) (xy 37.60925 -355.041781)
			(xy 37.608764 -355.01453) (xy 35.721478 -355.01453) (xy 35.719414 -355.015407) (xy 35.665457 -355.029513)
			(xy 35.61002 -355.035613) (xy 35.554286 -355.033576) (xy 35.499443 -355.023446) (xy 35.446659 -355.005439)
			(xy 35.397059 -354.979938) (xy 35.351701 -354.947487) (xy 35.311552 -354.908778) (xy 35.277466 -354.864635)
			(xy 35.25017 -354.816) (xy 35.230247 -354.763909) (xy 35.218121 -354.709472) (xy 35.21405 -354.65385)
			(xy 33.401 -354.65385) (xy 33.401 -355.4108) (xy 41.857303 -355.4108) (xy 41.861472 -355.355173)
			(xy 41.873886 -355.30079) (xy 41.894268 -355.248864) (xy 41.922161 -355.200556) (xy 41.956943 -355.156945)
			(xy 41.997837 -355.119006) (xy 42.04393 -355.087586) (xy 42.09419 -355.063388) (xy 42.147496 -355.046951)
			(xy 42.202657 -355.038644) (xy 42.230548 -355.038152) (xy 42.25788 -355.038623) (xy 42.31196 -355.046592)
			(xy 42.364295 -355.062379) (xy 42.41376 -355.085647) (xy 42.459292 -355.115895) (xy 42.499914 -355.152474)
			(xy 42.534753 -355.194597) (xy 42.549318 -355.21773) (xy 42.557239 -355.229955) (xy 42.578713 -355.249623)
			(xy 42.604866 -355.262425) (xy 42.633571 -355.267321) (xy 42.66249 -355.26391) (xy 42.676064 -355.258624)
			(xy 42.69928 -355.249149) (xy 42.74761 -355.235794) (xy 42.797297 -355.229059) (xy 42.822368 -355.228652)
			(xy 42.847438 -355.229064) (xy 42.897121 -355.235818) (xy 42.945455 -355.249155) (xy 42.968672 -355.258624)
			(xy 42.982249 -355.263871) (xy 43.011149 -355.267234) (xy 43.039827 -355.262322) (xy 43.065961 -355.249534)
			(xy 43.087437 -355.229904) (xy 43.095418 -355.21773) (xy 43.109987 -355.194599) (xy 43.14483 -355.152478)
			(xy 43.185453 -355.115899) (xy 43.230984 -355.085648) (xy 43.280446 -355.062372) (xy 43.332777 -355.046572)
			(xy 43.386856 -355.038586) (xy 43.44152 -355.038586) (xy 43.495599 -355.046572) (xy 43.54793 -355.062372)
			(xy 43.597392 -355.085648) (xy 43.642923 -355.115899) (xy 43.683546 -355.152478) (xy 43.718389 -355.194599)
			(xy 43.732958 -355.21773) (xy 43.740841 -355.229983) (xy 43.762325 -355.24965) (xy 43.788489 -355.262449)
			(xy 43.817203 -355.267337) (xy 43.846128 -355.263916) (xy 43.859704 -355.258624) (xy 43.882915 -355.249137)
			(xy 43.931247 -355.235786) (xy 43.980937 -355.229057) (xy 44.006008 -355.228652) (xy 44.033193 -355.229125)
			(xy 44.086987 -355.237015) (xy 44.139062 -355.252639) (xy 44.188314 -355.275667) (xy 44.233695 -355.305609)
			(xy 44.274243 -355.34183) (xy 44.309095 -355.383559) (xy 44.337512 -355.429911) (xy 44.348654 -355.454712)
			(xy 44.354556 -355.467303) (xy 44.371962 -355.48897) (xy 44.394568 -355.50514) (xy 44.420697 -355.514612)
			(xy 44.448413 -355.516686) (xy 44.475661 -355.511206) (xy 44.500421 -355.498581) (xy 44.51096 -355.48951)
			(xy 44.532202 -355.470607) (xy 44.579249 -355.438674) (xy 44.630518 -355.414084) (xy 44.684871 -355.397383)
			(xy 44.741102 -355.388941) (xy 44.769532 -355.388418) (xy 44.787551 -355.38864) (xy 44.823426 -355.392074)
			(xy 44.84116 -355.395276) (xy 44.856375 -355.397561) (xy 44.88692 -355.394044) (xy 44.915035 -355.381595)
			(xy 44.93817 -355.361343) (xy 44.954229 -355.335122) (xy 44.958508 -355.320346) (xy 44.965907 -355.293302)
			(xy 44.987537 -355.241577) (xy 45.016502 -355.193572) (xy 45.052177 -355.15032) (xy 45.093796 -355.112754)
			(xy 45.140463 -355.081679) (xy 45.191174 -355.057766) (xy 45.244838 -355.041529) (xy 45.300299 -355.033317)
			(xy 45.328332 -355.032818) (xy 45.355585 -355.033248) (xy 45.409536 -355.04101) (xy 45.461834 -355.05637)
			(xy 45.511413 -355.079017) (xy 45.557264 -355.108489) (xy 45.598455 -355.144186) (xy 45.634146 -355.185382)
			(xy 45.663611 -355.231238) (xy 45.68625 -355.280821) (xy 45.701603 -355.33312) (xy 45.709356 -355.387073)
			(xy 45.709777 -355.4108) (xy 51.545729 -355.4108) (xy 51.549897 -355.355185) (xy 51.562307 -355.300812)
			(xy 51.582681 -355.248895) (xy 51.610566 -355.200595) (xy 51.645337 -355.15699) (xy 51.686219 -355.119054)
			(xy 51.732297 -355.087635) (xy 51.782544 -355.063434) (xy 51.835837 -355.046991) (xy 51.890984 -355.038675)
			(xy 51.91887 -355.038152) (xy 51.946203 -355.038606) (xy 52.000284 -355.046577) (xy 52.052619 -355.062368)
			(xy 52.102083 -355.085639) (xy 52.147616 -355.115889) (xy 52.188237 -355.15247) (xy 52.223075 -355.194596)
			(xy 52.23764 -355.21773) (xy 52.24554 -355.22997) (xy 52.267019 -355.249638) (xy 52.293179 -355.262438)
			(xy 52.321888 -355.26733) (xy 52.350811 -355.263914) (xy 52.364386 -355.258624) (xy 52.387599 -355.249143)
			(xy 52.43593 -355.235789) (xy 52.485619 -355.229058) (xy 52.51069 -355.228652) (xy 52.535759 -355.229089)
			(xy 52.585442 -355.235833) (xy 52.633776 -355.24916) (xy 52.656994 -355.258624) (xy 52.670599 -355.263789)
			(xy 52.699485 -355.267169) (xy 52.728153 -355.262276) (xy 52.754282 -355.249507) (xy 52.775757 -355.229895)
			(xy 52.78374 -355.21773) (xy 52.798309 -355.194599) (xy 52.833152 -355.152478) (xy 52.873775 -355.115899)
			(xy 52.919306 -355.085648) (xy 52.968768 -355.062372) (xy 53.021099 -355.046572) (xy 53.075178 -355.038586)
			(xy 53.129842 -355.038586) (xy 53.183921 -355.046572) (xy 53.236252 -355.062372) (xy 53.285714 -355.085648)
			(xy 53.331245 -355.115899) (xy 53.371868 -355.152478) (xy 53.406711 -355.194599) (xy 53.42128 -355.21773)
			(xy 53.429237 -355.229929) (xy 53.450701 -355.249597) (xy 53.476845 -355.262403) (xy 53.505541 -355.267305)
			(xy 53.534453 -355.263904) (xy 53.548026 -355.258624) (xy 53.571234 -355.24913) (xy 53.619568 -355.235782)
			(xy 53.669258 -355.229055) (xy 53.69433 -355.228652) (xy 53.721172 -355.22911) (xy 53.774301 -355.236818)
			(xy 53.825774 -355.25207) (xy 53.874526 -355.27455) (xy 53.919548 -355.303792) (xy 53.959907 -355.339193)
			(xy 53.994769 -355.380018) (xy 54.023412 -355.425424) (xy 54.045244 -355.47447) (xy 54.052978 -355.500178)
			(xy 54.057673 -355.514662) (xy 54.074188 -355.540221) (xy 54.097497 -355.559782) (xy 54.125532 -355.571613)
			(xy 54.155809 -355.574663) (xy 54.185641 -355.568663) (xy 54.199282 -355.5619) (xy 54.227424 -355.547258)
			(xy 54.287377 -355.526534) (xy 54.349937 -355.516039) (xy 54.381654 -355.515418) (xy 54.409825 -355.515918)
			(xy 54.465554 -355.524209) (xy 54.492652 -355.531928) (xy 54.506084 -355.535519) (xy 54.533869 -355.53613)
			(xy 54.56079 -355.529225) (xy 54.584851 -355.515317) (xy 54.60427 -355.495435) (xy 54.617608 -355.471053)
			(xy 54.623877 -355.443977) (xy 54.623716 -355.430074) (xy 54.623208 -355.413056) (xy 54.623208 -355.412802)
			(xy 54.623654 -355.385561) (xy 54.631447 -355.331638) (xy 54.64683 -355.279371) (xy 54.669492 -355.229825)
			(xy 54.698971 -355.184006) (xy 54.734668 -355.142846) (xy 54.775858 -355.107183) (xy 54.821701 -355.077741)
			(xy 54.871266 -355.05512) (xy 54.923545 -355.03978) (xy 54.977474 -355.032032) (xy 55.004716 -355.031548)
			(xy 55.031966 -355.032063) (xy 55.08591 -355.03982) (xy 55.138202 -355.055175) (xy 55.187776 -355.077815)
			(xy 55.233624 -355.107279) (xy 55.274813 -355.142967) (xy 55.310504 -355.184153) (xy 55.339972 -355.229999)
			(xy 55.362615 -355.279572) (xy 55.377974 -355.331863) (xy 55.385735 -355.385806) (xy 55.386224 -355.413056)
			(xy 55.38572 -355.440629) (xy 55.377774 -355.4952) (xy 55.362056 -355.548059) (xy 55.338893 -355.598105)
			(xy 55.308768 -355.644295) (xy 55.272308 -355.685669) (xy 55.251604 -355.703886) (xy 55.240751 -355.713829)
			(xy 55.224677 -355.738467) (xy 55.216288 -355.766663) (xy 55.216279 -355.79608) (xy 55.224653 -355.824281)
			(xy 55.240713 -355.848928) (xy 55.251604 -355.858826) (xy 55.272265 -355.87709) (xy 55.308728 -355.918455)
			(xy 55.338855 -355.964639) (xy 55.362019 -356.01468) (xy 55.377736 -356.067534) (xy 55.38568 -356.122101)
			(xy 55.385684 -356.177242) (xy 55.377749 -356.23181) (xy 55.362039 -356.284667) (xy 55.338883 -356.334711)
			(xy 55.308763 -356.3809) (xy 55.272306 -356.42227) (xy 55.251604 -356.440486) (xy 55.240751 -356.450429)
			(xy 55.224677 -356.475067) (xy 55.216288 -356.503263) (xy 55.216279 -356.53268) (xy 55.224653 -356.560881)
			(xy 55.240713 -356.585528) (xy 55.251604 -356.595426) (xy 55.272332 -356.613619) (xy 55.308801 -356.654992)
			(xy 55.338931 -356.701185) (xy 55.362093 -356.751237) (xy 55.377806 -356.804103) (xy 55.385741 -356.85868)
			(xy 55.386224 -356.886256) (xy 55.385704 -356.913507) (xy 55.377953 -356.967455) (xy 55.362604 -357.019751)
			(xy 55.339967 -357.06933) (xy 55.310505 -357.115182) (xy 55.274818 -357.156375) (xy 55.23363 -357.192069)
			(xy 55.187783 -357.221539) (xy 55.138207 -357.244183) (xy 55.085914 -357.25954) (xy 55.031967 -357.2673)
			(xy 55.004716 -357.267764) (xy 54.978798 -357.267319) (xy 54.927439 -357.26031) (xy 54.877503 -357.246404)
			(xy 54.829912 -357.22586) (xy 54.785546 -357.199055) (xy 54.745221 -357.166484) (xy 54.709682 -357.128749)
			(xy 54.679585 -357.086546) (xy 54.66715 -357.063802) (xy 54.659833 -357.051012) (xy 54.639245 -357.029952)
			(xy 54.613507 -357.015635) (xy 54.584755 -357.009251) (xy 54.555377 -357.011328) (xy 54.54142 -357.01605)
			(xy 54.509071 -357.027446) (xy 54.441598 -357.039713) (xy 54.407308 -357.040434) (xy 54.407054 -357.040434)
			(xy 54.392905 -357.040345) (xy 54.364682 -357.038308) (xy 54.350666 -357.03637) (xy 54.337314 -357.034836)
			(xy 54.31063 -357.037929) (xy 54.285681 -357.04789) (xy 54.264204 -357.064025) (xy 54.24769 -357.085213)
			(xy 54.237288 -357.10998) (xy 54.235096 -357.123238) (xy 54.231023 -357.150394) (xy 54.21605 -357.203226)
			(xy 54.193657 -357.253366) (xy 54.164308 -357.299777) (xy 54.12861 -357.341502) (xy 54.087298 -357.377679)
			(xy 54.041227 -357.407559) (xy 53.991348 -357.430527) (xy 53.938692 -357.446107) (xy 53.884346 -357.453977)
			(xy 53.85689 -357.454454) (xy 53.829641 -357.453932) (xy 53.775697 -357.446175) (xy 53.723405 -357.430821)
			(xy 53.673831 -357.408182) (xy 53.627983 -357.378719) (xy 53.586794 -357.343031) (xy 53.551103 -357.301846)
			(xy 53.521635 -357.256001) (xy 53.498992 -357.206428) (xy 53.483633 -357.154139) (xy 53.475871 -357.100195)
			(xy 53.475382 -357.072946) (xy 53.475886 -357.045373) (xy 53.483831 -356.990802) (xy 53.499549 -356.937943)
			(xy 53.522712 -356.887897) (xy 53.552838 -356.841707) (xy 53.589298 -356.800333) (xy 53.610002 -356.782116)
			(xy 53.620852 -356.77217) (xy 53.636926 -356.747533) (xy 53.645315 -356.719338) (xy 53.645323 -356.689921)
			(xy 53.636951 -356.661721) (xy 53.620892 -356.637075) (xy 53.610002 -356.627176) (xy 53.589276 -356.608981)
			(xy 53.552807 -356.567609) (xy 53.522677 -356.521415) (xy 53.499513 -356.471364) (xy 53.4838 -356.418499)
			(xy 53.475865 -356.363922) (xy 53.475382 -356.336346) (xy 53.475827 -356.309845) (xy 53.483175 -356.257353)
			(xy 53.497722 -356.206386) (xy 53.519187 -356.157924) (xy 53.547156 -356.112901) (xy 53.563774 -356.092252)
			(xy 53.573204 -356.080099) (xy 53.584989 -356.051701) (xy 53.587811 -356.021084) (xy 53.581417 -355.991011)
			(xy 53.566382 -355.964191) (xy 53.544063 -355.943044) (xy 53.5305 -355.935788) (xy 53.506801 -355.923703)
			(xy 53.462822 -355.893775) (xy 53.423543 -355.857899) (xy 53.389762 -355.816804) (xy 53.37556 -355.79431)
			(xy 53.36765 -355.782076) (xy 53.346176 -355.762403) (xy 53.320019 -355.749599) (xy 53.29131 -355.744707)
			(xy 53.262388 -355.748125) (xy 53.248814 -355.753416) (xy 53.2256 -355.762894) (xy 53.177269 -355.776249)
			(xy 53.127581 -355.782982) (xy 53.10251 -355.783388) (xy 53.077441 -355.782948) (xy 53.027759 -355.776205)
			(xy 52.979424 -355.762879) (xy 52.956206 -355.753416) (xy 52.942619 -355.748185) (xy 52.913715 -355.744801)
			(xy 52.885029 -355.749698) (xy 52.858885 -355.762479) (xy 52.837401 -355.782108) (xy 52.82946 -355.79431)
			(xy 52.814891 -355.817441) (xy 52.780048 -355.859562) (xy 52.739425 -355.896141) (xy 52.693894 -355.926392)
			(xy 52.644432 -355.949668) (xy 52.592101 -355.965468) (xy 52.538022 -355.973454) (xy 52.483358 -355.973454)
			(xy 52.429279 -355.965468) (xy 52.376948 -355.949668) (xy 52.327486 -355.926392) (xy 52.281955 -355.896141)
			(xy 52.241332 -355.859562) (xy 52.206489 -355.817441) (xy 52.19192 -355.79431) (xy 52.183953 -355.782117)
			(xy 52.162494 -355.762445) (xy 52.136353 -355.749635) (xy 52.107657 -355.744732) (xy 52.078746 -355.748134)
			(xy 52.065174 -355.753416) (xy 52.041965 -355.762907) (xy 51.993631 -355.776257) (xy 51.943942 -355.782985)
			(xy 51.91887 -355.783388) (xy 51.890984 -355.782925) (xy 51.835837 -355.774609) (xy 51.782544 -355.758166)
			(xy 51.732297 -355.733965) (xy 51.686219 -355.702546) (xy 51.645337 -355.66461) (xy 51.610566 -355.621005)
			(xy 51.582681 -355.572705) (xy 51.562307 -355.520788) (xy 51.549897 -355.466415) (xy 51.545729 -355.4108)
			(xy 45.709777 -355.4108) (xy 45.70984 -355.414326) (xy 45.709344 -355.4419) (xy 45.701401 -355.496472)
			(xy 45.685683 -355.549332) (xy 45.662519 -355.599379) (xy 45.632391 -355.645569) (xy 45.595926 -355.68694)
			(xy 45.57522 -355.705156) (xy 45.564295 -355.715027) (xy 45.548221 -355.739685) (xy 45.539839 -355.7679)
			(xy 45.539844 -355.797334) (xy 45.548235 -355.825546) (xy 45.564318 -355.850198) (xy 45.57522 -355.860096)
			(xy 45.595951 -355.878284) (xy 45.632412 -355.91966) (xy 45.662537 -355.965854) (xy 45.685697 -356.015904)
			(xy 45.70141 -356.068768) (xy 45.709347 -356.123342) (xy 45.709345 -356.178491) (xy 45.701402 -356.233065)
			(xy 45.685685 -356.285927) (xy 45.662521 -356.335976) (xy 45.632392 -356.382167) (xy 45.595927 -356.42354)
			(xy 45.57522 -356.441756) (xy 45.564295 -356.451627) (xy 45.548221 -356.476285) (xy 45.548141 -356.476554)
			(xy 48.08804 -356.476554) (xy 48.092111 -356.420932) (xy 48.104237 -356.366495) (xy 48.12416 -356.314404)
			(xy 48.151456 -356.265769) (xy 48.185542 -356.221626) (xy 48.225691 -356.182917) (xy 48.271049 -356.150466)
			(xy 48.320649 -356.124965) (xy 48.373433 -356.106958) (xy 48.428276 -356.096828) (xy 48.48401 -356.094791)
			(xy 48.539447 -356.100891) (xy 48.593404 -356.114997) (xy 48.644733 -356.136809) (xy 48.692339 -356.165863)
			(xy 48.735207 -356.201538) (xy 48.772424 -356.243075) (xy 48.803197 -356.289588) (xy 48.826869 -356.340085)
			(xy 48.842937 -356.393492) (xy 48.851057 -356.448668) (xy 48.851566 -356.476554) (xy 48.851057 -356.50444)
			(xy 48.842937 -356.559616) (xy 48.826869 -356.613023) (xy 48.803197 -356.66352) (xy 48.772424 -356.710033)
			(xy 48.735207 -356.75157) (xy 48.692339 -356.787245) (xy 48.644733 -356.816299) (xy 48.593404 -356.838111)
			(xy 48.539447 -356.852217) (xy 48.48401 -356.858317) (xy 48.428276 -356.85628) (xy 48.373433 -356.84615)
			(xy 48.320649 -356.828143) (xy 48.271049 -356.802642) (xy 48.225691 -356.770191) (xy 48.185542 -356.731482)
			(xy 48.151456 -356.687339) (xy 48.12416 -356.638704) (xy 48.104237 -356.586613) (xy 48.092111 -356.532176)
			(xy 48.08804 -356.476554) (xy 45.548141 -356.476554) (xy 45.539839 -356.5045) (xy 45.539844 -356.533934)
			(xy 45.548235 -356.562146) (xy 45.564318 -356.586798) (xy 45.57522 -356.596696) (xy 45.595936 -356.614901)
			(xy 45.632405 -356.656272) (xy 45.662536 -356.702463) (xy 45.685701 -356.752512) (xy 45.701417 -356.805375)
			(xy 45.709355 -356.859951) (xy 45.70984 -356.887526) (xy 45.709346 -356.914776) (xy 45.701587 -356.968722)
			(xy 45.68623 -357.021015) (xy 45.663589 -357.07059) (xy 45.634123 -357.116439) (xy 45.598432 -357.157628)
			(xy 45.557244 -357.193319) (xy 45.511395 -357.222786) (xy 45.46182 -357.245428) (xy 45.409528 -357.260786)
			(xy 45.355582 -357.268546) (xy 45.328332 -357.269034) (xy 45.300479 -357.268457) (xy 45.245367 -357.260339)
			(xy 45.192019 -357.244299) (xy 45.141568 -357.220679) (xy 45.095084 -357.189979) (xy 45.053555 -357.15285)
			(xy 45.01786 -357.110082) (xy 44.988758 -357.062581) (xy 44.966867 -357.011356) (xy 44.95927 -356.984554)
			(xy 44.955023 -356.97043) (xy 44.939621 -356.945288) (xy 44.917696 -356.925576) (xy 44.891063 -356.912927)
			(xy 44.861931 -356.90839) (xy 44.847256 -356.909878) (xy 44.834303 -356.911544) (xy 44.808245 -356.913321)
			(xy 44.795186 -356.913434) (xy 44.794932 -356.913434) (xy 44.794678 -356.913434) (xy 44.765642 -356.912893)
			(xy 44.708242 -356.90409) (xy 44.680378 -356.895908) (xy 44.66662 -356.892054) (xy 44.638072 -356.891306)
			(xy 44.610434 -356.898498) (xy 44.58587 -356.913066) (xy 44.566305 -356.933869) (xy 44.553269 -356.959279)
			(xy 44.547784 -356.987305) (xy 44.548552 -357.001572) (xy 44.550076 -357.034846) (xy 44.549665 -357.0621)
			(xy 44.541901 -357.116052) (xy 44.526539 -357.16835) (xy 44.50389 -357.21793) (xy 44.474416 -357.263781)
			(xy 44.443447 -357.299514) (xy 47.423576 -357.299514) (xy 47.427647 -357.243892) (xy 47.439773 -357.189455)
			(xy 47.459696 -357.137364) (xy 47.486992 -357.088729) (xy 47.521078 -357.044586) (xy 47.561227 -357.005877)
			(xy 47.606585 -356.973426) (xy 47.656185 -356.947925) (xy 47.708969 -356.929918) (xy 47.763812 -356.919788)
			(xy 47.819546 -356.917751) (xy 47.874983 -356.923851) (xy 47.92894 -356.937957) (xy 47.980269 -356.959769)
			(xy 48.027875 -356.988823) (xy 48.070743 -357.024498) (xy 48.10796 -357.066035) (xy 48.138733 -357.112548)
			(xy 48.162405 -357.163045) (xy 48.178473 -357.216452) (xy 48.186593 -357.271628) (xy 48.187102 -357.299514)
			(xy 48.186593 -357.3274) (xy 48.178473 -357.382576) (xy 48.162405 -357.435983) (xy 48.138733 -357.48648)
			(xy 48.10796 -357.532993) (xy 48.070743 -357.57453) (xy 48.027875 -357.610205) (xy 47.980269 -357.639259)
			(xy 47.92894 -357.661071) (xy 47.874983 -357.675177) (xy 47.819546 -357.681277) (xy 47.763812 -357.67924)
			(xy 47.708969 -357.66911) (xy 47.656185 -357.651103) (xy 47.606585 -357.625602) (xy 47.561227 -357.593151)
			(xy 47.521078 -357.554442) (xy 47.486992 -357.510299) (xy 47.459696 -357.461664) (xy 47.439773 -357.409573)
			(xy 47.427647 -357.355136) (xy 47.423576 -357.299514) (xy 44.443447 -357.299514) (xy 44.438717 -357.304972)
			(xy 44.397519 -357.340663) (xy 44.351661 -357.370127) (xy 44.302077 -357.392766) (xy 44.249776 -357.408118)
			(xy 44.195822 -357.41587) (xy 44.168568 -357.416354) (xy 44.141318 -357.415852) (xy 44.087373 -357.408092)
			(xy 44.035082 -357.392736) (xy 43.985507 -357.370094) (xy 43.939659 -357.340629) (xy 43.898471 -357.304939)
			(xy 43.86278 -357.263752) (xy 43.833313 -357.217905) (xy 43.810669 -357.168331) (xy 43.795311 -357.11604)
			(xy 43.787549 -357.062096) (xy 43.78706 -357.034846) (xy 43.787536 -357.007272) (xy 43.795484 -356.952698)
			(xy 43.811205 -356.899838) (xy 43.834373 -356.849791) (xy 43.864505 -356.803602) (xy 43.900973 -356.762231)
			(xy 43.92168 -356.744016) (xy 43.932533 -356.734071) (xy 43.948609 -356.709435) (xy 43.957 -356.681239)
			(xy 43.957009 -356.651821) (xy 43.948635 -356.623619) (xy 43.932572 -356.598973) (xy 43.92168 -356.589076)
			(xy 43.90095 -356.570885) (xy 43.864482 -356.529512) (xy 43.834353 -356.483317) (xy 43.81119 -356.433265)
			(xy 43.795478 -356.3804) (xy 43.787543 -356.325822) (xy 43.78706 -356.298246) (xy 43.787663 -356.268495)
			(xy 43.796938 -356.209719) (xy 43.81521 -356.15309) (xy 43.842036 -356.099976) (xy 43.858942 -356.075488)
			(xy 43.866861 -356.063559) (xy 43.87646 -356.036601) (xy 43.878193 -356.008037) (xy 43.871925 -355.980115)
			(xy 43.85815 -355.955033) (xy 43.83795 -355.934763) (xy 43.825668 -355.927406) (xy 43.804606 -355.915307)
			(xy 43.765515 -355.886475) (xy 43.7305 -355.852809) (xy 43.700154 -355.814881) (xy 43.687238 -355.79431)
			(xy 43.679349 -355.782061) (xy 43.657869 -355.762388) (xy 43.631706 -355.749586) (xy 43.602992 -355.744698)
			(xy 43.574067 -355.748121) (xy 43.560492 -355.753416) (xy 43.53728 -355.762901) (xy 43.488948 -355.776254)
			(xy 43.439259 -355.782984) (xy 43.414188 -355.783388) (xy 43.389119 -355.782955) (xy 43.339436 -355.776209)
			(xy 43.291102 -355.76288) (xy 43.267884 -355.753416) (xy 43.254305 -355.748162) (xy 43.225397 -355.744783)
			(xy 43.196708 -355.749685) (xy 43.170562 -355.762471) (xy 43.149078 -355.782106) (xy 43.141138 -355.79431)
			(xy 43.126569 -355.817441) (xy 43.091726 -355.859562) (xy 43.051103 -355.896141) (xy 43.005572 -355.926392)
			(xy 42.95611 -355.949668) (xy 42.903779 -355.965468) (xy 42.8497 -355.973454) (xy 42.795036 -355.973454)
			(xy 42.740957 -355.965468) (xy 42.688626 -355.949668) (xy 42.639164 -355.926392) (xy 42.593633 -355.896141)
			(xy 42.55301 -355.859562) (xy 42.518167 -355.817441) (xy 42.503598 -355.79431) (xy 42.495652 -355.782102)
			(xy 42.474188 -355.76243) (xy 42.44804 -355.749622) (xy 42.41934 -355.744723) (xy 42.390425 -355.748131)
			(xy 42.376852 -355.753416) (xy 42.353645 -355.762913) (xy 42.305311 -355.776261) (xy 42.25562 -355.782986)
			(xy 42.230548 -355.783388) (xy 42.202657 -355.782956) (xy 42.147496 -355.774649) (xy 42.09419 -355.758212)
			(xy 42.04393 -355.734014) (xy 41.997837 -355.702594) (xy 41.956943 -355.664655) (xy 41.922161 -355.621044)
			(xy 41.894268 -355.572736) (xy 41.873886 -355.52081) (xy 41.861472 -355.466427) (xy 41.857303 -355.4108)
			(xy 33.401 -355.4108) (xy 33.401 -356.80523) (xy 37.03396 -356.80523) (xy 37.038031 -356.749608)
			(xy 37.050157 -356.695171) (xy 37.07008 -356.64308) (xy 37.097376 -356.594445) (xy 37.131462 -356.550302)
			(xy 37.171611 -356.511593) (xy 37.216969 -356.479142) (xy 37.266569 -356.453641) (xy 37.319353 -356.435634)
			(xy 37.374196 -356.425504) (xy 37.42993 -356.423467) (xy 37.485367 -356.429567) (xy 37.539324 -356.443673)
			(xy 37.590653 -356.465485) (xy 37.60879 -356.476554) (xy 38.399718 -356.476554) (xy 38.403789 -356.420932)
			(xy 38.415915 -356.366495) (xy 38.435838 -356.314404) (xy 38.463134 -356.265769) (xy 38.49722 -356.221626)
			(xy 38.537369 -356.182917) (xy 38.582727 -356.150466) (xy 38.632327 -356.124965) (xy 38.685111 -356.106958)
			(xy 38.739954 -356.096828) (xy 38.795688 -356.094791) (xy 38.851125 -356.100891) (xy 38.905082 -356.114997)
			(xy 38.956411 -356.136809) (xy 39.004017 -356.165863) (xy 39.046885 -356.201538) (xy 39.084102 -356.243075)
			(xy 39.114875 -356.289588) (xy 39.138547 -356.340085) (xy 39.154615 -356.393492) (xy 39.162735 -356.448668)
			(xy 39.163244 -356.476554) (xy 39.162735 -356.50444) (xy 39.154615 -356.559616) (xy 39.138547 -356.613023)
			(xy 39.114875 -356.66352) (xy 39.084102 -356.710033) (xy 39.046885 -356.75157) (xy 39.004017 -356.787245)
			(xy 38.956411 -356.816299) (xy 38.905082 -356.838111) (xy 38.851125 -356.852217) (xy 38.795688 -356.858317)
			(xy 38.739954 -356.85628) (xy 38.685111 -356.84615) (xy 38.632327 -356.828143) (xy 38.582727 -356.802642)
			(xy 38.537369 -356.770191) (xy 38.49722 -356.731482) (xy 38.463134 -356.687339) (xy 38.435838 -356.638704)
			(xy 38.415915 -356.586613) (xy 38.403789 -356.532176) (xy 38.399718 -356.476554) (xy 37.60879 -356.476554)
			(xy 37.638259 -356.494539) (xy 37.681127 -356.530214) (xy 37.718344 -356.571751) (xy 37.749117 -356.618264)
			(xy 37.772789 -356.668761) (xy 37.788857 -356.722168) (xy 37.796977 -356.777344) (xy 37.797486 -356.80523)
			(xy 37.796977 -356.833116) (xy 37.788857 -356.888292) (xy 37.772789 -356.941699) (xy 37.749117 -356.992196)
			(xy 37.718344 -357.038709) (xy 37.681127 -357.080246) (xy 37.638259 -357.115921) (xy 37.590653 -357.144975)
			(xy 37.539324 -357.166787) (xy 37.485367 -357.180893) (xy 37.42993 -357.186993) (xy 37.374196 -357.184956)
			(xy 37.319353 -357.174826) (xy 37.266569 -357.156819) (xy 37.216969 -357.131318) (xy 37.171611 -357.098867)
			(xy 37.131462 -357.060158) (xy 37.097376 -357.016015) (xy 37.07008 -356.96738) (xy 37.050157 -356.915289)
			(xy 37.038031 -356.860852) (xy 37.03396 -356.80523) (xy 33.401 -356.80523) (xy 33.401 -365.674148)
			(xy 33.709356 -365.982504) (xy 37.519864 -365.982504) (xy 37.519864 -358.35209) (xy 37.520484 -358.327107)
			(xy 37.530224 -358.278099) (xy 37.549329 -358.231929) (xy 37.577065 -358.190368) (xy 37.594286 -358.172258)
			(xy 38.493446 -357.273098) (xy 38.511573 -357.255895) (xy 38.553126 -357.228148) (xy 38.59929 -357.209035)
			(xy 38.648296 -357.199289) (xy 38.673278 -357.198676) (xy 39.216838 -357.198676) (xy 39.228776 -357.164894)
			(xy 39.239183 -357.137554) (xy 39.267155 -357.086176) (xy 39.302638 -357.039668) (xy 39.344803 -356.999119)
			(xy 39.392661 -356.965479) (xy 39.445093 -356.939535) (xy 39.500868 -356.921896) (xy 39.558683 -356.912975)
			(xy 39.587932 -356.912418) (xy 39.615185 -356.912848) (xy 39.669136 -356.92061) (xy 39.721434 -356.93597)
			(xy 39.771013 -356.958617) (xy 39.816864 -356.988089) (xy 39.858055 -357.023786) (xy 39.893746 -357.064982)
			(xy 39.923211 -357.110838) (xy 39.94585 -357.160421) (xy 39.961203 -357.21272) (xy 39.968956 -357.266673)
			(xy 39.969102 -357.274876) (xy 40.83177 -357.274876) (xy 40.832255 -357.247625) (xy 40.840015 -357.193679)
			(xy 40.855372 -357.141385) (xy 40.878014 -357.091809) (xy 40.907481 -357.04596) (xy 40.943172 -357.004771)
			(xy 40.984362 -356.96908) (xy 41.030211 -356.939613) (xy 41.079787 -356.916971) (xy 41.132081 -356.901614)
			(xy 41.186027 -356.893855) (xy 41.213278 -356.893368) (xy 41.240528 -356.893899) (xy 41.294472 -356.901652)
			(xy 41.346765 -356.917003) (xy 41.39634 -356.939639) (xy 41.44219 -356.969101) (xy 41.483379 -357.004788)
			(xy 41.519071 -357.045974) (xy 41.548538 -357.091819) (xy 41.571181 -357.141392) (xy 41.586539 -357.193683)
			(xy 41.594298 -357.247626) (xy 41.594786 -357.274876) (xy 41.594544 -357.293543) (xy 41.590858 -357.330695)
			(xy 41.58742 -357.349044) (xy 41.585129 -357.363318) (xy 41.587649 -357.3921) (xy 41.598137 -357.419022)
			(xy 41.615752 -357.441924) (xy 41.63908 -357.458969) (xy 41.666252 -357.468792) (xy 41.680638 -357.470202)
			(xy 41.70929 -357.472578) (xy 41.765453 -357.484869) (xy 41.819137 -357.505447) (xy 41.869127 -357.533844)
			(xy 41.914291 -357.569419) (xy 41.953607 -357.611366) (xy 41.986186 -357.658737) (xy 42.01129 -357.710459)
			(xy 42.028351 -357.765361) (xy 42.036983 -357.822202) (xy 42.037508 -357.850948) (xy 42.037067 -357.8782)
			(xy 42.029304 -357.93215) (xy 42.013943 -357.984445) (xy 41.991296 -358.034023) (xy 41.961825 -358.079873)
			(xy 41.926129 -358.121063) (xy 41.884934 -358.156753) (xy 41.839081 -358.186219) (xy 41.7895 -358.208859)
			(xy 41.737203 -358.224214) (xy 41.683252 -358.23197) (xy 41.656 -358.232456) (xy 41.628751 -358.231922)
			(xy 41.574807 -358.224167) (xy 41.522516 -358.208814) (xy 41.472942 -358.186177) (xy 41.427094 -358.156715)
			(xy 41.385905 -358.121029) (xy 41.350214 -358.079844) (xy 41.320746 -358.034) (xy 41.298102 -357.984429)
			(xy 41.282743 -357.93214) (xy 41.274981 -357.878197) (xy 41.274492 -357.850948) (xy 41.27473 -357.832281)
			(xy 41.278424 -357.79513) (xy 41.281858 -357.77678) (xy 41.284144 -357.762505) (xy 41.28163 -357.733721)
			(xy 41.271145 -357.706797) (xy 41.25353 -357.683894) (xy 41.2302 -357.666849) (xy 41.203027 -357.65703)
			(xy 41.18864 -357.655622) (xy 41.159985 -357.653254) (xy 41.103817 -357.64097) (xy 41.050129 -357.620398)
			(xy 41.000134 -357.592003) (xy 40.954967 -357.556428) (xy 40.915648 -357.514478) (xy 40.88307 -357.467103)
			(xy 40.857969 -357.415376) (xy 40.840913 -357.360469) (xy 40.83229 -357.303624) (xy 40.83177 -357.274876)
			(xy 39.969102 -357.274876) (xy 39.96944 -357.293926) (xy 39.969031 -357.319265) (xy 39.962318 -357.369495)
			(xy 39.949016 -357.418395) (xy 39.929357 -357.465104) (xy 39.903688 -357.508799) (xy 39.87246 -357.548712)
			(xy 39.854632 -357.566722) (xy 39.845256 -357.576494) (xy 39.831545 -357.599837) (xy 39.82444 -357.625959)
			(xy 39.824439 -357.653031) (xy 39.831541 -357.679154) (xy 39.84525 -357.702498) (xy 39.854632 -357.712264)
			(xy 39.872449 -357.730285) (xy 39.903676 -357.770195) (xy 39.929346 -357.813888) (xy 39.949006 -357.860595)
			(xy 39.962309 -357.909493) (xy 39.969023 -357.959722) (xy 39.969319 -357.977694) (xy 40.221914 -357.977694)
			(xy 40.225985 -357.922072) (xy 40.238111 -357.867635) (xy 40.258034 -357.815544) (xy 40.28533 -357.766909)
			(xy 40.319416 -357.722766) (xy 40.359565 -357.684057) (xy 40.404923 -357.651606) (xy 40.454523 -357.626105)
			(xy 40.507307 -357.608098) (xy 40.56215 -357.597968) (xy 40.617884 -357.595931) (xy 40.673321 -357.602031)
			(xy 40.727278 -357.616137) (xy 40.778607 -357.637949) (xy 40.826213 -357.667003) (xy 40.869081 -357.702678)
			(xy 40.906298 -357.744215) (xy 40.937071 -357.790728) (xy 40.960743 -357.841225) (xy 40.976811 -357.894632)
			(xy 40.984931 -357.949808) (xy 40.98544 -357.977694) (xy 40.984931 -358.00558) (xy 40.976811 -358.060756)
			(xy 40.960743 -358.114163) (xy 40.937071 -358.16466) (xy 40.906298 -358.211173) (xy 40.869081 -358.25271)
			(xy 40.826213 -358.288385) (xy 40.778607 -358.317439) (xy 40.727278 -358.339251) (xy 40.673321 -358.353357)
			(xy 40.617884 -358.359457) (xy 40.56215 -358.35742) (xy 40.507307 -358.34729) (xy 40.454523 -358.329283)
			(xy 40.404923 -358.303782) (xy 40.359565 -358.271331) (xy 40.319416 -358.232622) (xy 40.28533 -358.188479)
			(xy 40.258034 -358.139844) (xy 40.238111 -358.087753) (xy 40.225985 -358.033316) (xy 40.221914 -357.977694)
			(xy 39.969319 -357.977694) (xy 39.96944 -357.98506) (xy 39.968908 -358.01231) (xy 39.961157 -358.066257)
			(xy 39.945808 -358.118552) (xy 39.923172 -358.16813) (xy 39.893711 -358.213981) (xy 39.858025 -358.255174)
			(xy 39.816839 -358.290868) (xy 39.770993 -358.320337) (xy 39.721419 -358.342982) (xy 39.669128 -358.358342)
			(xy 39.615182 -358.366102) (xy 39.587932 -358.366568) (xy 39.559452 -358.365992) (xy 39.503124 -358.35752)
			(xy 39.44868 -358.340774) (xy 39.397329 -358.316125) (xy 39.350208 -358.284122) (xy 39.308365 -358.245473)
			(xy 39.272728 -358.201037) (xy 39.244088 -358.1518) (xy 39.233094 -358.125522) (xy 39.220394 -358.093264)
			(xy 39.055802 -358.093264) (xy 38.42258 -358.72674) (xy 38.42258 -359.74909) (xy 47.794164 -359.74909)
			(xy 47.794164 -358.32923) (xy 47.794747 -358.304245) (xy 47.804499 -358.255235) (xy 47.823614 -358.209066)
			(xy 47.851361 -358.167507) (xy 47.868586 -358.149398) (xy 48.668686 -357.349298) (xy 48.686797 -357.332076)
			(xy 48.728355 -357.304333) (xy 48.774525 -357.285225) (xy 48.823534 -357.275485) (xy 48.848518 -357.274876)
			(xy 48.894238 -357.274876) (xy 48.907192 -357.242872) (xy 48.918268 -357.216783) (xy 48.946968 -357.167914)
			(xy 48.982584 -357.12383) (xy 49.024333 -357.085503) (xy 49.071295 -357.053776) (xy 49.122435 -357.02935)
			(xy 49.176627 -357.012761) (xy 49.232677 -357.004375) (xy 49.261014 -357.003858) (xy 49.288264 -357.004365)
			(xy 49.342209 -357.012122) (xy 49.394502 -357.027477) (xy 49.444077 -357.050118) (xy 49.489925 -357.079582)
			(xy 49.531114 -357.115271) (xy 49.566806 -357.156459) (xy 49.596273 -357.202306) (xy 49.618916 -357.25188)
			(xy 49.634274 -357.304171) (xy 49.642034 -357.358116) (xy 49.642522 -357.385366) (xy 49.642079 -357.410704)
			(xy 49.635374 -357.460933) (xy 49.622079 -357.509833) (xy 49.602426 -357.556542) (xy 49.576763 -357.600238)
			(xy 49.54554 -357.640151) (xy 49.527714 -357.658162) (xy 49.518299 -357.667899) (xy 49.504594 -357.691253)
			(xy 49.497496 -357.717384) (xy 49.497502 -357.744462) (xy 49.504612 -357.77059) (xy 49.518328 -357.793937)
			(xy 49.527714 -357.803704) (xy 49.545547 -357.82171) (xy 49.576774 -357.861623) (xy 49.602441 -357.905319)
			(xy 49.622098 -357.952029) (xy 49.635398 -358.00093) (xy 49.635935 -358.00495) (xy 49.911272 -358.00495)
			(xy 49.911272 -357.95045) (xy 49.919027 -357.896506) (xy 49.93438 -357.844214) (xy 49.957018 -357.794639)
			(xy 49.986481 -357.74879) (xy 50.022168 -357.7076) (xy 50.063353 -357.671908) (xy 50.109199 -357.64244)
			(xy 50.158771 -357.619796) (xy 50.211061 -357.604437) (xy 50.265004 -357.596675) (xy 50.292254 -357.596186)
			(xy 50.32106 -357.596711) (xy 50.378016 -357.605388) (xy 50.433023 -357.62252) (xy 50.484832 -357.647721)
			(xy 50.532268 -357.680417) (xy 50.574256 -357.719867) (xy 50.609841 -357.765176) (xy 50.624486 -357.789988)
			(xy 50.707798 -357.7971) (xy 50.730404 -357.772208) (xy 50.740446 -357.761125) (xy 50.754329 -357.734658)
			(xy 50.759967 -357.705307) (xy 50.756878 -357.67558) (xy 50.745326 -357.648016) (xy 50.726298 -357.624968)
			(xy 50.714148 -357.616252) (xy 50.69202 -357.601012) (xy 50.651853 -357.565328) (xy 50.617087 -357.524363)
			(xy 50.588411 -357.478927) (xy 50.566391 -357.429918) (xy 50.551463 -357.378305) (xy 50.543921 -357.325108)
			(xy 50.54346 -357.298244) (xy 50.543946 -357.270993) (xy 50.551702 -357.217045) (xy 50.567057 -357.16475)
			(xy 50.589699 -357.115173) (xy 50.619165 -357.069323) (xy 50.654856 -357.028132) (xy 50.696047 -356.992441)
			(xy 50.741897 -356.962975) (xy 50.791474 -356.940333) (xy 50.843769 -356.924978) (xy 50.897717 -356.917222)
			(xy 50.952219 -356.917222) (xy 51.006167 -356.924978) (xy 51.058462 -356.940333) (xy 51.108039 -356.962975)
			(xy 51.153889 -356.992441) (xy 51.19508 -357.028132) (xy 51.230771 -357.069323) (xy 51.260237 -357.115173)
			(xy 51.282879 -357.16475) (xy 51.298234 -357.217045) (xy 51.30599 -357.270993) (xy 51.306476 -357.298244)
			(xy 51.305909 -357.327899) (xy 51.296725 -357.386495) (xy 51.278585 -357.442963) (xy 51.251926 -357.495945)
			(xy 51.217391 -357.544164) (xy 51.197002 -357.565706) (xy 51.186943 -357.576775) (xy 51.17306 -357.603246)
			(xy 51.167424 -357.632601) (xy 51.170516 -357.662332) (xy 51.182073 -357.689898) (xy 51.201106 -357.712946)
			(xy 51.213258 -357.721662) (xy 51.235394 -357.736891) (xy 51.275561 -357.772577) (xy 51.310325 -357.813544)
			(xy 51.339 -357.858982) (xy 51.361019 -357.907993) (xy 51.375946 -357.959607) (xy 51.383486 -358.012805)
			(xy 51.383946 -358.03967) (xy 51.383394 -358.066919) (xy 51.375643 -358.120862) (xy 51.360293 -358.173153)
			(xy 51.337658 -358.222728) (xy 51.308199 -358.268576) (xy 51.272514 -358.309766) (xy 51.231331 -358.345458)
			(xy 51.185487 -358.374926) (xy 51.135917 -358.397569) (xy 51.083629 -358.412928) (xy 51.029687 -358.420689)
			(xy 51.002438 -358.421178) (xy 50.97328 -358.420631) (xy 50.915643 -358.411762) (xy 50.860027 -358.394223)
			(xy 50.807728 -358.368424) (xy 50.759965 -358.334966) (xy 50.717851 -358.294628) (xy 50.69967 -358.271826)
			(xy 50.690711 -358.260963) (xy 50.668153 -358.244136) (xy 50.64186 -358.234099) (xy 50.613827 -358.231613)
			(xy 50.586179 -358.236866) (xy 50.561011 -358.24946) (xy 50.550318 -358.258618) (xy 50.529074 -358.27741)
			(xy 50.482094 -358.309185) (xy 50.430927 -358.333651) (xy 50.376701 -358.350272) (xy 50.320612 -358.358678)
			(xy 50.292254 -358.359202) (xy 50.265004 -358.358725) (xy 50.211061 -358.350963) (xy 50.158771 -358.335604)
			(xy 50.109199 -358.31296) (xy 50.063353 -358.283492) (xy 50.022168 -358.2478) (xy 49.986481 -358.20661)
			(xy 49.957018 -358.160761) (xy 49.93438 -358.111186) (xy 49.919027 -358.058894) (xy 49.911272 -358.00495)
			(xy 49.635935 -358.00495) (xy 49.642108 -358.051161) (xy 49.642522 -358.0765) (xy 49.642022 -358.103751)
			(xy 49.634266 -358.157697) (xy 49.618912 -358.209991) (xy 49.596272 -358.259567) (xy 49.566807 -358.305417)
			(xy 49.531117 -358.346607) (xy 49.489928 -358.382298) (xy 49.444079 -358.411765) (xy 49.394504 -358.434407)
			(xy 49.342211 -358.449763) (xy 49.288265 -358.457521) (xy 49.261014 -358.458008) (xy 49.232619 -358.457498)
			(xy 49.176457 -358.449075) (xy 49.122165 -358.432414) (xy 49.070947 -358.407883) (xy 49.023934 -358.376025)
			(xy 49.002696 -358.35717) (xy 48.966628 -358.32415) (xy 48.69434 -358.596692) (xy 48.69434 -359.461562)
			(xy 48.814482 -359.581704) (xy 53.73624 -359.581704) (xy 53.761234 -359.582382) (xy 53.810254 -359.592174)
			(xy 53.856425 -359.611336) (xy 53.897973 -359.639131) (xy 53.916072 -359.65638) (xy 54.84749 -360.587798)
			(xy 54.864715 -360.605905) (xy 54.892459 -360.647464) (xy 54.911566 -360.693635) (xy 54.921304 -360.742646)
			(xy 54.921912 -360.76763) (xy 54.921912 -364.592108) (xy 55.39308 -364.592108) (xy 55.397151 -364.536486)
			(xy 55.409277 -364.482049) (xy 55.4292 -364.429958) (xy 55.456496 -364.381323) (xy 55.490582 -364.33718)
			(xy 55.530731 -364.298471) (xy 55.576089 -364.26602) (xy 55.625689 -364.240519) (xy 55.678473 -364.222512)
			(xy 55.733316 -364.212382) (xy 55.78905 -364.210345) (xy 55.844487 -364.216445) (xy 55.898444 -364.230551)
			(xy 55.949773 -364.252363) (xy 55.997379 -364.281417) (xy 56.040247 -364.317092) (xy 56.077464 -364.358629)
			(xy 56.108237 -364.405142) (xy 56.131909 -364.455639) (xy 56.147977 -364.509046) (xy 56.156097 -364.564222)
			(xy 56.156606 -364.592108) (xy 56.156097 -364.619994) (xy 56.147977 -364.67517) (xy 56.131909 -364.728577)
			(xy 56.108237 -364.779074) (xy 56.077464 -364.825587) (xy 56.040247 -364.867124) (xy 55.997379 -364.902799)
			(xy 55.949773 -364.931853) (xy 55.898444 -364.953665) (xy 55.844487 -364.967771) (xy 55.78905 -364.973871)
			(xy 55.733316 -364.971834) (xy 55.678473 -364.961704) (xy 55.625689 -364.943697) (xy 55.576089 -364.918196)
			(xy 55.530731 -364.885745) (xy 55.490582 -364.847036) (xy 55.456496 -364.802893) (xy 55.4292 -364.754258)
			(xy 55.409277 -364.702167) (xy 55.397151 -364.64773) (xy 55.39308 -364.592108) (xy 54.921912 -364.592108)
			(xy 54.921912 -365.608108) (xy 55.39308 -365.608108) (xy 55.397151 -365.552486) (xy 55.409277 -365.498049)
			(xy 55.4292 -365.445958) (xy 55.456496 -365.397323) (xy 55.490582 -365.35318) (xy 55.530731 -365.314471)
			(xy 55.576089 -365.28202) (xy 55.625689 -365.256519) (xy 55.678473 -365.238512) (xy 55.733316 -365.228382)
			(xy 55.78905 -365.226345) (xy 55.844487 -365.232445) (xy 55.898444 -365.246551) (xy 55.949773 -365.268363)
			(xy 55.997379 -365.297417) (xy 56.040247 -365.333092) (xy 56.077464 -365.374629) (xy 56.108237 -365.421142)
			(xy 56.131909 -365.471639) (xy 56.147977 -365.525046) (xy 56.156097 -365.580222) (xy 56.156606 -365.608108)
			(xy 56.156097 -365.635994) (xy 56.147977 -365.69117) (xy 56.131909 -365.744577) (xy 56.108237 -365.795074)
			(xy 56.077464 -365.841587) (xy 56.040247 -365.883124) (xy 55.997379 -365.918799) (xy 55.949773 -365.947853)
			(xy 55.898444 -365.969665) (xy 55.844487 -365.983771) (xy 55.78905 -365.989871) (xy 55.733316 -365.987834)
			(xy 55.678473 -365.977704) (xy 55.625689 -365.959697) (xy 55.576089 -365.934196) (xy 55.530731 -365.901745)
			(xy 55.490582 -365.863036) (xy 55.456496 -365.818893) (xy 55.4292 -365.770258) (xy 55.409277 -365.718167)
			(xy 55.397151 -365.66373) (xy 55.39308 -365.608108) (xy 54.921912 -365.608108) (xy 54.921912 -366.624108)
			(xy 55.39308 -366.624108) (xy 55.397151 -366.568486) (xy 55.409277 -366.514049) (xy 55.4292 -366.461958)
			(xy 55.456496 -366.413323) (xy 55.490582 -366.36918) (xy 55.530731 -366.330471) (xy 55.576089 -366.29802)
			(xy 55.625689 -366.272519) (xy 55.678473 -366.254512) (xy 55.733316 -366.244382) (xy 55.78905 -366.242345)
			(xy 55.844487 -366.248445) (xy 55.898444 -366.262551) (xy 55.949773 -366.284363) (xy 55.997379 -366.313417)
			(xy 56.040247 -366.349092) (xy 56.077464 -366.390629) (xy 56.108237 -366.437142) (xy 56.131909 -366.487639)
			(xy 56.147977 -366.541046) (xy 56.156097 -366.596222) (xy 56.156606 -366.624108) (xy 56.156097 -366.651994)
			(xy 56.147977 -366.70717) (xy 56.131909 -366.760577) (xy 56.108237 -366.811074) (xy 56.077464 -366.857587)
			(xy 56.040247 -366.899124) (xy 55.997379 -366.934799) (xy 55.949773 -366.963853) (xy 55.898444 -366.985665)
			(xy 55.844487 -366.999771) (xy 55.78905 -367.005871) (xy 55.733316 -367.003834) (xy 55.678473 -366.993704)
			(xy 55.625689 -366.975697) (xy 55.576089 -366.950196) (xy 55.530731 -366.917745) (xy 55.490582 -366.879036)
			(xy 55.456496 -366.834893) (xy 55.4292 -366.786258) (xy 55.409277 -366.734167) (xy 55.397151 -366.67973)
			(xy 55.39308 -366.624108) (xy 54.921912 -366.624108) (xy 54.921912 -366.86363) (xy 56.051958 -367.993676)
			(xy 56.069184 -368.011782) (xy 56.096924 -368.053343) (xy 56.116031 -368.099514) (xy 56.12577 -368.148524)
			(xy 56.12638 -368.173508) (xy 56.12638 -369.117118) (xy 56.16829 -369.124738) (xy 56.194361 -369.129917)
			(xy 56.244866 -369.146484) (xy 56.292581 -369.169904) (xy 56.33658 -369.199724) (xy 56.376012 -369.235366)
			(xy 56.410112 -369.276138) (xy 56.438219 -369.321252) (xy 56.459788 -369.369831) (xy 56.474402 -369.420935)
			(xy 56.481777 -369.473574) (xy 56.482234 -369.50015) (xy 56.481698 -369.5274) (xy 56.473949 -369.581347)
			(xy 56.4586 -369.633642) (xy 56.435966 -369.683221) (xy 56.406505 -369.729073) (xy 56.370819 -369.770265)
			(xy 56.329634 -369.80596) (xy 56.283787 -369.835429) (xy 56.234214 -369.858074) (xy 56.181922 -369.873433)
			(xy 56.127976 -369.881193) (xy 56.100726 -369.881658) (xy 56.074347 -369.881216) (xy 56.022091 -369.873955)
			(xy 55.971332 -369.859567) (xy 55.923038 -369.838327) (xy 55.878129 -369.810639) (xy 55.837461 -369.77703)
			(xy 55.801807 -369.738142) (xy 55.771849 -369.694715) (xy 55.759604 -369.671346) (xy 55.752902 -369.658987)
			(xy 55.733927 -369.638259) (xy 55.710013 -369.623497) (xy 55.682977 -369.615825) (xy 55.654875 -369.615825)
			(xy 55.627839 -369.623497) (xy 55.603925 -369.638259) (xy 55.58495 -369.658987) (xy 55.578248 -369.671346)
			(xy 55.566006 -369.694716) (xy 55.536042 -369.738138) (xy 55.500386 -369.777022) (xy 55.459716 -369.810627)
			(xy 55.414808 -369.838314) (xy 55.366516 -369.859554) (xy 55.315759 -369.873945) (xy 55.263505 -369.881211)
			(xy 55.237126 -369.881658) (xy 55.209872 -369.88122) (xy 55.155917 -369.873466) (xy 55.103616 -369.85811)
			(xy 55.054032 -369.835467) (xy 55.008177 -369.805997) (xy 54.966982 -369.770301) (xy 54.931288 -369.729104)
			(xy 54.901821 -369.683247) (xy 54.879181 -369.633662) (xy 54.863829 -369.581359) (xy 54.856078 -369.527405)
			(xy 54.855618 -369.50015) (xy 54.85603 -369.472893) (xy 54.86377 -369.418931) (xy 54.879113 -369.366621)
			(xy 54.901748 -369.317029) (xy 54.931212 -369.271163) (xy 54.966905 -369.22996) (xy 55.008102 -369.194258)
			(xy 55.053961 -369.164785) (xy 55.103549 -369.14214) (xy 55.155856 -369.126786) (xy 55.18277 -369.122452)
			(xy 55.226204 -369.116102) (xy 55.226204 -368.436398) (xy 54.106826 -367.316766) (xy 54.089617 -367.298645)
			(xy 54.061874 -367.257089) (xy 54.042764 -367.210922) (xy 54.033018 -367.161917) (xy 54.032404 -367.136934)
			(xy 54.032404 -361.04576) (xy 53.468524 -360.48188) (xy 48.526954 -360.48188) (xy 48.501971 -360.48127)
			(xy 48.452963 -360.471524) (xy 48.406794 -360.452417) (xy 48.365233 -360.424679) (xy 48.347122 -360.407458)
			(xy 47.868586 -359.928922) (xy 47.851366 -359.91081) (xy 47.823623 -359.869252) (xy 47.804514 -359.823083)
			(xy 47.794774 -359.774074) (xy 47.794164 -359.74909) (xy 38.42258 -359.74909) (xy 38.42258 -361.049316)
			(xy 38.985952 -361.049316) (xy 38.986493 -361.022067) (xy 38.994246 -360.968123) (xy 39.009597 -360.915832)
			(xy 39.032234 -360.866258) (xy 39.061695 -360.820409) (xy 39.09738 -360.77922) (xy 39.138564 -360.743528)
			(xy 39.184409 -360.714061) (xy 39.23398 -360.691417) (xy 39.286269 -360.676058) (xy 39.340211 -360.668297)
			(xy 39.36746 -360.667808) (xy 39.394829 -360.668296) (xy 39.449008 -360.676108) (xy 39.501511 -360.691592)
			(xy 39.551258 -360.714429) (xy 39.597226 -360.744149) (xy 39.618158 -360.761788) (xy 39.629486 -360.771024)
			(xy 39.656043 -360.7832) (xy 39.68496 -360.787373) (xy 39.713877 -360.7832) (xy 39.740434 -360.771024)
			(xy 39.751762 -360.761788) (xy 39.772696 -360.744151) (xy 39.818668 -360.71444) (xy 39.868416 -360.691603)
			(xy 39.920916 -360.676112) (xy 39.975091 -360.668283) (xy 40.00246 -360.667808) (xy 40.031376 -360.668352)
			(xy 40.088546 -360.677075) (xy 40.143745 -360.694328) (xy 40.195706 -360.719715) (xy 40.243241 -360.752654)
			(xy 40.285259 -360.792391) (xy 40.30345 -360.814874) (xy 40.313347 -360.826679) (xy 40.338671 -360.844198)
			(xy 40.368064 -360.853374) (xy 40.398856 -360.853374) (xy 40.428249 -360.844198) (xy 40.453573 -360.826679)
			(xy 40.46347 -360.814874) (xy 40.481671 -360.792399) (xy 40.52369 -360.752665) (xy 40.571223 -360.719726)
			(xy 40.623182 -360.694336) (xy 40.678377 -360.677077) (xy 40.735545 -360.668345) (xy 40.76446 -360.667808)
			(xy 40.791713 -360.668293) (xy 40.845664 -360.676045) (xy 40.897962 -360.691396) (xy 40.947543 -360.714035)
			(xy 40.993397 -360.743501) (xy 41.034591 -360.779192) (xy 41.070285 -360.820384) (xy 41.099753 -360.866236)
			(xy 41.122395 -360.915815) (xy 41.13775 -360.968113) (xy 41.145506 -361.022063) (xy 41.145968 -361.049316)
			(xy 41.145407 -361.078446) (xy 41.136539 -361.136027) (xy 41.119011 -361.191589) (xy 41.093232 -361.243835)
			(xy 41.059802 -361.29155) (xy 41.04005 -361.312968) (xy 41.031213 -361.322807) (xy 41.018431 -361.345945)
			(xy 41.012034 -361.371593) (xy 41.012456 -361.398024) (xy 41.019666 -361.423456) (xy 41.033179 -361.446175)
			(xy 41.042336 -361.455716) (xy 41.063488 -361.477374) (xy 41.089422 -361.512612) (xy 44.706032 -361.512612)
			(xy 44.706601 -361.483444) (xy 44.715499 -361.425789) (xy 44.733074 -361.370162) (xy 44.758916 -361.317861)
			(xy 44.792423 -361.270106) (xy 44.832811 -361.228011) (xy 44.855638 -361.209844) (xy 44.866037 -361.201446)
			(xy 44.882331 -361.180263) (xy 44.892574 -361.155579) (xy 44.896065 -361.129083) (xy 44.892565 -361.102588)
			(xy 44.882314 -361.077908) (xy 44.866013 -361.05673) (xy 44.855638 -361.0483) (xy 44.832794 -361.03015)
			(xy 44.792392 -360.988061) (xy 44.758878 -360.940306) (xy 44.733034 -360.888) (xy 44.715466 -360.832365)
			(xy 44.706583 -360.774703) (xy 44.706032 -360.745532) (xy 44.706485 -360.718278) (xy 44.714239 -360.664325)
			(xy 44.729593 -360.612024) (xy 44.752235 -360.562442) (xy 44.781703 -360.516586) (xy 44.817398 -360.475392)
			(xy 44.858593 -360.439698) (xy 44.904449 -360.410231) (xy 44.954032 -360.38759) (xy 45.006333 -360.372237)
			(xy 45.060286 -360.364485) (xy 45.08754 -360.364024) (xy 45.116456 -360.364576) (xy 45.173626 -360.373297)
			(xy 45.228824 -360.390547) (xy 45.280786 -360.415933) (xy 45.328321 -360.448871) (xy 45.370339 -360.488607)
			(xy 45.38853 -360.51109) (xy 45.398427 -360.522895) (xy 45.423751 -360.540414) (xy 45.453144 -360.54959)
			(xy 45.483936 -360.54959) (xy 45.513329 -360.540414) (xy 45.538653 -360.522895) (xy 45.54855 -360.51109)
			(xy 45.566767 -360.488628) (xy 45.608781 -360.448892) (xy 45.656311 -360.415951) (xy 45.708267 -360.390559)
			(xy 45.76346 -360.373298) (xy 45.820626 -360.364563) (xy 45.84954 -360.364024) (xy 45.878086 -360.364584)
			(xy 45.934539 -360.373094) (xy 45.989094 -360.389919) (xy 46.040535 -360.414683) (xy 46.064424 -360.430318)
			(xy 46.075556 -360.4374) (xy 46.100412 -360.446212) (xy 46.126699 -360.448341) (xy 46.152649 -360.443643)
			(xy 46.176521 -360.432435) (xy 46.196711 -360.415469) (xy 46.204632 -360.404918) (xy 46.22004 -360.383903)
			(xy 46.255641 -360.345851) (xy 46.296087 -360.312995) (xy 46.340626 -360.285946) (xy 46.38843 -360.265206)
			(xy 46.438611 -360.251161) (xy 46.490235 -360.244072) (xy 46.51629 -360.243628) (xy 46.545207 -360.244143)
			(xy 46.602379 -360.252871) (xy 46.657578 -360.270129) (xy 46.70954 -360.295521) (xy 46.757074 -360.328466)
			(xy 46.79909 -360.368208) (xy 46.81728 -360.390694) (xy 46.827177 -360.402499) (xy 46.852501 -360.420018)
			(xy 46.881894 -360.429194) (xy 46.912686 -360.429194) (xy 46.942079 -360.420018) (xy 46.967403 -360.402499)
			(xy 46.9773 -360.390694) (xy 46.995489 -360.368209) (xy 47.03751 -360.328474) (xy 47.085045 -360.295536)
			(xy 47.137007 -360.270148) (xy 47.192204 -360.252892) (xy 47.249374 -360.244163) (xy 47.27829 -360.243628)
			(xy 47.305544 -360.244065) (xy 47.359498 -360.251821) (xy 47.411799 -360.267178) (xy 47.461381 -360.289822)
			(xy 47.507236 -360.319292) (xy 47.54843 -360.354989) (xy 47.584123 -360.396185) (xy 47.613591 -360.442042)
			(xy 47.636231 -360.491626) (xy 47.651584 -360.543927) (xy 47.659337 -360.597882) (xy 47.659798 -360.625136)
			(xy 47.659322 -360.651178) (xy 47.652244 -360.702778) (xy 47.638212 -360.752936) (xy 47.617485 -360.800718)
			(xy 47.59045 -360.845235) (xy 47.557609 -360.88566) (xy 47.538894 -360.903774) (xy 47.528968 -360.91375)
			(xy 47.514501 -360.937875) (xy 47.507156 -360.965029) (xy 47.507487 -360.993157) (xy 47.515471 -361.020131)
			(xy 47.530501 -361.043909) (xy 47.540672 -361.053634) (xy 47.56026 -361.07179) (xy 47.59465 -361.112652)
			(xy 47.623006 -361.157912) (xy 47.644772 -361.206684) (xy 47.659523 -361.258015) (xy 47.666971 -361.310902)
			(xy 47.667418 -361.337606) (xy 47.66692 -361.365376) (xy 47.658866 -361.420328) (xy 47.64293 -361.473533)
			(xy 47.619447 -361.523864) (xy 47.588915 -361.570258) (xy 47.551979 -361.611735) (xy 47.53102 -361.62996)
			(xy 47.520368 -361.639481) (xy 47.504384 -361.663145) (xy 47.495592 -361.690314) (xy 47.494682 -361.718856)
			(xy 47.501726 -361.74653) (xy 47.516171 -361.771164) (xy 47.526194 -361.781344) (xy 47.544559 -361.799414)
			(xy 47.576728 -361.839658) (xy 47.603195 -361.883862) (xy 47.623477 -361.931223) (xy 47.637207 -361.980882)
			(xy 47.644135 -362.031935) (xy 47.644558 -362.057696) (xy 47.6441 -362.085067) (xy 47.636282 -362.139246)
			(xy 47.620791 -362.19175) (xy 47.597948 -362.241497) (xy 47.568221 -362.287463) (xy 47.550578 -362.308394)
			(xy 47.541347 -362.319725) (xy 47.529172 -362.346282) (xy 47.524999 -362.375197) (xy 47.52917 -362.404112)
			(xy 47.541343 -362.43067) (xy 47.550578 -362.441998) (xy 47.568215 -362.462934) (xy 47.597939 -362.508901)
			(xy 47.620784 -362.558647) (xy 47.636281 -362.611149) (xy 47.64411 -362.665327) (xy 47.64411 -362.720067)
			(xy 47.636282 -362.774245) (xy 47.620787 -362.826747) (xy 47.597942 -362.876493) (xy 47.568218 -362.922461)
			(xy 47.550578 -362.943394) (xy 47.541347 -362.954725) (xy 47.529172 -362.981282) (xy 47.524999 -363.010197)
			(xy 47.52917 -363.039112) (xy 47.541343 -363.06567) (xy 47.550578 -363.076998) (xy 47.568215 -363.097934)
			(xy 47.597939 -363.143901) (xy 47.620784 -363.193647) (xy 47.636281 -363.246149) (xy 47.63987 -363.270984)
			(xy 48.72126 -363.270984) (xy 48.72126 -363.186288) (xy 48.729311 -363.101974) (xy 48.74534 -363.018808)
			(xy 48.769201 -362.937541) (xy 48.80068 -362.858911) (xy 48.839491 -362.78363) (xy 48.885281 -362.712378)
			(xy 48.937637 -362.645802) (xy 48.996085 -362.584504) (xy 49.060095 -362.529039) (xy 49.129087 -362.47991)
			(xy 49.202437 -362.437561) (xy 49.27948 -362.402377) (xy 49.359519 -362.374675) (xy 49.441828 -362.354707)
			(xy 49.525663 -362.342654) (xy 49.610264 -362.338624) (xy 49.694865 -362.342654) (xy 49.7787 -362.354707)
			(xy 49.861009 -362.374675) (xy 49.941048 -362.402377) (xy 50.018091 -362.437561) (xy 50.091441 -362.47991)
			(xy 50.160433 -362.529039) (xy 50.224443 -362.584504) (xy 50.282891 -362.645802) (xy 50.335247 -362.712378)
			(xy 50.381037 -362.78363) (xy 50.419848 -362.858911) (xy 50.451327 -362.937541) (xy 50.475188 -363.018808)
			(xy 50.491217 -363.101974) (xy 50.499268 -363.186288) (xy 50.499772 -363.228636) (xy 51.245773 -363.228636)
			(xy 51.249809 -363.145189) (xy 51.261881 -363.062521) (xy 51.281874 -362.981404) (xy 51.309603 -362.902595)
			(xy 51.344809 -362.82683) (xy 51.387163 -362.754817) (xy 51.436269 -362.687228) (xy 51.49167 -362.624694)
			(xy 51.552847 -362.567799) (xy 51.61923 -362.517073) (xy 51.690198 -362.472992) (xy 51.76509 -362.435966)
			(xy 51.843206 -362.40634) (xy 51.923816 -362.384392) (xy 52.006168 -362.370327) (xy 52.089494 -362.364275)
			(xy 52.173014 -362.366294) (xy 52.25595 -362.376364) (xy 52.337526 -362.394392) (xy 52.416982 -362.420209)
			(xy 52.493575 -362.453574) (xy 52.566591 -362.494175) (xy 52.635347 -362.541634) (xy 52.699201 -362.595507)
			(xy 52.757558 -362.655292) (xy 52.809873 -362.720429) (xy 52.855656 -362.790312) (xy 52.894481 -362.864287)
			(xy 52.925986 -362.941664) (xy 52.949875 -363.021721) (xy 52.965926 -363.103709) (xy 52.973989 -363.186864)
			(xy 52.974494 -363.228636) (xy 52.973989 -363.270408) (xy 52.965926 -363.353563) (xy 52.949875 -363.435551)
			(xy 52.925986 -363.515608) (xy 52.894481 -363.592985) (xy 52.855656 -363.66696) (xy 52.809873 -363.736843)
			(xy 52.757558 -363.80198) (xy 52.699201 -363.861765) (xy 52.635347 -363.915638) (xy 52.566591 -363.963097)
			(xy 52.493575 -364.003698) (xy 52.416982 -364.037063) (xy 52.337526 -364.06288) (xy 52.25595 -364.080908)
			(xy 52.173014 -364.090978) (xy 52.089494 -364.092997) (xy 52.006168 -364.086945) (xy 51.923816 -364.07288)
			(xy 51.843206 -364.050932) (xy 51.76509 -364.021306) (xy 51.690198 -363.98428) (xy 51.61923 -363.940199)
			(xy 51.552847 -363.889473) (xy 51.49167 -363.832578) (xy 51.436269 -363.770044) (xy 51.387163 -363.702455)
			(xy 51.344809 -363.630442) (xy 51.309603 -363.554677) (xy 51.281874 -363.475868) (xy 51.261881 -363.394751)
			(xy 51.249809 -363.312083) (xy 51.245773 -363.228636) (xy 50.499772 -363.228636) (xy 50.499268 -363.270984)
			(xy 50.491217 -363.355298) (xy 50.475188 -363.438464) (xy 50.451327 -363.519731) (xy 50.419848 -363.598361)
			(xy 50.381037 -363.673642) (xy 50.335247 -363.744894) (xy 50.282891 -363.81147) (xy 50.224443 -363.872768)
			(xy 50.160433 -363.928233) (xy 50.091441 -363.977362) (xy 50.018091 -364.019711) (xy 49.941048 -364.054895)
			(xy 49.861009 -364.082597) (xy 49.7787 -364.102565) (xy 49.694865 -364.114618) (xy 49.610264 -364.118649)
			(xy 49.525663 -364.114618) (xy 49.441828 -364.102565) (xy 49.359519 -364.082597) (xy 49.27948 -364.054895)
			(xy 49.202437 -364.019711) (xy 49.129087 -363.977362) (xy 49.060095 -363.928233) (xy 48.996085 -363.872768)
			(xy 48.937637 -363.81147) (xy 48.885281 -363.744894) (xy 48.839491 -363.673642) (xy 48.80068 -363.598361)
			(xy 48.769201 -363.519731) (xy 48.74534 -363.438464) (xy 48.729311 -363.355298) (xy 48.72126 -363.270984)
			(xy 47.63987 -363.270984) (xy 47.64411 -363.300327) (xy 47.64411 -363.355067) (xy 47.636282 -363.409245)
			(xy 47.620787 -363.461747) (xy 47.597942 -363.511493) (xy 47.568218 -363.557461) (xy 47.550578 -363.578394)
			(xy 47.541347 -363.589725) (xy 47.529172 -363.616282) (xy 47.524999 -363.645197) (xy 47.52917 -363.674112)
			(xy 47.541343 -363.70067) (xy 47.550578 -363.711998) (xy 47.568226 -363.732923) (xy 47.597937 -363.778897)
			(xy 47.620772 -363.828647) (xy 47.636261 -363.881149) (xy 47.644086 -363.935326) (xy 47.644558 -363.962696)
			(xy 47.644141 -363.989951) (xy 47.636383 -364.043906) (xy 47.621025 -364.096208) (xy 47.598379 -364.145791)
			(xy 47.568907 -364.191647) (xy 47.533208 -364.232841) (xy 47.49201 -364.268535) (xy 47.446151 -364.298001)
			(xy 47.396565 -364.320641) (xy 47.344261 -364.335993) (xy 47.290305 -364.343744) (xy 47.26305 -364.344204)
			(xy 47.234133 -364.343686) (xy 47.17696 -364.334962) (xy 47.121759 -364.317706) (xy 47.069797 -364.292315)
			(xy 47.022263 -364.259369) (xy 46.980249 -364.219625) (xy 46.96206 -364.197138) (xy 46.952163 -364.185333)
			(xy 46.926839 -364.167814) (xy 46.897446 -364.158638) (xy 46.866654 -364.158638) (xy 46.837261 -364.167814)
			(xy 46.811937 -364.185333) (xy 46.80204 -364.197138) (xy 46.783836 -364.21961) (xy 46.741818 -364.259344)
			(xy 46.694285 -364.292284) (xy 46.642327 -364.317674) (xy 46.587132 -364.334933) (xy 46.529965 -364.343666)
			(xy 46.50105 -364.344204) (xy 46.473798 -364.343698) (xy 46.419849 -364.335948) (xy 46.367551 -364.320598)
			(xy 46.317971 -364.297961) (xy 46.272117 -364.268498) (xy 46.230924 -364.232808) (xy 46.19523 -364.191619)
			(xy 46.165761 -364.145769) (xy 46.143118 -364.096192) (xy 46.127762 -364.043896) (xy 46.120005 -363.989948)
			(xy 46.119542 -363.962696) (xy 46.119995 -363.935325) (xy 46.127815 -363.881145) (xy 46.143306 -363.828642)
			(xy 46.166151 -363.778895) (xy 46.195879 -363.732929) (xy 46.213522 -363.711998) (xy 46.222761 -363.700673)
			(xy 46.234935 -363.674114) (xy 46.239106 -363.645197) (xy 46.234933 -363.61628) (xy 46.222758 -363.589722)
			(xy 46.213522 -363.578394) (xy 46.195878 -363.557464) (xy 46.166153 -363.511496) (xy 46.143309 -363.461749)
			(xy 46.127813 -363.409247) (xy 46.119985 -363.355068) (xy 46.119985 -363.300326) (xy 46.127814 -363.246148)
			(xy 46.143311 -363.193645) (xy 46.166156 -363.143899) (xy 46.195881 -363.097931) (xy 46.213522 -363.076998)
			(xy 46.222761 -363.065673) (xy 46.234935 -363.039114) (xy 46.239106 -363.010197) (xy 46.234933 -362.98128)
			(xy 46.222758 -362.954722) (xy 46.213522 -362.943394) (xy 46.195878 -362.922464) (xy 46.166153 -362.876496)
			(xy 46.143309 -362.826749) (xy 46.127813 -362.774247) (xy 46.119985 -362.720068) (xy 46.119985 -362.665326)
			(xy 46.127814 -362.611148) (xy 46.143311 -362.558645) (xy 46.166156 -362.508899) (xy 46.195881 -362.462931)
			(xy 46.213522 -362.441998) (xy 46.222761 -362.430673) (xy 46.234935 -362.404114) (xy 46.239106 -362.375197)
			(xy 46.234933 -362.34628) (xy 46.222758 -362.319722) (xy 46.213522 -362.308394) (xy 46.19587 -362.287472)
			(xy 46.166159 -362.241497) (xy 46.143326 -362.191747) (xy 46.127838 -362.139244) (xy 46.120014 -362.085066)
			(xy 46.119542 -362.057696) (xy 46.119779 -362.038641) (xy 46.123595 -362.000723) (xy 46.127162 -361.982004)
			(xy 46.129464 -361.968526) (xy 46.127624 -361.941254) (xy 46.118615 -361.915448) (xy 46.103081 -361.892958)
			(xy 46.082137 -361.875395) (xy 46.057284 -361.864018) (xy 46.030303 -361.859643) (xy 46.003128 -361.862584)
			(xy 45.990256 -361.867196) (xy 45.967794 -361.875742) (xy 45.921251 -361.887724) (xy 45.87357 -361.893759)
			(xy 45.84954 -361.89412) (xy 45.820623 -361.893603) (xy 45.76345 -361.884878) (xy 45.70825 -361.867622)
			(xy 45.656288 -361.84223) (xy 45.608754 -361.809285) (xy 45.566739 -361.769541) (xy 45.54855 -361.747054)
			(xy 45.538653 -361.735249) (xy 45.513329 -361.71773) (xy 45.483936 -361.708554) (xy 45.453144 -361.708554)
			(xy 45.423751 -361.71773) (xy 45.398427 -361.735249) (xy 45.38853 -361.747054) (xy 45.370336 -361.769534)
			(xy 45.328315 -361.809267) (xy 45.28078 -361.842205) (xy 45.22882 -361.867593) (xy 45.173624 -361.884851)
			(xy 45.116456 -361.893583) (xy 45.08754 -361.89412) (xy 45.060289 -361.893608) (xy 45.00634 -361.885856)
			(xy 44.954044 -361.870506) (xy 44.904465 -361.847869) (xy 44.858612 -361.818406) (xy 44.817419 -361.782718)
			(xy 44.781725 -361.74153) (xy 44.752256 -361.695681) (xy 44.729612 -361.646105) (xy 44.714255 -361.593811)
			(xy 44.706496 -361.539863) (xy 44.706032 -361.512612) (xy 41.089422 -361.512612) (xy 41.09937 -361.526129)
			(xy 41.127101 -361.579939) (xy 41.145985 -361.637453) (xy 41.155547 -361.697228) (xy 41.156128 -361.727496)
			(xy 41.155677 -361.754867) (xy 41.147858 -361.809047) (xy 41.132367 -361.861551) (xy 41.109521 -361.911298)
			(xy 41.079792 -361.957264) (xy 41.062148 -361.978194) (xy 41.052919 -361.989526) (xy 41.040748 -362.016083)
			(xy 41.036577 -362.044997) (xy 41.040746 -362.073911) (xy 41.052916 -362.100469) (xy 41.062148 -362.111798)
			(xy 41.079786 -362.132733) (xy 41.109513 -362.1787) (xy 41.13236 -362.228446) (xy 41.147857 -362.280948)
			(xy 41.155687 -362.335126) (xy 41.155687 -362.389868) (xy 41.147859 -362.444046) (xy 41.132362 -362.496549)
			(xy 41.109516 -362.546295) (xy 41.079789 -362.592262) (xy 41.062148 -362.613194) (xy 41.052919 -362.624526)
			(xy 41.040748 -362.651083) (xy 41.036577 -362.679997) (xy 41.040746 -362.708911) (xy 41.052916 -362.735469)
			(xy 41.062148 -362.746798) (xy 41.079792 -362.767727) (xy 41.109504 -362.8137) (xy 41.13234 -362.863448)
			(xy 41.14783 -362.91595) (xy 41.155656 -362.970126) (xy 41.156128 -362.997496) (xy 41.155634 -363.026414)
			(xy 41.146904 -363.083588) (xy 41.129643 -363.138788) (xy 41.104247 -363.19075) (xy 41.071298 -363.238283)
			(xy 41.031551 -363.280298) (xy 41.009062 -363.298486) (xy 40.997256 -363.308385) (xy 40.97973 -363.333706)
			(xy 40.970549 -363.3631) (xy 40.970548 -363.393895) (xy 40.979728 -363.42329) (xy 40.997253 -363.448611)
			(xy 41.009062 -363.458506) (xy 41.02984 -363.475265) (xy 41.066968 -363.513618) (xy 41.098388 -363.556773)
			(xy 41.123486 -363.603885) (xy 41.141771 -363.654037) (xy 41.152887 -363.706247) (xy 41.156617 -363.759498)
			(xy 41.152888 -363.812748) (xy 41.141773 -363.864959) (xy 41.123488 -363.91511) (xy 41.098391 -363.962223)
			(xy 41.066972 -364.005378) (xy 41.029844 -364.043732) (xy 41.009062 -364.060486) (xy 40.997256 -364.070385)
			(xy 40.97973 -364.095706) (xy 40.970549 -364.1251) (xy 40.970548 -364.155895) (xy 40.979728 -364.18529)
			(xy 40.997253 -364.210611) (xy 41.009062 -364.220506) (xy 41.03154 -364.238703) (xy 41.071278 -364.280721)
			(xy 41.104218 -364.328254) (xy 41.129608 -364.380214) (xy 41.146865 -364.435411) (xy 41.155593 -364.49258)
			(xy 41.156128 -364.521496) (xy 41.155566 -364.550626) (xy 41.146699 -364.608208) (xy 41.129172 -364.66377)
			(xy 41.103393 -364.716016) (xy 41.069963 -364.763731) (xy 41.05021 -364.785148) (xy 41.039828 -364.796775)
			(xy 41.026037 -364.824712) (xy 41.021295 -364.855504) (xy 41.02604 -364.886296) (xy 41.039833 -364.914232)
			(xy 41.05021 -364.925864) (xy 41.069921 -364.947315) (xy 41.10333 -364.995035) (xy 41.129104 -365.047275)
			(xy 41.146646 -365.102823) (xy 41.15555 -365.16039) (xy 41.156128 -365.189516) (xy 41.155637 -365.216767)
			(xy 41.147879 -365.270713) (xy 41.132523 -365.323007) (xy 41.109881 -365.372583) (xy 41.080415 -365.418432)
			(xy 41.044724 -365.459622) (xy 41.003535 -365.495313) (xy 40.957686 -365.524779) (xy 40.90811 -365.547421)
			(xy 40.855817 -365.562778) (xy 40.801871 -365.570537) (xy 40.77462 -365.571024) (xy 40.745702 -365.57052)
			(xy 40.688529 -365.561792) (xy 40.633329 -365.544533) (xy 40.581366 -365.519139) (xy 40.533833 -365.486192)
			(xy 40.491818 -365.446446) (xy 40.47363 -365.423958) (xy 40.463733 -365.412153) (xy 40.438409 -365.394634)
			(xy 40.409016 -365.385458) (xy 40.378224 -365.385458) (xy 40.348831 -365.394634) (xy 40.323507 -365.412153)
			(xy 40.31361 -365.423958) (xy 40.295403 -365.446428) (xy 40.253388 -365.486166) (xy 40.205856 -365.519108)
			(xy 40.153898 -365.544499) (xy 40.098703 -365.561757) (xy 40.041535 -365.570488) (xy 40.01262 -365.571024)
			(xy 39.985249 -365.570565) (xy 39.931069 -365.562748) (xy 39.878565 -365.547258) (xy 39.828818 -365.524415)
			(xy 39.782853 -365.494687) (xy 39.761922 -365.477044) (xy 39.750594 -365.467808) (xy 39.724037 -365.455632)
			(xy 39.69512 -365.451459) (xy 39.666203 -365.455632) (xy 39.639646 -365.467808) (xy 39.628318 -365.477044)
			(xy 39.607396 -365.494695) (xy 39.56142 -365.524404) (xy 39.51167 -365.547237) (xy 39.459167 -365.562725)
			(xy 39.40499 -365.570551) (xy 39.37762 -365.571024) (xy 39.350368 -365.570526) (xy 39.29642 -365.562772)
			(xy 39.244123 -365.54742) (xy 39.194544 -365.524781) (xy 39.148692 -365.495316) (xy 39.107499 -365.459626)
			(xy 39.071805 -365.418437) (xy 39.042337 -365.372587) (xy 39.019693 -365.32301) (xy 39.004335 -365.270716)
			(xy 38.996576 -365.216768) (xy 38.996112 -365.189516) (xy 38.996698 -365.160387) (xy 39.005561 -365.102807)
			(xy 39.023083 -365.047246) (xy 39.048857 -364.994999) (xy 39.082281 -364.947283) (xy 39.10203 -364.925864)
			(xy 39.112397 -364.914226) (xy 39.126184 -364.886292) (xy 39.130927 -364.855504) (xy 39.126186 -364.824716)
			(xy 39.112402 -364.796781) (xy 39.10203 -364.785148) (xy 39.082267 -364.763743) (xy 39.048868 -364.71601)
			(xy 39.023104 -364.663758) (xy 39.005574 -364.6082) (xy 38.996683 -364.550625) (xy 38.996112 -364.521496)
			(xy 38.996623 -364.492579) (xy 39.005353 -364.435407) (xy 39.022612 -364.380208) (xy 39.048005 -364.328246)
			(xy 39.08095 -364.280713) (xy 39.120692 -364.238696) (xy 39.143178 -364.220506) (xy 39.154988 -364.210613)
			(xy 39.172507 -364.185289) (xy 39.181683 -364.155894) (xy 39.181682 -364.125101) (xy 39.172505 -364.095707)
			(xy 39.154984 -364.070383) (xy 39.143178 -364.060486) (xy 39.12239 -364.043738) (xy 39.085258 -364.005385)
			(xy 39.053835 -363.96223) (xy 39.028735 -363.915116) (xy 39.010448 -363.864963) (xy 38.999331 -363.81275)
			(xy 38.995601 -363.759498) (xy 38.999331 -363.706245) (xy 39.010449 -363.654032) (xy 39.028737 -363.60388)
			(xy 39.053838 -363.556766) (xy 39.085261 -363.513611) (xy 39.122394 -363.475259) (xy 39.143178 -363.458506)
			(xy 39.154988 -363.448613) (xy 39.172507 -363.423289) (xy 39.181683 -363.393894) (xy 39.181682 -363.363101)
			(xy 39.172505 -363.333707) (xy 39.154984 -363.308383) (xy 39.143178 -363.298486) (xy 39.120683 -363.280308)
			(xy 39.08095 -363.238285) (xy 39.048013 -363.190747) (xy 39.022626 -363.138784) (xy 39.005372 -363.083584)
			(xy 38.996646 -363.026413) (xy 38.996112 -362.997496) (xy 38.996573 -362.970126) (xy 39.004391 -362.915946)
			(xy 39.019882 -362.863443) (xy 39.042725 -362.813696) (xy 39.07245 -362.767729) (xy 39.090092 -362.746798)
			(xy 39.099333 -362.735474) (xy 39.111511 -362.708915) (xy 39.115683 -362.679997) (xy 39.11151 -362.651079)
			(xy 39.09933 -362.624521) (xy 39.090092 -362.613194) (xy 39.072449 -362.592264) (xy 39.042727 -362.546295)
			(xy 39.019884 -362.496548) (xy 39.004389 -362.444046) (xy 38.996562 -362.389867) (xy 38.996562 -362.335127)
			(xy 39.004391 -362.280948) (xy 39.019886 -362.228447) (xy 39.04273 -362.1787) (xy 39.072452 -362.132731)
			(xy 39.090092 -362.111798) (xy 39.099333 -362.100474) (xy 39.111511 -362.073915) (xy 39.115683 -362.044997)
			(xy 39.11151 -362.016079) (xy 39.09933 -361.989521) (xy 39.090092 -361.978194) (xy 39.072435 -361.957276)
			(xy 39.042726 -361.911299) (xy 39.019894 -361.861548) (xy 39.004407 -361.809044) (xy 38.996584 -361.754866)
			(xy 38.996112 -361.727496) (xy 38.996686 -361.698366) (xy 39.005552 -361.640786) (xy 39.023077 -361.585225)
			(xy 39.048853 -361.532978) (xy 39.08228 -361.485263) (xy 39.10203 -361.463844) (xy 39.110857 -361.453996)
			(xy 39.123643 -361.430861) (xy 39.130042 -361.405215) (xy 39.129623 -361.378785) (xy 39.122414 -361.353354)
			(xy 39.108901 -361.330636) (xy 39.099744 -361.321096) (xy 39.078595 -361.299436) (xy 39.042713 -361.250681)
			(xy 39.014981 -361.196872) (xy 38.996097 -361.139358) (xy 38.986534 -361.079583) (xy 38.985952 -361.049316)
			(xy 38.42258 -361.049316) (xy 38.42258 -365.713772) (xy 38.56074 -365.851948) (xy 41.654982 -365.851948)
			(xy 41.659053 -365.796326) (xy 41.671179 -365.741889) (xy 41.691102 -365.689798) (xy 41.718398 -365.641163)
			(xy 41.752484 -365.59702) (xy 41.792633 -365.558311) (xy 41.837991 -365.52586) (xy 41.887591 -365.500359)
			(xy 41.940375 -365.482352) (xy 41.995218 -365.472222) (xy 42.050952 -365.470185) (xy 42.106389 -365.476285)
			(xy 42.160346 -365.490391) (xy 42.211675 -365.512203) (xy 42.259281 -365.541257) (xy 42.302149 -365.576932)
			(xy 42.339366 -365.618469) (xy 42.370139 -365.664982) (xy 42.393811 -365.715479) (xy 42.409879 -365.768886)
			(xy 42.417999 -365.824062) (xy 42.418508 -365.851948) (xy 42.417999 -365.879834) (xy 42.409879 -365.93501)
			(xy 42.393811 -365.988417) (xy 42.370139 -366.038914) (xy 42.339366 -366.085427) (xy 42.302149 -366.126964)
			(xy 42.259281 -366.162639) (xy 42.211675 -366.191693) (xy 42.160346 -366.213505) (xy 42.106389 -366.227611)
			(xy 42.050952 -366.233711) (xy 41.995218 -366.231674) (xy 41.940375 -366.221544) (xy 41.887591 -366.203537)
			(xy 41.837991 -366.178036) (xy 41.792633 -366.145585) (xy 41.752484 -366.106876) (xy 41.718398 -366.062733)
			(xy 41.691102 -366.014098) (xy 41.671179 -365.962007) (xy 41.659053 -365.90757) (xy 41.654982 -365.851948)
			(xy 38.56074 -365.851948) (xy 40.67683 -367.968276) (xy 43.74261 -367.968276) (xy 43.74896 -367.924588)
			(xy 43.753269 -367.897652) (xy 43.768588 -367.845297) (xy 43.791207 -367.795657) (xy 43.820664 -367.749744)
			(xy 43.85636 -367.708494) (xy 43.897566 -367.672748) (xy 43.943442 -367.643234) (xy 43.993054 -367.620553)
			(xy 44.04539 -367.605169) (xy 44.099383 -367.597395) (xy 44.126658 -367.596928) (xy 44.153911 -367.597394)
			(xy 44.207864 -367.605147) (xy 44.260164 -367.620499) (xy 44.309747 -367.643139) (xy 44.355602 -367.672606)
			(xy 44.396796 -367.7083) (xy 44.43249 -367.749494) (xy 44.461958 -367.795348) (xy 44.484599 -367.84493)
			(xy 44.499952 -367.89723) (xy 44.507705 -367.951183) (xy 44.508166 -367.978436) (xy 44.507743 -368.004816)
			(xy 44.500485 -368.057076) (xy 44.486098 -368.107837) (xy 44.464857 -368.156133) (xy 44.437166 -368.201043)
			(xy 44.403553 -368.241711) (xy 44.36466 -368.277362) (xy 44.321226 -368.307317) (xy 44.297854 -368.319558)
			(xy 44.285462 -368.326205) (xy 44.264725 -368.345188) (xy 44.24996 -368.369113) (xy 44.242289 -368.396159)
			(xy 44.242293 -368.424273) (xy 44.249973 -368.451317) (xy 44.264746 -368.475237) (xy 44.285489 -368.494214)
			(xy 44.297854 -368.500914) (xy 44.32121 -368.513181) (xy 44.364631 -368.543142) (xy 44.403515 -368.578795)
			(xy 44.437121 -368.619461) (xy 44.464809 -368.664366) (xy 44.486052 -368.712654) (xy 44.500446 -368.763407)
			(xy 44.507717 -368.815659) (xy 44.508166 -368.842036) (xy 44.507778 -368.869292) (xy 44.500016 -368.923248)
			(xy 44.484653 -368.975549) (xy 44.462003 -369.025133) (xy 44.432527 -369.070988) (xy 44.396826 -369.112181)
			(xy 44.355625 -369.147874) (xy 44.309764 -369.17734) (xy 44.260176 -369.19998) (xy 44.207871 -369.215332)
			(xy 44.153914 -369.223084) (xy 44.126658 -369.223544) (xy 44.100321 -369.223079) (xy 44.048145 -369.215853)
			(xy 43.997461 -369.201515) (xy 43.949231 -369.18034) (xy 43.904374 -369.152729) (xy 43.863743 -369.119209)
			(xy 43.828111 -369.080416) (xy 43.798156 -369.037089) (xy 43.774448 -368.990052) (xy 43.757438 -368.940201)
			(xy 43.752008 -368.914426) (xy 43.744134 -368.873024) (xy 40.410384 -368.873024) (xy 40.3854 -368.872411)
			(xy 40.336392 -368.86267) (xy 40.290222 -368.843563) (xy 40.248662 -368.815824) (xy 40.230552 -368.798602)
			(xy 37.594286 -366.162336) (xy 37.577073 -366.144218) (xy 37.549328 -366.102662) (xy 37.530218 -366.056495)
			(xy 37.520475 -366.007487) (xy 37.519864 -365.982504) (xy 33.709356 -365.982504) (xy 40.1828 -372.455948)
			(xy 57.277 -372.455948)
		)
		(stroke
			(width 0)
			(type solid)
		)
		(fill yes)
		(layer "In6.Cu")
		(net "GND")
	)
	(gr_poly
		(pts
			(xy 348.526354 -236.37748) (xy 348.543562 -236.358988) (xy 348.582597 -236.326932) (xy 348.626056 -236.301191)
			(xy 348.672927 -236.282363) (xy 348.722117 -236.270888) (xy 348.77248 -236.267033) (xy 348.822843 -236.270888)
			(xy 348.872033 -236.282363) (xy 348.918904 -236.301191) (xy 348.962363 -236.326932) (xy 349.001398 -236.358988)
			(xy 349.018606 -236.37748) (xy 349.466154 -236.37748) (xy 349.483362 -236.358988) (xy 349.522397 -236.326932)
			(xy 349.565856 -236.301191) (xy 349.612727 -236.282363) (xy 349.661917 -236.270888) (xy 349.71228 -236.267033)
			(xy 349.762643 -236.270888) (xy 349.811833 -236.282363) (xy 349.858704 -236.301191) (xy 349.902163 -236.326932)
			(xy 349.941198 -236.358988) (xy 349.958406 -236.37748) (xy 350.492822 -236.37748) (xy 350.502982 -236.339888)
			(xy 350.510057 -236.315465) (xy 350.53067 -236.268986) (xy 350.558158 -236.226212) (xy 350.591875 -236.188153)
			(xy 350.631023 -236.155709) (xy 350.674679 -236.129644) (xy 350.721813 -236.110574) (xy 350.771311 -236.098949)
			(xy 350.822006 -236.095043) (xy 350.872701 -236.098949) (xy 350.922199 -236.110574) (xy 350.969333 -236.129644)
			(xy 351.012989 -236.155709) (xy 351.052137 -236.188153) (xy 351.085854 -236.226212) (xy 351.113342 -236.268986)
			(xy 351.133955 -236.315465) (xy 351.14103 -236.339888) (xy 351.15119 -236.37748) (xy 352.130106 -236.37748)
			(xy 352.728784 -235.778802) (xy 352.728784 -233.763566) (xy 352.728228 -233.74836) (xy 352.719285 -233.719292)
			(xy 352.702175 -233.69415) (xy 352.678415 -233.675166) (xy 352.650117 -233.664026) (xy 352.619792 -233.661719)
			(xy 352.604832 -233.664506) (xy 352.586849 -233.668317) (xy 352.550315 -233.672391) (xy 352.531934 -233.672634)
			(xy 352.505965 -233.672154) (xy 352.454664 -233.664033) (xy 352.405266 -233.647988) (xy 352.358987 -233.624411)
			(xy 352.316965 -233.593885) (xy 352.280237 -233.55716) (xy 352.249707 -233.515142) (xy 352.226125 -233.468865)
			(xy 352.210074 -233.419469) (xy 352.201949 -233.368169) (xy 352.201949 -233.316231) (xy 352.210074 -233.264931)
			(xy 352.226125 -233.215535) (xy 352.249707 -233.169258) (xy 352.280237 -233.12724) (xy 352.316965 -233.090515)
			(xy 352.358987 -233.059989) (xy 352.405266 -233.036412) (xy 352.454664 -233.020367) (xy 352.505965 -233.012246)
			(xy 352.531934 -233.011726) (xy 352.550314 -233.011977) (xy 352.586848 -233.016049) (xy 352.604832 -233.019854)
			(xy 352.619789 -233.022651) (xy 352.650112 -233.020319) (xy 352.678406 -233.009169) (xy 352.702168 -232.990189)
			(xy 352.719294 -232.965057) (xy 352.728268 -232.936) (xy 352.728784 -232.920794) (xy 352.728784 -232.714546)
			(xy 352.715244 -232.693847) (xy 352.693802 -232.649276) (xy 352.679237 -232.602009) (xy 352.671875 -232.5531)
			(xy 352.671879 -232.50364) (xy 352.67925 -232.454733) (xy 352.693824 -232.407468) (xy 352.715274 -232.362902)
			(xy 352.728784 -232.342182) (xy 352.728784 -232.135934) (xy 352.728223 -232.120731) (xy 352.719276 -232.091672)
			(xy 352.702164 -232.066538) (xy 352.678407 -232.047562) (xy 352.650114 -232.036426) (xy 352.619796 -232.034119)
			(xy 352.604832 -232.036874) (xy 352.586786 -232.040695) (xy 352.550124 -232.044768) (xy 352.53168 -232.045002)
			(xy 352.50571 -232.044491) (xy 352.45441 -232.036363) (xy 352.405013 -232.02031) (xy 352.358735 -231.996728)
			(xy 352.316716 -231.966197) (xy 352.27999 -231.929469) (xy 352.249461 -231.887448) (xy 352.225882 -231.841169)
			(xy 352.209832 -231.791771) (xy 352.201707 -231.74047) (xy 352.201707 -231.68853) (xy 352.209832 -231.637229)
			(xy 352.225882 -231.587831) (xy 352.249461 -231.541552) (xy 352.27999 -231.499531) (xy 352.316716 -231.462803)
			(xy 352.358735 -231.432272) (xy 352.405013 -231.40869) (xy 352.45441 -231.392637) (xy 352.50571 -231.384509)
			(xy 352.53168 -231.384094) (xy 352.550124 -231.384334) (xy 352.586786 -231.388406) (xy 352.604832 -231.392222)
			(xy 352.619788 -231.395019) (xy 352.650107 -231.392688) (xy 352.678398 -231.381538) (xy 352.702156 -231.362556)
			(xy 352.719276 -231.337424) (xy 352.728242 -231.308366) (xy 352.728784 -231.293162) (xy 352.728784 -231.08666)
			(xy 352.715243 -231.065961) (xy 352.693799 -231.02139) (xy 352.679232 -230.974122) (xy 352.671868 -230.925212)
			(xy 352.671871 -230.875751) (xy 352.67924 -230.826842) (xy 352.693812 -230.779576) (xy 352.715262 -230.735008)
			(xy 352.728784 -230.714296) (xy 352.728784 -229.945946) (xy 352.665284 -229.882446) (xy 351.880678 -229.882446)
			(xy 351.880678 -229.88143) (xy 351.502726 -229.503478) (xy 351.492946 -229.494274) (xy 351.469673 -229.480888)
			(xy 351.443718 -229.474026) (xy 351.41687 -229.47416) (xy 351.390985 -229.481281) (xy 351.367847 -229.494899)
			(xy 351.3582 -229.50424) (xy 351.339427 -229.522656) (xy 351.297124 -229.553892) (xy 351.250405 -229.57803)
			(xy 351.200452 -229.59446) (xy 351.148527 -229.602767) (xy 351.122234 -229.6033) (xy 351.096264 -229.602793)
			(xy 351.044962 -229.594674) (xy 350.995562 -229.578628) (xy 350.94928 -229.555053) (xy 350.907256 -229.524528)
			(xy 350.870524 -229.487805) (xy 350.839989 -229.445788) (xy 350.816402 -229.399512) (xy 350.800345 -229.350116)
			(xy 350.792213 -229.298816) (xy 350.79178 -229.272846) (xy 350.792291 -229.246553) (xy 350.800621 -229.194632)
			(xy 350.817062 -229.144683) (xy 350.8412 -229.097965) (xy 350.872427 -229.055655) (xy 350.89084 -229.03688)
			(xy 350.900148 -229.027198) (xy 350.913781 -229.004069) (xy 350.920918 -228.978186) (xy 350.921067 -228.951338)
			(xy 350.914218 -228.925378) (xy 350.900842 -228.902098) (xy 350.891602 -228.892354) (xy 350.76892 -228.769672)
			(xy 350.740218 -228.777546) (xy 350.718616 -228.783148) (xy 350.674394 -228.789143) (xy 350.65208 -228.789484)
			(xy 350.626113 -228.788973) (xy 350.574819 -228.780847) (xy 350.525427 -228.764797) (xy 350.479153 -228.741218)
			(xy 350.437138 -228.710692) (xy 350.400414 -228.67397) (xy 350.369887 -228.631955) (xy 350.346307 -228.585682)
			(xy 350.330256 -228.536291) (xy 350.322128 -228.484997) (xy 350.321626 -228.45903) (xy 350.321998 -228.436719)
			(xy 350.327993 -228.3925) (xy 350.333564 -228.370892) (xy 350.341438 -228.34219) (xy 350.066864 -228.067616)
			(xy 350.066864 -227.95611) (xy 350.038162 -227.942394) (xy 350.014617 -227.930374) (xy 349.971355 -227.899997)
			(xy 349.933477 -227.863124) (xy 349.901947 -227.820694) (xy 349.877571 -227.773789) (xy 349.860967 -227.723602)
			(xy 349.852559 -227.671413) (xy 349.852562 -227.618552) (xy 349.860975 -227.566364) (xy 349.877584 -227.516179)
			(xy 349.901966 -227.469276) (xy 349.9335 -227.426849) (xy 349.971382 -227.38998) (xy 350.014647 -227.359608)
			(xy 350.038162 -227.347526) (xy 350.066864 -227.33381) (xy 350.066864 -227.073206) (xy 350.002094 -227.007674)
			(xy 349.964502 -227.044758) (xy 349.962978 -227.046282) (xy 349.947221 -227.064039) (xy 349.911488 -227.095294)
			(xy 349.871648 -227.12111) (xy 349.828522 -227.140956) (xy 349.782999 -227.154422) (xy 349.736017 -227.161231)
			(xy 349.71228 -227.161598) (xy 349.686313 -227.161087) (xy 349.635017 -227.152961) (xy 349.585625 -227.136911)
			(xy 349.53935 -227.113333) (xy 349.497334 -227.082807) (xy 349.460609 -227.046085) (xy 349.43008 -227.00407)
			(xy 349.406498 -226.957798) (xy 349.390445 -226.908406) (xy 349.382315 -226.857111) (xy 349.381826 -226.831144)
			(xy 349.382284 -226.8062) (xy 349.389787 -226.75688) (xy 349.404613 -226.709246) (xy 349.426426 -226.66438)
			(xy 349.454732 -226.623299) (xy 349.488887 -226.586937) (xy 349.528117 -226.556118) (xy 349.571531 -226.531542)
			(xy 349.618145 -226.513766) (xy 349.64243 -226.508056) (xy 349.655646 -226.504753) (xy 349.679789 -226.492159)
			(xy 349.699736 -226.473621) (xy 349.714063 -226.450463) (xy 349.721746 -226.424339) (xy 349.722238 -226.397113)
			(xy 349.715504 -226.370728) (xy 349.702024 -226.347067) (xy 349.692722 -226.337114) (xy 349.61322 -226.257612)
			(xy 349.603656 -226.248615) (xy 349.580977 -226.235397) (xy 349.555672 -226.22842) (xy 349.529424 -226.228148)
			(xy 349.50398 -226.234598) (xy 349.481031 -226.247341) (xy 349.471234 -226.256088) (xy 349.452657 -226.273199)
			(xy 349.411277 -226.302154) (xy 349.365975 -226.324479) (xy 349.317804 -226.339654) (xy 349.267886 -226.347325)
			(xy 349.242634 -226.347782) (xy 349.216662 -226.347302) (xy 349.165357 -226.339181) (xy 349.115954 -226.323135)
			(xy 349.06967 -226.299557) (xy 349.027644 -226.26903) (xy 348.990911 -226.232303) (xy 348.960375 -226.190283)
			(xy 348.936789 -226.144003) (xy 348.920733 -226.094603) (xy 348.912603 -226.0433) (xy 348.91218 -226.017328)
			(xy 348.912662 -225.992079) (xy 348.920345 -225.942167) (xy 348.935523 -225.894003) (xy 348.957842 -225.848704)
			(xy 348.986784 -225.807322) (xy 349.003874 -225.788728) (xy 349.012631 -225.778953) (xy 349.025303 -225.755981)
			(xy 349.031711 -225.730541) (xy 349.031432 -225.704308) (xy 349.024486 -225.679009) (xy 349.01133 -225.656312)
			(xy 349.00235 -225.646742) (xy 348.874588 -225.51898) (xy 348.847156 -225.52533) (xy 348.828751 -225.529363)
			(xy 348.79132 -225.533689) (xy 348.77248 -225.533966) (xy 348.746493 -225.533481) (xy 348.695159 -225.525347)
			(xy 348.64573 -225.509283) (xy 348.599423 -225.485683) (xy 348.557377 -225.45513) (xy 348.52063 -225.418375)
			(xy 348.490084 -225.376324) (xy 348.466493 -225.330013) (xy 348.450438 -225.28058) (xy 348.442314 -225.229245)
			(xy 348.441772 -225.203258) (xy 348.442362 -225.175213) (xy 348.451805 -225.119923) (xy 348.460568 -225.093276)
			(xy 348.468442 -225.071178) (xy 348.264988 -224.71888) (xy 348.242128 -224.714562) (xy 348.217163 -224.709424)
			(xy 348.169087 -224.692495) (xy 348.124179 -224.66839) (xy 348.083501 -224.637679) (xy 348.048017 -224.601091)
			(xy 348.018568 -224.559491) (xy 347.99585 -224.513865) (xy 347.980402 -224.465293) (xy 347.97259 -224.414927)
			(xy 347.972126 -224.389442) (xy 347.972636 -224.363455) (xy 347.980766 -224.31212) (xy 347.996827 -224.26269)
			(xy 348.020423 -224.21638) (xy 348.050973 -224.174332) (xy 348.087724 -224.137581) (xy 348.129772 -224.107031)
			(xy 348.176082 -224.083435) (xy 348.225512 -224.067374) (xy 348.276847 -224.059244) (xy 348.328821 -224.059244)
			(xy 348.380156 -224.067374) (xy 348.429586 -224.083435) (xy 348.475896 -224.107031) (xy 348.517944 -224.137581)
			(xy 348.554695 -224.174332) (xy 348.585245 -224.21638) (xy 348.608841 -224.26269) (xy 348.624902 -224.31212)
			(xy 348.633032 -224.363455) (xy 348.633542 -224.389442) (xy 348.632952 -224.417487) (xy 348.62351 -224.472777)
			(xy 348.614746 -224.499424) (xy 348.606872 -224.521522) (xy 348.810326 -224.87382) (xy 348.833186 -224.878138)
			(xy 348.865698 -224.886012) (xy 348.894654 -224.894394) (xy 349.010478 -224.77857) (xy 349.010478 -224.6249)
			(xy 348.992143 -224.606145) (xy 348.961049 -224.563907) (xy 348.937021 -224.517287) (xy 348.920662 -224.467456)
			(xy 348.912383 -224.415666) (xy 348.911926 -224.389442) (xy 348.91244 -224.362408) (xy 348.921199 -224.309056)
			(xy 348.938538 -224.257845) (xy 348.950788 -224.23374) (xy 348.968568 -224.20072) (xy 348.687898 -223.92005)
			(xy 348.687898 -223.896936) (xy 348.655132 -223.88449) (xy 348.631983 -223.875189) (xy 348.58856 -223.850631)
			(xy 348.549321 -223.819825) (xy 348.51516 -223.78347) (xy 348.486853 -223.742392) (xy 348.465042 -223.697526)
			(xy 348.450224 -223.649891) (xy 348.442736 -223.600569) (xy 348.44228 -223.575626) (xy 348.442716 -223.551531)
			(xy 348.449719 -223.503851) (xy 348.46358 -223.457697) (xy 348.484004 -223.414048) (xy 348.510558 -223.373833)
			(xy 348.542677 -223.337906) (xy 348.560898 -223.322134) (xy 348.571411 -223.312747) (xy 348.587259 -223.289454)
			(xy 348.596139 -223.262717) (xy 348.597377 -223.234571) (xy 348.590878 -223.207157) (xy 348.577136 -223.182562)
			(xy 348.567502 -223.172274) (xy 348.452948 -223.05772) (xy 348.422214 -223.069658) (xy 348.393464 -223.080036)
			(xy 348.333391 -223.091277) (xy 348.302834 -223.09201) (xy 348.276864 -223.09153) (xy 348.225564 -223.083409)
			(xy 348.176165 -223.067361) (xy 348.129886 -223.043783) (xy 348.087866 -223.013254) (xy 348.05114 -222.976526)
			(xy 348.020612 -222.934505) (xy 347.997035 -222.888225) (xy 347.980989 -222.838827) (xy 347.97287 -222.787526)
			(xy 347.97238 -222.761556) (xy 347.972634 -222.746316) (xy 347.972825 -222.732605) (xy 347.966767 -222.705871)
			(xy 347.953818 -222.681712) (xy 347.934909 -222.661868) (xy 347.911402 -222.647768) (xy 347.884992 -222.640428)
			(xy 347.871288 -222.63989) (xy 347.79458 -222.63989) (xy 347.780858 -222.640331) (xy 347.754403 -222.647635)
			(xy 347.730858 -222.661735) (xy 347.711931 -222.681607) (xy 347.698994 -222.705811) (xy 347.692986 -222.732589)
			(xy 347.693234 -222.746316) (xy 347.693488 -222.761556) (xy 347.692979 -222.787523) (xy 347.684854 -222.838818)
			(xy 347.668806 -222.888211) (xy 347.645228 -222.934485) (xy 347.614702 -222.976501) (xy 347.577979 -223.013224)
			(xy 347.535963 -223.04375) (xy 347.489689 -223.067328) (xy 347.440296 -223.083376) (xy 347.389001 -223.091501)
			(xy 347.337067 -223.091501) (xy 347.285772 -223.083376) (xy 347.236379 -223.067328) (xy 347.190105 -223.04375)
			(xy 347.148089 -223.013224) (xy 347.111366 -222.976501) (xy 347.08084 -222.934485) (xy 347.057262 -222.888211)
			(xy 347.041214 -222.838818) (xy 347.033089 -222.787523) (xy 347.03258 -222.761556) (xy 347.032834 -222.746316)
			(xy 347.033025 -222.732605) (xy 347.026967 -222.705871) (xy 347.014018 -222.681712) (xy 346.995109 -222.661868)
			(xy 346.971602 -222.647768) (xy 346.945192 -222.640428) (xy 346.931488 -222.63989) (xy 346.85478 -222.63989)
			(xy 346.841058 -222.640331) (xy 346.814603 -222.647635) (xy 346.791058 -222.661735) (xy 346.772131 -222.681607)
			(xy 346.759194 -222.705811) (xy 346.753186 -222.732589) (xy 346.753434 -222.746316) (xy 346.753688 -222.761556)
			(xy 346.753179 -222.787523) (xy 346.745054 -222.838818) (xy 346.729006 -222.888211) (xy 346.705428 -222.934485)
			(xy 346.674902 -222.976501) (xy 346.638179 -223.013224) (xy 346.596163 -223.04375) (xy 346.549889 -223.067328)
			(xy 346.500496 -223.083376) (xy 346.449201 -223.091501) (xy 346.397267 -223.091501) (xy 346.345972 -223.083376)
			(xy 346.296579 -223.067328) (xy 346.250305 -223.04375) (xy 346.208289 -223.013224) (xy 346.171566 -222.976501)
			(xy 346.14104 -222.934485) (xy 346.117462 -222.888211) (xy 346.101414 -222.838818) (xy 346.093289 -222.787523)
			(xy 346.09278 -222.761556) (xy 346.093034 -222.746316) (xy 346.093225 -222.732605) (xy 346.087167 -222.705871)
			(xy 346.074218 -222.681712) (xy 346.055309 -222.661868) (xy 346.031802 -222.647768) (xy 346.005392 -222.640428)
			(xy 345.991688 -222.63989) (xy 345.91498 -222.63989) (xy 345.901258 -222.640331) (xy 345.874803 -222.647635)
			(xy 345.851258 -222.661735) (xy 345.832331 -222.681607) (xy 345.819394 -222.705811) (xy 345.813386 -222.732589)
			(xy 345.813634 -222.746316) (xy 345.813888 -222.761556) (xy 345.813379 -222.787523) (xy 345.805254 -222.838818)
			(xy 345.789206 -222.888211) (xy 345.765628 -222.934485) (xy 345.735102 -222.976501) (xy 345.698379 -223.013224)
			(xy 345.656363 -223.04375) (xy 345.610089 -223.067328) (xy 345.560696 -223.083376) (xy 345.509401 -223.091501)
			(xy 345.457467 -223.091501) (xy 345.406172 -223.083376) (xy 345.356779 -223.067328) (xy 345.310505 -223.04375)
			(xy 345.268489 -223.013224) (xy 345.231766 -222.976501) (xy 345.20124 -222.934485) (xy 345.177662 -222.888211)
			(xy 345.161614 -222.838818) (xy 345.153489 -222.787523) (xy 345.15298 -222.761556) (xy 345.153479 -222.735676)
			(xy 345.161543 -222.684548) (xy 345.177484 -222.635304) (xy 345.20091 -222.589149) (xy 345.231249 -222.547213)
			(xy 345.267757 -222.510522) (xy 345.288362 -222.494856) (xy 345.299704 -222.485935) (xy 345.317291 -222.463077)
			(xy 345.327794 -222.436216) (xy 345.330374 -222.40749) (xy 345.324827 -222.379187) (xy 345.311594 -222.35356)
			(xy 345.302078 -222.34271) (xy 345.302078 -222.337122) (xy 345.301607 -222.322437) (xy 345.293276 -222.294273)
			(xy 345.277269 -222.269649) (xy 345.254913 -222.250602) (xy 345.228058 -222.238712) (xy 345.198928 -222.234963)
			(xy 345.169937 -222.239664) (xy 345.156536 -222.245682) (xy 345.134077 -222.255982) (xy 345.086849 -222.270492)
			(xy 345.037984 -222.277798) (xy 345.01328 -222.278194) (xy 344.987313 -222.277683) (xy 344.936018 -222.269557)
			(xy 344.886625 -222.253507) (xy 344.840351 -222.229929) (xy 344.798335 -222.199403) (xy 344.76161 -222.16268)
			(xy 344.731082 -222.120666) (xy 344.707501 -222.074393) (xy 344.691448 -222.025002) (xy 344.683318 -221.973707)
			(xy 344.682826 -221.94774) (xy 344.683436 -221.919759) (xy 344.692882 -221.8646) (xy 344.701622 -221.838012)
			(xy 344.709242 -221.815914) (xy 344.505534 -221.463108) (xy 344.482674 -221.45879) (xy 344.457743 -221.453641)
			(xy 344.409738 -221.436703) (xy 344.3649 -221.412601) (xy 344.32429 -221.381906) (xy 344.288869 -221.345344)
			(xy 344.259477 -221.303782) (xy 344.236809 -221.258202) (xy 344.221401 -221.209684) (xy 344.213618 -221.159377)
			(xy 344.21318 -221.133924) (xy 344.213689 -221.107957) (xy 344.221814 -221.056662) (xy 344.237862 -221.007269)
			(xy 344.26144 -220.960995) (xy 344.291966 -220.918979) (xy 344.328689 -220.882256) (xy 344.370705 -220.85173)
			(xy 344.416979 -220.828152) (xy 344.466372 -220.812104) (xy 344.517667 -220.803979) (xy 344.569601 -220.803979)
			(xy 344.620896 -220.812104) (xy 344.670289 -220.828152) (xy 344.716563 -220.85173) (xy 344.758579 -220.882256)
			(xy 344.795302 -220.918979) (xy 344.825828 -220.960995) (xy 344.849406 -221.007269) (xy 344.865454 -221.056662)
			(xy 344.873579 -221.107957) (xy 344.874088 -221.133924) (xy 344.873473 -221.161904) (xy 344.864017 -221.21706)
			(xy 344.855292 -221.243652) (xy 344.847672 -221.26575) (xy 345.05138 -221.618556) (xy 345.07424 -221.622874)
			(xy 345.095525 -221.627202) (xy 345.136807 -221.640711) (xy 345.156536 -221.649798) (xy 345.169969 -221.655708)
			(xy 345.198933 -221.660364) (xy 345.228026 -221.656599) (xy 345.25485 -221.644722) (xy 345.277194 -221.625713)
			(xy 345.293216 -221.601139) (xy 345.301595 -221.573025) (xy 345.302078 -221.558358) (xy 345.302078 -221.410276)
			(xy 345.279591 -221.394823) (xy 345.239542 -221.357775) (xy 345.206115 -221.314657) (xy 345.180217 -221.266638)
			(xy 345.16255 -221.21502) (xy 345.153593 -221.161203) (xy 345.15298 -221.133924) (xy 345.15334 -221.112464)
			(xy 345.158951 -221.069911) (xy 345.164156 -221.049088) (xy 345.171522 -221.020894) (xy 344.776298 -220.62567)
			(xy 344.198956 -220.62567) (xy 344.19032 -220.628972) (xy 344.176678 -220.633991) (xy 344.148695 -220.641874)
			(xy 344.13444 -220.64472) (xy 344.11158 -220.649038) (xy 343.907872 -221.002098) (xy 343.915492 -221.024196)
			(xy 343.924284 -221.050771) (xy 343.93373 -221.105938) (xy 343.934288 -221.133924) (xy 343.933779 -221.159891)
			(xy 343.925654 -221.211186) (xy 343.909606 -221.260579) (xy 343.886028 -221.306853) (xy 343.855502 -221.348869)
			(xy 343.818779 -221.385592) (xy 343.776763 -221.416118) (xy 343.730489 -221.439696) (xy 343.681096 -221.455744)
			(xy 343.629801 -221.463869) (xy 343.577867 -221.463869) (xy 343.526572 -221.455744) (xy 343.477179 -221.439696)
			(xy 343.430905 -221.416118) (xy 343.388889 -221.385592) (xy 343.352166 -221.348869) (xy 343.32164 -221.306853)
			(xy 343.298062 -221.260579) (xy 343.282014 -221.211186) (xy 343.273889 -221.159891) (xy 343.27338 -221.133924)
			(xy 343.273854 -221.108477) (xy 343.281665 -221.058187) (xy 343.297089 -221.009687) (xy 343.319764 -220.964124)
			(xy 343.349153 -220.922574) (xy 343.384562 -220.886018) (xy 343.425155 -220.85532) (xy 343.469973 -220.831206)
			(xy 343.517956 -220.814243) (xy 343.542874 -220.809058) (xy 343.565734 -220.80474) (xy 343.769442 -220.45168)
			(xy 343.761822 -220.429582) (xy 343.753032 -220.403007) (xy 343.743589 -220.347839) (xy 343.743026 -220.319854)
			(xy 343.743172 -220.306523) (xy 343.745334 -220.279948) (xy 343.747344 -220.266768) (xy 343.751408 -220.24086)
			(xy 343.173558 -219.66301) (xy 342.954864 -219.66301) (xy 342.942384 -219.685151) (xy 342.911683 -219.725652)
			(xy 342.875142 -219.760976) (xy 342.833625 -219.79029) (xy 342.78811 -219.812902) (xy 342.739669 -219.82828)
			(xy 342.689445 -219.83606) (xy 342.638623 -219.83606) (xy 342.588399 -219.82828) (xy 342.539958 -219.812902)
			(xy 342.494443 -219.79029) (xy 342.452926 -219.760976) (xy 342.416385 -219.725652) (xy 342.385684 -219.685151)
			(xy 342.373204 -219.66301) (xy 342.015064 -219.66301) (xy 342.002584 -219.685151) (xy 341.971883 -219.725652)
			(xy 341.935342 -219.760976) (xy 341.893825 -219.79029) (xy 341.84831 -219.812902) (xy 341.799869 -219.82828)
			(xy 341.749645 -219.83606) (xy 341.698823 -219.83606) (xy 341.648599 -219.82828) (xy 341.600158 -219.812902)
			(xy 341.554643 -219.79029) (xy 341.513126 -219.760976) (xy 341.476585 -219.725652) (xy 341.445884 -219.685151)
			(xy 341.433404 -219.66301) (xy 341.075264 -219.66301) (xy 341.062784 -219.685151) (xy 341.032083 -219.725652)
			(xy 340.995542 -219.760976) (xy 340.954025 -219.79029) (xy 340.90851 -219.812902) (xy 340.860069 -219.82828)
			(xy 340.809845 -219.83606) (xy 340.759023 -219.83606) (xy 340.708799 -219.82828) (xy 340.660358 -219.812902)
			(xy 340.614843 -219.79029) (xy 340.573326 -219.760976) (xy 340.536785 -219.725652) (xy 340.506084 -219.685151)
			(xy 340.493604 -219.66301) (xy 340.135464 -219.66301) (xy 340.122984 -219.685151) (xy 340.092283 -219.725652)
			(xy 340.055742 -219.760976) (xy 340.014225 -219.79029) (xy 339.96871 -219.812902) (xy 339.920269 -219.82828)
			(xy 339.870045 -219.83606) (xy 339.819223 -219.83606) (xy 339.768999 -219.82828) (xy 339.720558 -219.812902)
			(xy 339.675043 -219.79029) (xy 339.633526 -219.760976) (xy 339.596985 -219.725652) (xy 339.566284 -219.685151)
			(xy 339.553804 -219.66301) (xy 339.195664 -219.66301) (xy 339.183186 -219.685151) (xy 339.152486 -219.725653)
			(xy 339.115946 -219.760976) (xy 339.074428 -219.790288) (xy 339.028911 -219.812896) (xy 338.98047 -219.828267)
			(xy 338.930245 -219.836039) (xy 338.904834 -219.836492) (xy 338.878864 -219.835985) (xy 338.827563 -219.827865)
			(xy 338.778163 -219.81182) (xy 338.731882 -219.788245) (xy 338.689858 -219.75772) (xy 338.653127 -219.720997)
			(xy 338.622593 -219.67898) (xy 338.599007 -219.632704) (xy 338.582951 -219.583308) (xy 338.57482 -219.532008)
			(xy 338.57438 -219.506038) (xy 338.57438 -219.498164) (xy 338.574888 -219.47632) (xy 338.174838 -219.07627)
			(xy 337.95589 -219.07627) (xy 337.95589 -219.172536) (xy 338.001102 -219.177616) (xy 338.027726 -219.181069)
			(xy 338.079438 -219.195482) (xy 338.128141 -219.218064) (xy 338.172553 -219.248221) (xy 338.211506 -219.28516)
			(xy 338.243977 -219.32791) (xy 338.269111 -219.375346) (xy 338.286246 -219.426221) (xy 338.294933 -219.479196)
			(xy 338.295488 -219.506038) (xy 338.294979 -219.532005) (xy 338.286854 -219.5833) (xy 338.270806 -219.632693)
			(xy 338.247228 -219.678967) (xy 338.216702 -219.720983) (xy 338.179979 -219.757706) (xy 338.137963 -219.788232)
			(xy 338.091689 -219.81181) (xy 338.042296 -219.827858) (xy 337.991001 -219.835983) (xy 337.939067 -219.835983)
			(xy 337.887772 -219.827858) (xy 337.838379 -219.81181) (xy 337.792105 -219.788232) (xy 337.750089 -219.757706)
			(xy 337.713366 -219.720983) (xy 337.68284 -219.678967) (xy 337.659262 -219.632693) (xy 337.643214 -219.5833)
			(xy 337.635089 -219.532005) (xy 337.63458 -219.506038) (xy 337.634997 -219.482274) (xy 337.641818 -219.435237)
			(xy 337.65531 -219.389663) (xy 337.675194 -219.346494) (xy 337.701061 -219.30662) (xy 337.732375 -219.270865)
			(xy 337.75015 -219.255086) (xy 337.760308 -219.245796) (xy 337.775675 -219.222972) (xy 337.784388 -219.196872)
			(xy 337.785811 -219.169393) (xy 337.779843 -219.142532) (xy 337.766916 -219.118242) (xy 337.74797 -219.098288)
			(xy 337.724383 -219.084119) (xy 337.697868 -219.076767) (xy 337.68411 -219.07627) (xy 337.306158 -219.07627)
			(xy 337.292398 -219.07673) (xy 337.26588 -219.08409) (xy 337.242291 -219.098266) (xy 337.223345 -219.118226)
			(xy 337.210417 -219.142522) (xy 337.204448 -219.169387) (xy 337.20587 -219.196871) (xy 337.214581 -219.222977)
			(xy 337.229947 -219.245808) (xy 337.240118 -219.255086) (xy 337.257914 -219.270845) (xy 337.28924 -219.306597)
			(xy 337.315114 -219.346473) (xy 337.335002 -219.389647) (xy 337.348491 -219.435227) (xy 337.355304 -219.482271)
			(xy 337.355688 -219.506038) (xy 337.355179 -219.532005) (xy 337.347054 -219.5833) (xy 337.331006 -219.632693)
			(xy 337.307428 -219.678967) (xy 337.276902 -219.720983) (xy 337.240179 -219.757706) (xy 337.198163 -219.788232)
			(xy 337.151889 -219.81181) (xy 337.102496 -219.827858) (xy 337.051201 -219.835983) (xy 336.999267 -219.835983)
			(xy 336.947972 -219.827858) (xy 336.898579 -219.81181) (xy 336.852305 -219.788232) (xy 336.810289 -219.757706)
			(xy 336.773566 -219.720983) (xy 336.74304 -219.678967) (xy 336.719462 -219.632693) (xy 336.703414 -219.5833)
			(xy 336.695289 -219.532005) (xy 336.69478 -219.506038) (xy 336.695197 -219.482274) (xy 336.702018 -219.435237)
			(xy 336.71551 -219.389663) (xy 336.735394 -219.346494) (xy 336.761261 -219.30662) (xy 336.792575 -219.270865)
			(xy 336.81035 -219.255086) (xy 336.820508 -219.245796) (xy 336.835875 -219.222972) (xy 336.844588 -219.196872)
			(xy 336.846011 -219.169393) (xy 336.840043 -219.142532) (xy 336.827116 -219.118242) (xy 336.80817 -219.098288)
			(xy 336.784583 -219.084119) (xy 336.758068 -219.076767) (xy 336.74431 -219.07627) (xy 336.351118 -219.07627)
			(xy 336.132678 -218.85783) (xy 336.132678 -218.25966) (xy 336.132195 -218.249722) (xy 336.124622 -218.231345)
			(xy 336.110629 -218.217228) (xy 336.092319 -218.209494) (xy 336.082386 -218.20886) (xy 336.056573 -218.208127)
			(xy 336.00564 -218.199631) (xy 335.956649 -218.183316) (xy 335.910791 -218.159581) (xy 335.869183 -218.129001)
			(xy 335.832837 -218.092323) (xy 335.802639 -218.050437) (xy 335.779322 -218.004365) (xy 335.763455 -217.955227)
			(xy 335.755424 -217.904218) (xy 335.755424 -217.852582) (xy 335.763455 -217.801574) (xy 335.779322 -217.752435)
			(xy 335.802638 -217.706363) (xy 335.832837 -217.664477) (xy 335.869183 -217.627799) (xy 335.910791 -217.597219)
			(xy 335.956649 -217.573484) (xy 336.00564 -217.557169) (xy 336.056573 -217.548673) (xy 336.082386 -217.547952)
			(xy 336.092325 -217.54738) (xy 336.110643 -217.539633) (xy 336.124633 -217.525495) (xy 336.132187 -217.507097)
			(xy 336.132678 -217.497152) (xy 336.132678 -216.631774) (xy 336.132198 -216.621834) (xy 336.124627 -216.603452)
			(xy 336.110633 -216.589331) (xy 336.092321 -216.581595) (xy 336.082386 -216.580974) (xy 336.056677 -216.580266)
			(xy 336.005939 -216.571867) (xy 335.957115 -216.55571) (xy 335.911383 -216.532185) (xy 335.869847 -216.50186)
			(xy 335.833509 -216.465467) (xy 335.803248 -216.423884) (xy 335.779793 -216.378116) (xy 335.763712 -216.329267)
			(xy 335.755391 -216.278516) (xy 335.754726 -216.252806) (xy 335.754472 -216.231724) (xy 334.145128 -214.62238)
			(xy 334.145128 -213.25967) (xy 328.770488 -207.88503) (xy 328.733658 -207.856074) (xy 328.704513 -207.832709)
			(xy 328.650339 -207.781272) (xy 328.601303 -207.724916) (xy 328.579226 -207.694784) (xy 328.576686 -207.691228)
			(xy 321.843654 -200.958196) (xy 314.308236 -195.051934) (xy 314.27801 -195.070222) (xy 314.256939 -195.082668)
			(xy 314.212112 -195.102302) (xy 314.165021 -195.115618) (xy 314.116551 -195.122366) (xy 314.092082 -195.1228)
			(xy 314.0641 -195.12225) (xy 314.008826 -195.113492) (xy 313.955601 -195.096196) (xy 313.905738 -195.070787)
			(xy 313.860464 -195.03789) (xy 313.820893 -194.998316) (xy 313.787999 -194.95304) (xy 313.762594 -194.903175)
			(xy 313.745302 -194.849949) (xy 313.736548 -194.794674) (xy 313.735974 -194.766692) (xy 313.736552 -194.737816)
			(xy 313.74591 -194.680827) (xy 313.764345 -194.626096) (xy 313.777376 -194.600322) (xy 313.793632 -194.569334)
			(xy 312.391044 -192.977262) (xy 312.381913 -192.967488) (xy 312.359642 -192.952692) (xy 312.334287 -192.944202)
			(xy 312.307597 -192.942602) (xy 312.28141 -192.948003) (xy 312.25753 -192.960032) (xy 312.24728 -192.968626)
			(xy 312.226191 -192.986753) (xy 312.179753 -193.017343) (xy 312.129368 -193.040874) (xy 312.076103 -193.056847)
			(xy 312.021084 -193.064925) (xy 311.99328 -193.0654) (xy 311.966915 -193.06496) (xy 311.914685 -193.057707)
			(xy 311.863953 -193.043328) (xy 311.815685 -193.022097) (xy 311.770802 -192.99442) (xy 311.73016 -192.960823)
			(xy 311.694533 -192.921949) (xy 311.664602 -192.878536) (xy 311.640936 -192.831415) (xy 311.632092 -192.806574)
			(xy 311.620408 -192.77203) (xy 310.902604 -192.77203) (xy 310.89219 -192.77711) (xy 310.866023 -192.789268)
			(xy 310.810943 -192.806449) (xy 310.753906 -192.815158) (xy 310.725058 -192.815718) (xy 310.696207 -192.815189)
			(xy 310.639166 -192.806488) (xy 310.584091 -192.789277) (xy 310.557926 -192.77711) (xy 310.547512 -192.77203)
			(xy 310.458358 -192.77203) (xy 309.797196 -192.110868) (xy 308.72557 -191.86271) (xy 307.933598 -191.86271)
			(xy 307.933598 -192.597786) (xy 309.917338 -194.581526) (xy 311.364884 -194.581526) (xy 311.40654 -194.623182)
			(xy 311.41644 -194.632485) (xy 311.44002 -194.645955) (xy 311.466318 -194.65273) (xy 311.493471 -194.652329)
			(xy 311.519557 -194.64478) (xy 311.542729 -194.630618) (xy 311.561345 -194.610847) (xy 311.568084 -194.599052)
			(xy 311.581485 -194.57503) (xy 311.614537 -194.531065) (xy 311.653958 -194.492706) (xy 311.698809 -194.460866)
			(xy 311.748023 -194.436301) (xy 311.800429 -194.419597) (xy 311.85478 -194.411151) (xy 311.882282 -194.410584)
			(xy 311.910269 -194.411103) (xy 311.965553 -194.419856) (xy 312.018787 -194.43715) (xy 312.068661 -194.46256)
			(xy 312.113945 -194.495458) (xy 312.153525 -194.535035) (xy 312.186427 -194.580317) (xy 312.21184 -194.630189)
			(xy 312.229138 -194.683422) (xy 312.237895 -194.738706) (xy 312.23839 -194.766692) (xy 312.237879 -194.794197)
			(xy 312.229423 -194.848553) (xy 312.212711 -194.900963) (xy 312.18814 -194.95018) (xy 312.156294 -194.995034)
			(xy 312.11793 -195.034459) (xy 312.073962 -195.067517) (xy 312.049922 -195.08089) (xy 312.038153 -195.087655)
			(xy 312.018422 -195.106283) (xy 312.00429 -195.129448) (xy 311.996755 -195.155516) (xy 311.996348 -195.182649)
			(xy 312.003099 -195.208931) (xy 312.01653 -195.232509) (xy 312.025792 -195.242434) (xy 313.015884 -196.232526)
			(xy 313.032648 -196.232526) (xy 313.293485 -196.493363) (xy 313.736472 -196.493363) (xy 313.736472 -196.440065)
			(xy 313.744415 -196.387361) (xy 313.760125 -196.336431) (xy 313.783251 -196.28841) (xy 313.813275 -196.244373)
			(xy 313.849527 -196.205302) (xy 313.891198 -196.172071) (xy 313.937356 -196.145422) (xy 313.98697 -196.12595)
			(xy 314.038932 -196.11409) (xy 314.092082 -196.110107) (xy 314.145232 -196.11409) (xy 314.197194 -196.12595)
			(xy 314.246808 -196.145422) (xy 314.292966 -196.172071) (xy 314.334637 -196.205302) (xy 314.370889 -196.244373)
			(xy 314.400913 -196.28841) (xy 314.424039 -196.336431) (xy 314.439749 -196.387361) (xy 314.447692 -196.440065)
			(xy 314.44819 -196.466714) (xy 314.447692 -196.493363) (xy 314.439749 -196.546067) (xy 314.424039 -196.596997)
			(xy 314.400913 -196.645018) (xy 314.370889 -196.689055) (xy 314.334637 -196.728126) (xy 314.292966 -196.761357)
			(xy 314.246808 -196.788006) (xy 314.197194 -196.807478) (xy 314.145232 -196.819338) (xy 314.092082 -196.823322)
			(xy 314.038932 -196.819338) (xy 313.98697 -196.807478) (xy 313.937356 -196.788006) (xy 313.891198 -196.761357)
			(xy 313.849527 -196.728126) (xy 313.813275 -196.689055) (xy 313.783251 -196.645018) (xy 313.760125 -196.596997)
			(xy 313.744415 -196.546067) (xy 313.736472 -196.493363) (xy 313.293485 -196.493363) (xy 314.744862 -197.94474)
			(xy 315.717936 -197.94474) (xy 315.799978 -198.026782) (xy 315.799978 -198.027036) (xy 321.784726 -204.011784)
			(xy 322.533518 -204.011784) (xy 326.875394 -208.35366) (xy 326.875394 -213.283546) (xy 329.512227 -215.920379)
			(xy 333.472791 -215.920379) (xy 333.472791 -215.868445) (xy 333.480916 -215.81715) (xy 333.496964 -215.767757)
			(xy 333.520542 -215.721483) (xy 333.551068 -215.679467) (xy 333.587791 -215.642744) (xy 333.629807 -215.612218)
			(xy 333.676081 -215.58864) (xy 333.725474 -215.572592) (xy 333.776769 -215.564467) (xy 333.828703 -215.564467)
			(xy 333.879998 -215.572592) (xy 333.929391 -215.58864) (xy 333.975665 -215.612218) (xy 334.017681 -215.642744)
			(xy 334.054404 -215.679467) (xy 334.08493 -215.721483) (xy 334.108508 -215.767757) (xy 334.124556 -215.81715)
			(xy 334.132681 -215.868445) (xy 334.13319 -215.894412) (xy 334.132681 -215.920379) (xy 334.124556 -215.971674)
			(xy 334.108508 -216.021067) (xy 334.08493 -216.067341) (xy 334.054404 -216.109357) (xy 334.017681 -216.14608)
			(xy 333.975665 -216.176606) (xy 333.929391 -216.200184) (xy 333.879998 -216.216232) (xy 333.828703 -216.224357)
			(xy 333.776769 -216.224357) (xy 333.725474 -216.216232) (xy 333.676081 -216.200184) (xy 333.629807 -216.176606)
			(xy 333.587791 -216.14608) (xy 333.551068 -216.109357) (xy 333.520542 -216.067341) (xy 333.496964 -216.021067)
			(xy 333.480916 -215.971674) (xy 333.472791 -215.920379) (xy 329.512227 -215.920379) (xy 329.868335 -216.276487)
			(xy 334.815181 -216.276487) (xy 334.815181 -216.224553) (xy 334.823306 -216.173258) (xy 334.839354 -216.123865)
			(xy 334.862932 -216.077591) (xy 334.893458 -216.035575) (xy 334.930181 -215.998852) (xy 334.972197 -215.968326)
			(xy 335.018471 -215.944748) (xy 335.067864 -215.9287) (xy 335.119159 -215.920575) (xy 335.171093 -215.920575)
			(xy 335.222388 -215.9287) (xy 335.271781 -215.944748) (xy 335.318055 -215.968326) (xy 335.360071 -215.998852)
			(xy 335.396794 -216.035575) (xy 335.42732 -216.077591) (xy 335.450898 -216.123865) (xy 335.466946 -216.173258)
			(xy 335.475071 -216.224553) (xy 335.47558 -216.25052) (xy 335.475071 -216.276487) (xy 335.466946 -216.327782)
			(xy 335.450898 -216.377175) (xy 335.42732 -216.423449) (xy 335.396794 -216.465465) (xy 335.360071 -216.502188)
			(xy 335.318055 -216.532714) (xy 335.271781 -216.556292) (xy 335.222388 -216.57234) (xy 335.171093 -216.580465)
			(xy 335.119159 -216.580465) (xy 335.067864 -216.57234) (xy 335.018471 -216.556292) (xy 334.972197 -216.532714)
			(xy 334.930181 -216.502188) (xy 334.893458 -216.465465) (xy 334.862932 -216.423449) (xy 334.839354 -216.377175)
			(xy 334.823306 -216.327782) (xy 334.815181 -216.276487) (xy 329.868335 -216.276487) (xy 330.682151 -217.090303)
			(xy 333.405735 -217.090303) (xy 333.405735 -217.038369) (xy 333.41386 -216.987074) (xy 333.429908 -216.937681)
			(xy 333.453486 -216.891407) (xy 333.484012 -216.849391) (xy 333.520735 -216.812668) (xy 333.562751 -216.782142)
			(xy 333.609025 -216.758564) (xy 333.658418 -216.742516) (xy 333.709713 -216.734391) (xy 333.761647 -216.734391)
			(xy 333.812942 -216.742516) (xy 333.862335 -216.758564) (xy 333.908609 -216.782142) (xy 333.950625 -216.812668)
			(xy 333.987348 -216.849391) (xy 334.017874 -216.891407) (xy 334.041452 -216.937681) (xy 334.0575 -216.987074)
			(xy 334.065625 -217.038369) (xy 334.066134 -217.064336) (xy 334.065625 -217.090303) (xy 334.345535 -217.090303)
			(xy 334.345535 -217.038369) (xy 334.35366 -216.987074) (xy 334.369708 -216.937681) (xy 334.393286 -216.891407)
			(xy 334.423812 -216.849391) (xy 334.460535 -216.812668) (xy 334.502551 -216.782142) (xy 334.548825 -216.758564)
			(xy 334.598218 -216.742516) (xy 334.649513 -216.734391) (xy 334.701447 -216.734391) (xy 334.752742 -216.742516)
			(xy 334.802135 -216.758564) (xy 334.848409 -216.782142) (xy 334.890425 -216.812668) (xy 334.927148 -216.849391)
			(xy 334.957674 -216.891407) (xy 334.981252 -216.937681) (xy 334.9973 -216.987074) (xy 335.005425 -217.038369)
			(xy 335.005934 -217.064336) (xy 335.005425 -217.090303) (xy 335.285335 -217.090303) (xy 335.285335 -217.038369)
			(xy 335.29346 -216.987074) (xy 335.309508 -216.937681) (xy 335.333086 -216.891407) (xy 335.363612 -216.849391)
			(xy 335.400335 -216.812668) (xy 335.442351 -216.782142) (xy 335.488625 -216.758564) (xy 335.538018 -216.742516)
			(xy 335.589313 -216.734391) (xy 335.641247 -216.734391) (xy 335.692542 -216.742516) (xy 335.741935 -216.758564)
			(xy 335.788209 -216.782142) (xy 335.830225 -216.812668) (xy 335.866948 -216.849391) (xy 335.897474 -216.891407)
			(xy 335.921052 -216.937681) (xy 335.9371 -216.987074) (xy 335.945225 -217.038369) (xy 335.945734 -217.064336)
			(xy 335.945225 -217.090303) (xy 335.9371 -217.141598) (xy 335.921052 -217.190991) (xy 335.897474 -217.237265)
			(xy 335.866948 -217.279281) (xy 335.830225 -217.316004) (xy 335.788209 -217.34653) (xy 335.741935 -217.370108)
			(xy 335.692542 -217.386156) (xy 335.641247 -217.394281) (xy 335.589313 -217.394281) (xy 335.538018 -217.386156)
			(xy 335.488625 -217.370108) (xy 335.442351 -217.34653) (xy 335.400335 -217.316004) (xy 335.363612 -217.279281)
			(xy 335.333086 -217.237265) (xy 335.309508 -217.190991) (xy 335.29346 -217.141598) (xy 335.285335 -217.090303)
			(xy 335.005425 -217.090303) (xy 334.9973 -217.141598) (xy 334.981252 -217.190991) (xy 334.957674 -217.237265)
			(xy 334.927148 -217.279281) (xy 334.890425 -217.316004) (xy 334.848409 -217.34653) (xy 334.802135 -217.370108)
			(xy 334.752742 -217.386156) (xy 334.701447 -217.394281) (xy 334.649513 -217.394281) (xy 334.598218 -217.386156)
			(xy 334.548825 -217.370108) (xy 334.502551 -217.34653) (xy 334.460535 -217.316004) (xy 334.423812 -217.279281)
			(xy 334.393286 -217.237265) (xy 334.369708 -217.190991) (xy 334.35366 -217.141598) (xy 334.345535 -217.090303)
			(xy 334.065625 -217.090303) (xy 334.0575 -217.141598) (xy 334.041452 -217.190991) (xy 334.017874 -217.237265)
			(xy 333.987348 -217.279281) (xy 333.950625 -217.316004) (xy 333.908609 -217.34653) (xy 333.862335 -217.370108)
			(xy 333.812942 -217.386156) (xy 333.761647 -217.394281) (xy 333.709713 -217.394281) (xy 333.658418 -217.386156)
			(xy 333.609025 -217.370108) (xy 333.562751 -217.34653) (xy 333.520735 -217.316004) (xy 333.484012 -217.279281)
			(xy 333.453486 -217.237265) (xy 333.429908 -217.190991) (xy 333.41386 -217.141598) (xy 333.405735 -217.090303)
			(xy 330.682151 -217.090303) (xy 331.542703 -217.950855) (xy 332.985619 -217.950855) (xy 332.985619 -217.898921)
			(xy 332.993744 -217.847626) (xy 333.009792 -217.798233) (xy 333.03337 -217.751959) (xy 333.063896 -217.709943)
			(xy 333.100619 -217.67322) (xy 333.142635 -217.642694) (xy 333.188909 -217.619116) (xy 333.238302 -217.603068)
			(xy 333.289597 -217.594943) (xy 333.341531 -217.594943) (xy 333.392826 -217.603068) (xy 333.442219 -217.619116)
			(xy 333.488493 -217.642694) (xy 333.530509 -217.67322) (xy 333.567232 -217.709943) (xy 333.597758 -217.751959)
			(xy 333.621336 -217.798233) (xy 333.637384 -217.847626) (xy 333.645509 -217.898921) (xy 333.645616 -217.904373)
			(xy 333.875635 -217.904373) (xy 333.875635 -217.852439) (xy 333.88376 -217.801144) (xy 333.899808 -217.751751)
			(xy 333.923386 -217.705477) (xy 333.953912 -217.663461) (xy 333.990635 -217.626738) (xy 334.032651 -217.596212)
			(xy 334.078925 -217.572634) (xy 334.128318 -217.556586) (xy 334.179613 -217.548461) (xy 334.231547 -217.548461)
			(xy 334.282842 -217.556586) (xy 334.332235 -217.572634) (xy 334.378509 -217.596212) (xy 334.420525 -217.626738)
			(xy 334.457248 -217.663461) (xy 334.487774 -217.705477) (xy 334.511352 -217.751751) (xy 334.5274 -217.801144)
			(xy 334.535525 -217.852439) (xy 334.536034 -217.878406) (xy 334.535525 -217.904373) (xy 334.815181 -217.904373)
			(xy 334.815181 -217.852439) (xy 334.823306 -217.801144) (xy 334.839354 -217.751751) (xy 334.862932 -217.705477)
			(xy 334.893458 -217.663461) (xy 334.930181 -217.626738) (xy 334.972197 -217.596212) (xy 335.018471 -217.572634)
			(xy 335.067864 -217.556586) (xy 335.119159 -217.548461) (xy 335.171093 -217.548461) (xy 335.222388 -217.556586)
			(xy 335.271781 -217.572634) (xy 335.318055 -217.596212) (xy 335.360071 -217.626738) (xy 335.396794 -217.663461)
			(xy 335.42732 -217.705477) (xy 335.450898 -217.751751) (xy 335.466946 -217.801144) (xy 335.475071 -217.852439)
			(xy 335.47558 -217.878406) (xy 335.475071 -217.904373) (xy 335.466946 -217.955668) (xy 335.450898 -218.005061)
			(xy 335.42732 -218.051335) (xy 335.396794 -218.093351) (xy 335.360071 -218.130074) (xy 335.318055 -218.1606)
			(xy 335.271781 -218.184178) (xy 335.222388 -218.200226) (xy 335.171093 -218.208351) (xy 335.119159 -218.208351)
			(xy 335.067864 -218.200226) (xy 335.018471 -218.184178) (xy 334.972197 -218.1606) (xy 334.930181 -218.130074)
			(xy 334.893458 -218.093351) (xy 334.862932 -218.051335) (xy 334.839354 -218.005061) (xy 334.823306 -217.955668)
			(xy 334.815181 -217.904373) (xy 334.535525 -217.904373) (xy 334.5274 -217.955668) (xy 334.511352 -218.005061)
			(xy 334.487774 -218.051335) (xy 334.457248 -218.093351) (xy 334.420525 -218.130074) (xy 334.378509 -218.1606)
			(xy 334.332235 -218.184178) (xy 334.282842 -218.200226) (xy 334.231547 -218.208351) (xy 334.179613 -218.208351)
			(xy 334.128318 -218.200226) (xy 334.078925 -218.184178) (xy 334.032651 -218.1606) (xy 333.990635 -218.130074)
			(xy 333.953912 -218.093351) (xy 333.923386 -218.051335) (xy 333.899808 -218.005061) (xy 333.88376 -217.955668)
			(xy 333.875635 -217.904373) (xy 333.645616 -217.904373) (xy 333.646018 -217.924888) (xy 333.645509 -217.950855)
			(xy 333.637384 -218.00215) (xy 333.621336 -218.051543) (xy 333.597758 -218.097817) (xy 333.567232 -218.139833)
			(xy 333.530509 -218.176556) (xy 333.488493 -218.207082) (xy 333.442219 -218.23066) (xy 333.392826 -218.246708)
			(xy 333.341531 -218.254833) (xy 333.289597 -218.254833) (xy 333.238302 -218.246708) (xy 333.188909 -218.23066)
			(xy 333.142635 -218.207082) (xy 333.100619 -218.176556) (xy 333.063896 -218.139833) (xy 333.03337 -218.097817)
			(xy 333.009792 -218.051543) (xy 332.993744 -218.00215) (xy 332.985619 -217.950855) (xy 331.542703 -217.950855)
			(xy 331.967078 -218.37523) (xy 331.967078 -218.718189) (xy 335.285589 -218.718189) (xy 335.285589 -218.666255)
			(xy 335.293714 -218.61496) (xy 335.309762 -218.565567) (xy 335.33334 -218.519293) (xy 335.363866 -218.477277)
			(xy 335.400589 -218.440554) (xy 335.442605 -218.410028) (xy 335.488879 -218.38645) (xy 335.538272 -218.370402)
			(xy 335.589567 -218.362277) (xy 335.641501 -218.362277) (xy 335.692796 -218.370402) (xy 335.742189 -218.38645)
			(xy 335.788463 -218.410028) (xy 335.830479 -218.440554) (xy 335.867202 -218.477277) (xy 335.897728 -218.519293)
			(xy 335.921306 -218.565567) (xy 335.937354 -218.61496) (xy 335.945479 -218.666255) (xy 335.945988 -218.692222)
			(xy 335.945479 -218.718189) (xy 335.937354 -218.769484) (xy 335.921306 -218.818877) (xy 335.897728 -218.865151)
			(xy 335.867202 -218.907167) (xy 335.830479 -218.94389) (xy 335.788463 -218.974416) (xy 335.742189 -218.997994)
			(xy 335.692796 -219.014042) (xy 335.641501 -219.022167) (xy 335.589567 -219.022167) (xy 335.538272 -219.014042)
			(xy 335.488879 -218.997994) (xy 335.442605 -218.974416) (xy 335.400589 -218.94389) (xy 335.363866 -218.907167)
			(xy 335.33334 -218.865151) (xy 335.309762 -218.818877) (xy 335.293714 -218.769484) (xy 335.285589 -218.718189)
			(xy 331.967078 -218.718189) (xy 331.967078 -219.06103) (xy 332.438053 -219.532005) (xy 335.755489 -219.532005)
			(xy 335.755489 -219.480071) (xy 335.763614 -219.428776) (xy 335.779662 -219.379383) (xy 335.80324 -219.333109)
			(xy 335.833766 -219.291093) (xy 335.870489 -219.25437) (xy 335.912505 -219.223844) (xy 335.958779 -219.200266)
			(xy 336.008172 -219.184218) (xy 336.059467 -219.176093) (xy 336.111401 -219.176093) (xy 336.162696 -219.184218)
			(xy 336.212089 -219.200266) (xy 336.258363 -219.223844) (xy 336.300379 -219.25437) (xy 336.337102 -219.291093)
			(xy 336.367628 -219.333109) (xy 336.391206 -219.379383) (xy 336.407254 -219.428776) (xy 336.415379 -219.480071)
			(xy 336.415888 -219.506038) (xy 336.415379 -219.532005) (xy 336.407254 -219.5833) (xy 336.391206 -219.632693)
			(xy 336.367628 -219.678967) (xy 336.337102 -219.720983) (xy 336.300379 -219.757706) (xy 336.258363 -219.788232)
			(xy 336.212089 -219.81181) (xy 336.162696 -219.827858) (xy 336.111401 -219.835983) (xy 336.059467 -219.835983)
			(xy 336.008172 -219.827858) (xy 335.958779 -219.81181) (xy 335.912505 -219.788232) (xy 335.870489 -219.757706)
			(xy 335.833766 -219.720983) (xy 335.80324 -219.678967) (xy 335.779662 -219.632693) (xy 335.763614 -219.5833)
			(xy 335.755489 -219.532005) (xy 332.438053 -219.532005) (xy 333.250871 -220.344823) (xy 334.35847 -220.344823)
			(xy 334.35847 -220.294885) (xy 334.366282 -220.245561) (xy 334.381713 -220.198067) (xy 334.404385 -220.153571)
			(xy 334.433738 -220.11317) (xy 334.46905 -220.077858) (xy 334.509451 -220.048505) (xy 334.553947 -220.025833)
			(xy 334.601441 -220.010402) (xy 334.650765 -220.00259) (xy 334.700703 -220.00259) (xy 334.750027 -220.010402)
			(xy 334.797521 -220.025833) (xy 334.842017 -220.048505) (xy 334.882418 -220.077858) (xy 334.91773 -220.11317)
			(xy 334.947083 -220.153571) (xy 334.969755 -220.198067) (xy 334.985186 -220.245561) (xy 334.992998 -220.294885)
			(xy 334.993488 -220.319854) (xy 334.992998 -220.344823) (xy 334.99284 -220.345821) (xy 336.225389 -220.345821)
			(xy 336.225389 -220.293887) (xy 336.233514 -220.242592) (xy 336.249562 -220.193199) (xy 336.27314 -220.146925)
			(xy 336.303666 -220.104909) (xy 336.340389 -220.068186) (xy 336.382405 -220.03766) (xy 336.428679 -220.014082)
			(xy 336.478072 -219.998034) (xy 336.529367 -219.989909) (xy 336.581301 -219.989909) (xy 336.632596 -219.998034)
			(xy 336.681989 -220.014082) (xy 336.728263 -220.03766) (xy 336.770279 -220.068186) (xy 336.807002 -220.104909)
			(xy 336.837528 -220.146925) (xy 336.861106 -220.193199) (xy 336.877154 -220.242592) (xy 336.885279 -220.293887)
			(xy 336.885788 -220.319854) (xy 336.885279 -220.345821) (xy 337.165189 -220.345821) (xy 337.165189 -220.293887)
			(xy 337.173314 -220.242592) (xy 337.189362 -220.193199) (xy 337.21294 -220.146925) (xy 337.243466 -220.104909)
			(xy 337.280189 -220.068186) (xy 337.322205 -220.03766) (xy 337.368479 -220.014082) (xy 337.417872 -219.998034)
			(xy 337.469167 -219.989909) (xy 337.521101 -219.989909) (xy 337.572396 -219.998034) (xy 337.621789 -220.014082)
			(xy 337.668063 -220.03766) (xy 337.710079 -220.068186) (xy 337.746802 -220.104909) (xy 337.777328 -220.146925)
			(xy 337.800906 -220.193199) (xy 337.816954 -220.242592) (xy 337.825079 -220.293887) (xy 337.825588 -220.319854)
			(xy 337.825079 -220.345821) (xy 337.816954 -220.397116) (xy 337.800906 -220.446509) (xy 337.777328 -220.492783)
			(xy 337.746802 -220.534799) (xy 337.710079 -220.571522) (xy 337.668063 -220.602048) (xy 337.621789 -220.625626)
			(xy 337.572396 -220.641674) (xy 337.521101 -220.649799) (xy 337.469167 -220.649799) (xy 337.417872 -220.641674)
			(xy 337.368479 -220.625626) (xy 337.322205 -220.602048) (xy 337.280189 -220.571522) (xy 337.243466 -220.534799)
			(xy 337.21294 -220.492783) (xy 337.189362 -220.446509) (xy 337.173314 -220.397116) (xy 337.165189 -220.345821)
			(xy 336.885279 -220.345821) (xy 336.877154 -220.397116) (xy 336.861106 -220.446509) (xy 336.837528 -220.492783)
			(xy 336.807002 -220.534799) (xy 336.770279 -220.571522) (xy 336.728263 -220.602048) (xy 336.681989 -220.625626)
			(xy 336.632596 -220.641674) (xy 336.581301 -220.649799) (xy 336.529367 -220.649799) (xy 336.478072 -220.641674)
			(xy 336.428679 -220.625626) (xy 336.382405 -220.602048) (xy 336.340389 -220.571522) (xy 336.303666 -220.534799)
			(xy 336.27314 -220.492783) (xy 336.249562 -220.446509) (xy 336.233514 -220.397116) (xy 336.225389 -220.345821)
			(xy 334.99284 -220.345821) (xy 334.985186 -220.394147) (xy 334.969755 -220.441641) (xy 334.947083 -220.486137)
			(xy 334.91773 -220.526538) (xy 334.882418 -220.56185) (xy 334.842017 -220.591203) (xy 334.797521 -220.613875)
			(xy 334.750027 -220.629306) (xy 334.700703 -220.637118) (xy 334.650765 -220.637118) (xy 334.601441 -220.629306)
			(xy 334.553947 -220.613875) (xy 334.509451 -220.591203) (xy 334.46905 -220.56185) (xy 334.433738 -220.526538)
			(xy 334.404385 -220.486137) (xy 334.381713 -220.441641) (xy 334.366282 -220.394147) (xy 334.35847 -220.344823)
			(xy 333.250871 -220.344823) (xy 333.541878 -220.63583) (xy 333.541878 -221.159891) (xy 335.755489 -221.159891)
			(xy 335.755489 -221.107957) (xy 335.763614 -221.056662) (xy 335.779662 -221.007269) (xy 335.80324 -220.960995)
			(xy 335.833766 -220.918979) (xy 335.870489 -220.882256) (xy 335.912505 -220.85173) (xy 335.958779 -220.828152)
			(xy 336.008172 -220.812104) (xy 336.059467 -220.803979) (xy 336.111401 -220.803979) (xy 336.162696 -220.812104)
			(xy 336.212089 -220.828152) (xy 336.258363 -220.85173) (xy 336.300379 -220.882256) (xy 336.337102 -220.918979)
			(xy 336.367628 -220.960995) (xy 336.391206 -221.007269) (xy 336.407254 -221.056662) (xy 336.415379 -221.107957)
			(xy 336.415888 -221.133924) (xy 336.69478 -221.133924) (xy 336.695289 -221.107957) (xy 336.703414 -221.056662)
			(xy 336.719462 -221.007269) (xy 336.74304 -220.960995) (xy 336.773566 -220.918979) (xy 336.810289 -220.882256)
			(xy 336.852305 -220.85173) (xy 336.898579 -220.828152) (xy 336.947972 -220.812104) (xy 336.999267 -220.803979)
			(xy 337.051201 -220.803979) (xy 337.102496 -220.812104) (xy 337.151889 -220.828152) (xy 337.198163 -220.85173)
			(xy 337.240179 -220.882256) (xy 337.276902 -220.918979) (xy 337.307428 -220.960995) (xy 337.331006 -221.007269)
			(xy 337.347054 -221.056662) (xy 337.355179 -221.107957) (xy 337.355688 -221.133924) (xy 337.63458 -221.133924)
			(xy 337.634971 -221.108469) (xy 337.642761 -221.05816) (xy 337.658176 -221.009641) (xy 337.680851 -220.964061)
			(xy 337.710249 -220.922499) (xy 337.745675 -220.885938) (xy 337.78629 -220.855244) (xy 337.831132 -220.831143)
			(xy 337.879141 -220.814206) (xy 337.904074 -220.809058) (xy 337.926934 -220.80474) (xy 338.130642 -220.45168)
			(xy 338.123022 -220.429582) (xy 338.114281 -220.402995) (xy 338.104835 -220.347835) (xy 338.104226 -220.319854)
			(xy 338.104735 -220.293887) (xy 338.11286 -220.242592) (xy 338.128908 -220.193199) (xy 338.152486 -220.146925)
			(xy 338.183012 -220.104909) (xy 338.219735 -220.068186) (xy 338.261751 -220.03766) (xy 338.308025 -220.014082)
			(xy 338.357418 -219.998034) (xy 338.408713 -219.989909) (xy 338.460647 -219.989909) (xy 338.511942 -219.998034)
			(xy 338.561335 -220.014082) (xy 338.607609 -220.03766) (xy 338.649625 -220.068186) (xy 338.686348 -220.104909)
			(xy 338.716874 -220.146925) (xy 338.740452 -220.193199) (xy 338.7565 -220.242592) (xy 338.764625 -220.293887)
			(xy 338.765134 -220.319854) (xy 338.764712 -220.345307) (xy 338.764632 -220.345821) (xy 339.044789 -220.345821)
			(xy 339.044789 -220.293887) (xy 339.052914 -220.242592) (xy 339.068962 -220.193199) (xy 339.09254 -220.146925)
			(xy 339.123066 -220.104909) (xy 339.159789 -220.068186) (xy 339.201805 -220.03766) (xy 339.248079 -220.014082)
			(xy 339.297472 -219.998034) (xy 339.348767 -219.989909) (xy 339.400701 -219.989909) (xy 339.451996 -219.998034)
			(xy 339.501389 -220.014082) (xy 339.547663 -220.03766) (xy 339.589679 -220.068186) (xy 339.626402 -220.104909)
			(xy 339.656928 -220.146925) (xy 339.680506 -220.193199) (xy 339.696554 -220.242592) (xy 339.704679 -220.293887)
			(xy 339.705188 -220.319854) (xy 339.704679 -220.345821) (xy 339.696554 -220.397116) (xy 339.680506 -220.446509)
			(xy 339.656928 -220.492783) (xy 339.626402 -220.534799) (xy 339.589679 -220.571522) (xy 339.547663 -220.602048)
			(xy 339.501389 -220.625626) (xy 339.451996 -220.641674) (xy 339.400701 -220.649799) (xy 339.348767 -220.649799)
			(xy 339.297472 -220.641674) (xy 339.248079 -220.625626) (xy 339.201805 -220.602048) (xy 339.159789 -220.571522)
			(xy 339.123066 -220.534799) (xy 339.09254 -220.492783) (xy 339.068962 -220.446509) (xy 339.052914 -220.397116)
			(xy 339.044789 -220.345821) (xy 338.764632 -220.345821) (xy 338.756926 -220.395615) (xy 338.741514 -220.444132)
			(xy 338.718843 -220.489711) (xy 338.689449 -220.531273) (xy 338.654027 -220.567835) (xy 338.613416 -220.59853)
			(xy 338.568577 -220.622632) (xy 338.520571 -220.639571) (xy 338.49564 -220.64472) (xy 338.47278 -220.649038)
			(xy 338.269072 -221.002098) (xy 338.276692 -221.024196) (xy 338.285429 -221.050785) (xy 338.294877 -221.105944)
			(xy 338.295488 -221.133924) (xy 338.57438 -221.133924) (xy 338.574889 -221.107957) (xy 338.583014 -221.056662)
			(xy 338.599062 -221.007269) (xy 338.62264 -220.960995) (xy 338.653166 -220.918979) (xy 338.689889 -220.882256)
			(xy 338.731905 -220.85173) (xy 338.778179 -220.828152) (xy 338.827572 -220.812104) (xy 338.878867 -220.803979)
			(xy 338.930801 -220.803979) (xy 338.982096 -220.812104) (xy 339.031489 -220.828152) (xy 339.077763 -220.85173)
			(xy 339.119779 -220.882256) (xy 339.156502 -220.918979) (xy 339.187028 -220.960995) (xy 339.210606 -221.007269)
			(xy 339.226654 -221.056662) (xy 339.234779 -221.107957) (xy 339.235288 -221.133924) (xy 339.51418 -221.133924)
			(xy 339.514571 -221.108469) (xy 339.522361 -221.05816) (xy 339.537776 -221.009641) (xy 339.560451 -220.964061)
			(xy 339.589849 -220.922499) (xy 339.625275 -220.885938) (xy 339.66589 -220.855244) (xy 339.710732 -220.831143)
			(xy 339.758741 -220.814206) (xy 339.783674 -220.809058) (xy 339.806534 -220.80474) (xy 340.010242 -220.45168)
			(xy 340.002622 -220.429582) (xy 339.993881 -220.402995) (xy 339.984435 -220.347835) (xy 339.983826 -220.319854)
			(xy 339.984335 -220.293887) (xy 339.99246 -220.242592) (xy 340.008508 -220.193199) (xy 340.032086 -220.146925)
			(xy 340.062612 -220.104909) (xy 340.099335 -220.068186) (xy 340.141351 -220.03766) (xy 340.187625 -220.014082)
			(xy 340.237018 -219.998034) (xy 340.288313 -219.989909) (xy 340.340247 -219.989909) (xy 340.391542 -219.998034)
			(xy 340.440935 -220.014082) (xy 340.487209 -220.03766) (xy 340.529225 -220.068186) (xy 340.565948 -220.104909)
			(xy 340.596474 -220.146925) (xy 340.620052 -220.193199) (xy 340.6361 -220.242592) (xy 340.644225 -220.293887)
			(xy 340.644734 -220.319854) (xy 340.644312 -220.345307) (xy 340.644232 -220.345821) (xy 340.924389 -220.345821)
			(xy 340.924389 -220.293887) (xy 340.932514 -220.242592) (xy 340.948562 -220.193199) (xy 340.97214 -220.146925)
			(xy 341.002666 -220.104909) (xy 341.039389 -220.068186) (xy 341.081405 -220.03766) (xy 341.127679 -220.014082)
			(xy 341.177072 -219.998034) (xy 341.228367 -219.989909) (xy 341.280301 -219.989909) (xy 341.331596 -219.998034)
			(xy 341.380989 -220.014082) (xy 341.427263 -220.03766) (xy 341.469279 -220.068186) (xy 341.506002 -220.104909)
			(xy 341.536528 -220.146925) (xy 341.560106 -220.193199) (xy 341.576154 -220.242592) (xy 341.584279 -220.293887)
			(xy 341.584788 -220.319854) (xy 341.584279 -220.345821) (xy 341.576154 -220.397116) (xy 341.560106 -220.446509)
			(xy 341.536528 -220.492783) (xy 341.506002 -220.534799) (xy 341.469279 -220.571522) (xy 341.427263 -220.602048)
			(xy 341.380989 -220.625626) (xy 341.331596 -220.641674) (xy 341.280301 -220.649799) (xy 341.228367 -220.649799)
			(xy 341.177072 -220.641674) (xy 341.127679 -220.625626) (xy 341.081405 -220.602048) (xy 341.039389 -220.571522)
			(xy 341.002666 -220.534799) (xy 340.97214 -220.492783) (xy 340.948562 -220.446509) (xy 340.932514 -220.397116)
			(xy 340.924389 -220.345821) (xy 340.644232 -220.345821) (xy 340.636526 -220.395615) (xy 340.621114 -220.444132)
			(xy 340.598443 -220.489711) (xy 340.569049 -220.531273) (xy 340.533627 -220.567835) (xy 340.493016 -220.59853)
			(xy 340.448177 -220.622632) (xy 340.400171 -220.639571) (xy 340.37524 -220.64472) (xy 340.35238 -220.649038)
			(xy 340.148672 -221.002098) (xy 340.156292 -221.024196) (xy 340.165029 -221.050785) (xy 340.174477 -221.105944)
			(xy 340.175088 -221.133924) (xy 340.45398 -221.133924) (xy 340.454489 -221.107957) (xy 340.462614 -221.056662)
			(xy 340.478662 -221.007269) (xy 340.50224 -220.960995) (xy 340.532766 -220.918979) (xy 340.569489 -220.882256)
			(xy 340.611505 -220.85173) (xy 340.657779 -220.828152) (xy 340.707172 -220.812104) (xy 340.758467 -220.803979)
			(xy 340.810401 -220.803979) (xy 340.861696 -220.812104) (xy 340.911089 -220.828152) (xy 340.957363 -220.85173)
			(xy 340.999379 -220.882256) (xy 341.036102 -220.918979) (xy 341.066628 -220.960995) (xy 341.090206 -221.007269)
			(xy 341.106254 -221.056662) (xy 341.114379 -221.107957) (xy 341.114888 -221.133924) (xy 341.39378 -221.133924)
			(xy 341.394171 -221.108469) (xy 341.401961 -221.05816) (xy 341.417376 -221.009641) (xy 341.440051 -220.964061)
			(xy 341.469449 -220.922499) (xy 341.504875 -220.885938) (xy 341.54549 -220.855244) (xy 341.590332 -220.831143)
			(xy 341.638341 -220.814206) (xy 341.663274 -220.809058) (xy 341.686134 -220.80474) (xy 341.889842 -220.45168)
			(xy 341.882222 -220.429582) (xy 341.873481 -220.402995) (xy 341.864035 -220.347835) (xy 341.863426 -220.319854)
			(xy 341.863935 -220.293887) (xy 341.87206 -220.242592) (xy 341.888108 -220.193199) (xy 341.911686 -220.146925)
			(xy 341.942212 -220.104909) (xy 341.978935 -220.068186) (xy 342.020951 -220.03766) (xy 342.067225 -220.014082)
			(xy 342.116618 -219.998034) (xy 342.167913 -219.989909) (xy 342.219847 -219.989909) (xy 342.271142 -219.998034)
			(xy 342.320535 -220.014082) (xy 342.366809 -220.03766) (xy 342.408825 -220.068186) (xy 342.445548 -220.104909)
			(xy 342.476074 -220.146925) (xy 342.499652 -220.193199) (xy 342.5157 -220.242592) (xy 342.523825 -220.293887)
			(xy 342.524334 -220.319854) (xy 342.523912 -220.345307) (xy 342.523832 -220.345821) (xy 342.803989 -220.345821)
			(xy 342.803989 -220.293887) (xy 342.812114 -220.242592) (xy 342.828162 -220.193199) (xy 342.85174 -220.146925)
			(xy 342.882266 -220.104909) (xy 342.918989 -220.068186) (xy 342.961005 -220.03766) (xy 343.007279 -220.014082)
			(xy 343.056672 -219.998034) (xy 343.107967 -219.989909) (xy 343.159901 -219.989909) (xy 343.211196 -219.998034)
			(xy 343.260589 -220.014082) (xy 343.306863 -220.03766) (xy 343.348879 -220.068186) (xy 343.385602 -220.104909)
			(xy 343.416128 -220.146925) (xy 343.439706 -220.193199) (xy 343.455754 -220.242592) (xy 343.463879 -220.293887)
			(xy 343.464388 -220.319854) (xy 343.463879 -220.345821) (xy 343.455754 -220.397116) (xy 343.439706 -220.446509)
			(xy 343.416128 -220.492783) (xy 343.385602 -220.534799) (xy 343.348879 -220.571522) (xy 343.306863 -220.602048)
			(xy 343.260589 -220.625626) (xy 343.211196 -220.641674) (xy 343.159901 -220.649799) (xy 343.107967 -220.649799)
			(xy 343.056672 -220.641674) (xy 343.007279 -220.625626) (xy 342.961005 -220.602048) (xy 342.918989 -220.571522)
			(xy 342.882266 -220.534799) (xy 342.85174 -220.492783) (xy 342.828162 -220.446509) (xy 342.812114 -220.397116)
			(xy 342.803989 -220.345821) (xy 342.523832 -220.345821) (xy 342.516126 -220.395615) (xy 342.500714 -220.444132)
			(xy 342.478043 -220.489711) (xy 342.448649 -220.531273) (xy 342.413227 -220.567835) (xy 342.372616 -220.59853)
			(xy 342.327777 -220.622632) (xy 342.279771 -220.639571) (xy 342.25484 -220.64472) (xy 342.23198 -220.649038)
			(xy 342.028272 -221.002098) (xy 342.035892 -221.024196) (xy 342.044629 -221.050785) (xy 342.054077 -221.105944)
			(xy 342.054688 -221.133924) (xy 342.33358 -221.133924) (xy 342.334089 -221.107957) (xy 342.342214 -221.056662)
			(xy 342.358262 -221.007269) (xy 342.38184 -220.960995) (xy 342.412366 -220.918979) (xy 342.449089 -220.882256)
			(xy 342.491105 -220.85173) (xy 342.537379 -220.828152) (xy 342.586772 -220.812104) (xy 342.638067 -220.803979)
			(xy 342.690001 -220.803979) (xy 342.741296 -220.812104) (xy 342.790689 -220.828152) (xy 342.836963 -220.85173)
			(xy 342.878979 -220.882256) (xy 342.915702 -220.918979) (xy 342.946228 -220.960995) (xy 342.969806 -221.007269)
			(xy 342.985854 -221.056662) (xy 342.993979 -221.107957) (xy 342.994488 -221.133924) (xy 342.993942 -221.16191)
			(xy 342.984487 -221.217078) (xy 342.975692 -221.243652) (xy 342.968072 -221.26575) (xy 343.17178 -221.618556)
			(xy 343.19464 -221.622874) (xy 343.219563 -221.628034) (xy 343.267548 -221.644999) (xy 343.312366 -221.669118)
			(xy 343.352959 -221.699819) (xy 343.388368 -221.736378) (xy 343.417756 -221.777931) (xy 343.44043 -221.823497)
			(xy 343.455853 -221.871999) (xy 343.463661 -221.922292) (xy 343.464134 -221.94774) (xy 343.463625 -221.973707)
			(xy 343.743535 -221.973707) (xy 343.743535 -221.921773) (xy 343.75166 -221.870478) (xy 343.767708 -221.821085)
			(xy 343.791286 -221.774811) (xy 343.821812 -221.732795) (xy 343.858535 -221.696072) (xy 343.900551 -221.665546)
			(xy 343.946825 -221.641968) (xy 343.996218 -221.62592) (xy 344.047513 -221.617795) (xy 344.099447 -221.617795)
			(xy 344.150742 -221.62592) (xy 344.200135 -221.641968) (xy 344.246409 -221.665546) (xy 344.288425 -221.696072)
			(xy 344.325148 -221.732795) (xy 344.355674 -221.774811) (xy 344.379252 -221.821085) (xy 344.3953 -221.870478)
			(xy 344.403425 -221.921773) (xy 344.403934 -221.94774) (xy 344.403425 -221.973707) (xy 344.3953 -222.025002)
			(xy 344.379252 -222.074395) (xy 344.355674 -222.120669) (xy 344.325148 -222.162685) (xy 344.288425 -222.199408)
			(xy 344.246409 -222.229934) (xy 344.200135 -222.253512) (xy 344.150742 -222.26956) (xy 344.099447 -222.277685)
			(xy 344.047513 -222.277685) (xy 343.996218 -222.26956) (xy 343.946825 -222.253512) (xy 343.900551 -222.229934)
			(xy 343.858535 -222.199408) (xy 343.821812 -222.162685) (xy 343.791286 -222.120669) (xy 343.767708 -222.074395)
			(xy 343.75166 -222.025002) (xy 343.743535 -221.973707) (xy 343.463625 -221.973707) (xy 343.4555 -222.025002)
			(xy 343.439452 -222.074395) (xy 343.415874 -222.120669) (xy 343.385348 -222.162685) (xy 343.348625 -222.199408)
			(xy 343.306609 -222.229934) (xy 343.260335 -222.253512) (xy 343.210942 -222.26956) (xy 343.159647 -222.277685)
			(xy 343.107713 -222.277685) (xy 343.056418 -222.26956) (xy 343.007025 -222.253512) (xy 342.960751 -222.229934)
			(xy 342.918735 -222.199408) (xy 342.882012 -222.162685) (xy 342.851486 -222.120669) (xy 342.827908 -222.074395)
			(xy 342.81186 -222.025002) (xy 342.803735 -221.973707) (xy 342.803226 -221.94774) (xy 342.803787 -221.919755)
			(xy 342.813231 -221.864587) (xy 342.822022 -221.838012) (xy 342.829642 -221.815914) (xy 342.625934 -221.463108)
			(xy 342.603074 -221.45879) (xy 342.578145 -221.453653) (xy 342.530158 -221.436688) (xy 342.485337 -221.412568)
			(xy 342.444743 -221.381864) (xy 342.409334 -221.345302) (xy 342.379946 -221.303745) (xy 342.357274 -221.258175)
			(xy 342.341854 -221.209669) (xy 342.33405 -221.159373) (xy 342.33358 -221.133924) (xy 342.054688 -221.133924)
			(xy 342.054179 -221.159891) (xy 342.046054 -221.211186) (xy 342.030006 -221.260579) (xy 342.006428 -221.306853)
			(xy 341.975902 -221.348869) (xy 341.939179 -221.385592) (xy 341.897163 -221.416118) (xy 341.850889 -221.439696)
			(xy 341.801496 -221.455744) (xy 341.750201 -221.463869) (xy 341.698267 -221.463869) (xy 341.646972 -221.455744)
			(xy 341.597579 -221.439696) (xy 341.551305 -221.416118) (xy 341.509289 -221.385592) (xy 341.472566 -221.348869)
			(xy 341.44204 -221.306853) (xy 341.418462 -221.260579) (xy 341.402414 -221.211186) (xy 341.394289 -221.159891)
			(xy 341.39378 -221.133924) (xy 341.114888 -221.133924) (xy 341.114342 -221.16191) (xy 341.104887 -221.217078)
			(xy 341.096092 -221.243652) (xy 341.088472 -221.26575) (xy 341.29218 -221.618556) (xy 341.31504 -221.622874)
			(xy 341.339963 -221.628034) (xy 341.387948 -221.644999) (xy 341.432766 -221.669118) (xy 341.473359 -221.699819)
			(xy 341.508768 -221.736378) (xy 341.538156 -221.777931) (xy 341.56083 -221.823497) (xy 341.576253 -221.871999)
			(xy 341.584061 -221.922292) (xy 341.584534 -221.94774) (xy 341.584025 -221.973707) (xy 341.863935 -221.973707)
			(xy 341.863935 -221.921773) (xy 341.87206 -221.870478) (xy 341.888108 -221.821085) (xy 341.911686 -221.774811)
			(xy 341.942212 -221.732795) (xy 341.978935 -221.696072) (xy 342.020951 -221.665546) (xy 342.067225 -221.641968)
			(xy 342.116618 -221.62592) (xy 342.167913 -221.617795) (xy 342.219847 -221.617795) (xy 342.271142 -221.62592)
			(xy 342.320535 -221.641968) (xy 342.366809 -221.665546) (xy 342.408825 -221.696072) (xy 342.445548 -221.732795)
			(xy 342.476074 -221.774811) (xy 342.499652 -221.821085) (xy 342.5157 -221.870478) (xy 342.523825 -221.921773)
			(xy 342.524334 -221.94774) (xy 342.523825 -221.973707) (xy 342.5157 -222.025002) (xy 342.499652 -222.074395)
			(xy 342.476074 -222.120669) (xy 342.445548 -222.162685) (xy 342.408825 -222.199408) (xy 342.366809 -222.229934)
			(xy 342.320535 -222.253512) (xy 342.271142 -222.26956) (xy 342.219847 -222.277685) (xy 342.167913 -222.277685)
			(xy 342.116618 -222.26956) (xy 342.067225 -222.253512) (xy 342.020951 -222.229934) (xy 341.978935 -222.199408)
			(xy 341.942212 -222.162685) (xy 341.911686 -222.120669) (xy 341.888108 -222.074395) (xy 341.87206 -222.025002)
			(xy 341.863935 -221.973707) (xy 341.584025 -221.973707) (xy 341.5759 -222.025002) (xy 341.559852 -222.074395)
			(xy 341.536274 -222.120669) (xy 341.505748 -222.162685) (xy 341.469025 -222.199408) (xy 341.427009 -222.229934)
			(xy 341.380735 -222.253512) (xy 341.331342 -222.26956) (xy 341.280047 -222.277685) (xy 341.228113 -222.277685)
			(xy 341.176818 -222.26956) (xy 341.127425 -222.253512) (xy 341.081151 -222.229934) (xy 341.039135 -222.199408)
			(xy 341.002412 -222.162685) (xy 340.971886 -222.120669) (xy 340.948308 -222.074395) (xy 340.93226 -222.025002)
			(xy 340.924135 -221.973707) (xy 340.923626 -221.94774) (xy 340.924187 -221.919755) (xy 340.933631 -221.864587)
			(xy 340.942422 -221.838012) (xy 340.950042 -221.815914) (xy 340.746334 -221.463108) (xy 340.723474 -221.45879)
			(xy 340.698545 -221.453653) (xy 340.650558 -221.436688) (xy 340.605737 -221.412568) (xy 340.565143 -221.381864)
			(xy 340.529734 -221.345302) (xy 340.500346 -221.303745) (xy 340.477674 -221.258175) (xy 340.462254 -221.209669)
			(xy 340.45445 -221.159373) (xy 340.45398 -221.133924) (xy 340.175088 -221.133924) (xy 340.174579 -221.159891)
			(xy 340.166454 -221.211186) (xy 340.150406 -221.260579) (xy 340.126828 -221.306853) (xy 340.096302 -221.348869)
			(xy 340.059579 -221.385592) (xy 340.017563 -221.416118) (xy 339.971289 -221.439696) (xy 339.921896 -221.455744)
			(xy 339.870601 -221.463869) (xy 339.818667 -221.463869) (xy 339.767372 -221.455744) (xy 339.717979 -221.439696)
			(xy 339.671705 -221.416118) (xy 339.629689 -221.385592) (xy 339.592966 -221.348869) (xy 339.56244 -221.306853)
			(xy 339.538862 -221.260579) (xy 339.522814 -221.211186) (xy 339.514689 -221.159891) (xy 339.51418 -221.133924)
			(xy 339.235288 -221.133924) (xy 339.234742 -221.16191) (xy 339.225287 -221.217078) (xy 339.216492 -221.243652)
			(xy 339.208872 -221.26575) (xy 339.41258 -221.618556) (xy 339.43544 -221.622874) (xy 339.460363 -221.628034)
			(xy 339.508348 -221.644999) (xy 339.553166 -221.669118) (xy 339.593759 -221.699819) (xy 339.629168 -221.736378)
			(xy 339.658556 -221.777931) (xy 339.68123 -221.823497) (xy 339.696653 -221.871999) (xy 339.704461 -221.922292)
			(xy 339.704934 -221.94774) (xy 339.704425 -221.973707) (xy 339.984335 -221.973707) (xy 339.984335 -221.921773)
			(xy 339.99246 -221.870478) (xy 340.008508 -221.821085) (xy 340.032086 -221.774811) (xy 340.062612 -221.732795)
			(xy 340.099335 -221.696072) (xy 340.141351 -221.665546) (xy 340.187625 -221.641968) (xy 340.237018 -221.62592)
			(xy 340.288313 -221.617795) (xy 340.340247 -221.617795) (xy 340.391542 -221.62592) (xy 340.440935 -221.641968)
			(xy 340.487209 -221.665546) (xy 340.529225 -221.696072) (xy 340.565948 -221.732795) (xy 340.596474 -221.774811)
			(xy 340.620052 -221.821085) (xy 340.6361 -221.870478) (xy 340.644225 -221.921773) (xy 340.644734 -221.94774)
			(xy 340.644225 -221.973707) (xy 340.6361 -222.025002) (xy 340.620052 -222.074395) (xy 340.596474 -222.120669)
			(xy 340.565948 -222.162685) (xy 340.529225 -222.199408) (xy 340.487209 -222.229934) (xy 340.440935 -222.253512)
			(xy 340.391542 -222.26956) (xy 340.340247 -222.277685) (xy 340.288313 -222.277685) (xy 340.237018 -222.26956)
			(xy 340.187625 -222.253512) (xy 340.141351 -222.229934) (xy 340.099335 -222.199408) (xy 340.062612 -222.162685)
			(xy 340.032086 -222.120669) (xy 340.008508 -222.074395) (xy 339.99246 -222.025002) (xy 339.984335 -221.973707)
			(xy 339.704425 -221.973707) (xy 339.6963 -222.025002) (xy 339.680252 -222.074395) (xy 339.656674 -222.120669)
			(xy 339.626148 -222.162685) (xy 339.589425 -222.199408) (xy 339.547409 -222.229934) (xy 339.501135 -222.253512)
			(xy 339.451742 -222.26956) (xy 339.400447 -222.277685) (xy 339.348513 -222.277685) (xy 339.297218 -222.26956)
			(xy 339.247825 -222.253512) (xy 339.201551 -222.229934) (xy 339.159535 -222.199408) (xy 339.122812 -222.162685)
			(xy 339.092286 -222.120669) (xy 339.068708 -222.074395) (xy 339.05266 -222.025002) (xy 339.044535 -221.973707)
			(xy 339.044026 -221.94774) (xy 339.044587 -221.919755) (xy 339.054031 -221.864587) (xy 339.062822 -221.838012)
			(xy 339.070442 -221.815914) (xy 338.866734 -221.463108) (xy 338.843874 -221.45879) (xy 338.818945 -221.453653)
			(xy 338.770958 -221.436688) (xy 338.726137 -221.412568) (xy 338.685543 -221.381864) (xy 338.650134 -221.345302)
			(xy 338.620746 -221.303745) (xy 338.598074 -221.258175) (xy 338.582654 -221.209669) (xy 338.57485 -221.159373)
			(xy 338.57438 -221.133924) (xy 338.295488 -221.133924) (xy 338.294979 -221.159891) (xy 338.286854 -221.211186)
			(xy 338.270806 -221.260579) (xy 338.247228 -221.306853) (xy 338.216702 -221.348869) (xy 338.179979 -221.385592)
			(xy 338.137963 -221.416118) (xy 338.091689 -221.439696) (xy 338.042296 -221.455744) (xy 337.991001 -221.463869)
			(xy 337.939067 -221.463869) (xy 337.887772 -221.455744) (xy 337.838379 -221.439696) (xy 337.792105 -221.416118)
			(xy 337.750089 -221.385592) (xy 337.713366 -221.348869) (xy 337.68284 -221.306853) (xy 337.659262 -221.260579)
			(xy 337.643214 -221.211186) (xy 337.635089 -221.159891) (xy 337.63458 -221.133924) (xy 337.355688 -221.133924)
			(xy 337.355142 -221.16191) (xy 337.345687 -221.217078) (xy 337.336892 -221.243652) (xy 337.329272 -221.26575)
			(xy 337.53298 -221.618556) (xy 337.55584 -221.622874) (xy 337.580763 -221.628034) (xy 337.628748 -221.644999)
			(xy 337.673566 -221.669118) (xy 337.714159 -221.699819) (xy 337.749568 -221.736378) (xy 337.778956 -221.777931)
			(xy 337.80163 -221.823497) (xy 337.817053 -221.871999) (xy 337.824861 -221.922292) (xy 337.825334 -221.94774)
			(xy 337.824825 -221.973707) (xy 338.104735 -221.973707) (xy 338.104735 -221.921773) (xy 338.11286 -221.870478)
			(xy 338.128908 -221.821085) (xy 338.152486 -221.774811) (xy 338.183012 -221.732795) (xy 338.219735 -221.696072)
			(xy 338.261751 -221.665546) (xy 338.308025 -221.641968) (xy 338.357418 -221.62592) (xy 338.408713 -221.617795)
			(xy 338.460647 -221.617795) (xy 338.511942 -221.62592) (xy 338.561335 -221.641968) (xy 338.607609 -221.665546)
			(xy 338.649625 -221.696072) (xy 338.686348 -221.732795) (xy 338.716874 -221.774811) (xy 338.740452 -221.821085)
			(xy 338.7565 -221.870478) (xy 338.764625 -221.921773) (xy 338.765134 -221.94774) (xy 338.764625 -221.973707)
			(xy 338.7565 -222.025002) (xy 338.740452 -222.074395) (xy 338.716874 -222.120669) (xy 338.686348 -222.162685)
			(xy 338.649625 -222.199408) (xy 338.607609 -222.229934) (xy 338.561335 -222.253512) (xy 338.511942 -222.26956)
			(xy 338.460647 -222.277685) (xy 338.408713 -222.277685) (xy 338.357418 -222.26956) (xy 338.308025 -222.253512)
			(xy 338.261751 -222.229934) (xy 338.219735 -222.199408) (xy 338.183012 -222.162685) (xy 338.152486 -222.120669)
			(xy 338.128908 -222.074395) (xy 338.11286 -222.025002) (xy 338.104735 -221.973707) (xy 337.824825 -221.973707)
			(xy 337.8167 -222.025002) (xy 337.800652 -222.074395) (xy 337.777074 -222.120669) (xy 337.746548 -222.162685)
			(xy 337.709825 -222.199408) (xy 337.667809 -222.229934) (xy 337.621535 -222.253512) (xy 337.572142 -222.26956)
			(xy 337.520847 -222.277685) (xy 337.468913 -222.277685) (xy 337.417618 -222.26956) (xy 337.368225 -222.253512)
			(xy 337.321951 -222.229934) (xy 337.279935 -222.199408) (xy 337.243212 -222.162685) (xy 337.212686 -222.120669)
			(xy 337.189108 -222.074395) (xy 337.17306 -222.025002) (xy 337.164935 -221.973707) (xy 337.164426 -221.94774)
			(xy 337.164987 -221.919755) (xy 337.174431 -221.864587) (xy 337.183222 -221.838012) (xy 337.190842 -221.815914)
			(xy 336.987134 -221.463108) (xy 336.964274 -221.45879) (xy 336.939345 -221.453653) (xy 336.891358 -221.436688)
			(xy 336.846537 -221.412568) (xy 336.805943 -221.381864) (xy 336.770534 -221.345302) (xy 336.741146 -221.303745)
			(xy 336.718474 -221.258175) (xy 336.703054 -221.209669) (xy 336.69525 -221.159373) (xy 336.69478 -221.133924)
			(xy 336.415888 -221.133924) (xy 336.415379 -221.159891) (xy 336.407254 -221.211186) (xy 336.391206 -221.260579)
			(xy 336.367628 -221.306853) (xy 336.337102 -221.348869) (xy 336.300379 -221.385592) (xy 336.258363 -221.416118)
			(xy 336.212089 -221.439696) (xy 336.162696 -221.455744) (xy 336.111401 -221.463869) (xy 336.059467 -221.463869)
			(xy 336.008172 -221.455744) (xy 335.958779 -221.439696) (xy 335.912505 -221.416118) (xy 335.870489 -221.385592)
			(xy 335.833766 -221.348869) (xy 335.80324 -221.306853) (xy 335.779662 -221.260579) (xy 335.763614 -221.211186)
			(xy 335.755489 -221.159891) (xy 333.541878 -221.159891) (xy 333.541878 -221.972709) (xy 334.35847 -221.972709)
			(xy 334.35847 -221.922771) (xy 334.366282 -221.873447) (xy 334.381713 -221.825953) (xy 334.404385 -221.781457)
			(xy 334.433738 -221.741056) (xy 334.46905 -221.705744) (xy 334.509451 -221.676391) (xy 334.553947 -221.653719)
			(xy 334.601441 -221.638288) (xy 334.650765 -221.630476) (xy 334.700703 -221.630476) (xy 334.750027 -221.638288)
			(xy 334.797521 -221.653719) (xy 334.842017 -221.676391) (xy 334.882418 -221.705744) (xy 334.91773 -221.741056)
			(xy 334.947083 -221.781457) (xy 334.969755 -221.825953) (xy 334.985186 -221.873447) (xy 334.992998 -221.922771)
			(xy 334.993488 -221.94774) (xy 334.992998 -221.972709) (xy 334.99284 -221.973707) (xy 335.285589 -221.973707)
			(xy 335.285589 -221.921773) (xy 335.293714 -221.870478) (xy 335.309762 -221.821085) (xy 335.33334 -221.774811)
			(xy 335.363866 -221.732795) (xy 335.400589 -221.696072) (xy 335.442605 -221.665546) (xy 335.488879 -221.641968)
			(xy 335.538272 -221.62592) (xy 335.589567 -221.617795) (xy 335.641501 -221.617795) (xy 335.692796 -221.62592)
			(xy 335.742189 -221.641968) (xy 335.788463 -221.665546) (xy 335.830479 -221.696072) (xy 335.867202 -221.732795)
			(xy 335.897728 -221.774811) (xy 335.921306 -221.821085) (xy 335.937354 -221.870478) (xy 335.945479 -221.921773)
			(xy 335.945988 -221.94774) (xy 335.945479 -221.973707) (xy 336.225135 -221.973707) (xy 336.225135 -221.921773)
			(xy 336.23326 -221.870478) (xy 336.249308 -221.821085) (xy 336.272886 -221.774811) (xy 336.303412 -221.732795)
			(xy 336.340135 -221.696072) (xy 336.382151 -221.665546) (xy 336.428425 -221.641968) (xy 336.477818 -221.62592)
			(xy 336.529113 -221.617795) (xy 336.581047 -221.617795) (xy 336.632342 -221.62592) (xy 336.681735 -221.641968)
			(xy 336.728009 -221.665546) (xy 336.770025 -221.696072) (xy 336.806748 -221.732795) (xy 336.837274 -221.774811)
			(xy 336.860852 -221.821085) (xy 336.8769 -221.870478) (xy 336.885025 -221.921773) (xy 336.885534 -221.94774)
			(xy 336.885025 -221.973707) (xy 336.8769 -222.025002) (xy 336.860852 -222.074395) (xy 336.837274 -222.120669)
			(xy 336.806748 -222.162685) (xy 336.770025 -222.199408) (xy 336.728009 -222.229934) (xy 336.681735 -222.253512)
			(xy 336.632342 -222.26956) (xy 336.581047 -222.277685) (xy 336.529113 -222.277685) (xy 336.477818 -222.26956)
			(xy 336.428425 -222.253512) (xy 336.382151 -222.229934) (xy 336.340135 -222.199408) (xy 336.303412 -222.162685)
			(xy 336.272886 -222.120669) (xy 336.249308 -222.074395) (xy 336.23326 -222.025002) (xy 336.225135 -221.973707)
			(xy 335.945479 -221.973707) (xy 335.937354 -222.025002) (xy 335.921306 -222.074395) (xy 335.897728 -222.120669)
			(xy 335.867202 -222.162685) (xy 335.830479 -222.199408) (xy 335.788463 -222.229934) (xy 335.742189 -222.253512)
			(xy 335.692796 -222.26956) (xy 335.641501 -222.277685) (xy 335.589567 -222.277685) (xy 335.538272 -222.26956)
			(xy 335.488879 -222.253512) (xy 335.442605 -222.229934) (xy 335.400589 -222.199408) (xy 335.363866 -222.162685)
			(xy 335.33334 -222.120669) (xy 335.309762 -222.074395) (xy 335.293714 -222.025002) (xy 335.285589 -221.973707)
			(xy 334.99284 -221.973707) (xy 334.985186 -222.022033) (xy 334.969755 -222.069527) (xy 334.947083 -222.114023)
			(xy 334.91773 -222.154424) (xy 334.882418 -222.189736) (xy 334.842017 -222.219089) (xy 334.797521 -222.241761)
			(xy 334.750027 -222.257192) (xy 334.700703 -222.265004) (xy 334.650765 -222.265004) (xy 334.601441 -222.257192)
			(xy 334.553947 -222.241761) (xy 334.509451 -222.219089) (xy 334.46905 -222.189736) (xy 334.433738 -222.154424)
			(xy 334.404385 -222.114023) (xy 334.381713 -222.069527) (xy 334.366282 -222.022033) (xy 334.35847 -221.972709)
			(xy 333.541878 -221.972709) (xy 333.541878 -222.08363) (xy 333.948278 -222.49003) (xy 334.016858 -222.49003)
			(xy 334.029304 -222.482156) (xy 334.049209 -222.470063) (xy 334.091692 -222.450977) (xy 334.136433 -222.438042)
			(xy 334.182547 -222.431511) (xy 334.205834 -222.431102) (xy 334.23091 -222.431574) (xy 334.280487 -222.439156)
			(xy 334.328354 -222.454126) (xy 334.373417 -222.476142) (xy 334.394302 -222.49003) (xy 334.957166 -222.49003)
			(xy 334.978032 -222.476107) (xy 335.023088 -222.454062) (xy 335.070964 -222.439093) (xy 335.120553 -222.431548)
			(xy 335.145634 -222.431102) (xy 335.17071 -222.431574) (xy 335.220287 -222.439156) (xy 335.268154 -222.454126)
			(xy 335.313217 -222.476142) (xy 335.334102 -222.49003) (xy 335.896966 -222.49003) (xy 335.917832 -222.476107)
			(xy 335.962888 -222.454062) (xy 336.010764 -222.439093) (xy 336.060353 -222.431548) (xy 336.085434 -222.431102)
			(xy 336.11051 -222.431574) (xy 336.160087 -222.439156) (xy 336.207954 -222.454126) (xy 336.253017 -222.476142)
			(xy 336.273902 -222.49003) (xy 336.836766 -222.49003) (xy 336.857632 -222.476107) (xy 336.902688 -222.454062)
			(xy 336.950564 -222.439093) (xy 337.000153 -222.431548) (xy 337.025234 -222.431102) (xy 337.05031 -222.431574)
			(xy 337.099887 -222.439156) (xy 337.147754 -222.454126) (xy 337.192817 -222.476142) (xy 337.213702 -222.49003)
			(xy 337.776566 -222.49003) (xy 337.797432 -222.476107) (xy 337.842488 -222.454062) (xy 337.890364 -222.439093)
			(xy 337.939953 -222.431548) (xy 337.965034 -222.431102) (xy 337.99011 -222.431574) (xy 338.039687 -222.439156)
			(xy 338.087554 -222.454126) (xy 338.132617 -222.476142) (xy 338.153502 -222.49003) (xy 338.716366 -222.49003)
			(xy 338.737232 -222.476107) (xy 338.782288 -222.454062) (xy 338.830164 -222.439093) (xy 338.879753 -222.431548)
			(xy 338.904834 -222.431102) (xy 338.92991 -222.431574) (xy 338.979487 -222.439156) (xy 339.027354 -222.454126)
			(xy 339.072417 -222.476142) (xy 339.093302 -222.49003) (xy 339.656166 -222.49003) (xy 339.677032 -222.476107)
			(xy 339.722088 -222.454062) (xy 339.769964 -222.439093) (xy 339.819553 -222.431548) (xy 339.844634 -222.431102)
			(xy 339.86971 -222.431574) (xy 339.919287 -222.439156) (xy 339.967154 -222.454126) (xy 340.012217 -222.476142)
			(xy 340.033102 -222.49003) (xy 340.595966 -222.49003) (xy 340.616832 -222.476107) (xy 340.661888 -222.454062)
			(xy 340.709764 -222.439093) (xy 340.759353 -222.431548) (xy 340.784434 -222.431102) (xy 340.811925 -222.43165)
			(xy 340.866149 -222.440752) (xy 340.91812 -222.458699) (xy 340.966406 -222.484997) (xy 341.009675 -222.518921)
			(xy 341.046736 -222.559536) (xy 341.076567 -222.605722) (xy 341.087964 -222.630746) (xy 341.091774 -222.639636)
			(xy 341.224616 -222.772478) (xy 341.234899 -222.78212) (xy 341.259509 -222.795847) (xy 341.286932 -222.802329)
			(xy 341.315083 -222.801074) (xy 341.34182 -222.792177) (xy 341.365111 -222.776315) (xy 341.383183 -222.754695)
			(xy 341.394663 -222.72896) (xy 341.397082 -222.715074) (xy 341.401279 -222.689146) (xy 341.416803 -222.638972)
			(xy 341.440067 -222.591885) (xy 341.470484 -222.549069) (xy 341.507291 -222.511602) (xy 341.549559 -222.480429)
			(xy 341.596225 -222.456332) (xy 341.646116 -222.439918) (xy 341.697974 -222.431602) (xy 341.724234 -222.431102)
			(xy 341.750201 -222.431614) (xy 341.801494 -222.439742) (xy 341.850885 -222.455793) (xy 341.897157 -222.479372)
			(xy 341.939172 -222.509898) (xy 341.975895 -222.54662) (xy 342.006423 -222.588634) (xy 342.030003 -222.634906)
			(xy 342.046056 -222.684296) (xy 342.054185 -222.735589) (xy 342.054688 -222.761556) (xy 342.054191 -222.787523)
			(xy 342.334089 -222.787523) (xy 342.334089 -222.735589) (xy 342.342214 -222.684294) (xy 342.358262 -222.634901)
			(xy 342.38184 -222.588627) (xy 342.412366 -222.546611) (xy 342.449089 -222.509888) (xy 342.491105 -222.479362)
			(xy 342.537379 -222.455784) (xy 342.586772 -222.439736) (xy 342.638067 -222.431611) (xy 342.690001 -222.431611)
			(xy 342.741296 -222.439736) (xy 342.790689 -222.455784) (xy 342.836963 -222.479362) (xy 342.878979 -222.509888)
			(xy 342.915702 -222.546611) (xy 342.946228 -222.588627) (xy 342.969806 -222.634901) (xy 342.985854 -222.684294)
			(xy 342.993979 -222.735589) (xy 342.994488 -222.761556) (xy 342.993979 -222.787523) (xy 343.273889 -222.787523)
			(xy 343.273889 -222.735589) (xy 343.282014 -222.684294) (xy 343.298062 -222.634901) (xy 343.32164 -222.588627)
			(xy 343.352166 -222.546611) (xy 343.388889 -222.509888) (xy 343.430905 -222.479362) (xy 343.477179 -222.455784)
			(xy 343.526572 -222.439736) (xy 343.577867 -222.431611) (xy 343.629801 -222.431611) (xy 343.681096 -222.439736)
			(xy 343.730489 -222.455784) (xy 343.776763 -222.479362) (xy 343.818779 -222.509888) (xy 343.855502 -222.546611)
			(xy 343.886028 -222.588627) (xy 343.909606 -222.634901) (xy 343.925654 -222.684294) (xy 343.933779 -222.735589)
			(xy 343.934288 -222.761556) (xy 343.933779 -222.787523) (xy 344.213689 -222.787523) (xy 344.213689 -222.735589)
			(xy 344.221814 -222.684294) (xy 344.237862 -222.634901) (xy 344.26144 -222.588627) (xy 344.291966 -222.546611)
			(xy 344.328689 -222.509888) (xy 344.370705 -222.479362) (xy 344.416979 -222.455784) (xy 344.466372 -222.439736)
			(xy 344.517667 -222.431611) (xy 344.569601 -222.431611) (xy 344.620896 -222.439736) (xy 344.670289 -222.455784)
			(xy 344.716563 -222.479362) (xy 344.758579 -222.509888) (xy 344.795302 -222.546611) (xy 344.825828 -222.588627)
			(xy 344.849406 -222.634901) (xy 344.865454 -222.684294) (xy 344.873579 -222.735589) (xy 344.874088 -222.761556)
			(xy 344.873579 -222.787523) (xy 344.865454 -222.838818) (xy 344.849406 -222.888211) (xy 344.825828 -222.934485)
			(xy 344.795302 -222.976501) (xy 344.758579 -223.013224) (xy 344.716563 -223.04375) (xy 344.670289 -223.067328)
			(xy 344.620896 -223.083376) (xy 344.569601 -223.091501) (xy 344.517667 -223.091501) (xy 344.466372 -223.083376)
			(xy 344.416979 -223.067328) (xy 344.370705 -223.04375) (xy 344.328689 -223.013224) (xy 344.291966 -222.976501)
			(xy 344.26144 -222.934485) (xy 344.237862 -222.888211) (xy 344.221814 -222.838818) (xy 344.213689 -222.787523)
			(xy 343.933779 -222.787523) (xy 343.925654 -222.838818) (xy 343.909606 -222.888211) (xy 343.886028 -222.934485)
			(xy 343.855502 -222.976501) (xy 343.818779 -223.013224) (xy 343.776763 -223.04375) (xy 343.730489 -223.067328)
			(xy 343.681096 -223.083376) (xy 343.629801 -223.091501) (xy 343.577867 -223.091501) (xy 343.526572 -223.083376)
			(xy 343.477179 -223.067328) (xy 343.430905 -223.04375) (xy 343.388889 -223.013224) (xy 343.352166 -222.976501)
			(xy 343.32164 -222.934485) (xy 343.298062 -222.888211) (xy 343.282014 -222.838818) (xy 343.273889 -222.787523)
			(xy 342.993979 -222.787523) (xy 342.985854 -222.838818) (xy 342.969806 -222.888211) (xy 342.946228 -222.934485)
			(xy 342.915702 -222.976501) (xy 342.878979 -223.013224) (xy 342.836963 -223.04375) (xy 342.790689 -223.067328)
			(xy 342.741296 -223.083376) (xy 342.690001 -223.091501) (xy 342.638067 -223.091501) (xy 342.586772 -223.083376)
			(xy 342.537379 -223.067328) (xy 342.491105 -223.04375) (xy 342.449089 -223.013224) (xy 342.412366 -222.976501)
			(xy 342.38184 -222.934485) (xy 342.358262 -222.888211) (xy 342.342214 -222.838818) (xy 342.334089 -222.787523)
			(xy 342.054191 -222.787523) (xy 342.054185 -222.787818) (xy 342.045882 -222.839682) (xy 342.029477 -222.889578)
			(xy 342.005385 -222.936251) (xy 341.974211 -222.978524) (xy 341.936742 -223.015332) (xy 341.893921 -223.045748)
			(xy 341.846828 -223.069006) (xy 341.796647 -223.08452) (xy 341.770716 -223.088708) (xy 341.75684 -223.091164)
			(xy 341.731115 -223.102641) (xy 341.709503 -223.120707) (xy 341.693647 -223.14399) (xy 341.684752 -223.170718)
			(xy 341.683496 -223.198859) (xy 341.689974 -223.226273) (xy 341.703692 -223.250875) (xy 341.713312 -223.261174)
			(xy 341.80526 -223.353122) (xy 341.8152 -223.362472) (xy 341.838887 -223.375998) (xy 341.865311 -223.382767)
			(xy 341.892585 -223.382296) (xy 341.918759 -223.374617) (xy 341.941965 -223.36028) (xy 341.951564 -223.350582)
			(xy 341.970488 -223.331022) (xy 342.013553 -223.297752) (xy 342.061483 -223.27198) (xy 342.112985 -223.254401)
			(xy 342.16667 -223.24549) (xy 342.19388 -223.244918) (xy 342.21987 -223.2454) (xy 342.271209 -223.253529)
			(xy 342.320645 -223.269589) (xy 342.366959 -223.293186) (xy 342.409011 -223.323739) (xy 342.445765 -223.360494)
			(xy 342.476317 -223.402546) (xy 342.499913 -223.448861) (xy 342.515973 -223.498297) (xy 342.524101 -223.549636)
			(xy 342.524588 -223.575626) (xy 342.524079 -223.601589) (xy 342.524078 -223.601593) (xy 342.803989 -223.601593)
			(xy 342.803989 -223.549659) (xy 342.812114 -223.498364) (xy 342.828162 -223.448971) (xy 342.85174 -223.402697)
			(xy 342.882266 -223.360681) (xy 342.918989 -223.323958) (xy 342.961005 -223.293432) (xy 343.007279 -223.269854)
			(xy 343.056672 -223.253806) (xy 343.107967 -223.245681) (xy 343.159901 -223.245681) (xy 343.211196 -223.253806)
			(xy 343.260589 -223.269854) (xy 343.306863 -223.293432) (xy 343.348879 -223.323958) (xy 343.385602 -223.360681)
			(xy 343.416128 -223.402697) (xy 343.439706 -223.448971) (xy 343.455754 -223.498364) (xy 343.463879 -223.549659)
			(xy 343.464388 -223.575626) (xy 343.463879 -223.601593) (xy 343.455754 -223.652888) (xy 343.439706 -223.702281)
			(xy 343.416128 -223.748555) (xy 343.385602 -223.790571) (xy 343.348879 -223.827294) (xy 343.306863 -223.85782)
			(xy 343.260589 -223.881398) (xy 343.211196 -223.897446) (xy 343.159901 -223.905571) (xy 343.107967 -223.905571)
			(xy 343.056672 -223.897446) (xy 343.007279 -223.881398) (xy 342.961005 -223.85782) (xy 342.918989 -223.827294)
			(xy 342.882266 -223.790571) (xy 342.85174 -223.748555) (xy 342.828162 -223.702281) (xy 342.812114 -223.652888)
			(xy 342.803989 -223.601593) (xy 342.524078 -223.601593) (xy 342.515964 -223.652877) (xy 342.499936 -223.702268)
			(xy 342.476391 -223.748549) (xy 342.445905 -223.790584) (xy 342.409227 -223.827341) (xy 342.367258 -223.857918)
			(xy 342.321028 -223.881563) (xy 342.296496 -223.890078) (xy 342.261444 -223.901508) (xy 342.261444 -224.079054)
			(xy 342.261955 -224.093946) (xy 342.270535 -224.122467) (xy 342.286979 -224.1473) (xy 342.309887 -224.166332)
			(xy 342.337313 -224.177946) (xy 342.366923 -224.181154) (xy 342.3962 -224.175683) (xy 342.422653 -224.161997)
			(xy 342.433656 -224.151952) (xy 342.452291 -224.134553) (xy 342.493917 -224.105117) (xy 342.539567 -224.082417)
			(xy 342.588159 -224.066991) (xy 342.638543 -224.059203) (xy 342.664034 -224.058734) (xy 342.69002 -224.05922)
			(xy 342.741352 -224.067355) (xy 342.79078 -224.083421) (xy 342.837085 -224.107021) (xy 342.879128 -224.137575)
			(xy 342.915874 -224.174329) (xy 342.946418 -224.21638) (xy 342.970008 -224.262691) (xy 342.986062 -224.312122)
			(xy 342.994186 -224.363456) (xy 342.994742 -224.389442) (xy 343.273126 -224.389442) (xy 343.273538 -224.363966)
			(xy 343.281333 -224.313615) (xy 343.29676 -224.265055) (xy 343.319455 -224.219437) (xy 343.348879 -224.177841)
			(xy 343.384336 -224.141251) (xy 343.424987 -224.110534) (xy 343.469869 -224.086417) (xy 343.51792 -224.069471)
			(xy 343.542874 -224.064322) (xy 343.565988 -224.060004) (xy 343.769442 -223.707452) (xy 343.761568 -223.685608)
			(xy 343.752825 -223.658955) (xy 343.743369 -223.60367) (xy 343.742772 -223.575626) (xy 343.743282 -223.549639)
			(xy 343.751412 -223.498304) (xy 343.767473 -223.448874) (xy 343.791069 -223.402564) (xy 343.821619 -223.360516)
			(xy 343.85837 -223.323765) (xy 343.900418 -223.293215) (xy 343.946728 -223.269619) (xy 343.996158 -223.253558)
			(xy 344.047493 -223.245428) (xy 344.099467 -223.245428) (xy 344.150802 -223.253558) (xy 344.200232 -223.269619)
			(xy 344.246542 -223.293215) (xy 344.28859 -223.323765) (xy 344.325341 -223.360516) (xy 344.355891 -223.402564)
			(xy 344.379487 -223.448874) (xy 344.395548 -223.498304) (xy 344.403678 -223.549639) (xy 344.404188 -223.575626)
			(xy 344.403697 -223.601109) (xy 344.403622 -223.601593) (xy 344.683589 -223.601593) (xy 344.683589 -223.549659)
			(xy 344.691714 -223.498364) (xy 344.707762 -223.448971) (xy 344.73134 -223.402697) (xy 344.761866 -223.360681)
			(xy 344.798589 -223.323958) (xy 344.840605 -223.293432) (xy 344.886879 -223.269854) (xy 344.936272 -223.253806)
			(xy 344.987567 -223.245681) (xy 345.039501 -223.245681) (xy 345.090796 -223.253806) (xy 345.140189 -223.269854)
			(xy 345.186463 -223.293432) (xy 345.228479 -223.323958) (xy 345.265202 -223.360681) (xy 345.295728 -223.402697)
			(xy 345.319306 -223.448971) (xy 345.335354 -223.498364) (xy 345.343479 -223.549659) (xy 345.343988 -223.575626)
			(xy 345.343479 -223.601593) (xy 345.335354 -223.652888) (xy 345.319306 -223.702281) (xy 345.295728 -223.748555)
			(xy 345.265202 -223.790571) (xy 345.228479 -223.827294) (xy 345.186463 -223.85782) (xy 345.140189 -223.881398)
			(xy 345.090796 -223.897446) (xy 345.039501 -223.905571) (xy 344.987567 -223.905571) (xy 344.936272 -223.897446)
			(xy 344.886879 -223.881398) (xy 344.840605 -223.85782) (xy 344.798589 -223.827294) (xy 344.761866 -223.790571)
			(xy 344.73134 -223.748555) (xy 344.707762 -223.702281) (xy 344.691714 -223.652888) (xy 344.683589 -223.601593)
			(xy 344.403622 -223.601593) (xy 344.395888 -223.651474) (xy 344.380444 -223.700045) (xy 344.357729 -223.74567)
			(xy 344.328283 -223.787269) (xy 344.292802 -223.823858) (xy 344.252128 -223.854569) (xy 344.207222 -223.878676)
			(xy 344.15915 -223.895606) (xy 344.134186 -223.900746) (xy 344.111072 -223.905064) (xy 343.907872 -224.257362)
			(xy 343.915746 -224.27946) (xy 343.924506 -224.306108) (xy 343.933951 -224.361397) (xy 343.934542 -224.389442)
			(xy 344.212926 -224.389442) (xy 344.213436 -224.363455) (xy 344.221566 -224.31212) (xy 344.237627 -224.26269)
			(xy 344.261223 -224.21638) (xy 344.291773 -224.174332) (xy 344.328524 -224.137581) (xy 344.370572 -224.107031)
			(xy 344.416882 -224.083435) (xy 344.466312 -224.067374) (xy 344.517647 -224.059244) (xy 344.569621 -224.059244)
			(xy 344.620956 -224.067374) (xy 344.670386 -224.083435) (xy 344.716696 -224.107031) (xy 344.758744 -224.137581)
			(xy 344.795495 -224.174332) (xy 344.826045 -224.21638) (xy 344.849641 -224.26269) (xy 344.865702 -224.31212)
			(xy 344.873832 -224.363455) (xy 344.874342 -224.389442) (xy 345.152726 -224.389442) (xy 345.153138 -224.363966)
			(xy 345.160933 -224.313615) (xy 345.17636 -224.265055) (xy 345.199055 -224.219437) (xy 345.228479 -224.177841)
			(xy 345.263936 -224.141251) (xy 345.304587 -224.110534) (xy 345.349469 -224.086417) (xy 345.39752 -224.069471)
			(xy 345.422474 -224.064322) (xy 345.445588 -224.060004) (xy 345.649042 -223.707452) (xy 345.641168 -223.685608)
			(xy 345.632425 -223.658955) (xy 345.622969 -223.60367) (xy 345.622372 -223.575626) (xy 345.622882 -223.549639)
			(xy 345.631012 -223.498304) (xy 345.647073 -223.448874) (xy 345.670669 -223.402564) (xy 345.701219 -223.360516)
			(xy 345.73797 -223.323765) (xy 345.780018 -223.293215) (xy 345.826328 -223.269619) (xy 345.875758 -223.253558)
			(xy 345.927093 -223.245428) (xy 345.979067 -223.245428) (xy 346.030402 -223.253558) (xy 346.079832 -223.269619)
			(xy 346.126142 -223.293215) (xy 346.16819 -223.323765) (xy 346.204941 -223.360516) (xy 346.235491 -223.402564)
			(xy 346.259087 -223.448874) (xy 346.275148 -223.498304) (xy 346.283278 -223.549639) (xy 346.283788 -223.575626)
			(xy 346.283297 -223.601109) (xy 346.283222 -223.601593) (xy 346.563189 -223.601593) (xy 346.563189 -223.549659)
			(xy 346.571314 -223.498364) (xy 346.587362 -223.448971) (xy 346.61094 -223.402697) (xy 346.641466 -223.360681)
			(xy 346.678189 -223.323958) (xy 346.720205 -223.293432) (xy 346.766479 -223.269854) (xy 346.815872 -223.253806)
			(xy 346.867167 -223.245681) (xy 346.919101 -223.245681) (xy 346.970396 -223.253806) (xy 347.019789 -223.269854)
			(xy 347.066063 -223.293432) (xy 347.108079 -223.323958) (xy 347.144802 -223.360681) (xy 347.175328 -223.402697)
			(xy 347.198906 -223.448971) (xy 347.214954 -223.498364) (xy 347.223079 -223.549659) (xy 347.223588 -223.575626)
			(xy 347.223079 -223.601593) (xy 347.214954 -223.652888) (xy 347.198906 -223.702281) (xy 347.175328 -223.748555)
			(xy 347.144802 -223.790571) (xy 347.108079 -223.827294) (xy 347.066063 -223.85782) (xy 347.019789 -223.881398)
			(xy 346.970396 -223.897446) (xy 346.919101 -223.905571) (xy 346.867167 -223.905571) (xy 346.815872 -223.897446)
			(xy 346.766479 -223.881398) (xy 346.720205 -223.85782) (xy 346.678189 -223.827294) (xy 346.641466 -223.790571)
			(xy 346.61094 -223.748555) (xy 346.587362 -223.702281) (xy 346.571314 -223.652888) (xy 346.563189 -223.601593)
			(xy 346.283222 -223.601593) (xy 346.275488 -223.651474) (xy 346.260044 -223.700045) (xy 346.237329 -223.74567)
			(xy 346.207883 -223.787269) (xy 346.172402 -223.823858) (xy 346.131728 -223.854569) (xy 346.086822 -223.878676)
			(xy 346.03875 -223.895606) (xy 346.013786 -223.900746) (xy 345.990672 -223.905064) (xy 345.787472 -224.257362)
			(xy 345.795346 -224.27946) (xy 345.804106 -224.306108) (xy 345.813551 -224.361397) (xy 345.814142 -224.389442)
			(xy 346.092526 -224.389442) (xy 346.093036 -224.363455) (xy 346.101166 -224.31212) (xy 346.117227 -224.26269)
			(xy 346.140823 -224.21638) (xy 346.171373 -224.174332) (xy 346.208124 -224.137581) (xy 346.250172 -224.107031)
			(xy 346.296482 -224.083435) (xy 346.345912 -224.067374) (xy 346.397247 -224.059244) (xy 346.449221 -224.059244)
			(xy 346.500556 -224.067374) (xy 346.549986 -224.083435) (xy 346.596296 -224.107031) (xy 346.638344 -224.137581)
			(xy 346.675095 -224.174332) (xy 346.705645 -224.21638) (xy 346.729241 -224.26269) (xy 346.745302 -224.31212)
			(xy 346.753432 -224.363455) (xy 346.753942 -224.389442) (xy 347.032326 -224.389442) (xy 347.032738 -224.363966)
			(xy 347.040533 -224.313615) (xy 347.05596 -224.265055) (xy 347.078655 -224.219437) (xy 347.108079 -224.177841)
			(xy 347.143536 -224.141251) (xy 347.184187 -224.110534) (xy 347.229069 -224.086417) (xy 347.27712 -224.069471)
			(xy 347.302074 -224.064322) (xy 347.325188 -224.060004) (xy 347.528642 -223.707452) (xy 347.520768 -223.685608)
			(xy 347.512025 -223.658955) (xy 347.502569 -223.60367) (xy 347.501972 -223.575626) (xy 347.502482 -223.549639)
			(xy 347.510612 -223.498304) (xy 347.526673 -223.448874) (xy 347.550269 -223.402564) (xy 347.580819 -223.360516)
			(xy 347.61757 -223.323765) (xy 347.659618 -223.293215) (xy 347.705928 -223.269619) (xy 347.755358 -223.253558)
			(xy 347.806693 -223.245428) (xy 347.858667 -223.245428) (xy 347.910002 -223.253558) (xy 347.959432 -223.269619)
			(xy 348.005742 -223.293215) (xy 348.04779 -223.323765) (xy 348.084541 -223.360516) (xy 348.115091 -223.402564)
			(xy 348.138687 -223.448874) (xy 348.154748 -223.498304) (xy 348.162878 -223.549639) (xy 348.163388 -223.575626)
			(xy 348.162897 -223.601109) (xy 348.155088 -223.651474) (xy 348.139644 -223.700045) (xy 348.116929 -223.74567)
			(xy 348.087483 -223.787269) (xy 348.052002 -223.823858) (xy 348.011328 -223.854569) (xy 347.966422 -223.878676)
			(xy 347.91835 -223.895606) (xy 347.893386 -223.900746) (xy 347.870272 -223.905064) (xy 347.667072 -224.257362)
			(xy 347.674946 -224.27946) (xy 347.683706 -224.306108) (xy 347.693151 -224.361397) (xy 347.693742 -224.389442)
			(xy 347.693232 -224.415429) (xy 347.685102 -224.466764) (xy 347.669041 -224.516194) (xy 347.645445 -224.562504)
			(xy 347.614895 -224.604552) (xy 347.578144 -224.641303) (xy 347.536096 -224.671853) (xy 347.489786 -224.695449)
			(xy 347.440356 -224.71151) (xy 347.389021 -224.71964) (xy 347.337047 -224.71964) (xy 347.285712 -224.71151)
			(xy 347.236282 -224.695449) (xy 347.189972 -224.671853) (xy 347.147924 -224.641303) (xy 347.111173 -224.604552)
			(xy 347.080623 -224.562504) (xy 347.057027 -224.516194) (xy 347.040966 -224.466764) (xy 347.032836 -224.415429)
			(xy 347.032326 -224.389442) (xy 346.753942 -224.389442) (xy 346.753391 -224.417491) (xy 346.743946 -224.472786)
			(xy 346.735146 -224.499424) (xy 346.727272 -224.521522) (xy 346.930726 -224.87382) (xy 346.953586 -224.878138)
			(xy 346.978547 -224.883289) (xy 347.026614 -224.900227) (xy 347.071515 -224.924337) (xy 347.112187 -224.955049)
			(xy 347.147667 -224.991635) (xy 347.177116 -225.03323) (xy 347.199837 -225.07885) (xy 347.215292 -225.127415)
			(xy 347.223115 -225.177776) (xy 347.223588 -225.203258) (xy 347.223078 -225.229225) (xy 347.502735 -225.229225)
			(xy 347.502735 -225.177291) (xy 347.51086 -225.125996) (xy 347.526908 -225.076603) (xy 347.550486 -225.030329)
			(xy 347.581012 -224.988313) (xy 347.617735 -224.95159) (xy 347.659751 -224.921064) (xy 347.706025 -224.897486)
			(xy 347.755418 -224.881438) (xy 347.806713 -224.873313) (xy 347.858647 -224.873313) (xy 347.909942 -224.881438)
			(xy 347.959335 -224.897486) (xy 348.005609 -224.921064) (xy 348.047625 -224.95159) (xy 348.084348 -224.988313)
			(xy 348.114874 -225.030329) (xy 348.138452 -225.076603) (xy 348.1545 -225.125996) (xy 348.162625 -225.177291)
			(xy 348.163134 -225.203258) (xy 348.162625 -225.229225) (xy 348.1545 -225.28052) (xy 348.138452 -225.329913)
			(xy 348.114874 -225.376187) (xy 348.084348 -225.418203) (xy 348.047625 -225.454926) (xy 348.005609 -225.485452)
			(xy 347.959335 -225.50903) (xy 347.909942 -225.525078) (xy 347.858647 -225.533203) (xy 347.806713 -225.533203)
			(xy 347.755418 -225.525078) (xy 347.706025 -225.50903) (xy 347.659751 -225.485452) (xy 347.617735 -225.454926)
			(xy 347.581012 -225.418203) (xy 347.550486 -225.376187) (xy 347.526908 -225.329913) (xy 347.51086 -225.28052)
			(xy 347.502735 -225.229225) (xy 347.223078 -225.229225) (xy 347.223078 -225.229245) (xy 347.214948 -225.28058)
			(xy 347.198887 -225.33001) (xy 347.175291 -225.37632) (xy 347.144741 -225.418368) (xy 347.10799 -225.455119)
			(xy 347.065942 -225.485669) (xy 347.019632 -225.509265) (xy 346.970202 -225.525326) (xy 346.918867 -225.533456)
			(xy 346.866893 -225.533456) (xy 346.815558 -225.525326) (xy 346.766128 -225.509265) (xy 346.719818 -225.485669)
			(xy 346.67777 -225.455119) (xy 346.641019 -225.418368) (xy 346.610469 -225.37632) (xy 346.586873 -225.33001)
			(xy 346.570812 -225.28058) (xy 346.562682 -225.229245) (xy 346.562172 -225.203258) (xy 346.562722 -225.175209)
			(xy 346.572167 -225.119914) (xy 346.580968 -225.093276) (xy 346.588842 -225.071178) (xy 346.385388 -224.71888)
			(xy 346.362528 -224.714562) (xy 346.337569 -224.709401) (xy 346.289502 -224.692465) (xy 346.2446 -224.668356)
			(xy 346.203928 -224.637646) (xy 346.168448 -224.601061) (xy 346.138999 -224.559467) (xy 346.116278 -224.513848)
			(xy 346.100823 -224.465284) (xy 346.092999 -224.414924) (xy 346.092526 -224.389442) (xy 345.814142 -224.389442)
			(xy 345.813632 -224.415429) (xy 345.805502 -224.466764) (xy 345.789441 -224.516194) (xy 345.765845 -224.562504)
			(xy 345.735295 -224.604552) (xy 345.698544 -224.641303) (xy 345.656496 -224.671853) (xy 345.610186 -224.695449)
			(xy 345.560756 -224.71151) (xy 345.509421 -224.71964) (xy 345.457447 -224.71964) (xy 345.406112 -224.71151)
			(xy 345.356682 -224.695449) (xy 345.310372 -224.671853) (xy 345.268324 -224.641303) (xy 345.231573 -224.604552)
			(xy 345.201023 -224.562504) (xy 345.177427 -224.516194) (xy 345.161366 -224.466764) (xy 345.153236 -224.415429)
			(xy 345.152726 -224.389442) (xy 344.874342 -224.389442) (xy 344.873791 -224.417491) (xy 344.864346 -224.472786)
			(xy 344.855546 -224.499424) (xy 344.847672 -224.521522) (xy 345.051126 -224.87382) (xy 345.073986 -224.878138)
			(xy 345.098947 -224.883289) (xy 345.147014 -224.900227) (xy 345.191915 -224.924337) (xy 345.232587 -224.955049)
			(xy 345.268067 -224.991635) (xy 345.297516 -225.03323) (xy 345.320237 -225.07885) (xy 345.335692 -225.127415)
			(xy 345.343515 -225.177776) (xy 345.343988 -225.203258) (xy 345.343478 -225.229225) (xy 345.623135 -225.229225)
			(xy 345.623135 -225.177291) (xy 345.63126 -225.125996) (xy 345.647308 -225.076603) (xy 345.670886 -225.030329)
			(xy 345.701412 -224.988313) (xy 345.738135 -224.95159) (xy 345.780151 -224.921064) (xy 345.826425 -224.897486)
			(xy 345.875818 -224.881438) (xy 345.927113 -224.873313) (xy 345.979047 -224.873313) (xy 346.030342 -224.881438)
			(xy 346.079735 -224.897486) (xy 346.126009 -224.921064) (xy 346.168025 -224.95159) (xy 346.204748 -224.988313)
			(xy 346.235274 -225.030329) (xy 346.258852 -225.076603) (xy 346.2749 -225.125996) (xy 346.283025 -225.177291)
			(xy 346.283534 -225.203258) (xy 346.283025 -225.229225) (xy 346.2749 -225.28052) (xy 346.258852 -225.329913)
			(xy 346.235274 -225.376187) (xy 346.204748 -225.418203) (xy 346.168025 -225.454926) (xy 346.126009 -225.485452)
			(xy 346.079735 -225.50903) (xy 346.030342 -225.525078) (xy 345.979047 -225.533203) (xy 345.927113 -225.533203)
			(xy 345.875818 -225.525078) (xy 345.826425 -225.50903) (xy 345.780151 -225.485452) (xy 345.738135 -225.454926)
			(xy 345.701412 -225.418203) (xy 345.670886 -225.376187) (xy 345.647308 -225.329913) (xy 345.63126 -225.28052)
			(xy 345.623135 -225.229225) (xy 345.343478 -225.229225) (xy 345.343478 -225.229245) (xy 345.335348 -225.28058)
			(xy 345.319287 -225.33001) (xy 345.295691 -225.37632) (xy 345.265141 -225.418368) (xy 345.22839 -225.455119)
			(xy 345.186342 -225.485669) (xy 345.140032 -225.509265) (xy 345.090602 -225.525326) (xy 345.039267 -225.533456)
			(xy 344.987293 -225.533456) (xy 344.935958 -225.525326) (xy 344.886528 -225.509265) (xy 344.840218 -225.485669)
			(xy 344.79817 -225.455119) (xy 344.761419 -225.418368) (xy 344.730869 -225.37632) (xy 344.707273 -225.33001)
			(xy 344.691212 -225.28058) (xy 344.683082 -225.229245) (xy 344.682572 -225.203258) (xy 344.683122 -225.175209)
			(xy 344.692567 -225.119914) (xy 344.701368 -225.093276) (xy 344.709242 -225.071178) (xy 344.505788 -224.71888)
			(xy 344.482928 -224.714562) (xy 344.457969 -224.709401) (xy 344.409902 -224.692465) (xy 344.365 -224.668356)
			(xy 344.324328 -224.637646) (xy 344.288848 -224.601061) (xy 344.259399 -224.559467) (xy 344.236678 -224.513848)
			(xy 344.221223 -224.465284) (xy 344.213399 -224.414924) (xy 344.212926 -224.389442) (xy 343.934542 -224.389442)
			(xy 343.934032 -224.415429) (xy 343.925902 -224.466764) (xy 343.909841 -224.516194) (xy 343.886245 -224.562504)
			(xy 343.855695 -224.604552) (xy 343.818944 -224.641303) (xy 343.776896 -224.671853) (xy 343.730586 -224.695449)
			(xy 343.681156 -224.71151) (xy 343.629821 -224.71964) (xy 343.577847 -224.71964) (xy 343.526512 -224.71151)
			(xy 343.477082 -224.695449) (xy 343.430772 -224.671853) (xy 343.388724 -224.641303) (xy 343.351973 -224.604552)
			(xy 343.321423 -224.562504) (xy 343.297827 -224.516194) (xy 343.281766 -224.466764) (xy 343.273636 -224.415429)
			(xy 343.273126 -224.389442) (xy 342.994742 -224.389442) (xy 342.994152 -224.417487) (xy 342.98471 -224.472777)
			(xy 342.975946 -224.499424) (xy 342.968072 -224.521522) (xy 343.171526 -224.87382) (xy 343.194386 -224.878138)
			(xy 343.208236 -224.880865) (xy 343.23545 -224.88837) (xy 343.248742 -224.893124) (xy 343.257378 -224.896426)
			(xy 343.950544 -224.896426) (xy 343.958926 -224.893378) (xy 343.986592 -224.883801) (xy 344.044211 -224.87346)
			(xy 344.07348 -224.872804) (xy 344.099449 -224.873312) (xy 344.150749 -224.881433) (xy 344.200147 -224.89748)
			(xy 344.246427 -224.921056) (xy 344.288449 -224.951581) (xy 344.325179 -224.988304) (xy 344.355712 -225.03032)
			(xy 344.379297 -225.076595) (xy 344.395352 -225.12599) (xy 344.403483 -225.177289) (xy 344.403934 -225.203258)
			(xy 344.403434 -225.228996) (xy 344.395446 -225.279848) (xy 344.379688 -225.328852) (xy 344.356539 -225.374829)
			(xy 344.341958 -225.396044) (xy 344.341958 -225.61423) (xy 344.432382 -225.704654) (xy 344.460576 -225.697542)
			(xy 344.480979 -225.692565) (xy 344.522635 -225.687215) (xy 344.543634 -225.686874) (xy 344.569675 -225.687365)
			(xy 344.621112 -225.695541) (xy 344.670629 -225.711685) (xy 344.717 -225.735397) (xy 344.759077 -225.76609)
			(xy 344.795818 -225.803004) (xy 344.826314 -225.845225) (xy 344.838528 -225.86823) (xy 344.852752 -225.89617)
			(xy 345.174316 -225.89617) (xy 345.18854 -225.86823) (xy 345.200726 -225.84521) (xy 345.231228 -225.802991)
			(xy 345.267974 -225.76608) (xy 345.310057 -225.735391) (xy 345.356432 -225.711683) (xy 345.405953 -225.695544)
			(xy 345.457392 -225.687373) (xy 345.509476 -225.687373) (xy 345.560915 -225.695544) (xy 345.610436 -225.711683)
			(xy 345.656811 -225.735391) (xy 345.698894 -225.76608) (xy 345.73564 -225.802991) (xy 345.766142 -225.84521)
			(xy 345.778328 -225.86823) (xy 345.792552 -225.89617) (xy 346.114116 -225.89617) (xy 346.12834 -225.86823)
			(xy 346.140529 -225.845211) (xy 346.171032 -225.802994) (xy 346.20778 -225.766084) (xy 346.249861 -225.735393)
			(xy 346.296235 -225.711682) (xy 346.345754 -225.695538) (xy 346.397192 -225.687359) (xy 346.423234 -225.686874)
			(xy 346.449199 -225.687386) (xy 346.500488 -225.695515) (xy 346.549874 -225.711567) (xy 346.596141 -225.735147)
			(xy 346.63815 -225.765674) (xy 346.674866 -225.802397) (xy 346.705386 -225.844412) (xy 346.728957 -225.890683)
			(xy 346.745 -225.940072) (xy 346.753119 -225.991363) (xy 346.753688 -226.017328) (xy 346.753202 -226.042978)
			(xy 346.753152 -226.043295) (xy 347.033089 -226.043295) (xy 347.033089 -225.991361) (xy 347.041214 -225.940066)
			(xy 347.057262 -225.890673) (xy 347.08084 -225.844399) (xy 347.111366 -225.802383) (xy 347.148089 -225.76566)
			(xy 347.190105 -225.735134) (xy 347.236379 -225.711556) (xy 347.285772 -225.695508) (xy 347.337067 -225.687383)
			(xy 347.389001 -225.687383) (xy 347.440296 -225.695508) (xy 347.489689 -225.711556) (xy 347.535963 -225.735134)
			(xy 347.577979 -225.76566) (xy 347.614702 -225.802383) (xy 347.645228 -225.844399) (xy 347.668806 -225.890673)
			(xy 347.684854 -225.940066) (xy 347.692979 -225.991361) (xy 347.693488 -226.017328) (xy 347.692979 -226.043295)
			(xy 347.972889 -226.043295) (xy 347.972889 -225.991361) (xy 347.981014 -225.940066) (xy 347.997062 -225.890673)
			(xy 348.02064 -225.844399) (xy 348.051166 -225.802383) (xy 348.087889 -225.76566) (xy 348.129905 -225.735134)
			(xy 348.176179 -225.711556) (xy 348.225572 -225.695508) (xy 348.276867 -225.687383) (xy 348.328801 -225.687383)
			(xy 348.380096 -225.695508) (xy 348.429489 -225.711556) (xy 348.475763 -225.735134) (xy 348.517779 -225.76566)
			(xy 348.554502 -225.802383) (xy 348.585028 -225.844399) (xy 348.608606 -225.890673) (xy 348.624654 -225.940066)
			(xy 348.632779 -225.991361) (xy 348.633288 -226.017328) (xy 348.632779 -226.043295) (xy 348.624654 -226.09459)
			(xy 348.608606 -226.143983) (xy 348.585028 -226.190257) (xy 348.554502 -226.232273) (xy 348.517779 -226.268996)
			(xy 348.475763 -226.299522) (xy 348.429489 -226.3231) (xy 348.380096 -226.339148) (xy 348.328801 -226.347273)
			(xy 348.276867 -226.347273) (xy 348.225572 -226.339148) (xy 348.176179 -226.3231) (xy 348.129905 -226.299522)
			(xy 348.087889 -226.268996) (xy 348.051166 -226.232273) (xy 348.02064 -226.190257) (xy 347.997062 -226.143983)
			(xy 347.981014 -226.09459) (xy 347.972889 -226.043295) (xy 347.692979 -226.043295) (xy 347.684854 -226.09459)
			(xy 347.668806 -226.143983) (xy 347.645228 -226.190257) (xy 347.614702 -226.232273) (xy 347.577979 -226.268996)
			(xy 347.535963 -226.299522) (xy 347.489689 -226.3231) (xy 347.440296 -226.339148) (xy 347.389001 -226.347273)
			(xy 347.337067 -226.347273) (xy 347.285772 -226.339148) (xy 347.236379 -226.3231) (xy 347.190105 -226.299522)
			(xy 347.148089 -226.268996) (xy 347.111366 -226.232273) (xy 347.08084 -226.190257) (xy 347.057262 -226.143983)
			(xy 347.041214 -226.09459) (xy 347.033089 -226.043295) (xy 346.753152 -226.043295) (xy 346.745271 -226.09366)
			(xy 346.729603 -226.142509) (xy 346.706577 -226.18835) (xy 346.676743 -226.230082) (xy 346.64082 -226.266703)
			(xy 346.599669 -226.297334) (xy 346.554279 -226.321238) (xy 346.530168 -226.330002) (xy 346.495878 -226.341686)
			(xy 346.495878 -226.58705) (xy 346.511118 -226.60229) (xy 346.520921 -226.611528) (xy 346.544267 -226.624945)
			(xy 346.570313 -226.631775) (xy 346.597238 -226.631542) (xy 346.623162 -226.624261) (xy 346.646272 -226.610441)
			(xy 346.655898 -226.60102) (xy 346.674716 -226.582394) (xy 346.717181 -226.550774) (xy 346.764141 -226.526323)
			(xy 346.814395 -226.509663) (xy 346.866662 -226.501219) (xy 346.893134 -226.50069) (xy 346.9191 -226.501175)
			(xy 346.970393 -226.509305) (xy 347.019782 -226.525358) (xy 347.066052 -226.54894) (xy 347.108063 -226.579471)
			(xy 347.14478 -226.616197) (xy 347.1753 -226.658215) (xy 347.198872 -226.70449) (xy 347.214913 -226.753883)
			(xy 347.223031 -226.805178) (xy 347.223588 -226.831144) (xy 347.223094 -226.85698) (xy 347.223073 -226.857111)
			(xy 347.502989 -226.857111) (xy 347.502989 -226.805177) (xy 347.511114 -226.753882) (xy 347.527162 -226.704489)
			(xy 347.55074 -226.658215) (xy 347.581266 -226.616199) (xy 347.617989 -226.579476) (xy 347.660005 -226.54895)
			(xy 347.706279 -226.525372) (xy 347.755672 -226.509324) (xy 347.806967 -226.501199) (xy 347.858901 -226.501199)
			(xy 347.910196 -226.509324) (xy 347.959589 -226.525372) (xy 348.005863 -226.54895) (xy 348.047879 -226.579476)
			(xy 348.084602 -226.616199) (xy 348.115128 -226.658215) (xy 348.138706 -226.704489) (xy 348.154754 -226.753882)
			(xy 348.162879 -226.805177) (xy 348.163388 -226.831144) (xy 348.162879 -226.857111) (xy 348.442789 -226.857111)
			(xy 348.442789 -226.805177) (xy 348.450914 -226.753882) (xy 348.466962 -226.704489) (xy 348.49054 -226.658215)
			(xy 348.521066 -226.616199) (xy 348.557789 -226.579476) (xy 348.599805 -226.54895) (xy 348.646079 -226.525372)
			(xy 348.695472 -226.509324) (xy 348.746767 -226.501199) (xy 348.798701 -226.501199) (xy 348.849996 -226.509324)
			(xy 348.899389 -226.525372) (xy 348.945663 -226.54895) (xy 348.987679 -226.579476) (xy 349.024402 -226.616199)
			(xy 349.054928 -226.658215) (xy 349.078506 -226.704489) (xy 349.094554 -226.753882) (xy 349.102679 -226.805177)
			(xy 349.103188 -226.831144) (xy 349.102679 -226.857111) (xy 349.094554 -226.908406) (xy 349.078506 -226.957799)
			(xy 349.054928 -227.004073) (xy 349.024402 -227.046089) (xy 348.987679 -227.082812) (xy 348.945663 -227.113338)
			(xy 348.899389 -227.136916) (xy 348.849996 -227.152964) (xy 348.798701 -227.161089) (xy 348.746767 -227.161089)
			(xy 348.695472 -227.152964) (xy 348.646079 -227.136916) (xy 348.599805 -227.113338) (xy 348.557789 -227.082812)
			(xy 348.521066 -227.046089) (xy 348.49054 -227.004073) (xy 348.466962 -226.957799) (xy 348.450914 -226.908406)
			(xy 348.442789 -226.857111) (xy 348.162879 -226.857111) (xy 348.154754 -226.908406) (xy 348.138706 -226.957799)
			(xy 348.115128 -227.004073) (xy 348.084602 -227.046089) (xy 348.047879 -227.082812) (xy 348.005863 -227.113338)
			(xy 347.959589 -227.136916) (xy 347.910196 -227.152964) (xy 347.858901 -227.161089) (xy 347.806967 -227.161089)
			(xy 347.755672 -227.152964) (xy 347.706279 -227.136916) (xy 347.660005 -227.113338) (xy 347.617989 -227.082812)
			(xy 347.581266 -227.046089) (xy 347.55074 -227.004073) (xy 347.527162 -226.957799) (xy 347.511114 -226.908406)
			(xy 347.502989 -226.857111) (xy 347.223073 -226.857111) (xy 347.215063 -226.908025) (xy 347.199188 -226.957199)
			(xy 347.175855 -227.003303) (xy 347.145633 -227.045216) (xy 347.109258 -227.081917) (xy 347.088714 -227.09759)
			(xy 347.085666 -227.099876) (xy 347.047058 -227.138484) (xy 347.1037 -227.195126) (xy 347.1037 -227.242624)
			(xy 347.104175 -227.25676) (xy 347.111945 -227.283945) (xy 347.126859 -227.307965) (xy 347.147776 -227.326987)
			(xy 347.173101 -227.339559) (xy 347.200899 -227.34472) (xy 347.229048 -227.342077) (xy 347.242384 -227.337366)
			(xy 347.271346 -227.326747) (xy 347.331942 -227.31524) (xy 347.36278 -227.314506) (xy 347.388753 -227.314987)
			(xy 347.440061 -227.323111) (xy 347.489466 -227.339161) (xy 347.535752 -227.362742) (xy 347.577779 -227.393275)
			(xy 347.614512 -227.430005) (xy 347.645047 -227.472031) (xy 347.668631 -227.518315) (xy 347.684684 -227.567719)
			(xy 347.692811 -227.619027) (xy 347.692811 -227.670927) (xy 347.972889 -227.670927) (xy 347.972889 -227.618993)
			(xy 347.981014 -227.567698) (xy 347.997062 -227.518305) (xy 348.02064 -227.472031) (xy 348.051166 -227.430015)
			(xy 348.087889 -227.393292) (xy 348.129905 -227.362766) (xy 348.176179 -227.339188) (xy 348.225572 -227.32314)
			(xy 348.276867 -227.315015) (xy 348.328801 -227.315015) (xy 348.380096 -227.32314) (xy 348.429489 -227.339188)
			(xy 348.475763 -227.362766) (xy 348.517779 -227.393292) (xy 348.554502 -227.430015) (xy 348.585028 -227.472031)
			(xy 348.608606 -227.518305) (xy 348.624654 -227.567698) (xy 348.632779 -227.618993) (xy 348.633288 -227.64496)
			(xy 348.632779 -227.670927) (xy 348.912689 -227.670927) (xy 348.912689 -227.618993) (xy 348.920814 -227.567698)
			(xy 348.936862 -227.518305) (xy 348.96044 -227.472031) (xy 348.990966 -227.430015) (xy 349.027689 -227.393292)
			(xy 349.069705 -227.362766) (xy 349.115979 -227.339188) (xy 349.165372 -227.32314) (xy 349.216667 -227.315015)
			(xy 349.268601 -227.315015) (xy 349.319896 -227.32314) (xy 349.369289 -227.339188) (xy 349.415563 -227.362766)
			(xy 349.457579 -227.393292) (xy 349.494302 -227.430015) (xy 349.524828 -227.472031) (xy 349.548406 -227.518305)
			(xy 349.564454 -227.567698) (xy 349.572579 -227.618993) (xy 349.573088 -227.64496) (xy 349.572579 -227.670927)
			(xy 349.564454 -227.722222) (xy 349.548406 -227.771615) (xy 349.524828 -227.817889) (xy 349.494302 -227.859905)
			(xy 349.457579 -227.896628) (xy 349.415563 -227.927154) (xy 349.369289 -227.950732) (xy 349.319896 -227.96678)
			(xy 349.268601 -227.974905) (xy 349.216667 -227.974905) (xy 349.165372 -227.96678) (xy 349.115979 -227.950732)
			(xy 349.069705 -227.927154) (xy 349.027689 -227.896628) (xy 348.990966 -227.859905) (xy 348.96044 -227.817889)
			(xy 348.936862 -227.771615) (xy 348.920814 -227.722222) (xy 348.912689 -227.670927) (xy 348.632779 -227.670927)
			(xy 348.624654 -227.722222) (xy 348.608606 -227.771615) (xy 348.585028 -227.817889) (xy 348.554502 -227.859905)
			(xy 348.517779 -227.896628) (xy 348.475763 -227.927154) (xy 348.429489 -227.950732) (xy 348.380096 -227.96678)
			(xy 348.328801 -227.974905) (xy 348.276867 -227.974905) (xy 348.225572 -227.96678) (xy 348.176179 -227.950732)
			(xy 348.129905 -227.927154) (xy 348.087889 -227.896628) (xy 348.051166 -227.859905) (xy 348.02064 -227.817889)
			(xy 347.997062 -227.771615) (xy 347.981014 -227.722222) (xy 347.972889 -227.670927) (xy 347.692811 -227.670927)
			(xy 347.692811 -227.670973) (xy 347.684684 -227.722281) (xy 347.668631 -227.771685) (xy 347.645047 -227.817969)
			(xy 347.614512 -227.859995) (xy 347.577779 -227.896725) (xy 347.535752 -227.927258) (xy 347.489466 -227.950839)
			(xy 347.440061 -227.966889) (xy 347.388753 -227.975013) (xy 347.36278 -227.975414) (xy 347.331939 -227.974706)
			(xy 347.271338 -227.9632) (xy 347.242384 -227.952554) (xy 347.229044 -227.947819) (xy 347.200879 -227.945115)
			(xy 347.173054 -227.950246) (xy 347.147706 -227.962818) (xy 347.126783 -227.981866) (xy 347.111892 -228.005925)
			(xy 347.104177 -228.033148) (xy 347.1037 -228.047296) (xy 347.1037 -228.204522) (xy 347.123717 -228.221777)
			(xy 347.158529 -228.261535) (xy 347.18657 -228.306326) (xy 347.207125 -228.355009) (xy 347.21967 -228.406343)
			(xy 347.223885 -228.459019) (xy 347.221803 -228.484997) (xy 347.502735 -228.484997) (xy 347.502735 -228.433063)
			(xy 347.51086 -228.381768) (xy 347.526908 -228.332375) (xy 347.550486 -228.286101) (xy 347.581012 -228.244085)
			(xy 347.617735 -228.207362) (xy 347.659751 -228.176836) (xy 347.706025 -228.153258) (xy 347.755418 -228.13721)
			(xy 347.806713 -228.129085) (xy 347.858647 -228.129085) (xy 347.909942 -228.13721) (xy 347.959335 -228.153258)
			(xy 348.005609 -228.176836) (xy 348.047625 -228.207362) (xy 348.084348 -228.244085) (xy 348.114874 -228.286101)
			(xy 348.138452 -228.332375) (xy 348.1545 -228.381768) (xy 348.162625 -228.433063) (xy 348.163134 -228.45903)
			(xy 348.162625 -228.484997) (xy 348.442535 -228.484997) (xy 348.442535 -228.433063) (xy 348.45066 -228.381768)
			(xy 348.466708 -228.332375) (xy 348.490286 -228.286101) (xy 348.520812 -228.244085) (xy 348.557535 -228.207362)
			(xy 348.599551 -228.176836) (xy 348.645825 -228.153258) (xy 348.695218 -228.13721) (xy 348.746513 -228.129085)
			(xy 348.798447 -228.129085) (xy 348.849742 -228.13721) (xy 348.899135 -228.153258) (xy 348.945409 -228.176836)
			(xy 348.987425 -228.207362) (xy 349.024148 -228.244085) (xy 349.054674 -228.286101) (xy 349.078252 -228.332375)
			(xy 349.0943 -228.381768) (xy 349.102425 -228.433063) (xy 349.102934 -228.45903) (xy 349.102425 -228.484997)
			(xy 349.382335 -228.484997) (xy 349.382335 -228.433063) (xy 349.39046 -228.381768) (xy 349.406508 -228.332375)
			(xy 349.430086 -228.286101) (xy 349.460612 -228.244085) (xy 349.497335 -228.207362) (xy 349.539351 -228.176836)
			(xy 349.585625 -228.153258) (xy 349.635018 -228.13721) (xy 349.686313 -228.129085) (xy 349.738247 -228.129085)
			(xy 349.789542 -228.13721) (xy 349.838935 -228.153258) (xy 349.885209 -228.176836) (xy 349.927225 -228.207362)
			(xy 349.963948 -228.244085) (xy 349.994474 -228.286101) (xy 350.018052 -228.332375) (xy 350.0341 -228.381768)
			(xy 350.042225 -228.433063) (xy 350.042734 -228.45903) (xy 350.042225 -228.484997) (xy 350.0341 -228.536292)
			(xy 350.018052 -228.585685) (xy 349.994474 -228.631959) (xy 349.963948 -228.673975) (xy 349.927225 -228.710698)
			(xy 349.885209 -228.741224) (xy 349.838935 -228.764802) (xy 349.789542 -228.78085) (xy 349.738247 -228.788975)
			(xy 349.686313 -228.788975) (xy 349.635018 -228.78085) (xy 349.585625 -228.764802) (xy 349.539351 -228.741224)
			(xy 349.497335 -228.710698) (xy 349.460612 -228.673975) (xy 349.430086 -228.631959) (xy 349.406508 -228.585685)
			(xy 349.39046 -228.536292) (xy 349.382335 -228.484997) (xy 349.102425 -228.484997) (xy 349.0943 -228.536292)
			(xy 349.078252 -228.585685) (xy 349.054674 -228.631959) (xy 349.024148 -228.673975) (xy 348.987425 -228.710698)
			(xy 348.945409 -228.741224) (xy 348.899135 -228.764802) (xy 348.849742 -228.78085) (xy 348.798447 -228.788975)
			(xy 348.746513 -228.788975) (xy 348.695218 -228.78085) (xy 348.645825 -228.764802) (xy 348.599551 -228.741224)
			(xy 348.557535 -228.710698) (xy 348.520812 -228.673975) (xy 348.490286 -228.631959) (xy 348.466708 -228.585685)
			(xy 348.45066 -228.536292) (xy 348.442535 -228.484997) (xy 348.162625 -228.484997) (xy 348.1545 -228.536292)
			(xy 348.138452 -228.585685) (xy 348.114874 -228.631959) (xy 348.084348 -228.673975) (xy 348.047625 -228.710698)
			(xy 348.005609 -228.741224) (xy 347.959335 -228.764802) (xy 347.909942 -228.78085) (xy 347.858647 -228.788975)
			(xy 347.806713 -228.788975) (xy 347.755418 -228.78085) (xy 347.706025 -228.764802) (xy 347.659751 -228.741224)
			(xy 347.617735 -228.710698) (xy 347.581012 -228.673975) (xy 347.550486 -228.631959) (xy 347.526908 -228.585685)
			(xy 347.51086 -228.536292) (xy 347.502735 -228.484997) (xy 347.221803 -228.484997) (xy 347.219664 -228.511695)
			(xy 347.207113 -228.563027) (xy 347.186552 -228.611708) (xy 347.158506 -228.656496) (xy 347.123689 -228.69625)
			(xy 347.1037 -228.713538) (xy 347.1037 -228.87051) (xy 347.104124 -228.884666) (xy 347.111826 -228.911908)
			(xy 347.126718 -228.935985) (xy 347.147653 -228.955043) (xy 347.173018 -228.967614) (xy 347.200862 -228.97273)
			(xy 347.22904 -228.969998) (xy 347.242384 -228.965252) (xy 347.271407 -228.954616) (xy 347.332132 -228.943108)
			(xy 347.363034 -228.942392) (xy 347.388996 -228.942904) (xy 347.44028 -228.951031) (xy 347.489661 -228.96708)
			(xy 347.535924 -228.990657) (xy 347.577929 -229.021179) (xy 347.614643 -229.057897) (xy 347.645161 -229.099905)
			(xy 347.668733 -229.146171) (xy 347.684777 -229.195553) (xy 347.692899 -229.246838) (xy 347.692899 -229.298762)
			(xy 347.692891 -229.298813) (xy 347.972889 -229.298813) (xy 347.972889 -229.246879) (xy 347.981014 -229.195584)
			(xy 347.997062 -229.146191) (xy 348.02064 -229.099917) (xy 348.051166 -229.057901) (xy 348.087889 -229.021178)
			(xy 348.129905 -228.990652) (xy 348.176179 -228.967074) (xy 348.225572 -228.951026) (xy 348.276867 -228.942901)
			(xy 348.328801 -228.942901) (xy 348.380096 -228.951026) (xy 348.429489 -228.967074) (xy 348.475763 -228.990652)
			(xy 348.517779 -229.021178) (xy 348.554502 -229.057901) (xy 348.585028 -229.099917) (xy 348.608606 -229.146191)
			(xy 348.624654 -229.195584) (xy 348.632779 -229.246879) (xy 348.633288 -229.272846) (xy 348.632779 -229.298813)
			(xy 348.912435 -229.298813) (xy 348.912435 -229.246879) (xy 348.92056 -229.195584) (xy 348.936608 -229.146191)
			(xy 348.960186 -229.099917) (xy 348.990712 -229.057901) (xy 349.027435 -229.021178) (xy 349.069451 -228.990652)
			(xy 349.115725 -228.967074) (xy 349.165118 -228.951026) (xy 349.216413 -228.942901) (xy 349.268347 -228.942901)
			(xy 349.319642 -228.951026) (xy 349.369035 -228.967074) (xy 349.415309 -228.990652) (xy 349.457325 -229.021178)
			(xy 349.494048 -229.057901) (xy 349.524574 -229.099917) (xy 349.548152 -229.146191) (xy 349.5642 -229.195584)
			(xy 349.572325 -229.246879) (xy 349.572834 -229.272846) (xy 349.572325 -229.298813) (xy 349.852489 -229.298813)
			(xy 349.852489 -229.246879) (xy 349.860614 -229.195584) (xy 349.876662 -229.146191) (xy 349.90024 -229.099917)
			(xy 349.930766 -229.057901) (xy 349.967489 -229.021178) (xy 350.009505 -228.990652) (xy 350.055779 -228.967074)
			(xy 350.105172 -228.951026) (xy 350.156467 -228.942901) (xy 350.208401 -228.942901) (xy 350.259696 -228.951026)
			(xy 350.309089 -228.967074) (xy 350.355363 -228.990652) (xy 350.397379 -229.021178) (xy 350.434102 -229.057901)
			(xy 350.464628 -229.099917) (xy 350.488206 -229.146191) (xy 350.504254 -229.195584) (xy 350.512379 -229.246879)
			(xy 350.512888 -229.272846) (xy 350.512379 -229.298813) (xy 350.504254 -229.350108) (xy 350.488206 -229.399501)
			(xy 350.464628 -229.445775) (xy 350.434102 -229.487791) (xy 350.397379 -229.524514) (xy 350.355363 -229.55504)
			(xy 350.309089 -229.578618) (xy 350.259696 -229.594666) (xy 350.208401 -229.602791) (xy 350.156467 -229.602791)
			(xy 350.105172 -229.594666) (xy 350.055779 -229.578618) (xy 350.009505 -229.55504) (xy 349.967489 -229.524514)
			(xy 349.930766 -229.487791) (xy 349.90024 -229.445775) (xy 349.876662 -229.399501) (xy 349.860614 -229.350108)
			(xy 349.852489 -229.298813) (xy 349.572325 -229.298813) (xy 349.5642 -229.350108) (xy 349.548152 -229.399501)
			(xy 349.524574 -229.445775) (xy 349.494048 -229.487791) (xy 349.457325 -229.524514) (xy 349.415309 -229.55504)
			(xy 349.369035 -229.578618) (xy 349.319642 -229.594666) (xy 349.268347 -229.602791) (xy 349.216413 -229.602791)
			(xy 349.165118 -229.594666) (xy 349.115725 -229.578618) (xy 349.069451 -229.55504) (xy 349.027435 -229.524514)
			(xy 348.990712 -229.487791) (xy 348.960186 -229.445775) (xy 348.936608 -229.399501) (xy 348.92056 -229.350108)
			(xy 348.912435 -229.298813) (xy 348.632779 -229.298813) (xy 348.624654 -229.350108) (xy 348.608606 -229.399501)
			(xy 348.585028 -229.445775) (xy 348.554502 -229.487791) (xy 348.517779 -229.524514) (xy 348.475763 -229.55504)
			(xy 348.429489 -229.578618) (xy 348.380096 -229.594666) (xy 348.328801 -229.602791) (xy 348.276867 -229.602791)
			(xy 348.225572 -229.594666) (xy 348.176179 -229.578618) (xy 348.129905 -229.55504) (xy 348.087889 -229.524514)
			(xy 348.051166 -229.487791) (xy 348.02064 -229.445775) (xy 347.997062 -229.399501) (xy 347.981014 -229.350108)
			(xy 347.972889 -229.298813) (xy 347.692891 -229.298813) (xy 347.684777 -229.350047) (xy 347.668733 -229.399429)
			(xy 347.645161 -229.445695) (xy 347.614643 -229.487703) (xy 347.577929 -229.524421) (xy 347.535924 -229.554943)
			(xy 347.489661 -229.57852) (xy 347.44028 -229.594569) (xy 347.388996 -229.602696) (xy 347.363034 -229.6033)
			(xy 347.332129 -229.602611) (xy 347.271398 -229.591107) (xy 347.242384 -229.58044) (xy 347.229039 -229.575708)
			(xy 347.200866 -229.573009) (xy 347.173034 -229.578141) (xy 347.147676 -229.59071) (xy 347.126738 -229.609753)
			(xy 347.111827 -229.633808) (xy 347.104086 -229.661031) (xy 347.1037 -229.675182) (xy 347.1037 -229.832154)
			(xy 347.123722 -229.849409) (xy 347.158545 -229.889169) (xy 347.186596 -229.933963) (xy 347.207161 -229.982651)
			(xy 347.219715 -230.033992) (xy 347.223938 -230.086676) (xy 347.221861 -230.112629) (xy 347.502735 -230.112629)
			(xy 347.502735 -230.060695) (xy 347.51086 -230.0094) (xy 347.526908 -229.960007) (xy 347.550486 -229.913733)
			(xy 347.581012 -229.871717) (xy 347.617735 -229.834994) (xy 347.659751 -229.804468) (xy 347.706025 -229.78089)
			(xy 347.755418 -229.764842) (xy 347.806713 -229.756717) (xy 347.858647 -229.756717) (xy 347.909942 -229.764842)
			(xy 347.959335 -229.78089) (xy 348.005609 -229.804468) (xy 348.047625 -229.834994) (xy 348.084348 -229.871717)
			(xy 348.114874 -229.913733) (xy 348.138452 -229.960007) (xy 348.1545 -230.0094) (xy 348.162625 -230.060695)
			(xy 348.163134 -230.086662) (xy 348.162625 -230.112629) (xy 348.442535 -230.112629) (xy 348.442535 -230.060695)
			(xy 348.45066 -230.0094) (xy 348.466708 -229.960007) (xy 348.490286 -229.913733) (xy 348.520812 -229.871717)
			(xy 348.557535 -229.834994) (xy 348.599551 -229.804468) (xy 348.645825 -229.78089) (xy 348.695218 -229.764842)
			(xy 348.746513 -229.756717) (xy 348.798447 -229.756717) (xy 348.849742 -229.764842) (xy 348.899135 -229.78089)
			(xy 348.945409 -229.804468) (xy 348.987425 -229.834994) (xy 349.024148 -229.871717) (xy 349.054674 -229.913733)
			(xy 349.078252 -229.960007) (xy 349.0943 -230.0094) (xy 349.102425 -230.060695) (xy 349.102934 -230.086662)
			(xy 349.102425 -230.112629) (xy 349.382335 -230.112629) (xy 349.382335 -230.060695) (xy 349.39046 -230.0094)
			(xy 349.406508 -229.960007) (xy 349.430086 -229.913733) (xy 349.460612 -229.871717) (xy 349.497335 -229.834994)
			(xy 349.539351 -229.804468) (xy 349.585625 -229.78089) (xy 349.635018 -229.764842) (xy 349.686313 -229.756717)
			(xy 349.738247 -229.756717) (xy 349.789542 -229.764842) (xy 349.838935 -229.78089) (xy 349.885209 -229.804468)
			(xy 349.927225 -229.834994) (xy 349.963948 -229.871717) (xy 349.994474 -229.913733) (xy 350.018052 -229.960007)
			(xy 350.0341 -230.0094) (xy 350.042225 -230.060695) (xy 350.042734 -230.086662) (xy 350.042225 -230.112629)
			(xy 350.322135 -230.112629) (xy 350.322135 -230.060695) (xy 350.33026 -230.0094) (xy 350.346308 -229.960007)
			(xy 350.369886 -229.913733) (xy 350.400412 -229.871717) (xy 350.437135 -229.834994) (xy 350.479151 -229.804468)
			(xy 350.525425 -229.78089) (xy 350.574818 -229.764842) (xy 350.626113 -229.756717) (xy 350.678047 -229.756717)
			(xy 350.729342 -229.764842) (xy 350.778735 -229.78089) (xy 350.825009 -229.804468) (xy 350.867025 -229.834994)
			(xy 350.903748 -229.871717) (xy 350.934274 -229.913733) (xy 350.957852 -229.960007) (xy 350.9739 -230.0094)
			(xy 350.982025 -230.060695) (xy 350.982534 -230.086662) (xy 350.982025 -230.112629) (xy 350.9739 -230.163924)
			(xy 350.957852 -230.213317) (xy 350.934274 -230.259591) (xy 350.903748 -230.301607) (xy 350.867025 -230.33833)
			(xy 350.825009 -230.368856) (xy 350.778735 -230.392434) (xy 350.729342 -230.408482) (xy 350.678047 -230.416607)
			(xy 350.626113 -230.416607) (xy 350.574818 -230.408482) (xy 350.525425 -230.392434) (xy 350.479151 -230.368856)
			(xy 350.437135 -230.33833) (xy 350.400412 -230.301607) (xy 350.369886 -230.259591) (xy 350.346308 -230.213317)
			(xy 350.33026 -230.163924) (xy 350.322135 -230.112629) (xy 350.042225 -230.112629) (xy 350.0341 -230.163924)
			(xy 350.018052 -230.213317) (xy 349.994474 -230.259591) (xy 349.963948 -230.301607) (xy 349.927225 -230.33833)
			(xy 349.885209 -230.368856) (xy 349.838935 -230.392434) (xy 349.789542 -230.408482) (xy 349.738247 -230.416607)
			(xy 349.686313 -230.416607) (xy 349.635018 -230.408482) (xy 349.585625 -230.392434) (xy 349.539351 -230.368856)
			(xy 349.497335 -230.33833) (xy 349.460612 -230.301607) (xy 349.430086 -230.259591) (xy 349.406508 -230.213317)
			(xy 349.39046 -230.163924) (xy 349.382335 -230.112629) (xy 349.102425 -230.112629) (xy 349.0943 -230.163924)
			(xy 349.078252 -230.213317) (xy 349.054674 -230.259591) (xy 349.024148 -230.301607) (xy 348.987425 -230.33833)
			(xy 348.945409 -230.368856) (xy 348.899135 -230.392434) (xy 348.849742 -230.408482) (xy 348.798447 -230.416607)
			(xy 348.746513 -230.416607) (xy 348.695218 -230.408482) (xy 348.645825 -230.392434) (xy 348.599551 -230.368856)
			(xy 348.557535 -230.33833) (xy 348.520812 -230.301607) (xy 348.490286 -230.259591) (xy 348.466708 -230.213317)
			(xy 348.45066 -230.163924) (xy 348.442535 -230.112629) (xy 348.162625 -230.112629) (xy 348.1545 -230.163924)
			(xy 348.138452 -230.213317) (xy 348.114874 -230.259591) (xy 348.084348 -230.301607) (xy 348.047625 -230.33833)
			(xy 348.005609 -230.368856) (xy 347.959335 -230.392434) (xy 347.909942 -230.408482) (xy 347.858647 -230.416607)
			(xy 347.806713 -230.416607) (xy 347.755418 -230.408482) (xy 347.706025 -230.392434) (xy 347.659751 -230.368856)
			(xy 347.617735 -230.33833) (xy 347.581012 -230.301607) (xy 347.550486 -230.259591) (xy 347.526908 -230.213317)
			(xy 347.51086 -230.163924) (xy 347.502735 -230.112629) (xy 347.221861 -230.112629) (xy 347.219722 -230.13936)
			(xy 347.207176 -230.190703) (xy 347.186618 -230.239394) (xy 347.158574 -230.284192) (xy 347.123757 -230.323957)
			(xy 347.1037 -230.34117) (xy 347.1037 -230.498142) (xy 347.104116 -230.512305) (xy 347.111807 -230.539564)
			(xy 347.126695 -230.563658) (xy 347.147635 -230.582731) (xy 347.17301 -230.595311) (xy 347.200867 -230.600431)
			(xy 347.229058 -230.597694) (xy 347.242384 -230.592884) (xy 347.271407 -230.582247) (xy 347.332132 -230.570738)
			(xy 347.363034 -230.570024) (xy 347.389001 -230.570536) (xy 347.440296 -230.578665) (xy 347.489687 -230.594718)
			(xy 347.535959 -230.618299) (xy 347.577973 -230.648828) (xy 347.614694 -230.685553) (xy 347.645219 -230.72757)
			(xy 347.668795 -230.773845) (xy 347.684843 -230.823238) (xy 347.692967 -230.874533) (xy 347.692967 -230.926445)
			(xy 347.972889 -230.926445) (xy 347.972889 -230.874511) (xy 347.981014 -230.823216) (xy 347.997062 -230.773823)
			(xy 348.02064 -230.727549) (xy 348.051166 -230.685533) (xy 348.087889 -230.64881) (xy 348.129905 -230.618284)
			(xy 348.176179 -230.594706) (xy 348.225572 -230.578658) (xy 348.276867 -230.570533) (xy 348.328801 -230.570533)
			(xy 348.380096 -230.578658) (xy 348.429489 -230.594706) (xy 348.475763 -230.618284) (xy 348.517779 -230.64881)
			(xy 348.554502 -230.685533) (xy 348.585028 -230.727549) (xy 348.608606 -230.773823) (xy 348.624654 -230.823216)
			(xy 348.632779 -230.874511) (xy 348.633288 -230.900478) (xy 348.632779 -230.926445) (xy 348.912689 -230.926445)
			(xy 348.912689 -230.874511) (xy 348.920814 -230.823216) (xy 348.936862 -230.773823) (xy 348.96044 -230.727549)
			(xy 348.990966 -230.685533) (xy 349.027689 -230.64881) (xy 349.069705 -230.618284) (xy 349.115979 -230.594706)
			(xy 349.165372 -230.578658) (xy 349.216667 -230.570533) (xy 349.268601 -230.570533) (xy 349.319896 -230.578658)
			(xy 349.369289 -230.594706) (xy 349.415563 -230.618284) (xy 349.457579 -230.64881) (xy 349.494302 -230.685533)
			(xy 349.524828 -230.727549) (xy 349.548406 -230.773823) (xy 349.564454 -230.823216) (xy 349.572579 -230.874511)
			(xy 349.573088 -230.900478) (xy 349.572579 -230.926445) (xy 349.852489 -230.926445) (xy 349.852489 -230.874511)
			(xy 349.860614 -230.823216) (xy 349.876662 -230.773823) (xy 349.90024 -230.727549) (xy 349.930766 -230.685533)
			(xy 349.967489 -230.64881) (xy 350.009505 -230.618284) (xy 350.055779 -230.594706) (xy 350.105172 -230.578658)
			(xy 350.156467 -230.570533) (xy 350.208401 -230.570533) (xy 350.259696 -230.578658) (xy 350.309089 -230.594706)
			(xy 350.355363 -230.618284) (xy 350.397379 -230.64881) (xy 350.434102 -230.685533) (xy 350.464628 -230.727549)
			(xy 350.488206 -230.773823) (xy 350.504254 -230.823216) (xy 350.512379 -230.874511) (xy 350.512888 -230.900478)
			(xy 350.512379 -230.926445) (xy 350.792289 -230.926445) (xy 350.792289 -230.874511) (xy 350.800414 -230.823216)
			(xy 350.816462 -230.773823) (xy 350.84004 -230.727549) (xy 350.870566 -230.685533) (xy 350.907289 -230.64881)
			(xy 350.949305 -230.618284) (xy 350.995579 -230.594706) (xy 351.044972 -230.578658) (xy 351.096267 -230.570533)
			(xy 351.148201 -230.570533) (xy 351.199496 -230.578658) (xy 351.248889 -230.594706) (xy 351.295163 -230.618284)
			(xy 351.337179 -230.64881) (xy 351.373902 -230.685533) (xy 351.404428 -230.727549) (xy 351.428006 -230.773823)
			(xy 351.444054 -230.823216) (xy 351.452179 -230.874511) (xy 351.452688 -230.900478) (xy 351.452179 -230.926445)
			(xy 351.732089 -230.926445) (xy 351.732089 -230.874511) (xy 351.740214 -230.823216) (xy 351.756262 -230.773823)
			(xy 351.77984 -230.727549) (xy 351.810366 -230.685533) (xy 351.847089 -230.64881) (xy 351.889105 -230.618284)
			(xy 351.935379 -230.594706) (xy 351.984772 -230.578658) (xy 352.036067 -230.570533) (xy 352.088001 -230.570533)
			(xy 352.139296 -230.578658) (xy 352.188689 -230.594706) (xy 352.234963 -230.618284) (xy 352.276979 -230.64881)
			(xy 352.313702 -230.685533) (xy 352.344228 -230.727549) (xy 352.367806 -230.773823) (xy 352.383854 -230.823216)
			(xy 352.391979 -230.874511) (xy 352.392488 -230.900478) (xy 352.391979 -230.926445) (xy 352.383854 -230.97774)
			(xy 352.367806 -231.027133) (xy 352.344228 -231.073407) (xy 352.313702 -231.115423) (xy 352.276979 -231.152146)
			(xy 352.234963 -231.182672) (xy 352.188689 -231.20625) (xy 352.139296 -231.222298) (xy 352.088001 -231.230423)
			(xy 352.036067 -231.230423) (xy 351.984772 -231.222298) (xy 351.935379 -231.20625) (xy 351.889105 -231.182672)
			(xy 351.847089 -231.152146) (xy 351.810366 -231.115423) (xy 351.77984 -231.073407) (xy 351.756262 -231.027133)
			(xy 351.740214 -230.97774) (xy 351.732089 -230.926445) (xy 351.452179 -230.926445) (xy 351.444054 -230.97774)
			(xy 351.428006 -231.027133) (xy 351.404428 -231.073407) (xy 351.373902 -231.115423) (xy 351.337179 -231.152146)
			(xy 351.295163 -231.182672) (xy 351.248889 -231.20625) (xy 351.199496 -231.222298) (xy 351.148201 -231.230423)
			(xy 351.096267 -231.230423) (xy 351.044972 -231.222298) (xy 350.995579 -231.20625) (xy 350.949305 -231.182672)
			(xy 350.907289 -231.152146) (xy 350.870566 -231.115423) (xy 350.84004 -231.073407) (xy 350.816462 -231.027133)
			(xy 350.800414 -230.97774) (xy 350.792289 -230.926445) (xy 350.512379 -230.926445) (xy 350.504254 -230.97774)
			(xy 350.488206 -231.027133) (xy 350.464628 -231.073407) (xy 350.434102 -231.115423) (xy 350.397379 -231.152146)
			(xy 350.355363 -231.182672) (xy 350.309089 -231.20625) (xy 350.259696 -231.222298) (xy 350.208401 -231.230423)
			(xy 350.156467 -231.230423) (xy 350.105172 -231.222298) (xy 350.055779 -231.20625) (xy 350.009505 -231.182672)
			(xy 349.967489 -231.152146) (xy 349.930766 -231.115423) (xy 349.90024 -231.073407) (xy 349.876662 -231.027133)
			(xy 349.860614 -230.97774) (xy 349.852489 -230.926445) (xy 349.572579 -230.926445) (xy 349.564454 -230.97774)
			(xy 349.548406 -231.027133) (xy 349.524828 -231.073407) (xy 349.494302 -231.115423) (xy 349.457579 -231.152146)
			(xy 349.415563 -231.182672) (xy 349.369289 -231.20625) (xy 349.319896 -231.222298) (xy 349.268601 -231.230423)
			(xy 349.216667 -231.230423) (xy 349.165372 -231.222298) (xy 349.115979 -231.20625) (xy 349.069705 -231.182672)
			(xy 349.027689 -231.152146) (xy 348.990966 -231.115423) (xy 348.96044 -231.073407) (xy 348.936862 -231.027133)
			(xy 348.920814 -230.97774) (xy 348.912689 -230.926445) (xy 348.632779 -230.926445) (xy 348.624654 -230.97774)
			(xy 348.608606 -231.027133) (xy 348.585028 -231.073407) (xy 348.554502 -231.115423) (xy 348.517779 -231.152146)
			(xy 348.475763 -231.182672) (xy 348.429489 -231.20625) (xy 348.380096 -231.222298) (xy 348.328801 -231.230423)
			(xy 348.276867 -231.230423) (xy 348.225572 -231.222298) (xy 348.176179 -231.20625) (xy 348.129905 -231.182672)
			(xy 348.087889 -231.152146) (xy 348.051166 -231.115423) (xy 348.02064 -231.073407) (xy 347.997062 -231.027133)
			(xy 347.981014 -230.97774) (xy 347.972889 -230.926445) (xy 347.692967 -230.926445) (xy 347.692967 -230.926467)
			(xy 347.684843 -230.977762) (xy 347.668795 -231.027155) (xy 347.645219 -231.07343) (xy 347.614694 -231.115447)
			(xy 347.577973 -231.152172) (xy 347.535959 -231.182701) (xy 347.489687 -231.206282) (xy 347.440296 -231.222335)
			(xy 347.389001 -231.230464) (xy 347.363034 -231.230932) (xy 347.332128 -231.230243) (xy 347.271398 -231.218741)
			(xy 347.242384 -231.208072) (xy 347.229041 -231.203339) (xy 347.20087 -231.200639) (xy 347.173039 -231.20577)
			(xy 347.147684 -231.21834) (xy 347.126751 -231.237384) (xy 347.111845 -231.261441) (xy 347.104111 -231.288664)
			(xy 347.1037 -231.302814) (xy 347.1037 -231.46004) (xy 347.123715 -231.477295) (xy 347.158525 -231.517052)
			(xy 347.186563 -231.561843) (xy 347.207115 -231.610524) (xy 347.219658 -231.661857) (xy 347.223871 -231.714531)
			(xy 347.221788 -231.740515) (xy 347.502735 -231.740515) (xy 347.502735 -231.688581) (xy 347.51086 -231.637286)
			(xy 347.526908 -231.587893) (xy 347.550486 -231.541619) (xy 347.581012 -231.499603) (xy 347.617735 -231.46288)
			(xy 347.659751 -231.432354) (xy 347.706025 -231.408776) (xy 347.755418 -231.392728) (xy 347.806713 -231.384603)
			(xy 347.858647 -231.384603) (xy 347.909942 -231.392728) (xy 347.959335 -231.408776) (xy 348.005609 -231.432354)
			(xy 348.047625 -231.46288) (xy 348.084348 -231.499603) (xy 348.114874 -231.541619) (xy 348.138452 -231.587893)
			(xy 348.1545 -231.637286) (xy 348.162625 -231.688581) (xy 348.163134 -231.714548) (xy 348.162625 -231.740515)
			(xy 348.442789 -231.740515) (xy 348.442789 -231.688581) (xy 348.450914 -231.637286) (xy 348.466962 -231.587893)
			(xy 348.49054 -231.541619) (xy 348.521066 -231.499603) (xy 348.557789 -231.46288) (xy 348.599805 -231.432354)
			(xy 348.646079 -231.408776) (xy 348.695472 -231.392728) (xy 348.746767 -231.384603) (xy 348.798701 -231.384603)
			(xy 348.849996 -231.392728) (xy 348.899389 -231.408776) (xy 348.945663 -231.432354) (xy 348.987679 -231.46288)
			(xy 349.024402 -231.499603) (xy 349.054928 -231.541619) (xy 349.078506 -231.587893) (xy 349.094554 -231.637286)
			(xy 349.102679 -231.688581) (xy 349.103188 -231.714548) (xy 349.102679 -231.740515) (xy 349.382335 -231.740515)
			(xy 349.382335 -231.688581) (xy 349.39046 -231.637286) (xy 349.406508 -231.587893) (xy 349.430086 -231.541619)
			(xy 349.460612 -231.499603) (xy 349.497335 -231.46288) (xy 349.539351 -231.432354) (xy 349.585625 -231.408776)
			(xy 349.635018 -231.392728) (xy 349.686313 -231.384603) (xy 349.738247 -231.384603) (xy 349.789542 -231.392728)
			(xy 349.838935 -231.408776) (xy 349.885209 -231.432354) (xy 349.927225 -231.46288) (xy 349.963948 -231.499603)
			(xy 349.994474 -231.541619) (xy 350.018052 -231.587893) (xy 350.0341 -231.637286) (xy 350.042225 -231.688581)
			(xy 350.042734 -231.714548) (xy 350.042225 -231.740515) (xy 350.322135 -231.740515) (xy 350.322135 -231.688581)
			(xy 350.33026 -231.637286) (xy 350.346308 -231.587893) (xy 350.369886 -231.541619) (xy 350.400412 -231.499603)
			(xy 350.437135 -231.46288) (xy 350.479151 -231.432354) (xy 350.525425 -231.408776) (xy 350.574818 -231.392728)
			(xy 350.626113 -231.384603) (xy 350.678047 -231.384603) (xy 350.729342 -231.392728) (xy 350.778735 -231.408776)
			(xy 350.825009 -231.432354) (xy 350.867025 -231.46288) (xy 350.903748 -231.499603) (xy 350.934274 -231.541619)
			(xy 350.957852 -231.587893) (xy 350.9739 -231.637286) (xy 350.982025 -231.688581) (xy 350.982534 -231.714548)
			(xy 350.982025 -231.740515) (xy 351.261935 -231.740515) (xy 351.261935 -231.688581) (xy 351.27006 -231.637286)
			(xy 351.286108 -231.587893) (xy 351.309686 -231.541619) (xy 351.340212 -231.499603) (xy 351.376935 -231.46288)
			(xy 351.418951 -231.432354) (xy 351.465225 -231.408776) (xy 351.514618 -231.392728) (xy 351.565913 -231.384603)
			(xy 351.617847 -231.384603) (xy 351.669142 -231.392728) (xy 351.718535 -231.408776) (xy 351.764809 -231.432354)
			(xy 351.806825 -231.46288) (xy 351.843548 -231.499603) (xy 351.874074 -231.541619) (xy 351.897652 -231.587893)
			(xy 351.9137 -231.637286) (xy 351.921825 -231.688581) (xy 351.922334 -231.714548) (xy 351.921825 -231.740515)
			(xy 351.9137 -231.79181) (xy 351.897652 -231.841203) (xy 351.874074 -231.887477) (xy 351.843548 -231.929493)
			(xy 351.806825 -231.966216) (xy 351.764809 -231.996742) (xy 351.718535 -232.02032) (xy 351.669142 -232.036368)
			(xy 351.617847 -232.044493) (xy 351.565913 -232.044493) (xy 351.514618 -232.036368) (xy 351.465225 -232.02032)
			(xy 351.418951 -231.996742) (xy 351.376935 -231.966216) (xy 351.340212 -231.929493) (xy 351.309686 -231.887477)
			(xy 351.286108 -231.841203) (xy 351.27006 -231.79181) (xy 351.261935 -231.740515) (xy 350.982025 -231.740515)
			(xy 350.9739 -231.79181) (xy 350.957852 -231.841203) (xy 350.934274 -231.887477) (xy 350.903748 -231.929493)
			(xy 350.867025 -231.966216) (xy 350.825009 -231.996742) (xy 350.778735 -232.02032) (xy 350.729342 -232.036368)
			(xy 350.678047 -232.044493) (xy 350.626113 -232.044493) (xy 350.574818 -232.036368) (xy 350.525425 -232.02032)
			(xy 350.479151 -231.996742) (xy 350.437135 -231.966216) (xy 350.400412 -231.929493) (xy 350.369886 -231.887477)
			(xy 350.346308 -231.841203) (xy 350.33026 -231.79181) (xy 350.322135 -231.740515) (xy 350.042225 -231.740515)
			(xy 350.0341 -231.79181) (xy 350.018052 -231.841203) (xy 349.994474 -231.887477) (xy 349.963948 -231.929493)
			(xy 349.927225 -231.966216) (xy 349.885209 -231.996742) (xy 349.838935 -232.02032) (xy 349.789542 -232.036368)
			(xy 349.738247 -232.044493) (xy 349.686313 -232.044493) (xy 349.635018 -232.036368) (xy 349.585625 -232.02032)
			(xy 349.539351 -231.996742) (xy 349.497335 -231.966216) (xy 349.460612 -231.929493) (xy 349.430086 -231.887477)
			(xy 349.406508 -231.841203) (xy 349.39046 -231.79181) (xy 349.382335 -231.740515) (xy 349.102679 -231.740515)
			(xy 349.094554 -231.79181) (xy 349.078506 -231.841203) (xy 349.054928 -231.887477) (xy 349.024402 -231.929493)
			(xy 348.987679 -231.966216) (xy 348.945663 -231.996742) (xy 348.899389 -232.02032) (xy 348.849996 -232.036368)
			(xy 348.798701 -232.044493) (xy 348.746767 -232.044493) (xy 348.695472 -232.036368) (xy 348.646079 -232.02032)
			(xy 348.599805 -231.996742) (xy 348.557789 -231.966216) (xy 348.521066 -231.929493) (xy 348.49054 -231.887477)
			(xy 348.466962 -231.841203) (xy 348.450914 -231.79181) (xy 348.442789 -231.740515) (xy 348.162625 -231.740515)
			(xy 348.1545 -231.79181) (xy 348.138452 -231.841203) (xy 348.114874 -231.887477) (xy 348.084348 -231.929493)
			(xy 348.047625 -231.966216) (xy 348.005609 -231.996742) (xy 347.959335 -232.02032) (xy 347.909942 -232.036368)
			(xy 347.858647 -232.044493) (xy 347.806713 -232.044493) (xy 347.755418 -232.036368) (xy 347.706025 -232.02032)
			(xy 347.659751 -231.996742) (xy 347.617735 -231.966216) (xy 347.581012 -231.929493) (xy 347.550486 -231.887477)
			(xy 347.526908 -231.841203) (xy 347.51086 -231.79181) (xy 347.502735 -231.740515) (xy 347.221788 -231.740515)
			(xy 347.219648 -231.767204) (xy 347.207096 -231.818534) (xy 347.186534 -231.867212) (xy 347.158488 -231.911997)
			(xy 347.123671 -231.951748) (xy 347.1037 -231.969056) (xy 347.1037 -232.126028) (xy 347.104127 -232.140182)
			(xy 347.111831 -232.16742) (xy 347.126724 -232.191492) (xy 347.147657 -232.210546) (xy 347.17302 -232.223114)
			(xy 347.200861 -232.22823) (xy 347.229035 -232.225499) (xy 347.242384 -232.22077) (xy 347.271407 -232.210133)
			(xy 347.332132 -232.198625) (xy 347.363034 -232.19791) (xy 347.389002 -232.198422) (xy 347.440299 -232.206551)
			(xy 347.489692 -232.222605) (xy 347.535966 -232.246187) (xy 347.577982 -232.276717) (xy 347.614705 -232.313444)
			(xy 347.645231 -232.355463) (xy 347.668808 -232.401739) (xy 347.684857 -232.451134) (xy 347.692981 -232.502432)
			(xy 347.692981 -232.554331) (xy 347.972889 -232.554331) (xy 347.972889 -232.502397) (xy 347.981014 -232.451102)
			(xy 347.997062 -232.401709) (xy 348.02064 -232.355435) (xy 348.051166 -232.313419) (xy 348.087889 -232.276696)
			(xy 348.129905 -232.24617) (xy 348.176179 -232.222592) (xy 348.225572 -232.206544) (xy 348.276867 -232.198419)
			(xy 348.328801 -232.198419) (xy 348.380096 -232.206544) (xy 348.429489 -232.222592) (xy 348.475763 -232.24617)
			(xy 348.517779 -232.276696) (xy 348.554502 -232.313419) (xy 348.585028 -232.355435) (xy 348.608606 -232.401709)
			(xy 348.624654 -232.451102) (xy 348.632779 -232.502397) (xy 348.633288 -232.528364) (xy 348.632779 -232.554331)
			(xy 349.852489 -232.554331) (xy 349.852489 -232.502397) (xy 349.860614 -232.451102) (xy 349.876662 -232.401709)
			(xy 349.90024 -232.355435) (xy 349.930766 -232.313419) (xy 349.967489 -232.276696) (xy 350.009505 -232.24617)
			(xy 350.055779 -232.222592) (xy 350.105172 -232.206544) (xy 350.156467 -232.198419) (xy 350.208401 -232.198419)
			(xy 350.259696 -232.206544) (xy 350.309089 -232.222592) (xy 350.355363 -232.24617) (xy 350.397379 -232.276696)
			(xy 350.434102 -232.313419) (xy 350.464628 -232.355435) (xy 350.488206 -232.401709) (xy 350.504254 -232.451102)
			(xy 350.512379 -232.502397) (xy 350.512888 -232.528364) (xy 350.512379 -232.554331) (xy 350.792289 -232.554331)
			(xy 350.792289 -232.502397) (xy 350.800414 -232.451102) (xy 350.816462 -232.401709) (xy 350.84004 -232.355435)
			(xy 350.870566 -232.313419) (xy 350.907289 -232.276696) (xy 350.949305 -232.24617) (xy 350.995579 -232.222592)
			(xy 351.044972 -232.206544) (xy 351.096267 -232.198419) (xy 351.148201 -232.198419) (xy 351.199496 -232.206544)
			(xy 351.248889 -232.222592) (xy 351.295163 -232.24617) (xy 351.337179 -232.276696) (xy 351.373902 -232.313419)
			(xy 351.404428 -232.355435) (xy 351.428006 -232.401709) (xy 351.444054 -232.451102) (xy 351.452179 -232.502397)
			(xy 351.452688 -232.528364) (xy 351.452179 -232.554331) (xy 351.732089 -232.554331) (xy 351.732089 -232.502397)
			(xy 351.740214 -232.451102) (xy 351.756262 -232.401709) (xy 351.77984 -232.355435) (xy 351.810366 -232.313419)
			(xy 351.847089 -232.276696) (xy 351.889105 -232.24617) (xy 351.935379 -232.222592) (xy 351.984772 -232.206544)
			(xy 352.036067 -232.198419) (xy 352.088001 -232.198419) (xy 352.139296 -232.206544) (xy 352.188689 -232.222592)
			(xy 352.234963 -232.24617) (xy 352.276979 -232.276696) (xy 352.313702 -232.313419) (xy 352.344228 -232.355435)
			(xy 352.367806 -232.401709) (xy 352.383854 -232.451102) (xy 352.391979 -232.502397) (xy 352.392488 -232.528364)
			(xy 352.391979 -232.554331) (xy 352.383854 -232.605626) (xy 352.367806 -232.655019) (xy 352.344228 -232.701293)
			(xy 352.313702 -232.743309) (xy 352.276979 -232.780032) (xy 352.234963 -232.810558) (xy 352.188689 -232.834136)
			(xy 352.139296 -232.850184) (xy 352.088001 -232.858309) (xy 352.036067 -232.858309) (xy 351.984772 -232.850184)
			(xy 351.935379 -232.834136) (xy 351.889105 -232.810558) (xy 351.847089 -232.780032) (xy 351.810366 -232.743309)
			(xy 351.77984 -232.701293) (xy 351.756262 -232.655019) (xy 351.740214 -232.605626) (xy 351.732089 -232.554331)
			(xy 351.452179 -232.554331) (xy 351.444054 -232.605626) (xy 351.428006 -232.655019) (xy 351.404428 -232.701293)
			(xy 351.373902 -232.743309) (xy 351.337179 -232.780032) (xy 351.295163 -232.810558) (xy 351.248889 -232.834136)
			(xy 351.199496 -232.850184) (xy 351.148201 -232.858309) (xy 351.096267 -232.858309) (xy 351.044972 -232.850184)
			(xy 350.995579 -232.834136) (xy 350.949305 -232.810558) (xy 350.907289 -232.780032) (xy 350.870566 -232.743309)
			(xy 350.84004 -232.701293) (xy 350.816462 -232.655019) (xy 350.800414 -232.605626) (xy 350.792289 -232.554331)
			(xy 350.512379 -232.554331) (xy 350.504254 -232.605626) (xy 350.488206 -232.655019) (xy 350.464628 -232.701293)
			(xy 350.434102 -232.743309) (xy 350.397379 -232.780032) (xy 350.355363 -232.810558) (xy 350.309089 -232.834136)
			(xy 350.259696 -232.850184) (xy 350.208401 -232.858309) (xy 350.156467 -232.858309) (xy 350.105172 -232.850184)
			(xy 350.055779 -232.834136) (xy 350.009505 -232.810558) (xy 349.967489 -232.780032) (xy 349.930766 -232.743309)
			(xy 349.90024 -232.701293) (xy 349.876662 -232.655019) (xy 349.860614 -232.605626) (xy 349.852489 -232.554331)
			(xy 348.632779 -232.554331) (xy 348.624654 -232.605626) (xy 348.608606 -232.655019) (xy 348.585028 -232.701293)
			(xy 348.554502 -232.743309) (xy 348.517779 -232.780032) (xy 348.475763 -232.810558) (xy 348.429489 -232.834136)
			(xy 348.380096 -232.850184) (xy 348.328801 -232.858309) (xy 348.276867 -232.858309) (xy 348.225572 -232.850184)
			(xy 348.176179 -232.834136) (xy 348.129905 -232.810558) (xy 348.087889 -232.780032) (xy 348.051166 -232.743309)
			(xy 348.02064 -232.701293) (xy 347.997062 -232.655019) (xy 347.981014 -232.605626) (xy 347.972889 -232.554331)
			(xy 347.692981 -232.554331) (xy 347.692981 -232.554368) (xy 347.684857 -232.605666) (xy 347.668808 -232.655061)
			(xy 347.645231 -232.701337) (xy 347.614705 -232.743356) (xy 347.577982 -232.780083) (xy 347.535966 -232.810613)
			(xy 347.489692 -232.834195) (xy 347.440299 -232.850249) (xy 347.389002 -232.858378) (xy 347.363034 -232.858818)
			(xy 347.332129 -232.858129) (xy 347.271398 -232.846626) (xy 347.242384 -232.835958) (xy 347.22904 -232.831226)
			(xy 347.200868 -232.828526) (xy 347.173037 -232.833657) (xy 347.14768 -232.846227) (xy 347.126745 -232.86527)
			(xy 347.111837 -232.889326) (xy 347.1041 -232.916549) (xy 347.1037 -232.9307) (xy 347.1037 -233.087672)
			(xy 347.123721 -233.104927) (xy 347.158541 -233.144686) (xy 347.186589 -233.18948) (xy 347.207151 -233.238167)
			(xy 347.219703 -233.289505) (xy 347.223924 -233.342187) (xy 347.221846 -233.368147) (xy 347.502735 -233.368147)
			(xy 347.502735 -233.316213) (xy 347.51086 -233.264918) (xy 347.526908 -233.215525) (xy 347.550486 -233.169251)
			(xy 347.581012 -233.127235) (xy 347.617735 -233.090512) (xy 347.659751 -233.059986) (xy 347.706025 -233.036408)
			(xy 347.755418 -233.02036) (xy 347.806713 -233.012235) (xy 347.858647 -233.012235) (xy 347.909942 -233.02036)
			(xy 347.959335 -233.036408) (xy 348.005609 -233.059986) (xy 348.047625 -233.090512) (xy 348.084348 -233.127235)
			(xy 348.114874 -233.169251) (xy 348.138452 -233.215525) (xy 348.1545 -233.264918) (xy 348.162625 -233.316213)
			(xy 348.163134 -233.34218) (xy 348.162625 -233.368147) (xy 348.442535 -233.368147) (xy 348.442535 -233.316213)
			(xy 348.45066 -233.264918) (xy 348.466708 -233.215525) (xy 348.490286 -233.169251) (xy 348.520812 -233.127235)
			(xy 348.557535 -233.090512) (xy 348.599551 -233.059986) (xy 348.645825 -233.036408) (xy 348.695218 -233.02036)
			(xy 348.746513 -233.012235) (xy 348.798447 -233.012235) (xy 348.849742 -233.02036) (xy 348.899135 -233.036408)
			(xy 348.945409 -233.059986) (xy 348.987425 -233.090512) (xy 349.024148 -233.127235) (xy 349.054674 -233.169251)
			(xy 349.078252 -233.215525) (xy 349.0943 -233.264918) (xy 349.102425 -233.316213) (xy 349.102934 -233.34218)
			(xy 349.102425 -233.368147) (xy 350.322135 -233.368147) (xy 350.322135 -233.316213) (xy 350.33026 -233.264918)
			(xy 350.346308 -233.215525) (xy 350.369886 -233.169251) (xy 350.400412 -233.127235) (xy 350.437135 -233.090512)
			(xy 350.479151 -233.059986) (xy 350.525425 -233.036408) (xy 350.574818 -233.02036) (xy 350.626113 -233.012235)
			(xy 350.678047 -233.012235) (xy 350.729342 -233.02036) (xy 350.778735 -233.036408) (xy 350.825009 -233.059986)
			(xy 350.867025 -233.090512) (xy 350.903748 -233.127235) (xy 350.934274 -233.169251) (xy 350.957852 -233.215525)
			(xy 350.9739 -233.264918) (xy 350.982025 -233.316213) (xy 350.982534 -233.34218) (xy 350.982025 -233.368147)
			(xy 351.261935 -233.368147) (xy 351.261935 -233.316213) (xy 351.27006 -233.264918) (xy 351.286108 -233.215525)
			(xy 351.309686 -233.169251) (xy 351.340212 -233.127235) (xy 351.376935 -233.090512) (xy 351.418951 -233.059986)
			(xy 351.465225 -233.036408) (xy 351.514618 -233.02036) (xy 351.565913 -233.012235) (xy 351.617847 -233.012235)
			(xy 351.669142 -233.02036) (xy 351.718535 -233.036408) (xy 351.764809 -233.059986) (xy 351.806825 -233.090512)
			(xy 351.843548 -233.127235) (xy 351.874074 -233.169251) (xy 351.897652 -233.215525) (xy 351.9137 -233.264918)
			(xy 351.921825 -233.316213) (xy 351.922334 -233.34218) (xy 351.921825 -233.368147) (xy 351.9137 -233.419442)
			(xy 351.897652 -233.468835) (xy 351.874074 -233.515109) (xy 351.843548 -233.557125) (xy 351.806825 -233.593848)
			(xy 351.764809 -233.624374) (xy 351.718535 -233.647952) (xy 351.669142 -233.664) (xy 351.617847 -233.672125)
			(xy 351.565913 -233.672125) (xy 351.514618 -233.664) (xy 351.465225 -233.647952) (xy 351.418951 -233.624374)
			(xy 351.376935 -233.593848) (xy 351.340212 -233.557125) (xy 351.309686 -233.515109) (xy 351.286108 -233.468835)
			(xy 351.27006 -233.419442) (xy 351.261935 -233.368147) (xy 350.982025 -233.368147) (xy 350.9739 -233.419442)
			(xy 350.957852 -233.468835) (xy 350.934274 -233.515109) (xy 350.903748 -233.557125) (xy 350.867025 -233.593848)
			(xy 350.825009 -233.624374) (xy 350.778735 -233.647952) (xy 350.729342 -233.664) (xy 350.678047 -233.672125)
			(xy 350.626113 -233.672125) (xy 350.574818 -233.664) (xy 350.525425 -233.647952) (xy 350.479151 -233.624374)
			(xy 350.437135 -233.593848) (xy 350.400412 -233.557125) (xy 350.369886 -233.515109) (xy 350.346308 -233.468835)
			(xy 350.33026 -233.419442) (xy 350.322135 -233.368147) (xy 349.102425 -233.368147) (xy 349.0943 -233.419442)
			(xy 349.078252 -233.468835) (xy 349.054674 -233.515109) (xy 349.024148 -233.557125) (xy 348.987425 -233.593848)
			(xy 348.945409 -233.624374) (xy 348.899135 -233.647952) (xy 348.849742 -233.664) (xy 348.798447 -233.672125)
			(xy 348.746513 -233.672125) (xy 348.695218 -233.664) (xy 348.645825 -233.647952) (xy 348.599551 -233.624374)
			(xy 348.557535 -233.593848) (xy 348.520812 -233.557125) (xy 348.490286 -233.515109) (xy 348.466708 -233.468835)
			(xy 348.45066 -233.419442) (xy 348.442535 -233.368147) (xy 348.162625 -233.368147) (xy 348.1545 -233.419442)
			(xy 348.138452 -233.468835) (xy 348.114874 -233.515109) (xy 348.084348 -233.557125) (xy 348.047625 -233.593848)
			(xy 348.005609 -233.624374) (xy 347.959335 -233.647952) (xy 347.909942 -233.664) (xy 347.858647 -233.672125)
			(xy 347.806713 -233.672125) (xy 347.755418 -233.664) (xy 347.706025 -233.647952) (xy 347.659751 -233.624374)
			(xy 347.617735 -233.593848) (xy 347.581012 -233.557125) (xy 347.550486 -233.515109) (xy 347.526908 -233.468835)
			(xy 347.51086 -233.419442) (xy 347.502735 -233.368147) (xy 347.221846 -233.368147) (xy 347.219707 -233.394869)
			(xy 347.207159 -233.446209) (xy 347.186601 -233.494897) (xy 347.158556 -233.539693) (xy 347.123739 -233.579455)
			(xy 347.1037 -233.596688) (xy 347.1037 -233.753914) (xy 347.104125 -233.76807) (xy 347.111827 -233.795311)
			(xy 347.126719 -233.819387) (xy 347.147654 -233.838444) (xy 347.173019 -233.851014) (xy 347.200862 -233.85613)
			(xy 347.229039 -233.853398) (xy 347.242384 -233.848656) (xy 347.271407 -233.838019) (xy 347.332132 -233.826512)
			(xy 347.363034 -233.825796) (xy 347.388996 -233.826308) (xy 347.440279 -233.834435) (xy 347.489659 -233.850484)
			(xy 347.535921 -233.87406) (xy 347.577926 -233.904582) (xy 347.61464 -233.9413) (xy 347.645158 -233.983308)
			(xy 347.668729 -234.029572) (xy 347.684773 -234.078954) (xy 347.692895 -234.130238) (xy 347.692895 -234.182162)
			(xy 347.692886 -234.182217) (xy 347.972889 -234.182217) (xy 347.972889 -234.130283) (xy 347.981014 -234.078988)
			(xy 347.997062 -234.029595) (xy 348.02064 -233.983321) (xy 348.051166 -233.941305) (xy 348.087889 -233.904582)
			(xy 348.129905 -233.874056) (xy 348.176179 -233.850478) (xy 348.225572 -233.83443) (xy 348.276867 -233.826305)
			(xy 348.328801 -233.826305) (xy 348.380096 -233.83443) (xy 348.429489 -233.850478) (xy 348.475763 -233.874056)
			(xy 348.517779 -233.904582) (xy 348.554502 -233.941305) (xy 348.585028 -233.983321) (xy 348.608606 -234.029595)
			(xy 348.624654 -234.078988) (xy 348.632779 -234.130283) (xy 348.633288 -234.15625) (xy 348.632779 -234.182217)
			(xy 348.912435 -234.182217) (xy 348.912435 -234.130283) (xy 348.92056 -234.078988) (xy 348.936608 -234.029595)
			(xy 348.960186 -233.983321) (xy 348.990712 -233.941305) (xy 349.027435 -233.904582) (xy 349.069451 -233.874056)
			(xy 349.115725 -233.850478) (xy 349.165118 -233.83443) (xy 349.216413 -233.826305) (xy 349.268347 -233.826305)
			(xy 349.319642 -233.83443) (xy 349.369035 -233.850478) (xy 349.415309 -233.874056) (xy 349.457325 -233.904582)
			(xy 349.494048 -233.941305) (xy 349.524574 -233.983321) (xy 349.548152 -234.029595) (xy 349.5642 -234.078988)
			(xy 349.572325 -234.130283) (xy 349.572834 -234.15625) (xy 349.572325 -234.182217) (xy 349.852489 -234.182217)
			(xy 349.852489 -234.130283) (xy 349.860614 -234.078988) (xy 349.876662 -234.029595) (xy 349.90024 -233.983321)
			(xy 349.930766 -233.941305) (xy 349.967489 -233.904582) (xy 350.009505 -233.874056) (xy 350.055779 -233.850478)
			(xy 350.105172 -233.83443) (xy 350.156467 -233.826305) (xy 350.208401 -233.826305) (xy 350.259696 -233.83443)
			(xy 350.309089 -233.850478) (xy 350.355363 -233.874056) (xy 350.397379 -233.904582) (xy 350.434102 -233.941305)
			(xy 350.464628 -233.983321) (xy 350.488206 -234.029595) (xy 350.504254 -234.078988) (xy 350.512379 -234.130283)
			(xy 350.512888 -234.15625) (xy 350.512379 -234.182217) (xy 350.792289 -234.182217) (xy 350.792289 -234.130283)
			(xy 350.800414 -234.078988) (xy 350.816462 -234.029595) (xy 350.84004 -233.983321) (xy 350.870566 -233.941305)
			(xy 350.907289 -233.904582) (xy 350.949305 -233.874056) (xy 350.995579 -233.850478) (xy 351.044972 -233.83443)
			(xy 351.096267 -233.826305) (xy 351.148201 -233.826305) (xy 351.199496 -233.83443) (xy 351.248889 -233.850478)
			(xy 351.295163 -233.874056) (xy 351.337179 -233.904582) (xy 351.373902 -233.941305) (xy 351.404428 -233.983321)
			(xy 351.428006 -234.029595) (xy 351.444054 -234.078988) (xy 351.452179 -234.130283) (xy 351.452688 -234.15625)
			(xy 351.452179 -234.182217) (xy 351.732089 -234.182217) (xy 351.732089 -234.130283) (xy 351.740214 -234.078988)
			(xy 351.756262 -234.029595) (xy 351.77984 -233.983321) (xy 351.810366 -233.941305) (xy 351.847089 -233.904582)
			(xy 351.889105 -233.874056) (xy 351.935379 -233.850478) (xy 351.984772 -233.83443) (xy 352.036067 -233.826305)
			(xy 352.088001 -233.826305) (xy 352.139296 -233.83443) (xy 352.188689 -233.850478) (xy 352.234963 -233.874056)
			(xy 352.276979 -233.904582) (xy 352.313702 -233.941305) (xy 352.344228 -233.983321) (xy 352.367806 -234.029595)
			(xy 352.383854 -234.078988) (xy 352.391979 -234.130283) (xy 352.392488 -234.15625) (xy 352.391979 -234.182217)
			(xy 352.383854 -234.233512) (xy 352.367806 -234.282905) (xy 352.344228 -234.329179) (xy 352.313702 -234.371195)
			(xy 352.276979 -234.407918) (xy 352.234963 -234.438444) (xy 352.188689 -234.462022) (xy 352.139296 -234.47807)
			(xy 352.088001 -234.486195) (xy 352.036067 -234.486195) (xy 351.984772 -234.47807) (xy 351.935379 -234.462022)
			(xy 351.889105 -234.438444) (xy 351.847089 -234.407918) (xy 351.810366 -234.371195) (xy 351.77984 -234.329179)
			(xy 351.756262 -234.282905) (xy 351.740214 -234.233512) (xy 351.732089 -234.182217) (xy 351.452179 -234.182217)
			(xy 351.444054 -234.233512) (xy 351.428006 -234.282905) (xy 351.404428 -234.329179) (xy 351.373902 -234.371195)
			(xy 351.337179 -234.407918) (xy 351.295163 -234.438444) (xy 351.248889 -234.462022) (xy 351.199496 -234.47807)
			(xy 351.148201 -234.486195) (xy 351.096267 -234.486195) (xy 351.044972 -234.47807) (xy 350.995579 -234.462022)
			(xy 350.949305 -234.438444) (xy 350.907289 -234.407918) (xy 350.870566 -234.371195) (xy 350.84004 -234.329179)
			(xy 350.816462 -234.282905) (xy 350.800414 -234.233512) (xy 350.792289 -234.182217) (xy 350.512379 -234.182217)
			(xy 350.504254 -234.233512) (xy 350.488206 -234.282905) (xy 350.464628 -234.329179) (xy 350.434102 -234.371195)
			(xy 350.397379 -234.407918) (xy 350.355363 -234.438444) (xy 350.309089 -234.462022) (xy 350.259696 -234.47807)
			(xy 350.208401 -234.486195) (xy 350.156467 -234.486195) (xy 350.105172 -234.47807) (xy 350.055779 -234.462022)
			(xy 350.009505 -234.438444) (xy 349.967489 -234.407918) (xy 349.930766 -234.371195) (xy 349.90024 -234.329179)
			(xy 349.876662 -234.282905) (xy 349.860614 -234.233512) (xy 349.852489 -234.182217) (xy 349.572325 -234.182217)
			(xy 349.5642 -234.233512) (xy 349.548152 -234.282905) (xy 349.524574 -234.329179) (xy 349.494048 -234.371195)
			(xy 349.457325 -234.407918) (xy 349.415309 -234.438444) (xy 349.369035 -234.462022) (xy 349.319642 -234.47807)
			(xy 349.268347 -234.486195) (xy 349.216413 -234.486195) (xy 349.165118 -234.47807) (xy 349.115725 -234.462022)
			(xy 349.069451 -234.438444) (xy 349.027435 -234.407918) (xy 348.990712 -234.371195) (xy 348.960186 -234.329179)
			(xy 348.936608 -234.282905) (xy 348.92056 -234.233512) (xy 348.912435 -234.182217) (xy 348.632779 -234.182217)
			(xy 348.624654 -234.233512) (xy 348.608606 -234.282905) (xy 348.585028 -234.329179) (xy 348.554502 -234.371195)
			(xy 348.517779 -234.407918) (xy 348.475763 -234.438444) (xy 348.429489 -234.462022) (xy 348.380096 -234.47807)
			(xy 348.328801 -234.486195) (xy 348.276867 -234.486195) (xy 348.225572 -234.47807) (xy 348.176179 -234.462022)
			(xy 348.129905 -234.438444) (xy 348.087889 -234.407918) (xy 348.051166 -234.371195) (xy 348.02064 -234.329179)
			(xy 347.997062 -234.282905) (xy 347.981014 -234.233512) (xy 347.972889 -234.182217) (xy 347.692886 -234.182217)
			(xy 347.684773 -234.233446) (xy 347.668729 -234.282828) (xy 347.645158 -234.329092) (xy 347.61464 -234.3711)
			(xy 347.577926 -234.407818) (xy 347.535921 -234.43834) (xy 347.489659 -234.461916) (xy 347.440279 -234.477965)
			(xy 347.388996 -234.486092) (xy 347.363034 -234.486704) (xy 347.332129 -234.486015) (xy 347.271398 -234.474511)
			(xy 347.242384 -234.463844) (xy 347.22904 -234.459112) (xy 347.200867 -234.456413) (xy 347.173034 -234.461544)
			(xy 347.147677 -234.474114) (xy 347.12674 -234.493156) (xy 347.111829 -234.517212) (xy 347.104089 -234.544435)
			(xy 347.1037 -234.558586) (xy 347.1037 -234.715558) (xy 347.123722 -234.732813) (xy 347.158544 -234.772572)
			(xy 347.186595 -234.817367) (xy 347.207159 -234.866055) (xy 347.219712 -234.917395) (xy 347.223935 -234.970078)
			(xy 347.221858 -234.996033) (xy 347.502735 -234.996033) (xy 347.502735 -234.944099) (xy 347.51086 -234.892804)
			(xy 347.526908 -234.843411) (xy 347.550486 -234.797137) (xy 347.581012 -234.755121) (xy 347.617735 -234.718398)
			(xy 347.659751 -234.687872) (xy 347.706025 -234.664294) (xy 347.755418 -234.648246) (xy 347.806713 -234.640121)
			(xy 347.858647 -234.640121) (xy 347.909942 -234.648246) (xy 347.959335 -234.664294) (xy 348.005609 -234.687872)
			(xy 348.047625 -234.718398) (xy 348.084348 -234.755121) (xy 348.114874 -234.797137) (xy 348.138452 -234.843411)
			(xy 348.1545 -234.892804) (xy 348.162625 -234.944099) (xy 348.163134 -234.970066) (xy 348.162625 -234.996033)
			(xy 348.442535 -234.996033) (xy 348.442535 -234.944099) (xy 348.45066 -234.892804) (xy 348.466708 -234.843411)
			(xy 348.490286 -234.797137) (xy 348.520812 -234.755121) (xy 348.557535 -234.718398) (xy 348.599551 -234.687872)
			(xy 348.645825 -234.664294) (xy 348.695218 -234.648246) (xy 348.746513 -234.640121) (xy 348.798447 -234.640121)
			(xy 348.849742 -234.648246) (xy 348.899135 -234.664294) (xy 348.945409 -234.687872) (xy 348.987425 -234.718398)
			(xy 349.024148 -234.755121) (xy 349.054674 -234.797137) (xy 349.078252 -234.843411) (xy 349.0943 -234.892804)
			(xy 349.102425 -234.944099) (xy 349.102934 -234.970066) (xy 349.102425 -234.996033) (xy 349.382335 -234.996033)
			(xy 349.382335 -234.944099) (xy 349.39046 -234.892804) (xy 349.406508 -234.843411) (xy 349.430086 -234.797137)
			(xy 349.460612 -234.755121) (xy 349.497335 -234.718398) (xy 349.539351 -234.687872) (xy 349.585625 -234.664294)
			(xy 349.635018 -234.648246) (xy 349.686313 -234.640121) (xy 349.738247 -234.640121) (xy 349.789542 -234.648246)
			(xy 349.838935 -234.664294) (xy 349.885209 -234.687872) (xy 349.927225 -234.718398) (xy 349.963948 -234.755121)
			(xy 349.994474 -234.797137) (xy 350.018052 -234.843411) (xy 350.0341 -234.892804) (xy 350.042225 -234.944099)
			(xy 350.042734 -234.970066) (xy 350.042225 -234.996033) (xy 350.0341 -235.047328) (xy 350.018052 -235.096721)
			(xy 349.994474 -235.142995) (xy 349.963948 -235.185011) (xy 349.927225 -235.221734) (xy 349.885209 -235.25226)
			(xy 349.838935 -235.275838) (xy 349.789542 -235.291886) (xy 349.738247 -235.300011) (xy 349.686313 -235.300011)
			(xy 349.635018 -235.291886) (xy 349.585625 -235.275838) (xy 349.539351 -235.25226) (xy 349.497335 -235.221734)
			(xy 349.460612 -235.185011) (xy 349.430086 -235.142995) (xy 349.406508 -235.096721) (xy 349.39046 -235.047328)
			(xy 349.382335 -234.996033) (xy 349.102425 -234.996033) (xy 349.0943 -235.047328) (xy 349.078252 -235.096721)
			(xy 349.054674 -235.142995) (xy 349.024148 -235.185011) (xy 348.987425 -235.221734) (xy 348.945409 -235.25226)
			(xy 348.899135 -235.275838) (xy 348.849742 -235.291886) (xy 348.798447 -235.300011) (xy 348.746513 -235.300011)
			(xy 348.695218 -235.291886) (xy 348.645825 -235.275838) (xy 348.599551 -235.25226) (xy 348.557535 -235.221734)
			(xy 348.520812 -235.185011) (xy 348.490286 -235.142995) (xy 348.466708 -235.096721) (xy 348.45066 -235.047328)
			(xy 348.442535 -234.996033) (xy 348.162625 -234.996033) (xy 348.1545 -235.047328) (xy 348.138452 -235.096721)
			(xy 348.114874 -235.142995) (xy 348.084348 -235.185011) (xy 348.047625 -235.221734) (xy 348.005609 -235.25226)
			(xy 347.959335 -235.275838) (xy 347.909942 -235.291886) (xy 347.858647 -235.300011) (xy 347.806713 -235.300011)
			(xy 347.755418 -235.291886) (xy 347.706025 -235.275838) (xy 347.659751 -235.25226) (xy 347.617735 -235.221734)
			(xy 347.581012 -235.185011) (xy 347.550486 -235.142995) (xy 347.526908 -235.096721) (xy 347.51086 -235.047328)
			(xy 347.502735 -234.996033) (xy 347.221858 -234.996033) (xy 347.219719 -235.022762) (xy 347.207172 -235.074104)
			(xy 347.186615 -235.122794) (xy 347.15857 -235.167593) (xy 347.123753 -235.207357) (xy 347.1037 -235.224574)
			(xy 347.1037 -235.381546) (xy 347.104116 -235.395709) (xy 347.111808 -235.422967) (xy 347.126697 -235.44706)
			(xy 347.147636 -235.466132) (xy 347.173011 -235.478712) (xy 347.200867 -235.483831) (xy 347.229057 -235.481094)
			(xy 347.242384 -235.476288) (xy 347.271407 -235.46565) (xy 347.332132 -235.454142) (xy 347.363034 -235.453428)
			(xy 347.389 -235.45394) (xy 347.440292 -235.462068) (xy 347.489681 -235.47812) (xy 347.535952 -235.501699)
			(xy 347.577964 -235.532225) (xy 347.614685 -235.568948) (xy 347.64521 -235.610962) (xy 347.668787 -235.657234)
			(xy 347.684836 -235.706624) (xy 347.692961 -235.757916) (xy 347.693488 -235.783882) (xy 347.693009 -235.809478)
			(xy 347.692951 -235.809849) (xy 347.972889 -235.809849) (xy 347.972889 -235.757915) (xy 347.981014 -235.70662)
			(xy 347.997062 -235.657227) (xy 348.02064 -235.610953) (xy 348.051166 -235.568937) (xy 348.087889 -235.532214)
			(xy 348.129905 -235.501688) (xy 348.176179 -235.47811) (xy 348.225572 -235.462062) (xy 348.276867 -235.453937)
			(xy 348.328801 -235.453937) (xy 348.380096 -235.462062) (xy 348.429489 -235.47811) (xy 348.475763 -235.501688)
			(xy 348.517779 -235.532214) (xy 348.554502 -235.568937) (xy 348.585028 -235.610953) (xy 348.608606 -235.657227)
			(xy 348.624654 -235.70662) (xy 348.632779 -235.757915) (xy 348.633288 -235.783882) (xy 348.632779 -235.809849)
			(xy 348.912689 -235.809849) (xy 348.912689 -235.757915) (xy 348.920814 -235.70662) (xy 348.936862 -235.657227)
			(xy 348.96044 -235.610953) (xy 348.990966 -235.568937) (xy 349.027689 -235.532214) (xy 349.069705 -235.501688)
			(xy 349.115979 -235.47811) (xy 349.165372 -235.462062) (xy 349.216667 -235.453937) (xy 349.268601 -235.453937)
			(xy 349.319896 -235.462062) (xy 349.369289 -235.47811) (xy 349.415563 -235.501688) (xy 349.457579 -235.532214)
			(xy 349.494302 -235.568937) (xy 349.524828 -235.610953) (xy 349.548406 -235.657227) (xy 349.564454 -235.70662)
			(xy 349.572579 -235.757915) (xy 349.573088 -235.783882) (xy 349.572579 -235.809849) (xy 349.852489 -235.809849)
			(xy 349.852489 -235.757915) (xy 349.860614 -235.70662) (xy 349.876662 -235.657227) (xy 349.90024 -235.610953)
			(xy 349.930766 -235.568937) (xy 349.967489 -235.532214) (xy 350.009505 -235.501688) (xy 350.055779 -235.47811)
			(xy 350.105172 -235.462062) (xy 350.156467 -235.453937) (xy 350.208401 -235.453937) (xy 350.259696 -235.462062)
			(xy 350.309089 -235.47811) (xy 350.355363 -235.501688) (xy 350.397379 -235.532214) (xy 350.434102 -235.568937)
			(xy 350.464628 -235.610953) (xy 350.488206 -235.657227) (xy 350.504254 -235.70662) (xy 350.512379 -235.757915)
			(xy 350.512888 -235.783882) (xy 350.512379 -235.809849) (xy 350.504254 -235.861144) (xy 350.488206 -235.910537)
			(xy 350.464628 -235.956811) (xy 350.434102 -235.998827) (xy 350.397379 -236.03555) (xy 350.355363 -236.066076)
			(xy 350.309089 -236.089654) (xy 350.259696 -236.105702) (xy 350.208401 -236.113827) (xy 350.156467 -236.113827)
			(xy 350.105172 -236.105702) (xy 350.055779 -236.089654) (xy 350.009505 -236.066076) (xy 349.967489 -236.03555)
			(xy 349.930766 -235.998827) (xy 349.90024 -235.956811) (xy 349.876662 -235.910537) (xy 349.860614 -235.861144)
			(xy 349.852489 -235.809849) (xy 349.572579 -235.809849) (xy 349.564454 -235.861144) (xy 349.548406 -235.910537)
			(xy 349.524828 -235.956811) (xy 349.494302 -235.998827) (xy 349.457579 -236.03555) (xy 349.415563 -236.066076)
			(xy 349.369289 -236.089654) (xy 349.319896 -236.105702) (xy 349.268601 -236.113827) (xy 349.216667 -236.113827)
			(xy 349.165372 -236.105702) (xy 349.115979 -236.089654) (xy 349.069705 -236.066076) (xy 349.027689 -236.03555)
			(xy 348.990966 -235.998827) (xy 348.96044 -235.956811) (xy 348.936862 -235.910537) (xy 348.920814 -235.861144)
			(xy 348.912689 -235.809849) (xy 348.632779 -235.809849) (xy 348.624654 -235.861144) (xy 348.608606 -235.910537)
			(xy 348.585028 -235.956811) (xy 348.554502 -235.998827) (xy 348.517779 -236.03555) (xy 348.475763 -236.066076)
			(xy 348.429489 -236.089654) (xy 348.380096 -236.105702) (xy 348.328801 -236.113827) (xy 348.276867 -236.113827)
			(xy 348.225572 -236.105702) (xy 348.176179 -236.089654) (xy 348.129905 -236.066076) (xy 348.087889 -236.03555)
			(xy 348.051166 -235.998827) (xy 348.02064 -235.956811) (xy 347.997062 -235.910537) (xy 347.981014 -235.861144)
			(xy 347.972889 -235.809849) (xy 347.692951 -235.809849) (xy 347.685118 -235.86006) (xy 347.669522 -235.908819)
			(xy 347.646593 -235.95459) (xy 347.616881 -235.996278) (xy 347.581096 -236.032887) (xy 347.540095 -236.063539)
			(xy 347.51772 -236.075982) (xy 347.505951 -236.082747) (xy 347.486217 -236.101375) (xy 347.472084 -236.124541)
			(xy 347.464548 -236.150611) (xy 347.46414 -236.177744) (xy 347.470889 -236.204028) (xy 347.484319 -236.227609)
			(xy 347.49359 -236.237526) (xy 347.60789 -236.351826) (xy 347.642942 -236.327442) (xy 347.663907 -236.313313)
			(xy 347.70923 -236.290915) (xy 347.757437 -236.275689) (xy 347.807402 -236.267992) (xy 347.83268 -236.267498)
			(xy 347.860466 -236.268068) (xy 347.915253 -236.277364) (xy 347.967713 -236.295698) (xy 348.016365 -236.322552)
			(xy 348.059836 -236.357169) (xy 348.078806 -236.37748)
		)
		(stroke
			(width 0)
			(type solid)
		)
		(fill yes)
		(layer "In6.Cu")
		(net "P3V3_AUX")
	)
	(gr_poly
		(pts
			(xy 264.5918 -321.7926) (xy 266.253214 -321.7926) (xy 266.267301 -321.792144) (xy 266.294401 -321.784443)
			(xy 266.318365 -321.769629) (xy 266.33737 -321.748831) (xy 266.349969 -321.723632) (xy 266.355203 -321.695949)
			(xy 266.352673 -321.66789) (xy 266.342573 -321.641589) (xy 266.334494 -321.63004) (xy 266.317783 -321.6068)
			(xy 266.291223 -321.556098) (xy 266.273127 -321.501797) (xy 266.263963 -321.445299) (xy 266.263374 -321.41668)
			(xy 266.263872 -321.390031) (xy 266.271815 -321.337327) (xy 266.287525 -321.286397) (xy 266.310651 -321.238376)
			(xy 266.340675 -321.194339) (xy 266.376927 -321.155268) (xy 266.418598 -321.122037) (xy 266.464756 -321.095388)
			(xy 266.51437 -321.075916) (xy 266.566332 -321.064056) (xy 266.619482 -321.060073) (xy 266.672632 -321.064056)
			(xy 266.724594 -321.075916) (xy 266.774208 -321.095388) (xy 266.820366 -321.122037) (xy 266.862037 -321.155268)
			(xy 266.898289 -321.194339) (xy 266.928313 -321.238376) (xy 266.951439 -321.286397) (xy 266.967149 -321.337327)
			(xy 266.975092 -321.390031) (xy 266.97559 -321.41668) (xy 266.974991 -321.445295) (xy 266.96579 -321.501781)
			(xy 266.947686 -321.556072) (xy 266.921142 -321.606775) (xy 266.90447 -321.63004) (xy 266.896378 -321.64158)
			(xy 266.886271 -321.66788) (xy 266.883738 -321.695941) (xy 266.888972 -321.723625) (xy 266.901574 -321.748824)
			(xy 266.920586 -321.769618) (xy 266.944557 -321.784424) (xy 266.971662 -321.792112) (xy 266.98575 -321.7926)
			(xy 269.696946 -321.7926) (xy 269.711029 -321.79214) (xy 269.738121 -321.784433) (xy 269.762077 -321.769619)
			(xy 269.781075 -321.748823) (xy 269.79367 -321.723629) (xy 269.798902 -321.695952) (xy 269.796375 -321.667899)
			(xy 269.786281 -321.641603) (xy 269.778226 -321.63004) (xy 269.761518 -321.606799) (xy 269.734963 -321.556096)
			(xy 269.716871 -321.501795) (xy 269.707708 -321.445298) (xy 269.707106 -321.41668) (xy 269.707604 -321.390031)
			(xy 269.715547 -321.337327) (xy 269.731257 -321.286397) (xy 269.754383 -321.238376) (xy 269.784407 -321.194339)
			(xy 269.820659 -321.155268) (xy 269.86233 -321.122037) (xy 269.908488 -321.095388) (xy 269.958102 -321.075916)
			(xy 270.010064 -321.064056) (xy 270.063214 -321.060073) (xy 270.116364 -321.064056) (xy 270.168326 -321.075916)
			(xy 270.21794 -321.095388) (xy 270.264098 -321.122037) (xy 270.305769 -321.155268) (xy 270.342021 -321.194339)
			(xy 270.372045 -321.238376) (xy 270.395171 -321.286397) (xy 270.410881 -321.337327) (xy 270.418824 -321.390031)
			(xy 270.419322 -321.41668) (xy 270.418723 -321.445295) (xy 270.409523 -321.501782) (xy 270.39142 -321.556074)
			(xy 270.364878 -321.606778) (xy 270.348202 -321.63004) (xy 270.340113 -321.641584) (xy 270.330013 -321.667887)
			(xy 270.327483 -321.69595) (xy 270.332718 -321.723636) (xy 270.345318 -321.748838) (xy 270.364324 -321.769639)
			(xy 270.388291 -321.784455) (xy 270.415394 -321.792158) (xy 270.429482 -321.7926) (xy 273.797014 -321.7926)
			(xy 273.811101 -321.792144) (xy 273.838201 -321.784443) (xy 273.862165 -321.769629) (xy 273.88117 -321.748831)
			(xy 273.893769 -321.723632) (xy 273.899003 -321.695949) (xy 273.896473 -321.66789) (xy 273.886373 -321.641589)
			(xy 273.878294 -321.63004) (xy 273.861583 -321.6068) (xy 273.835023 -321.556098) (xy 273.816927 -321.501797)
			(xy 273.807763 -321.445299) (xy 273.807174 -321.41668) (xy 273.807672 -321.390031) (xy 273.815615 -321.337327)
			(xy 273.831325 -321.286397) (xy 273.854451 -321.238376) (xy 273.884475 -321.194339) (xy 273.920727 -321.155268)
			(xy 273.962398 -321.122037) (xy 274.008556 -321.095388) (xy 274.05817 -321.075916) (xy 274.110132 -321.064056)
			(xy 274.163282 -321.060073) (xy 274.216432 -321.064056) (xy 274.268394 -321.075916) (xy 274.318008 -321.095388)
			(xy 274.364166 -321.122037) (xy 274.405837 -321.155268) (xy 274.442089 -321.194339) (xy 274.472113 -321.238376)
			(xy 274.495239 -321.286397) (xy 274.510949 -321.337327) (xy 274.518892 -321.390031) (xy 274.51939 -321.41668)
			(xy 274.518791 -321.445295) (xy 274.50959 -321.501781) (xy 274.491486 -321.556072) (xy 274.464942 -321.606775)
			(xy 274.44827 -321.63004) (xy 274.440178 -321.64158) (xy 274.430071 -321.66788) (xy 274.427538 -321.695941)
			(xy 274.432772 -321.723625) (xy 274.445374 -321.748824) (xy 274.464386 -321.769618) (xy 274.488357 -321.784424)
			(xy 274.515462 -321.792112) (xy 274.52955 -321.7926) (xy 277.240746 -321.7926) (xy 277.254829 -321.79214)
			(xy 277.281921 -321.784433) (xy 277.305877 -321.769619) (xy 277.324875 -321.748823) (xy 277.33747 -321.723629)
			(xy 277.342702 -321.695952) (xy 277.340175 -321.667899) (xy 277.330081 -321.641603) (xy 277.322026 -321.63004)
			(xy 277.305318 -321.606799) (xy 277.278763 -321.556096) (xy 277.260671 -321.501795) (xy 277.251508 -321.445298)
			(xy 277.250906 -321.41668) (xy 277.251404 -321.390031) (xy 277.259347 -321.337327) (xy 277.275057 -321.286397)
			(xy 277.298183 -321.238376) (xy 277.328207 -321.194339) (xy 277.364459 -321.155268) (xy 277.40613 -321.122037)
			(xy 277.452288 -321.095388) (xy 277.501902 -321.075916) (xy 277.553864 -321.064056) (xy 277.607014 -321.060073)
			(xy 277.660164 -321.064056) (xy 277.712126 -321.075916) (xy 277.76174 -321.095388) (xy 277.807898 -321.122037)
			(xy 277.849569 -321.155268) (xy 277.885821 -321.194339) (xy 277.915845 -321.238376) (xy 277.938971 -321.286397)
			(xy 277.954681 -321.337327) (xy 277.962624 -321.390031) (xy 277.963122 -321.41668) (xy 277.962523 -321.445295)
			(xy 277.953323 -321.501782) (xy 277.93522 -321.556074) (xy 277.908678 -321.606778) (xy 277.892002 -321.63004)
			(xy 277.883913 -321.641584) (xy 277.873813 -321.667887) (xy 277.871283 -321.69595) (xy 277.876518 -321.723636)
			(xy 277.889118 -321.748838) (xy 277.908124 -321.769639) (xy 277.932091 -321.784455) (xy 277.959194 -321.792158)
			(xy 277.973282 -321.7926) (xy 280.862786 -321.7926) (xy 280.882886 -321.773666) (xy 280.927843 -321.741606)
			(xy 280.977207 -321.716863) (xy 281.029795 -321.70003) (xy 281.084351 -321.691508) (xy 281.11196 -321.691)
			(xy 281.137696 -321.69145) (xy 281.188633 -321.698853) (xy 281.237974 -321.71351) (xy 281.284691 -321.735117)
			(xy 281.327812 -321.763222) (xy 281.347418 -321.7799) (xy 281.361896 -321.7926) (xy 281.51328 -321.7926)
			(xy 281.51328 -321.7164) (xy 281.49296 -321.70116) (xy 281.471314 -321.684224) (xy 281.433006 -321.644817)
			(xy 281.401203 -321.599995) (xy 281.376659 -321.550821) (xy 281.359956 -321.498462) (xy 281.35149 -321.444159)
			(xy 281.350974 -321.41668) (xy 281.351433 -321.390567) (xy 281.359064 -321.338902) (xy 281.374158 -321.288906)
			(xy 281.396393 -321.24165) (xy 281.42529 -321.198148) (xy 281.442414 -321.178428) (xy 281.452183 -321.166745)
			(xy 281.465007 -321.13914) (xy 281.469145 -321.108984) (xy 281.464233 -321.078945) (xy 281.450704 -321.051679)
			(xy 281.440636 -321.040252) (xy 281.422341 -321.020275) (xy 281.391391 -320.975821) (xy 281.367528 -320.927193)
			(xy 281.351303 -320.875513) (xy 281.343089 -320.821972) (xy 281.342592 -320.794888) (xy 281.34309 -320.768239)
			(xy 281.351033 -320.715535) (xy 281.366743 -320.664605) (xy 281.389869 -320.616584) (xy 281.419893 -320.572547)
			(xy 281.456145 -320.533476) (xy 281.497816 -320.500245) (xy 281.543974 -320.473596) (xy 281.593588 -320.454124)
			(xy 281.64555 -320.442264) (xy 281.6987 -320.438281) (xy 281.75185 -320.442264) (xy 281.803812 -320.454124)
			(xy 281.853426 -320.473596) (xy 281.899584 -320.500245) (xy 281.941255 -320.533476) (xy 281.977507 -320.572547)
			(xy 282.007531 -320.616584) (xy 282.030657 -320.664605) (xy 282.046367 -320.715535) (xy 282.05431 -320.768239)
			(xy 282.054808 -320.794888) (xy 282.054351 -320.821001) (xy 282.046724 -320.872668) (xy 282.031633 -320.922667)
			(xy 282.009401 -320.969926) (xy 281.980504 -321.01343) (xy 281.963368 -321.03314) (xy 281.953588 -321.044821)
			(xy 281.940744 -321.072428) (xy 281.936594 -321.102592) (xy 281.941505 -321.132642) (xy 281.955042 -321.159916)
			(xy 281.965146 -321.171316) (xy 281.983438 -321.191293) (xy 282.014381 -321.23575) (xy 282.038236 -321.284378)
			(xy 282.054452 -321.336058) (xy 282.062657 -321.389598) (xy 282.06319 -321.41668) (xy 282.062591 -321.445295)
			(xy 282.05339 -321.501781) (xy 282.035286 -321.556072) (xy 282.008742 -321.606775) (xy 281.99207 -321.63004)
			(xy 281.983978 -321.64158) (xy 281.973871 -321.66788) (xy 281.971338 -321.695941) (xy 281.976572 -321.723625)
			(xy 281.989174 -321.748824) (xy 282.008186 -321.769618) (xy 282.032157 -321.784424) (xy 282.059262 -321.792112)
			(xy 282.07335 -321.7926) (xy 283.838904 -321.7926) (xy 284.828234 -321.382644) (xy 284.811216 -321.336924)
			(xy 284.801025 -321.307217) (xy 284.790041 -321.245387) (xy 284.789372 -321.213988) (xy 284.789799 -321.18829)
			(xy 284.797152 -321.137424) (xy 284.81176 -321.088149) (xy 284.822138 -321.064636) (xy 284.828057 -321.050516)
			(xy 284.832036 -321.020171) (xy 284.826857 -320.990009) (xy 284.812984 -320.96273) (xy 284.79166 -320.940777)
			(xy 284.764795 -320.926119) (xy 284.734795 -320.920066) (xy 284.719522 -320.921126) (xy 284.6832 -320.922904)
			(xy 284.65612 -320.922398) (xy 284.602585 -320.914197) (xy 284.550909 -320.897984) (xy 284.502285 -320.874132)
			(xy 284.457832 -320.843193) (xy 284.418578 -320.805879) (xy 284.385426 -320.76305) (xy 284.359142 -320.715696)
			(xy 284.340332 -320.664908) (xy 284.32943 -320.611857) (xy 284.326686 -320.557767) (xy 284.332165 -320.503885)
			(xy 284.34574 -320.451454) (xy 284.367098 -320.401684) (xy 284.395747 -320.355722) (xy 284.431025 -320.314627)
			(xy 284.472118 -320.279349) (xy 284.51808 -320.2507) (xy 284.567851 -320.229342) (xy 284.620281 -320.215766)
			(xy 284.674163 -320.210287) (xy 284.728253 -320.213029) (xy 284.781304 -320.223931) (xy 284.832093 -320.242741)
			(xy 284.879447 -320.269024) (xy 284.922276 -320.302175) (xy 284.95959 -320.341429) (xy 284.99053 -320.385881)
			(xy 285.014382 -320.434506) (xy 285.030596 -320.486181) (xy 285.038798 -320.539716) (xy 285.039308 -320.566796)
			(xy 285.038882 -320.592494) (xy 285.031531 -320.643361) (xy 285.016924 -320.692637) (xy 285.006542 -320.716148)
			(xy 285.000621 -320.730271) (xy 284.996639 -320.76062) (xy 285.001816 -320.790789) (xy 285.015689 -320.818075)
			(xy 285.037014 -320.840034) (xy 285.063882 -320.854699) (xy 285.093886 -320.860758) (xy 285.109158 -320.859658)
			(xy 285.14548 -320.85788) (xy 285.170812 -320.858324) (xy 285.220966 -320.865495) (xy 285.269599 -320.879697)
			(xy 285.31573 -320.900642) (xy 285.358431 -320.927909) (xy 285.396841 -320.960947) (xy 285.430185 -320.999092)
			(xy 285.457791 -321.041574) (xy 285.468822 -321.064382) (xy 285.489142 -321.108832) (xy 285.877 -320.94805)
			(xy 285.877 -319.2526) (xy 285.6738 -319.0494) (xy 280.226008 -319.0494) (xy 280.212101 -319.049828)
			(xy 280.185319 -319.05733) (xy 280.161554 -319.071781) (xy 280.14257 -319.092107) (xy 280.129774 -319.116802)
			(xy 280.124115 -319.144034) (xy 280.126015 -319.171782) (xy 280.13025 -319.185036) (xy 280.139846 -319.213813)
			(xy 280.150198 -319.27358) (xy 280.150824 -319.303908) (xy 280.150326 -319.330557) (xy 280.142383 -319.383261)
			(xy 280.126673 -319.434191) (xy 280.103547 -319.482212) (xy 280.073523 -319.526249) (xy 280.037271 -319.56532)
			(xy 279.9956 -319.598551) (xy 279.949442 -319.6252) (xy 279.899828 -319.644672) (xy 279.847866 -319.656532)
			(xy 279.794716 -319.660516) (xy 279.741566 -319.656532) (xy 279.689604 -319.644672) (xy 279.63999 -319.6252)
			(xy 279.593832 -319.598551) (xy 279.552161 -319.56532) (xy 279.515909 -319.526249) (xy 279.485885 -319.482212)
			(xy 279.462759 -319.434191) (xy 279.447049 -319.383261) (xy 279.439106 -319.330557) (xy 279.438608 -319.303908)
			(xy 279.4393 -319.273586) (xy 279.449644 -319.213827) (xy 279.459182 -319.185036) (xy 279.463438 -319.171789)
			(xy 279.46534 -319.14404) (xy 279.459681 -319.116808) (xy 279.44688 -319.092115) (xy 279.42789 -319.071793)
			(xy 279.404118 -319.057352) (xy 279.377331 -319.049864) (xy 279.363424 -319.0494) (xy 275.3868 -319.0494)
			(xy 274.6502 -318.3128) (xy 269.357094 -318.3128) (xy 269.338544 -318.333042) (xy 269.296317 -318.368134)
			(xy 269.249206 -318.396329) (xy 269.198325 -318.41696) (xy 269.144881 -318.429537) (xy 269.09014 -318.433763)
			(xy 269.035399 -318.429537) (xy 268.981955 -318.41696) (xy 268.931074 -318.396329) (xy 268.883963 -318.368134)
			(xy 268.841736 -318.333042) (xy 268.823186 -318.3128) (xy 259.273294 -318.3128) (xy 259.251239 -318.326953)
			(xy 259.203859 -318.349339) (xy 259.153714 -318.364555) (xy 259.101883 -318.372273) (xy 259.075682 -318.372744)
			(xy 259.049479 -318.372282) (xy 258.997639 -318.364597) (xy 258.94749 -318.349381) (xy 258.90012 -318.326965)
			(xy 258.87807 -318.3128) (xy 233.6546 -318.3128) (xy 228.727 -313.3852) (xy 228.727 -256.5654) (xy 230.3272 -254.9652)
			(xy 242.5446 -254.9652) (xy 242.8494 -254.6604) (xy 242.8494 -253.0348) (xy 242.4684 -252.6538) (xy 239.9538 -252.6538)
			(xy 239.3188 -252.0188) (xy 239.3188 -247.4976) (xy 240.4237 -246.3927) (xy 240.4237 -242.6589) (xy 229.0318 -231.267)
			(xy 229.0318 -200.5838) (xy 225.624136 -197.176136) (xy 219.733114 -194.050158) (xy 217.412062 -193.675508)
			(xy 217.39352 -193.699638) (xy 217.375356 -193.722511) (xy 217.333249 -193.762985) (xy 217.285461 -193.796563)
			(xy 217.23311 -193.822459) (xy 217.177423 -193.840067) (xy 217.119701 -193.848975) (xy 217.090498 -193.849498)
			(xy 217.064235 -193.84906) (xy 217.012205 -193.841856) (xy 216.961656 -193.827583) (xy 216.913541 -193.806513)
			(xy 216.868771 -193.779042) (xy 216.828192 -193.74569) (xy 216.792571 -193.707088) (xy 216.762581 -193.663966)
			(xy 216.738788 -193.617137) (xy 216.729818 -193.59245) (xy 216.719912 -193.563748) (xy 212.969094 -192.958212)
			(xy 212.95106 -192.986152) (xy 212.935948 -193.008826) (xy 212.900278 -193.050018) (xy 212.859108 -193.085713)
			(xy 212.813276 -193.115184) (xy 212.763715 -193.137831) (xy 212.711436 -193.153193) (xy 212.657503 -193.160957)
			(xy 212.630258 -193.161412) (xy 212.602272 -193.160917) (xy 212.5469 -193.152733) (xy 212.493319 -193.136546)
			(xy 212.442679 -193.112703) (xy 212.396065 -193.081718) (xy 212.354479 -193.044253) (xy 212.318814 -193.001115)
			(xy 212.289834 -192.953228) (xy 212.268162 -192.901621) (xy 212.260688 -192.874646) (xy 212.25256 -192.842388)
			(xy 209.26044 -192.35928) (xy 209.247232 -192.401444) (xy 209.238786 -192.426989) (xy 209.215716 -192.475594)
			(xy 209.186047 -192.520477) (xy 209.150366 -192.560745) (xy 209.109382 -192.595602) (xy 209.063908 -192.624355)
			(xy 209.014844 -192.646434) (xy 208.963166 -192.661401) (xy 208.909897 -192.668959) (xy 208.882996 -192.669414)
			(xy 208.855745 -192.668928) (xy 208.801797 -192.661171) (xy 208.749503 -192.645816) (xy 208.699925 -192.623174)
			(xy 208.654075 -192.593708) (xy 208.612885 -192.558017) (xy 208.577193 -192.516826) (xy 208.547727 -192.470976)
			(xy 208.525085 -192.421399) (xy 208.509729 -192.369105) (xy 208.501972 -192.315157) (xy 208.501488 -192.287906)
			(xy 208.501488 -192.281048) (xy 208.50225 -192.237106) (xy 208.38414 -192.218056) (xy 194.44081 -192.78219)
			(xy 194.3608 -192.8622) (xy 194.3608 -193.51625) (xy 198.62876 -193.51625) (xy 198.632831 -193.460628)
			(xy 198.644957 -193.406191) (xy 198.66488 -193.3541) (xy 198.692176 -193.305465) (xy 198.726262 -193.261322)
			(xy 198.766411 -193.222613) (xy 198.811769 -193.190162) (xy 198.861369 -193.164661) (xy 198.914153 -193.146654)
			(xy 198.968996 -193.136524) (xy 199.02473 -193.134487) (xy 199.080167 -193.140587) (xy 199.134124 -193.154693)
			(xy 199.185453 -193.176505) (xy 199.233059 -193.205559) (xy 199.275927 -193.241234) (xy 199.313144 -193.282771)
			(xy 199.343917 -193.329284) (xy 199.367589 -193.379781) (xy 199.372513 -193.396148) (xy 201.334908 -193.396148)
			(xy 201.334908 -193.341652) (xy 201.342663 -193.28771) (xy 201.358016 -193.235422) (xy 201.380654 -193.18585)
			(xy 201.410116 -193.140004) (xy 201.445802 -193.098818) (xy 201.486986 -193.063129) (xy 201.53283 -193.033665)
			(xy 201.582401 -193.011024) (xy 201.634689 -192.995668) (xy 201.68863 -192.98791) (xy 201.715878 -192.987422)
			(xy 201.742378 -192.987902) (xy 201.794868 -192.99524) (xy 201.845836 -193.009778) (xy 201.894299 -193.031235)
			(xy 201.939322 -193.059199) (xy 201.959972 -193.075814) (xy 201.971756 -193.084992) (xy 201.999263 -193.096605)
			(xy 202.028951 -193.099787) (xy 202.058294 -193.094267) (xy 202.084797 -193.080515) (xy 202.095862 -193.07048)
			(xy 202.117372 -193.050266) (xy 202.165461 -193.016039) (xy 202.218249 -192.989628) (xy 202.274474 -192.971663)
			(xy 202.332795 -192.962573) (xy 202.362308 -192.962022) (xy 202.392359 -192.962592) (xy 202.451717 -192.972029)
			(xy 202.508862 -192.990652) (xy 202.562382 -193.018001) (xy 202.610954 -193.0534) (xy 202.632564 -193.07429)
			(xy 202.643161 -193.084305) (xy 202.668755 -193.098255) (xy 202.697246 -193.104417) (xy 202.726318 -193.102291)
			(xy 202.753609 -193.09205) (xy 202.776902 -193.074526) (xy 202.78598 -193.063114) (xy 202.804131 -193.039616)
			(xy 202.846432 -192.997954) (xy 202.894675 -192.963348) (xy 202.947697 -192.936633) (xy 203.004218 -192.918454)
			(xy 203.062872 -192.90925) (xy 203.092558 -192.908682) (xy 203.119809 -192.909194) (xy 203.173758 -192.916945)
			(xy 203.226054 -192.932296) (xy 203.275634 -192.954932) (xy 203.321487 -192.984395) (xy 203.362679 -193.020084)
			(xy 203.398374 -193.061272) (xy 203.427843 -193.107121) (xy 203.450486 -193.156697) (xy 203.465844 -193.208991)
			(xy 203.473602 -193.262939) (xy 203.474066 -193.29019) (xy 203.473557 -193.318608) (xy 203.465135 -193.374817)
			(xy 203.448474 -193.429157) (xy 203.423944 -193.480427) (xy 203.392085 -193.527495) (xy 203.373228 -193.548762)
			(xy 203.363066 -193.560642) (xy 203.349771 -193.588915) (xy 203.345652 -193.619885) (xy 203.351093 -193.65065)
			(xy 203.365585 -193.678328) (xy 203.376276 -193.689732) (xy 203.397323 -193.711343) (xy 203.432966 -193.76001)
			(xy 203.460504 -193.81368) (xy 203.47925 -193.871016) (xy 203.488738 -193.930588) (xy 203.489306 -193.96075)
			(xy 203.48882 -193.988001) (xy 203.483645 -194.023996) (xy 206.570072 -194.023996) (xy 206.570572 -193.995412)
			(xy 206.579108 -193.938886) (xy 206.595988 -193.884268) (xy 206.620835 -193.832782) (xy 206.65309 -193.785584)
			(xy 206.692031 -193.743731) (xy 206.71409 -193.725546) (xy 206.725587 -193.71577) (xy 206.742667 -193.690904)
			(xy 206.751744 -193.662135) (xy 206.752028 -193.631969) (xy 206.743494 -193.603034) (xy 206.726885 -193.577851)
			(xy 206.715614 -193.567812) (xy 206.694419 -193.549605) (xy 206.657081 -193.508039) (xy 206.626204 -193.461472)
			(xy 206.60245 -193.410899) (xy 206.586327 -193.357402) (xy 206.578179 -193.302125) (xy 206.577692 -193.274188)
			(xy 206.578178 -193.246937) (xy 206.585934 -193.192989) (xy 206.601289 -193.140694) (xy 206.623931 -193.091117)
			(xy 206.653397 -193.045267) (xy 206.689088 -193.004076) (xy 206.730279 -192.968385) (xy 206.776129 -192.938919)
			(xy 206.825706 -192.916277) (xy 206.878001 -192.900922) (xy 206.931949 -192.893166) (xy 206.986451 -192.893166)
			(xy 207.040399 -192.900922) (xy 207.092694 -192.916277) (xy 207.142271 -192.938919) (xy 207.188121 -192.968385)
			(xy 207.229312 -193.004076) (xy 207.265003 -193.045267) (xy 207.294469 -193.091117) (xy 207.317111 -193.140694)
			(xy 207.332466 -193.192989) (xy 207.340222 -193.246937) (xy 207.340708 -193.274188) (xy 207.340167 -193.30277)
			(xy 207.331635 -193.359293) (xy 207.314761 -193.413909) (xy 207.289922 -193.465394) (xy 207.257676 -193.512594)
			(xy 207.218744 -193.554451) (xy 207.19669 -193.572638) (xy 207.185211 -193.582432) (xy 207.168134 -193.607294)
			(xy 207.159056 -193.636058) (xy 207.159002 -193.641726) (xy 208.51825 -193.641726) (xy 208.522321 -193.586104)
			(xy 208.534447 -193.531667) (xy 208.55437 -193.479576) (xy 208.581666 -193.430941) (xy 208.615752 -193.386798)
			(xy 208.655901 -193.348089) (xy 208.701259 -193.315638) (xy 208.750859 -193.290137) (xy 208.803643 -193.27213)
			(xy 208.858486 -193.262) (xy 208.91422 -193.259963) (xy 208.969657 -193.266063) (xy 209.023614 -193.280169)
			(xy 209.074943 -193.301981) (xy 209.122549 -193.331035) (xy 209.165417 -193.36671) (xy 209.202634 -193.408247)
			(xy 209.233407 -193.45476) (xy 209.257079 -193.505257) (xy 209.273147 -193.558664) (xy 209.281267 -193.61384)
			(xy 209.281776 -193.641726) (xy 209.281267 -193.669612) (xy 209.280661 -193.67373) (xy 212.17712 -193.67373)
			(xy 212.181191 -193.618108) (xy 212.193317 -193.563671) (xy 212.21324 -193.51158) (xy 212.240536 -193.462945)
			(xy 212.274622 -193.418802) (xy 212.314771 -193.380093) (xy 212.360129 -193.347642) (xy 212.409729 -193.322141)
			(xy 212.462513 -193.304134) (xy 212.517356 -193.294004) (xy 212.57309 -193.291967) (xy 212.628527 -193.298067)
			(xy 212.682484 -193.312173) (xy 212.733813 -193.333985) (xy 212.781419 -193.363039) (xy 212.824287 -193.398714)
			(xy 212.861504 -193.440251) (xy 212.892277 -193.486764) (xy 212.915949 -193.537261) (xy 212.932017 -193.590668)
			(xy 212.940137 -193.645844) (xy 212.940646 -193.67373) (xy 212.940137 -193.701616) (xy 212.932017 -193.756792)
			(xy 212.915949 -193.810199) (xy 212.912053 -193.81851) (xy 214.23706 -193.81851) (xy 214.241131 -193.762888)
			(xy 214.253257 -193.708451) (xy 214.27318 -193.65636) (xy 214.300476 -193.607725) (xy 214.334562 -193.563582)
			(xy 214.374711 -193.524873) (xy 214.420069 -193.492422) (xy 214.469669 -193.466921) (xy 214.522453 -193.448914)
			(xy 214.577296 -193.438784) (xy 214.63303 -193.436747) (xy 214.688467 -193.442847) (xy 214.742424 -193.456953)
			(xy 214.793753 -193.478765) (xy 214.841359 -193.507819) (xy 214.884227 -193.543494) (xy 214.921444 -193.585031)
			(xy 214.952217 -193.631544) (xy 214.975889 -193.682041) (xy 214.991957 -193.735448) (xy 215.000077 -193.790624)
			(xy 215.000586 -193.81851) (xy 215.000077 -193.846396) (xy 214.991957 -193.901572) (xy 214.975889 -193.954979)
			(xy 214.952217 -194.005476) (xy 214.921444 -194.051989) (xy 214.884227 -194.093526) (xy 214.841359 -194.129201)
			(xy 214.793753 -194.158255) (xy 214.742424 -194.180067) (xy 214.688467 -194.194173) (xy 214.63303 -194.200273)
			(xy 214.577296 -194.198236) (xy 214.522453 -194.188106) (xy 214.469669 -194.170099) (xy 214.420069 -194.144598)
			(xy 214.374711 -194.112147) (xy 214.334562 -194.073438) (xy 214.300476 -194.029295) (xy 214.27318 -193.98066)
			(xy 214.253257 -193.928569) (xy 214.241131 -193.874132) (xy 214.23706 -193.81851) (xy 212.912053 -193.81851)
			(xy 212.892277 -193.860696) (xy 212.861504 -193.907209) (xy 212.824287 -193.948746) (xy 212.781419 -193.984421)
			(xy 212.733813 -194.013475) (xy 212.682484 -194.035287) (xy 212.628527 -194.049393) (xy 212.57309 -194.055493)
			(xy 212.517356 -194.053456) (xy 212.462513 -194.043326) (xy 212.409729 -194.025319) (xy 212.360129 -193.999818)
			(xy 212.314771 -193.967367) (xy 212.274622 -193.928658) (xy 212.240536 -193.884515) (xy 212.21324 -193.83588)
			(xy 212.193317 -193.783789) (xy 212.181191 -193.729352) (xy 212.17712 -193.67373) (xy 209.280661 -193.67373)
			(xy 209.273147 -193.724788) (xy 209.257079 -193.778195) (xy 209.233407 -193.828692) (xy 209.202634 -193.875205)
			(xy 209.165417 -193.916742) (xy 209.122549 -193.952417) (xy 209.074943 -193.981471) (xy 209.023614 -194.003283)
			(xy 208.969657 -194.017389) (xy 208.91422 -194.023489) (xy 208.858486 -194.021452) (xy 208.803643 -194.011322)
			(xy 208.750859 -193.993315) (xy 208.701259 -193.967814) (xy 208.655901 -193.935363) (xy 208.615752 -193.896654)
			(xy 208.581666 -193.852511) (xy 208.55437 -193.803876) (xy 208.534447 -193.751785) (xy 208.522321 -193.697348)
			(xy 208.51825 -193.641726) (xy 207.159002 -193.641726) (xy 207.158769 -193.666219) (xy 207.167298 -193.69515)
			(xy 207.183899 -193.720332) (xy 207.195166 -193.730372) (xy 207.216349 -193.748592) (xy 207.253689 -193.790155)
			(xy 207.284568 -193.836719) (xy 207.308324 -193.88729) (xy 207.32445 -193.940785) (xy 207.3326 -193.99606)
			(xy 207.333088 -194.023996) (xy 207.332508 -194.054047) (xy 207.323073 -194.113404) (xy 207.304452 -194.170548)
			(xy 207.277106 -194.224069) (xy 207.241709 -194.272641) (xy 207.22082 -194.294252) (xy 207.211568 -194.304034)
			(xy 207.198172 -194.327383) (xy 207.19134 -194.35342) (xy 207.191547 -194.380338) (xy 207.198779 -194.406267)
			(xy 207.212532 -194.429407) (xy 207.231853 -194.44815) (xy 207.243426 -194.455034) (xy 207.266918 -194.468608)
			(xy 207.309881 -194.501739) (xy 207.34732 -194.541005) (xy 207.378368 -194.585497) (xy 207.402305 -194.634184)
			(xy 207.418579 -194.68594) (xy 207.426812 -194.739565) (xy 207.427322 -194.766692) (xy 207.426824 -194.793341)
			(xy 208.925404 -194.793341) (xy 208.925404 -194.740043) (xy 208.933347 -194.687339) (xy 208.949057 -194.636409)
			(xy 208.972183 -194.588388) (xy 209.002207 -194.544351) (xy 209.038459 -194.50528) (xy 209.08013 -194.472049)
			(xy 209.126288 -194.4454) (xy 209.175902 -194.425928) (xy 209.227864 -194.414068) (xy 209.281014 -194.410085)
			(xy 209.334164 -194.414068) (xy 209.386126 -194.425928) (xy 209.43574 -194.4454) (xy 209.481898 -194.472049)
			(xy 209.523569 -194.50528) (xy 209.559821 -194.544351) (xy 209.589845 -194.588388) (xy 209.612971 -194.636409)
			(xy 209.628681 -194.687339) (xy 209.636624 -194.740043) (xy 209.637122 -194.766692) (xy 209.636624 -194.793341)
			(xy 210.133936 -194.793341) (xy 210.133936 -194.740043) (xy 210.141879 -194.687339) (xy 210.157589 -194.636409)
			(xy 210.180715 -194.588388) (xy 210.210739 -194.544351) (xy 210.246991 -194.50528) (xy 210.288662 -194.472049)
			(xy 210.33482 -194.4454) (xy 210.384434 -194.425928) (xy 210.436396 -194.414068) (xy 210.489546 -194.410085)
			(xy 210.542696 -194.414068) (xy 210.594658 -194.425928) (xy 210.644272 -194.4454) (xy 210.69043 -194.472049)
			(xy 210.732101 -194.50528) (xy 210.768353 -194.544351) (xy 210.798377 -194.588388) (xy 210.821503 -194.636409)
			(xy 210.837213 -194.687339) (xy 210.845156 -194.740043) (xy 210.845654 -194.766692) (xy 210.845156 -194.793341)
			(xy 210.84404 -194.800748) (xy 212.620128 -194.800748) (xy 212.620128 -194.746252) (xy 212.627884 -194.692312)
			(xy 212.643237 -194.640024) (xy 212.665875 -194.590454) (xy 212.695337 -194.54461) (xy 212.731023 -194.503425)
			(xy 212.772208 -194.467738) (xy 212.818052 -194.438276) (xy 212.867622 -194.415637) (xy 212.91991 -194.400284)
			(xy 212.97385 -194.392528) (xy 213.001098 -194.392042) (xy 213.028633 -194.392549) (xy 213.083133 -194.400454)
			(xy 213.135929 -194.416115) (xy 213.185924 -194.439205) (xy 213.232079 -194.469245) (xy 213.273434 -194.505611)
			(xy 213.309129 -194.547545) (xy 213.324186 -194.570604) (xy 213.332511 -194.582854) (xy 213.354822 -194.602313)
			(xy 213.381772 -194.614569) (xy 213.411102 -194.618595) (xy 213.440357 -194.614053) (xy 213.467086 -194.601324)
			(xy 213.48905 -194.581474) (xy 213.49716 -194.56908) (xy 213.512062 -194.545308) (xy 213.547739 -194.502011)
			(xy 213.589372 -194.464404) (xy 213.636064 -194.433299) (xy 213.686806 -194.409365) (xy 213.740506 -194.39312)
			(xy 213.796006 -194.384914) (xy 213.824058 -194.384422) (xy 213.851778 -194.384895) (xy 213.906633 -194.39292)
			(xy 213.959748 -194.408806) (xy 214.010001 -194.432219) (xy 214.056332 -194.462664) (xy 214.097765 -194.4995)
			(xy 214.133425 -194.541948) (xy 214.148416 -194.56527) (xy 214.15649 -194.577384) (xy 214.178106 -194.596862)
			(xy 214.20434 -194.609446) (xy 214.233061 -194.614114) (xy 214.26193 -194.610485) (xy 214.288602 -194.598854)
			(xy 214.310906 -194.580169) (xy 214.319358 -194.568318) (xy 214.333626 -194.547868) (xy 214.3669 -194.510733)
			(xy 214.40503 -194.478604) (xy 214.44727 -194.452109) (xy 214.492794 -194.431768) (xy 214.540711 -194.417978)
			(xy 214.590083 -194.411008) (xy 214.615014 -194.410584) (xy 214.641662 -194.411099) (xy 214.694363 -194.419044)
			(xy 214.74529 -194.434755) (xy 214.793308 -194.45788) (xy 214.837342 -194.487904) (xy 214.87641 -194.524156)
			(xy 214.909639 -194.565825) (xy 214.936287 -194.611981) (xy 214.955758 -194.661593) (xy 214.967617 -194.713553)
			(xy 214.9716 -194.7667) (xy 214.969603 -194.793341) (xy 216.469204 -194.793341) (xy 216.469204 -194.740043)
			(xy 216.477147 -194.687339) (xy 216.492857 -194.636409) (xy 216.515983 -194.588388) (xy 216.546007 -194.544351)
			(xy 216.582259 -194.50528) (xy 216.62393 -194.472049) (xy 216.670088 -194.4454) (xy 216.719702 -194.425928)
			(xy 216.771664 -194.414068) (xy 216.824814 -194.410085) (xy 216.877964 -194.414068) (xy 216.929926 -194.425928)
			(xy 216.97954 -194.4454) (xy 217.025698 -194.472049) (xy 217.067369 -194.50528) (xy 217.103621 -194.544351)
			(xy 217.133645 -194.588388) (xy 217.156771 -194.636409) (xy 217.172481 -194.687339) (xy 217.180424 -194.740043)
			(xy 217.180922 -194.766692) (xy 217.180424 -194.793341) (xy 217.172481 -194.846045) (xy 217.156771 -194.896975)
			(xy 217.133645 -194.944996) (xy 217.103621 -194.989033) (xy 217.067369 -195.028104) (xy 217.025698 -195.061335)
			(xy 216.97954 -195.087984) (xy 216.929926 -195.107456) (xy 216.877964 -195.119316) (xy 216.824814 -195.1233)
			(xy 216.771664 -195.119316) (xy 216.719702 -195.107456) (xy 216.670088 -195.087984) (xy 216.62393 -195.061335)
			(xy 216.582259 -195.028104) (xy 216.546007 -194.989033) (xy 216.515983 -194.944996) (xy 216.492857 -194.896975)
			(xy 216.477147 -194.846045) (xy 216.469204 -194.793341) (xy 214.969603 -194.793341) (xy 214.967617 -194.819847)
			(xy 214.955758 -194.871807) (xy 214.936287 -194.921419) (xy 214.909639 -194.967575) (xy 214.87641 -195.009244)
			(xy 214.837342 -195.045496) (xy 214.793308 -195.07552) (xy 214.74529 -195.098645) (xy 214.694363 -195.114356)
			(xy 214.641662 -195.122301) (xy 214.615014 -195.1228) (xy 214.59003 -195.122343) (xy 214.540553 -195.115353)
			(xy 214.492537 -195.101522) (xy 214.446923 -195.08112) (xy 214.404605 -195.054548) (xy 214.366413 -195.022327)
			(xy 214.333095 -194.985088) (xy 214.31885 -194.964558) (xy 214.310416 -194.952723) (xy 214.288165 -194.934047)
			(xy 214.26155 -194.922403) (xy 214.232732 -194.918736) (xy 214.204049 -194.923344) (xy 214.17783 -194.935852)
			(xy 214.156201 -194.955245) (xy 214.148162 -194.967352) (xy 214.13314 -194.990592) (xy 214.097436 -195.032867)
			(xy 214.056 -195.069543) (xy 214.009702 -195.09985) (xy 213.959512 -195.123153) (xy 213.906482 -195.138963)
			(xy 213.851726 -195.146949) (xy 213.824058 -195.147438) (xy 213.796521 -195.146974) (xy 213.742019 -195.139062)
			(xy 213.689222 -195.123395) (xy 213.639226 -195.100298) (xy 213.593072 -195.070251) (xy 213.551718 -195.033879)
			(xy 213.516025 -194.991938) (xy 213.50097 -194.968876) (xy 213.492709 -194.956575) (xy 213.470388 -194.937098)
			(xy 213.443423 -194.924833) (xy 213.414074 -194.92081) (xy 213.384803 -194.925364) (xy 213.358065 -194.938114)
			(xy 213.3361 -194.957992) (xy 213.327996 -194.9704) (xy 213.313085 -194.994165) (xy 213.277405 -195.037458)
			(xy 213.235772 -195.075063) (xy 213.189083 -195.106167) (xy 213.138343 -195.130101) (xy 213.084646 -195.14635)
			(xy 213.029149 -195.154562) (xy 213.001098 -195.155058) (xy 212.97385 -195.154472) (xy 212.91991 -195.146716)
			(xy 212.867622 -195.131363) (xy 212.818052 -195.108724) (xy 212.772208 -195.079262) (xy 212.731023 -195.043575)
			(xy 212.695337 -195.00239) (xy 212.665875 -194.956546) (xy 212.643237 -194.906976) (xy 212.627884 -194.854688)
			(xy 212.620128 -194.800748) (xy 210.84404 -194.800748) (xy 210.837213 -194.846045) (xy 210.821503 -194.896975)
			(xy 210.798377 -194.944996) (xy 210.768353 -194.989033) (xy 210.732101 -195.028104) (xy 210.69043 -195.061335)
			(xy 210.644272 -195.087984) (xy 210.594658 -195.107456) (xy 210.542696 -195.119316) (xy 210.489546 -195.1233)
			(xy 210.436396 -195.119316) (xy 210.384434 -195.107456) (xy 210.33482 -195.087984) (xy 210.288662 -195.061335)
			(xy 210.246991 -195.028104) (xy 210.210739 -194.989033) (xy 210.180715 -194.944996) (xy 210.157589 -194.896975)
			(xy 210.141879 -194.846045) (xy 210.133936 -194.793341) (xy 209.636624 -194.793341) (xy 209.628681 -194.846045)
			(xy 209.612971 -194.896975) (xy 209.589845 -194.944996) (xy 209.559821 -194.989033) (xy 209.523569 -195.028104)
			(xy 209.481898 -195.061335) (xy 209.43574 -195.087984) (xy 209.386126 -195.107456) (xy 209.334164 -195.119316)
			(xy 209.281014 -195.1233) (xy 209.227864 -195.119316) (xy 209.175902 -195.107456) (xy 209.126288 -195.087984)
			(xy 209.08013 -195.061335) (xy 209.038459 -195.028104) (xy 209.002207 -194.989033) (xy 208.972183 -194.944996)
			(xy 208.949057 -194.896975) (xy 208.933347 -194.846045) (xy 208.925404 -194.793341) (xy 207.426824 -194.793341)
			(xy 207.418881 -194.846045) (xy 207.403171 -194.896975) (xy 207.380045 -194.944996) (xy 207.350021 -194.989033)
			(xy 207.313769 -195.028104) (xy 207.272098 -195.061335) (xy 207.22594 -195.087984) (xy 207.176326 -195.107456)
			(xy 207.124364 -195.119316) (xy 207.071214 -195.1233) (xy 207.018064 -195.119316) (xy 206.966102 -195.107456)
			(xy 206.916488 -195.087984) (xy 206.87033 -195.061335) (xy 206.828659 -195.028104) (xy 206.792407 -194.989033)
			(xy 206.762383 -194.944996) (xy 206.739257 -194.896975) (xy 206.723547 -194.846045) (xy 206.715604 -194.793341)
			(xy 206.715106 -194.766692) (xy 206.715589 -194.740094) (xy 206.723498 -194.68749) (xy 206.739152 -194.63665)
			(xy 206.762203 -194.588708) (xy 206.792137 -194.544734) (xy 206.809848 -194.524884) (xy 206.818732 -194.514748)
			(xy 206.831201 -194.49086) (xy 206.836983 -194.46454) (xy 206.835673 -194.437625) (xy 206.827363 -194.411991)
			(xy 206.812632 -194.389427) (xy 206.792509 -194.371505) (xy 206.780638 -194.365118) (xy 206.757238 -194.352908)
			(xy 206.713767 -194.322971) (xy 206.674837 -194.28733) (xy 206.64119 -194.246664) (xy 206.613467 -194.201749)
			(xy 206.592199 -194.153442) (xy 206.577791 -194.102665) (xy 206.570518 -194.050387) (xy 206.570072 -194.023996)
			(xy 203.483645 -194.023996) (xy 203.481064 -194.041949) (xy 203.465709 -194.094244) (xy 203.443067 -194.143821)
			(xy 203.413601 -194.189671) (xy 203.37791 -194.230862) (xy 203.336719 -194.266553) (xy 203.290869 -194.296019)
			(xy 203.241292 -194.318661) (xy 203.188997 -194.334016) (xy 203.135049 -194.341772) (xy 203.080547 -194.341772)
			(xy 203.026599 -194.334016) (xy 202.974304 -194.318661) (xy 202.924727 -194.296019) (xy 202.878877 -194.266553)
			(xy 202.837686 -194.230862) (xy 202.801995 -194.189671) (xy 202.772529 -194.143821) (xy 202.749887 -194.094244)
			(xy 202.734532 -194.041949) (xy 202.726776 -193.988001) (xy 202.72629 -193.96075) (xy 202.726834 -193.932333)
			(xy 202.73525 -193.876126) (xy 202.751903 -193.821787) (xy 202.776425 -193.770517) (xy 202.808275 -193.723446)
			(xy 202.827128 -193.702178) (xy 202.837344 -193.690343) (xy 202.850624 -193.662052) (xy 202.85473 -193.631071)
			(xy 202.849277 -193.600299) (xy 202.834775 -193.572615) (xy 202.82408 -193.561208) (xy 202.822302 -193.55943)
			(xy 202.811647 -193.549482) (xy 202.78607 -193.535525) (xy 202.757595 -193.529351) (xy 202.728535 -193.531464)
			(xy 202.701252 -193.541691) (xy 202.677963 -193.559201) (xy 202.668886 -193.570606) (xy 202.65076 -193.594124)
			(xy 202.608454 -193.635784) (xy 202.560205 -193.670388) (xy 202.507178 -193.697099) (xy 202.450653 -193.715273)
			(xy 202.391995 -193.724472) (xy 202.362308 -193.725038) (xy 202.335808 -193.724553) (xy 202.283319 -193.717214)
			(xy 202.232352 -193.702676) (xy 202.183889 -193.68122) (xy 202.138865 -193.65326) (xy 202.118214 -193.636646)
			(xy 202.106367 -193.627559) (xy 202.078883 -193.61594) (xy 202.049216 -193.612742) (xy 202.019887 -193.618238)
			(xy 201.993391 -193.631961) (xy 201.982324 -193.64198) (xy 201.960829 -193.662211) (xy 201.912735 -193.696433)
			(xy 201.859943 -193.72284) (xy 201.803715 -193.740801) (xy 201.745392 -193.749888) (xy 201.715878 -193.750438)
			(xy 201.68863 -193.74989) (xy 201.634689 -193.742132) (xy 201.582401 -193.726776) (xy 201.53283 -193.704135)
			(xy 201.486986 -193.674671) (xy 201.445802 -193.638982) (xy 201.410116 -193.597796) (xy 201.380654 -193.55195)
			(xy 201.358016 -193.502378) (xy 201.342663 -193.45009) (xy 201.334908 -193.396148) (xy 199.372513 -193.396148)
			(xy 199.383657 -193.433188) (xy 199.391777 -193.488364) (xy 199.392286 -193.51625) (xy 199.391777 -193.544136)
			(xy 199.383657 -193.599312) (xy 199.367589 -193.652719) (xy 199.343917 -193.703216) (xy 199.313144 -193.749729)
			(xy 199.275927 -193.791266) (xy 199.233059 -193.826941) (xy 199.185453 -193.855995) (xy 199.134124 -193.877807)
			(xy 199.080167 -193.891913) (xy 199.02473 -193.898013) (xy 198.968996 -193.895976) (xy 198.914153 -193.885846)
			(xy 198.861369 -193.867839) (xy 198.811769 -193.842338) (xy 198.766411 -193.809887) (xy 198.726262 -193.771178)
			(xy 198.692176 -193.727035) (xy 198.66488 -193.6784) (xy 198.644957 -193.626309) (xy 198.632831 -193.571872)
			(xy 198.62876 -193.51625) (xy 194.3608 -193.51625) (xy 194.3608 -194.044316) (xy 194.362324 -194.050158)
			(xy 194.365116 -194.06235) (xy 196.5485 -194.06235) (xy 196.552571 -194.006728) (xy 196.564697 -193.952291)
			(xy 196.58462 -193.9002) (xy 196.611916 -193.851565) (xy 196.646002 -193.807422) (xy 196.686151 -193.768713)
			(xy 196.731509 -193.736262) (xy 196.781109 -193.710761) (xy 196.833893 -193.692754) (xy 196.888736 -193.682624)
			(xy 196.94447 -193.680587) (xy 196.999907 -193.686687) (xy 197.053864 -193.700793) (xy 197.105193 -193.722605)
			(xy 197.152799 -193.751659) (xy 197.195667 -193.787334) (xy 197.232884 -193.828871) (xy 197.263657 -193.875384)
			(xy 197.287329 -193.925881) (xy 197.303397 -193.979288) (xy 197.311517 -194.034464) (xy 197.312026 -194.06235)
			(xy 197.311517 -194.090236) (xy 197.303397 -194.145412) (xy 197.287329 -194.198819) (xy 197.263657 -194.249316)
			(xy 197.232884 -194.295829) (xy 197.195667 -194.337366) (xy 197.152799 -194.373041) (xy 197.105193 -194.402095)
			(xy 197.053864 -194.423907) (xy 196.999907 -194.438013) (xy 196.94447 -194.444113) (xy 196.888736 -194.442076)
			(xy 196.833893 -194.431946) (xy 196.781109 -194.413939) (xy 196.731509 -194.388438) (xy 196.686151 -194.355987)
			(xy 196.646002 -194.317278) (xy 196.611916 -194.273135) (xy 196.58462 -194.2245) (xy 196.564697 -194.172409)
			(xy 196.552571 -194.117972) (xy 196.5485 -194.06235) (xy 194.365116 -194.06235) (xy 194.367449 -194.07254)
			(xy 194.372925 -194.118131) (xy 194.373246 -194.14109) (xy 194.372919 -194.164049) (xy 194.367443 -194.209639)
			(xy 194.362324 -194.232022) (xy 194.3608 -194.237864) (xy 194.3608 -194.452494) (xy 194.384851 -194.465871)
			(xy 194.428877 -194.49889) (xy 194.467294 -194.538295) (xy 194.499185 -194.583145) (xy 194.523789 -194.63237)
			(xy 194.540521 -194.684798) (xy 194.548981 -194.739176) (xy 194.549522 -194.766692) (xy 194.549198 -194.789686)
			(xy 194.548729 -194.793341) (xy 195.071736 -194.793341) (xy 195.071736 -194.740043) (xy 195.079679 -194.687339)
			(xy 195.095389 -194.636409) (xy 195.118515 -194.588388) (xy 195.148539 -194.544351) (xy 195.184791 -194.50528)
			(xy 195.226462 -194.472049) (xy 195.27262 -194.4454) (xy 195.322234 -194.425928) (xy 195.374196 -194.414068)
			(xy 195.427346 -194.410085) (xy 195.480496 -194.414068) (xy 195.532458 -194.425928) (xy 195.582072 -194.4454)
			(xy 195.62823 -194.472049) (xy 195.669901 -194.50528) (xy 195.706153 -194.544351) (xy 195.736177 -194.588388)
			(xy 195.759303 -194.636409) (xy 195.775013 -194.687339) (xy 195.782956 -194.740043) (xy 195.783454 -194.766692)
			(xy 195.783401 -194.769553) (xy 198.377763 -194.769553) (xy 198.377763 -194.715047) (xy 198.38552 -194.661097)
			(xy 198.400877 -194.608799) (xy 198.423519 -194.559219) (xy 198.452988 -194.513367) (xy 198.488682 -194.472175)
			(xy 198.529875 -194.436482) (xy 198.575728 -194.407015) (xy 198.625308 -194.384373) (xy 198.677606 -194.369018)
			(xy 198.731557 -194.361263) (xy 198.75881 -194.3608) (xy 198.78628 -194.361258) (xy 198.840652 -194.36914)
			(xy 198.893331 -194.38474) (xy 198.943228 -194.407734) (xy 198.98931 -194.437648) (xy 199.030625 -194.473862)
			(xy 199.066319 -194.515628) (xy 199.08139 -194.5386) (xy 199.089217 -194.550109) (xy 199.109877 -194.568741)
			(xy 199.134798 -194.581106) (xy 199.162133 -194.586286) (xy 199.18985 -194.583896) (xy 199.215894 -194.574113)
			(xy 199.238332 -194.557664) (xy 199.247252 -194.546982) (xy 199.264194 -194.526093) (xy 199.303367 -194.489238)
			(xy 199.347637 -194.458694) (xy 199.395998 -194.435157) (xy 199.447349 -194.419163) (xy 199.500522 -194.411075)
			(xy 199.527414 -194.410584) (xy 199.554062 -194.411099) (xy 199.606763 -194.419044) (xy 199.65769 -194.434755)
			(xy 199.705708 -194.45788) (xy 199.749742 -194.487904) (xy 199.78881 -194.524156) (xy 199.822039 -194.565825)
			(xy 199.848687 -194.611981) (xy 199.868158 -194.661593) (xy 199.880017 -194.713553) (xy 199.884 -194.7667)
			(xy 199.882003 -194.793341) (xy 201.381604 -194.793341) (xy 201.381604 -194.740043) (xy 201.389547 -194.687339)
			(xy 201.405257 -194.636409) (xy 201.428383 -194.588388) (xy 201.458407 -194.544351) (xy 201.494659 -194.50528)
			(xy 201.53633 -194.472049) (xy 201.582488 -194.4454) (xy 201.632102 -194.425928) (xy 201.684064 -194.414068)
			(xy 201.737214 -194.410085) (xy 201.790364 -194.414068) (xy 201.842326 -194.425928) (xy 201.89194 -194.4454)
			(xy 201.938098 -194.472049) (xy 201.979769 -194.50528) (xy 202.016021 -194.544351) (xy 202.046045 -194.588388)
			(xy 202.069171 -194.636409) (xy 202.084881 -194.687339) (xy 202.092824 -194.740043) (xy 202.093322 -194.766692)
			(xy 202.092824 -194.793341) (xy 202.084881 -194.846045) (xy 202.069171 -194.896975) (xy 202.052169 -194.932279)
			(xy 202.188308 -194.932279) (xy 202.188308 -194.878981) (xy 202.196251 -194.826277) (xy 202.211961 -194.775347)
			(xy 202.235087 -194.727326) (xy 202.265111 -194.683289) (xy 202.301363 -194.644218) (xy 202.343034 -194.610987)
			(xy 202.389192 -194.584338) (xy 202.438806 -194.564866) (xy 202.490768 -194.553006) (xy 202.543918 -194.549023)
			(xy 202.597068 -194.553006) (xy 202.64903 -194.564866) (xy 202.698644 -194.584338) (xy 202.744802 -194.610987)
			(xy 202.786473 -194.644218) (xy 202.822725 -194.683289) (xy 202.852749 -194.727326) (xy 202.875875 -194.775347)
			(xy 202.891585 -194.826277) (xy 202.899528 -194.878981) (xy 202.900026 -194.90563) (xy 202.899528 -194.932279)
			(xy 202.891585 -194.984983) (xy 202.875875 -195.035913) (xy 202.852749 -195.083934) (xy 202.822725 -195.127971)
			(xy 202.786473 -195.167042) (xy 202.744802 -195.200273) (xy 202.698644 -195.226922) (xy 202.64903 -195.246394)
			(xy 202.597068 -195.258254) (xy 202.543918 -195.262238) (xy 202.490768 -195.258254) (xy 202.438806 -195.246394)
			(xy 202.389192 -195.226922) (xy 202.343034 -195.200273) (xy 202.301363 -195.167042) (xy 202.265111 -195.127971)
			(xy 202.235087 -195.083934) (xy 202.211961 -195.035913) (xy 202.196251 -194.984983) (xy 202.188308 -194.932279)
			(xy 202.052169 -194.932279) (xy 202.046045 -194.944996) (xy 202.016021 -194.989033) (xy 201.979769 -195.028104)
			(xy 201.938098 -195.061335) (xy 201.89194 -195.087984) (xy 201.842326 -195.107456) (xy 201.790364 -195.119316)
			(xy 201.737214 -195.1233) (xy 201.684064 -195.119316) (xy 201.632102 -195.107456) (xy 201.582488 -195.087984)
			(xy 201.53633 -195.061335) (xy 201.494659 -195.028104) (xy 201.458407 -194.989033) (xy 201.428383 -194.944996)
			(xy 201.405257 -194.896975) (xy 201.389547 -194.846045) (xy 201.381604 -194.793341) (xy 199.882003 -194.793341)
			(xy 199.880017 -194.819847) (xy 199.868158 -194.871807) (xy 199.848687 -194.921419) (xy 199.822039 -194.967575)
			(xy 199.78881 -195.009244) (xy 199.749742 -195.045496) (xy 199.705708 -195.07552) (xy 199.65769 -195.098645)
			(xy 199.606763 -195.114356) (xy 199.554062 -195.122301) (xy 199.527414 -195.1228) (xy 199.498627 -195.122233)
			(xy 199.441805 -195.11296) (xy 199.387213 -195.094668) (xy 199.336275 -195.067834) (xy 199.290316 -195.033156)
			(xy 199.250532 -194.991539) (xy 199.23379 -194.968114) (xy 199.225493 -194.956949) (xy 199.204125 -194.93916)
			(xy 199.178755 -194.927785) (xy 199.151258 -194.923666) (xy 199.123668 -194.927107) (xy 199.098026 -194.937854)
			(xy 199.076227 -194.955112) (xy 199.067674 -194.966082) (xy 199.052256 -194.986683) (xy 199.016754 -195.023928)
			(xy 198.976564 -195.056061) (xy 198.932419 -195.082497) (xy 198.88512 -195.102757) (xy 198.835526 -195.116472)
			(xy 198.784538 -195.123393) (xy 198.75881 -195.123816) (xy 198.731557 -195.123337) (xy 198.677606 -195.115582)
			(xy 198.625308 -195.100227) (xy 198.575728 -195.077585) (xy 198.529875 -195.048118) (xy 198.488682 -195.012425)
			(xy 198.452988 -194.971233) (xy 198.423519 -194.925381) (xy 198.400877 -194.875801) (xy 198.38552 -194.823503)
			(xy 198.377763 -194.769553) (xy 195.783401 -194.769553) (xy 195.782956 -194.793341) (xy 195.775013 -194.846045)
			(xy 195.759303 -194.896975) (xy 195.736177 -194.944996) (xy 195.706153 -194.989033) (xy 195.669901 -195.028104)
			(xy 195.62823 -195.061335) (xy 195.582072 -195.087984) (xy 195.532458 -195.107456) (xy 195.480496 -195.119316)
			(xy 195.427346 -195.1233) (xy 195.374196 -195.119316) (xy 195.322234 -195.107456) (xy 195.27262 -195.087984)
			(xy 195.226462 -195.061335) (xy 195.184791 -195.028104) (xy 195.148539 -194.989033) (xy 195.118515 -194.944996)
			(xy 195.095389 -194.896975) (xy 195.079679 -194.846045) (xy 195.071736 -194.793341) (xy 194.548729 -194.793341)
			(xy 194.543344 -194.835297) (xy 194.537838 -194.857624) (xy 194.530218 -194.885818) (xy 195.020692 -195.376292)
			(xy 195.030618 -195.385617) (xy 195.054266 -195.399106) (xy 195.080641 -195.405855) (xy 195.107862 -195.405383)
			(xy 195.133987 -195.397724) (xy 195.157153 -195.383423) (xy 195.166742 -195.373752) (xy 195.187122 -195.352768)
			(xy 195.233469 -195.317087) (xy 195.285021 -195.289455) (xy 195.340394 -195.270613) (xy 195.3981 -195.261067)
			(xy 195.427346 -195.260468) (xy 195.455327 -195.26102) (xy 195.5106 -195.269781) (xy 195.563823 -195.287079)
			(xy 195.613684 -195.312489) (xy 195.658958 -195.345386) (xy 195.698528 -195.384959) (xy 195.731422 -195.430234)
			(xy 195.756829 -195.480098) (xy 195.774124 -195.533321) (xy 195.782881 -195.588595) (xy 195.783454 -195.616576)
			(xy 195.782867 -195.645823) (xy 195.773321 -195.703533) (xy 195.75448 -195.758909) (xy 195.726852 -195.810467)
			(xy 195.691176 -195.856822) (xy 195.67017 -195.87718) (xy 195.660541 -195.886791) (xy 195.646301 -195.909962)
			(xy 195.638678 -195.936068) (xy 195.638212 -195.96326) (xy 195.644936 -195.989613) (xy 195.658373 -196.013258)
			(xy 195.66763 -196.02323) (xy 195.707 -196.0626) (xy 197.335648 -196.0626) (xy 197.349344 -196.062149)
			(xy 197.37575 -196.054859) (xy 197.399269 -196.040816) (xy 197.418213 -196.021029) (xy 197.431218 -195.99692)
			(xy 197.437352 -195.970223) (xy 197.436172 -195.942855) (xy 197.427764 -195.916784) (xy 197.412731 -195.893884)
			(xy 197.402704 -195.884546) (xy 197.383952 -195.867566) (xy 197.350962 -195.829215) (xy 197.323738 -195.786577)
			(xy 197.302829 -195.740512) (xy 197.288657 -195.69195) (xy 197.281508 -195.64187) (xy 197.281038 -195.616576)
			(xy 197.281536 -195.589927) (xy 197.289479 -195.537223) (xy 197.305189 -195.486293) (xy 197.328315 -195.438272)
			(xy 197.358339 -195.394235) (xy 197.394591 -195.355164) (xy 197.436262 -195.321933) (xy 197.48242 -195.295284)
			(xy 197.532034 -195.275812) (xy 197.583996 -195.263952) (xy 197.637146 -195.259969) (xy 197.690296 -195.263952)
			(xy 197.742258 -195.275812) (xy 197.791872 -195.295284) (xy 197.83803 -195.321933) (xy 197.879701 -195.355164)
			(xy 197.915953 -195.394235) (xy 197.945977 -195.438272) (xy 197.969103 -195.486293) (xy 197.984813 -195.537223)
			(xy 197.992756 -195.589927) (xy 197.993254 -195.616576) (xy 197.992805 -195.641869) (xy 197.985635 -195.691944)
			(xy 197.971449 -195.740501) (xy 197.950534 -195.786561) (xy 197.92331 -195.829197) (xy 197.890325 -195.86755)
			(xy 197.871588 -195.884546) (xy 197.861576 -195.893914) (xy 197.84651 -195.916811) (xy 197.838075 -195.94289)
			(xy 197.836879 -195.970273) (xy 197.843006 -195.996988) (xy 197.856018 -196.021112) (xy 197.874975 -196.040907)
			(xy 197.898514 -196.054949) (xy 197.924939 -196.062226) (xy 197.938644 -196.0626) (xy 202.669648 -196.0626)
			(xy 202.683344 -196.062149) (xy 202.70975 -196.054859) (xy 202.733269 -196.040816) (xy 202.752213 -196.021029)
			(xy 202.765218 -195.99692) (xy 202.771352 -195.970223) (xy 202.770172 -195.942855) (xy 202.761764 -195.916784)
			(xy 202.746731 -195.893884) (xy 202.736704 -195.884546) (xy 202.717952 -195.867566) (xy 202.684962 -195.829215)
			(xy 202.657738 -195.786577) (xy 202.636829 -195.740512) (xy 202.622657 -195.69195) (xy 202.615508 -195.64187)
			(xy 202.615038 -195.616576) (xy 202.615536 -195.589927) (xy 202.623479 -195.537223) (xy 202.639189 -195.486293)
			(xy 202.662315 -195.438272) (xy 202.692339 -195.394235) (xy 202.728591 -195.355164) (xy 202.770262 -195.321933)
			(xy 202.81642 -195.295284) (xy 202.866034 -195.275812) (xy 202.917996 -195.263952) (xy 202.971146 -195.259969)
			(xy 203.024296 -195.263952) (xy 203.076258 -195.275812) (xy 203.125872 -195.295284) (xy 203.17203 -195.321933)
			(xy 203.213701 -195.355164) (xy 203.249953 -195.394235) (xy 203.279977 -195.438272) (xy 203.303103 -195.486293)
			(xy 203.318813 -195.537223) (xy 203.326756 -195.589927) (xy 203.327254 -195.616576) (xy 203.326805 -195.641869)
			(xy 203.319635 -195.691944) (xy 203.305449 -195.740501) (xy 203.284534 -195.786561) (xy 203.25731 -195.829197)
			(xy 203.224325 -195.86755) (xy 203.205588 -195.884546) (xy 203.195576 -195.893914) (xy 203.18051 -195.916811)
			(xy 203.172075 -195.94289) (xy 203.170879 -195.970273) (xy 203.177006 -195.996988) (xy 203.190018 -196.021112)
			(xy 203.208975 -196.040907) (xy 203.232514 -196.054949) (xy 203.258939 -196.062226) (xy 203.272644 -196.0626)
			(xy 204.879448 -196.0626) (xy 204.893144 -196.062149) (xy 204.91955 -196.054859) (xy 204.943069 -196.040816)
			(xy 204.962013 -196.021029) (xy 204.975018 -195.99692) (xy 204.981152 -195.970223) (xy 204.979972 -195.942855)
			(xy 204.971564 -195.916784) (xy 204.956531 -195.893884) (xy 204.946504 -195.884546) (xy 204.927752 -195.867566)
			(xy 204.894762 -195.829215) (xy 204.867538 -195.786577) (xy 204.846629 -195.740512) (xy 204.832457 -195.69195)
			(xy 204.825308 -195.64187) (xy 204.824838 -195.616576) (xy 204.82536 -195.588593) (xy 204.834119 -195.533317)
			(xy 204.851418 -195.480092) (xy 204.87683 -195.430229) (xy 204.90973 -195.384954) (xy 204.949308 -195.345385)
			(xy 204.994588 -195.312494) (xy 205.044457 -195.287091) (xy 205.097685 -195.269803) (xy 205.152963 -195.261055)
			(xy 205.180946 -195.260468) (xy 205.206195 -195.260904) (xy 205.256189 -195.268028) (xy 205.304675 -195.282141)
			(xy 205.350683 -195.302959) (xy 205.393289 -195.330066) (xy 205.431641 -195.362919) (xy 205.464968 -195.400858)
			(xy 205.479142 -195.421758) (xy 205.487207 -195.433316) (xy 205.508447 -195.451824) (xy 205.53394 -195.463816)
			(xy 205.56174 -195.468378) (xy 205.589728 -195.465162) (xy 205.615769 -195.454412) (xy 205.637877 -195.43695)
			(xy 205.646528 -195.425822) (xy 205.661958 -195.405161) (xy 205.697485 -195.367786) (xy 205.737723 -195.335538)
			(xy 205.781939 -195.309004) (xy 205.829326 -195.288669) (xy 205.879021 -195.274902) (xy 205.930117 -195.267956)
			(xy 205.9559 -195.26758) (xy 205.983152 -195.268066) (xy 206.0371 -195.275822) (xy 206.089395 -195.291177)
			(xy 206.138973 -195.313818) (xy 206.184825 -195.343284) (xy 206.226016 -195.378976) (xy 206.261709 -195.420166)
			(xy 206.291176 -195.466016) (xy 206.313819 -195.515593) (xy 206.329175 -195.567888) (xy 206.336933 -195.621836)
			(xy 206.337408 -195.649088) (xy 206.336956 -195.675882) (xy 206.32946 -195.728944) (xy 206.314615 -195.780435)
			(xy 206.292712 -195.829343) (xy 206.264181 -195.874706) (xy 206.247238 -195.895468) (xy 206.238304 -195.906824)
			(xy 206.226591 -195.933223) (xy 206.222742 -195.961846) (xy 206.227065 -195.990402) (xy 206.239214 -196.016603)
			(xy 206.258217 -196.038352) (xy 206.282551 -196.053906) (xy 206.310268 -196.062022) (xy 206.324708 -196.0626)
			(xy 206.769716 -196.0626) (xy 206.783416 -196.062153) (xy 206.809829 -196.054868) (xy 206.833356 -196.040826)
			(xy 206.852307 -196.021037) (xy 206.865317 -195.996924) (xy 206.871452 -195.97022) (xy 206.87027 -195.942847)
			(xy 206.861857 -195.916771) (xy 206.846818 -195.893868) (xy 206.836772 -195.884546) (xy 206.818016 -195.867568)
			(xy 206.785021 -195.829219) (xy 206.757792 -195.786582) (xy 206.736879 -195.740517) (xy 206.722704 -195.691953)
			(xy 206.715553 -195.641871) (xy 206.715106 -195.616576) (xy 206.715604 -195.589927) (xy 206.723547 -195.537223)
			(xy 206.739257 -195.486293) (xy 206.762383 -195.438272) (xy 206.792407 -195.394235) (xy 206.828659 -195.355164)
			(xy 206.87033 -195.321933) (xy 206.916488 -195.295284) (xy 206.966102 -195.275812) (xy 207.018064 -195.263952)
			(xy 207.071214 -195.259969) (xy 207.124364 -195.263952) (xy 207.176326 -195.275812) (xy 207.22594 -195.295284)
			(xy 207.272098 -195.321933) (xy 207.313769 -195.355164) (xy 207.350021 -195.394235) (xy 207.380045 -195.438272)
			(xy 207.403171 -195.486293) (xy 207.418881 -195.537223) (xy 207.426824 -195.589927) (xy 207.427322 -195.616576)
			(xy 207.426873 -195.641869) (xy 207.419702 -195.691943) (xy 207.405515 -195.740499) (xy 207.384598 -195.786558)
			(xy 207.357373 -195.829192) (xy 207.324387 -195.867543) (xy 207.305656 -195.884546) (xy 207.295639 -195.89391)
			(xy 207.280564 -195.916802) (xy 207.272123 -195.94288) (xy 207.270923 -195.970264) (xy 207.277052 -195.99698)
			(xy 207.290067 -196.021103) (xy 207.309031 -196.040893) (xy 207.332576 -196.054926) (xy 207.359007 -196.062189)
			(xy 207.372712 -196.0626) (xy 210.213448 -196.0626) (xy 210.227144 -196.062149) (xy 210.25355 -196.054859)
			(xy 210.277069 -196.040816) (xy 210.296013 -196.021029) (xy 210.309018 -195.99692) (xy 210.315152 -195.970223)
			(xy 210.313972 -195.942855) (xy 210.305564 -195.916784) (xy 210.290531 -195.893884) (xy 210.280504 -195.884546)
			(xy 210.261752 -195.867566) (xy 210.228762 -195.829215) (xy 210.201538 -195.786577) (xy 210.180629 -195.740512)
			(xy 210.166457 -195.69195) (xy 210.159308 -195.64187) (xy 210.158838 -195.616576) (xy 210.159336 -195.589927)
			(xy 210.167279 -195.537223) (xy 210.182989 -195.486293) (xy 210.206115 -195.438272) (xy 210.236139 -195.394235)
			(xy 210.272391 -195.355164) (xy 210.314062 -195.321933) (xy 210.36022 -195.295284) (xy 210.409834 -195.275812)
			(xy 210.461796 -195.263952) (xy 210.514946 -195.259969) (xy 210.568096 -195.263952) (xy 210.620058 -195.275812)
			(xy 210.669672 -195.295284) (xy 210.71583 -195.321933) (xy 210.757501 -195.355164) (xy 210.793753 -195.394235)
			(xy 210.823777 -195.438272) (xy 210.846903 -195.486293) (xy 210.862613 -195.537223) (xy 210.870556 -195.589927)
			(xy 210.871054 -195.616576) (xy 210.870605 -195.641869) (xy 210.863435 -195.691944) (xy 210.849249 -195.740501)
			(xy 210.828334 -195.786561) (xy 210.80111 -195.829197) (xy 210.768125 -195.86755) (xy 210.749388 -195.884546)
			(xy 210.739376 -195.893914) (xy 210.72431 -195.916811) (xy 210.715875 -195.94289) (xy 210.714679 -195.970273)
			(xy 210.720806 -195.996988) (xy 210.733818 -196.021112) (xy 210.752775 -196.040907) (xy 210.776314 -196.054949)
			(xy 210.802739 -196.062226) (xy 210.816444 -196.0626) (xy 212.423248 -196.0626) (xy 212.436944 -196.062149)
			(xy 212.46335 -196.054859) (xy 212.486869 -196.040816) (xy 212.505813 -196.021029) (xy 212.518818 -195.99692)
			(xy 212.524952 -195.970223) (xy 212.523772 -195.942855) (xy 212.515364 -195.916784) (xy 212.500331 -195.893884)
			(xy 212.490304 -195.884546) (xy 212.471552 -195.867566) (xy 212.438562 -195.829215) (xy 212.411338 -195.786577)
			(xy 212.390429 -195.740512) (xy 212.376257 -195.69195) (xy 212.369108 -195.64187) (xy 212.368638 -195.616576)
			(xy 212.369136 -195.589927) (xy 212.377079 -195.537223) (xy 212.392789 -195.486293) (xy 212.415915 -195.438272)
			(xy 212.445939 -195.394235) (xy 212.482191 -195.355164) (xy 212.523862 -195.321933) (xy 212.57002 -195.295284)
			(xy 212.619634 -195.275812) (xy 212.671596 -195.263952) (xy 212.724746 -195.259969) (xy 212.777896 -195.263952)
			(xy 212.829858 -195.275812) (xy 212.879472 -195.295284) (xy 212.92563 -195.321933) (xy 212.967301 -195.355164)
			(xy 213.003553 -195.394235) (xy 213.033577 -195.438272) (xy 213.056703 -195.486293) (xy 213.072413 -195.537223)
			(xy 213.080356 -195.589927) (xy 213.080854 -195.616576) (xy 213.080306 -195.644476) (xy 213.071592 -195.699591)
			(xy 213.054389 -195.752673) (xy 213.029119 -195.802423) (xy 212.996399 -195.847623) (xy 212.95703 -195.887167)
			(xy 212.911976 -195.920088) (xy 212.862339 -195.94558) (xy 212.809334 -195.963019) (xy 212.781896 -195.968112)
			(xy 212.768181 -195.970761) (xy 212.742846 -195.982503) (xy 212.721645 -196.000676) (xy 212.706167 -196.023918)
			(xy 212.697572 -196.050486) (xy 212.696505 -196.07839) (xy 212.703045 -196.105537) (xy 212.716702 -196.129893)
			(xy 212.72627 -196.14007) (xy 213.4362 -196.85) (xy 214.254334 -196.85) (xy 214.268543 -196.849537)
			(xy 214.295864 -196.841716) (xy 214.319967 -196.826663) (xy 214.338983 -196.805545) (xy 214.351437 -196.780001)
			(xy 214.356362 -196.752013) (xy 214.353375 -196.723753) (xy 214.342709 -196.697412) (xy 214.334344 -196.685916)
			(xy 214.316623 -196.662281) (xy 214.288448 -196.610365) (xy 214.269228 -196.55451) (xy 214.259492 -196.496249)
			(xy 214.258906 -196.466714) (xy 214.259404 -196.440065) (xy 214.267347 -196.387361) (xy 214.283057 -196.336431)
			(xy 214.306183 -196.28841) (xy 214.336207 -196.244373) (xy 214.372459 -196.205302) (xy 214.41413 -196.172071)
			(xy 214.460288 -196.145422) (xy 214.509902 -196.12595) (xy 214.561864 -196.11409) (xy 214.615014 -196.110107)
			(xy 214.668164 -196.11409) (xy 214.720126 -196.12595) (xy 214.76974 -196.145422) (xy 214.815898 -196.172071)
			(xy 214.857569 -196.205302) (xy 214.893821 -196.244373) (xy 214.923845 -196.28841) (xy 214.946971 -196.336431)
			(xy 214.962681 -196.387361) (xy 214.970624 -196.440065) (xy 214.971122 -196.466714) (xy 214.970541 -196.496248)
			(xy 214.960795 -196.554507) (xy 214.941573 -196.610361) (xy 214.9134 -196.662278) (xy 214.895684 -196.685916)
			(xy 214.887321 -196.697403) (xy 214.876698 -196.723743) (xy 214.873739 -196.75199) (xy 214.878675 -196.77996)
			(xy 214.891123 -196.805489) (xy 214.910121 -196.826602) (xy 214.934198 -196.841666) (xy 214.961494 -196.849517)
			(xy 214.975694 -196.85) (xy 216.464134 -196.85) (xy 216.478343 -196.849537) (xy 216.505664 -196.841716)
			(xy 216.529767 -196.826663) (xy 216.548783 -196.805545) (xy 216.561237 -196.780001) (xy 216.566162 -196.752013)
			(xy 216.563175 -196.723753) (xy 216.552509 -196.697412) (xy 216.544144 -196.685916) (xy 216.526423 -196.662281)
			(xy 216.498248 -196.610365) (xy 216.479028 -196.55451) (xy 216.469292 -196.496249) (xy 216.468706 -196.466714)
			(xy 216.469204 -196.440065) (xy 216.477147 -196.387361) (xy 216.492857 -196.336431) (xy 216.515983 -196.28841)
			(xy 216.546007 -196.244373) (xy 216.582259 -196.205302) (xy 216.62393 -196.172071) (xy 216.670088 -196.145422)
			(xy 216.719702 -196.12595) (xy 216.771664 -196.11409) (xy 216.824814 -196.110107) (xy 216.877964 -196.11409)
			(xy 216.929926 -196.12595) (xy 216.97954 -196.145422) (xy 217.025698 -196.172071) (xy 217.067369 -196.205302)
			(xy 217.103621 -196.244373) (xy 217.133645 -196.28841) (xy 217.156771 -196.336431) (xy 217.172481 -196.387361)
			(xy 217.180424 -196.440065) (xy 217.180922 -196.466714) (xy 217.180341 -196.496248) (xy 217.170595 -196.554507)
			(xy 217.151373 -196.610361) (xy 217.1232 -196.662278) (xy 217.105484 -196.685916) (xy 217.097121 -196.697403)
			(xy 217.086498 -196.723743) (xy 217.083539 -196.75199) (xy 217.088475 -196.77996) (xy 217.100923 -196.805489)
			(xy 217.119921 -196.826602) (xy 217.143998 -196.841666) (xy 217.171294 -196.849517) (xy 217.185494 -196.85)
			(xy 218.2114 -196.85) (xy 219.080588 -197.719188) (xy 219.091152 -197.729053) (xy 219.116478 -197.742956)
			(xy 219.144687 -197.749199) (xy 219.173514 -197.747282) (xy 219.200647 -197.737358) (xy 219.223909 -197.720224)
			(xy 219.241433 -197.697254) (xy 219.251812 -197.670292) (xy 219.253562 -197.655942) (xy 219.256473 -197.627718)
			(xy 219.269579 -197.572516) (xy 219.290719 -197.519864) (xy 219.319425 -197.470925) (xy 219.355065 -197.426778)
			(xy 219.396851 -197.388399) (xy 219.443862 -197.356633) (xy 219.49506 -197.332182) (xy 219.549316 -197.315585)
			(xy 219.605431 -197.30721) (xy 219.6338 -197.306692) (xy 219.661051 -197.307178) (xy 219.714999 -197.314934)
			(xy 219.767294 -197.330289) (xy 219.816871 -197.352931) (xy 219.862721 -197.382397) (xy 219.903912 -197.418088)
			(xy 219.939603 -197.459279) (xy 219.969069 -197.505129) (xy 219.991711 -197.554706) (xy 220.007066 -197.607001)
			(xy 220.014822 -197.660949) (xy 220.014822 -197.715451) (xy 220.007066 -197.769399) (xy 219.991711 -197.821694)
			(xy 219.969069 -197.871271) (xy 219.939603 -197.917121) (xy 219.903912 -197.958312) (xy 219.862721 -197.994003)
			(xy 219.816871 -198.023469) (xy 219.767294 -198.046111) (xy 219.714999 -198.061466) (xy 219.661051 -198.069222)
			(xy 219.6338 -198.069708) (xy 219.613905 -198.069503) (xy 219.574325 -198.065435) (xy 219.554806 -198.06158)
			(xy 219.527882 -198.055738) (xy 219.47251 -198.11111) (xy 219.5576 -198.1962) (xy 219.5576 -221.42323)
			(xy 224.34372 -221.42323) (xy 224.347791 -221.367608) (xy 224.359917 -221.313171) (xy 224.37984 -221.26108)
			(xy 224.407136 -221.212445) (xy 224.441222 -221.168302) (xy 224.481371 -221.129593) (xy 224.526729 -221.097142)
			(xy 224.576329 -221.071641) (xy 224.629113 -221.053634) (xy 224.683956 -221.043504) (xy 224.73969 -221.041467)
			(xy 224.795127 -221.047567) (xy 224.849084 -221.061673) (xy 224.900413 -221.083485) (xy 224.948019 -221.112539)
			(xy 224.990887 -221.148214) (xy 225.028104 -221.189751) (xy 225.058877 -221.236264) (xy 225.082549 -221.286761)
			(xy 225.098617 -221.340168) (xy 225.106737 -221.395344) (xy 225.107246 -221.42323) (xy 226.92182 -221.42323)
			(xy 226.925891 -221.367608) (xy 226.938017 -221.313171) (xy 226.95794 -221.26108) (xy 226.985236 -221.212445)
			(xy 227.019322 -221.168302) (xy 227.059471 -221.129593) (xy 227.104829 -221.097142) (xy 227.154429 -221.071641)
			(xy 227.207213 -221.053634) (xy 227.262056 -221.043504) (xy 227.31779 -221.041467) (xy 227.373227 -221.047567)
			(xy 227.427184 -221.061673) (xy 227.478513 -221.083485) (xy 227.526119 -221.112539) (xy 227.568987 -221.148214)
			(xy 227.606204 -221.189751) (xy 227.636977 -221.236264) (xy 227.660649 -221.286761) (xy 227.676717 -221.340168)
			(xy 227.684837 -221.395344) (xy 227.685346 -221.42323) (xy 227.684837 -221.451116) (xy 227.676717 -221.506292)
			(xy 227.660649 -221.559699) (xy 227.636977 -221.610196) (xy 227.606204 -221.656709) (xy 227.568987 -221.698246)
			(xy 227.526119 -221.733921) (xy 227.478513 -221.762975) (xy 227.427184 -221.784787) (xy 227.373227 -221.798893)
			(xy 227.31779 -221.804993) (xy 227.262056 -221.802956) (xy 227.207213 -221.792826) (xy 227.154429 -221.774819)
			(xy 227.104829 -221.749318) (xy 227.059471 -221.716867) (xy 227.019322 -221.678158) (xy 226.985236 -221.634015)
			(xy 226.95794 -221.58538) (xy 226.938017 -221.533289) (xy 226.925891 -221.478852) (xy 226.92182 -221.42323)
			(xy 225.107246 -221.42323) (xy 225.106737 -221.451116) (xy 225.098617 -221.506292) (xy 225.082549 -221.559699)
			(xy 225.058877 -221.610196) (xy 225.028104 -221.656709) (xy 224.990887 -221.698246) (xy 224.948019 -221.733921)
			(xy 224.900413 -221.762975) (xy 224.849084 -221.784787) (xy 224.795127 -221.798893) (xy 224.73969 -221.804993)
			(xy 224.683956 -221.802956) (xy 224.629113 -221.792826) (xy 224.576329 -221.774819) (xy 224.526729 -221.749318)
			(xy 224.481371 -221.716867) (xy 224.441222 -221.678158) (xy 224.407136 -221.634015) (xy 224.37984 -221.58538)
			(xy 224.359917 -221.533289) (xy 224.347791 -221.478852) (xy 224.34372 -221.42323) (xy 219.5576 -221.42323)
			(xy 219.5576 -222.69704) (xy 222.6691 -222.69704) (xy 222.669586 -222.669789) (xy 222.677342 -222.615841)
			(xy 222.692697 -222.563546) (xy 222.715339 -222.513969) (xy 222.744805 -222.468119) (xy 222.780496 -222.426928)
			(xy 222.821687 -222.391237) (xy 222.867537 -222.361771) (xy 222.917114 -222.339129) (xy 222.969409 -222.323774)
			(xy 223.023357 -222.316018) (xy 223.077859 -222.316018) (xy 223.131807 -222.323774) (xy 223.184102 -222.339129)
			(xy 223.233679 -222.361771) (xy 223.279529 -222.391237) (xy 223.32072 -222.426928) (xy 223.356411 -222.468119)
			(xy 223.385877 -222.513969) (xy 223.408519 -222.563546) (xy 223.423874 -222.615841) (xy 223.43163 -222.669789)
			(xy 223.432116 -222.69704) (xy 223.431635 -222.72329) (xy 223.424456 -222.775296) (xy 223.41021 -222.825826)
			(xy 223.389168 -222.873925) (xy 223.361727 -222.918682) (xy 223.328407 -222.959252) (xy 223.289836 -222.994868)
			(xy 223.26854 -223.010222) (xy 223.257104 -223.018661) (xy 223.239127 -223.040666) (xy 223.227903 -223.066769)
			(xy 223.224299 -223.094953) (xy 223.228593 -223.123041) (xy 223.240454 -223.148861) (xy 223.258965 -223.170418)
			(xy 223.270572 -223.178624) (xy 223.292795 -223.193862) (xy 223.333191 -223.229516) (xy 223.368166 -223.270502)
			(xy 223.397022 -223.316004) (xy 223.419185 -223.365115) (xy 223.434213 -223.416857) (xy 223.441807 -223.4702)
			(xy 223.442276 -223.49714) (xy 223.44179 -223.524391) (xy 223.434034 -223.578339) (xy 223.418679 -223.630634)
			(xy 223.396037 -223.680211) (xy 223.366571 -223.726061) (xy 223.33088 -223.767252) (xy 223.289689 -223.802943)
			(xy 223.243839 -223.832409) (xy 223.194262 -223.855051) (xy 223.141967 -223.870406) (xy 223.088019 -223.878162)
			(xy 223.033517 -223.878162) (xy 222.979569 -223.870406) (xy 222.927274 -223.855051) (xy 222.877697 -223.832409)
			(xy 222.831847 -223.802943) (xy 222.790656 -223.767252) (xy 222.754965 -223.726061) (xy 222.725499 -223.680211)
			(xy 222.702857 -223.630634) (xy 222.687502 -223.578339) (xy 222.679746 -223.524391) (xy 222.67926 -223.49714)
			(xy 222.679693 -223.470888) (xy 222.686877 -223.418878) (xy 222.701128 -223.368346) (xy 222.722178 -223.320246)
			(xy 222.749626 -223.275489) (xy 222.782956 -223.234921) (xy 222.821536 -223.199309) (xy 222.842836 -223.183958)
			(xy 222.854185 -223.175415) (xy 222.872146 -223.15343) (xy 222.883365 -223.127351) (xy 222.886976 -223.099192)
			(xy 222.882701 -223.071127) (xy 222.870868 -223.045321) (xy 222.852393 -223.023766) (xy 222.840804 -223.015556)
			(xy 222.818567 -223.000339) (xy 222.778171 -222.964681) (xy 222.743198 -222.92369) (xy 222.714344 -222.878185)
			(xy 222.692184 -222.829071) (xy 222.677159 -222.777326) (xy 222.669568 -222.723981) (xy 222.6691 -222.69704)
			(xy 219.5576 -222.69704) (xy 219.5576 -226.54133) (xy 227.455982 -226.54133) (xy 227.460053 -226.485708)
			(xy 227.472179 -226.431271) (xy 227.492102 -226.37918) (xy 227.519398 -226.330545) (xy 227.553484 -226.286402)
			(xy 227.593633 -226.247693) (xy 227.638991 -226.215242) (xy 227.688591 -226.189741) (xy 227.741375 -226.171734)
			(xy 227.796218 -226.161604) (xy 227.851952 -226.159567) (xy 227.907389 -226.165667) (xy 227.961346 -226.179773)
			(xy 228.012675 -226.201585) (xy 228.060281 -226.230639) (xy 228.103149 -226.266314) (xy 228.140366 -226.307851)
			(xy 228.171139 -226.354364) (xy 228.194811 -226.404861) (xy 228.210879 -226.458268) (xy 228.218999 -226.513444)
			(xy 228.219508 -226.54133) (xy 228.218999 -226.569216) (xy 228.210879 -226.624392) (xy 228.194811 -226.677799)
			(xy 228.171139 -226.728296) (xy 228.140366 -226.774809) (xy 228.103149 -226.816346) (xy 228.060281 -226.852021)
			(xy 228.012675 -226.881075) (xy 227.961346 -226.902887) (xy 227.907389 -226.916993) (xy 227.851952 -226.923093)
			(xy 227.796218 -226.921056) (xy 227.741375 -226.910926) (xy 227.688591 -226.892919) (xy 227.638991 -226.867418)
			(xy 227.593633 -226.834967) (xy 227.553484 -226.796258) (xy 227.519398 -226.752115) (xy 227.492102 -226.70348)
			(xy 227.472179 -226.651389) (xy 227.460053 -226.596952) (xy 227.455982 -226.54133) (xy 219.5576 -226.54133)
			(xy 219.5576 -232.785158) (xy 224.311208 -232.785158) (xy 224.315279 -232.729536) (xy 224.327405 -232.675099)
			(xy 224.347328 -232.623008) (xy 224.374624 -232.574373) (xy 224.40871 -232.53023) (xy 224.448859 -232.491521)
			(xy 224.494217 -232.45907) (xy 224.543817 -232.433569) (xy 224.596601 -232.415562) (xy 224.651444 -232.405432)
			(xy 224.707178 -232.403395) (xy 224.762615 -232.409495) (xy 224.816572 -232.423601) (xy 224.867901 -232.445413)
			(xy 224.915507 -232.474467) (xy 224.958375 -232.510142) (xy 224.995592 -232.551679) (xy 225.026365 -232.598192)
			(xy 225.050037 -232.648689) (xy 225.053063 -232.658746) (xy 226.267442 -232.658746) (xy 226.267443 -232.604238)
			(xy 226.275202 -232.550284) (xy 226.29056 -232.497984) (xy 226.313205 -232.448402) (xy 226.342676 -232.402548)
			(xy 226.378373 -232.361354) (xy 226.419569 -232.32566) (xy 226.465425 -232.296193) (xy 226.515009 -232.273551)
			(xy 226.56731 -232.258197) (xy 226.621264 -232.250442) (xy 226.648518 -232.24998) (xy 226.684078 -232.251758)
			(xy 226.699488 -232.252723) (xy 226.729686 -232.246341) (xy 226.756601 -232.231233) (xy 226.777778 -232.208779)
			(xy 226.791284 -232.181025) (xy 226.795887 -232.150505) (xy 226.79406 -232.135172) (xy 226.792026 -232.120908)
			(xy 226.789864 -232.092175) (xy 226.789742 -232.077768) (xy 226.79029 -232.050517) (xy 226.798051 -231.996571)
			(xy 226.81341 -231.944278) (xy 226.836055 -231.894704) (xy 226.865525 -231.848857) (xy 226.90122 -231.80767)
			(xy 226.942413 -231.771983) (xy 226.988265 -231.742522) (xy 227.037844 -231.719886) (xy 227.090139 -231.704536)
			(xy 227.144087 -231.696785) (xy 227.198589 -231.69679) (xy 227.252535 -231.704552) (xy 227.304827 -231.719912)
			(xy 227.354401 -231.742558) (xy 227.400248 -231.772029) (xy 227.441434 -231.807724) (xy 227.47712 -231.848918)
			(xy 227.506581 -231.894771) (xy 227.529217 -231.94435) (xy 227.544566 -231.996645) (xy 227.552316 -232.050593)
			(xy 227.55231 -232.105095) (xy 227.544547 -232.159041) (xy 227.529186 -232.211333) (xy 227.506539 -232.260907)
			(xy 227.477068 -232.306753) (xy 227.441372 -232.347938) (xy 227.400178 -232.383624) (xy 227.354324 -232.413084)
			(xy 227.304745 -232.435719) (xy 227.252449 -232.451067) (xy 227.198501 -232.458816) (xy 227.17125 -232.459276)
			(xy 227.13569 -232.457498) (xy 227.120281 -232.456554) (xy 227.090091 -232.462941) (xy 227.063183 -232.478048)
			(xy 227.042009 -232.500496) (xy 227.028501 -232.528241) (xy 227.023888 -232.558753) (xy 227.025708 -232.574084)
			(xy 227.027748 -232.588347) (xy 227.029906 -232.617081) (xy 227.030026 -232.631488) (xy 227.029558 -232.658742)
			(xy 227.021802 -232.712696) (xy 227.006447 -232.764997) (xy 226.983804 -232.81458) (xy 226.954336 -232.860436)
			(xy 226.918641 -232.901631) (xy 226.877447 -232.937328) (xy 226.831592 -232.966798) (xy 226.78201 -232.989442)
			(xy 226.72971 -233.004799) (xy 226.675756 -233.012557) (xy 226.621248 -233.012557) (xy 226.567294 -233.0048)
			(xy 226.514994 -232.989443) (xy 226.465411 -232.9668) (xy 226.419556 -232.93733) (xy 226.378362 -232.901634)
			(xy 226.342666 -232.860439) (xy 226.313198 -232.814583) (xy 226.290555 -232.765001) (xy 226.275199 -232.7127)
			(xy 226.267442 -232.658746) (xy 225.053063 -232.658746) (xy 225.066105 -232.702096) (xy 225.074225 -232.757272)
			(xy 225.074734 -232.785158) (xy 225.074225 -232.813044) (xy 225.066105 -232.86822) (xy 225.050037 -232.921627)
			(xy 225.026365 -232.972124) (xy 224.995592 -233.018637) (xy 224.958375 -233.060174) (xy 224.915507 -233.095849)
			(xy 224.867901 -233.124903) (xy 224.816572 -233.146715) (xy 224.762615 -233.160821) (xy 224.707178 -233.166921)
			(xy 224.651444 -233.164884) (xy 224.596601 -233.154754) (xy 224.543817 -233.136747) (xy 224.494217 -233.111246)
			(xy 224.448859 -233.078795) (xy 224.40871 -233.040086) (xy 224.374624 -232.995943) (xy 224.347328 -232.947308)
			(xy 224.327405 -232.895217) (xy 224.315279 -232.84078) (xy 224.311208 -232.785158) (xy 219.5576 -232.785158)
			(xy 219.5576 -233.84637) (xy 223.48647 -233.84637) (xy 223.490541 -233.790748) (xy 223.502667 -233.736311)
			(xy 223.52259 -233.68422) (xy 223.549886 -233.635585) (xy 223.583972 -233.591442) (xy 223.624121 -233.552733)
			(xy 223.669479 -233.520282) (xy 223.719079 -233.494781) (xy 223.771863 -233.476774) (xy 223.826706 -233.466644)
			(xy 223.88244 -233.464607) (xy 223.937877 -233.470707) (xy 223.991834 -233.484813) (xy 224.043163 -233.506625)
			(xy 224.090769 -233.535679) (xy 224.133637 -233.571354) (xy 224.170854 -233.612891) (xy 224.201627 -233.659404)
			(xy 224.225299 -233.709901) (xy 224.241367 -233.763308) (xy 224.249487 -233.818484) (xy 224.249996 -233.84637)
			(xy 224.249487 -233.874256) (xy 224.241367 -233.929432) (xy 224.225299 -233.982839) (xy 224.201627 -234.033336)
			(xy 224.170854 -234.079849) (xy 224.133637 -234.121386) (xy 224.090769 -234.157061) (xy 224.043163 -234.186115)
			(xy 223.991834 -234.207927) (xy 223.937877 -234.222033) (xy 223.88244 -234.228133) (xy 223.826706 -234.226096)
			(xy 223.771863 -234.215966) (xy 223.719079 -234.197959) (xy 223.669479 -234.172458) (xy 223.624121 -234.140007)
			(xy 223.583972 -234.101298) (xy 223.549886 -234.057155) (xy 223.52259 -234.00852) (xy 223.502667 -233.956429)
			(xy 223.490541 -233.901992) (xy 223.48647 -233.84637) (xy 219.5576 -233.84637) (xy 219.5576 -244.375432)
			(xy 232.529378 -244.375432) (xy 232.533449 -244.31981) (xy 232.545575 -244.265373) (xy 232.565498 -244.213282)
			(xy 232.592794 -244.164647) (xy 232.62688 -244.120504) (xy 232.667029 -244.081795) (xy 232.712387 -244.049344)
			(xy 232.761987 -244.023843) (xy 232.814771 -244.005836) (xy 232.869614 -243.995706) (xy 232.925348 -243.993669)
			(xy 232.980785 -243.999769) (xy 233.034742 -244.013875) (xy 233.086071 -244.035687) (xy 233.133677 -244.064741)
			(xy 233.176545 -244.100416) (xy 233.213762 -244.141953) (xy 233.244535 -244.188466) (xy 233.268207 -244.238963)
			(xy 233.284275 -244.29237) (xy 233.292395 -244.347546) (xy 233.292783 -244.368828) (xy 236.217966 -244.368828)
			(xy 236.222037 -244.313206) (xy 236.234163 -244.258769) (xy 236.254086 -244.206678) (xy 236.281382 -244.158043)
			(xy 236.315468 -244.1139) (xy 236.355617 -244.075191) (xy 236.400975 -244.04274) (xy 236.450575 -244.017239)
			(xy 236.503359 -243.999232) (xy 236.558202 -243.989102) (xy 236.613936 -243.987065) (xy 236.669373 -243.993165)
			(xy 236.72333 -244.007271) (xy 236.774659 -244.029083) (xy 236.822265 -244.058137) (xy 236.865133 -244.093812)
			(xy 236.90235 -244.135349) (xy 236.933123 -244.181862) (xy 236.956795 -244.232359) (xy 236.972863 -244.285766)
			(xy 236.980983 -244.340942) (xy 236.981492 -244.368828) (xy 236.980983 -244.396714) (xy 236.972863 -244.45189)
			(xy 236.956795 -244.505297) (xy 236.933123 -244.555794) (xy 236.90235 -244.602307) (xy 236.865133 -244.643844)
			(xy 236.822265 -244.679519) (xy 236.774659 -244.708573) (xy 236.72333 -244.730385) (xy 236.669373 -244.744491)
			(xy 236.613936 -244.750591) (xy 236.558202 -244.748554) (xy 236.503359 -244.738424) (xy 236.450575 -244.720417)
			(xy 236.400975 -244.694916) (xy 236.355617 -244.662465) (xy 236.315468 -244.623756) (xy 236.281382 -244.579613)
			(xy 236.254086 -244.530978) (xy 236.234163 -244.478887) (xy 236.222037 -244.42445) (xy 236.217966 -244.368828)
			(xy 233.292783 -244.368828) (xy 233.292904 -244.375432) (xy 233.292395 -244.403318) (xy 233.284275 -244.458494)
			(xy 233.268207 -244.511901) (xy 233.244535 -244.562398) (xy 233.213762 -244.608911) (xy 233.176545 -244.650448)
			(xy 233.133677 -244.686123) (xy 233.086071 -244.715177) (xy 233.034742 -244.736989) (xy 232.980785 -244.751095)
			(xy 232.925348 -244.757195) (xy 232.869614 -244.755158) (xy 232.814771 -244.745028) (xy 232.761987 -244.727021)
			(xy 232.712387 -244.70152) (xy 232.667029 -244.669069) (xy 232.62688 -244.63036) (xy 232.592794 -244.586217)
			(xy 232.565498 -244.537582) (xy 232.545575 -244.485491) (xy 232.533449 -244.431054) (xy 232.529378 -244.375432)
			(xy 219.5576 -244.375432) (xy 219.5576 -246.335158) (xy 227.726619 -246.335158) (xy 227.726619 -246.280642)
			(xy 227.734378 -246.226682) (xy 227.749738 -246.174375) (xy 227.772386 -246.124787) (xy 227.801861 -246.078928)
			(xy 227.837564 -246.03773) (xy 227.878766 -246.002033) (xy 227.92463 -245.972563) (xy 227.97422 -245.949921)
			(xy 228.026529 -245.934568) (xy 228.08049 -245.926816) (xy 228.107748 -245.926356) (xy 228.136409 -245.926886)
			(xy 228.193081 -245.935496) (xy 228.247829 -245.952485) (xy 228.29942 -245.97747) (xy 228.346694 -246.00989)
			(xy 228.388588 -246.049015) (xy 228.424159 -246.093966) (xy 228.452608 -246.143731) (xy 228.473294 -246.197192)
			(xy 228.485752 -246.253144) (xy 228.48824 -246.281702) (xy 228.489681 -246.296254) (xy 228.499842 -246.323664)
			(xy 228.517347 -246.347075) (xy 228.540765 -246.364573) (xy 228.568177 -246.374726) (xy 228.582728 -246.37619)
			(xy 228.611319 -246.37862) (xy 228.667336 -246.391048) (xy 228.72086 -246.411725) (xy 228.770684 -246.440184)
			(xy 228.815685 -246.475783) (xy 228.854848 -246.517719) (xy 228.887289 -246.565047) (xy 228.912277 -246.616699)
			(xy 228.929249 -246.671511) (xy 228.937821 -246.728246) (xy 228.938328 -246.756936) (xy 228.938328 -247.620536)
			(xy 228.938041 -247.637808) (xy 232.784902 -247.637808) (xy 232.788973 -247.582186) (xy 232.801099 -247.527749)
			(xy 232.821022 -247.475658) (xy 232.848318 -247.427023) (xy 232.882404 -247.38288) (xy 232.922553 -247.344171)
			(xy 232.967911 -247.31172) (xy 233.017511 -247.286219) (xy 233.070295 -247.268212) (xy 233.125138 -247.258082)
			(xy 233.180872 -247.256045) (xy 233.236309 -247.262145) (xy 233.290266 -247.276251) (xy 233.341595 -247.298063)
			(xy 233.389201 -247.327117) (xy 233.432069 -247.362792) (xy 233.469286 -247.404329) (xy 233.500059 -247.450842)
			(xy 233.523731 -247.501339) (xy 233.539799 -247.554746) (xy 233.547919 -247.609922) (xy 233.548428 -247.637808)
			(xy 233.547919 -247.665694) (xy 233.539799 -247.72087) (xy 233.523731 -247.774277) (xy 233.500059 -247.824774)
			(xy 233.469286 -247.871287) (xy 233.432069 -247.912824) (xy 233.389201 -247.948499) (xy 233.341595 -247.977553)
			(xy 233.290266 -247.999365) (xy 233.236309 -248.013471) (xy 233.180872 -248.019571) (xy 233.125138 -248.017534)
			(xy 233.070295 -248.007404) (xy 233.017511 -247.989397) (xy 232.967911 -247.963896) (xy 232.922553 -247.931445)
			(xy 232.882404 -247.892736) (xy 232.848318 -247.848593) (xy 232.821022 -247.799958) (xy 232.801099 -247.747867)
			(xy 232.788973 -247.69343) (xy 232.784902 -247.637808) (xy 228.938041 -247.637808) (xy 228.937851 -247.64922)
			(xy 228.929235 -247.705937) (xy 228.912231 -247.760728) (xy 228.887224 -247.812358) (xy 228.854775 -247.859668)
			(xy 228.815614 -247.901591) (xy 228.770623 -247.937185) (xy 228.720815 -247.965648) (xy 228.667308 -247.986341)
			(xy 228.611309 -247.998798) (xy 228.582728 -248.001282) (xy 228.568173 -248.002709) (xy 228.540758 -248.012868)
			(xy 228.517344 -248.030376) (xy 228.499846 -248.053798) (xy 228.493995 -248.069608) (xy 234.296202 -248.069608)
			(xy 234.300273 -248.013986) (xy 234.312399 -247.959549) (xy 234.332322 -247.907458) (xy 234.359618 -247.858823)
			(xy 234.393704 -247.81468) (xy 234.433853 -247.775971) (xy 234.479211 -247.74352) (xy 234.528811 -247.718019)
			(xy 234.581595 -247.700012) (xy 234.636438 -247.689882) (xy 234.692172 -247.687845) (xy 234.747609 -247.693945)
			(xy 234.801566 -247.708051) (xy 234.852895 -247.729863) (xy 234.900501 -247.758917) (xy 234.943369 -247.794592)
			(xy 234.980586 -247.836129) (xy 235.011359 -247.882642) (xy 235.035031 -247.933139) (xy 235.051099 -247.986546)
			(xy 235.059219 -248.041722) (xy 235.059728 -248.069608) (xy 235.059219 -248.097494) (xy 235.051099 -248.15267)
			(xy 235.035031 -248.206077) (xy 235.011359 -248.256574) (xy 234.980586 -248.303087) (xy 234.943369 -248.344624)
			(xy 234.900501 -248.380299) (xy 234.852895 -248.409353) (xy 234.801566 -248.431165) (xy 234.747609 -248.445271)
			(xy 234.692172 -248.451371) (xy 234.636438 -248.449334) (xy 234.581595 -248.439204) (xy 234.528811 -248.421197)
			(xy 234.479211 -248.395696) (xy 234.433853 -248.363245) (xy 234.393704 -248.324536) (xy 234.359618 -248.280393)
			(xy 234.332322 -248.231758) (xy 234.312399 -248.179667) (xy 234.300273 -248.12523) (xy 234.296202 -248.069608)
			(xy 228.493995 -248.069608) (xy 228.489699 -248.081217) (xy 228.48824 -248.09577) (xy 228.485763 -248.124334)
			(xy 228.473339 -248.180306) (xy 228.452675 -248.233786) (xy 228.424237 -248.28357) (xy 228.388667 -248.328535)
			(xy 228.346765 -248.367668) (xy 228.299478 -248.400087) (xy 228.247869 -248.425061) (xy 228.193103 -248.442028)
			(xy 228.136415 -248.450603) (xy 228.107748 -248.451116) (xy 228.080493 -248.45064) (xy 228.026538 -248.442889)
			(xy 227.974236 -248.427537) (xy 227.924651 -248.404898) (xy 227.878793 -248.375432) (xy 227.837595 -248.339739)
			(xy 227.801897 -248.298546) (xy 227.772425 -248.252691) (xy 227.74978 -248.203109) (xy 227.734422 -248.150808)
			(xy 227.726663 -248.096854) (xy 227.726663 -248.042346) (xy 227.734422 -247.988392) (xy 227.74978 -247.936091)
			(xy 227.772425 -247.886509) (xy 227.801897 -247.840654) (xy 227.837595 -247.799461) (xy 227.878793 -247.763768)
			(xy 227.924651 -247.734302) (xy 227.974236 -247.711663) (xy 228.026538 -247.696311) (xy 228.080493 -247.68856)
			(xy 228.107748 -247.6881) (xy 228.122734 -247.688354) (xy 228.133282 -247.688271) (xy 228.152911 -247.680603)
			(xy 228.16781 -247.665701) (xy 228.175473 -247.646071) (xy 228.175566 -247.635522) (xy 228.175312 -247.620536)
			(xy 228.175312 -246.756936) (xy 228.175566 -246.74195) (xy 228.175484 -246.731402) (xy 228.167813 -246.711776)
			(xy 228.152911 -246.696878) (xy 228.133283 -246.689213) (xy 228.122734 -246.689118) (xy 228.107748 -246.689372)
			(xy 228.08049 -246.688984) (xy 228.026529 -246.681232) (xy 227.97422 -246.665879) (xy 227.92463 -246.643237)
			(xy 227.878766 -246.613767) (xy 227.837564 -246.57807) (xy 227.801861 -246.536872) (xy 227.772386 -246.491013)
			(xy 227.749738 -246.441425) (xy 227.734378 -246.389118) (xy 227.726619 -246.335158) (xy 219.5576 -246.335158)
			(xy 219.5576 -249.765058) (xy 234.162344 -249.765058) (xy 234.166415 -249.709436) (xy 234.178541 -249.654999)
			(xy 234.198464 -249.602908) (xy 234.22576 -249.554273) (xy 234.259846 -249.51013) (xy 234.299995 -249.471421)
			(xy 234.345353 -249.43897) (xy 234.394953 -249.413469) (xy 234.447737 -249.395462) (xy 234.50258 -249.385332)
			(xy 234.558314 -249.383295) (xy 234.613751 -249.389395) (xy 234.667708 -249.403501) (xy 234.719037 -249.425313)
			(xy 234.766643 -249.454367) (xy 234.809511 -249.490042) (xy 234.846728 -249.531579) (xy 234.877501 -249.578092)
			(xy 234.901173 -249.628589) (xy 234.917241 -249.681996) (xy 234.925361 -249.737172) (xy 234.925736 -249.757692)
			(xy 235.897164 -249.757692) (xy 235.901235 -249.70207) (xy 235.913361 -249.647633) (xy 235.933284 -249.595542)
			(xy 235.96058 -249.546907) (xy 235.994666 -249.502764) (xy 236.034815 -249.464055) (xy 236.080173 -249.431604)
			(xy 236.129773 -249.406103) (xy 236.182557 -249.388096) (xy 236.2374 -249.377966) (xy 236.293134 -249.375929)
			(xy 236.348571 -249.382029) (xy 236.402528 -249.396135) (xy 236.453857 -249.417947) (xy 236.501463 -249.447001)
			(xy 236.544331 -249.482676) (xy 236.581548 -249.524213) (xy 236.612321 -249.570726) (xy 236.635993 -249.621223)
			(xy 236.652061 -249.67463) (xy 236.660181 -249.729806) (xy 236.66069 -249.757692) (xy 236.660181 -249.785578)
			(xy 236.652061 -249.840754) (xy 236.635993 -249.894161) (xy 236.612321 -249.944658) (xy 236.581548 -249.991171)
			(xy 236.544331 -250.032708) (xy 236.501463 -250.068383) (xy 236.453857 -250.097437) (xy 236.402528 -250.119249)
			(xy 236.348571 -250.133355) (xy 236.293134 -250.139455) (xy 236.2374 -250.137418) (xy 236.182557 -250.127288)
			(xy 236.129773 -250.109281) (xy 236.080173 -250.08378) (xy 236.034815 -250.051329) (xy 235.994666 -250.01262)
			(xy 235.96058 -249.968477) (xy 235.933284 -249.919842) (xy 235.913361 -249.867751) (xy 235.901235 -249.813314)
			(xy 235.897164 -249.757692) (xy 234.925736 -249.757692) (xy 234.92587 -249.765058) (xy 234.925361 -249.792944)
			(xy 234.917241 -249.84812) (xy 234.901173 -249.901527) (xy 234.877501 -249.952024) (xy 234.846728 -249.998537)
			(xy 234.809511 -250.040074) (xy 234.766643 -250.075749) (xy 234.719037 -250.104803) (xy 234.667708 -250.126615)
			(xy 234.613751 -250.140721) (xy 234.558314 -250.146821) (xy 234.50258 -250.144784) (xy 234.447737 -250.134654)
			(xy 234.394953 -250.116647) (xy 234.345353 -250.091146) (xy 234.299995 -250.058695) (xy 234.259846 -250.019986)
			(xy 234.22576 -249.975843) (xy 234.198464 -249.927208) (xy 234.178541 -249.875117) (xy 234.166415 -249.82068)
			(xy 234.162344 -249.765058) (xy 219.5576 -249.765058) (xy 219.5576 -250.441206) (xy 231.986834 -250.441206)
			(xy 231.990905 -250.385584) (xy 232.003031 -250.331147) (xy 232.022954 -250.279056) (xy 232.05025 -250.230421)
			(xy 232.084336 -250.186278) (xy 232.124485 -250.147569) (xy 232.169843 -250.115118) (xy 232.219443 -250.089617)
			(xy 232.272227 -250.07161) (xy 232.32707 -250.06148) (xy 232.382804 -250.059443) (xy 232.438241 -250.065543)
			(xy 232.492198 -250.079649) (xy 232.543527 -250.101461) (xy 232.591133 -250.130515) (xy 232.634001 -250.16619)
			(xy 232.671218 -250.207727) (xy 232.701991 -250.25424) (xy 232.725663 -250.304737) (xy 232.741731 -250.358144)
			(xy 232.749031 -250.407745) (xy 237.616485 -250.407745) (xy 237.616486 -250.353244) (xy 237.624243 -250.299298)
			(xy 237.639599 -250.247005) (xy 237.66224 -250.197429) (xy 237.691706 -250.15158) (xy 237.727397 -250.110391)
			(xy 237.768586 -250.074701) (xy 237.814436 -250.045236) (xy 237.864012 -250.022596) (xy 237.916306 -250.007241)
			(xy 237.970252 -249.999486) (xy 238.024753 -249.999486) (xy 238.0787 -250.007243) (xy 238.130993 -250.022598)
			(xy 238.180569 -250.045238) (xy 238.226418 -250.074704) (xy 238.267607 -250.110395) (xy 238.303297 -250.151584)
			(xy 238.332763 -250.197434) (xy 238.355403 -250.24701) (xy 238.370758 -250.299303) (xy 238.378514 -250.353249)
			(xy 238.379 -250.3805) (xy 238.378846 -250.396579) (xy 238.376177 -250.428626) (xy 238.373666 -250.444508)
			(xy 238.371718 -250.458448) (xy 238.374735 -250.486424) (xy 238.385279 -250.512513) (xy 238.402549 -250.534728)
			(xy 238.425229 -250.551382) (xy 238.451597 -250.561208) (xy 238.479645 -250.563457) (xy 238.507241 -250.55796)
			(xy 238.51997 -250.55195) (xy 238.54704 -250.538714) (xy 238.604321 -250.520021) (xy 238.663832 -250.510585)
			(xy 238.69396 -250.51004) (xy 238.721214 -250.510435) (xy 238.775168 -250.518187) (xy 238.82747 -250.533538)
			(xy 238.877054 -250.556176) (xy 238.922912 -250.58564) (xy 238.964111 -250.621331) (xy 238.99981 -250.662521)
			(xy 239.029284 -250.708373) (xy 239.051933 -250.757953) (xy 239.067296 -250.810251) (xy 239.075059 -250.864203)
			(xy 239.075065 -250.918711) (xy 239.067314 -250.972665) (xy 239.051963 -251.024967) (xy 239.029325 -251.074552)
			(xy 238.999861 -251.12041) (xy 238.964171 -251.161609) (xy 238.922981 -251.197309) (xy 238.877129 -251.226783)
			(xy 238.82755 -251.249432) (xy 238.775251 -251.264795) (xy 238.721299 -251.272559) (xy 238.666791 -251.272565)
			(xy 238.612837 -251.264815) (xy 238.560535 -251.249464) (xy 238.51095 -251.226827) (xy 238.465092 -251.197363)
			(xy 238.423893 -251.161673) (xy 238.388193 -251.120483) (xy 238.358718 -251.074632) (xy 238.336069 -251.025052)
			(xy 238.320705 -250.972754) (xy 238.312941 -250.918802) (xy 238.312452 -250.891548) (xy 238.3126 -250.875469)
			(xy 238.315274 -250.843422) (xy 238.317786 -250.82754) (xy 238.319706 -250.8136) (xy 238.316678 -250.785635)
			(xy 238.30613 -250.759559) (xy 238.288865 -250.737353) (xy 238.266193 -250.720704) (xy 238.239837 -250.710876)
			(xy 238.2118 -250.708617) (xy 238.18421 -250.714098) (xy 238.171482 -250.720098) (xy 238.144418 -250.733347)
			(xy 238.087134 -250.752037) (xy 238.027621 -250.761467) (xy 237.997492 -250.762008) (xy 237.970241 -250.761514)
			(xy 237.916295 -250.753756) (xy 237.864002 -250.7384) (xy 237.814427 -250.715759) (xy 237.768578 -250.686293)
			(xy 237.727389 -250.650601) (xy 237.691699 -250.609411) (xy 237.662235 -250.563562) (xy 237.639595 -250.513985)
			(xy 237.624241 -250.461692) (xy 237.616485 -250.407745) (xy 232.749031 -250.407745) (xy 232.749851 -250.41332)
			(xy 232.75036 -250.441206) (xy 232.749851 -250.469092) (xy 232.741731 -250.524268) (xy 232.725663 -250.577675)
			(xy 232.701991 -250.628172) (xy 232.671218 -250.674685) (xy 232.634001 -250.716222) (xy 232.591133 -250.751897)
			(xy 232.543527 -250.780951) (xy 232.492198 -250.802763) (xy 232.438241 -250.816869) (xy 232.382804 -250.822969)
			(xy 232.32707 -250.820932) (xy 232.272227 -250.810802) (xy 232.219443 -250.792795) (xy 232.169843 -250.767294)
			(xy 232.124485 -250.734843) (xy 232.084336 -250.696134) (xy 232.05025 -250.651991) (xy 232.022954 -250.603356)
			(xy 232.003031 -250.551265) (xy 231.990905 -250.496828) (xy 231.986834 -250.441206) (xy 219.5576 -250.441206)
			(xy 219.5576 -251.517658) (xy 234.14177 -251.517658) (xy 234.145841 -251.462036) (xy 234.157967 -251.407599)
			(xy 234.17789 -251.355508) (xy 234.205186 -251.306873) (xy 234.239272 -251.26273) (xy 234.279421 -251.224021)
			(xy 234.324779 -251.19157) (xy 234.374379 -251.166069) (xy 234.427163 -251.148062) (xy 234.482006 -251.137932)
			(xy 234.53774 -251.135895) (xy 234.593177 -251.141995) (xy 234.647134 -251.156101) (xy 234.698463 -251.177913)
			(xy 234.746069 -251.206967) (xy 234.788937 -251.242642) (xy 234.826154 -251.284179) (xy 234.856927 -251.330692)
			(xy 234.880599 -251.381189) (xy 234.896667 -251.434596) (xy 234.904787 -251.489772) (xy 234.905296 -251.517658)
			(xy 234.90525 -251.520198) (xy 235.907578 -251.520198) (xy 235.911649 -251.464576) (xy 235.923775 -251.410139)
			(xy 235.943698 -251.358048) (xy 235.970994 -251.309413) (xy 236.00508 -251.26527) (xy 236.045229 -251.226561)
			(xy 236.090587 -251.19411) (xy 236.140187 -251.168609) (xy 236.192971 -251.150602) (xy 236.247814 -251.140472)
			(xy 236.303548 -251.138435) (xy 236.358985 -251.144535) (xy 236.412942 -251.158641) (xy 236.464271 -251.180453)
			(xy 236.511877 -251.209507) (xy 236.554745 -251.245182) (xy 236.591962 -251.286719) (xy 236.622735 -251.333232)
			(xy 236.646407 -251.383729) (xy 236.662475 -251.437136) (xy 236.670595 -251.492312) (xy 236.671104 -251.520198)
			(xy 236.670595 -251.548084) (xy 236.662475 -251.60326) (xy 236.646407 -251.656667) (xy 236.622735 -251.707164)
			(xy 236.591962 -251.753677) (xy 236.554745 -251.795214) (xy 236.511877 -251.830889) (xy 236.464271 -251.859943)
			(xy 236.412942 -251.881755) (xy 236.358985 -251.895861) (xy 236.303548 -251.901961) (xy 236.247814 -251.899924)
			(xy 236.192971 -251.889794) (xy 236.140187 -251.871787) (xy 236.090587 -251.846286) (xy 236.045229 -251.813835)
			(xy 236.00508 -251.775126) (xy 235.970994 -251.730983) (xy 235.943698 -251.682348) (xy 235.923775 -251.630257)
			(xy 235.911649 -251.57582) (xy 235.907578 -251.520198) (xy 234.90525 -251.520198) (xy 234.904787 -251.545544)
			(xy 234.896667 -251.60072) (xy 234.880599 -251.654127) (xy 234.856927 -251.704624) (xy 234.826154 -251.751137)
			(xy 234.788937 -251.792674) (xy 234.746069 -251.828349) (xy 234.698463 -251.857403) (xy 234.647134 -251.879215)
			(xy 234.593177 -251.893321) (xy 234.53774 -251.899421) (xy 234.482006 -251.897384) (xy 234.427163 -251.887254)
			(xy 234.374379 -251.869247) (xy 234.324779 -251.843746) (xy 234.279421 -251.811295) (xy 234.239272 -251.772586)
			(xy 234.205186 -251.728443) (xy 234.17789 -251.679808) (xy 234.157967 -251.627717) (xy 234.145841 -251.57328)
			(xy 234.14177 -251.517658) (xy 219.5576 -251.517658) (xy 219.5576 -253.200408) (xy 234.425742 -253.200408)
			(xy 234.429813 -253.144786) (xy 234.441939 -253.090349) (xy 234.461862 -253.038258) (xy 234.489158 -252.989623)
			(xy 234.523244 -252.94548) (xy 234.563393 -252.906771) (xy 234.608751 -252.87432) (xy 234.658351 -252.848819)
			(xy 234.711135 -252.830812) (xy 234.765978 -252.820682) (xy 234.821712 -252.818645) (xy 234.877149 -252.824745)
			(xy 234.931106 -252.838851) (xy 234.982435 -252.860663) (xy 235.030041 -252.889717) (xy 235.072909 -252.925392)
			(xy 235.110126 -252.966929) (xy 235.140899 -253.013442) (xy 235.164571 -253.063939) (xy 235.180639 -253.117346)
			(xy 235.188759 -253.172522) (xy 235.189083 -253.190248) (xy 236.424722 -253.190248) (xy 236.428793 -253.134626)
			(xy 236.440919 -253.080189) (xy 236.460842 -253.028098) (xy 236.488138 -252.979463) (xy 236.522224 -252.93532)
			(xy 236.562373 -252.896611) (xy 236.607731 -252.86416) (xy 236.657331 -252.838659) (xy 236.710115 -252.820652)
			(xy 236.764958 -252.810522) (xy 236.820692 -252.808485) (xy 236.876129 -252.814585) (xy 236.930086 -252.828691)
			(xy 236.981415 -252.850503) (xy 237.029021 -252.879557) (xy 237.071889 -252.915232) (xy 237.109106 -252.956769)
			(xy 237.139879 -253.003282) (xy 237.163551 -253.053779) (xy 237.179619 -253.107186) (xy 237.187739 -253.162362)
			(xy 237.188248 -253.190248) (xy 237.187739 -253.218134) (xy 237.179619 -253.27331) (xy 237.163551 -253.326717)
			(xy 237.139879 -253.377214) (xy 237.109106 -253.423727) (xy 237.071889 -253.465264) (xy 237.029021 -253.500939)
			(xy 236.981415 -253.529993) (xy 236.930086 -253.551805) (xy 236.876129 -253.565911) (xy 236.820692 -253.572011)
			(xy 236.764958 -253.569974) (xy 236.710115 -253.559844) (xy 236.657331 -253.541837) (xy 236.607731 -253.516336)
			(xy 236.562373 -253.483885) (xy 236.522224 -253.445176) (xy 236.488138 -253.401033) (xy 236.460842 -253.352398)
			(xy 236.440919 -253.300307) (xy 236.428793 -253.24587) (xy 236.424722 -253.190248) (xy 235.189083 -253.190248)
			(xy 235.189268 -253.200408) (xy 235.188759 -253.228294) (xy 235.180639 -253.28347) (xy 235.164571 -253.336877)
			(xy 235.140899 -253.387374) (xy 235.110126 -253.433887) (xy 235.072909 -253.475424) (xy 235.030041 -253.511099)
			(xy 234.982435 -253.540153) (xy 234.931106 -253.561965) (xy 234.877149 -253.576071) (xy 234.821712 -253.582171)
			(xy 234.765978 -253.580134) (xy 234.711135 -253.570004) (xy 234.658351 -253.551997) (xy 234.608751 -253.526496)
			(xy 234.563393 -253.494045) (xy 234.523244 -253.455336) (xy 234.489158 -253.411193) (xy 234.461862 -253.362558)
			(xy 234.441939 -253.310467) (xy 234.429813 -253.25603) (xy 234.425742 -253.200408) (xy 219.5576 -253.200408)
			(xy 219.5576 -314.3504) (xy 218.8718 -315.0362) (xy 216.8652 -315.0362) (xy 215.558137 -316.343263)
			(xy 216.469204 -316.343263) (xy 216.469204 -316.289965) (xy 216.477147 -316.237261) (xy 216.492857 -316.186331)
			(xy 216.515983 -316.13831) (xy 216.546007 -316.094273) (xy 216.582259 -316.055202) (xy 216.62393 -316.021971)
			(xy 216.670088 -315.995322) (xy 216.719702 -315.97585) (xy 216.771664 -315.96399) (xy 216.824814 -315.960007)
			(xy 216.877964 -315.96399) (xy 216.929926 -315.97585) (xy 216.97954 -315.995322) (xy 217.025698 -316.021971)
			(xy 217.067369 -316.055202) (xy 217.103621 -316.094273) (xy 217.133645 -316.13831) (xy 217.156771 -316.186331)
			(xy 217.172481 -316.237261) (xy 217.180424 -316.289965) (xy 217.180922 -316.316614) (xy 217.180424 -316.343263)
			(xy 217.172481 -316.395967) (xy 217.156771 -316.446897) (xy 217.133645 -316.494918) (xy 217.103621 -316.538955)
			(xy 217.067369 -316.578026) (xy 217.025698 -316.611257) (xy 216.97954 -316.637906) (xy 216.929926 -316.657378)
			(xy 216.877964 -316.669238) (xy 216.824814 -316.673222) (xy 216.771664 -316.669238) (xy 216.719702 -316.657378)
			(xy 216.670088 -316.637906) (xy 216.62393 -316.611257) (xy 216.582259 -316.578026) (xy 216.546007 -316.538955)
			(xy 216.515983 -316.494918) (xy 216.492857 -316.446897) (xy 216.477147 -316.395967) (xy 216.469204 -316.343263)
			(xy 215.558137 -316.343263) (xy 214.97163 -316.92977) (xy 214.977472 -316.956694) (xy 214.981167 -316.975141)
			(xy 214.985117 -317.012558) (xy 214.985346 -317.03137) (xy 214.984799 -317.059356) (xy 214.976048 -317.114639)
			(xy 214.958757 -317.167872) (xy 214.933351 -317.217745) (xy 214.900456 -317.26303) (xy 214.860882 -317.302612)
			(xy 214.815603 -317.335515) (xy 214.765735 -317.360931) (xy 214.712505 -317.378232) (xy 214.657224 -317.386994)
			(xy 214.629238 -317.387478) (xy 214.610425 -317.38725) (xy 214.573008 -317.383308) (xy 214.554562 -317.379604)
			(xy 214.527638 -317.373762) (xy 214.310468 -317.590932) (xy 216.59418 -317.590932) (xy 216.598251 -317.53531)
			(xy 216.610377 -317.480873) (xy 216.6303 -317.428782) (xy 216.657596 -317.380147) (xy 216.691682 -317.336004)
			(xy 216.731831 -317.297295) (xy 216.777189 -317.264844) (xy 216.826789 -317.239343) (xy 216.879573 -317.221336)
			(xy 216.934416 -317.211206) (xy 216.99015 -317.209169) (xy 217.045587 -317.215269) (xy 217.099544 -317.229375)
			(xy 217.150873 -317.251187) (xy 217.198479 -317.280241) (xy 217.241347 -317.315916) (xy 217.278564 -317.357453)
			(xy 217.309337 -317.403966) (xy 217.333009 -317.454463) (xy 217.349077 -317.50787) (xy 217.357197 -317.563046)
			(xy 217.357706 -317.590932) (xy 217.357197 -317.618818) (xy 217.349077 -317.673994) (xy 217.333009 -317.727401)
			(xy 217.309337 -317.777898) (xy 217.278564 -317.824411) (xy 217.241347 -317.865948) (xy 217.198479 -317.901623)
			(xy 217.150873 -317.930677) (xy 217.099544 -317.952489) (xy 217.045587 -317.966595) (xy 216.99015 -317.972695)
			(xy 216.934416 -317.970658) (xy 216.879573 -317.960528) (xy 216.826789 -317.942521) (xy 216.777189 -317.91702)
			(xy 216.731831 -317.884569) (xy 216.691682 -317.84586) (xy 216.657596 -317.801717) (xy 216.6303 -317.753082)
			(xy 216.610377 -317.700991) (xy 216.598251 -317.646554) (xy 216.59418 -317.590932) (xy 214.310468 -317.590932)
			(xy 213.858115 -318.043285) (xy 214.259404 -318.043285) (xy 214.259404 -317.989987) (xy 214.267347 -317.937283)
			(xy 214.283057 -317.886353) (xy 214.306183 -317.838332) (xy 214.336207 -317.794295) (xy 214.372459 -317.755224)
			(xy 214.41413 -317.721993) (xy 214.460288 -317.695344) (xy 214.509902 -317.675872) (xy 214.561864 -317.664012)
			(xy 214.615014 -317.660029) (xy 214.668164 -317.664012) (xy 214.720126 -317.675872) (xy 214.76974 -317.695344)
			(xy 214.815898 -317.721993) (xy 214.857569 -317.755224) (xy 214.893821 -317.794295) (xy 214.923845 -317.838332)
			(xy 214.946971 -317.886353) (xy 214.962681 -317.937283) (xy 214.970624 -317.989987) (xy 214.971122 -318.016636)
			(xy 214.970624 -318.043285) (xy 214.962681 -318.095989) (xy 214.946971 -318.146919) (xy 214.923845 -318.19494)
			(xy 214.893821 -318.238977) (xy 214.857569 -318.278048) (xy 214.815898 -318.311279) (xy 214.76974 -318.337928)
			(xy 214.720126 -318.3574) (xy 214.668164 -318.36926) (xy 214.615014 -318.373244) (xy 214.561864 -318.36926)
			(xy 214.509902 -318.3574) (xy 214.460288 -318.337928) (xy 214.41413 -318.311279) (xy 214.372459 -318.278048)
			(xy 214.336207 -318.238977) (xy 214.306183 -318.19494) (xy 214.283057 -318.146919) (xy 214.267347 -318.095989)
			(xy 214.259404 -318.043285) (xy 213.858115 -318.043285) (xy 213.045802 -318.855598) (xy 213.036412 -318.865699)
			(xy 213.022919 -318.889738) (xy 213.022013 -318.893423) (xy 258.720072 -318.893423) (xy 258.720072 -318.840125)
			(xy 258.728015 -318.787421) (xy 258.743725 -318.736491) (xy 258.766851 -318.68847) (xy 258.796875 -318.644433)
			(xy 258.833127 -318.605362) (xy 258.874798 -318.572131) (xy 258.920956 -318.545482) (xy 258.97057 -318.52601)
			(xy 259.022532 -318.51415) (xy 259.075682 -318.510167) (xy 259.128832 -318.51415) (xy 259.180794 -318.52601)
			(xy 259.230408 -318.545482) (xy 259.276566 -318.572131) (xy 259.318237 -318.605362) (xy 259.354489 -318.644433)
			(xy 259.384513 -318.68847) (xy 259.407639 -318.736491) (xy 259.423349 -318.787421) (xy 259.431292 -318.840125)
			(xy 259.43179 -318.866774) (xy 259.431292 -318.893423) (xy 259.423349 -318.946127) (xy 259.407639 -318.997057)
			(xy 259.384513 -319.045078) (xy 259.373441 -319.061317) (xy 261.33297 -319.061317) (xy 261.33297 -319.008019)
			(xy 261.340913 -318.955315) (xy 261.356623 -318.904385) (xy 261.379749 -318.856364) (xy 261.409773 -318.812327)
			(xy 261.446025 -318.773256) (xy 261.487696 -318.740025) (xy 261.533854 -318.713376) (xy 261.583468 -318.693904)
			(xy 261.63543 -318.682044) (xy 261.68858 -318.678061) (xy 261.74173 -318.682044) (xy 261.793692 -318.693904)
			(xy 261.843306 -318.713376) (xy 261.889464 -318.740025) (xy 261.931135 -318.773256) (xy 261.967387 -318.812327)
			(xy 261.997411 -318.856364) (xy 262.020537 -318.904385) (xy 262.036247 -318.955315) (xy 262.04419 -319.008019)
			(xy 262.044688 -319.034668) (xy 262.04419 -319.061317) (xy 262.036247 -319.114021) (xy 262.020537 -319.164951)
			(xy 261.997411 -319.212972) (xy 261.967387 -319.257009) (xy 261.931135 -319.29608) (xy 261.889464 -319.329311)
			(xy 261.843306 -319.35596) (xy 261.793692 -319.375432) (xy 261.74173 -319.387292) (xy 261.68858 -319.391276)
			(xy 261.63543 -319.387292) (xy 261.583468 -319.375432) (xy 261.533854 -319.35596) (xy 261.487696 -319.329311)
			(xy 261.446025 -319.29608) (xy 261.409773 -319.257009) (xy 261.379749 -319.212972) (xy 261.356623 -319.164951)
			(xy 261.340913 -319.114021) (xy 261.33297 -319.061317) (xy 259.373441 -319.061317) (xy 259.354489 -319.089115)
			(xy 259.318237 -319.128186) (xy 259.276566 -319.161417) (xy 259.230408 -319.188066) (xy 259.180794 -319.207538)
			(xy 259.128832 -319.219398) (xy 259.075682 -319.223382) (xy 259.022532 -319.219398) (xy 258.97057 -319.207538)
			(xy 258.920956 -319.188066) (xy 258.874798 -319.161417) (xy 258.833127 -319.128186) (xy 258.796875 -319.089115)
			(xy 258.766851 -319.045078) (xy 258.743725 -318.997057) (xy 258.728015 -318.946127) (xy 258.720072 -318.893423)
			(xy 213.022013 -318.893423) (xy 213.016339 -318.916509) (xy 213.017152 -318.944065) (xy 213.025298 -318.970401)
			(xy 213.040185 -318.993604) (xy 213.05012 -319.003172) (xy 213.068477 -319.020145) (xy 213.10073 -319.058346)
			(xy 213.127327 -319.100679) (xy 213.147748 -319.146314) (xy 213.161591 -319.194355) (xy 213.168584 -319.243858)
			(xy 213.168628 -319.246562) (xy 213.671463 -319.246562) (xy 213.676943 -319.192674) (xy 213.690521 -319.140238)
			(xy 213.711882 -319.090463) (xy 213.740535 -319.044496) (xy 213.775819 -319.003399) (xy 213.816919 -318.968119)
			(xy 213.862888 -318.939469) (xy 213.912665 -318.918112) (xy 213.965102 -318.904538) (xy 214.01899 -318.899062)
			(xy 214.073086 -318.901809) (xy 214.126142 -318.912717) (xy 214.176934 -318.931533) (xy 214.224291 -318.957824)
			(xy 214.267121 -318.990983) (xy 214.304435 -319.030246) (xy 214.335373 -319.074707) (xy 214.359222 -319.12334)
			(xy 214.375431 -319.175023) (xy 214.383626 -319.228565) (xy 214.384128 -319.255648) (xy 214.38362 -319.27292)
			(xy 214.383405 -319.286782) (xy 214.384123 -319.289917) (xy 254.17017 -319.289917) (xy 254.17017 -319.236619)
			(xy 254.178113 -319.183915) (xy 254.193823 -319.132985) (xy 254.216949 -319.084964) (xy 254.246973 -319.040927)
			(xy 254.283225 -319.001856) (xy 254.324896 -318.968625) (xy 254.371054 -318.941976) (xy 254.420668 -318.922504)
			(xy 254.47263 -318.910644) (xy 254.52578 -318.906661) (xy 254.57893 -318.910644) (xy 254.630892 -318.922504)
			(xy 254.680506 -318.941976) (xy 254.726664 -318.968625) (xy 254.768335 -319.001856) (xy 254.804587 -319.040927)
			(xy 254.834611 -319.084964) (xy 254.857737 -319.132985) (xy 254.873447 -319.183915) (xy 254.88139 -319.236619)
			(xy 254.881888 -319.263268) (xy 254.88139 -319.289917) (xy 254.873447 -319.342621) (xy 254.869647 -319.354941)
			(xy 256.830312 -319.354941) (xy 256.830312 -319.301643) (xy 256.838255 -319.248939) (xy 256.853965 -319.198009)
			(xy 256.877091 -319.149988) (xy 256.907115 -319.105951) (xy 256.943367 -319.06688) (xy 256.985038 -319.033649)
			(xy 257.031196 -319.007) (xy 257.08081 -318.987528) (xy 257.132772 -318.975668) (xy 257.185922 -318.971685)
			(xy 257.239072 -318.975668) (xy 257.291034 -318.987528) (xy 257.340648 -319.007) (xy 257.386806 -319.033649)
			(xy 257.428477 -319.06688) (xy 257.464729 -319.105951) (xy 257.494753 -319.149988) (xy 257.517879 -319.198009)
			(xy 257.533589 -319.248939) (xy 257.541532 -319.301643) (xy 257.54203 -319.328292) (xy 257.541532 -319.354941)
			(xy 257.533589 -319.407645) (xy 257.527125 -319.428601) (xy 264.396464 -319.428601) (xy 264.396464 -319.375303)
			(xy 264.404407 -319.322599) (xy 264.420117 -319.271669) (xy 264.443243 -319.223648) (xy 264.473267 -319.179611)
			(xy 264.509519 -319.14054) (xy 264.55119 -319.107309) (xy 264.597348 -319.08066) (xy 264.646962 -319.061188)
			(xy 264.698924 -319.049328) (xy 264.752074 -319.045345) (xy 264.805224 -319.049328) (xy 264.857186 -319.061188)
			(xy 264.9068 -319.08066) (xy 264.952958 -319.107309) (xy 264.994629 -319.14054) (xy 265.030881 -319.179611)
			(xy 265.060905 -319.223648) (xy 265.084031 -319.271669) (xy 265.099741 -319.322599) (xy 265.107684 -319.375303)
			(xy 265.108182 -319.401952) (xy 265.107684 -319.428601) (xy 265.099741 -319.481305) (xy 265.084031 -319.532235)
			(xy 265.060905 -319.580256) (xy 265.030881 -319.624293) (xy 264.994629 -319.663364) (xy 264.952958 -319.696595)
			(xy 264.9068 -319.723244) (xy 264.857186 -319.742716) (xy 264.805224 -319.754576) (xy 264.752074 -319.75856)
			(xy 264.698924 -319.754576) (xy 264.646962 -319.742716) (xy 264.597348 -319.723244) (xy 264.55119 -319.696595)
			(xy 264.509519 -319.663364) (xy 264.473267 -319.624293) (xy 264.443243 -319.580256) (xy 264.420117 -319.532235)
			(xy 264.404407 -319.481305) (xy 264.396464 -319.428601) (xy 257.527125 -319.428601) (xy 257.517879 -319.458575)
			(xy 257.494753 -319.506596) (xy 257.464729 -319.550633) (xy 257.428477 -319.589704) (xy 257.386806 -319.622935)
			(xy 257.340648 -319.649584) (xy 257.291034 -319.669056) (xy 257.239072 -319.680916) (xy 257.185922 -319.6849)
			(xy 257.132772 -319.680916) (xy 257.08081 -319.669056) (xy 257.031196 -319.649584) (xy 256.985038 -319.622935)
			(xy 256.943367 -319.589704) (xy 256.907115 -319.550633) (xy 256.877091 -319.506596) (xy 256.853965 -319.458575)
			(xy 256.838255 -319.407645) (xy 256.830312 -319.354941) (xy 254.869647 -319.354941) (xy 254.857737 -319.393551)
			(xy 254.834611 -319.441572) (xy 254.804587 -319.485609) (xy 254.768335 -319.52468) (xy 254.726664 -319.557911)
			(xy 254.680506 -319.58456) (xy 254.630892 -319.604032) (xy 254.57893 -319.615892) (xy 254.52578 -319.619876)
			(xy 254.47263 -319.615892) (xy 254.420668 -319.604032) (xy 254.371054 -319.58456) (xy 254.324896 -319.557911)
			(xy 254.283225 -319.52468) (xy 254.246973 -319.485609) (xy 254.216949 -319.441572) (xy 254.193823 -319.393551)
			(xy 254.178113 -319.342621) (xy 254.17017 -319.289917) (xy 214.384123 -319.289917) (xy 214.389588 -319.313797)
			(xy 214.402801 -319.338158) (xy 214.422074 -319.358073) (xy 214.445989 -319.372078) (xy 214.472787 -319.379143)
			(xy 214.500498 -319.378748) (xy 214.513922 -319.375282) (xy 214.538626 -319.368399) (xy 214.589373 -319.361011)
			(xy 214.615014 -319.36055) (xy 214.642094 -319.361113) (xy 214.695628 -319.369316) (xy 214.747302 -319.385532)
			(xy 214.795926 -319.409385) (xy 214.840376 -319.440327) (xy 214.879628 -319.477643) (xy 214.912777 -319.520472)
			(xy 214.939058 -319.567828) (xy 214.957864 -319.618617) (xy 214.968763 -319.671668) (xy 214.971503 -319.725758)
			(xy 214.96602 -319.779639) (xy 214.952441 -319.832068) (xy 214.948006 -319.8424) (xy 265.583856 -319.8424)
			(xy 265.58784 -319.789241) (xy 265.599703 -319.73727) (xy 265.61918 -319.687648) (xy 265.645835 -319.641483)
			(xy 265.679074 -319.599806) (xy 265.718154 -319.56355) (xy 265.762201 -319.533524) (xy 265.810232 -319.510398)
			(xy 265.861173 -319.49469) (xy 265.913886 -319.48675) (xy 265.94054 -319.48628) (xy 265.970434 -319.486922)
			(xy 266.029384 -319.496903) (xy 266.085843 -319.516578) (xy 266.138228 -319.545396) (xy 266.162028 -319.563496)
			(xy 266.17374 -319.57209) (xy 266.20061 -319.583077) (xy 266.229486 -319.586052) (xy 266.258032 -319.580775)
			(xy 266.283936 -319.567673) (xy 266.305102 -319.547806) (xy 266.312904 -319.535556) (xy 266.326713 -319.513054)
			(xy 266.359973 -319.472055) (xy 266.398924 -319.436418) (xy 266.442711 -319.406925) (xy 266.490375 -319.384222)
			(xy 266.540868 -319.368809) (xy 266.593085 -319.361024) (xy 266.619482 -319.36055) (xy 266.646131 -319.361106)
			(xy 266.698834 -319.369047) (xy 266.705805 -319.371197) (xy 271.930104 -319.371197) (xy 271.930104 -319.317899)
			(xy 271.938047 -319.265195) (xy 271.953757 -319.214265) (xy 271.976883 -319.166244) (xy 272.006907 -319.122207)
			(xy 272.043159 -319.083136) (xy 272.08483 -319.049905) (xy 272.130988 -319.023256) (xy 272.180602 -319.003784)
			(xy 272.232564 -318.991924) (xy 272.285714 -318.987941) (xy 272.338864 -318.991924) (xy 272.390826 -319.003784)
			(xy 272.44044 -319.023256) (xy 272.486598 -319.049905) (xy 272.528269 -319.083136) (xy 272.564521 -319.122207)
			(xy 272.594545 -319.166244) (xy 272.617671 -319.214265) (xy 272.633381 -319.265195) (xy 272.641324 -319.317899)
			(xy 272.641822 -319.344548) (xy 272.641324 -319.371197) (xy 272.633381 -319.423901) (xy 272.617671 -319.474831)
			(xy 272.594545 -319.522852) (xy 272.564521 -319.566889) (xy 272.528269 -319.60596) (xy 272.486598 -319.639191)
			(xy 272.44044 -319.66584) (xy 272.390826 -319.685312) (xy 272.338864 -319.697172) (xy 272.285714 -319.701156)
			(xy 272.232564 -319.697172) (xy 272.180602 -319.685312) (xy 272.130988 -319.66584) (xy 272.08483 -319.639191)
			(xy 272.043159 -319.60596) (xy 272.006907 -319.566889) (xy 271.976883 -319.522852) (xy 271.953757 -319.474831)
			(xy 271.938047 -319.423901) (xy 271.930104 -319.371197) (xy 266.705805 -319.371197) (xy 266.749764 -319.384755)
			(xy 266.797785 -319.407878) (xy 266.841822 -319.4379) (xy 266.880893 -319.474151) (xy 266.914125 -319.51582)
			(xy 266.940774 -319.561977) (xy 266.960247 -319.61159) (xy 266.972107 -319.663551) (xy 266.97609 -319.7167)
			(xy 266.972107 -319.769849) (xy 266.964244 -319.8043) (xy 273.07948 -319.8043) (xy 273.083463 -319.751151)
			(xy 273.095323 -319.699188) (xy 273.114794 -319.649574) (xy 273.141443 -319.603415) (xy 273.174673 -319.561744)
			(xy 273.213742 -319.525491) (xy 273.257779 -319.495465) (xy 273.305798 -319.472338) (xy 273.356728 -319.456626)
			(xy 273.409431 -319.448679) (xy 273.43608 -319.44818) (xy 273.464857 -319.448735) (xy 273.521662 -319.457981)
			(xy 273.576238 -319.476252) (xy 273.627161 -319.503072) (xy 273.673101 -319.537739) (xy 273.693382 -319.558162)
			(xy 273.703036 -319.56762) (xy 273.726146 -319.581609) (xy 273.752118 -319.589035) (xy 273.77913 -319.589376)
			(xy 273.805282 -319.582608) (xy 273.828737 -319.569208) (xy 273.847848 -319.550116) (xy 273.854926 -319.538604)
			(xy 273.868632 -319.515743) (xy 273.901858 -319.474066) (xy 273.940927 -319.437809) (xy 273.984966 -319.407783)
			(xy 274.03299 -319.384658) (xy 274.083924 -319.368953) (xy 274.136631 -319.361017) (xy 274.163282 -319.36055)
			(xy 274.189931 -319.361106) (xy 274.242634 -319.369047) (xy 274.293564 -319.384755) (xy 274.341585 -319.407878)
			(xy 274.385622 -319.4379) (xy 274.424693 -319.474151) (xy 274.457925 -319.51582) (xy 274.484574 -319.561977)
			(xy 274.504047 -319.61159) (xy 274.515907 -319.663551) (xy 274.51989 -319.7167) (xy 274.515907 -319.769849)
			(xy 274.504047 -319.82181) (xy 274.484574 -319.871423) (xy 274.457925 -319.91758) (xy 274.424693 -319.959249)
			(xy 274.385622 -319.9955) (xy 274.341585 -320.025522) (xy 274.293564 -320.048645) (xy 274.242634 -320.064353)
			(xy 274.189931 -320.072294) (xy 274.163282 -320.072766) (xy 274.134503 -320.072252) (xy 274.077695 -320.062998)
			(xy 274.023118 -320.044718) (xy 273.972196 -320.017889) (xy 273.926259 -319.983212) (xy 273.90598 -319.962784)
			(xy 273.896355 -319.953296) (xy 273.873237 -319.939318) (xy 273.847258 -319.931901) (xy 273.820244 -319.931567)
			(xy 273.79409 -319.938338) (xy 273.770633 -319.95174) (xy 273.751517 -319.970831) (xy 273.744436 -319.982342)
			(xy 273.730704 -320.005186) (xy 273.69748 -320.04686) (xy 273.658414 -320.083117) (xy 273.61438 -320.113144)
			(xy 273.566361 -320.136271) (xy 273.515432 -320.151982) (xy 273.462729 -320.159924) (xy 273.43608 -320.160396)
			(xy 273.409431 -320.159921) (xy 273.356728 -320.151974) (xy 273.305798 -320.136262) (xy 273.257779 -320.113135)
			(xy 273.213742 -320.083109) (xy 273.174673 -320.046856) (xy 273.141443 -320.005185) (xy 273.114794 -319.959026)
			(xy 273.095323 -319.909412) (xy 273.083463 -319.857449) (xy 273.07948 -319.8043) (xy 266.964244 -319.8043)
			(xy 266.960247 -319.82181) (xy 266.940774 -319.871423) (xy 266.914125 -319.91758) (xy 266.880893 -319.959249)
			(xy 266.841822 -319.9955) (xy 266.797785 -320.025522) (xy 266.749764 -320.048645) (xy 266.698834 -320.064353)
			(xy 266.646131 -320.072294) (xy 266.619482 -320.072766) (xy 266.589586 -320.072156) (xy 266.530636 -320.062164)
			(xy 266.474177 -320.042479) (xy 266.421793 -320.013653) (xy 266.397994 -319.99555) (xy 266.386351 -319.986854)
			(xy 266.359458 -319.97587) (xy 266.33056 -319.972906) (xy 266.301997 -319.978202) (xy 266.276083 -319.99133)
			(xy 266.254916 -320.011225) (xy 266.247118 -320.02349) (xy 266.233311 -320.045992) (xy 266.200049 -320.086989)
			(xy 266.161097 -320.122625) (xy 266.117309 -320.152117) (xy 266.069646 -320.174819) (xy 266.019153 -320.190233)
			(xy 265.966937 -320.198021) (xy 265.94054 -320.198496) (xy 265.913886 -320.19805) (xy 265.861173 -320.19011)
			(xy 265.810232 -320.174402) (xy 265.762201 -320.151276) (xy 265.718154 -320.12125) (xy 265.679074 -320.084994)
			(xy 265.645835 -320.043317) (xy 265.61918 -319.997152) (xy 265.599703 -319.94753) (xy 265.58784 -319.895559)
			(xy 265.583856 -319.8424) (xy 214.948006 -319.8424) (xy 214.93108 -319.881836) (xy 214.902428 -319.927796)
			(xy 214.867147 -319.968887) (xy 214.826051 -320.004161) (xy 214.780086 -320.032806) (xy 214.730315 -320.05416)
			(xy 214.677883 -320.06773) (xy 214.624002 -320.073204) (xy 214.569912 -320.070456) (xy 214.516863 -320.059549)
			(xy 214.466077 -320.040734) (xy 214.418726 -320.014446) (xy 214.375901 -319.981291) (xy 214.338591 -319.942032)
			(xy 214.307657 -319.897577) (xy 214.283811 -319.84895) (xy 214.267603 -319.797273) (xy 214.259408 -319.743738)
			(xy 214.258906 -319.716658) (xy 214.259414 -319.699386) (xy 214.25958 -319.685526) (xy 214.253401 -319.658518)
			(xy 214.240194 -319.634162) (xy 214.22093 -319.61425) (xy 214.197025 -319.600245) (xy 214.170237 -319.593176)
			(xy 214.142534 -319.593563) (xy 214.129112 -319.597024) (xy 214.104406 -319.6039) (xy 214.05366 -319.611292)
			(xy 214.02802 -319.611756) (xy 214.000937 -319.611224) (xy 213.947396 -319.603024) (xy 213.895714 -319.586811)
			(xy 213.847083 -319.562959) (xy 213.802624 -319.532017) (xy 213.763365 -319.4947) (xy 213.730209 -319.451868)
			(xy 213.703922 -319.404509) (xy 213.685109 -319.353715) (xy 213.674206 -319.300658) (xy 213.671463 -319.246562)
			(xy 213.168628 -319.246562) (xy 213.168992 -319.268856) (xy 213.168475 -319.296843) (xy 213.159724 -319.352129)
			(xy 213.142432 -319.405365) (xy 213.117024 -319.45524) (xy 213.084126 -319.500526) (xy 213.044548 -319.540108)
			(xy 212.999264 -319.573009) (xy 212.949391 -319.598421) (xy 212.896156 -319.615718) (xy 212.840871 -319.624473)
			(xy 212.812884 -319.624964) (xy 212.78529 -319.624445) (xy 212.730764 -319.615933) (xy 212.678202 -319.599114)
			(xy 212.628862 -319.574391) (xy 212.583925 -319.542356) (xy 212.544465 -319.503774) (xy 212.511427 -319.459569)
			(xy 212.4856 -319.410798) (xy 212.467603 -319.358627) (xy 212.457866 -319.304306) (xy 212.456776 -319.27673)
			(xy 212.45576 -319.2272) (xy 205.685898 -319.2272) (xy 205.672585 -319.227584) (xy 205.646862 -319.234458)
			(xy 205.623799 -319.247762) (xy 205.604971 -319.266588) (xy 205.591664 -319.289649) (xy 205.584786 -319.31537)
			(xy 205.584808 -319.341995) (xy 205.587854 -319.354962) (xy 205.59345 -319.377471) (xy 205.59944 -319.423465)
			(xy 205.599792 -319.446656) (xy 205.599294 -319.473305) (xy 205.591351 -319.526009) (xy 205.575641 -319.576939)
			(xy 205.552515 -319.62496) (xy 205.522491 -319.668997) (xy 205.486239 -319.708068) (xy 205.444568 -319.741299)
			(xy 205.44109 -319.743307) (xy 206.00415 -319.743307) (xy 206.00415 -319.690009) (xy 206.012093 -319.637305)
			(xy 206.027803 -319.586375) (xy 206.050929 -319.538354) (xy 206.080953 -319.494317) (xy 206.117205 -319.455246)
			(xy 206.158876 -319.422015) (xy 206.205034 -319.395366) (xy 206.254648 -319.375894) (xy 206.30661 -319.364034)
			(xy 206.35976 -319.360051) (xy 206.41291 -319.364034) (xy 206.464872 -319.375894) (xy 206.514486 -319.395366)
			(xy 206.560644 -319.422015) (xy 206.602315 -319.455246) (xy 206.638567 -319.494317) (xy 206.668591 -319.538354)
			(xy 206.691717 -319.586375) (xy 206.707427 -319.637305) (xy 206.71537 -319.690009) (xy 206.715868 -319.716658)
			(xy 206.71537 -319.743307) (xy 206.707427 -319.796011) (xy 206.691717 -319.846941) (xy 206.668591 -319.894962)
			(xy 206.638567 -319.938999) (xy 206.602315 -319.97807) (xy 206.560644 -320.011301) (xy 206.514486 -320.03795)
			(xy 206.464872 -320.057422) (xy 206.41291 -320.069282) (xy 206.35976 -320.073266) (xy 206.30661 -320.069282)
			(xy 206.254648 -320.057422) (xy 206.205034 -320.03795) (xy 206.158876 -320.011301) (xy 206.117205 -319.97807)
			(xy 206.080953 -319.938999) (xy 206.050929 -319.894962) (xy 206.027803 -319.846941) (xy 206.012093 -319.796011)
			(xy 206.00415 -319.743307) (xy 205.44109 -319.743307) (xy 205.39841 -319.767948) (xy 205.348796 -319.78742)
			(xy 205.296834 -319.79928) (xy 205.243684 -319.803264) (xy 205.190534 -319.79928) (xy 205.138572 -319.78742)
			(xy 205.088958 -319.767948) (xy 205.0428 -319.741299) (xy 205.001129 -319.708068) (xy 204.964877 -319.668997)
			(xy 204.934853 -319.62496) (xy 204.911727 -319.576939) (xy 204.896017 -319.526009) (xy 204.888074 -319.473305)
			(xy 204.887576 -319.446656) (xy 204.887932 -319.423465) (xy 204.893919 -319.377471) (xy 204.899514 -319.354962)
			(xy 204.90252 -319.341998) (xy 204.902493 -319.315396) (xy 204.895594 -319.289704) (xy 204.88229 -319.266668)
			(xy 204.863485 -319.247851) (xy 204.840458 -319.234532) (xy 204.81477 -319.227615) (xy 204.80147 -319.2272)
			(xy 198.157338 -319.2272) (xy 198.14372 -319.227642) (xy 198.117455 -319.234854) (xy 198.094028 -319.248748)
			(xy 198.075104 -319.268338) (xy 198.062028 -319.292231) (xy 198.055729 -319.31873) (xy 198.055738 -319.332356)
			(xy 198.055992 -319.345056) (xy 198.055494 -319.371705) (xy 198.047551 -319.424409) (xy 198.031841 -319.475339)
			(xy 198.008715 -319.52336) (xy 197.978691 -319.567397) (xy 197.942439 -319.606468) (xy 197.900768 -319.639699)
			(xy 197.85461 -319.666348) (xy 197.804996 -319.68582) (xy 197.753034 -319.69768) (xy 197.699884 -319.701664)
			(xy 197.646734 -319.69768) (xy 197.594772 -319.68582) (xy 197.545158 -319.666348) (xy 197.499 -319.639699)
			(xy 197.457329 -319.606468) (xy 197.421077 -319.567397) (xy 197.391053 -319.52336) (xy 197.367927 -319.475339)
			(xy 197.352217 -319.424409) (xy 197.344274 -319.371705) (xy 197.343776 -319.345056) (xy 197.34403 -319.332356)
			(xy 197.344071 -319.318725) (xy 197.337787 -319.292212) (xy 197.324712 -319.268307) (xy 197.305779 -319.248712)
			(xy 197.282336 -319.234825) (xy 197.256054 -319.227634) (xy 197.24243 -319.2272) (xy 194.870832 -319.2272)
			(xy 194.852246 -319.247828) (xy 194.809808 -319.283631) (xy 194.76233 -319.312418) (xy 194.710962 -319.333493)
			(xy 194.656947 -319.346346) (xy 194.601592 -319.350665) (xy 194.546237 -319.346346) (xy 194.492222 -319.333493)
			(xy 194.440854 -319.312418) (xy 194.393376 -319.283631) (xy 194.350938 -319.247828) (xy 194.332352 -319.2272)
			(xy 190.421006 -319.2272) (xy 190.41999 -319.27673) (xy 190.418939 -319.302995) (xy 190.410067 -319.354803)
			(xy 190.393678 -319.404745) (xy 190.370127 -319.451737) (xy 190.339925 -319.494757) (xy 190.30373 -319.532871)
			(xy 190.262326 -319.565253) (xy 190.216613 -319.591198) (xy 190.167583 -319.610143) (xy 190.116302 -319.621678)
			(xy 190.063882 -319.625551) (xy 190.011462 -319.621678) (xy 189.960181 -319.610143) (xy 189.911151 -319.591198)
			(xy 189.865438 -319.565253) (xy 189.824034 -319.532871) (xy 189.787839 -319.494757) (xy 189.757637 -319.451737)
			(xy 189.734086 -319.404745) (xy 189.717697 -319.354803) (xy 189.708825 -319.302995) (xy 189.707774 -319.27673)
			(xy 189.706758 -319.2272) (xy 183.094122 -319.2272) (xy 183.078889 -319.227763) (xy 183.049773 -319.236731)
			(xy 183.02459 -319.253877) (xy 183.005576 -319.27768) (xy 182.994416 -319.306028) (xy 182.992776 -319.32118)
			(xy 182.990267 -319.3477) (xy 182.978373 -319.399623) (xy 182.958877 -319.449195) (xy 182.932215 -319.49531)
			(xy 182.898981 -319.536939) (xy 182.859917 -319.573153) (xy 182.815894 -319.603145) (xy 182.767896 -319.626244)
			(xy 182.716992 -319.641936) (xy 182.664318 -319.649871) (xy 182.61105 -319.649871) (xy 182.558376 -319.641936)
			(xy 182.507472 -319.626244) (xy 182.459474 -319.603145) (xy 182.415451 -319.573153) (xy 182.376387 -319.536939)
			(xy 182.343153 -319.49531) (xy 182.316491 -319.449195) (xy 182.296995 -319.399623) (xy 182.285101 -319.3477)
			(xy 182.282592 -319.32118) (xy 182.280941 -319.306025) (xy 182.269799 -319.277663) (xy 182.250791 -319.253845)
			(xy 182.225606 -319.236691) (xy 182.196483 -319.227723) (xy 182.181246 -319.2272) (xy 179.802282 -319.2272)
			(xy 179.791868 -319.26403) (xy 179.783983 -319.290003) (xy 179.761442 -319.339377) (xy 179.731669 -319.384759)
			(xy 179.695354 -319.425098) (xy 179.653338 -319.459458) (xy 179.606595 -319.487046) (xy 179.556207 -319.50722)
			(xy 179.503341 -319.519515) (xy 179.449222 -319.523645) (xy 179.395103 -319.519515) (xy 179.342237 -319.50722)
			(xy 179.291849 -319.487046) (xy 179.245106 -319.459458) (xy 179.20309 -319.425098) (xy 179.166775 -319.384759)
			(xy 179.137002 -319.339377) (xy 179.114461 -319.290003) (xy 179.106576 -319.26403) (xy 179.096162 -319.2272)
			(xy 175.341788 -319.2272) (xy 175.340772 -319.27673) (xy 175.339721 -319.302995) (xy 175.330849 -319.354803)
			(xy 175.31446 -319.404745) (xy 175.290909 -319.451737) (xy 175.260707 -319.494757) (xy 175.224512 -319.532871)
			(xy 175.183108 -319.565253) (xy 175.137395 -319.591198) (xy 175.088365 -319.610143) (xy 175.037084 -319.621678)
			(xy 174.984664 -319.625551) (xy 174.932244 -319.621678) (xy 174.880963 -319.610143) (xy 174.831933 -319.591198)
			(xy 174.78622 -319.565253) (xy 174.744816 -319.532871) (xy 174.708621 -319.494757) (xy 174.678419 -319.451737)
			(xy 174.654868 -319.404745) (xy 174.638479 -319.354803) (xy 174.629607 -319.302995) (xy 174.628556 -319.27673)
			(xy 174.62754 -319.2272) (xy 172.130212 -319.2272) (xy 172.115593 -319.227676) (xy 172.087551 -319.235953)
			(xy 172.063002 -319.251833) (xy 172.043955 -319.274016) (xy 172.03197 -319.300685) (xy 172.02803 -319.329656)
			(xy 172.032455 -319.358557) (xy 172.038264 -319.37198) (xy 172.048845 -319.39571) (xy 172.063786 -319.445472)
			(xy 172.071333 -319.496878) (xy 172.071792 -319.522856) (xy 172.071294 -319.549505) (xy 172.063351 -319.602209)
			(xy 172.047641 -319.653139) (xy 172.024515 -319.70116) (xy 171.99578 -319.743307) (xy 183.46419 -319.743307)
			(xy 183.46419 -319.690009) (xy 183.472133 -319.637305) (xy 183.487843 -319.586375) (xy 183.510969 -319.538354)
			(xy 183.540993 -319.494317) (xy 183.577245 -319.455246) (xy 183.618916 -319.422015) (xy 183.665074 -319.395366)
			(xy 183.714688 -319.375894) (xy 183.76665 -319.364034) (xy 183.8198 -319.360051) (xy 183.87295 -319.364034)
			(xy 183.924912 -319.375894) (xy 183.974526 -319.395366) (xy 184.020684 -319.422015) (xy 184.062355 -319.455246)
			(xy 184.098607 -319.494317) (xy 184.128631 -319.538354) (xy 184.151757 -319.586375) (xy 184.167467 -319.637305)
			(xy 184.17541 -319.690009) (xy 184.175908 -319.716658) (xy 184.17541 -319.743307) (xy 184.167467 -319.796011)
			(xy 184.151757 -319.846941) (xy 184.128631 -319.894962) (xy 184.12033 -319.907137) (xy 198.55941 -319.907137)
			(xy 198.55941 -319.853839) (xy 198.567353 -319.801135) (xy 198.583063 -319.750205) (xy 198.606189 -319.702184)
			(xy 198.636213 -319.658147) (xy 198.672465 -319.619076) (xy 198.714136 -319.585845) (xy 198.760294 -319.559196)
			(xy 198.809908 -319.539724) (xy 198.86187 -319.527864) (xy 198.91502 -319.523881) (xy 198.96817 -319.527864)
			(xy 199.020132 -319.539724) (xy 199.069746 -319.559196) (xy 199.115904 -319.585845) (xy 199.157575 -319.619076)
			(xy 199.193827 -319.658147) (xy 199.223851 -319.702184) (xy 199.246977 -319.750205) (xy 199.262687 -319.801135)
			(xy 199.27063 -319.853839) (xy 199.271128 -319.880488) (xy 199.27063 -319.907137) (xy 199.262687 -319.959841)
			(xy 199.246977 -320.010771) (xy 199.223851 -320.058792) (xy 199.193827 -320.102829) (xy 199.157575 -320.1419)
			(xy 199.115904 -320.175131) (xy 199.069746 -320.20178) (xy 199.020132 -320.221252) (xy 198.96817 -320.233112)
			(xy 198.91502 -320.237096) (xy 198.86187 -320.233112) (xy 198.809908 -320.221252) (xy 198.760294 -320.20178)
			(xy 198.714136 -320.175131) (xy 198.672465 -320.1419) (xy 198.636213 -320.102829) (xy 198.606189 -320.058792)
			(xy 198.583063 -320.010771) (xy 198.567353 -319.959841) (xy 198.55941 -319.907137) (xy 184.12033 -319.907137)
			(xy 184.098607 -319.938999) (xy 184.062355 -319.97807) (xy 184.020684 -320.011301) (xy 183.974526 -320.03795)
			(xy 183.924912 -320.057422) (xy 183.87295 -320.069282) (xy 183.8198 -320.073266) (xy 183.76665 -320.069282)
			(xy 183.714688 -320.057422) (xy 183.665074 -320.03795) (xy 183.618916 -320.011301) (xy 183.577245 -319.97807)
			(xy 183.540993 -319.938999) (xy 183.510969 -319.894962) (xy 183.487843 -319.846941) (xy 183.472133 -319.796011)
			(xy 183.46419 -319.743307) (xy 171.99578 -319.743307) (xy 171.994491 -319.745197) (xy 171.958239 -319.784268)
			(xy 171.916568 -319.817499) (xy 171.87041 -319.844148) (xy 171.820796 -319.86362) (xy 171.768834 -319.87548)
			(xy 171.715684 -319.879464) (xy 171.662534 -319.87548) (xy 171.610572 -319.86362) (xy 171.560958 -319.844148)
			(xy 171.5148 -319.817499) (xy 171.473129 -319.784268) (xy 171.436877 -319.745197) (xy 171.406853 -319.70116)
			(xy 171.383727 -319.653139) (xy 171.368017 -319.602209) (xy 171.360074 -319.549505) (xy 171.359576 -319.522856)
			(xy 171.36005 -319.496879) (xy 171.367601 -319.445477) (xy 171.382537 -319.395716) (xy 171.393104 -319.37198)
			(xy 171.398883 -319.358546) (xy 171.403303 -319.329648) (xy 171.399363 -319.300681) (xy 171.387383 -319.274015)
			(xy 171.368345 -319.25183) (xy 171.343806 -319.235943) (xy 171.315773 -319.227652) (xy 171.301156 -319.2272)
			(xy 167.966898 -319.2272) (xy 167.953585 -319.227584) (xy 167.927862 -319.234458) (xy 167.904799 -319.247762)
			(xy 167.885971 -319.266588) (xy 167.872664 -319.289649) (xy 167.865786 -319.31537) (xy 167.865808 -319.341995)
			(xy 167.868854 -319.354962) (xy 167.87445 -319.377471) (xy 167.88044 -319.423465) (xy 167.880792 -319.446656)
			(xy 167.880294 -319.473305) (xy 167.872351 -319.526009) (xy 167.856641 -319.576939) (xy 167.833515 -319.62496)
			(xy 167.803491 -319.668997) (xy 167.767239 -319.708068) (xy 167.725568 -319.741299) (xy 167.67941 -319.767948)
			(xy 167.629796 -319.78742) (xy 167.577834 -319.79928) (xy 167.524684 -319.803264) (xy 167.471534 -319.79928)
			(xy 167.419572 -319.78742) (xy 167.369958 -319.767948) (xy 167.3238 -319.741299) (xy 167.282129 -319.708068)
			(xy 167.245877 -319.668997) (xy 167.215853 -319.62496) (xy 167.192727 -319.576939) (xy 167.177017 -319.526009)
			(xy 167.169074 -319.473305) (xy 167.168576 -319.446656) (xy 167.168932 -319.423465) (xy 167.174919 -319.377471)
			(xy 167.180514 -319.354962) (xy 167.18352 -319.341998) (xy 167.183493 -319.315396) (xy 167.176594 -319.289704)
			(xy 167.16329 -319.266668) (xy 167.144485 -319.247851) (xy 167.121458 -319.234532) (xy 167.09577 -319.227615)
			(xy 167.08247 -319.2272) (xy 162.122612 -319.2272) (xy 162.10792 -319.227686) (xy 162.079751 -319.236045)
			(xy 162.055126 -319.252075) (xy 162.036081 -319.27445) (xy 162.024191 -319.30132) (xy 162.02044 -319.330463)
			(xy 162.025137 -319.359468) (xy 162.037895 -319.385937) (xy 162.047428 -319.397126) (xy 162.064826 -319.41692)
			(xy 162.0942 -319.460673) (xy 162.116812 -319.508273) (xy 162.132169 -319.558684) (xy 162.139935 -319.610807)
			(xy 162.140392 -319.637156) (xy 162.139889 -319.664593) (xy 162.131477 -319.718819) (xy 162.114847 -319.771113)
			(xy 162.090391 -319.820237) (xy 162.058688 -319.865027) (xy 162.020489 -319.904424) (xy 161.998914 -319.921382)
			(xy 161.987041 -319.930993) (xy 161.969202 -319.955772) (xy 161.959483 -319.984716) (xy 161.95875 -320.01524)
			(xy 161.967071 -320.044616) (xy 161.983702 -320.070222) (xy 161.995104 -320.080386) (xy 162.014737 -320.097399)
			(xy 162.049343 -320.136141) (xy 162.07795 -320.179502) (xy 162.099951 -320.226561) (xy 162.113853 -320.272897)
			(xy 164.15765 -320.272897) (xy 164.15765 -320.219599) (xy 164.165593 -320.166895) (xy 164.181303 -320.115965)
			(xy 164.204429 -320.067944) (xy 164.234453 -320.023907) (xy 164.270705 -319.984836) (xy 164.312376 -319.951605)
			(xy 164.358534 -319.924956) (xy 164.408148 -319.905484) (xy 164.46011 -319.893624) (xy 164.51326 -319.889641)
			(xy 164.56641 -319.893624) (xy 164.618372 -319.905484) (xy 164.667887 -319.924917) (xy 168.46041 -319.924917)
			(xy 168.46041 -319.871619) (xy 168.468353 -319.818915) (xy 168.484063 -319.767985) (xy 168.507189 -319.719964)
			(xy 168.537213 -319.675927) (xy 168.573465 -319.636856) (xy 168.615136 -319.603625) (xy 168.661294 -319.576976)
			(xy 168.710908 -319.557504) (xy 168.76287 -319.545644) (xy 168.81602 -319.541661) (xy 168.86917 -319.545644)
			(xy 168.921132 -319.557504) (xy 168.970746 -319.576976) (xy 169.016904 -319.603625) (xy 169.058575 -319.636856)
			(xy 169.094827 -319.675927) (xy 169.124851 -319.719964) (xy 169.147977 -319.767985) (xy 169.163687 -319.818915)
			(xy 169.17163 -319.871619) (xy 169.172128 -319.898268) (xy 169.17163 -319.924917) (xy 169.163687 -319.977621)
			(xy 169.147977 -320.028551) (xy 169.124851 -320.076572) (xy 169.094827 -320.120609) (xy 169.058575 -320.15968)
			(xy 169.016904 -320.192911) (xy 168.970746 -320.21956) (xy 168.921132 -320.239032) (xy 168.86917 -320.250892)
			(xy 168.81602 -320.254876) (xy 168.76287 -320.250892) (xy 168.710908 -320.239032) (xy 168.661294 -320.21956)
			(xy 168.615136 -320.192911) (xy 168.573465 -320.15968) (xy 168.537213 -320.120609) (xy 168.507189 -320.076572)
			(xy 168.484063 -320.028551) (xy 168.468353 -319.977621) (xy 168.46041 -319.924917) (xy 164.667887 -319.924917)
			(xy 164.667986 -319.924956) (xy 164.714144 -319.951605) (xy 164.755815 -319.984836) (xy 164.792067 -320.023907)
			(xy 164.822091 -320.067944) (xy 164.845217 -320.115965) (xy 164.860927 -320.166895) (xy 164.86887 -320.219599)
			(xy 164.869368 -320.246248) (xy 164.86887 -320.272897) (xy 164.860927 -320.325601) (xy 164.845217 -320.376531)
			(xy 164.822091 -320.424552) (xy 164.792067 -320.468589) (xy 164.755815 -320.50766) (xy 164.714144 -320.540891)
			(xy 164.667986 -320.56754) (xy 164.618372 -320.587012) (xy 164.56641 -320.598872) (xy 164.51326 -320.602856)
			(xy 164.46011 -320.598872) (xy 164.408148 -320.587012) (xy 164.358534 -320.56754) (xy 164.312376 -320.540891)
			(xy 164.270705 -320.50766) (xy 164.234453 -320.468589) (xy 164.204429 -320.424552) (xy 164.181303 -320.376531)
			(xy 164.165593 -320.325601) (xy 164.15765 -320.272897) (xy 162.113853 -320.272897) (xy 162.114879 -320.276318)
			(xy 162.122417 -320.327716) (xy 162.122866 -320.35369) (xy 162.122368 -320.380339) (xy 162.114425 -320.433043)
			(xy 162.098715 -320.483973) (xy 162.075589 -320.531994) (xy 162.045565 -320.576031) (xy 162.009313 -320.615102)
			(xy 161.967642 -320.648333) (xy 161.921484 -320.674982) (xy 161.87187 -320.694454) (xy 161.819908 -320.706314)
			(xy 161.766758 -320.710298) (xy 161.713608 -320.706314) (xy 161.661646 -320.694454) (xy 161.612032 -320.674982)
			(xy 161.565874 -320.648333) (xy 161.524203 -320.615102) (xy 161.487951 -320.576031) (xy 161.457927 -320.531994)
			(xy 161.434801 -320.483973) (xy 161.419091 -320.433043) (xy 161.411148 -320.380339) (xy 161.41065 -320.35369)
			(xy 161.41115 -320.32625) (xy 161.419554 -320.272019) (xy 161.436178 -320.219719) (xy 161.460628 -320.170587)
			(xy 161.492325 -320.125788) (xy 161.530518 -320.086381) (xy 161.552128 -320.069464) (xy 161.563988 -320.059851)
			(xy 161.581804 -320.035075) (xy 161.591506 -320.006142) (xy 161.592228 -319.975634) (xy 161.583905 -319.946274)
			(xy 161.56728 -319.920684) (xy 161.555938 -319.91046) (xy 161.53638 -319.892934) (xy 161.525492 -319.883069)
			(xy 161.499451 -319.869492) (xy 161.470621 -319.863896) (xy 161.441391 -319.866745) (xy 161.414185 -319.877803)
			(xy 161.391255 -319.896153) (xy 161.382456 -319.90792) (xy 161.365645 -319.931051) (xy 161.325884 -319.97214)
			(xy 161.280075 -320.006356) (xy 161.229391 -320.032821) (xy 161.175132 -320.050856) (xy 161.118691 -320.059999)
			(xy 161.090102 -320.060574) (xy 161.063453 -320.060101) (xy 161.010751 -320.052158) (xy 160.959822 -320.036448)
			(xy 160.911802 -320.013324) (xy 160.867766 -319.9833) (xy 160.828696 -319.947049) (xy 160.795465 -319.905379)
			(xy 160.768817 -319.859223) (xy 160.749345 -319.809609) (xy 160.737485 -319.757648) (xy 160.733502 -319.7045)
			(xy 160.737485 -319.651352) (xy 160.749345 -319.599391) (xy 160.768817 -319.549777) (xy 160.795465 -319.503621)
			(xy 160.828696 -319.461951) (xy 160.867766 -319.4257) (xy 160.911802 -319.395676) (xy 160.959822 -319.372552)
			(xy 161.010751 -319.356842) (xy 161.063453 -319.348899) (xy 161.090102 -319.348358) (xy 161.117532 -319.348862)
			(xy 161.171746 -319.357266) (xy 161.224032 -319.373875) (xy 161.273157 -319.398297) (xy 161.317962 -319.429956)
			(xy 161.338006 -319.448688) (xy 161.348895 -319.458553) (xy 161.374938 -319.472131) (xy 161.40377 -319.477729)
			(xy 161.433002 -319.474882) (xy 161.460212 -319.463828) (xy 161.483147 -319.445481) (xy 161.49193 -319.433702)
			(xy 161.498698 -319.424143) (xy 161.513314 -319.40584) (xy 161.52114 -319.397126) (xy 161.530655 -319.385924)
			(xy 161.543403 -319.359455) (xy 161.548095 -319.330453) (xy 161.544343 -319.301315) (xy 161.532458 -319.274447)
			(xy 161.513421 -319.252071) (xy 161.488806 -319.236034) (xy 161.460645 -319.227661) (xy 161.445956 -319.2272)
			(xy 159.6136 -319.2272) (xy 159.258 -319.5828) (xy 159.258 -320.6242) (xy 159.5374 -320.9036) (xy 160.155636 -320.9036)
			(xy 160.169065 -320.903185) (xy 160.194992 -320.89617) (xy 160.218192 -320.882636) (xy 160.237058 -320.863518)
			(xy 160.250284 -320.840142) (xy 160.256955 -320.814124) (xy 160.256609 -320.787267) (xy 160.249269 -320.761431)
			(xy 160.242758 -320.749676) (xy 160.230762 -320.728866) (xy 160.211858 -320.684709) (xy 160.199061 -320.638411)
			(xy 160.192604 -320.590813) (xy 160.192212 -320.566796) (xy 160.19271 -320.540147) (xy 160.200653 -320.487443)
			(xy 160.216363 -320.436513) (xy 160.239489 -320.388492) (xy 160.269513 -320.344455) (xy 160.305765 -320.305384)
			(xy 160.347436 -320.272153) (xy 160.393594 -320.245504) (xy 160.443208 -320.226032) (xy 160.49517 -320.214172)
			(xy 160.54832 -320.210189) (xy 160.60147 -320.214172) (xy 160.653432 -320.226032) (xy 160.703046 -320.245504)
			(xy 160.749204 -320.272153) (xy 160.790875 -320.305384) (xy 160.827127 -320.344455) (xy 160.857151 -320.388492)
			(xy 160.880277 -320.436513) (xy 160.895987 -320.487443) (xy 160.90393 -320.540147) (xy 160.904428 -320.566796)
			(xy 160.904034 -320.590813) (xy 160.897579 -320.638411) (xy 160.884783 -320.684709) (xy 160.865881 -320.728868)
			(xy 160.853882 -320.749676) (xy 160.847316 -320.761406) (xy 160.839969 -320.787255) (xy 160.839621 -320.814125)
			(xy 160.846296 -320.840156) (xy 160.859532 -320.863543) (xy 160.878411 -320.882667) (xy 160.901625 -320.896203)
			(xy 160.927568 -320.903214) (xy 160.941004 -320.9036) (xy 167.2336 -320.9036) (xy 167.291237 -320.961237)
			(xy 167.63999 -320.961237) (xy 167.63999 -320.907939) (xy 167.647933 -320.855235) (xy 167.663643 -320.804305)
			(xy 167.686769 -320.756284) (xy 167.716793 -320.712247) (xy 167.753045 -320.673176) (xy 167.794716 -320.639945)
			(xy 167.840874 -320.613296) (xy 167.890488 -320.593824) (xy 167.94245 -320.581964) (xy 167.9956 -320.577981)
			(xy 168.04875 -320.581964) (xy 168.100712 -320.593824) (xy 168.150326 -320.613296) (xy 168.196484 -320.639945)
			(xy 168.238155 -320.673176) (xy 168.274407 -320.712247) (xy 168.304431 -320.756284) (xy 168.327557 -320.804305)
			(xy 168.343267 -320.855235) (xy 168.35121 -320.907939) (xy 168.351708 -320.934588) (xy 168.35121 -320.961237)
			(xy 168.343267 -321.013941) (xy 168.327557 -321.064871) (xy 168.304431 -321.112892) (xy 168.274407 -321.156929)
			(xy 168.258701 -321.173856) (xy 168.971976 -321.173856) (xy 168.97251 -321.146594) (xy 168.98082 -321.092708)
			(xy 168.997254 -321.04072) (xy 169.021427 -320.991848) (xy 169.052773 -320.947237) (xy 169.07129 -320.927222)
			(xy 169.081209 -320.916226) (xy 169.09478 -320.88992) (xy 169.100227 -320.860826) (xy 169.097091 -320.831392)
			(xy 169.085637 -320.804098) (xy 169.076624 -320.792348) (xy 169.061457 -320.773185) (xy 169.035972 -320.731484)
			(xy 169.016427 -320.68669) (xy 169.00319 -320.639645) (xy 168.996509 -320.591232) (xy 168.996106 -320.566796)
			(xy 168.996604 -320.540147) (xy 169.004547 -320.487443) (xy 169.020257 -320.436513) (xy 169.043383 -320.388492)
			(xy 169.073407 -320.344455) (xy 169.109659 -320.305384) (xy 169.15133 -320.272153) (xy 169.197488 -320.245504)
			(xy 169.247102 -320.226032) (xy 169.299064 -320.214172) (xy 169.352214 -320.210189) (xy 169.405364 -320.214172)
			(xy 169.457326 -320.226032) (xy 169.50694 -320.245504) (xy 169.553098 -320.272153) (xy 169.594769 -320.305384)
			(xy 169.631021 -320.344455) (xy 169.661045 -320.388492) (xy 169.684171 -320.436513) (xy 169.699881 -320.487443)
			(xy 169.707824 -320.540147) (xy 169.708322 -320.566796) (xy 169.707831 -320.593445) (xy 171.85131 -320.593445)
			(xy 171.85131 -320.540147) (xy 171.859253 -320.487443) (xy 171.874963 -320.436513) (xy 171.898089 -320.388492)
			(xy 171.928113 -320.344455) (xy 171.964365 -320.305384) (xy 172.006036 -320.272153) (xy 172.052194 -320.245504)
			(xy 172.101808 -320.226032) (xy 172.15377 -320.214172) (xy 172.20692 -320.210189) (xy 172.26007 -320.214172)
			(xy 172.312032 -320.226032) (xy 172.361646 -320.245504) (xy 172.407804 -320.272153) (xy 172.449475 -320.305384)
			(xy 172.485727 -320.344455) (xy 172.515751 -320.388492) (xy 172.534608 -320.427649) (xy 175.944883 -320.427649)
			(xy 175.950365 -320.373766) (xy 175.963943 -320.321333) (xy 175.985305 -320.271562) (xy 176.013958 -320.2256)
			(xy 176.04924 -320.184506) (xy 176.090338 -320.149229) (xy 176.136305 -320.120583) (xy 176.186079 -320.099228)
			(xy 176.238513 -320.085656) (xy 176.292397 -320.080182) (xy 176.346489 -320.08293) (xy 176.399542 -320.093838)
			(xy 176.45033 -320.112653) (xy 176.497684 -320.138943) (xy 176.54051 -320.172101) (xy 176.577821 -320.211361)
			(xy 176.608757 -320.255819) (xy 176.632604 -320.304449) (xy 176.648811 -320.356129) (xy 176.657006 -320.409667)
			(xy 176.657508 -320.436748) (xy 176.657214 -320.457191) (xy 176.6525 -320.497805) (xy 176.64811 -320.517774)
			(xy 176.64542 -320.531376) (xy 176.646629 -320.559064) (xy 176.649155 -320.5668) (xy 178.755764 -320.5668)
			(xy 178.759748 -320.513644) (xy 178.771609 -320.461676) (xy 178.791084 -320.412057) (xy 178.817737 -320.365894)
			(xy 178.850973 -320.32422) (xy 178.890049 -320.287964) (xy 178.934092 -320.257938) (xy 178.982119 -320.234812)
			(xy 179.033056 -320.219102) (xy 179.085766 -320.21116) (xy 179.112418 -320.210688) (xy 179.140505 -320.211212)
			(xy 179.195981 -320.220047) (xy 179.249383 -320.237479) (xy 179.299386 -320.263077) (xy 179.344753 -320.296206)
			(xy 179.384357 -320.336044) (xy 179.401216 -320.358516) (xy 179.409643 -320.369387) (xy 179.43112 -320.386554)
			(xy 179.456394 -320.397377) (xy 179.483639 -320.401074) (xy 179.510884 -320.397377) (xy 179.536158 -320.386554)
			(xy 179.557635 -320.369387) (xy 179.566062 -320.358516) (xy 179.582909 -320.336033) (xy 179.622506 -320.296183)
			(xy 179.667872 -320.263048) (xy 179.71788 -320.237451) (xy 179.771289 -320.220029) (xy 179.826771 -320.211213)
			(xy 179.85486 -320.210688) (xy 179.881513 -320.211166) (xy 179.934224 -320.219106) (xy 179.985162 -320.234813)
			(xy 180.033191 -320.257938) (xy 180.077236 -320.287963) (xy 180.116314 -320.324217) (xy 180.149551 -320.365892)
			(xy 180.176206 -320.412055) (xy 180.195682 -320.461675) (xy 180.207544 -320.513644) (xy 180.211528 -320.5668)
			(xy 180.209531 -320.593445) (xy 184.084204 -320.593445) (xy 184.084204 -320.540147) (xy 184.092147 -320.487443)
			(xy 184.107857 -320.436513) (xy 184.130983 -320.388492) (xy 184.161007 -320.344455) (xy 184.197259 -320.305384)
			(xy 184.23893 -320.272153) (xy 184.285088 -320.245504) (xy 184.334702 -320.226032) (xy 184.386664 -320.214172)
			(xy 184.439814 -320.210189) (xy 184.492964 -320.214172) (xy 184.544926 -320.226032) (xy 184.59454 -320.245504)
			(xy 184.640698 -320.272153) (xy 184.682369 -320.305384) (xy 184.718621 -320.344455) (xy 184.748645 -320.388492)
			(xy 184.771771 -320.436513) (xy 184.787481 -320.487443) (xy 184.795424 -320.540147) (xy 184.795922 -320.566796)
			(xy 184.795424 -320.593445) (xy 186.98971 -320.593445) (xy 186.98971 -320.540147) (xy 186.997653 -320.487443)
			(xy 187.013363 -320.436513) (xy 187.036489 -320.388492) (xy 187.066513 -320.344455) (xy 187.102765 -320.305384)
			(xy 187.144436 -320.272153) (xy 187.190594 -320.245504) (xy 187.240208 -320.226032) (xy 187.29217 -320.214172)
			(xy 187.34532 -320.210189) (xy 187.39847 -320.214172) (xy 187.450432 -320.226032) (xy 187.500046 -320.245504)
			(xy 187.546204 -320.272153) (xy 187.587875 -320.305384) (xy 187.624127 -320.344455) (xy 187.650679 -320.3834)
			(xy 190.905401 -320.3834) (xy 190.909383 -320.330252) (xy 190.921243 -320.27829) (xy 190.940715 -320.228677)
			(xy 190.967364 -320.18252) (xy 191.000594 -320.140851) (xy 191.039664 -320.104599) (xy 191.0837 -320.074576)
			(xy 191.13172 -320.051451) (xy 191.182649 -320.035741) (xy 191.235351 -320.027798) (xy 191.262 -320.0273)
			(xy 191.28869 -320.027759) (xy 191.341473 -320.035726) (xy 191.392475 -320.051483) (xy 191.440554 -320.074674)
			(xy 191.484633 -320.104783) (xy 191.523724 -320.141133) (xy 191.556952 -320.18291) (xy 191.583572 -320.229179)
			(xy 191.593724 -320.253868) (xy 191.599213 -320.266562) (xy 191.615757 -320.288704) (xy 191.637635 -320.305595)
			(xy 191.663243 -320.315997) (xy 191.690702 -320.319148) (xy 191.718 -320.314816) (xy 191.743135 -320.303318)
			(xy 191.753998 -320.294762) (xy 191.773344 -320.278968) (xy 191.81563 -320.252395) (xy 191.861211 -320.231986)
			(xy 191.909196 -320.21814) (xy 191.958643 -320.211128) (xy 191.983614 -320.210688) (xy 192.010262 -320.211195)
			(xy 192.062963 -320.21914) (xy 192.113892 -320.234851) (xy 192.16191 -320.257977) (xy 192.205945 -320.288001)
			(xy 192.245013 -320.324253) (xy 192.278243 -320.365923) (xy 192.30489 -320.412079) (xy 192.324361 -320.461692)
			(xy 192.336221 -320.513652) (xy 192.340204 -320.5668) (xy 192.338207 -320.593445) (xy 194.48271 -320.593445)
			(xy 194.48271 -320.540147) (xy 194.490653 -320.487443) (xy 194.506363 -320.436513) (xy 194.529489 -320.388492)
			(xy 194.559513 -320.344455) (xy 194.595765 -320.305384) (xy 194.637436 -320.272153) (xy 194.683594 -320.245504)
			(xy 194.733208 -320.226032) (xy 194.78517 -320.214172) (xy 194.83832 -320.210189) (xy 194.89147 -320.214172)
			(xy 194.943432 -320.226032) (xy 194.993046 -320.245504) (xy 195.039204 -320.272153) (xy 195.080875 -320.305384)
			(xy 195.117127 -320.344455) (xy 195.147151 -320.388492) (xy 195.170277 -320.436513) (xy 195.185987 -320.487443)
			(xy 195.19393 -320.540147) (xy 195.194428 -320.566796) (xy 195.19393 -320.593445) (xy 199.171804 -320.593445)
			(xy 199.171804 -320.540147) (xy 199.179747 -320.487443) (xy 199.195457 -320.436513) (xy 199.218583 -320.388492)
			(xy 199.248607 -320.344455) (xy 199.284859 -320.305384) (xy 199.32653 -320.272153) (xy 199.372688 -320.245504)
			(xy 199.422302 -320.226032) (xy 199.474264 -320.214172) (xy 199.527414 -320.210189) (xy 199.580564 -320.214172)
			(xy 199.632526 -320.226032) (xy 199.68214 -320.245504) (xy 199.728298 -320.272153) (xy 199.769969 -320.305384)
			(xy 199.806221 -320.344455) (xy 199.836245 -320.388492) (xy 199.859371 -320.436513) (xy 199.875081 -320.487443)
			(xy 199.883024 -320.540147) (xy 199.883522 -320.566796) (xy 199.883024 -320.593445) (xy 202.05191 -320.593445)
			(xy 202.05191 -320.540147) (xy 202.059853 -320.487443) (xy 202.075563 -320.436513) (xy 202.098689 -320.388492)
			(xy 202.128713 -320.344455) (xy 202.164965 -320.305384) (xy 202.206636 -320.272153) (xy 202.252794 -320.245504)
			(xy 202.302408 -320.226032) (xy 202.35437 -320.214172) (xy 202.40752 -320.210189) (xy 202.46067 -320.214172)
			(xy 202.512632 -320.226032) (xy 202.562246 -320.245504) (xy 202.608404 -320.272153) (xy 202.650075 -320.305384)
			(xy 202.686327 -320.344455) (xy 202.716351 -320.388492) (xy 202.739477 -320.436513) (xy 202.755187 -320.487443)
			(xy 202.76313 -320.540147) (xy 202.763628 -320.566796) (xy 202.76313 -320.593445) (xy 206.715604 -320.593445)
			(xy 206.715604 -320.540147) (xy 206.723547 -320.487443) (xy 206.739257 -320.436513) (xy 206.762383 -320.388492)
			(xy 206.792407 -320.344455) (xy 206.828659 -320.305384) (xy 206.87033 -320.272153) (xy 206.916488 -320.245504)
			(xy 206.966102 -320.226032) (xy 207.018064 -320.214172) (xy 207.071214 -320.210189) (xy 207.124364 -320.214172)
			(xy 207.176326 -320.226032) (xy 207.22594 -320.245504) (xy 207.272098 -320.272153) (xy 207.313769 -320.305384)
			(xy 207.350021 -320.344455) (xy 207.380045 -320.388492) (xy 207.403171 -320.436513) (xy 207.418881 -320.487443)
			(xy 207.426824 -320.540147) (xy 207.427322 -320.566796) (xy 207.426824 -320.593445) (xy 209.63889 -320.593445)
			(xy 209.63889 -320.540147) (xy 209.646833 -320.487443) (xy 209.662543 -320.436513) (xy 209.685669 -320.388492)
			(xy 209.715693 -320.344455) (xy 209.751945 -320.305384) (xy 209.793616 -320.272153) (xy 209.839774 -320.245504)
			(xy 209.889388 -320.226032) (xy 209.94135 -320.214172) (xy 209.9945 -320.210189) (xy 210.04765 -320.214172)
			(xy 210.099612 -320.226032) (xy 210.149226 -320.245504) (xy 210.195384 -320.272153) (xy 210.237055 -320.305384)
			(xy 210.273307 -320.344455) (xy 210.303331 -320.388492) (xy 210.326457 -320.436513) (xy 210.342167 -320.487443)
			(xy 210.35011 -320.540147) (xy 210.350608 -320.566796) (xy 210.35011 -320.593445) (xy 214.259404 -320.593445)
			(xy 214.259404 -320.540147) (xy 214.267347 -320.487443) (xy 214.283057 -320.436513) (xy 214.306183 -320.388492)
			(xy 214.336207 -320.344455) (xy 214.372459 -320.305384) (xy 214.41413 -320.272153) (xy 214.460288 -320.245504)
			(xy 214.509902 -320.226032) (xy 214.561864 -320.214172) (xy 214.615014 -320.210189) (xy 214.668164 -320.214172)
			(xy 214.720126 -320.226032) (xy 214.76974 -320.245504) (xy 214.815898 -320.272153) (xy 214.857569 -320.305384)
			(xy 214.893821 -320.344455) (xy 214.923845 -320.388492) (xy 214.946971 -320.436513) (xy 214.962681 -320.487443)
			(xy 214.970624 -320.540147) (xy 214.971122 -320.566796) (xy 214.970624 -320.593445) (xy 254.620004 -320.593445)
			(xy 254.620004 -320.540147) (xy 254.627947 -320.487443) (xy 254.643657 -320.436513) (xy 254.666783 -320.388492)
			(xy 254.696807 -320.344455) (xy 254.733059 -320.305384) (xy 254.77473 -320.272153) (xy 254.820888 -320.245504)
			(xy 254.870502 -320.226032) (xy 254.922464 -320.214172) (xy 254.975614 -320.210189) (xy 255.028764 -320.214172)
			(xy 255.080726 -320.226032) (xy 255.13034 -320.245504) (xy 255.176498 -320.272153) (xy 255.218169 -320.305384)
			(xy 255.254421 -320.344455) (xy 255.284445 -320.388492) (xy 255.307571 -320.436513) (xy 255.323281 -320.487443)
			(xy 255.331224 -320.540147) (xy 255.331722 -320.566796) (xy 255.331224 -320.593445) (xy 258.720072 -320.593445)
			(xy 258.720072 -320.540147) (xy 258.728015 -320.487443) (xy 258.743725 -320.436513) (xy 258.766851 -320.388492)
			(xy 258.796875 -320.344455) (xy 258.833127 -320.305384) (xy 258.874798 -320.272153) (xy 258.920956 -320.245504)
			(xy 258.97057 -320.226032) (xy 259.022532 -320.214172) (xy 259.075682 -320.210189) (xy 259.128832 -320.214172)
			(xy 259.180794 -320.226032) (xy 259.230408 -320.245504) (xy 259.276566 -320.272153) (xy 259.318237 -320.305384)
			(xy 259.354489 -320.344455) (xy 259.384513 -320.388492) (xy 259.388782 -320.397357) (xy 261.47521 -320.397357)
			(xy 261.47521 -320.344059) (xy 261.483153 -320.291355) (xy 261.498863 -320.240425) (xy 261.521989 -320.192404)
			(xy 261.552013 -320.148367) (xy 261.588265 -320.109296) (xy 261.629936 -320.076065) (xy 261.676094 -320.049416)
			(xy 261.725708 -320.029944) (xy 261.77767 -320.018084) (xy 261.83082 -320.014101) (xy 261.88397 -320.018084)
			(xy 261.935932 -320.029944) (xy 261.985546 -320.049416) (xy 262.031704 -320.076065) (xy 262.073375 -320.109296)
			(xy 262.109627 -320.148367) (xy 262.139651 -320.192404) (xy 262.162777 -320.240425) (xy 262.178487 -320.291355)
			(xy 262.18643 -320.344059) (xy 262.186928 -320.370708) (xy 262.18643 -320.397357) (xy 262.178487 -320.450061)
			(xy 262.162777 -320.500991) (xy 262.139651 -320.549012) (xy 262.109627 -320.593049) (xy 262.073375 -320.63212)
			(xy 262.031704 -320.665351) (xy 261.985546 -320.692) (xy 261.935932 -320.711472) (xy 261.88397 -320.723332)
			(xy 261.83082 -320.727316) (xy 261.77767 -320.723332) (xy 261.725708 -320.711472) (xy 261.676094 -320.692)
			(xy 261.629936 -320.665351) (xy 261.588265 -320.63212) (xy 261.552013 -320.593049) (xy 261.521989 -320.549012)
			(xy 261.498863 -320.500991) (xy 261.483153 -320.450061) (xy 261.47521 -320.397357) (xy 259.388782 -320.397357)
			(xy 259.407639 -320.436513) (xy 259.423349 -320.487443) (xy 259.431292 -320.540147) (xy 259.43179 -320.566796)
			(xy 259.431292 -320.593445) (xy 259.423349 -320.646149) (xy 259.407639 -320.697079) (xy 259.384513 -320.7451)
			(xy 259.354489 -320.789137) (xy 259.318237 -320.828208) (xy 259.276566 -320.861439) (xy 259.230408 -320.888088)
			(xy 259.180794 -320.90756) (xy 259.128832 -320.91942) (xy 259.075682 -320.923404) (xy 259.022532 -320.91942)
			(xy 258.97057 -320.90756) (xy 258.920956 -320.888088) (xy 258.874798 -320.861439) (xy 258.833127 -320.828208)
			(xy 258.796875 -320.789137) (xy 258.766851 -320.7451) (xy 258.743725 -320.697079) (xy 258.728015 -320.646149)
			(xy 258.720072 -320.593445) (xy 255.331224 -320.593445) (xy 255.323281 -320.646149) (xy 255.307571 -320.697079)
			(xy 255.284445 -320.7451) (xy 255.254421 -320.789137) (xy 255.218169 -320.828208) (xy 255.176498 -320.861439)
			(xy 255.13034 -320.888088) (xy 255.080726 -320.90756) (xy 255.028764 -320.91942) (xy 254.975614 -320.923404)
			(xy 254.922464 -320.91942) (xy 254.870502 -320.90756) (xy 254.820888 -320.888088) (xy 254.77473 -320.861439)
			(xy 254.733059 -320.828208) (xy 254.696807 -320.789137) (xy 254.666783 -320.7451) (xy 254.643657 -320.697079)
			(xy 254.627947 -320.646149) (xy 254.620004 -320.593445) (xy 214.970624 -320.593445) (xy 214.962681 -320.646149)
			(xy 214.946971 -320.697079) (xy 214.923845 -320.7451) (xy 214.893821 -320.789137) (xy 214.857569 -320.828208)
			(xy 214.815898 -320.861439) (xy 214.76974 -320.888088) (xy 214.720126 -320.90756) (xy 214.668164 -320.91942)
			(xy 214.615014 -320.923404) (xy 214.561864 -320.91942) (xy 214.509902 -320.90756) (xy 214.460288 -320.888088)
			(xy 214.41413 -320.861439) (xy 214.372459 -320.828208) (xy 214.336207 -320.789137) (xy 214.306183 -320.7451)
			(xy 214.283057 -320.697079) (xy 214.267347 -320.646149) (xy 214.259404 -320.593445) (xy 210.35011 -320.593445)
			(xy 210.342167 -320.646149) (xy 210.326457 -320.697079) (xy 210.303331 -320.7451) (xy 210.273307 -320.789137)
			(xy 210.237055 -320.828208) (xy 210.195384 -320.861439) (xy 210.149226 -320.888088) (xy 210.099612 -320.90756)
			(xy 210.04765 -320.91942) (xy 209.9945 -320.923404) (xy 209.94135 -320.91942) (xy 209.889388 -320.90756)
			(xy 209.839774 -320.888088) (xy 209.793616 -320.861439) (xy 209.751945 -320.828208) (xy 209.715693 -320.789137)
			(xy 209.685669 -320.7451) (xy 209.662543 -320.697079) (xy 209.646833 -320.646149) (xy 209.63889 -320.593445)
			(xy 207.426824 -320.593445) (xy 207.418881 -320.646149) (xy 207.403171 -320.697079) (xy 207.380045 -320.7451)
			(xy 207.350021 -320.789137) (xy 207.313769 -320.828208) (xy 207.272098 -320.861439) (xy 207.22594 -320.888088)
			(xy 207.176326 -320.90756) (xy 207.124364 -320.91942) (xy 207.071214 -320.923404) (xy 207.018064 -320.91942)
			(xy 206.966102 -320.90756) (xy 206.916488 -320.888088) (xy 206.87033 -320.861439) (xy 206.828659 -320.828208)
			(xy 206.792407 -320.789137) (xy 206.762383 -320.7451) (xy 206.739257 -320.697079) (xy 206.723547 -320.646149)
			(xy 206.715604 -320.593445) (xy 202.76313 -320.593445) (xy 202.755187 -320.646149) (xy 202.739477 -320.697079)
			(xy 202.716351 -320.7451) (xy 202.686327 -320.789137) (xy 202.650075 -320.828208) (xy 202.608404 -320.861439)
			(xy 202.562246 -320.888088) (xy 202.512632 -320.90756) (xy 202.46067 -320.91942) (xy 202.40752 -320.923404)
			(xy 202.35437 -320.91942) (xy 202.302408 -320.90756) (xy 202.252794 -320.888088) (xy 202.206636 -320.861439)
			(xy 202.164965 -320.828208) (xy 202.128713 -320.789137) (xy 202.098689 -320.7451) (xy 202.075563 -320.697079)
			(xy 202.059853 -320.646149) (xy 202.05191 -320.593445) (xy 199.883024 -320.593445) (xy 199.875081 -320.646149)
			(xy 199.859371 -320.697079) (xy 199.836245 -320.7451) (xy 199.806221 -320.789137) (xy 199.769969 -320.828208)
			(xy 199.728298 -320.861439) (xy 199.68214 -320.888088) (xy 199.632526 -320.90756) (xy 199.580564 -320.91942)
			(xy 199.527414 -320.923404) (xy 199.474264 -320.91942) (xy 199.422302 -320.90756) (xy 199.372688 -320.888088)
			(xy 199.32653 -320.861439) (xy 199.284859 -320.828208) (xy 199.248607 -320.789137) (xy 199.218583 -320.7451)
			(xy 199.195457 -320.697079) (xy 199.179747 -320.646149) (xy 199.171804 -320.593445) (xy 195.19393 -320.593445)
			(xy 195.185987 -320.646149) (xy 195.170277 -320.697079) (xy 195.147151 -320.7451) (xy 195.117127 -320.789137)
			(xy 195.080875 -320.828208) (xy 195.039204 -320.861439) (xy 194.993046 -320.888088) (xy 194.943432 -320.90756)
			(xy 194.89147 -320.91942) (xy 194.83832 -320.923404) (xy 194.78517 -320.91942) (xy 194.733208 -320.90756)
			(xy 194.683594 -320.888088) (xy 194.637436 -320.861439) (xy 194.595765 -320.828208) (xy 194.559513 -320.789137)
			(xy 194.529489 -320.7451) (xy 194.506363 -320.697079) (xy 194.490653 -320.646149) (xy 194.48271 -320.593445)
			(xy 192.338207 -320.593445) (xy 192.336221 -320.619948) (xy 192.324361 -320.671908) (xy 192.30489 -320.721521)
			(xy 192.278243 -320.767677) (xy 192.245013 -320.809347) (xy 192.205945 -320.845599) (xy 192.16191 -320.875623)
			(xy 192.113892 -320.898749) (xy 192.062963 -320.91446) (xy 192.010262 -320.922405) (xy 191.983614 -320.922904)
			(xy 191.956924 -320.92243) (xy 191.904143 -320.914465) (xy 191.853141 -320.898711) (xy 191.805062 -320.875521)
			(xy 191.760983 -320.845415) (xy 191.721892 -320.809067) (xy 191.688663 -320.767291) (xy 191.662042 -320.721024)
			(xy 191.65189 -320.696336) (xy 191.646381 -320.683652) (xy 191.62984 -320.661511) (xy 191.607966 -320.64462)
			(xy 191.582363 -320.634216) (xy 191.554906 -320.631064) (xy 191.527611 -320.635394) (xy 191.502478 -320.646888)
			(xy 191.491616 -320.655442) (xy 191.472266 -320.67123) (xy 191.429981 -320.697804) (xy 191.3844 -320.718214)
			(xy 191.336417 -320.732062) (xy 191.28697 -320.739075) (xy 191.262 -320.739516) (xy 191.235351 -320.739002)
			(xy 191.182649 -320.731059) (xy 191.13172 -320.715349) (xy 191.0837 -320.692224) (xy 191.039664 -320.662201)
			(xy 191.000594 -320.625949) (xy 190.967364 -320.58428) (xy 190.940715 -320.538123) (xy 190.921243 -320.48851)
			(xy 190.909383 -320.436548) (xy 190.905401 -320.3834) (xy 187.650679 -320.3834) (xy 187.654151 -320.388492)
			(xy 187.677277 -320.436513) (xy 187.692987 -320.487443) (xy 187.70093 -320.540147) (xy 187.701428 -320.566796)
			(xy 187.70093 -320.593445) (xy 187.692987 -320.646149) (xy 187.677277 -320.697079) (xy 187.654151 -320.7451)
			(xy 187.624127 -320.789137) (xy 187.587875 -320.828208) (xy 187.546204 -320.861439) (xy 187.500046 -320.888088)
			(xy 187.450432 -320.90756) (xy 187.39847 -320.91942) (xy 187.34532 -320.923404) (xy 187.29217 -320.91942)
			(xy 187.240208 -320.90756) (xy 187.190594 -320.888088) (xy 187.144436 -320.861439) (xy 187.102765 -320.828208)
			(xy 187.066513 -320.789137) (xy 187.036489 -320.7451) (xy 187.013363 -320.697079) (xy 186.997653 -320.646149)
			(xy 186.98971 -320.593445) (xy 184.795424 -320.593445) (xy 184.787481 -320.646149) (xy 184.771771 -320.697079)
			(xy 184.748645 -320.7451) (xy 184.718621 -320.789137) (xy 184.682369 -320.828208) (xy 184.640698 -320.861439)
			(xy 184.59454 -320.888088) (xy 184.544926 -320.90756) (xy 184.492964 -320.91942) (xy 184.439814 -320.923404)
			(xy 184.386664 -320.91942) (xy 184.334702 -320.90756) (xy 184.285088 -320.888088) (xy 184.23893 -320.861439)
			(xy 184.197259 -320.828208) (xy 184.161007 -320.789137) (xy 184.130983 -320.7451) (xy 184.107857 -320.697079)
			(xy 184.092147 -320.646149) (xy 184.084204 -320.593445) (xy 180.209531 -320.593445) (xy 180.207544 -320.619956)
			(xy 180.195682 -320.671925) (xy 180.176206 -320.721545) (xy 180.149551 -320.767708) (xy 180.116314 -320.809383)
			(xy 180.077236 -320.845637) (xy 180.033191 -320.875662) (xy 179.985162 -320.898787) (xy 179.934224 -320.914494)
			(xy 179.881513 -320.922434) (xy 179.85486 -320.922904) (xy 179.826772 -320.922399) (xy 179.771295 -320.913561)
			(xy 179.717893 -320.896125) (xy 179.667889 -320.870523) (xy 179.622523 -320.837391) (xy 179.58292 -320.797549)
			(xy 179.566062 -320.775076) (xy 179.557662 -320.764161) (xy 179.536206 -320.746911) (xy 179.510917 -320.736031)
			(xy 179.483639 -320.732314) (xy 179.456361 -320.736031) (xy 179.431072 -320.746911) (xy 179.409616 -320.764161)
			(xy 179.401216 -320.775076) (xy 179.38438 -320.797567) (xy 179.344781 -320.837418) (xy 179.299413 -320.870552)
			(xy 179.249402 -320.896147) (xy 179.195992 -320.913568) (xy 179.140508 -320.922381) (xy 179.112418 -320.922904)
			(xy 179.085766 -320.92244) (xy 179.033056 -320.914498) (xy 178.982119 -320.898788) (xy 178.934092 -320.875662)
			(xy 178.890049 -320.845636) (xy 178.850973 -320.80938) (xy 178.817737 -320.767706) (xy 178.791084 -320.721543)
			(xy 178.771609 -320.671924) (xy 178.759748 -320.619956) (xy 178.755764 -320.5668) (xy 176.649155 -320.5668)
			(xy 176.655233 -320.58541) (xy 176.670598 -320.608477) (xy 176.691594 -320.626567) (xy 176.716679 -320.638353)
			(xy 176.744008 -320.642966) (xy 176.757838 -320.64198) (xy 176.795684 -320.639948) (xy 176.822766 -320.640481)
			(xy 176.876307 -320.64868) (xy 176.927988 -320.664894) (xy 176.976618 -320.688746) (xy 177.021075 -320.719688)
			(xy 177.060334 -320.757005) (xy 177.093489 -320.799836) (xy 177.119776 -320.847195) (xy 177.138587 -320.897988)
			(xy 177.149491 -320.951044) (xy 177.152233 -321.005139) (xy 177.146753 -321.059026) (xy 177.133175 -321.111461)
			(xy 177.111814 -321.161236) (xy 177.083161 -321.207202) (xy 177.047878 -321.248298) (xy 177.006779 -321.283578)
			(xy 176.960811 -321.312227) (xy 176.912771 -321.332839) (xy 179.978548 -321.332839) (xy 179.978548 -321.279541)
			(xy 179.986491 -321.226837) (xy 180.002201 -321.175907) (xy 180.025327 -321.127886) (xy 180.055351 -321.083849)
			(xy 180.091603 -321.044778) (xy 180.133274 -321.011547) (xy 180.179432 -320.984898) (xy 180.229046 -320.965426)
			(xy 180.281008 -320.953566) (xy 180.334158 -320.949583) (xy 180.387308 -320.953566) (xy 180.43927 -320.965426)
			(xy 180.488884 -320.984898) (xy 180.535042 -321.011547) (xy 180.576713 -321.044778) (xy 180.612965 -321.083849)
			(xy 180.642989 -321.127886) (xy 180.666115 -321.175907) (xy 180.681825 -321.226837) (xy 180.689768 -321.279541)
			(xy 180.690266 -321.30619) (xy 180.689768 -321.332839) (xy 180.681825 -321.385543) (xy 180.666115 -321.436473)
			(xy 180.662813 -321.443329) (xy 184.075568 -321.443329) (xy 184.075568 -321.390031) (xy 184.083511 -321.337327)
			(xy 184.099221 -321.286397) (xy 184.122347 -321.238376) (xy 184.152371 -321.194339) (xy 184.188623 -321.155268)
			(xy 184.230294 -321.122037) (xy 184.276452 -321.095388) (xy 184.326066 -321.075916) (xy 184.378028 -321.064056)
			(xy 184.431178 -321.060073) (xy 184.484328 -321.064056) (xy 184.53629 -321.075916) (xy 184.585904 -321.095388)
			(xy 184.632062 -321.122037) (xy 184.673733 -321.155268) (xy 184.709985 -321.194339) (xy 184.740009 -321.238376)
			(xy 184.763135 -321.286397) (xy 184.778845 -321.337327) (xy 184.786788 -321.390031) (xy 184.787286 -321.41668)
			(xy 184.786788 -321.443329) (xy 187.527428 -321.443329) (xy 187.527428 -321.390031) (xy 187.535371 -321.337327)
			(xy 187.551081 -321.286397) (xy 187.574207 -321.238376) (xy 187.604231 -321.194339) (xy 187.640483 -321.155268)
			(xy 187.682154 -321.122037) (xy 187.728312 -321.095388) (xy 187.777926 -321.075916) (xy 187.829888 -321.064056)
			(xy 187.883038 -321.060073) (xy 187.936188 -321.064056) (xy 187.98815 -321.075916) (xy 188.037764 -321.095388)
			(xy 188.083922 -321.122037) (xy 188.125593 -321.155268) (xy 188.161845 -321.194339) (xy 188.191869 -321.238376)
			(xy 188.214995 -321.286397) (xy 188.230705 -321.337327) (xy 188.238648 -321.390031) (xy 188.239146 -321.41668)
			(xy 188.238648 -321.443329) (xy 191.616828 -321.443329) (xy 191.616828 -321.390031) (xy 191.624771 -321.337327)
			(xy 191.640481 -321.286397) (xy 191.663607 -321.238376) (xy 191.693631 -321.194339) (xy 191.729883 -321.155268)
			(xy 191.771554 -321.122037) (xy 191.817712 -321.095388) (xy 191.867326 -321.075916) (xy 191.919288 -321.064056)
			(xy 191.972438 -321.060073) (xy 192.025588 -321.064056) (xy 192.07755 -321.075916) (xy 192.127164 -321.095388)
			(xy 192.173322 -321.122037) (xy 192.214993 -321.155268) (xy 192.251245 -321.194339) (xy 192.281269 -321.238376)
			(xy 192.304395 -321.286397) (xy 192.320105 -321.337327) (xy 192.328048 -321.390031) (xy 192.328546 -321.41668)
			(xy 192.328048 -321.443329) (xy 195.071736 -321.443329) (xy 195.071736 -321.390031) (xy 195.079679 -321.337327)
			(xy 195.095389 -321.286397) (xy 195.118515 -321.238376) (xy 195.148539 -321.194339) (xy 195.184791 -321.155268)
			(xy 195.226462 -321.122037) (xy 195.27262 -321.095388) (xy 195.322234 -321.075916) (xy 195.374196 -321.064056)
			(xy 195.427346 -321.060073) (xy 195.480496 -321.064056) (xy 195.532458 -321.075916) (xy 195.582072 -321.095388)
			(xy 195.62823 -321.122037) (xy 195.669901 -321.155268) (xy 195.706153 -321.194339) (xy 195.736177 -321.238376)
			(xy 195.759303 -321.286397) (xy 195.775013 -321.337327) (xy 195.782956 -321.390031) (xy 195.783454 -321.41668)
			(xy 195.782956 -321.443329) (xy 199.171804 -321.443329) (xy 199.171804 -321.390031) (xy 199.179747 -321.337327)
			(xy 199.195457 -321.286397) (xy 199.218583 -321.238376) (xy 199.248607 -321.194339) (xy 199.284859 -321.155268)
			(xy 199.32653 -321.122037) (xy 199.372688 -321.095388) (xy 199.422302 -321.075916) (xy 199.474264 -321.064056)
			(xy 199.527414 -321.060073) (xy 199.580564 -321.064056) (xy 199.632526 -321.075916) (xy 199.68214 -321.095388)
			(xy 199.728298 -321.122037) (xy 199.769969 -321.155268) (xy 199.806221 -321.194339) (xy 199.836245 -321.238376)
			(xy 199.859371 -321.286397) (xy 199.875081 -321.337327) (xy 199.883024 -321.390031) (xy 199.883522 -321.41668)
			(xy 199.883024 -321.443329) (xy 202.615536 -321.443329) (xy 202.615536 -321.390031) (xy 202.623479 -321.337327)
			(xy 202.639189 -321.286397) (xy 202.662315 -321.238376) (xy 202.692339 -321.194339) (xy 202.728591 -321.155268)
			(xy 202.770262 -321.122037) (xy 202.81642 -321.095388) (xy 202.866034 -321.075916) (xy 202.917996 -321.064056)
			(xy 202.971146 -321.060073) (xy 203.024296 -321.064056) (xy 203.076258 -321.075916) (xy 203.125872 -321.095388)
			(xy 203.17203 -321.122037) (xy 203.213701 -321.155268) (xy 203.249953 -321.194339) (xy 203.279977 -321.238376)
			(xy 203.303103 -321.286397) (xy 203.318813 -321.337327) (xy 203.326756 -321.390031) (xy 203.327254 -321.41668)
			(xy 203.326756 -321.443329) (xy 206.715604 -321.443329) (xy 206.715604 -321.390031) (xy 206.723547 -321.337327)
			(xy 206.739257 -321.286397) (xy 206.762383 -321.238376) (xy 206.792407 -321.194339) (xy 206.828659 -321.155268)
			(xy 206.87033 -321.122037) (xy 206.916488 -321.095388) (xy 206.966102 -321.075916) (xy 207.018064 -321.064056)
			(xy 207.071214 -321.060073) (xy 207.124364 -321.064056) (xy 207.176326 -321.075916) (xy 207.22594 -321.095388)
			(xy 207.272098 -321.122037) (xy 207.313769 -321.155268) (xy 207.350021 -321.194339) (xy 207.380045 -321.238376)
			(xy 207.403171 -321.286397) (xy 207.418881 -321.337327) (xy 207.426824 -321.390031) (xy 207.427322 -321.41668)
			(xy 207.426824 -321.443329) (xy 210.159336 -321.443329) (xy 210.159336 -321.390031) (xy 210.167279 -321.337327)
			(xy 210.182989 -321.286397) (xy 210.206115 -321.238376) (xy 210.236139 -321.194339) (xy 210.272391 -321.155268)
			(xy 210.314062 -321.122037) (xy 210.36022 -321.095388) (xy 210.409834 -321.075916) (xy 210.461796 -321.064056)
			(xy 210.514946 -321.060073) (xy 210.568096 -321.064056) (xy 210.620058 -321.075916) (xy 210.669672 -321.095388)
			(xy 210.71583 -321.122037) (xy 210.757501 -321.155268) (xy 210.793753 -321.194339) (xy 210.823777 -321.238376)
			(xy 210.846903 -321.286397) (xy 210.862613 -321.337327) (xy 210.870556 -321.390031) (xy 210.871054 -321.41668)
			(xy 210.870556 -321.443329) (xy 214.259404 -321.443329) (xy 214.259404 -321.390031) (xy 214.267347 -321.337327)
			(xy 214.283057 -321.286397) (xy 214.306183 -321.238376) (xy 214.336207 -321.194339) (xy 214.372459 -321.155268)
			(xy 214.41413 -321.122037) (xy 214.460288 -321.095388) (xy 214.509902 -321.075916) (xy 214.561864 -321.064056)
			(xy 214.615014 -321.060073) (xy 214.668164 -321.064056) (xy 214.720126 -321.075916) (xy 214.76974 -321.095388)
			(xy 214.815898 -321.122037) (xy 214.857569 -321.155268) (xy 214.893821 -321.194339) (xy 214.923845 -321.238376)
			(xy 214.946971 -321.286397) (xy 214.959109 -321.325748) (xy 247.496582 -321.325748) (xy 247.500653 -321.270126)
			(xy 247.512779 -321.215689) (xy 247.532702 -321.163598) (xy 247.559998 -321.114963) (xy 247.594084 -321.07082)
			(xy 247.634233 -321.032111) (xy 247.679591 -320.99966) (xy 247.729191 -320.974159) (xy 247.781975 -320.956152)
			(xy 247.836818 -320.946022) (xy 247.892552 -320.943985) (xy 247.947989 -320.950085) (xy 247.961499 -320.953617)
			(xy 265.05661 -320.953617) (xy 265.05661 -320.900319) (xy 265.064553 -320.847615) (xy 265.080263 -320.796685)
			(xy 265.103389 -320.748664) (xy 265.133413 -320.704627) (xy 265.169665 -320.665556) (xy 265.211336 -320.632325)
			(xy 265.257494 -320.605676) (xy 265.307108 -320.586204) (xy 265.35907 -320.574344) (xy 265.41222 -320.570361)
			(xy 265.46537 -320.574344) (xy 265.517332 -320.586204) (xy 265.535782 -320.593445) (xy 266.263872 -320.593445)
			(xy 266.263872 -320.540147) (xy 266.271815 -320.487443) (xy 266.287525 -320.436513) (xy 266.310651 -320.388492)
			(xy 266.340675 -320.344455) (xy 266.376927 -320.305384) (xy 266.418598 -320.272153) (xy 266.464756 -320.245504)
			(xy 266.51437 -320.226032) (xy 266.566332 -320.214172) (xy 266.619482 -320.210189) (xy 266.672632 -320.214172)
			(xy 266.724594 -320.226032) (xy 266.774208 -320.245504) (xy 266.820366 -320.272153) (xy 266.862037 -320.305384)
			(xy 266.898289 -320.344455) (xy 266.928313 -320.388492) (xy 266.951439 -320.436513) (xy 266.967149 -320.487443)
			(xy 266.975092 -320.540147) (xy 266.97559 -320.566796) (xy 266.975092 -320.593445) (xy 269.22221 -320.593445)
			(xy 269.22221 -320.540147) (xy 269.230153 -320.487443) (xy 269.245863 -320.436513) (xy 269.268989 -320.388492)
			(xy 269.299013 -320.344455) (xy 269.335265 -320.305384) (xy 269.376936 -320.272153) (xy 269.423094 -320.245504)
			(xy 269.472708 -320.226032) (xy 269.52467 -320.214172) (xy 269.57782 -320.210189) (xy 269.63097 -320.214172)
			(xy 269.682932 -320.226032) (xy 269.732546 -320.245504) (xy 269.778704 -320.272153) (xy 269.820375 -320.305384)
			(xy 269.856627 -320.344455) (xy 269.886651 -320.388492) (xy 269.909777 -320.436513) (xy 269.925487 -320.487443)
			(xy 269.93343 -320.540147) (xy 269.933928 -320.566796) (xy 269.93343 -320.593445) (xy 273.807672 -320.593445)
			(xy 273.807672 -320.540147) (xy 273.815615 -320.487443) (xy 273.831325 -320.436513) (xy 273.854451 -320.388492)
			(xy 273.884475 -320.344455) (xy 273.920727 -320.305384) (xy 273.962398 -320.272153) (xy 274.008556 -320.245504)
			(xy 274.05817 -320.226032) (xy 274.110132 -320.214172) (xy 274.163282 -320.210189) (xy 274.216432 -320.214172)
			(xy 274.268394 -320.226032) (xy 274.318008 -320.245504) (xy 274.364166 -320.272153) (xy 274.405837 -320.305384)
			(xy 274.442089 -320.344455) (xy 274.472113 -320.388492) (xy 274.495239 -320.436513) (xy 274.510949 -320.487443)
			(xy 274.518892 -320.540147) (xy 274.51939 -320.566796) (xy 274.518892 -320.593445) (xy 276.75839 -320.593445)
			(xy 276.75839 -320.540147) (xy 276.766333 -320.487443) (xy 276.782043 -320.436513) (xy 276.805169 -320.388492)
			(xy 276.835193 -320.344455) (xy 276.871445 -320.305384) (xy 276.913116 -320.272153) (xy 276.959274 -320.245504)
			(xy 277.008888 -320.226032) (xy 277.06085 -320.214172) (xy 277.114 -320.210189) (xy 277.16715 -320.214172)
			(xy 277.219112 -320.226032) (xy 277.268726 -320.245504) (xy 277.314884 -320.272153) (xy 277.356555 -320.305384)
			(xy 277.392807 -320.344455) (xy 277.422831 -320.388492) (xy 277.445957 -320.436513) (xy 277.461667 -320.487443)
			(xy 277.46961 -320.540147) (xy 277.470108 -320.566796) (xy 277.46961 -320.593445) (xy 277.461667 -320.646149)
			(xy 277.445957 -320.697079) (xy 277.422831 -320.7451) (xy 277.392807 -320.789137) (xy 277.356555 -320.828208)
			(xy 277.314884 -320.861439) (xy 277.268726 -320.888088) (xy 277.219112 -320.90756) (xy 277.16715 -320.91942)
			(xy 277.114 -320.923404) (xy 277.06085 -320.91942) (xy 277.008888 -320.90756) (xy 276.959274 -320.888088)
			(xy 276.913116 -320.861439) (xy 276.871445 -320.828208) (xy 276.835193 -320.789137) (xy 276.805169 -320.7451)
			(xy 276.782043 -320.697079) (xy 276.766333 -320.646149) (xy 276.75839 -320.593445) (xy 274.518892 -320.593445)
			(xy 274.510949 -320.646149) (xy 274.495239 -320.697079) (xy 274.472113 -320.7451) (xy 274.442089 -320.789137)
			(xy 274.405837 -320.828208) (xy 274.364166 -320.861439) (xy 274.318008 -320.888088) (xy 274.268394 -320.90756)
			(xy 274.216432 -320.91942) (xy 274.163282 -320.923404) (xy 274.110132 -320.91942) (xy 274.05817 -320.90756)
			(xy 274.008556 -320.888088) (xy 273.962398 -320.861439) (xy 273.920727 -320.828208) (xy 273.884475 -320.789137)
			(xy 273.854451 -320.7451) (xy 273.831325 -320.697079) (xy 273.815615 -320.646149) (xy 273.807672 -320.593445)
			(xy 269.93343 -320.593445) (xy 269.925487 -320.646149) (xy 269.909777 -320.697079) (xy 269.886651 -320.7451)
			(xy 269.856627 -320.789137) (xy 269.820375 -320.828208) (xy 269.778704 -320.861439) (xy 269.732546 -320.888088)
			(xy 269.682932 -320.90756) (xy 269.63097 -320.91942) (xy 269.57782 -320.923404) (xy 269.52467 -320.91942)
			(xy 269.472708 -320.90756) (xy 269.423094 -320.888088) (xy 269.376936 -320.861439) (xy 269.335265 -320.828208)
			(xy 269.299013 -320.789137) (xy 269.268989 -320.7451) (xy 269.245863 -320.697079) (xy 269.230153 -320.646149)
			(xy 269.22221 -320.593445) (xy 266.975092 -320.593445) (xy 266.967149 -320.646149) (xy 266.951439 -320.697079)
			(xy 266.928313 -320.7451) (xy 266.898289 -320.789137) (xy 266.862037 -320.828208) (xy 266.820366 -320.861439)
			(xy 266.774208 -320.888088) (xy 266.724594 -320.90756) (xy 266.672632 -320.91942) (xy 266.619482 -320.923404)
			(xy 266.566332 -320.91942) (xy 266.51437 -320.90756) (xy 266.464756 -320.888088) (xy 266.418598 -320.861439)
			(xy 266.376927 -320.828208) (xy 266.340675 -320.789137) (xy 266.310651 -320.7451) (xy 266.287525 -320.697079)
			(xy 266.271815 -320.646149) (xy 266.263872 -320.593445) (xy 265.535782 -320.593445) (xy 265.566946 -320.605676)
			(xy 265.613104 -320.632325) (xy 265.654775 -320.665556) (xy 265.691027 -320.704627) (xy 265.721051 -320.748664)
			(xy 265.744177 -320.796685) (xy 265.759887 -320.847615) (xy 265.76783 -320.900319) (xy 265.768328 -320.926968)
			(xy 265.76783 -320.953617) (xy 265.759887 -321.006321) (xy 265.756557 -321.017117) (xy 272.56231 -321.017117)
			(xy 272.56231 -320.963819) (xy 272.570253 -320.911115) (xy 272.585963 -320.860185) (xy 272.609089 -320.812164)
			(xy 272.639113 -320.768127) (xy 272.675365 -320.729056) (xy 272.717036 -320.695825) (xy 272.763194 -320.669176)
			(xy 272.812808 -320.649704) (xy 272.86477 -320.637844) (xy 272.91792 -320.633861) (xy 272.97107 -320.637844)
			(xy 273.023032 -320.649704) (xy 273.072646 -320.669176) (xy 273.118804 -320.695825) (xy 273.160475 -320.729056)
			(xy 273.196727 -320.768127) (xy 273.226751 -320.812164) (xy 273.249877 -320.860185) (xy 273.265587 -320.911115)
			(xy 273.27353 -320.963819) (xy 273.273861 -320.981557) (xy 279.94101 -320.981557) (xy 279.94101 -320.928259)
			(xy 279.948953 -320.875555) (xy 279.964663 -320.824625) (xy 279.987789 -320.776604) (xy 280.017813 -320.732567)
			(xy 280.054065 -320.693496) (xy 280.095736 -320.660265) (xy 280.141894 -320.633616) (xy 280.191508 -320.614144)
			(xy 280.24347 -320.602284) (xy 280.29662 -320.598301) (xy 280.34977 -320.602284) (xy 280.401732 -320.614144)
			(xy 280.451346 -320.633616) (xy 280.497504 -320.660265) (xy 280.539175 -320.693496) (xy 280.575427 -320.732567)
			(xy 280.605451 -320.776604) (xy 280.628577 -320.824625) (xy 280.644287 -320.875555) (xy 280.65223 -320.928259)
			(xy 280.652728 -320.954908) (xy 280.65223 -320.981557) (xy 280.644287 -321.034261) (xy 280.628577 -321.085191)
			(xy 280.605451 -321.133212) (xy 280.575427 -321.177249) (xy 280.539175 -321.21632) (xy 280.497504 -321.249551)
			(xy 280.451346 -321.2762) (xy 280.401732 -321.295672) (xy 280.34977 -321.307532) (xy 280.29662 -321.311516)
			(xy 280.24347 -321.307532) (xy 280.191508 -321.295672) (xy 280.141894 -321.2762) (xy 280.095736 -321.249551)
			(xy 280.054065 -321.21632) (xy 280.017813 -321.177249) (xy 279.987789 -321.133212) (xy 279.964663 -321.085191)
			(xy 279.948953 -321.034261) (xy 279.94101 -320.981557) (xy 273.273861 -320.981557) (xy 273.274028 -320.990468)
			(xy 273.27353 -321.017117) (xy 273.265587 -321.069821) (xy 273.249877 -321.120751) (xy 273.226751 -321.168772)
			(xy 273.196727 -321.212809) (xy 273.160475 -321.25188) (xy 273.118804 -321.285111) (xy 273.072646 -321.31176)
			(xy 273.023032 -321.331232) (xy 272.97107 -321.343092) (xy 272.91792 -321.347076) (xy 272.86477 -321.343092)
			(xy 272.812808 -321.331232) (xy 272.763194 -321.31176) (xy 272.717036 -321.285111) (xy 272.675365 -321.25188)
			(xy 272.639113 -321.212809) (xy 272.609089 -321.168772) (xy 272.585963 -321.120751) (xy 272.570253 -321.069821)
			(xy 272.56231 -321.017117) (xy 265.756557 -321.017117) (xy 265.744177 -321.057251) (xy 265.721051 -321.105272)
			(xy 265.691027 -321.149309) (xy 265.654775 -321.18838) (xy 265.613104 -321.221611) (xy 265.566946 -321.24826)
			(xy 265.517332 -321.267732) (xy 265.46537 -321.279592) (xy 265.41222 -321.283576) (xy 265.35907 -321.279592)
			(xy 265.307108 -321.267732) (xy 265.257494 -321.24826) (xy 265.211336 -321.221611) (xy 265.169665 -321.18838)
			(xy 265.133413 -321.149309) (xy 265.103389 -321.105272) (xy 265.080263 -321.057251) (xy 265.064553 -321.006321)
			(xy 265.05661 -320.953617) (xy 247.961499 -320.953617) (xy 248.001946 -320.964191) (xy 248.053275 -320.986003)
			(xy 248.100881 -321.015057) (xy 248.143749 -321.050732) (xy 248.180966 -321.092269) (xy 248.211739 -321.138782)
			(xy 248.235411 -321.189279) (xy 248.251479 -321.242686) (xy 248.259599 -321.297862) (xy 248.260108 -321.325748)
			(xy 248.259599 -321.353634) (xy 248.251479 -321.40881) (xy 248.241094 -321.443329) (xy 254.620004 -321.443329)
			(xy 254.620004 -321.390031) (xy 254.627947 -321.337327) (xy 254.643657 -321.286397) (xy 254.666783 -321.238376)
			(xy 254.696807 -321.194339) (xy 254.733059 -321.155268) (xy 254.77473 -321.122037) (xy 254.820888 -321.095388)
			(xy 254.870502 -321.075916) (xy 254.922464 -321.064056) (xy 254.975614 -321.060073) (xy 255.028764 -321.064056)
			(xy 255.080726 -321.075916) (xy 255.13034 -321.095388) (xy 255.176498 -321.122037) (xy 255.218169 -321.155268)
			(xy 255.254421 -321.194339) (xy 255.284445 -321.238376) (xy 255.307571 -321.286397) (xy 255.323281 -321.337327)
			(xy 255.331224 -321.390031) (xy 255.331722 -321.41668) (xy 255.331224 -321.443329) (xy 258.720072 -321.443329)
			(xy 258.720072 -321.390031) (xy 258.728015 -321.337327) (xy 258.743725 -321.286397) (xy 258.766851 -321.238376)
			(xy 258.796875 -321.194339) (xy 258.833127 -321.155268) (xy 258.874798 -321.122037) (xy 258.920956 -321.095388)
			(xy 258.97057 -321.075916) (xy 259.022532 -321.064056) (xy 259.075682 -321.060073) (xy 259.128832 -321.064056)
			(xy 259.180794 -321.075916) (xy 259.230408 -321.095388) (xy 259.276566 -321.122037) (xy 259.318237 -321.155268)
			(xy 259.354489 -321.194339) (xy 259.384513 -321.238376) (xy 259.407639 -321.286397) (xy 259.423349 -321.337327)
			(xy 259.431292 -321.390031) (xy 259.43179 -321.41668) (xy 259.431292 -321.443329) (xy 259.423349 -321.496033)
			(xy 259.407639 -321.546963) (xy 259.384513 -321.594984) (xy 259.354489 -321.639021) (xy 259.318237 -321.678092)
			(xy 259.291893 -321.6991) (xy 261.461496 -321.6991) (xy 261.465479 -321.645949) (xy 261.47734 -321.593985)
			(xy 261.496813 -321.54437) (xy 261.523464 -321.498212) (xy 261.556697 -321.456541) (xy 261.59577 -321.420289)
			(xy 261.63981 -321.390265) (xy 261.687832 -321.367141) (xy 261.738765 -321.351433) (xy 261.79147 -321.343492)
			(xy 261.81812 -321.34302) (xy 261.844355 -321.343479) (xy 261.896263 -321.351139) (xy 261.946479 -321.366348)
			(xy 261.993914 -321.388776) (xy 262.015986 -321.402964) (xy 262.027996 -321.410429) (xy 262.05491 -321.419073)
			(xy 262.083162 -321.420013) (xy 262.11059 -321.413176) (xy 262.135096 -321.399086) (xy 262.154803 -321.378821)
			(xy 262.168204 -321.353932) (xy 262.171688 -321.340226) (xy 262.177956 -321.314158) (xy 262.197167 -321.264107)
			(xy 262.223667 -321.217504) (xy 262.256856 -321.175402) (xy 262.295985 -321.138753) (xy 262.340167 -321.108388)
			(xy 262.388404 -321.084992) (xy 262.439604 -321.069095) (xy 262.492608 -321.061057) (xy 262.519414 -321.060572)
			(xy 262.546061 -321.061111) (xy 262.59876 -321.069056) (xy 262.649686 -321.084766) (xy 262.697702 -321.107891)
			(xy 262.741735 -321.137914) (xy 262.780801 -321.174164) (xy 262.814029 -321.215832) (xy 262.840676 -321.261986)
			(xy 262.860146 -321.311597) (xy 262.872004 -321.363555) (xy 262.875987 -321.4167) (xy 262.872004 -321.469845)
			(xy 262.860146 -321.521803) (xy 262.840676 -321.571414) (xy 262.814029 -321.617568) (xy 262.780801 -321.659236)
			(xy 262.741735 -321.695486) (xy 262.697702 -321.725509) (xy 262.649686 -321.748634) (xy 262.59876 -321.764344)
			(xy 262.546061 -321.772289) (xy 262.519414 -321.772788) (xy 262.493178 -321.77236) (xy 262.441269 -321.764691)
			(xy 262.391052 -321.749473) (xy 262.343619 -321.727037) (xy 262.321548 -321.712844) (xy 262.309516 -321.705416)
			(xy 262.28261 -321.696766) (xy 262.254363 -321.69582) (xy 262.226938 -321.70265) (xy 262.202434 -321.716735)
			(xy 262.182729 -321.736995) (xy 262.169329 -321.761879) (xy 262.165846 -321.775582) (xy 262.159644 -321.801668)
			(xy 262.140428 -321.851723) (xy 262.113921 -321.898329) (xy 262.080723 -321.940433) (xy 262.041586 -321.977081)
			(xy 261.997395 -322.007444) (xy 261.949149 -322.030835) (xy 261.897941 -322.046726) (xy 261.844929 -322.054756)
			(xy 261.81812 -322.055236) (xy 261.79147 -322.054708) (xy 261.738765 -322.046767) (xy 261.687832 -322.031059)
			(xy 261.63981 -322.007935) (xy 261.59577 -321.977911) (xy 261.556697 -321.941659) (xy 261.523464 -321.899988)
			(xy 261.496813 -321.85383) (xy 261.47734 -321.804215) (xy 261.465479 -321.752251) (xy 261.461496 -321.6991)
			(xy 259.291893 -321.6991) (xy 259.276566 -321.711323) (xy 259.230408 -321.737972) (xy 259.180794 -321.757444)
			(xy 259.128832 -321.769304) (xy 259.075682 -321.773288) (xy 259.022532 -321.769304) (xy 258.97057 -321.757444)
			(xy 258.920956 -321.737972) (xy 258.874798 -321.711323) (xy 258.833127 -321.678092) (xy 258.796875 -321.639021)
			(xy 258.766851 -321.594984) (xy 258.743725 -321.546963) (xy 258.728015 -321.496033) (xy 258.720072 -321.443329)
			(xy 255.331224 -321.443329) (xy 255.323281 -321.496033) (xy 255.307571 -321.546963) (xy 255.284445 -321.594984)
			(xy 255.254421 -321.639021) (xy 255.218169 -321.678092) (xy 255.176498 -321.711323) (xy 255.13034 -321.737972)
			(xy 255.080726 -321.757444) (xy 255.028764 -321.769304) (xy 254.975614 -321.773288) (xy 254.922464 -321.769304)
			(xy 254.870502 -321.757444) (xy 254.820888 -321.737972) (xy 254.77473 -321.711323) (xy 254.733059 -321.678092)
			(xy 254.696807 -321.639021) (xy 254.666783 -321.594984) (xy 254.643657 -321.546963) (xy 254.627947 -321.496033)
			(xy 254.620004 -321.443329) (xy 248.241094 -321.443329) (xy 248.235411 -321.462217) (xy 248.211739 -321.512714)
			(xy 248.180966 -321.559227) (xy 248.143749 -321.600764) (xy 248.100881 -321.636439) (xy 248.053275 -321.665493)
			(xy 248.001946 -321.687305) (xy 247.947989 -321.701411) (xy 247.892552 -321.707511) (xy 247.836818 -321.705474)
			(xy 247.781975 -321.695344) (xy 247.729191 -321.677337) (xy 247.679591 -321.651836) (xy 247.634233 -321.619385)
			(xy 247.594084 -321.580676) (xy 247.559998 -321.536533) (xy 247.532702 -321.487898) (xy 247.512779 -321.435807)
			(xy 247.500653 -321.38137) (xy 247.496582 -321.325748) (xy 214.959109 -321.325748) (xy 214.962681 -321.337327)
			(xy 214.970624 -321.390031) (xy 214.971122 -321.41668) (xy 214.970624 -321.443329) (xy 214.962681 -321.496033)
			(xy 214.946971 -321.546963) (xy 214.923845 -321.594984) (xy 214.893821 -321.639021) (xy 214.857569 -321.678092)
			(xy 214.815898 -321.711323) (xy 214.76974 -321.737972) (xy 214.720126 -321.757444) (xy 214.668164 -321.769304)
			(xy 214.615014 -321.773288) (xy 214.561864 -321.769304) (xy 214.509902 -321.757444) (xy 214.460288 -321.737972)
			(xy 214.41413 -321.711323) (xy 214.372459 -321.678092) (xy 214.336207 -321.639021) (xy 214.306183 -321.594984)
			(xy 214.283057 -321.546963) (xy 214.267347 -321.496033) (xy 214.259404 -321.443329) (xy 210.870556 -321.443329)
			(xy 210.862613 -321.496033) (xy 210.846903 -321.546963) (xy 210.823777 -321.594984) (xy 210.793753 -321.639021)
			(xy 210.757501 -321.678092) (xy 210.71583 -321.711323) (xy 210.669672 -321.737972) (xy 210.620058 -321.757444)
			(xy 210.568096 -321.769304) (xy 210.514946 -321.773288) (xy 210.461796 -321.769304) (xy 210.409834 -321.757444)
			(xy 210.36022 -321.737972) (xy 210.314062 -321.711323) (xy 210.272391 -321.678092) (xy 210.236139 -321.639021)
			(xy 210.206115 -321.594984) (xy 210.182989 -321.546963) (xy 210.167279 -321.496033) (xy 210.159336 -321.443329)
			(xy 207.426824 -321.443329) (xy 207.418881 -321.496033) (xy 207.403171 -321.546963) (xy 207.380045 -321.594984)
			(xy 207.350021 -321.639021) (xy 207.313769 -321.678092) (xy 207.272098 -321.711323) (xy 207.22594 -321.737972)
			(xy 207.176326 -321.757444) (xy 207.124364 -321.769304) (xy 207.071214 -321.773288) (xy 207.018064 -321.769304)
			(xy 206.966102 -321.757444) (xy 206.916488 -321.737972) (xy 206.87033 -321.711323) (xy 206.828659 -321.678092)
			(xy 206.792407 -321.639021) (xy 206.762383 -321.594984) (xy 206.739257 -321.546963) (xy 206.723547 -321.496033)
			(xy 206.715604 -321.443329) (xy 203.326756 -321.443329) (xy 203.318813 -321.496033) (xy 203.303103 -321.546963)
			(xy 203.279977 -321.594984) (xy 203.249953 -321.639021) (xy 203.213701 -321.678092) (xy 203.17203 -321.711323)
			(xy 203.125872 -321.737972) (xy 203.076258 -321.757444) (xy 203.024296 -321.769304) (xy 202.971146 -321.773288)
			(xy 202.917996 -321.769304) (xy 202.866034 -321.757444) (xy 202.81642 -321.737972) (xy 202.770262 -321.711323)
			(xy 202.728591 -321.678092) (xy 202.692339 -321.639021) (xy 202.662315 -321.594984) (xy 202.639189 -321.546963)
			(xy 202.623479 -321.496033) (xy 202.615536 -321.443329) (xy 199.883024 -321.443329) (xy 199.875081 -321.496033)
			(xy 199.859371 -321.546963) (xy 199.836245 -321.594984) (xy 199.806221 -321.639021) (xy 199.769969 -321.678092)
			(xy 199.728298 -321.711323) (xy 199.68214 -321.737972) (xy 199.632526 -321.757444) (xy 199.580564 -321.769304)
			(xy 199.527414 -321.773288) (xy 199.474264 -321.769304) (xy 199.422302 -321.757444) (xy 199.372688 -321.737972)
			(xy 199.32653 -321.711323) (xy 199.284859 -321.678092) (xy 199.248607 -321.639021) (xy 199.218583 -321.594984)
			(xy 199.195457 -321.546963) (xy 199.179747 -321.496033) (xy 199.171804 -321.443329) (xy 195.782956 -321.443329)
			(xy 195.775013 -321.496033) (xy 195.759303 -321.546963) (xy 195.736177 -321.594984) (xy 195.706153 -321.639021)
			(xy 195.669901 -321.678092) (xy 195.62823 -321.711323) (xy 195.582072 -321.737972) (xy 195.532458 -321.757444)
			(xy 195.480496 -321.769304) (xy 195.427346 -321.773288) (xy 195.374196 -321.769304) (xy 195.322234 -321.757444)
			(xy 195.27262 -321.737972) (xy 195.226462 -321.711323) (xy 195.184791 -321.678092) (xy 195.148539 -321.639021)
			(xy 195.118515 -321.594984) (xy 195.095389 -321.546963) (xy 195.079679 -321.496033) (xy 195.071736 -321.443329)
			(xy 192.328048 -321.443329) (xy 192.320105 -321.496033) (xy 192.304395 -321.546963) (xy 192.281269 -321.594984)
			(xy 192.251245 -321.639021) (xy 192.214993 -321.678092) (xy 192.173322 -321.711323) (xy 192.127164 -321.737972)
			(xy 192.07755 -321.757444) (xy 192.025588 -321.769304) (xy 191.972438 -321.773288) (xy 191.919288 -321.769304)
			(xy 191.867326 -321.757444) (xy 191.817712 -321.737972) (xy 191.771554 -321.711323) (xy 191.729883 -321.678092)
			(xy 191.693631 -321.639021) (xy 191.663607 -321.594984) (xy 191.640481 -321.546963) (xy 191.624771 -321.496033)
			(xy 191.616828 -321.443329) (xy 188.238648 -321.443329) (xy 188.230705 -321.496033) (xy 188.214995 -321.546963)
			(xy 188.191869 -321.594984) (xy 188.161845 -321.639021) (xy 188.125593 -321.678092) (xy 188.083922 -321.711323)
			(xy 188.037764 -321.737972) (xy 187.98815 -321.757444) (xy 187.936188 -321.769304) (xy 187.883038 -321.773288)
			(xy 187.829888 -321.769304) (xy 187.777926 -321.757444) (xy 187.728312 -321.737972) (xy 187.682154 -321.711323)
			(xy 187.640483 -321.678092) (xy 187.604231 -321.639021) (xy 187.574207 -321.594984) (xy 187.551081 -321.546963)
			(xy 187.535371 -321.496033) (xy 187.527428 -321.443329) (xy 184.786788 -321.443329) (xy 184.778845 -321.496033)
			(xy 184.763135 -321.546963) (xy 184.740009 -321.594984) (xy 184.709985 -321.639021) (xy 184.673733 -321.678092)
			(xy 184.632062 -321.711323) (xy 184.585904 -321.737972) (xy 184.53629 -321.757444) (xy 184.484328 -321.769304)
			(xy 184.431178 -321.773288) (xy 184.378028 -321.769304) (xy 184.326066 -321.757444) (xy 184.276452 -321.737972)
			(xy 184.230294 -321.711323) (xy 184.188623 -321.678092) (xy 184.152371 -321.639021) (xy 184.122347 -321.594984)
			(xy 184.099221 -321.546963) (xy 184.083511 -321.496033) (xy 184.075568 -321.443329) (xy 180.662813 -321.443329)
			(xy 180.642989 -321.484494) (xy 180.612965 -321.528531) (xy 180.576713 -321.567602) (xy 180.535042 -321.600833)
			(xy 180.488884 -321.627482) (xy 180.43927 -321.646954) (xy 180.387308 -321.658814) (xy 180.334158 -321.662798)
			(xy 180.281008 -321.658814) (xy 180.229046 -321.646954) (xy 180.179432 -321.627482) (xy 180.133274 -321.600833)
			(xy 180.091603 -321.567602) (xy 180.055351 -321.528531) (xy 180.025327 -321.484494) (xy 180.002201 -321.436473)
			(xy 179.986491 -321.385543) (xy 179.978548 -321.332839) (xy 176.912771 -321.332839) (xy 176.911035 -321.333584)
			(xy 176.858598 -321.347158) (xy 176.804711 -321.352634) (xy 176.750616 -321.349887) (xy 176.697561 -321.33898)
			(xy 176.646769 -321.320164) (xy 176.599413 -321.293874) (xy 176.556584 -321.260715) (xy 176.51927 -321.221453)
			(xy 176.488332 -321.176994) (xy 176.464483 -321.128362) (xy 176.448274 -321.07668) (xy 176.440078 -321.023138)
			(xy 176.439576 -320.996056) (xy 176.439871 -320.975613) (xy 176.444584 -320.934999) (xy 176.448974 -320.91503)
			(xy 176.451677 -320.90143) (xy 176.450469 -320.873738) (xy 176.441865 -320.84739) (xy 176.426498 -320.824321)
			(xy 176.405498 -320.80623) (xy 176.380409 -320.794446) (xy 176.353078 -320.789836) (xy 176.339246 -320.790824)
			(xy 176.3014 -320.792856) (xy 176.274319 -320.792302) (xy 176.220782 -320.7841) (xy 176.169104 -320.767886)
			(xy 176.120477 -320.744033) (xy 176.076024 -320.713091) (xy 176.036768 -320.675774) (xy 176.003617 -320.632944)
			(xy 175.977333 -320.585587) (xy 175.958524 -320.534795) (xy 175.947624 -320.481742) (xy 175.944883 -320.427649)
			(xy 172.534608 -320.427649) (xy 172.538877 -320.436513) (xy 172.554587 -320.487443) (xy 172.56253 -320.540147)
			(xy 172.563028 -320.566796) (xy 172.56253 -320.593445) (xy 172.554587 -320.646149) (xy 172.538877 -320.697079)
			(xy 172.515751 -320.7451) (xy 172.485727 -320.789137) (xy 172.449475 -320.828208) (xy 172.407804 -320.861439)
			(xy 172.361646 -320.888088) (xy 172.312032 -320.90756) (xy 172.26007 -320.91942) (xy 172.20692 -320.923404)
			(xy 172.15377 -320.91942) (xy 172.101808 -320.90756) (xy 172.052194 -320.888088) (xy 172.006036 -320.861439)
			(xy 171.964365 -320.828208) (xy 171.928113 -320.789137) (xy 171.898089 -320.7451) (xy 171.874963 -320.697079)
			(xy 171.859253 -320.646149) (xy 171.85131 -320.593445) (xy 169.707831 -320.593445) (xy 169.70782 -320.594059)
			(xy 169.699503 -320.647947) (xy 169.683061 -320.699935) (xy 169.658881 -320.748806) (xy 169.627528 -320.793416)
			(xy 169.609008 -320.81343) (xy 169.599135 -320.824464) (xy 169.58556 -320.850756) (xy 169.580104 -320.87984)
			(xy 169.583228 -320.909265) (xy 169.594668 -320.936554) (xy 169.603674 -320.948304) (xy 169.618819 -320.967484)
			(xy 169.644307 -321.009181) (xy 169.663856 -321.05397) (xy 169.677099 -321.101011) (xy 169.683786 -321.149421)
			(xy 169.684192 -321.173856) (xy 169.683694 -321.200505) (xy 169.675751 -321.253209) (xy 169.660041 -321.304139)
			(xy 169.648788 -321.327505) (xy 172.376074 -321.327505) (xy 172.376074 -321.274207) (xy 172.384017 -321.221503)
			(xy 172.399727 -321.170573) (xy 172.422853 -321.122552) (xy 172.452877 -321.078515) (xy 172.489129 -321.039444)
			(xy 172.5308 -321.006213) (xy 172.576958 -320.979564) (xy 172.626572 -320.960092) (xy 172.678534 -320.948232)
			(xy 172.731684 -320.944249) (xy 172.784834 -320.948232) (xy 172.836796 -320.960092) (xy 172.88641 -320.979564)
			(xy 172.932568 -321.006213) (xy 172.974239 -321.039444) (xy 173.010491 -321.078515) (xy 173.040515 -321.122552)
			(xy 173.063641 -321.170573) (xy 173.079351 -321.221503) (xy 173.087294 -321.274207) (xy 173.087792 -321.300856)
			(xy 173.087294 -321.327505) (xy 173.079351 -321.380209) (xy 173.063641 -321.431139) (xy 173.040515 -321.47916)
			(xy 173.010491 -321.523197) (xy 172.974239 -321.562268) (xy 172.932568 -321.595499) (xy 172.88641 -321.622148)
			(xy 172.836796 -321.64162) (xy 172.784834 -321.65348) (xy 172.731684 -321.657464) (xy 172.678534 -321.65348)
			(xy 172.626572 -321.64162) (xy 172.576958 -321.622148) (xy 172.5308 -321.595499) (xy 172.489129 -321.562268)
			(xy 172.452877 -321.523197) (xy 172.422853 -321.47916) (xy 172.399727 -321.431139) (xy 172.384017 -321.380209)
			(xy 172.376074 -321.327505) (xy 169.648788 -321.327505) (xy 169.636915 -321.35216) (xy 169.606891 -321.396197)
			(xy 169.570639 -321.435268) (xy 169.528968 -321.468499) (xy 169.48281 -321.495148) (xy 169.433196 -321.51462)
			(xy 169.381234 -321.52648) (xy 169.328084 -321.530464) (xy 169.274934 -321.52648) (xy 169.222972 -321.51462)
			(xy 169.173358 -321.495148) (xy 169.1272 -321.468499) (xy 169.085529 -321.435268) (xy 169.049277 -321.396197)
			(xy 169.019253 -321.35216) (xy 168.996127 -321.304139) (xy 168.980417 -321.253209) (xy 168.972474 -321.200505)
			(xy 168.971976 -321.173856) (xy 168.258701 -321.173856) (xy 168.238155 -321.196) (xy 168.196484 -321.229231)
			(xy 168.150326 -321.25588) (xy 168.100712 -321.275352) (xy 168.04875 -321.287212) (xy 167.9956 -321.291196)
			(xy 167.94245 -321.287212) (xy 167.890488 -321.275352) (xy 167.840874 -321.25588) (xy 167.794716 -321.229231)
			(xy 167.753045 -321.196) (xy 167.716793 -321.156929) (xy 167.686769 -321.112892) (xy 167.663643 -321.064871)
			(xy 167.647933 -321.013941) (xy 167.63999 -320.961237) (xy 167.291237 -320.961237) (xy 168.6941 -322.3641)
			(xy 194.6275 -322.3641) (xy 194.6656 -322.4022) (xy 263.9822 -322.4022)
		)
		(stroke
			(width 0)
			(type solid)
		)
		(fill yes)
		(layer "In6.Cu")
		(net "P3V3_AUX")
	)
	(gr_poly
		(pts
			(xy 437.568594 -181.985412) (xy 437.568594 -176.87417) (xy 440.197494 -174.24527) (xy 446.671954 -174.24527)
			(xy 447.620898 -173.296326) (xy 447.620898 -146.336004) (xy 444.597028 -143.31188) (xy 438.371234 -143.31188)
			(xy 438.342115 -143.31142) (xy 438.284377 -143.303809) (xy 438.228127 -143.288726) (xy 438.174326 -143.26643)
			(xy 438.123897 -143.237301) (xy 438.077702 -143.201839) (xy 438.056782 -143.181578) (xy 435.036214 -140.161264)
			(xy 432.639724 -140.161264) (xy 432.60932 -140.16077) (xy 432.549079 -140.152494) (xy 432.490526 -140.136091)
			(xy 432.434752 -140.111867) (xy 432.382797 -140.080275) (xy 432.335627 -140.041901) (xy 432.294121 -139.997463)
			(xy 432.259054 -139.947786) (xy 432.231078 -139.893796) (xy 432.210714 -139.836501) (xy 432.198342 -139.776965)
			(xy 432.194192 -139.7163) (xy 432.198342 -139.655635) (xy 432.210714 -139.596099) (xy 432.231078 -139.538804)
			(xy 432.259054 -139.484814) (xy 432.294121 -139.435137) (xy 432.335627 -139.390699) (xy 432.382797 -139.352325)
			(xy 432.434752 -139.320733) (xy 432.490526 -139.296509) (xy 432.549079 -139.280106) (xy 432.60932 -139.27183)
			(xy 432.639724 -139.271248) (xy 433.194206 -139.271248) (xy 433.209206 -139.270667) (xy 433.237886 -139.261852)
			(xy 433.262761 -139.245076) (xy 433.281681 -139.22179) (xy 433.293008 -139.194007) (xy 433.295764 -139.16413)
			(xy 433.293266 -139.149328) (xy 433.29225 -139.144248) (xy 433.29225 -139.143232) (xy 433.291234 -139.138406)
			(xy 433.28817 -139.121486) (xy 433.284739 -139.087271) (xy 433.284376 -139.07008) (xy 433.284376 -139.061698)
			(xy 433.285154 -139.03465) (xy 433.293404 -138.981171) (xy 433.309129 -138.929396) (xy 433.332014 -138.880362)
			(xy 433.361598 -138.835055) (xy 433.397288 -138.794383) (xy 433.438368 -138.759163) (xy 433.484012 -138.730101)
			(xy 433.533306 -138.707782) (xy 433.585259 -138.692653) (xy 433.638828 -138.685018) (xy 433.665884 -138.684508)
			(xy 433.676574 -138.684554) (xy 433.697922 -138.6857) (xy 433.708556 -138.686794) (xy 433.722732 -138.687116)
			(xy 433.750377 -138.680854) (xy 433.775237 -138.667238) (xy 433.795399 -138.647317) (xy 433.809313 -138.622622)
			(xy 433.815907 -138.595055) (xy 433.815744 -138.580876) (xy 433.81422 -138.560302) (xy 433.813712 -138.539728)
			(xy 433.813712 -138.539474) (xy 433.814188 -138.510251) (xy 433.821869 -138.452313) (xy 433.837068 -138.395878)
			(xy 433.859525 -138.341919) (xy 433.888852 -138.291364) (xy 433.924545 -138.245084) (xy 433.96599 -138.203875)
			(xy 434.012473 -138.168445) (xy 434.063194 -138.139406) (xy 434.11728 -138.117257) (xy 434.1738 -138.102379)
			(xy 434.231781 -138.095028) (xy 434.261006 -138.09472) (xy 434.78069 -138.09472) (xy 434.809169 -138.095188)
			(xy 434.865656 -138.102496) (xy 434.920746 -138.116966) (xy 434.947314 -138.127232) (xy 434.984144 -138.141964)
			(xy 435.042056 -138.062462) (xy 434.96103 -137.981436) (xy 434.262276 -137.981436) (xy 434.233148 -137.980964)
			(xy 434.175395 -137.973324) (xy 434.119135 -137.958203) (xy 434.065332 -137.935862) (xy 434.01491 -137.906683)
			(xy 433.968733 -137.871166) (xy 433.947824 -137.85088) (xy 433.861972 -137.765028) (xy 433.8417 -137.74411)
			(xy 433.806206 -137.697921) (xy 433.777041 -137.647497) (xy 433.754704 -137.593699) (xy 433.739575 -137.537446)
			(xy 433.731914 -137.479701) (xy 433.731416 -137.450576) (xy 433.731894 -137.421441) (xy 433.739503 -137.363671)
			(xy 433.754587 -137.307388) (xy 433.776888 -137.253556) (xy 433.806026 -137.203095) (xy 433.8415 -137.156869)
			(xy 433.882705 -137.115668) (xy 433.928935 -137.080199) (xy 433.979399 -137.051067) (xy 434.033234 -137.028771)
			(xy 434.089518 -137.013693) (xy 434.147289 -137.006091) (xy 434.176424 -137.005568) (xy 434.204532 -137.005994)
			(xy 434.260299 -137.013072) (xy 434.314729 -137.027124) (xy 434.366953 -137.047927) (xy 434.416138 -137.075148)
			(xy 434.43906 -137.09142) (xy 435.14518 -137.09142) (xy 435.174309 -137.091889) (xy 435.232064 -137.099525)
			(xy 435.288326 -137.114643) (xy 435.342131 -137.136982) (xy 435.392555 -137.166161) (xy 435.438733 -137.201679)
			(xy 435.459632 -137.221976) (xy 436.247032 -138.009376) (xy 436.267304 -138.030294) (xy 436.302797 -138.076483)
			(xy 436.331961 -138.126908) (xy 436.354298 -138.180706) (xy 436.369426 -138.236958) (xy 436.377086 -138.294703)
			(xy 436.377588 -138.323828) (xy 436.377588 -138.825478) (xy 438.971182 -141.419072) (xy 445.196976 -141.419072)
			(xy 445.226105 -141.419541) (xy 445.283861 -141.427176) (xy 445.340125 -141.442291) (xy 445.393931 -141.464629)
			(xy 445.444358 -141.493806) (xy 445.490539 -141.529321) (xy 445.511428 -141.549628) (xy 447.409316 -143.447262)
			(xy 447.447416 -143.485362) (xy 447.458385 -143.495585) (xy 447.48481 -143.509723) (xy 447.5142 -143.51559)
			(xy 447.544028 -143.512682) (xy 447.571731 -143.501247) (xy 447.594926 -143.482269) (xy 447.611621 -143.457379)
			(xy 447.620379 -143.428718) (xy 447.620898 -143.413734) (xy 447.620898 -120.208294) (xy 442.723524 -115.31092)
			(xy 431.396394 -115.31092) (xy 431.382735 -115.311401) (xy 431.356413 -115.318721) (xy 431.332973 -115.332755)
			(xy 431.31409 -115.3525) (xy 431.301116 -115.376544) (xy 431.294978 -115.403166) (xy 431.296115 -115.430464)
			(xy 431.304447 -115.456483) (xy 431.319376 -115.479364) (xy 431.329338 -115.48872) (xy 431.351683 -115.506915)
			(xy 431.391159 -115.548891) (xy 431.423871 -115.596328) (xy 431.449073 -115.648146) (xy 431.466192 -115.703167)
			(xy 431.474839 -115.760137) (xy 431.475388 -115.788948) (xy 431.474902 -115.816199) (xy 431.467146 -115.870147)
			(xy 431.451791 -115.922442) (xy 431.429149 -115.972019) (xy 431.399683 -116.017869) (xy 431.363992 -116.05906)
			(xy 431.322801 -116.094751) (xy 431.276951 -116.124217) (xy 431.227374 -116.146859) (xy 431.175079 -116.162214)
			(xy 431.121131 -116.16997) (xy 431.066629 -116.16997) (xy 431.012681 -116.162214) (xy 430.960386 -116.146859)
			(xy 430.910809 -116.124217) (xy 430.864959 -116.094751) (xy 430.823768 -116.05906) (xy 430.788077 -116.017869)
			(xy 430.758611 -115.972019) (xy 430.735969 -115.922442) (xy 430.720614 -115.870147) (xy 430.712858 -115.816199)
			(xy 430.712372 -115.788948) (xy 430.712902 -115.760137) (xy 430.72157 -115.703172) (xy 430.738701 -115.648156)
			(xy 430.763907 -115.59634) (xy 430.796614 -115.548901) (xy 430.83608 -115.506917) (xy 430.858422 -115.48872)
			(xy 430.868383 -115.479346) (xy 430.883354 -115.456469) (xy 430.891718 -115.430438) (xy 430.892874 -115.403122)
			(xy 430.88674 -115.376477) (xy 430.873756 -115.352416) (xy 430.854852 -115.332663) (xy 430.831385 -115.318634)
			(xy 430.805036 -115.311336) (xy 430.791366 -115.31092) (xy 430.507394 -115.31092) (xy 430.493735 -115.311401)
			(xy 430.467413 -115.318721) (xy 430.443973 -115.332755) (xy 430.42509 -115.3525) (xy 430.412116 -115.376544)
			(xy 430.405978 -115.403166) (xy 430.407115 -115.430464) (xy 430.415447 -115.456483) (xy 430.430376 -115.479364)
			(xy 430.440338 -115.48872) (xy 430.462683 -115.506915) (xy 430.502159 -115.548891) (xy 430.534871 -115.596328)
			(xy 430.560073 -115.648146) (xy 430.577192 -115.703167) (xy 430.585839 -115.760137) (xy 430.586388 -115.788948)
			(xy 430.585902 -115.816199) (xy 430.578146 -115.870147) (xy 430.562791 -115.922442) (xy 430.540149 -115.972019)
			(xy 430.510683 -116.017869) (xy 430.474992 -116.05906) (xy 430.433801 -116.094751) (xy 430.387951 -116.124217)
			(xy 430.338374 -116.146859) (xy 430.286079 -116.162214) (xy 430.232131 -116.16997) (xy 430.177629 -116.16997)
			(xy 430.123681 -116.162214) (xy 430.071386 -116.146859) (xy 430.021809 -116.124217) (xy 429.975959 -116.094751)
			(xy 429.934768 -116.05906) (xy 429.899077 -116.017869) (xy 429.869611 -115.972019) (xy 429.846969 -115.922442)
			(xy 429.831614 -115.870147) (xy 429.823858 -115.816199) (xy 429.823372 -115.788948) (xy 429.823902 -115.760137)
			(xy 429.83257 -115.703172) (xy 429.849701 -115.648156) (xy 429.874907 -115.59634) (xy 429.907614 -115.548901)
			(xy 429.94708 -115.506917) (xy 429.969422 -115.48872) (xy 429.979383 -115.479346) (xy 429.994354 -115.456469)
			(xy 430.002718 -115.430438) (xy 430.003874 -115.403122) (xy 429.99774 -115.376477) (xy 429.984756 -115.352416)
			(xy 429.965852 -115.332663) (xy 429.942385 -115.318634) (xy 429.916036 -115.311336) (xy 429.902366 -115.31092)
			(xy 414.403794 -115.31092) (xy 413.245046 -116.469668) (xy 433.69814 -116.469668) (xy 433.702211 -116.414046)
			(xy 433.714337 -116.359609) (xy 433.73426 -116.307518) (xy 433.761556 -116.258883) (xy 433.795642 -116.21474)
			(xy 433.835791 -116.176031) (xy 433.881149 -116.14358) (xy 433.930749 -116.118079) (xy 433.983533 -116.100072)
			(xy 434.038376 -116.089942) (xy 434.09411 -116.087905) (xy 434.149547 -116.094005) (xy 434.203504 -116.108111)
			(xy 434.214534 -116.112798) (xy 434.96814 -116.112798) (xy 434.972211 -116.057176) (xy 434.984337 -116.002739)
			(xy 435.00426 -115.950648) (xy 435.031556 -115.902013) (xy 435.065642 -115.85787) (xy 435.105791 -115.819161)
			(xy 435.151149 -115.78671) (xy 435.200749 -115.761209) (xy 435.253533 -115.743202) (xy 435.308376 -115.733072)
			(xy 435.36411 -115.731035) (xy 435.419547 -115.737135) (xy 435.473504 -115.751241) (xy 435.524833 -115.773053)
			(xy 435.572439 -115.802107) (xy 435.615307 -115.837782) (xy 435.652524 -115.879319) (xy 435.683297 -115.925832)
			(xy 435.706969 -115.976329) (xy 435.723037 -116.029736) (xy 435.731157 -116.084912) (xy 435.731666 -116.112798)
			(xy 435.731157 -116.140684) (xy 435.723037 -116.19586) (xy 435.706969 -116.249267) (xy 435.683297 -116.299764)
			(xy 435.652524 -116.346277) (xy 435.615307 -116.387814) (xy 435.572439 -116.423489) (xy 435.571687 -116.423948)
			(xy 436.807862 -116.423948) (xy 436.811933 -116.368326) (xy 436.824059 -116.313889) (xy 436.843982 -116.261798)
			(xy 436.871278 -116.213163) (xy 436.905364 -116.16902) (xy 436.945513 -116.130311) (xy 436.990871 -116.09786)
			(xy 437.040471 -116.072359) (xy 437.093255 -116.054352) (xy 437.148098 -116.044222) (xy 437.203832 -116.042185)
			(xy 437.259269 -116.048285) (xy 437.313226 -116.062391) (xy 437.364555 -116.084203) (xy 437.412161 -116.113257)
			(xy 437.455029 -116.148932) (xy 437.492246 -116.190469) (xy 437.523019 -116.236982) (xy 437.546691 -116.287479)
			(xy 437.562759 -116.340886) (xy 437.570879 -116.396062) (xy 437.571388 -116.423948) (xy 437.570879 -116.451834)
			(xy 437.562759 -116.50701) (xy 437.546691 -116.560417) (xy 437.523019 -116.610914) (xy 437.492246 -116.657427)
			(xy 437.455029 -116.698964) (xy 437.412161 -116.734639) (xy 437.364555 -116.763693) (xy 437.313226 -116.785505)
			(xy 437.259269 -116.799611) (xy 437.203832 -116.805711) (xy 437.148098 -116.803674) (xy 437.093255 -116.793544)
			(xy 437.040471 -116.775537) (xy 436.990871 -116.750036) (xy 436.945513 -116.717585) (xy 436.905364 -116.678876)
			(xy 436.871278 -116.634733) (xy 436.843982 -116.586098) (xy 436.824059 -116.534007) (xy 436.811933 -116.47957)
			(xy 436.807862 -116.423948) (xy 435.571687 -116.423948) (xy 435.524833 -116.452543) (xy 435.473504 -116.474355)
			(xy 435.419547 -116.488461) (xy 435.36411 -116.494561) (xy 435.308376 -116.492524) (xy 435.253533 -116.482394)
			(xy 435.200749 -116.464387) (xy 435.151149 -116.438886) (xy 435.105791 -116.406435) (xy 435.065642 -116.367726)
			(xy 435.031556 -116.323583) (xy 435.00426 -116.274948) (xy 434.984337 -116.222857) (xy 434.972211 -116.16842)
			(xy 434.96814 -116.112798) (xy 434.214534 -116.112798) (xy 434.254833 -116.129923) (xy 434.302439 -116.158977)
			(xy 434.345307 -116.194652) (xy 434.382524 -116.236189) (xy 434.413297 -116.282702) (xy 434.436969 -116.333199)
			(xy 434.453037 -116.386606) (xy 434.461157 -116.441782) (xy 434.461666 -116.469668) (xy 434.461157 -116.497554)
			(xy 434.453037 -116.55273) (xy 434.436969 -116.606137) (xy 434.413297 -116.656634) (xy 434.382524 -116.703147)
			(xy 434.345307 -116.744684) (xy 434.302439 -116.780359) (xy 434.254833 -116.809413) (xy 434.203504 -116.831225)
			(xy 434.149547 -116.845331) (xy 434.09411 -116.851431) (xy 434.038376 -116.849394) (xy 433.983533 -116.839264)
			(xy 433.930749 -116.821257) (xy 433.881149 -116.795756) (xy 433.835791 -116.763305) (xy 433.795642 -116.724596)
			(xy 433.761556 -116.680453) (xy 433.73426 -116.631818) (xy 433.714337 -116.579727) (xy 433.702211 -116.52529)
			(xy 433.69814 -116.469668) (xy 413.245046 -116.469668) (xy 412.105094 -117.60962) (xy 427.592742 -117.60962)
			(xy 427.596813 -117.553998) (xy 427.608939 -117.499561) (xy 427.628862 -117.44747) (xy 427.656158 -117.398835)
			(xy 427.690244 -117.354692) (xy 427.730393 -117.315983) (xy 427.775751 -117.283532) (xy 427.825351 -117.258031)
			(xy 427.878135 -117.240024) (xy 427.932978 -117.229894) (xy 427.988712 -117.227857) (xy 428.044149 -117.233957)
			(xy 428.098106 -117.248063) (xy 428.149435 -117.269875) (xy 428.197041 -117.298929) (xy 428.239909 -117.334604)
			(xy 428.277126 -117.376141) (xy 428.307899 -117.422654) (xy 428.331571 -117.473151) (xy 428.342826 -117.51056)
			(xy 428.648112 -117.51056) (xy 428.652183 -117.454938) (xy 428.664309 -117.400501) (xy 428.684232 -117.34841)
			(xy 428.711528 -117.299775) (xy 428.745614 -117.255632) (xy 428.785763 -117.216923) (xy 428.831121 -117.184472)
			(xy 428.880721 -117.158971) (xy 428.933505 -117.140964) (xy 428.988348 -117.130834) (xy 429.044082 -117.128797)
			(xy 429.099519 -117.134897) (xy 429.153476 -117.149003) (xy 429.204805 -117.170815) (xy 429.252411 -117.199869)
			(xy 429.295279 -117.235544) (xy 429.332496 -117.277081) (xy 429.363269 -117.323594) (xy 429.386941 -117.374091)
			(xy 429.403009 -117.427498) (xy 429.411129 -117.482674) (xy 429.411638 -117.51056) (xy 429.411129 -117.538446)
			(xy 429.403009 -117.593622) (xy 429.386941 -117.647029) (xy 429.363269 -117.697526) (xy 429.332496 -117.744039)
			(xy 429.295279 -117.785576) (xy 429.252411 -117.821251) (xy 429.204805 -117.850305) (xy 429.153476 -117.872117)
			(xy 429.099519 -117.886223) (xy 429.044082 -117.892323) (xy 428.988348 -117.890286) (xy 428.933505 -117.880156)
			(xy 428.880721 -117.862149) (xy 428.831121 -117.836648) (xy 428.785763 -117.804197) (xy 428.745614 -117.765488)
			(xy 428.711528 -117.721345) (xy 428.684232 -117.67271) (xy 428.664309 -117.620619) (xy 428.652183 -117.566182)
			(xy 428.648112 -117.51056) (xy 428.342826 -117.51056) (xy 428.347639 -117.526558) (xy 428.355759 -117.581734)
			(xy 428.356268 -117.60962) (xy 428.355759 -117.637506) (xy 428.347639 -117.692682) (xy 428.331571 -117.746089)
			(xy 428.307899 -117.796586) (xy 428.277126 -117.843099) (xy 428.239909 -117.884636) (xy 428.197041 -117.920311)
			(xy 428.149435 -117.949365) (xy 428.098106 -117.971177) (xy 428.044149 -117.985283) (xy 427.988712 -117.991383)
			(xy 427.932978 -117.989346) (xy 427.878135 -117.979216) (xy 427.825351 -117.961209) (xy 427.775751 -117.935708)
			(xy 427.730393 -117.903257) (xy 427.690244 -117.864548) (xy 427.656158 -117.820405) (xy 427.628862 -117.77177)
			(xy 427.608939 -117.719679) (xy 427.596813 -117.665242) (xy 427.592742 -117.60962) (xy 412.105094 -117.60962)
			(xy 411.639766 -118.074948) (xy 443.284862 -118.074948) (xy 443.288933 -118.019326) (xy 443.301059 -117.964889)
			(xy 443.320982 -117.912798) (xy 443.348278 -117.864163) (xy 443.382364 -117.82002) (xy 443.422513 -117.781311)
			(xy 443.467871 -117.74886) (xy 443.517471 -117.723359) (xy 443.570255 -117.705352) (xy 443.625098 -117.695222)
			(xy 443.680832 -117.693185) (xy 443.736269 -117.699285) (xy 443.790226 -117.713391) (xy 443.841555 -117.735203)
			(xy 443.889161 -117.764257) (xy 443.932029 -117.799932) (xy 443.969246 -117.841469) (xy 444.000019 -117.887982)
			(xy 444.023691 -117.938479) (xy 444.039759 -117.991886) (xy 444.047879 -118.047062) (xy 444.048388 -118.074948)
			(xy 444.047879 -118.102834) (xy 444.039759 -118.15801) (xy 444.023691 -118.211417) (xy 444.000019 -118.261914)
			(xy 443.969246 -118.308427) (xy 443.932029 -118.349964) (xy 443.889161 -118.385639) (xy 443.841555 -118.414693)
			(xy 443.790226 -118.436505) (xy 443.736269 -118.450611) (xy 443.680832 -118.456711) (xy 443.625098 -118.454674)
			(xy 443.570255 -118.444544) (xy 443.517471 -118.426537) (xy 443.467871 -118.401036) (xy 443.422513 -118.368585)
			(xy 443.382364 -118.329876) (xy 443.348278 -118.285733) (xy 443.320982 -118.237098) (xy 443.301059 -118.185007)
			(xy 443.288933 -118.13057) (xy 443.284862 -118.074948) (xy 411.639766 -118.074948) (xy 410.41574 -119.298974)
			(xy 410.41574 -119.916448) (xy 422.520362 -119.916448) (xy 422.524433 -119.860826) (xy 422.536559 -119.806389)
			(xy 422.556482 -119.754298) (xy 422.583778 -119.705663) (xy 422.617864 -119.66152) (xy 422.658013 -119.622811)
			(xy 422.703371 -119.59036) (xy 422.752971 -119.564859) (xy 422.805755 -119.546852) (xy 422.860598 -119.536722)
			(xy 422.916332 -119.534685) (xy 422.971769 -119.540785) (xy 423.025726 -119.554891) (xy 423.077055 -119.576703)
			(xy 423.124661 -119.605757) (xy 423.167529 -119.641432) (xy 423.204746 -119.682969) (xy 423.235519 -119.729482)
			(xy 423.259191 -119.779979) (xy 423.275259 -119.833386) (xy 423.283379 -119.888562) (xy 423.283888 -119.916448)
			(xy 423.283379 -119.944334) (xy 423.275259 -119.99951) (xy 423.259191 -120.052917) (xy 423.235519 -120.103414)
			(xy 423.204746 -120.149927) (xy 423.167529 -120.191464) (xy 423.124661 -120.227139) (xy 423.077055 -120.256193)
			(xy 423.025726 -120.278005) (xy 422.971769 -120.292111) (xy 422.916332 -120.298211) (xy 422.860598 -120.296174)
			(xy 422.805755 -120.286044) (xy 422.752971 -120.268037) (xy 422.703371 -120.242536) (xy 422.658013 -120.210085)
			(xy 422.617864 -120.171376) (xy 422.583778 -120.127233) (xy 422.556482 -120.078598) (xy 422.536559 -120.026507)
			(xy 422.524433 -119.97207) (xy 422.520362 -119.916448) (xy 410.41574 -119.916448) (xy 410.41574 -141.9225)
			(xy 411.205934 -141.9225) (xy 411.230917 -141.923014) (xy 411.280262 -141.930868) (xy 411.327776 -141.946332)
			(xy 411.372292 -141.969026) (xy 411.412718 -141.998392) (xy 411.430724 -142.015718) (xy 411.584385 -142.169388)
			(xy 412.820612 -142.169388) (xy 412.820612 -131.136644) (xy 412.821243 -131.106668) (xy 412.830626 -131.047456)
			(xy 412.849152 -130.990438) (xy 412.876365 -130.937019) (xy 412.911596 -130.888512) (xy 412.932372 -130.866896)
			(xy 421.99179 -121.807478) (xy 422.013362 -121.786741) (xy 422.061791 -121.751601) (xy 422.115112 -121.724451)
			(xy 422.172018 -121.705959) (xy 422.231113 -121.696576) (xy 422.26103 -121.695972) (xy 422.261538 -121.695972)
			(xy 422.288773 -121.696396) (xy 422.342689 -121.704154) (xy 422.394951 -121.719505) (xy 422.444497 -121.742137)
			(xy 422.490318 -121.77159) (xy 422.531481 -121.807264) (xy 422.567148 -121.848433) (xy 422.596594 -121.894259)
			(xy 422.619218 -121.943809) (xy 422.63456 -121.996074) (xy 422.642308 -122.049991) (xy 422.642792 -122.077226)
			(xy 422.642792 -122.077734) (xy 422.642172 -122.107652) (xy 422.632813 -122.16675) (xy 422.614328 -122.223659)
			(xy 422.587174 -122.276978) (xy 422.552018 -122.325397) (xy 422.531286 -122.346974) (xy 413.583628 -131.294632)
			(xy 413.583628 -142.0114) (xy 413.909256 -142.337028) (xy 414.992312 -142.337028) (xy 414.992312 -134.87908)
			(xy 414.992939 -134.854084) (xy 415.002747 -134.805061) (xy 415.021923 -134.75889) (xy 415.049732 -134.717344)
			(xy 415.066988 -134.699248) (xy 421.05072 -128.715516) (xy 421.068816 -128.69826) (xy 421.11036 -128.670449)
			(xy 421.156532 -128.651276) (xy 421.205556 -128.641477) (xy 421.230552 -128.64084) (xy 425.398692 -128.64084)
			(xy 425.398692 -118.73484) (xy 431.253392 -118.73484) (xy 431.572946 -119.054626) (xy 431.95824 -119.054626)
			(xy 431.962311 -118.999004) (xy 431.974437 -118.944567) (xy 431.99436 -118.892476) (xy 432.021656 -118.843841)
			(xy 432.055742 -118.799698) (xy 432.095891 -118.760989) (xy 432.141249 -118.728538) (xy 432.190849 -118.703037)
			(xy 432.243633 -118.68503) (xy 432.298476 -118.6749) (xy 432.35421 -118.672863) (xy 432.409647 -118.678963)
			(xy 432.463604 -118.693069) (xy 432.514933 -118.714881) (xy 432.562539 -118.743935) (xy 432.605407 -118.77961)
			(xy 432.642624 -118.821147) (xy 432.673397 -118.86766) (xy 432.697069 -118.918157) (xy 432.713137 -118.971564)
			(xy 432.721257 -119.02674) (xy 432.721766 -119.054626) (xy 432.721257 -119.082512) (xy 432.713137 -119.137688)
			(xy 432.697069 -119.191095) (xy 432.696269 -119.192802) (xy 436.989726 -119.192802) (xy 436.993797 -119.13718)
			(xy 437.005923 -119.082743) (xy 437.025846 -119.030652) (xy 437.053142 -118.982017) (xy 437.087228 -118.937874)
			(xy 437.127377 -118.899165) (xy 437.172735 -118.866714) (xy 437.222335 -118.841213) (xy 437.275119 -118.823206)
			(xy 437.329962 -118.813076) (xy 437.385696 -118.811039) (xy 437.441133 -118.817139) (xy 437.49509 -118.831245)
			(xy 437.546419 -118.853057) (xy 437.594025 -118.882111) (xy 437.636893 -118.917786) (xy 437.67411 -118.959323)
			(xy 437.704883 -119.005836) (xy 437.728555 -119.056333) (xy 437.744623 -119.10974) (xy 437.752743 -119.164916)
			(xy 437.753252 -119.192802) (xy 437.752743 -119.220688) (xy 437.744623 -119.275864) (xy 437.728555 -119.329271)
			(xy 437.704883 -119.379768) (xy 437.67411 -119.426281) (xy 437.636893 -119.467818) (xy 437.594025 -119.503493)
			(xy 437.546419 -119.532547) (xy 437.49509 -119.554359) (xy 437.441133 -119.568465) (xy 437.385696 -119.574565)
			(xy 437.329962 -119.572528) (xy 437.275119 -119.562398) (xy 437.222335 -119.544391) (xy 437.172735 -119.51889)
			(xy 437.127377 -119.486439) (xy 437.087228 -119.44773) (xy 437.053142 -119.403587) (xy 437.025846 -119.354952)
			(xy 437.005923 -119.302861) (xy 436.993797 -119.248424) (xy 436.989726 -119.192802) (xy 432.696269 -119.192802)
			(xy 432.673397 -119.241592) (xy 432.642624 -119.288105) (xy 432.605407 -119.329642) (xy 432.562539 -119.365317)
			(xy 432.514933 -119.394371) (xy 432.463604 -119.416183) (xy 432.409647 -119.430289) (xy 432.35421 -119.436389)
			(xy 432.298476 -119.434352) (xy 432.243633 -119.424222) (xy 432.190849 -119.406215) (xy 432.141249 -119.380714)
			(xy 432.095891 -119.348263) (xy 432.055742 -119.309554) (xy 432.021656 -119.265411) (xy 431.99436 -119.216776)
			(xy 431.974437 -119.164685) (xy 431.962311 -119.110248) (xy 431.95824 -119.054626) (xy 431.572946 -119.054626)
			(xy 431.603404 -119.085106) (xy 431.603404 -119.584216) (xy 433.69814 -119.584216) (xy 433.702211 -119.528594)
			(xy 433.714337 -119.474157) (xy 433.73426 -119.422066) (xy 433.761556 -119.373431) (xy 433.795642 -119.329288)
			(xy 433.835791 -119.290579) (xy 433.881149 -119.258128) (xy 433.930749 -119.232627) (xy 433.983533 -119.21462)
			(xy 434.038376 -119.20449) (xy 434.09411 -119.202453) (xy 434.149547 -119.208553) (xy 434.203504 -119.222659)
			(xy 434.254833 -119.244471) (xy 434.302439 -119.273525) (xy 434.345307 -119.3092) (xy 434.382524 -119.350737)
			(xy 434.413297 -119.39725) (xy 434.436969 -119.447747) (xy 434.453037 -119.501154) (xy 434.461157 -119.55633)
			(xy 434.461666 -119.584216) (xy 434.96814 -119.584216) (xy 434.972211 -119.528594) (xy 434.984337 -119.474157)
			(xy 435.00426 -119.422066) (xy 435.031556 -119.373431) (xy 435.065642 -119.329288) (xy 435.105791 -119.290579)
			(xy 435.151149 -119.258128) (xy 435.200749 -119.232627) (xy 435.253533 -119.21462) (xy 435.308376 -119.20449)
			(xy 435.36411 -119.202453) (xy 435.419547 -119.208553) (xy 435.473504 -119.222659) (xy 435.524833 -119.244471)
			(xy 435.572439 -119.273525) (xy 435.615307 -119.3092) (xy 435.652524 -119.350737) (xy 435.683297 -119.39725)
			(xy 435.706969 -119.447747) (xy 435.723037 -119.501154) (xy 435.731157 -119.55633) (xy 435.731666 -119.584216)
			(xy 435.731157 -119.612102) (xy 435.723037 -119.667278) (xy 435.706969 -119.720685) (xy 435.683297 -119.771182)
			(xy 435.652524 -119.817695) (xy 435.615307 -119.859232) (xy 435.572439 -119.894907) (xy 435.524833 -119.923961)
			(xy 435.473504 -119.945773) (xy 435.419547 -119.959879) (xy 435.36411 -119.965979) (xy 435.308376 -119.963942)
			(xy 435.253533 -119.953812) (xy 435.200749 -119.935805) (xy 435.151149 -119.910304) (xy 435.105791 -119.877853)
			(xy 435.065642 -119.839144) (xy 435.031556 -119.795001) (xy 435.00426 -119.746366) (xy 434.984337 -119.694275)
			(xy 434.972211 -119.639838) (xy 434.96814 -119.584216) (xy 434.461666 -119.584216) (xy 434.461157 -119.612102)
			(xy 434.453037 -119.667278) (xy 434.436969 -119.720685) (xy 434.413297 -119.771182) (xy 434.382524 -119.817695)
			(xy 434.345307 -119.859232) (xy 434.302439 -119.894907) (xy 434.254833 -119.923961) (xy 434.203504 -119.945773)
			(xy 434.149547 -119.959879) (xy 434.09411 -119.965979) (xy 434.038376 -119.963942) (xy 433.983533 -119.953812)
			(xy 433.930749 -119.935805) (xy 433.881149 -119.910304) (xy 433.835791 -119.877853) (xy 433.795642 -119.839144)
			(xy 433.761556 -119.795001) (xy 433.73426 -119.746366) (xy 433.714337 -119.694275) (xy 433.702211 -119.639838)
			(xy 433.69814 -119.584216) (xy 431.603404 -119.584216) (xy 431.603404 -120.120664) (xy 431.226803 -120.497346)
			(xy 435.408576 -120.497346) (xy 435.412647 -120.441724) (xy 435.424773 -120.387287) (xy 435.444696 -120.335196)
			(xy 435.471992 -120.286561) (xy 435.506078 -120.242418) (xy 435.546227 -120.203709) (xy 435.591585 -120.171258)
			(xy 435.641185 -120.145757) (xy 435.693969 -120.12775) (xy 435.748812 -120.11762) (xy 435.804546 -120.115583)
			(xy 435.859983 -120.121683) (xy 435.91394 -120.135789) (xy 435.965269 -120.157601) (xy 436.012875 -120.186655)
			(xy 436.055743 -120.22233) (xy 436.09296 -120.263867) (xy 436.123733 -120.31038) (xy 436.147405 -120.360877)
			(xy 436.163473 -120.414284) (xy 436.171593 -120.46946) (xy 436.172102 -120.497346) (xy 436.171593 -120.525232)
			(xy 436.163473 -120.580408) (xy 436.147405 -120.633815) (xy 436.123733 -120.684312) (xy 436.09296 -120.730825)
			(xy 436.055743 -120.772362) (xy 436.012875 -120.808037) (xy 435.965269 -120.837091) (xy 435.91394 -120.858903)
			(xy 435.859983 -120.873009) (xy 435.804546 -120.879109) (xy 435.748812 -120.877072) (xy 435.693969 -120.866942)
			(xy 435.641185 -120.848935) (xy 435.591585 -120.823434) (xy 435.546227 -120.790983) (xy 435.506078 -120.752274)
			(xy 435.471992 -120.708131) (xy 435.444696 -120.659496) (xy 435.424773 -120.607405) (xy 435.412647 -120.552968)
			(xy 435.408576 -120.497346) (xy 431.226803 -120.497346) (xy 430.419764 -121.304558) (xy 430.419764 -121.524522)
			(xy 435.516018 -121.524522) (xy 435.520089 -121.4689) (xy 435.532215 -121.414463) (xy 435.552138 -121.362372)
			(xy 435.579434 -121.313737) (xy 435.61352 -121.269594) (xy 435.653669 -121.230885) (xy 435.699027 -121.198434)
			(xy 435.748627 -121.172933) (xy 435.801411 -121.154926) (xy 435.856254 -121.144796) (xy 435.911988 -121.142759)
			(xy 435.967425 -121.148859) (xy 436.021382 -121.162965) (xy 436.072711 -121.184777) (xy 436.120317 -121.213831)
			(xy 436.163185 -121.249506) (xy 436.200402 -121.291043) (xy 436.231175 -121.337556) (xy 436.254847 -121.388053)
			(xy 436.26679 -121.427748) (xy 439.280298 -121.427748) (xy 439.284369 -121.372126) (xy 439.296495 -121.317689)
			(xy 439.316418 -121.265598) (xy 439.343714 -121.216963) (xy 439.3778 -121.17282) (xy 439.417949 -121.134111)
			(xy 439.463307 -121.10166) (xy 439.512907 -121.076159) (xy 439.565691 -121.058152) (xy 439.620534 -121.048022)
			(xy 439.676268 -121.045985) (xy 439.731705 -121.052085) (xy 439.785662 -121.066191) (xy 439.836991 -121.088003)
			(xy 439.884597 -121.117057) (xy 439.927465 -121.152732) (xy 439.964682 -121.194269) (xy 439.995455 -121.240782)
			(xy 440.019127 -121.291279) (xy 440.035195 -121.344686) (xy 440.043315 -121.399862) (xy 440.043824 -121.427748)
			(xy 440.043315 -121.455634) (xy 440.035195 -121.51081) (xy 440.019127 -121.564217) (xy 439.995455 -121.614714)
			(xy 439.964682 -121.661227) (xy 439.927465 -121.702764) (xy 439.884597 -121.738439) (xy 439.836991 -121.767493)
			(xy 439.785662 -121.789305) (xy 439.731705 -121.803411) (xy 439.676268 -121.809511) (xy 439.620534 -121.807474)
			(xy 439.565691 -121.797344) (xy 439.512907 -121.779337) (xy 439.463307 -121.753836) (xy 439.417949 -121.721385)
			(xy 439.3778 -121.682676) (xy 439.343714 -121.638533) (xy 439.316418 -121.589898) (xy 439.296495 -121.537807)
			(xy 439.284369 -121.48337) (xy 439.280298 -121.427748) (xy 436.26679 -121.427748) (xy 436.270915 -121.44146)
			(xy 436.279035 -121.496636) (xy 436.279544 -121.524522) (xy 436.279035 -121.552408) (xy 436.270915 -121.607584)
			(xy 436.254847 -121.660991) (xy 436.231175 -121.711488) (xy 436.200402 -121.758001) (xy 436.163185 -121.799538)
			(xy 436.120317 -121.835213) (xy 436.072711 -121.864267) (xy 436.021382 -121.886079) (xy 435.967425 -121.900185)
			(xy 435.911988 -121.906285) (xy 435.856254 -121.904248) (xy 435.801411 -121.894118) (xy 435.748627 -121.876111)
			(xy 435.699027 -121.85061) (xy 435.653669 -121.818159) (xy 435.61352 -121.77945) (xy 435.579434 -121.735307)
			(xy 435.552138 -121.686672) (xy 435.532215 -121.634581) (xy 435.520089 -121.580144) (xy 435.516018 -121.524522)
			(xy 430.419764 -121.524522) (xy 430.419764 -122.158506) (xy 441.404246 -122.158506) (xy 441.408317 -122.102884)
			(xy 441.420443 -122.048447) (xy 441.440366 -121.996356) (xy 441.467662 -121.947721) (xy 441.501748 -121.903578)
			(xy 441.541897 -121.864869) (xy 441.587255 -121.832418) (xy 441.636855 -121.806917) (xy 441.689639 -121.78891)
			(xy 441.744482 -121.77878) (xy 441.800216 -121.776743) (xy 441.855653 -121.782843) (xy 441.90961 -121.796949)
			(xy 441.960939 -121.818761) (xy 442.008545 -121.847815) (xy 442.051413 -121.88349) (xy 442.08863 -121.925027)
			(xy 442.119403 -121.97154) (xy 442.143075 -122.022037) (xy 442.159143 -122.075444) (xy 442.167263 -122.13062)
			(xy 442.167772 -122.158506) (xy 442.167263 -122.186392) (xy 442.159143 -122.241568) (xy 442.143075 -122.294975)
			(xy 442.119403 -122.345472) (xy 442.08863 -122.391985) (xy 442.051413 -122.433522) (xy 442.008545 -122.469197)
			(xy 441.960939 -122.498251) (xy 441.90961 -122.520063) (xy 441.855653 -122.534169) (xy 441.800216 -122.540269)
			(xy 441.744482 -122.538232) (xy 441.689639 -122.528102) (xy 441.636855 -122.510095) (xy 441.587255 -122.484594)
			(xy 441.541897 -122.452143) (xy 441.501748 -122.413434) (xy 441.467662 -122.369291) (xy 441.440366 -122.320656)
			(xy 441.420443 -122.268565) (xy 441.408317 -122.214128) (xy 441.404246 -122.158506) (xy 430.419764 -122.158506)
			(xy 430.419764 -122.86488) (xy 435.519574 -122.86488) (xy 435.523645 -122.809258) (xy 435.535771 -122.754821)
			(xy 435.555694 -122.70273) (xy 435.58299 -122.654095) (xy 435.617076 -122.609952) (xy 435.657225 -122.571243)
			(xy 435.702583 -122.538792) (xy 435.752183 -122.513291) (xy 435.804967 -122.495284) (xy 435.85981 -122.485154)
			(xy 435.915544 -122.483117) (xy 435.970981 -122.489217) (xy 436.024938 -122.503323) (xy 436.076267 -122.525135)
			(xy 436.123873 -122.554189) (xy 436.166741 -122.589864) (xy 436.203958 -122.631401) (xy 436.21542 -122.648726)
			(xy 437.90057 -122.648726) (xy 437.904641 -122.593104) (xy 437.916767 -122.538667) (xy 437.93669 -122.486576)
			(xy 437.963986 -122.437941) (xy 437.998072 -122.393798) (xy 438.038221 -122.355089) (xy 438.083579 -122.322638)
			(xy 438.133179 -122.297137) (xy 438.185963 -122.27913) (xy 438.240806 -122.269) (xy 438.29654 -122.266963)
			(xy 438.351977 -122.273063) (xy 438.405934 -122.287169) (xy 438.457263 -122.308981) (xy 438.504869 -122.338035)
			(xy 438.547737 -122.37371) (xy 438.584954 -122.415247) (xy 438.615727 -122.46176) (xy 438.639399 -122.512257)
			(xy 438.655467 -122.565664) (xy 438.663587 -122.62084) (xy 438.664096 -122.648726) (xy 438.663587 -122.676612)
			(xy 438.655467 -122.731788) (xy 438.639399 -122.785195) (xy 438.615727 -122.835692) (xy 438.584954 -122.882205)
			(xy 438.547737 -122.923742) (xy 438.504869 -122.959417) (xy 438.457263 -122.988471) (xy 438.405934 -123.010283)
			(xy 438.351977 -123.024389) (xy 438.29654 -123.030489) (xy 438.240806 -123.028452) (xy 438.185963 -123.018322)
			(xy 438.133179 -123.000315) (xy 438.083579 -122.974814) (xy 438.038221 -122.942363) (xy 437.998072 -122.903654)
			(xy 437.963986 -122.859511) (xy 437.93669 -122.810876) (xy 437.916767 -122.758785) (xy 437.904641 -122.704348)
			(xy 437.90057 -122.648726) (xy 436.21542 -122.648726) (xy 436.234731 -122.677914) (xy 436.258403 -122.728411)
			(xy 436.274471 -122.781818) (xy 436.282591 -122.836994) (xy 436.2831 -122.86488) (xy 436.282591 -122.892766)
			(xy 436.274471 -122.947942) (xy 436.258403 -123.001349) (xy 436.234731 -123.051846) (xy 436.203958 -123.098359)
			(xy 436.166741 -123.139896) (xy 436.123873 -123.175571) (xy 436.076267 -123.204625) (xy 436.024938 -123.226437)
			(xy 435.970981 -123.240543) (xy 435.915544 -123.246643) (xy 435.85981 -123.244606) (xy 435.804967 -123.234476)
			(xy 435.752183 -123.216469) (xy 435.702583 -123.190968) (xy 435.657225 -123.158517) (xy 435.617076 -123.119808)
			(xy 435.58299 -123.075665) (xy 435.555694 -123.02703) (xy 435.535771 -122.974939) (xy 435.523645 -122.920502)
			(xy 435.519574 -122.86488) (xy 430.419764 -122.86488) (xy 430.419764 -123.87199) (xy 435.521606 -123.87199)
			(xy 435.525677 -123.816368) (xy 435.537803 -123.761931) (xy 435.557726 -123.70984) (xy 435.585022 -123.661205)
			(xy 435.619108 -123.617062) (xy 435.659257 -123.578353) (xy 435.704615 -123.545902) (xy 435.754215 -123.520401)
			(xy 435.806999 -123.502394) (xy 435.861842 -123.492264) (xy 435.917576 -123.490227) (xy 435.973013 -123.496327)
			(xy 436.02697 -123.510433) (xy 436.078299 -123.532245) (xy 436.125905 -123.561299) (xy 436.168773 -123.596974)
			(xy 436.20599 -123.638511) (xy 436.223334 -123.664726) (xy 439.889898 -123.664726) (xy 439.893969 -123.609104)
			(xy 439.906095 -123.554667) (xy 439.926018 -123.502576) (xy 439.953314 -123.453941) (xy 439.9874 -123.409798)
			(xy 440.027549 -123.371089) (xy 440.072907 -123.338638) (xy 440.122507 -123.313137) (xy 440.175291 -123.29513)
			(xy 440.230134 -123.285) (xy 440.285868 -123.282963) (xy 440.341305 -123.289063) (xy 440.395262 -123.303169)
			(xy 440.446591 -123.324981) (xy 440.494197 -123.354035) (xy 440.537065 -123.38971) (xy 440.574282 -123.431247)
			(xy 440.605055 -123.47776) (xy 440.628727 -123.528257) (xy 440.644795 -123.581664) (xy 440.652915 -123.63684)
			(xy 440.653424 -123.664726) (xy 440.652915 -123.692612) (xy 440.644795 -123.747788) (xy 440.628727 -123.801195)
			(xy 440.605055 -123.851692) (xy 440.574282 -123.898205) (xy 440.537065 -123.939742) (xy 440.494197 -123.975417)
			(xy 440.446591 -124.004471) (xy 440.395262 -124.026283) (xy 440.341305 -124.040389) (xy 440.285868 -124.046489)
			(xy 440.230134 -124.044452) (xy 440.175291 -124.034322) (xy 440.122507 -124.016315) (xy 440.072907 -123.990814)
			(xy 440.027549 -123.958363) (xy 439.9874 -123.919654) (xy 439.953314 -123.875511) (xy 439.926018 -123.826876)
			(xy 439.906095 -123.774785) (xy 439.893969 -123.720348) (xy 439.889898 -123.664726) (xy 436.223334 -123.664726)
			(xy 436.236763 -123.685024) (xy 436.260435 -123.735521) (xy 436.276503 -123.788928) (xy 436.284623 -123.844104)
			(xy 436.285132 -123.87199) (xy 436.284623 -123.899876) (xy 436.276503 -123.955052) (xy 436.260435 -124.008459)
			(xy 436.236763 -124.058956) (xy 436.20599 -124.105469) (xy 436.168773 -124.147006) (xy 436.125905 -124.182681)
			(xy 436.078299 -124.211735) (xy 436.02697 -124.233547) (xy 435.973013 -124.247653) (xy 435.917576 -124.253753)
			(xy 435.861842 -124.251716) (xy 435.806999 -124.241586) (xy 435.754215 -124.223579) (xy 435.704615 -124.198078)
			(xy 435.659257 -124.165627) (xy 435.619108 -124.126918) (xy 435.585022 -124.082775) (xy 435.557726 -124.03414)
			(xy 435.537803 -123.982049) (xy 435.525677 -123.927612) (xy 435.521606 -123.87199) (xy 430.419764 -123.87199)
			(xy 430.419764 -124.823728) (xy 430.481694 -124.885704) (xy 435.552594 -124.885704) (xy 435.556665 -124.830082)
			(xy 435.568791 -124.775645) (xy 435.588714 -124.723554) (xy 435.61601 -124.674919) (xy 435.650096 -124.630776)
			(xy 435.690245 -124.592067) (xy 435.735603 -124.559616) (xy 435.785203 -124.534115) (xy 435.837987 -124.516108)
			(xy 435.89283 -124.505978) (xy 435.948564 -124.503941) (xy 436.004001 -124.510041) (xy 436.057958 -124.524147)
			(xy 436.109287 -124.545959) (xy 436.156893 -124.575013) (xy 436.199761 -124.610688) (xy 436.236978 -124.652225)
			(xy 436.255834 -124.680726) (xy 439.889898 -124.680726) (xy 439.893969 -124.625104) (xy 439.906095 -124.570667)
			(xy 439.926018 -124.518576) (xy 439.953314 -124.469941) (xy 439.9874 -124.425798) (xy 440.027549 -124.387089)
			(xy 440.072907 -124.354638) (xy 440.122507 -124.329137) (xy 440.175291 -124.31113) (xy 440.230134 -124.301)
			(xy 440.285868 -124.298963) (xy 440.341305 -124.305063) (xy 440.395262 -124.319169) (xy 440.446591 -124.340981)
			(xy 440.494197 -124.370035) (xy 440.537065 -124.40571) (xy 440.574282 -124.447247) (xy 440.605055 -124.49376)
			(xy 440.628727 -124.544257) (xy 440.644795 -124.597664) (xy 440.652915 -124.65284) (xy 440.653424 -124.680726)
			(xy 440.652915 -124.708612) (xy 440.644795 -124.763788) (xy 440.628727 -124.817195) (xy 440.605055 -124.867692)
			(xy 440.574282 -124.914205) (xy 440.537065 -124.955742) (xy 440.494197 -124.991417) (xy 440.446591 -125.020471)
			(xy 440.395262 -125.042283) (xy 440.341305 -125.056389) (xy 440.285868 -125.062489) (xy 440.230134 -125.060452)
			(xy 440.175291 -125.050322) (xy 440.122507 -125.032315) (xy 440.072907 -125.006814) (xy 440.027549 -124.974363)
			(xy 439.9874 -124.935654) (xy 439.953314 -124.891511) (xy 439.926018 -124.842876) (xy 439.906095 -124.790785)
			(xy 439.893969 -124.736348) (xy 439.889898 -124.680726) (xy 436.255834 -124.680726) (xy 436.267751 -124.698738)
			(xy 436.291423 -124.749235) (xy 436.307491 -124.802642) (xy 436.315611 -124.857818) (xy 436.31612 -124.885704)
			(xy 436.315611 -124.91359) (xy 436.307491 -124.968766) (xy 436.291423 -125.022173) (xy 436.267751 -125.07267)
			(xy 436.236978 -125.119183) (xy 436.199761 -125.16072) (xy 436.156893 -125.196395) (xy 436.109287 -125.225449)
			(xy 436.057958 -125.247261) (xy 436.004001 -125.261367) (xy 435.948564 -125.267467) (xy 435.89283 -125.26543)
			(xy 435.837987 -125.2553) (xy 435.785203 -125.237293) (xy 435.735603 -125.211792) (xy 435.690245 -125.179341)
			(xy 435.650096 -125.140632) (xy 435.61601 -125.096489) (xy 435.588714 -125.047854) (xy 435.568791 -124.995763)
			(xy 435.556665 -124.941326) (xy 435.552594 -124.885704) (xy 430.481694 -124.885704) (xy 430.761902 -125.16612)
			(xy 431.224436 -125.16612) (xy 431.957462 -125.89891) (xy 435.50408 -125.89891) (xy 435.508151 -125.843288)
			(xy 435.520277 -125.788851) (xy 435.5402 -125.73676) (xy 435.567496 -125.688125) (xy 435.601582 -125.643982)
			(xy 435.641731 -125.605273) (xy 435.687089 -125.572822) (xy 435.736689 -125.547321) (xy 435.789473 -125.529314)
			(xy 435.844316 -125.519184) (xy 435.90005 -125.517147) (xy 435.955487 -125.523247) (xy 436.009444 -125.537353)
			(xy 436.060773 -125.559165) (xy 436.108379 -125.588219) (xy 436.151247 -125.623894) (xy 436.188464 -125.665431)
			(xy 436.219237 -125.711944) (xy 436.242909 -125.762441) (xy 436.258977 -125.815848) (xy 436.267097 -125.871024)
			(xy 436.267606 -125.89891) (xy 436.267097 -125.926796) (xy 436.258977 -125.981972) (xy 436.242909 -126.035379)
			(xy 436.219237 -126.085876) (xy 436.188464 -126.132389) (xy 436.151247 -126.173926) (xy 436.108379 -126.209601)
			(xy 436.060773 -126.238655) (xy 436.009444 -126.260467) (xy 435.955487 -126.274573) (xy 435.90005 -126.280673)
			(xy 435.844316 -126.278636) (xy 435.789473 -126.268506) (xy 435.736689 -126.250499) (xy 435.687089 -126.224998)
			(xy 435.641731 -126.192547) (xy 435.601582 -126.153838) (xy 435.567496 -126.109695) (xy 435.5402 -126.06106)
			(xy 435.520277 -126.008969) (xy 435.508151 -125.954532) (xy 435.50408 -125.89891) (xy 431.957462 -125.89891)
			(xy 432.014884 -125.956314) (xy 432.047396 -125.940312) (xy 432.073619 -125.928044) (xy 432.128862 -125.910729)
			(xy 432.18609 -125.901981) (xy 432.215036 -125.90145) (xy 432.21529 -125.90145) (xy 432.242539 -125.901987)
			(xy 432.296483 -125.909741) (xy 432.348774 -125.925093) (xy 432.398348 -125.94773) (xy 432.444197 -125.977191)
			(xy 432.485386 -126.012877) (xy 432.521077 -126.054062) (xy 432.550545 -126.099906) (xy 432.573189 -126.149477)
			(xy 432.588547 -126.201766) (xy 432.596309 -126.255709) (xy 432.596798 -126.282958) (xy 432.596258 -126.310514)
			(xy 432.588308 -126.365051) (xy 432.572596 -126.417877) (xy 432.54945 -126.467894) (xy 432.519349 -126.514062)
			(xy 432.482921 -126.55542) (xy 432.440923 -126.591107) (xy 432.394228 -126.620383) (xy 432.369214 -126.631954)
			(xy 432.338988 -126.645416) (xy 432.338988 -126.959614) (xy 432.374548 -126.97079) (xy 432.40149 -126.979873)
			(xy 432.452587 -127.004796) (xy 432.499421 -127.037025) (xy 432.540955 -127.075847) (xy 432.576268 -127.120401)
			(xy 432.60458 -127.169702) (xy 432.625262 -127.222659) (xy 432.637859 -127.278097) (xy 432.642089 -127.334792)
			(xy 432.637861 -127.391486) (xy 432.625267 -127.446925) (xy 432.604587 -127.499882) (xy 432.576278 -127.549185)
			(xy 432.540966 -127.593741) (xy 432.499435 -127.632564) (xy 432.452602 -127.664795) (xy 432.401505 -127.68972)
			(xy 432.374548 -127.698754) (xy 432.338988 -127.70993) (xy 432.338988 -128.199896) (xy 432.339616 -128.214839)
			(xy 432.348379 -128.243415) (xy 432.36504 -128.26823) (xy 432.388171 -128.287161) (xy 432.415792 -128.298584)
			(xy 432.445537 -128.301523) (xy 432.474859 -128.295726) (xy 432.501248 -128.281689) (xy 432.512216 -128.271524)
			(xy 432.77663 -128.007364) (xy 432.977544 -127.522224) (xy 432.987628 -127.499341) (xy 433.015389 -127.457756)
			(xy 433.032662 -127.439674) (xy 433.374292 -127.09779) (xy 433.374292 -127.021336) (xy 433.35956 -127.006604)
			(xy 433.338659 -126.985002) (xy 433.303247 -126.936435) (xy 433.275892 -126.882914) (xy 433.257274 -126.825764)
			(xy 433.247852 -126.766401) (xy 433.247292 -126.736348) (xy 433.247778 -126.709097) (xy 433.255534 -126.655149)
			(xy 433.270889 -126.602854) (xy 433.293531 -126.553277) (xy 433.322997 -126.507427) (xy 433.358688 -126.466236)
			(xy 433.399879 -126.430545) (xy 433.445729 -126.401079) (xy 433.495306 -126.378437) (xy 433.547601 -126.363082)
			(xy 433.601549 -126.355326) (xy 433.656051 -126.355326) (xy 433.709999 -126.363082) (xy 433.762294 -126.378437)
			(xy 433.811871 -126.401079) (xy 433.857721 -126.430545) (xy 433.898912 -126.466236) (xy 433.934603 -126.507427)
			(xy 433.964069 -126.553277) (xy 433.986711 -126.602854) (xy 434.002066 -126.655149) (xy 434.009822 -126.709097)
			(xy 434.010308 -126.736348) (xy 434.00987 -126.763083) (xy 434.002409 -126.81603) (xy 433.987627 -126.867416)
			(xy 433.965812 -126.916234) (xy 433.937393 -126.961527) (xy 433.902927 -127.002406) (xy 433.883308 -127.020574)
			(xy 433.883308 -127.2032) (xy 433.882692 -127.228197) (xy 433.872885 -127.277222) (xy 433.853705 -127.323393)
			(xy 433.825891 -127.364938) (xy 433.808632 -127.383032) (xy 433.76215 -127.429514) (xy 433.807616 -127.47498)
			(xy 433.820316 -127.478536) (xy 433.846759 -127.486326) (xy 433.897201 -127.508566) (xy 433.943916 -127.537836)
			(xy 433.98593 -127.573527) (xy 434.022368 -127.614894) (xy 434.052472 -127.661076) (xy 434.075613 -127.711111)
			(xy 434.09131 -127.763956) (xy 434.099235 -127.81851) (xy 434.099716 -127.846074) (xy 434.099297 -127.872454)
			(xy 434.092035 -127.924712) (xy 434.077645 -127.975473) (xy 434.056402 -128.023768) (xy 434.028711 -128.068677)
			(xy 433.995099 -128.109345) (xy 433.956207 -128.144997) (xy 433.912775 -128.174953) (xy 433.889404 -128.187196)
			(xy 433.877071 -128.193938) (xy 433.856351 -128.21291) (xy 433.841595 -128.236816) (xy 433.833924 -128.263842)
			(xy 433.833921 -128.291935) (xy 433.841586 -128.318963) (xy 433.856336 -128.342872) (xy 433.877052 -128.361848)
			(xy 433.889404 -128.368552) (xy 433.912764 -128.380812) (xy 433.956188 -128.410771) (xy 433.995074 -128.446424)
			(xy 434.028681 -128.487091) (xy 434.056369 -128.531997) (xy 434.077611 -128.580288) (xy 434.092002 -128.631043)
			(xy 434.099269 -128.683296) (xy 434.099716 -128.709674) (xy 434.09923 -128.736925) (xy 434.091474 -128.790873)
			(xy 434.076119 -128.843168) (xy 434.053477 -128.892745) (xy 434.024011 -128.938595) (xy 433.98832 -128.979786)
			(xy 433.947129 -129.015477) (xy 433.901279 -129.044943) (xy 433.851702 -129.067585) (xy 433.799407 -129.08294)
			(xy 433.745459 -129.090696) (xy 433.690957 -129.090696) (xy 433.637009 -129.08294) (xy 433.584714 -129.067585)
			(xy 433.535137 -129.044943) (xy 433.489287 -129.015477) (xy 433.448096 -128.979786) (xy 433.412405 -128.938595)
			(xy 433.382939 -128.892745) (xy 433.360297 -128.843168) (xy 433.344942 -128.790873) (xy 433.337186 -128.736925)
			(xy 433.3367 -128.709674) (xy 433.33715 -128.683295) (xy 433.344406 -128.631037) (xy 433.35879 -128.580278)
			(xy 433.380028 -128.531982) (xy 433.407715 -128.487073) (xy 433.441324 -128.446404) (xy 433.480213 -128.410752)
			(xy 433.523642 -128.380795) (xy 433.547012 -128.368552) (xy 433.559389 -128.361886) (xy 433.580112 -128.3429)
			(xy 433.594866 -128.31898) (xy 433.602533 -128.291941) (xy 433.60253 -128.263836) (xy 433.594857 -128.236799)
			(xy 433.580097 -128.212882) (xy 433.55937 -128.193901) (xy 433.547012 -128.187196) (xy 433.517483 -128.17156)
			(xy 433.463963 -128.131568) (xy 433.440586 -128.107694) (xy 433.430286 -128.097504) (xy 433.405284 -128.082886)
			(xy 433.377182 -128.075881) (xy 433.348244 -128.077053) (xy 433.3208 -128.086307) (xy 433.297062 -128.102898)
			(xy 433.27894 -128.12549) (xy 433.272946 -128.138682) (xy 433.227226 -128.248664) (xy 433.21715 -128.271551)
			(xy 433.189383 -128.313133) (xy 433.172108 -128.331214) (xy 432.583336 -128.919986) (xy 432.565229 -128.937211)
			(xy 432.523668 -128.96495) (xy 432.477497 -128.984057) (xy 432.428488 -128.993797) (xy 432.403504 -128.994408)
			(xy 432.338988 -128.994408) (xy 432.338988 -129.505456) (xy 431.631852 -129.505456) (xy 431.6222 -129.50952)
			(xy 431.597969 -129.519406) (xy 431.546761 -129.530159) (xy 431.5206 -129.530856) (xy 421.49395 -129.530856)
			(xy 420.519098 -130.505708) (xy 425.236638 -130.505708) (xy 425.240709 -130.450086) (xy 425.252835 -130.395649)
			(xy 425.272758 -130.343558) (xy 425.300054 -130.294923) (xy 425.33414 -130.25078) (xy 425.374289 -130.212071)
			(xy 425.419647 -130.17962) (xy 425.469247 -130.154119) (xy 425.522031 -130.136112) (xy 425.576874 -130.125982)
			(xy 425.632608 -130.123945) (xy 425.688045 -130.130045) (xy 425.742002 -130.144151) (xy 425.793331 -130.165963)
			(xy 425.840937 -130.195017) (xy 425.883805 -130.230692) (xy 425.921022 -130.272229) (xy 425.951795 -130.318742)
			(xy 425.956687 -130.329178) (xy 429.131728 -130.329178) (xy 429.135799 -130.273556) (xy 429.147925 -130.219119)
			(xy 429.167848 -130.167028) (xy 429.195144 -130.118393) (xy 429.22923 -130.07425) (xy 429.269379 -130.035541)
			(xy 429.314737 -130.00309) (xy 429.364337 -129.977589) (xy 429.417121 -129.959582) (xy 429.471964 -129.949452)
			(xy 429.527698 -129.947415) (xy 429.583135 -129.953515) (xy 429.637092 -129.967621) (xy 429.688421 -129.989433)
			(xy 429.736027 -130.018487) (xy 429.778895 -130.054162) (xy 429.816112 -130.095699) (xy 429.846885 -130.142212)
			(xy 429.870557 -130.192709) (xy 429.886625 -130.246116) (xy 429.894745 -130.301292) (xy 429.895254 -130.329178)
			(xy 431.304444 -130.329178) (xy 431.308515 -130.273556) (xy 431.320641 -130.219119) (xy 431.340564 -130.167028)
			(xy 431.36786 -130.118393) (xy 431.401946 -130.07425) (xy 431.442095 -130.035541) (xy 431.487453 -130.00309)
			(xy 431.537053 -129.977589) (xy 431.589837 -129.959582) (xy 431.64468 -129.949452) (xy 431.700414 -129.947415)
			(xy 431.755851 -129.953515) (xy 431.809808 -129.967621) (xy 431.861137 -129.989433) (xy 431.908743 -130.018487)
			(xy 431.951611 -130.054162) (xy 431.988828 -130.095699) (xy 432.019601 -130.142212) (xy 432.043273 -130.192709)
			(xy 432.059341 -130.246116) (xy 432.067461 -130.301292) (xy 432.06797 -130.329178) (xy 432.067461 -130.357064)
			(xy 432.059341 -130.41224) (xy 432.043273 -130.465647) (xy 432.040337 -130.471911) (xy 433.378888 -130.471911)
			(xy 433.378894 -130.41741) (xy 433.386656 -130.363464) (xy 433.402016 -130.311173) (xy 433.424662 -130.261599)
			(xy 433.454133 -130.215753) (xy 433.489828 -130.174568) (xy 433.531021 -130.138882) (xy 433.576873 -130.109422)
			(xy 433.626451 -130.086787) (xy 433.678746 -130.071438) (xy 433.732693 -130.063688) (xy 433.787194 -130.063694)
			(xy 433.84114 -130.071457) (xy 433.893431 -130.086818) (xy 433.943004 -130.109464) (xy 433.98885 -130.138935)
			(xy 434.030035 -130.174631) (xy 434.06572 -130.215824) (xy 434.09518 -130.261677) (xy 434.117814 -130.311255)
			(xy 434.133163 -130.36355) (xy 434.140912 -130.417497) (xy 434.141372 -130.444748) (xy 434.141021 -130.467824)
			(xy 434.135445 -130.513638) (xy 434.12437 -130.558442) (xy 434.11648 -130.58013) (xy 434.112148 -130.592902)
			(xy 434.109514 -130.61973) (xy 434.113997 -130.646312) (xy 434.125283 -130.670792) (xy 434.142586 -130.691463)
			(xy 434.164698 -130.706882) (xy 434.190076 -130.715973) (xy 434.216949 -130.718102) (xy 434.230272 -130.71602)
			(xy 434.247635 -130.712941) (xy 434.282744 -130.709636) (xy 434.300376 -130.709416) (xy 434.327631 -130.709829)
			(xy 434.381585 -130.717583) (xy 434.433888 -130.732937) (xy 434.483472 -130.755578) (xy 434.52933 -130.785045)
			(xy 434.570528 -130.820738) (xy 434.606226 -130.861931) (xy 434.635699 -130.907785) (xy 434.658346 -130.957367)
			(xy 434.673707 -131.009668) (xy 434.681467 -131.063621) (xy 434.681471 -131.118131) (xy 434.673717 -131.172085)
			(xy 434.658363 -131.224388) (xy 434.635722 -131.273972) (xy 434.606255 -131.31983) (xy 434.570562 -131.361028)
			(xy 434.529369 -131.396726) (xy 434.483515 -131.426199) (xy 434.433933 -131.448846) (xy 434.381632 -131.464207)
			(xy 434.327679 -131.471967) (xy 434.273169 -131.471971) (xy 434.219215 -131.464217) (xy 434.166912 -131.448863)
			(xy 434.117328 -131.426222) (xy 434.07147 -131.396755) (xy 434.030272 -131.361062) (xy 433.994574 -131.319869)
			(xy 433.965101 -131.274015) (xy 433.942454 -131.224433) (xy 433.927093 -131.172132) (xy 433.919333 -131.118179)
			(xy 433.918868 -131.090924) (xy 433.919209 -131.067847) (xy 433.924788 -131.022033) (xy 433.935868 -130.97723)
			(xy 433.94376 -130.955542) (xy 433.948192 -130.942799) (xy 433.950824 -130.915954) (xy 433.946334 -130.889357)
			(xy 433.935035 -130.864865) (xy 433.917716 -130.844186) (xy 433.895585 -130.828766) (xy 433.870188 -130.81968)
			(xy 433.843298 -130.817562) (xy 433.829968 -130.819652) (xy 433.812604 -130.822725) (xy 433.777496 -130.826034)
			(xy 433.759864 -130.826256) (xy 433.732614 -130.825706) (xy 433.678668 -130.817945) (xy 433.626376 -130.802585)
			(xy 433.576803 -130.77994) (xy 433.530957 -130.75047) (xy 433.489771 -130.714775) (xy 433.454085 -130.673583)
			(xy 433.424624 -130.62773) (xy 433.401988 -130.578152) (xy 433.386639 -130.525858) (xy 433.378888 -130.471911)
			(xy 432.040337 -130.471911) (xy 432.019601 -130.516144) (xy 431.988828 -130.562657) (xy 431.951611 -130.604194)
			(xy 431.908743 -130.639869) (xy 431.861137 -130.668923) (xy 431.809808 -130.690735) (xy 431.755851 -130.704841)
			(xy 431.700414 -130.710941) (xy 431.64468 -130.708904) (xy 431.589837 -130.698774) (xy 431.537053 -130.680767)
			(xy 431.487453 -130.655266) (xy 431.442095 -130.622815) (xy 431.401946 -130.584106) (xy 431.36786 -130.539963)
			(xy 431.340564 -130.491328) (xy 431.320641 -130.439237) (xy 431.308515 -130.3848) (xy 431.304444 -130.329178)
			(xy 429.895254 -130.329178) (xy 429.894745 -130.357064) (xy 429.886625 -130.41224) (xy 429.870557 -130.465647)
			(xy 429.846885 -130.516144) (xy 429.816112 -130.562657) (xy 429.778895 -130.604194) (xy 429.736027 -130.639869)
			(xy 429.688421 -130.668923) (xy 429.637092 -130.690735) (xy 429.583135 -130.704841) (xy 429.527698 -130.710941)
			(xy 429.471964 -130.708904) (xy 429.417121 -130.698774) (xy 429.364337 -130.680767) (xy 429.314737 -130.655266)
			(xy 429.269379 -130.622815) (xy 429.22923 -130.584106) (xy 429.195144 -130.539963) (xy 429.167848 -130.491328)
			(xy 429.147925 -130.439237) (xy 429.135799 -130.3848) (xy 429.131728 -130.329178) (xy 425.956687 -130.329178)
			(xy 425.975467 -130.369239) (xy 425.991535 -130.422646) (xy 425.999655 -130.477822) (xy 426.000164 -130.505708)
			(xy 425.999655 -130.533594) (xy 425.991535 -130.58877) (xy 425.975467 -130.642177) (xy 425.951795 -130.692674)
			(xy 425.926771 -130.730498) (xy 427.27829 -130.730498) (xy 427.282361 -130.674876) (xy 427.294487 -130.620439)
			(xy 427.31441 -130.568348) (xy 427.341706 -130.519713) (xy 427.375792 -130.47557) (xy 427.415941 -130.436861)
			(xy 427.461299 -130.40441) (xy 427.510899 -130.378909) (xy 427.563683 -130.360902) (xy 427.618526 -130.350772)
			(xy 427.67426 -130.348735) (xy 427.729697 -130.354835) (xy 427.783654 -130.368941) (xy 427.834983 -130.390753)
			(xy 427.882589 -130.419807) (xy 427.925457 -130.455482) (xy 427.962674 -130.497019) (xy 427.993447 -130.543532)
			(xy 428.017119 -130.594029) (xy 428.033187 -130.647436) (xy 428.041307 -130.702612) (xy 428.041816 -130.730498)
			(xy 428.041307 -130.758384) (xy 428.033187 -130.81356) (xy 428.017119 -130.866967) (xy 427.993447 -130.917464)
			(xy 427.962674 -130.963977) (xy 427.925457 -131.005514) (xy 427.882589 -131.041189) (xy 427.834983 -131.070243)
			(xy 427.783654 -131.092055) (xy 427.729697 -131.106161) (xy 427.67426 -131.112261) (xy 427.618526 -131.110224)
			(xy 427.563683 -131.100094) (xy 427.510899 -131.082087) (xy 427.461299 -131.056586) (xy 427.415941 -131.024135)
			(xy 427.375792 -130.985426) (xy 427.341706 -130.941283) (xy 427.31441 -130.892648) (xy 427.294487 -130.840557)
			(xy 427.282361 -130.78612) (xy 427.27829 -130.730498) (xy 425.926771 -130.730498) (xy 425.921022 -130.739187)
			(xy 425.883805 -130.780724) (xy 425.840937 -130.816399) (xy 425.793331 -130.845453) (xy 425.742002 -130.867265)
			(xy 425.688045 -130.881371) (xy 425.632608 -130.887471) (xy 425.576874 -130.885434) (xy 425.522031 -130.875304)
			(xy 425.469247 -130.857297) (xy 425.419647 -130.831796) (xy 425.374289 -130.799345) (xy 425.33414 -130.760636)
			(xy 425.300054 -130.716493) (xy 425.272758 -130.667858) (xy 425.252835 -130.615767) (xy 425.240709 -130.56133)
			(xy 425.236638 -130.505708) (xy 420.519098 -130.505708) (xy 419.475666 -131.54914) (xy 420.687752 -131.54914)
			(xy 420.691823 -131.493518) (xy 420.703949 -131.439081) (xy 420.723872 -131.38699) (xy 420.751168 -131.338355)
			(xy 420.785254 -131.294212) (xy 420.825403 -131.255503) (xy 420.870761 -131.223052) (xy 420.920361 -131.197551)
			(xy 420.973145 -131.179544) (xy 421.027988 -131.169414) (xy 421.083722 -131.167377) (xy 421.139159 -131.173477)
			(xy 421.193116 -131.187583) (xy 421.244445 -131.209395) (xy 421.292051 -131.238449) (xy 421.334919 -131.274124)
			(xy 421.372136 -131.315661) (xy 421.402909 -131.362174) (xy 421.426581 -131.412671) (xy 421.442649 -131.466078)
			(xy 421.450769 -131.521254) (xy 421.451278 -131.54914) (xy 421.450769 -131.577026) (xy 421.447509 -131.599178)
			(xy 428.565054 -131.599178) (xy 428.569125 -131.543556) (xy 428.581251 -131.489119) (xy 428.601174 -131.437028)
			(xy 428.62847 -131.388393) (xy 428.662556 -131.34425) (xy 428.702705 -131.305541) (xy 428.748063 -131.27309)
			(xy 428.797663 -131.247589) (xy 428.850447 -131.229582) (xy 428.90529 -131.219452) (xy 428.961024 -131.217415)
			(xy 429.016461 -131.223515) (xy 429.070418 -131.237621) (xy 429.121747 -131.259433) (xy 429.169353 -131.288487)
			(xy 429.212221 -131.324162) (xy 429.249438 -131.365699) (xy 429.280211 -131.412212) (xy 429.303883 -131.462709)
			(xy 429.319951 -131.516116) (xy 429.328071 -131.571292) (xy 429.32858 -131.599178) (xy 431.856386 -131.599178)
			(xy 431.860457 -131.543556) (xy 431.872583 -131.489119) (xy 431.892506 -131.437028) (xy 431.919802 -131.388393)
			(xy 431.953888 -131.34425) (xy 431.994037 -131.305541) (xy 432.039395 -131.27309) (xy 432.088995 -131.247589)
			(xy 432.141779 -131.229582) (xy 432.196622 -131.219452) (xy 432.252356 -131.217415) (xy 432.307793 -131.223515)
			(xy 432.36175 -131.237621) (xy 432.413079 -131.259433) (xy 432.460685 -131.288487) (xy 432.503553 -131.324162)
			(xy 432.54077 -131.365699) (xy 432.571543 -131.412212) (xy 432.595215 -131.462709) (xy 432.611283 -131.516116)
			(xy 432.619403 -131.571292) (xy 432.619912 -131.599178) (xy 432.619403 -131.627064) (xy 432.611283 -131.68224)
			(xy 432.595215 -131.735647) (xy 432.571543 -131.786144) (xy 432.54077 -131.832657) (xy 432.503553 -131.874194)
			(xy 432.460685 -131.909869) (xy 432.413079 -131.938923) (xy 432.36175 -131.960735) (xy 432.307793 -131.974841)
			(xy 432.252356 -131.980941) (xy 432.196622 -131.978904) (xy 432.141779 -131.968774) (xy 432.088995 -131.950767)
			(xy 432.039395 -131.925266) (xy 431.994037 -131.892815) (xy 431.953888 -131.854106) (xy 431.919802 -131.809963)
			(xy 431.892506 -131.761328) (xy 431.872583 -131.709237) (xy 431.860457 -131.6548) (xy 431.856386 -131.599178)
			(xy 429.32858 -131.599178) (xy 429.328071 -131.627064) (xy 429.319951 -131.68224) (xy 429.303883 -131.735647)
			(xy 429.280211 -131.786144) (xy 429.249438 -131.832657) (xy 429.212221 -131.874194) (xy 429.169353 -131.909869)
			(xy 429.121747 -131.938923) (xy 429.070418 -131.960735) (xy 429.016461 -131.974841) (xy 428.961024 -131.980941)
			(xy 428.90529 -131.978904) (xy 428.850447 -131.968774) (xy 428.797663 -131.950767) (xy 428.748063 -131.925266)
			(xy 428.702705 -131.892815) (xy 428.662556 -131.854106) (xy 428.62847 -131.809963) (xy 428.601174 -131.761328)
			(xy 428.581251 -131.709237) (xy 428.569125 -131.6548) (xy 428.565054 -131.599178) (xy 421.447509 -131.599178)
			(xy 421.442649 -131.632202) (xy 421.426581 -131.685609) (xy 421.402909 -131.736106) (xy 421.372136 -131.782619)
			(xy 421.334919 -131.824156) (xy 421.292051 -131.859831) (xy 421.244445 -131.888885) (xy 421.193116 -131.910697)
			(xy 421.139159 -131.924803) (xy 421.083722 -131.930903) (xy 421.027988 -131.928866) (xy 420.973145 -131.918736)
			(xy 420.920361 -131.900729) (xy 420.870761 -131.875228) (xy 420.825403 -131.842777) (xy 420.785254 -131.804068)
			(xy 420.751168 -131.759925) (xy 420.723872 -131.71129) (xy 420.703949 -131.659199) (xy 420.691823 -131.604762)
			(xy 420.687752 -131.54914) (xy 419.475666 -131.54914) (xy 415.882328 -135.142478) (xy 415.882328 -138.602556)
			(xy 419.001343 -138.602556) (xy 419.001343 -138.548044) (xy 419.009101 -138.494087) (xy 419.02446 -138.441784)
			(xy 419.047107 -138.392199) (xy 419.076581 -138.346342) (xy 419.112281 -138.305147) (xy 419.15348 -138.269452)
			(xy 419.199341 -138.239984) (xy 419.248929 -138.217344) (xy 419.301234 -138.201991) (xy 419.355192 -138.19424)
			(xy 419.382448 -138.19378) (xy 419.383718 -138.19378) (xy 419.397064 -138.19341) (xy 419.422861 -138.186561)
			(xy 419.445999 -138.173257) (xy 419.464897 -138.154408) (xy 419.47826 -138.131304) (xy 419.485176 -138.105525)
			(xy 419.485572 -138.09218) (xy 419.485572 -137.518394) (xy 419.460257 -137.510027) (xy 419.41222 -137.486904)
			(xy 419.368166 -137.456878) (xy 419.32908 -137.420621) (xy 419.295836 -137.378943) (xy 419.269175 -137.332775)
			(xy 419.249694 -137.283149) (xy 419.237828 -137.231174) (xy 419.233842 -137.17801) (xy 419.237825 -137.124846)
			(xy 419.249688 -137.07287) (xy 419.269166 -137.023243) (xy 419.295824 -136.977073) (xy 419.329067 -136.935394)
			(xy 419.368151 -136.899135) (xy 419.412203 -136.869107) (xy 419.460238 -136.84598) (xy 419.485572 -136.837674)
			(xy 419.485572 -136.502394) (xy 419.460257 -136.494027) (xy 419.41222 -136.470904) (xy 419.368166 -136.440878)
			(xy 419.32908 -136.404621) (xy 419.295836 -136.362943) (xy 419.269175 -136.316775) (xy 419.249694 -136.267149)
			(xy 419.237828 -136.215174) (xy 419.233842 -136.16201) (xy 419.237825 -136.108846) (xy 419.249688 -136.05687)
			(xy 419.269166 -136.007243) (xy 419.295824 -135.961073) (xy 419.329067 -135.919394) (xy 419.368151 -135.883135)
			(xy 419.412203 -135.853107) (xy 419.460238 -135.82998) (xy 419.485572 -135.821674) (xy 419.485572 -135.516366)
			(xy 419.450774 -135.504936) (xy 419.424209 -135.495684) (xy 419.373958 -135.470404) (xy 419.32796 -135.438023)
			(xy 419.287214 -135.399242) (xy 419.2526 -135.3549) (xy 419.224868 -135.305959) (xy 419.20462 -135.253478)
			(xy 419.192294 -135.198593) (xy 419.188156 -135.142493) (xy 419.192296 -135.086394) (xy 419.204624 -135.031509)
			(xy 419.224874 -134.979029) (xy 419.252607 -134.930088) (xy 419.287223 -134.885748) (xy 419.327971 -134.846968)
			(xy 419.37397 -134.814589) (xy 419.424222 -134.78931) (xy 419.450774 -134.78002) (xy 419.485572 -134.76859)
			(xy 419.485572 -134.262876) (xy 419.46146 -134.250951) (xy 419.416727 -134.221084) (xy 419.376999 -134.184825)
			(xy 419.34318 -134.142999) (xy 419.316043 -134.09656) (xy 419.296203 -134.046566) (xy 419.284115 -133.994155)
			(xy 419.280052 -133.940521) (xy 419.284108 -133.886887) (xy 419.296191 -133.834475) (xy 419.316024 -133.784478)
			(xy 419.343156 -133.738035) (xy 419.37697 -133.696206) (xy 419.416694 -133.659942) (xy 419.461423 -133.63007)
			(xy 419.485572 -133.618224) (xy 419.485572 -133.433312) (xy 419.462107 -133.421153) (xy 419.418671 -133.391054)
			(xy 419.380164 -133.354863) (xy 419.347432 -133.313375) (xy 419.321195 -133.267503) (xy 419.302031 -133.218255)
			(xy 419.29036 -133.166715) (xy 419.28644 -133.114015) (xy 419.290356 -133.061315) (xy 419.302022 -133.009774)
			(xy 419.321182 -132.960524) (xy 419.347415 -132.91465) (xy 419.380143 -132.873159) (xy 419.418648 -132.836965)
			(xy 419.462081 -132.806862) (xy 419.485572 -132.794756) (xy 419.485572 -132.560568) (xy 419.460847 -132.553266)
			(xy 419.413639 -132.532552) (xy 419.369909 -132.505249) (xy 419.330571 -132.471929) (xy 419.296447 -132.433287)
			(xy 419.268249 -132.390129) (xy 419.246566 -132.343358) (xy 419.231852 -132.29395) (xy 419.224412 -132.242936)
			(xy 419.223952 -132.21716) (xy 419.224504 -132.189178) (xy 419.233264 -132.133903) (xy 419.250561 -132.080679)
			(xy 419.275971 -132.030815) (xy 419.308867 -131.98554) (xy 419.34844 -131.945967) (xy 419.393715 -131.913071)
			(xy 419.443579 -131.887661) (xy 419.496803 -131.870364) (xy 419.552078 -131.861604) (xy 419.58006 -131.861052)
			(xy 419.605537 -131.861488) (xy 419.655973 -131.868738) (xy 419.704858 -131.88311) (xy 419.751192 -131.904309)
			(xy 419.794028 -131.931903) (xy 419.832489 -131.965326) (xy 419.865787 -132.003894) (xy 419.893242 -132.046819)
			(xy 419.904164 -132.06984) (xy 423.847768 -132.06984) (xy 423.847768 -132.462778) (xy 431.231292 -132.462778)
			(xy 431.235363 -132.407156) (xy 431.247489 -132.352719) (xy 431.267412 -132.300628) (xy 431.294708 -132.251993)
			(xy 431.328794 -132.20785) (xy 431.368943 -132.169141) (xy 431.414301 -132.13669) (xy 431.463901 -132.111189)
			(xy 431.516685 -132.093182) (xy 431.571528 -132.083052) (xy 431.627262 -132.081015) (xy 431.682699 -132.087115)
			(xy 431.736656 -132.101221) (xy 431.787985 -132.123033) (xy 431.835591 -132.152087) (xy 431.878459 -132.187762)
			(xy 431.915676 -132.229299) (xy 431.946449 -132.275812) (xy 431.970121 -132.326309) (xy 431.986189 -132.379716)
			(xy 431.994309 -132.434892) (xy 431.994818 -132.462778) (xy 431.994309 -132.490664) (xy 431.986189 -132.54584)
			(xy 431.970121 -132.599247) (xy 431.946449 -132.649744) (xy 431.915676 -132.696257) (xy 431.878459 -132.737794)
			(xy 431.835591 -132.773469) (xy 431.787985 -132.802523) (xy 431.736656 -132.824335) (xy 431.682699 -132.838441)
			(xy 431.627262 -132.844541) (xy 431.571528 -132.842504) (xy 431.516685 -132.832374) (xy 431.463901 -132.814367)
			(xy 431.414301 -132.788866) (xy 431.368943 -132.756415) (xy 431.328794 -132.717706) (xy 431.294708 -132.673563)
			(xy 431.267412 -132.624928) (xy 431.247489 -132.572837) (xy 431.235363 -132.5184) (xy 431.231292 -132.462778)
			(xy 423.847768 -132.462778) (xy 423.847768 -133.071108) (xy 425.474382 -133.071108) (xy 425.478453 -133.015486)
			(xy 425.490579 -132.961049) (xy 425.510502 -132.908958) (xy 425.537798 -132.860323) (xy 425.571884 -132.81618)
			(xy 425.612033 -132.777471) (xy 425.657391 -132.74502) (xy 425.706991 -132.719519) (xy 425.759775 -132.701512)
			(xy 425.814618 -132.691382) (xy 425.870352 -132.689345) (xy 425.925789 -132.695445) (xy 425.979746 -132.709551)
			(xy 426.031075 -132.731363) (xy 426.078681 -132.760417) (xy 426.121549 -132.796092) (xy 426.158766 -132.837629)
			(xy 426.189539 -132.884142) (xy 426.213211 -132.934639) (xy 426.229279 -132.988046) (xy 426.237399 -133.043222)
			(xy 426.237908 -133.071108) (xy 426.237399 -133.098994) (xy 426.229279 -133.15417) (xy 426.213211 -133.207577)
			(xy 426.189539 -133.258074) (xy 426.158766 -133.304587) (xy 426.121549 -133.346124) (xy 426.078681 -133.381799)
			(xy 426.031075 -133.410853) (xy 425.979746 -133.432665) (xy 425.925789 -133.446771) (xy 425.870352 -133.452871)
			(xy 425.814618 -133.450834) (xy 425.759775 -133.440704) (xy 425.706991 -133.422697) (xy 425.657391 -133.397196)
			(xy 425.612033 -133.364745) (xy 425.571884 -133.326036) (xy 425.537798 -133.281893) (xy 425.510502 -133.233258)
			(xy 425.490579 -133.181167) (xy 425.478453 -133.12673) (xy 425.474382 -133.071108) (xy 423.847768 -133.071108)
			(xy 423.847768 -133.478778) (xy 429.131728 -133.478778) (xy 429.135799 -133.423156) (xy 429.147925 -133.368719)
			(xy 429.167848 -133.316628) (xy 429.195144 -133.267993) (xy 429.22923 -133.22385) (xy 429.269379 -133.185141)
			(xy 429.314737 -133.15269) (xy 429.364337 -133.127189) (xy 429.417121 -133.109182) (xy 429.471964 -133.099052)
			(xy 429.527698 -133.097015) (xy 429.583135 -133.103115) (xy 429.637092 -133.117221) (xy 429.688421 -133.139033)
			(xy 429.736027 -133.168087) (xy 429.778895 -133.203762) (xy 429.816112 -133.245299) (xy 429.846885 -133.291812)
			(xy 429.870557 -133.342309) (xy 429.886625 -133.395716) (xy 429.894745 -133.450892) (xy 429.895254 -133.478778)
			(xy 429.894745 -133.506664) (xy 429.886625 -133.56184) (xy 429.870557 -133.615247) (xy 429.863684 -133.629908)
			(xy 432.162202 -133.629908) (xy 432.166273 -133.574286) (xy 432.178399 -133.519849) (xy 432.198322 -133.467758)
			(xy 432.225618 -133.419123) (xy 432.259704 -133.37498) (xy 432.299853 -133.336271) (xy 432.345211 -133.30382)
			(xy 432.394811 -133.278319) (xy 432.447595 -133.260312) (xy 432.502438 -133.250182) (xy 432.558172 -133.248145)
			(xy 432.613609 -133.254245) (xy 432.667566 -133.268351) (xy 432.718895 -133.290163) (xy 432.766501 -133.319217)
			(xy 432.809369 -133.354892) (xy 432.846586 -133.396429) (xy 432.877359 -133.442942) (xy 432.901031 -133.493439)
			(xy 432.917099 -133.546846) (xy 432.925219 -133.602022) (xy 432.925728 -133.629908) (xy 432.925219 -133.657794)
			(xy 432.917099 -133.71297) (xy 432.901031 -133.766377) (xy 432.877359 -133.816874) (xy 432.846586 -133.863387)
			(xy 432.809369 -133.904924) (xy 432.766501 -133.940599) (xy 432.718895 -133.969653) (xy 432.667566 -133.991465)
			(xy 432.613609 -134.005571) (xy 432.558172 -134.011671) (xy 432.502438 -134.009634) (xy 432.447595 -133.999504)
			(xy 432.394811 -133.981497) (xy 432.345211 -133.955996) (xy 432.299853 -133.923545) (xy 432.259704 -133.884836)
			(xy 432.225618 -133.840693) (xy 432.198322 -133.792058) (xy 432.178399 -133.739967) (xy 432.166273 -133.68553)
			(xy 432.162202 -133.629908) (xy 429.863684 -133.629908) (xy 429.846885 -133.665744) (xy 429.816112 -133.712257)
			(xy 429.778895 -133.753794) (xy 429.736027 -133.789469) (xy 429.688421 -133.818523) (xy 429.637092 -133.840335)
			(xy 429.583135 -133.854441) (xy 429.527698 -133.860541) (xy 429.471964 -133.858504) (xy 429.417121 -133.848374)
			(xy 429.364337 -133.830367) (xy 429.314737 -133.804866) (xy 429.269379 -133.772415) (xy 429.22923 -133.733706)
			(xy 429.195144 -133.689563) (xy 429.167848 -133.640928) (xy 429.147925 -133.588837) (xy 429.135799 -133.5344)
			(xy 429.131728 -133.478778) (xy 423.847768 -133.478778) (xy 423.847768 -134.747762) (xy 429.158398 -134.747762)
			(xy 429.162469 -134.69214) (xy 429.174595 -134.637703) (xy 429.194518 -134.585612) (xy 429.221814 -134.536977)
			(xy 429.2559 -134.492834) (xy 429.296049 -134.454125) (xy 429.341407 -134.421674) (xy 429.391007 -134.396173)
			(xy 429.443791 -134.378166) (xy 429.498634 -134.368036) (xy 429.554368 -134.365999) (xy 429.609805 -134.372099)
			(xy 429.663762 -134.386205) (xy 429.715091 -134.408017) (xy 429.762697 -134.437071) (xy 429.805565 -134.472746)
			(xy 429.842782 -134.514283) (xy 429.873555 -134.560796) (xy 429.897227 -134.611293) (xy 429.913295 -134.6647)
			(xy 429.921415 -134.719876) (xy 429.921924 -134.747762) (xy 429.921415 -134.775648) (xy 429.913295 -134.830824)
			(xy 429.897227 -134.884231) (xy 429.873555 -134.934728) (xy 429.842782 -134.981241) (xy 429.805565 -135.022778)
			(xy 429.762697 -135.058453) (xy 429.715091 -135.087507) (xy 429.663762 -135.109319) (xy 429.609805 -135.123425)
			(xy 429.554368 -135.129525) (xy 429.498634 -135.127488) (xy 429.443791 -135.117358) (xy 429.391007 -135.099351)
			(xy 429.341407 -135.07385) (xy 429.296049 -135.041399) (xy 429.2559 -135.00269) (xy 429.221814 -134.958547)
			(xy 429.194518 -134.909912) (xy 429.174595 -134.857821) (xy 429.162469 -134.803384) (xy 429.158398 -134.747762)
			(xy 423.847768 -134.747762) (xy 423.847768 -137.130028) (xy 428.753016 -137.130028) (xy 428.753463 -137.103293)
			(xy 428.760925 -137.050348) (xy 428.775708 -136.998963) (xy 428.797521 -136.950146) (xy 428.825937 -136.904853)
			(xy 428.860399 -136.863971) (xy 428.880016 -136.845802) (xy 428.890822 -136.835406) (xy 428.906368 -136.809781)
			(xy 428.913789 -136.780743) (xy 428.912443 -136.750802) (xy 428.902446 -136.722547) (xy 428.893986 -136.710166)
			(xy 428.876517 -136.68545) (xy 428.848814 -136.631639) (xy 428.829949 -136.574132) (xy 428.820397 -136.514367)
			(xy 428.819818 -136.484106) (xy 428.82029 -136.455888) (xy 428.828576 -136.400063) (xy 428.844998 -136.34607)
			(xy 428.869197 -136.295085) (xy 428.900645 -136.248223) (xy 428.938655 -136.206507) (xy 428.982397 -136.170847)
			(xy 429.030917 -136.142022) (xy 429.083154 -136.120661) (xy 429.137969 -136.107232) (xy 429.16602 -136.104122)
			(xy 429.180402 -136.102296) (xy 429.207356 -136.091662) (xy 429.230235 -136.073881) (xy 429.247195 -136.050386)
			(xy 429.256869 -136.023073) (xy 429.258478 -135.994141) (xy 429.255682 -135.979916) (xy 429.250944 -135.958447)
			(xy 429.245847 -135.914777) (xy 429.245522 -135.892794) (xy 429.246008 -135.865543) (xy 429.253764 -135.811595)
			(xy 429.269119 -135.7593) (xy 429.291761 -135.709723) (xy 429.321227 -135.663873) (xy 429.356918 -135.622682)
			(xy 429.398109 -135.586991) (xy 429.443959 -135.557525) (xy 429.493536 -135.534883) (xy 429.545831 -135.519528)
			(xy 429.599779 -135.511772) (xy 429.654281 -135.511772) (xy 429.708229 -135.519528) (xy 429.760524 -135.534883)
			(xy 429.782825 -135.545068) (xy 431.227736 -135.545068) (xy 431.231807 -135.489446) (xy 431.243933 -135.435009)
			(xy 431.263856 -135.382918) (xy 431.291152 -135.334283) (xy 431.325238 -135.29014) (xy 431.365387 -135.251431)
			(xy 431.410745 -135.21898) (xy 431.460345 -135.193479) (xy 431.513129 -135.175472) (xy 431.567972 -135.165342)
			(xy 431.623706 -135.163305) (xy 431.679143 -135.169405) (xy 431.7331 -135.183511) (xy 431.784429 -135.205323)
			(xy 431.832035 -135.234377) (xy 431.874903 -135.270052) (xy 431.91212 -135.311589) (xy 431.942893 -135.358102)
			(xy 431.966565 -135.408599) (xy 431.982633 -135.462006) (xy 431.990753 -135.517182) (xy 431.991262 -135.545068)
			(xy 431.990753 -135.572954) (xy 431.982633 -135.62813) (xy 431.966565 -135.681537) (xy 431.942893 -135.732034)
			(xy 431.91212 -135.778547) (xy 431.887022 -135.806558) (xy 432.659911 -135.806558) (xy 432.659911 -135.752042)
			(xy 432.66767 -135.698081) (xy 432.68303 -135.645773) (xy 432.705678 -135.596185) (xy 432.735154 -135.550324)
			(xy 432.770857 -135.509125) (xy 432.812059 -135.473428) (xy 432.857923 -135.443957) (xy 432.907515 -135.421315)
			(xy 432.959824 -135.405961) (xy 433.013786 -135.398208) (xy 433.041044 -135.397748) (xy 433.071983 -135.398373)
			(xy 433.133051 -135.408358) (xy 433.191705 -135.428075) (xy 433.246404 -135.457005) (xy 433.271422 -135.475218)
			(xy 433.282668 -135.48321) (xy 433.308295 -135.493405) (xy 433.335716 -135.496354) (xy 433.362924 -135.491841)
			(xy 433.387925 -135.480197) (xy 433.408887 -135.462274) (xy 433.416964 -135.451088) (xy 433.432273 -135.429314)
			(xy 433.467904 -135.389775) (xy 433.508688 -135.355577) (xy 433.553832 -135.327383) (xy 433.602458 -135.305741)
			(xy 433.653621 -135.291072) (xy 433.706328 -135.283661) (xy 433.73294 -135.283194) (xy 433.76019 -135.283679)
			(xy 433.793893 -135.288528) (xy 435.509922 -135.288528) (xy 435.513993 -135.232906) (xy 435.526119 -135.178469)
			(xy 435.546042 -135.126378) (xy 435.573338 -135.077743) (xy 435.607424 -135.0336) (xy 435.647573 -134.994891)
			(xy 435.692931 -134.96244) (xy 435.742531 -134.936939) (xy 435.795315 -134.918932) (xy 435.850158 -134.908802)
			(xy 435.905892 -134.906765) (xy 435.961329 -134.912865) (xy 436.015286 -134.926971) (xy 436.066615 -134.948783)
			(xy 436.114221 -134.977837) (xy 436.157089 -135.013512) (xy 436.194306 -135.055049) (xy 436.225079 -135.101562)
			(xy 436.248751 -135.152059) (xy 436.264819 -135.205466) (xy 436.272939 -135.260642) (xy 436.273448 -135.288528)
			(xy 436.272939 -135.316414) (xy 436.264819 -135.37159) (xy 436.248751 -135.424997) (xy 436.225079 -135.475494)
			(xy 436.194306 -135.522007) (xy 436.157089 -135.563544) (xy 436.114221 -135.599219) (xy 436.066615 -135.628273)
			(xy 436.015286 -135.650085) (xy 435.961329 -135.664191) (xy 435.905892 -135.670291) (xy 435.850158 -135.668254)
			(xy 435.795315 -135.658124) (xy 435.742531 -135.640117) (xy 435.692931 -135.614616) (xy 435.647573 -135.582165)
			(xy 435.607424 -135.543456) (xy 435.573338 -135.499313) (xy 435.546042 -135.450678) (xy 435.526119 -135.398587)
			(xy 435.513993 -135.34415) (xy 435.509922 -135.288528) (xy 433.793893 -135.288528) (xy 433.814133 -135.29144)
			(xy 433.866423 -135.306798) (xy 433.915996 -135.329442) (xy 433.961842 -135.358909) (xy 434.003027 -135.394601)
			(xy 434.038715 -135.435791) (xy 434.068177 -135.481639) (xy 434.090816 -135.531214) (xy 434.106169 -135.583506)
			(xy 434.113924 -135.63745) (xy 434.113924 -135.69195) (xy 434.106169 -135.745894) (xy 434.090816 -135.798186)
			(xy 434.068177 -135.847761) (xy 434.038715 -135.893609) (xy 434.003027 -135.934799) (xy 433.961842 -135.970491)
			(xy 433.915996 -135.999958) (xy 433.866423 -136.022602) (xy 433.814133 -136.03796) (xy 433.76019 -136.045721)
			(xy 433.73294 -136.04621) (xy 433.702 -136.045601) (xy 433.640931 -136.035612) (xy 433.582277 -136.015891)
			(xy 433.527579 -135.986955) (xy 433.502562 -135.96874) (xy 433.491321 -135.960741) (xy 433.465693 -135.950554)
			(xy 433.438271 -135.94761) (xy 433.411064 -135.952124) (xy 433.386063 -135.963767) (xy 433.365099 -135.981685)
			(xy 433.35702 -135.99287) (xy 433.341708 -136.014642) (xy 433.306079 -136.054183) (xy 433.265296 -136.088383)
			(xy 433.220153 -136.116578) (xy 433.171527 -136.13822) (xy 433.120363 -136.152888) (xy 433.067656 -136.160298)
			(xy 433.041044 -136.160764) (xy 433.013786 -136.160392) (xy 432.959824 -136.152639) (xy 432.907515 -136.137285)
			(xy 432.857923 -136.114643) (xy 432.812059 -136.085172) (xy 432.770857 -136.049475) (xy 432.735154 -136.008276)
			(xy 432.705678 -135.962415) (xy 432.68303 -135.912827) (xy 432.66767 -135.860519) (xy 432.659911 -135.806558)
			(xy 431.887022 -135.806558) (xy 431.874903 -135.820084) (xy 431.832035 -135.855759) (xy 431.784429 -135.884813)
			(xy 431.7331 -135.906625) (xy 431.679143 -135.920731) (xy 431.623706 -135.926831) (xy 431.567972 -135.924794)
			(xy 431.513129 -135.914664) (xy 431.460345 -135.896657) (xy 431.410745 -135.871156) (xy 431.365387 -135.838705)
			(xy 431.325238 -135.799996) (xy 431.291152 -135.755853) (xy 431.263856 -135.707218) (xy 431.243933 -135.655127)
			(xy 431.231807 -135.60069) (xy 431.227736 -135.545068) (xy 429.782825 -135.545068) (xy 429.810101 -135.557525)
			(xy 429.855951 -135.586991) (xy 429.897142 -135.622682) (xy 429.932833 -135.663873) (xy 429.962299 -135.709723)
			(xy 429.984941 -135.7593) (xy 430.000296 -135.811595) (xy 430.008052 -135.865543) (xy 430.008538 -135.892794)
			(xy 430.008015 -135.92101) (xy 429.999731 -135.97683) (xy 429.983312 -136.030819) (xy 429.959117 -136.081801)
			(xy 429.927675 -136.128661) (xy 429.889671 -136.170376) (xy 429.845935 -136.206037) (xy 429.797423 -136.234864)
			(xy 429.745192 -136.256229) (xy 429.690384 -136.269664) (xy 429.662336 -136.272778) (xy 429.64796 -136.274645)
			(xy 429.621005 -136.285266) (xy 429.598123 -136.303038) (xy 429.58116 -136.326525) (xy 429.571485 -136.353834)
			(xy 429.569877 -136.382761) (xy 429.572674 -136.396984) (xy 429.577413 -136.418453) (xy 429.582509 -136.462123)
			(xy 429.582834 -136.484106) (xy 429.582359 -136.51084) (xy 429.574905 -136.563785) (xy 429.560129 -136.61517)
			(xy 429.538321 -136.663988) (xy 429.509909 -136.709281) (xy 429.47545 -136.750163) (xy 429.455834 -136.768332)
			(xy 429.444998 -136.778702) (xy 429.429448 -136.804333) (xy 429.422029 -136.83338) (xy 429.423384 -136.863329)
			(xy 429.433395 -136.891588) (xy 429.441864 -136.903968) (xy 429.459298 -136.928708) (xy 429.487011 -136.982509)
			(xy 429.505885 -137.04001) (xy 429.515448 -137.099769) (xy 429.516032 -137.130028) (xy 429.515546 -137.157279)
			(xy 429.50779 -137.211227) (xy 429.492435 -137.263522) (xy 429.469793 -137.313099) (xy 429.440327 -137.358949)
			(xy 429.404636 -137.40014) (xy 429.363445 -137.435831) (xy 429.317595 -137.465297) (xy 429.268018 -137.487939)
			(xy 429.215723 -137.503294) (xy 429.161775 -137.51105) (xy 429.107273 -137.51105) (xy 429.053325 -137.503294)
			(xy 429.00103 -137.487939) (xy 428.951453 -137.465297) (xy 428.905603 -137.435831) (xy 428.864412 -137.40014)
			(xy 428.828721 -137.358949) (xy 428.799255 -137.313099) (xy 428.776613 -137.263522) (xy 428.761258 -137.211227)
			(xy 428.753502 -137.157279) (xy 428.753016 -137.130028) (xy 423.847768 -137.130028) (xy 423.847768 -137.542778)
			(xy 431.333146 -137.542778) (xy 431.337217 -137.487156) (xy 431.349343 -137.432719) (xy 431.369266 -137.380628)
			(xy 431.396562 -137.331993) (xy 431.430648 -137.28785) (xy 431.470797 -137.249141) (xy 431.516155 -137.21669)
			(xy 431.565755 -137.191189) (xy 431.618539 -137.173182) (xy 431.673382 -137.163052) (xy 431.729116 -137.161015)
			(xy 431.784553 -137.167115) (xy 431.83851 -137.181221) (xy 431.889839 -137.203033) (xy 431.937445 -137.232087)
			(xy 431.980313 -137.267762) (xy 432.01753 -137.309299) (xy 432.048303 -137.355812) (xy 432.071975 -137.406309)
			(xy 432.088043 -137.459716) (xy 432.096163 -137.514892) (xy 432.096672 -137.542778) (xy 432.096163 -137.570664)
			(xy 432.088043 -137.62584) (xy 432.071975 -137.679247) (xy 432.048303 -137.729744) (xy 432.01753 -137.776257)
			(xy 431.980313 -137.817794) (xy 431.937445 -137.853469) (xy 431.889839 -137.882523) (xy 431.83851 -137.904335)
			(xy 431.784553 -137.918441) (xy 431.729116 -137.924541) (xy 431.673382 -137.922504) (xy 431.618539 -137.912374)
			(xy 431.565755 -137.894367) (xy 431.516155 -137.868866) (xy 431.470797 -137.836415) (xy 431.430648 -137.797706)
			(xy 431.396562 -137.753563) (xy 431.369266 -137.704928) (xy 431.349343 -137.652837) (xy 431.337217 -137.5984)
			(xy 431.333146 -137.542778) (xy 423.847768 -137.542778) (xy 423.847768 -138.143996) (xy 428.762158 -138.143996)
			(xy 428.766229 -138.088374) (xy 428.778355 -138.033937) (xy 428.798278 -137.981846) (xy 428.825574 -137.933211)
			(xy 428.85966 -137.889068) (xy 428.899809 -137.850359) (xy 428.945167 -137.817908) (xy 428.994767 -137.792407)
			(xy 429.047551 -137.7744) (xy 429.102394 -137.76427) (xy 429.158128 -137.762233) (xy 429.213565 -137.768333)
			(xy 429.267522 -137.782439) (xy 429.318851 -137.804251) (xy 429.366457 -137.833305) (xy 429.409325 -137.86898)
			(xy 429.446542 -137.910517) (xy 429.477315 -137.95703) (xy 429.500987 -138.007527) (xy 429.517055 -138.060934)
			(xy 429.525175 -138.11611) (xy 429.525684 -138.143996) (xy 429.525175 -138.171882) (xy 429.517055 -138.227058)
			(xy 429.500987 -138.280465) (xy 429.477315 -138.330962) (xy 429.446542 -138.377475) (xy 429.409325 -138.419012)
			(xy 429.366457 -138.454687) (xy 429.318851 -138.483741) (xy 429.267522 -138.505553) (xy 429.213565 -138.519659)
			(xy 429.158128 -138.525759) (xy 429.102394 -138.523722) (xy 429.047551 -138.513592) (xy 428.994767 -138.495585)
			(xy 428.945167 -138.470084) (xy 428.899809 -138.437633) (xy 428.85966 -138.398924) (xy 428.825574 -138.354781)
			(xy 428.798278 -138.306146) (xy 428.778355 -138.254055) (xy 428.766229 -138.199618) (xy 428.762158 -138.143996)
			(xy 423.847768 -138.143996) (xy 423.847768 -138.235436) (xy 423.907712 -138.29538) (xy 425.746672 -138.29538)
			(xy 426.146468 -138.695176) (xy 426.146468 -140.264388) (xy 426.322996 -140.264388) (xy 426.327067 -140.208766)
			(xy 426.339193 -140.154329) (xy 426.359116 -140.102238) (xy 426.386412 -140.053603) (xy 426.420498 -140.00946)
			(xy 426.460647 -139.970751) (xy 426.506005 -139.9383) (xy 426.555605 -139.912799) (xy 426.608389 -139.894792)
			(xy 426.663232 -139.884662) (xy 426.718966 -139.882625) (xy 426.774403 -139.888725) (xy 426.82836 -139.902831)
			(xy 426.879689 -139.924643) (xy 426.927295 -139.953697) (xy 426.970163 -139.989372) (xy 427.00738 -140.030909)
			(xy 427.038153 -140.077422) (xy 427.061825 -140.127919) (xy 427.077893 -140.181326) (xy 427.086013 -140.236502)
			(xy 427.086522 -140.264388) (xy 427.086013 -140.292274) (xy 427.077893 -140.34745) (xy 427.061825 -140.400857)
			(xy 427.038153 -140.451354) (xy 427.00738 -140.497867) (xy 426.970163 -140.539404) (xy 426.927295 -140.575079)
			(xy 426.879689 -140.604133) (xy 426.82836 -140.625945) (xy 426.774403 -140.640051) (xy 426.718966 -140.646151)
			(xy 426.663232 -140.644114) (xy 426.608389 -140.633984) (xy 426.555605 -140.615977) (xy 426.506005 -140.590476)
			(xy 426.460647 -140.558025) (xy 426.420498 -140.519316) (xy 426.386412 -140.475173) (xy 426.359116 -140.426538)
			(xy 426.339193 -140.374447) (xy 426.327067 -140.32001) (xy 426.322996 -140.264388) (xy 426.146468 -140.264388)
			(xy 426.146468 -140.967714) (xy 426.146991 -140.981938) (xy 426.154869 -141.009274) (xy 426.169984 -141.033376)
			(xy 426.19116 -141.052374) (xy 426.216756 -141.064792) (xy 426.244784 -141.069667) (xy 426.27307 -141.066621)
			(xy 426.286422 -141.061694) (xy 426.309328 -141.052773) (xy 426.35686 -141.040239) (xy 426.405608 -141.0339)
			(xy 426.430186 -141.0335) (xy 426.43044 -141.0335) (xy 426.457175 -141.033941) (xy 426.510122 -141.041401)
			(xy 426.561508 -141.056183) (xy 426.610326 -141.077997) (xy 426.655619 -141.106415) (xy 426.696498 -141.140881)
			(xy 426.714666 -141.1605) (xy 428.366936 -141.1605) (xy 428.391931 -141.161153) (xy 428.43061 -141.168882)
			(xy 431.19116 -141.168882) (xy 431.195231 -141.11326) (xy 431.207357 -141.058823) (xy 431.22728 -141.006732)
			(xy 431.254576 -140.958097) (xy 431.288662 -140.913954) (xy 431.328811 -140.875245) (xy 431.374169 -140.842794)
			(xy 431.423769 -140.817293) (xy 431.476553 -140.799286) (xy 431.531396 -140.789156) (xy 431.58713 -140.787119)
			(xy 431.642567 -140.793219) (xy 431.696524 -140.807325) (xy 431.747853 -140.829137) (xy 431.795459 -140.858191)
			(xy 431.838327 -140.893866) (xy 431.875544 -140.935403) (xy 431.906317 -140.981916) (xy 431.929989 -141.032413)
			(xy 431.946057 -141.08582) (xy 431.954177 -141.140996) (xy 431.954686 -141.168882) (xy 431.954177 -141.196768)
			(xy 431.946057 -141.251944) (xy 431.929989 -141.305351) (xy 431.906317 -141.355848) (xy 431.875544 -141.402361)
			(xy 431.838327 -141.443898) (xy 431.795459 -141.479573) (xy 431.747853 -141.508627) (xy 431.696524 -141.530439)
			(xy 431.642567 -141.544545) (xy 431.58713 -141.550645) (xy 431.531396 -141.548608) (xy 431.476553 -141.538478)
			(xy 431.423769 -141.520471) (xy 431.374169 -141.49497) (xy 431.328811 -141.462519) (xy 431.288662 -141.42381)
			(xy 431.254576 -141.379667) (xy 431.22728 -141.331032) (xy 431.207357 -141.278941) (xy 431.195231 -141.224504)
			(xy 431.19116 -141.168882) (xy 428.43061 -141.168882) (xy 428.440954 -141.170949) (xy 428.487126 -141.190117)
			(xy 428.528672 -141.217922) (xy 428.546768 -141.235176) (xy 432.016662 -144.70507) (xy 435.98668 -144.70507)
			(xy 435.990751 -144.649448) (xy 436.002877 -144.595011) (xy 436.0228 -144.54292) (xy 436.050096 -144.494285)
			(xy 436.084182 -144.450142) (xy 436.124331 -144.411433) (xy 436.169689 -144.378982) (xy 436.219289 -144.353481)
			(xy 436.272073 -144.335474) (xy 436.326916 -144.325344) (xy 436.38265 -144.323307) (xy 436.438087 -144.329407)
			(xy 436.492044 -144.343513) (xy 436.543373 -144.365325) (xy 436.590979 -144.394379) (xy 436.633847 -144.430054)
			(xy 436.671064 -144.471591) (xy 436.701837 -144.518104) (xy 436.725509 -144.568601) (xy 436.741577 -144.622008)
			(xy 436.749697 -144.677184) (xy 436.750206 -144.70507) (xy 436.749697 -144.732956) (xy 436.741577 -144.788132)
			(xy 436.725509 -144.841539) (xy 436.701837 -144.892036) (xy 436.671064 -144.938549) (xy 436.633847 -144.980086)
			(xy 436.590979 -145.015761) (xy 436.543373 -145.044815) (xy 436.492044 -145.066627) (xy 436.438087 -145.080733)
			(xy 436.38265 -145.086833) (xy 436.326916 -145.084796) (xy 436.272073 -145.074666) (xy 436.219289 -145.056659)
			(xy 436.169689 -145.031158) (xy 436.124331 -144.998707) (xy 436.084182 -144.959998) (xy 436.050096 -144.915855)
			(xy 436.0228 -144.86722) (xy 436.002877 -144.815129) (xy 435.990751 -144.760692) (xy 435.98668 -144.70507)
			(xy 432.016662 -144.70507) (xy 434.741066 -147.429474) (xy 434.758293 -147.44758) (xy 434.786032 -147.489141)
			(xy 434.805138 -147.535312) (xy 434.814878 -147.584322) (xy 434.815488 -147.609306) (xy 434.815488 -153.774902)
			(xy 436.385725 -153.774902) (xy 436.389718 -153.565161) (xy 436.401694 -153.355724) (xy 436.421635 -153.146895)
			(xy 436.449512 -152.938976) (xy 436.485284 -152.732269) (xy 436.528899 -152.527074) (xy 436.580295 -152.323689)
			(xy 436.639397 -152.122407) (xy 436.706119 -151.923521) (xy 436.780364 -151.72732) (xy 436.862024 -151.534088)
			(xy 436.950982 -151.344104) (xy 437.047109 -151.157645) (xy 437.150264 -150.974981) (xy 437.260299 -150.796376)
			(xy 437.377053 -150.62209) (xy 437.500358 -150.452375) (xy 437.630035 -150.287477) (xy 437.765896 -150.127636)
			(xy 437.907743 -149.973083) (xy 438.055372 -149.824043) (xy 438.208567 -149.68073) (xy 438.367108 -149.543354)
			(xy 438.530763 -149.412113) (xy 438.699297 -149.287198) (xy 438.872463 -149.16879) (xy 439.050013 -149.05706)
			(xy 439.231687 -148.95217) (xy 439.417222 -148.854273) (xy 439.60635 -148.763511) (xy 439.798797 -148.680014)
			(xy 439.994282 -148.603904) (xy 440.192524 -148.535292) (xy 440.393234 -148.474277) (xy 440.596121 -148.420948)
			(xy 440.800891 -148.375381) (xy 441.007248 -148.337642) (xy 441.214892 -148.307788) (xy 441.423522 -148.28586)
			(xy 441.632835 -148.271891) (xy 441.842529 -148.2659) (xy 442.052298 -148.267897) (xy 442.26184 -148.277879)
			(xy 442.47085 -148.295831) (xy 442.679024 -148.321727) (xy 442.886062 -148.355529) (xy 443.091663 -148.397189)
			(xy 443.295529 -148.446647) (xy 443.497364 -148.50383) (xy 443.696876 -148.568655) (xy 443.893775 -148.641029)
			(xy 444.087776 -148.720846) (xy 444.278598 -148.807992) (xy 444.465964 -148.902339) (xy 444.649602 -149.00375)
			(xy 444.829246 -149.11208) (xy 445.004636 -149.22717) (xy 445.175517 -149.348854) (xy 445.341641 -149.476955)
			(xy 445.502768 -149.611288) (xy 445.658665 -149.751657) (xy 445.809104 -149.89786) (xy 445.953868 -150.049684)
			(xy 446.092747 -150.20691) (xy 446.22554 -150.369309) (xy 446.352054 -150.536645) (xy 446.472106 -150.708677)
			(xy 446.585521 -150.885154) (xy 446.692135 -151.065822) (xy 446.791794 -151.250417) (xy 446.884353 -151.438672)
			(xy 446.969678 -151.630315) (xy 447.047645 -151.825067) (xy 447.118141 -152.022647) (xy 447.181064 -152.222766)
			(xy 447.236323 -152.425137) (xy 447.283837 -152.629464) (xy 447.323538 -152.835452) (xy 447.355368 -153.042803)
			(xy 447.379281 -153.251214) (xy 447.395242 -153.460385) (xy 447.403229 -153.670012) (xy 447.403728 -153.774902)
			(xy 447.403229 -153.879792) (xy 447.395242 -154.089419) (xy 447.379281 -154.29859) (xy 447.355368 -154.507001)
			(xy 447.323538 -154.714352) (xy 447.283837 -154.92034) (xy 447.236323 -155.124667) (xy 447.181064 -155.327038)
			(xy 447.118141 -155.527157) (xy 447.047645 -155.724737) (xy 446.969678 -155.919489) (xy 446.884353 -156.111132)
			(xy 446.791794 -156.299387) (xy 446.692135 -156.483982) (xy 446.585521 -156.66465) (xy 446.472106 -156.841127)
			(xy 446.352054 -157.013159) (xy 446.22554 -157.180495) (xy 446.092747 -157.342894) (xy 445.953868 -157.50012)
			(xy 445.809104 -157.651944) (xy 445.658665 -157.798147) (xy 445.502768 -157.938516) (xy 445.341641 -158.072849)
			(xy 445.175517 -158.20095) (xy 445.004636 -158.322634) (xy 444.829246 -158.437724) (xy 444.649602 -158.546054)
			(xy 444.465964 -158.647465) (xy 444.278598 -158.741812) (xy 444.087776 -158.828958) (xy 443.893775 -158.908775)
			(xy 443.696876 -158.981149) (xy 443.497364 -159.045974) (xy 443.295529 -159.103157) (xy 443.091663 -159.152615)
			(xy 442.886062 -159.194275) (xy 442.679024 -159.228077) (xy 442.47085 -159.253973) (xy 442.26184 -159.271925)
			(xy 442.052298 -159.281907) (xy 441.842529 -159.283904) (xy 441.632835 -159.277913) (xy 441.423522 -159.263944)
			(xy 441.214892 -159.242016) (xy 441.007248 -159.212162) (xy 440.800891 -159.174423) (xy 440.596121 -159.128856)
			(xy 440.393234 -159.075527) (xy 440.192524 -159.014512) (xy 439.994282 -158.9459) (xy 439.798797 -158.86979)
			(xy 439.60635 -158.786293) (xy 439.417222 -158.695531) (xy 439.231687 -158.597634) (xy 439.050013 -158.492744)
			(xy 438.872463 -158.381014) (xy 438.699297 -158.262606) (xy 438.530763 -158.137691) (xy 438.367108 -158.00645)
			(xy 438.208567 -157.869074) (xy 438.055372 -157.725761) (xy 437.907743 -157.576721) (xy 437.765896 -157.422168)
			(xy 437.630035 -157.262327) (xy 437.500358 -157.097429) (xy 437.377053 -156.927714) (xy 437.260299 -156.753428)
			(xy 437.150264 -156.574823) (xy 437.047109 -156.392159) (xy 436.950982 -156.2057) (xy 436.862024 -156.015716)
			(xy 436.780364 -155.822484) (xy 436.706119 -155.626283) (xy 436.639397 -155.427397) (xy 436.580295 -155.226115)
			(xy 436.528899 -155.02273) (xy 436.485284 -154.817535) (xy 436.449512 -154.610828) (xy 436.421635 -154.402909)
			(xy 436.401694 -154.19408) (xy 436.389718 -153.984643) (xy 436.385725 -153.774902) (xy 434.815488 -153.774902)
			(xy 434.815488 -156.138372) (xy 439.386472 -160.709356) (xy 439.403743 -160.727438) (xy 439.431552 -160.768987)
			(xy 439.450721 -160.815163) (xy 439.460515 -160.86419) (xy 439.461148 -160.889188) (xy 439.461148 -167.932608)
			(xy 439.460525 -167.957605) (xy 439.450718 -168.006629) (xy 439.431541 -168.052799) (xy 439.403729 -168.094345)
			(xy 439.386472 -168.11244) (xy 436.678832 -170.82008) (xy 436.660756 -170.837358) (xy 436.619205 -170.865165)
			(xy 436.573027 -170.884332) (xy 436.523998 -170.894124) (xy 436.499 -170.894756) (xy 436.002938 -170.894756)
			(xy 432.815492 -174.082202) (xy 432.815492 -174.578264) (xy 432.81483 -174.603259) (xy 432.805033 -174.65228)
			(xy 432.785867 -174.69845) (xy 432.758067 -174.739998) (xy 432.740816 -174.758096) (xy 431.901854 -175.597058)
			(xy 434.095902 -175.597058) (xy 434.099991 -175.541176) (xy 434.112174 -175.486486) (xy 434.13219 -175.434152)
			(xy 434.159613 -175.38529) (xy 434.193858 -175.340942) (xy 434.234194 -175.302052) (xy 434.279764 -175.26945)
			(xy 434.329595 -175.243831) (xy 434.382625 -175.225739) (xy 434.437723 -175.215562) (xy 434.493717 -175.213516)
			(xy 434.549412 -175.219644) (xy 434.603621 -175.233816) (xy 434.655189 -175.25573) (xy 434.703017 -175.284919)
			(xy 434.746085 -175.32076) (xy 434.783475 -175.36249) (xy 434.814391 -175.40922) (xy 434.838174 -175.459953)
			(xy 434.854316 -175.513609) (xy 434.862475 -175.569043) (xy 434.862986 -175.597058) (xy 434.862601 -175.61814)
			(xy 435.603902 -175.61814) (xy 435.607973 -175.562518) (xy 435.620099 -175.508081) (xy 435.640022 -175.45599)
			(xy 435.667318 -175.407355) (xy 435.701404 -175.363212) (xy 435.741553 -175.324503) (xy 435.786911 -175.292052)
			(xy 435.836511 -175.266551) (xy 435.889295 -175.248544) (xy 435.944138 -175.238414) (xy 435.999872 -175.236377)
			(xy 436.055309 -175.242477) (xy 436.109266 -175.256583) (xy 436.160595 -175.278395) (xy 436.208201 -175.307449)
			(xy 436.251069 -175.343124) (xy 436.288286 -175.384661) (xy 436.319059 -175.431174) (xy 436.342731 -175.481671)
			(xy 436.358799 -175.535078) (xy 436.366919 -175.590254) (xy 436.367428 -175.61814) (xy 436.366919 -175.646026)
			(xy 436.358799 -175.701202) (xy 436.342731 -175.754609) (xy 436.319059 -175.805106) (xy 436.288286 -175.851619)
			(xy 436.251069 -175.893156) (xy 436.208201 -175.928831) (xy 436.160595 -175.957885) (xy 436.109266 -175.979697)
			(xy 436.055309 -175.993803) (xy 435.999872 -175.999903) (xy 435.944138 -175.997866) (xy 435.889295 -175.987736)
			(xy 435.836511 -175.969729) (xy 435.786911 -175.944228) (xy 435.741553 -175.911777) (xy 435.701404 -175.873068)
			(xy 435.667318 -175.828925) (xy 435.640022 -175.78029) (xy 435.620099 -175.728199) (xy 435.607973 -175.673762)
			(xy 435.603902 -175.61814) (xy 434.862601 -175.61814) (xy 434.862475 -175.625073) (xy 434.854316 -175.680507)
			(xy 434.838174 -175.734163) (xy 434.814391 -175.784896) (xy 434.783475 -175.831626) (xy 434.746085 -175.873356)
			(xy 434.703017 -175.909197) (xy 434.655189 -175.938386) (xy 434.603621 -175.9603) (xy 434.549412 -175.974472)
			(xy 434.493717 -175.9806) (xy 434.437723 -175.978554) (xy 434.382625 -175.968377) (xy 434.329595 -175.950285)
			(xy 434.279764 -175.924666) (xy 434.234194 -175.892064) (xy 434.193858 -175.853174) (xy 434.159613 -175.808826)
			(xy 434.13219 -175.759964) (xy 434.112174 -175.70763) (xy 434.099991 -175.65294) (xy 434.095902 -175.597058)
			(xy 431.901854 -175.597058) (xy 430.594008 -176.904904) (xy 434.675278 -176.904904) (xy 434.679349 -176.849282)
			(xy 434.691475 -176.794845) (xy 434.711398 -176.742754) (xy 434.738694 -176.694119) (xy 434.77278 -176.649976)
			(xy 434.812929 -176.611267) (xy 434.858287 -176.578816) (xy 434.907887 -176.553315) (xy 434.960671 -176.535308)
			(xy 435.015514 -176.525178) (xy 435.071248 -176.523141) (xy 435.126685 -176.529241) (xy 435.180642 -176.543347)
			(xy 435.231971 -176.565159) (xy 435.279577 -176.594213) (xy 435.322445 -176.629888) (xy 435.359662 -176.671425)
			(xy 435.390435 -176.717938) (xy 435.414107 -176.768435) (xy 435.430175 -176.821842) (xy 435.438295 -176.877018)
			(xy 435.438804 -176.904904) (xy 435.438295 -176.93279) (xy 435.430175 -176.987966) (xy 435.414107 -177.041373)
			(xy 435.390435 -177.09187) (xy 435.359662 -177.138383) (xy 435.322445 -177.17992) (xy 435.279577 -177.215595)
			(xy 435.231971 -177.244649) (xy 435.180642 -177.266461) (xy 435.126685 -177.280567) (xy 435.071248 -177.286667)
			(xy 435.015514 -177.28463) (xy 434.960671 -177.2745) (xy 434.907887 -177.256493) (xy 434.858287 -177.230992)
			(xy 434.812929 -177.198541) (xy 434.77278 -177.159832) (xy 434.738694 -177.115689) (xy 434.711398 -177.067054)
			(xy 434.691475 -177.014963) (xy 434.679349 -176.960526) (xy 434.675278 -176.904904) (xy 430.594008 -176.904904)
			(xy 429.454564 -178.044348) (xy 434.953662 -178.044348) (xy 434.957733 -177.988726) (xy 434.969859 -177.934289)
			(xy 434.989782 -177.882198) (xy 435.017078 -177.833563) (xy 435.051164 -177.78942) (xy 435.091313 -177.750711)
			(xy 435.136671 -177.71826) (xy 435.186271 -177.692759) (xy 435.239055 -177.674752) (xy 435.293898 -177.664622)
			(xy 435.349632 -177.662585) (xy 435.405069 -177.668685) (xy 435.459026 -177.682791) (xy 435.510355 -177.704603)
			(xy 435.557961 -177.733657) (xy 435.600829 -177.769332) (xy 435.638046 -177.810869) (xy 435.668819 -177.857382)
			(xy 435.692491 -177.907879) (xy 435.708559 -177.961286) (xy 435.716679 -178.016462) (xy 435.717188 -178.044348)
			(xy 435.716679 -178.072234) (xy 435.708559 -178.12741) (xy 435.692491 -178.180817) (xy 435.668819 -178.231314)
			(xy 435.638046 -178.277827) (xy 435.600829 -178.319364) (xy 435.557961 -178.355039) (xy 435.510355 -178.384093)
			(xy 435.459026 -178.405905) (xy 435.405069 -178.420011) (xy 435.349632 -178.426111) (xy 435.293898 -178.424074)
			(xy 435.239055 -178.413944) (xy 435.186271 -178.395937) (xy 435.136671 -178.370436) (xy 435.091313 -178.337985)
			(xy 435.051164 -178.299276) (xy 435.017078 -178.255133) (xy 434.989782 -178.206498) (xy 434.969859 -178.154407)
			(xy 434.957733 -178.09997) (xy 434.953662 -178.044348) (xy 429.454564 -178.044348) (xy 428.946564 -178.552348)
			(xy 430.915572 -178.552348) (xy 430.916058 -178.525097) (xy 430.923814 -178.471149) (xy 430.939169 -178.418854)
			(xy 430.961811 -178.369277) (xy 430.991277 -178.323427) (xy 431.026968 -178.282236) (xy 431.068159 -178.246545)
			(xy 431.114009 -178.217079) (xy 431.163586 -178.194437) (xy 431.215881 -178.179082) (xy 431.269829 -178.171326)
			(xy 431.324331 -178.171326) (xy 431.378279 -178.179082) (xy 431.430574 -178.194437) (xy 431.480151 -178.217079)
			(xy 431.526001 -178.246545) (xy 431.567192 -178.282236) (xy 431.602883 -178.323427) (xy 431.632349 -178.369277)
			(xy 431.654991 -178.418854) (xy 431.670346 -178.471149) (xy 431.678102 -178.525097) (xy 431.678588 -178.552348)
			(xy 431.678009 -178.582075) (xy 431.66878 -178.640807) (xy 431.652522 -178.691286) (xy 433.98897 -178.691286)
			(xy 433.993041 -178.635664) (xy 434.005167 -178.581227) (xy 434.02509 -178.529136) (xy 434.052386 -178.480501)
			(xy 434.086472 -178.436358) (xy 434.126621 -178.397649) (xy 434.171979 -178.365198) (xy 434.221579 -178.339697)
			(xy 434.274363 -178.32169) (xy 434.329206 -178.31156) (xy 434.38494 -178.309523) (xy 434.440377 -178.315623)
			(xy 434.494334 -178.329729) (xy 434.545663 -178.351541) (xy 434.593269 -178.380595) (xy 434.636137 -178.41627)
			(xy 434.673354 -178.457807) (xy 434.704127 -178.50432) (xy 434.727799 -178.554817) (xy 434.743867 -178.608224)
			(xy 434.751987 -178.6634) (xy 434.752496 -178.691286) (xy 434.751987 -178.719172) (xy 434.743867 -178.774348)
			(xy 434.727799 -178.827755) (xy 434.704127 -178.878252) (xy 434.673354 -178.924765) (xy 434.636137 -178.966302)
			(xy 434.593269 -179.001977) (xy 434.545663 -179.031031) (xy 434.494334 -179.052843) (xy 434.440377 -179.066949)
			(xy 434.38494 -179.073049) (xy 434.329206 -179.071012) (xy 434.274363 -179.060882) (xy 434.221579 -179.042875)
			(xy 434.171979 -179.017374) (xy 434.126621 -178.984923) (xy 434.086472 -178.946214) (xy 434.052386 -178.902071)
			(xy 434.02509 -178.853436) (xy 434.005167 -178.801345) (xy 433.993041 -178.746908) (xy 433.98897 -178.691286)
			(xy 431.652522 -178.691286) (xy 431.650554 -178.697398) (xy 431.623772 -178.750477) (xy 431.589081 -178.79876)
			(xy 431.568606 -178.820318) (xy 431.559494 -178.83014) (xy 431.546293 -178.853443) (xy 431.539604 -178.879377)
			(xy 431.539887 -178.906158) (xy 431.547121 -178.931945) (xy 431.56081 -178.954965) (xy 431.57013 -178.96459)
			(xy 431.58827 -178.982779) (xy 431.620002 -179.023176) (xy 431.633376 -179.045108) (xy 431.641506 -179.057796)
			(xy 431.663615 -179.07824) (xy 431.690727 -179.091344) (xy 431.720482 -179.095966) (xy 431.750292 -179.091704)
			(xy 431.77756 -179.07893) (xy 431.799915 -179.058754) (xy 431.808128 -179.046124) (xy 431.822982 -179.022263)
			(xy 431.858628 -178.978807) (xy 431.900265 -178.941053) (xy 431.946992 -178.909818) (xy 431.997798 -178.88578)
			(xy 432.051581 -178.869458) (xy 432.107177 -178.861206) (xy 432.13528 -178.860704) (xy 432.162535 -178.861142)
			(xy 432.21649 -178.868896) (xy 432.268791 -178.884251) (xy 432.318376 -178.906893) (xy 432.364233 -178.936362)
			(xy 432.405429 -178.972057) (xy 432.441126 -179.013251) (xy 432.470597 -179.059107) (xy 432.493242 -179.10869)
			(xy 432.508599 -179.160991) (xy 432.516357 -179.214945) (xy 432.516357 -179.269455) (xy 432.508599 -179.323409)
			(xy 432.493242 -179.37571) (xy 432.470597 -179.425293) (xy 432.441126 -179.471149) (xy 432.405429 -179.512343)
			(xy 432.364233 -179.548038) (xy 432.318376 -179.577507) (xy 432.268791 -179.600149) (xy 432.21649 -179.615504)
			(xy 432.162535 -179.623258) (xy 432.13528 -179.62372) (xy 432.106914 -179.623166) (xy 432.050806 -179.614767)
			(xy 431.996558 -179.598159) (xy 431.945366 -179.573705) (xy 431.898356 -179.541945) (xy 431.856564 -179.503578)
			(xy 431.820909 -179.459449) (xy 431.806096 -179.435252) (xy 431.798001 -179.422542) (xy 431.775882 -179.402103)
			(xy 431.748764 -179.389006) (xy 431.719003 -179.384389) (xy 431.689191 -179.388654) (xy 431.661919 -179.40143)
			(xy 431.63956 -179.421605) (xy 431.631344 -179.434236) (xy 431.616495 -179.458101) (xy 431.58085 -179.501559)
			(xy 431.539213 -179.539314) (xy 431.492484 -179.570549) (xy 431.441678 -179.594587) (xy 431.387893 -179.610907)
			(xy 431.332295 -179.619156) (xy 431.304192 -179.619656) (xy 431.276943 -179.61913) (xy 431.222999 -179.611373)
			(xy 431.170708 -179.59602) (xy 431.121134 -179.573381) (xy 431.075286 -179.543919) (xy 431.034097 -179.508231)
			(xy 430.998405 -179.467046) (xy 430.968938 -179.421201) (xy 430.946294 -179.37163) (xy 430.930935 -179.31934)
			(xy 430.923173 -179.265397) (xy 430.922684 -179.238148) (xy 430.923269 -179.208422) (xy 430.932497 -179.14969)
			(xy 430.950722 -179.093099) (xy 430.977503 -179.04002) (xy 431.012192 -178.991737) (xy 431.032666 -178.970178)
			(xy 431.041785 -178.960361) (xy 431.054989 -178.937057) (xy 431.061679 -178.911121) (xy 431.061396 -178.884338)
			(xy 431.054158 -178.858549) (xy 431.040465 -178.835529) (xy 431.031142 -178.825906) (xy 431.01323 -178.807853)
			(xy 430.981796 -178.767877) (xy 430.955952 -178.724079) (xy 430.936156 -178.677236) (xy 430.922758 -178.628178)
			(xy 430.915995 -178.577775) (xy 430.915572 -178.552348) (xy 428.946564 -178.552348) (xy 427.27753 -180.221382)
			(xy 430.50409 -180.221382) (xy 430.508161 -180.16576) (xy 430.520287 -180.111323) (xy 430.54021 -180.059232)
			(xy 430.567506 -180.010597) (xy 430.601592 -179.966454) (xy 430.641741 -179.927745) (xy 430.687099 -179.895294)
			(xy 430.736699 -179.869793) (xy 430.789483 -179.851786) (xy 430.844326 -179.841656) (xy 430.90006 -179.839619)
			(xy 430.955497 -179.845719) (xy 431.009454 -179.859825) (xy 431.060783 -179.881637) (xy 431.108389 -179.910691)
			(xy 431.151257 -179.946366) (xy 431.188474 -179.987903) (xy 431.219247 -180.034416) (xy 431.242919 -180.084913)
			(xy 431.258987 -180.13832) (xy 431.267107 -180.193496) (xy 431.267616 -180.221382) (xy 431.267107 -180.249268)
			(xy 431.258987 -180.304444) (xy 431.242919 -180.357851) (xy 431.219247 -180.408348) (xy 431.188474 -180.454861)
			(xy 431.151257 -180.496398) (xy 431.108389 -180.532073) (xy 431.060783 -180.561127) (xy 431.009454 -180.582939)
			(xy 430.955497 -180.597045) (xy 430.90006 -180.603145) (xy 430.844326 -180.601108) (xy 430.789483 -180.590978)
			(xy 430.736699 -180.572971) (xy 430.687099 -180.54747) (xy 430.641741 -180.515019) (xy 430.601592 -180.47631)
			(xy 430.567506 -180.432167) (xy 430.54021 -180.383532) (xy 430.520287 -180.331441) (xy 430.508161 -180.277004)
			(xy 430.50409 -180.221382) (xy 427.27753 -180.221382) (xy 426.229272 -181.26964) (xy 426.211173 -181.286892)
			(xy 426.16963 -181.314706) (xy 426.12346 -181.333881) (xy 426.074436 -181.34368) (xy 426.04944 -181.344316)
			(xy 421.91051 -181.344316) (xy 421.116252 -182.13832) (xy 421.098174 -182.155595) (xy 421.056622 -182.183401)
			(xy 421.010446 -182.202569) (xy 420.961418 -182.212362) (xy 420.93642 -182.212996) (xy 420.279068 -182.212996)
			(xy 420.254071 -182.212374) (xy 420.205048 -182.202564) (xy 420.158878 -182.183386) (xy 420.117332 -182.155576)
			(xy 420.099236 -182.13832) (xy 419.777418 -181.816502) (xy 419.756082 -181.816502) (xy 419.728805 -181.816104)
			(xy 419.674797 -181.808402) (xy 419.622437 -181.793086) (xy 419.572793 -181.770469) (xy 419.526876 -181.741012)
			(xy 419.485622 -181.705315) (xy 419.449874 -181.664106) (xy 419.420359 -181.618226) (xy 419.39768 -181.568609)
			(xy 419.382299 -181.516269) (xy 419.37453 -181.462271) (xy 419.374066 -181.434994) (xy 419.374572 -181.407744)
			(xy 419.382329 -181.353798) (xy 419.397683 -181.301505) (xy 419.420323 -181.25193) (xy 419.449788 -181.206081)
			(xy 419.485477 -181.164891) (xy 419.526665 -181.1292) (xy 419.572512 -181.099733) (xy 419.622087 -181.07709)
			(xy 419.674379 -181.061733) (xy 419.728324 -181.053974) (xy 419.755574 -181.053486) (xy 419.785261 -181.054065)
			(xy 419.843919 -181.06326) (xy 419.900444 -181.081431) (xy 419.953471 -181.108139) (xy 420.001721 -181.142741)
			(xy 420.044027 -181.184399) (xy 420.062152 -181.207918) (xy 420.070578 -181.218525) (xy 420.091891 -181.235232)
			(xy 420.116845 -181.245751) (xy 420.143686 -181.249341) (xy 420.170527 -181.245751) (xy 420.195481 -181.235232)
			(xy 420.216794 -181.218525) (xy 420.22522 -181.207918) (xy 420.243376 -181.18437) (xy 420.285751 -181.142659)
			(xy 420.334083 -181.108026) (xy 420.387203 -181.081312) (xy 420.443824 -181.063161) (xy 420.502576 -181.054015)
			(xy 420.532306 -181.053486) (xy 420.553642 -181.053486) (xy 421.078152 -180.528976) (xy 421.096228 -180.511698)
			(xy 421.13778 -180.483893) (xy 421.183957 -180.464726) (xy 421.232986 -180.454933) (xy 421.257984 -180.4543)
			(xy 425.786042 -180.4543) (xy 431.925476 -174.314866) (xy 431.925476 -173.818804) (xy 431.926099 -173.793807)
			(xy 431.935905 -173.744783) (xy 431.955082 -173.698612) (xy 431.982894 -173.657067) (xy 432.000152 -173.638972)
			(xy 435.559708 -170.079416) (xy 435.577809 -170.062166) (xy 435.619352 -170.034354) (xy 435.665521 -170.015179)
			(xy 435.714544 -170.005378) (xy 435.73954 -170.00474) (xy 436.235602 -170.00474) (xy 438.571132 -167.66921)
			(xy 438.571132 -161.152586) (xy 433.987448 -156.568648) (xy 433.970182 -156.550561) (xy 433.942372 -156.509014)
			(xy 433.923201 -156.46284) (xy 433.913406 -156.413813) (xy 433.912772 -156.388816) (xy 433.912772 -147.878038)
			(xy 428.29099 -142.256256) (xy 426.036486 -142.256256) (xy 426.011489 -142.255635) (xy 425.962466 -142.245827)
			(xy 425.916295 -142.226649) (xy 425.874749 -142.198837) (xy 425.856654 -142.18158) (xy 425.742354 -142.06728)
			(xy 425.706032 -142.103856) (xy 419.485572 -142.103856) (xy 419.485572 -139.058396) (xy 419.485205 -139.045049)
			(xy 419.478283 -139.019267) (xy 419.464914 -138.996161) (xy 419.446011 -138.977311) (xy 419.422868 -138.964007)
			(xy 419.397066 -138.957158) (xy 419.383718 -138.956796) (xy 419.382448 -138.956796) (xy 419.355192 -138.95636)
			(xy 419.301234 -138.948609) (xy 419.248929 -138.933256) (xy 419.199341 -138.910616) (xy 419.15348 -138.881148)
			(xy 419.112281 -138.845453) (xy 419.076581 -138.804258) (xy 419.047107 -138.758401) (xy 419.02446 -138.708816)
			(xy 419.009101 -138.656513) (xy 419.001343 -138.602556) (xy 415.882328 -138.602556) (xy 415.882328 -139.48664)
			(xy 417.582602 -139.48664) (xy 417.586673 -139.431018) (xy 417.598799 -139.376581) (xy 417.618722 -139.32449)
			(xy 417.646018 -139.275855) (xy 417.680104 -139.231712) (xy 417.720253 -139.193003) (xy 417.765611 -139.160552)
			(xy 417.815211 -139.135051) (xy 417.867995 -139.117044) (xy 417.922838 -139.106914) (xy 417.978572 -139.104877)
			(xy 418.034009 -139.110977) (xy 418.087966 -139.125083) (xy 418.139295 -139.146895) (xy 418.186901 -139.175949)
			(xy 418.229769 -139.211624) (xy 418.266986 -139.253161) (xy 418.297759 -139.299674) (xy 418.321431 -139.350171)
			(xy 418.337499 -139.403578) (xy 418.345619 -139.458754) (xy 418.346128 -139.48664) (xy 418.345619 -139.514526)
			(xy 418.337499 -139.569702) (xy 418.321431 -139.623109) (xy 418.297759 -139.673606) (xy 418.266986 -139.720119)
			(xy 418.229769 -139.761656) (xy 418.186901 -139.797331) (xy 418.139295 -139.826385) (xy 418.087966 -139.848197)
			(xy 418.034009 -139.862303) (xy 417.978572 -139.868403) (xy 417.922838 -139.866366) (xy 417.867995 -139.856236)
			(xy 417.815211 -139.838229) (xy 417.765611 -139.812728) (xy 417.720253 -139.780277) (xy 417.680104 -139.741568)
			(xy 417.646018 -139.697425) (xy 417.618722 -139.64879) (xy 417.598799 -139.596699) (xy 417.586673 -139.542262)
			(xy 417.582602 -139.48664) (xy 415.882328 -139.48664) (xy 415.882328 -142.07363) (xy 416.267646 -142.458948)
			(xy 416.868862 -142.458948) (xy 416.872933 -142.403326) (xy 416.885059 -142.348889) (xy 416.904982 -142.296798)
			(xy 416.932278 -142.248163) (xy 416.966364 -142.20402) (xy 417.006513 -142.165311) (xy 417.051871 -142.13286)
			(xy 417.101471 -142.107359) (xy 417.154255 -142.089352) (xy 417.209098 -142.079222) (xy 417.264832 -142.077185)
			(xy 417.320269 -142.083285) (xy 417.374226 -142.097391) (xy 417.425555 -142.119203) (xy 417.473161 -142.148257)
			(xy 417.516029 -142.183932) (xy 417.553246 -142.225469) (xy 417.584019 -142.271982) (xy 417.607691 -142.322479)
			(xy 417.623759 -142.375886) (xy 417.631879 -142.431062) (xy 417.632388 -142.458948) (xy 417.631879 -142.486834)
			(xy 417.623759 -142.54201) (xy 417.607691 -142.595417) (xy 417.584019 -142.645914) (xy 417.553246 -142.692427)
			(xy 417.516029 -142.733964) (xy 417.473161 -142.769639) (xy 417.425555 -142.798693) (xy 417.374226 -142.820505)
			(xy 417.320269 -142.834611) (xy 417.264832 -142.840711) (xy 417.209098 -142.838674) (xy 417.154255 -142.828544)
			(xy 417.101471 -142.810537) (xy 417.051871 -142.785036) (xy 417.006513 -142.752585) (xy 416.966364 -142.713876)
			(xy 416.932278 -142.669733) (xy 416.904982 -142.621098) (xy 416.885059 -142.569007) (xy 416.872933 -142.51457)
			(xy 416.868862 -142.458948) (xy 416.267646 -142.458948) (xy 416.952938 -143.14424) (xy 426.4152 -143.14424)
			(xy 426.440196 -143.144871) (xy 426.489219 -143.154676) (xy 426.53539 -143.173851) (xy 426.576936 -143.20166)
			(xy 426.595032 -143.218916) (xy 427.056042 -143.679672) (xy 427.066498 -143.689482) (xy 427.091594 -143.703323)
			(xy 427.11955 -143.709633) (xy 427.148159 -143.707914) (xy 427.175158 -143.698302) (xy 427.198417 -143.681556)
			(xy 427.216097 -143.659) (xy 427.221904 -143.64589) (xy 427.232667 -143.620522) (xy 427.260431 -143.572922)
			(xy 427.294759 -143.529815) (xy 427.334934 -143.492099) (xy 427.38012 -143.460558) (xy 427.40453 -143.44777)
			(xy 427.416899 -143.441083) (xy 427.437636 -143.422108) (xy 427.452403 -143.398191) (xy 427.460078 -143.371151)
			(xy 427.460077 -143.343042) (xy 427.4524 -143.316003) (xy 427.437631 -143.292087) (xy 427.416893 -143.273113)
			(xy 427.40453 -143.266414) (xy 427.38114 -143.254209) (xy 427.337718 -143.224239) (xy 427.298835 -143.188577)
			(xy 427.265232 -143.147902) (xy 427.237548 -143.102988) (xy 427.216311 -143.054691) (xy 427.201924 -143.00393)
			(xy 427.194662 -142.951672) (xy 427.194218 -142.925292) (xy 427.194704 -142.898041) (xy 427.20246 -142.844093)
			(xy 427.217815 -142.791798) (xy 427.240457 -142.742221) (xy 427.269923 -142.696371) (xy 427.305614 -142.65518)
			(xy 427.346805 -142.619489) (xy 427.392655 -142.590023) (xy 427.442232 -142.567381) (xy 427.494527 -142.552026)
			(xy 427.548475 -142.54427) (xy 427.602977 -142.54427) (xy 427.656925 -142.552026) (xy 427.70922 -142.567381)
			(xy 427.758797 -142.590023) (xy 427.804647 -142.619489) (xy 427.845838 -142.65518) (xy 427.881529 -142.696371)
			(xy 427.910995 -142.742221) (xy 427.933637 -142.791798) (xy 427.948992 -142.844093) (xy 427.956748 -142.898041)
			(xy 427.957234 -142.925292) (xy 427.956737 -142.95167) (xy 427.949487 -143.003924) (xy 427.935108 -143.054682)
			(xy 427.913877 -143.102976) (xy 427.886196 -143.147886) (xy 427.852595 -143.188555) (xy 427.813712 -143.224209)
			(xy 427.770289 -143.254169) (xy 427.746922 -143.266414) (xy 427.734572 -143.273128) (xy 427.713846 -143.292103)
			(xy 427.699087 -143.316014) (xy 427.691415 -143.343047) (xy 427.691415 -143.371146) (xy 427.699084 -143.398179)
			(xy 427.713841 -143.422092) (xy 427.734566 -143.441068) (xy 427.746922 -143.44777) (xy 427.770294 -143.460009)
			(xy 427.813717 -143.489972) (xy 427.852602 -143.525628) (xy 427.886208 -143.566298) (xy 427.913894 -143.611207)
			(xy 427.935135 -143.6595) (xy 427.949524 -143.710258) (xy 427.956788 -143.762513) (xy 427.957234 -143.788892)
			(xy 427.956714 -143.817204) (xy 427.948339 -143.873204) (xy 427.931785 -143.927353) (xy 427.907416 -143.978465)
			(xy 427.875766 -144.025417) (xy 427.83753 -144.06718) (xy 427.793545 -144.102838) (xy 427.744776 -144.13161)
			(xy 427.718728 -144.142714) (xy 427.705665 -144.14858) (xy 427.68318 -144.166286) (xy 427.666489 -144.189535)
			(xy 427.656902 -144.216502) (xy 427.655172 -144.245069) (xy 427.661434 -144.272996) (xy 427.675198 -144.298089)
			(xy 427.684946 -144.308576) (xy 429.267112 -145.890996) (xy 429.284361 -145.909098) (xy 429.312172 -145.950641)
			(xy 429.331347 -145.99681) (xy 429.341149 -146.045832) (xy 429.341788 -146.070828) (xy 429.341788 -153.848308)
			(xy 429.341154 -153.873304) (xy 429.331348 -153.922327) (xy 429.312174 -153.968497) (xy 429.284367 -154.010043)
			(xy 429.267112 -154.02814) (xy 427.31436 -155.980892) (xy 427.304994 -155.990902) (xy 427.291489 -156.014746)
			(xy 427.28481 -156.041322) (xy 427.285438 -156.068718) (xy 427.293328 -156.09496) (xy 427.307912 -156.11816)
			(xy 427.32814 -156.136647) (xy 427.352555 -156.149089) (xy 427.379399 -156.154592) (xy 427.3931 -156.15412)
			(xy 427.407814 -156.153173) (xy 427.437284 -156.152155) (xy 427.452028 -156.152088) (xy 427.493586 -156.152616)
			(xy 427.576317 -156.160599) (xy 427.6579 -156.17649) (xy 427.737579 -156.200141) (xy 427.814619 -156.231334)
			(xy 427.888309 -156.269781) (xy 427.957966 -156.315125) (xy 428.022947 -156.366949) (xy 428.082651 -156.424772)
			(xy 428.136527 -156.488062) (xy 428.184077 -156.556232) (xy 428.224862 -156.628654) (xy 428.258504 -156.704657)
			(xy 428.284692 -156.783539) (xy 428.303185 -156.864571) (xy 428.313812 -156.947004) (xy 428.316474 -157.030077)
			(xy 428.311146 -157.113022) (xy 428.297879 -157.195072) (xy 428.276795 -157.275469) (xy 428.248088 -157.35347)
			(xy 428.212024 -157.428354) (xy 428.168936 -157.499429) (xy 428.119222 -157.566038) (xy 428.063343 -157.627565)
			(xy 428.001813 -157.683443) (xy 427.935202 -157.733154) (xy 427.864126 -157.776239) (xy 427.78924 -157.812301)
			(xy 427.711238 -157.841005) (xy 427.630841 -157.862086) (xy 427.54879 -157.87535) (xy 427.465845 -157.880674)
			(xy 427.382772 -157.878009) (xy 427.300339 -157.867379) (xy 427.219308 -157.848883) (xy 427.140427 -157.822692)
			(xy 427.064425 -157.789047) (xy 426.992005 -157.74826) (xy 426.923837 -157.700708) (xy 426.860549 -157.646829)
			(xy 426.802728 -157.587122) (xy 426.750906 -157.52214) (xy 426.705564 -157.452481) (xy 426.667121 -157.37879)
			(xy 426.635931 -157.301749) (xy 426.612283 -157.222068) (xy 426.596395 -157.140485) (xy 426.588414 -157.057754)
			(xy 426.58792 -157.016196) (xy 426.587989 -157.001452) (xy 426.589005 -156.971982) (xy 426.589952 -156.957268)
			(xy 426.590429 -156.943558) (xy 426.584958 -156.916689) (xy 426.572531 -156.892246) (xy 426.554044 -156.871995)
			(xy 426.530832 -156.857397) (xy 426.504572 -156.849506) (xy 426.477158 -156.848891) (xy 426.45057 -156.855599)
			(xy 426.426728 -156.869143) (xy 426.416724 -156.878528) (xy 425.788328 -157.507178) (xy 425.788328 -159.558666)
			(xy 426.563024 -159.558666) (xy 426.563024 -159.47397) (xy 426.571075 -159.389656) (xy 426.587104 -159.30649)
			(xy 426.610965 -159.225223) (xy 426.642444 -159.146593) (xy 426.681255 -159.071312) (xy 426.727045 -159.00006)
			(xy 426.779401 -158.933484) (xy 426.837849 -158.872186) (xy 426.901859 -158.816721) (xy 426.970851 -158.767592)
			(xy 427.044201 -158.725243) (xy 427.121244 -158.690059) (xy 427.201283 -158.662357) (xy 427.283592 -158.642389)
			(xy 427.367427 -158.630336) (xy 427.452028 -158.626306) (xy 427.536629 -158.630336) (xy 427.620464 -158.642389)
			(xy 427.702773 -158.662357) (xy 427.782812 -158.690059) (xy 427.859855 -158.725243) (xy 427.933205 -158.767592)
			(xy 428.002197 -158.816721) (xy 428.066207 -158.872186) (xy 428.124655 -158.933484) (xy 428.177011 -159.00006)
			(xy 428.222801 -159.071312) (xy 428.261612 -159.146593) (xy 428.293091 -159.225223) (xy 428.316952 -159.30649)
			(xy 428.332981 -159.389656) (xy 428.341032 -159.47397) (xy 428.341536 -159.516318) (xy 428.341032 -159.558666)
			(xy 428.332981 -159.64298) (xy 428.316952 -159.726146) (xy 428.293091 -159.807413) (xy 428.261612 -159.886043)
			(xy 428.222801 -159.961324) (xy 428.177011 -160.032576) (xy 428.124655 -160.099152) (xy 428.066207 -160.16045)
			(xy 428.002197 -160.215915) (xy 427.933205 -160.265044) (xy 427.859855 -160.307393) (xy 427.782812 -160.342577)
			(xy 427.702773 -160.370279) (xy 427.620464 -160.390247) (xy 427.536629 -160.4023) (xy 427.452028 -160.406331)
			(xy 427.367427 -160.4023) (xy 427.283592 -160.390247) (xy 427.201283 -160.370279) (xy 427.121244 -160.342577)
			(xy 427.044201 -160.307393) (xy 426.970851 -160.265044) (xy 426.901859 -160.215915) (xy 426.837849 -160.16045)
			(xy 426.779401 -160.099152) (xy 426.727045 -160.032576) (xy 426.681255 -159.961324) (xy 426.642444 -159.886043)
			(xy 426.610965 -159.807413) (xy 426.587104 -159.726146) (xy 426.571075 -159.64298) (xy 426.563024 -159.558666)
			(xy 425.788328 -159.558666) (xy 425.788328 -161.478976) (xy 425.787692 -161.503972) (xy 425.77789 -161.552996)
			(xy 425.758716 -161.599167) (xy 425.730908 -161.640712) (xy 425.713652 -161.658808) (xy 424.201844 -163.170616)
			(xy 425.480988 -163.170616) (xy 425.48147 -163.143364) (xy 425.489225 -163.089414) (xy 425.504579 -163.037116)
			(xy 425.527219 -162.987537) (xy 425.556685 -162.941684) (xy 425.592377 -162.900491) (xy 425.633568 -162.864797)
			(xy 425.679419 -162.835329) (xy 425.728998 -162.812686) (xy 425.781294 -162.797329) (xy 425.835244 -162.789572)
			(xy 425.862496 -162.789108) (xy 425.890642 -162.789598) (xy 425.946324 -162.797875) (xy 426.000186 -162.814237)
			(xy 426.051064 -162.838327) (xy 426.097854 -162.869626) (xy 426.119036 -162.888168) (xy 426.130841 -162.8982)
			(xy 426.15893 -162.911235) (xy 426.189633 -162.915257) (xy 426.220131 -162.909897) (xy 426.247624 -162.895647)
			(xy 426.25899 -162.88512) (xy 426.280551 -162.864437) (xy 426.328964 -162.829427) (xy 426.382244 -162.802395)
			(xy 426.439087 -162.784001) (xy 426.498103 -162.774696) (xy 426.527976 -162.774122) (xy 426.556122 -162.77462)
			(xy 426.611803 -162.782895) (xy 426.665666 -162.799254) (xy 426.716544 -162.823343) (xy 426.763334 -162.85464)
			(xy 426.784516 -162.873182) (xy 426.796337 -162.883193) (xy 426.82442 -162.896228) (xy 426.855118 -162.900253)
			(xy 426.885612 -162.894899) (xy 426.913103 -162.880657) (xy 426.92447 -162.870134) (xy 426.946042 -162.849463)
			(xy 426.994452 -162.814451) (xy 427.047729 -162.787416) (xy 427.10457 -162.76902) (xy 427.163584 -162.759712)
			(xy 427.193456 -162.759136) (xy 427.22071 -162.759596) (xy 427.274663 -162.767348) (xy 427.326964 -162.782701)
			(xy 427.376547 -162.805342) (xy 427.422402 -162.834809) (xy 427.463596 -162.870504) (xy 427.499291 -162.911698)
			(xy 427.528758 -162.957553) (xy 427.551399 -163.007136) (xy 427.566752 -163.059437) (xy 427.574504 -163.11339)
			(xy 427.574964 -163.140644) (xy 427.57445 -163.169383) (xy 427.565822 -163.22621) (xy 427.548769 -163.2811)
			(xy 427.523676 -163.332812) (xy 427.49111 -163.380175) (xy 427.47184 -163.401502) (xy 427.461724 -163.413001)
			(xy 427.448385 -163.44056) (xy 427.443809 -163.470832) (xy 427.448405 -163.501102) (xy 427.461761 -163.528652)
			(xy 427.47184 -163.540186) (xy 427.491156 -163.561474) (xy 427.523723 -163.608842) (xy 427.548814 -163.66056)
			(xy 427.565863 -163.715457) (xy 427.574482 -163.77229) (xy 427.574477 -163.829774) (xy 427.565849 -163.886606)
			(xy 427.548791 -163.9415) (xy 427.52369 -163.993213) (xy 427.491116 -164.040576) (xy 427.47184 -164.061902)
			(xy 427.461724 -164.073401) (xy 427.448385 -164.10096) (xy 427.443809 -164.131232) (xy 427.448405 -164.161502)
			(xy 427.461761 -164.189052) (xy 427.47184 -164.200586) (xy 427.491156 -164.221874) (xy 427.523723 -164.269242)
			(xy 427.548814 -164.32096) (xy 427.565863 -164.375857) (xy 427.574482 -164.43269) (xy 427.574477 -164.490174)
			(xy 427.565849 -164.547006) (xy 427.548791 -164.6019) (xy 427.52369 -164.653613) (xy 427.491116 -164.700976)
			(xy 427.47184 -164.722302) (xy 427.461724 -164.733801) (xy 427.448385 -164.76136) (xy 427.443809 -164.791632)
			(xy 427.448405 -164.821902) (xy 427.461761 -164.849452) (xy 427.47184 -164.860986) (xy 427.491156 -164.882274)
			(xy 427.523723 -164.929642) (xy 427.548814 -164.98136) (xy 427.565863 -165.036257) (xy 427.574482 -165.09309)
			(xy 427.574477 -165.150574) (xy 427.565849 -165.207406) (xy 427.548791 -165.2623) (xy 427.52369 -165.314013)
			(xy 427.491116 -165.361376) (xy 427.47184 -165.382702) (xy 427.461724 -165.394201) (xy 427.448385 -165.42176)
			(xy 427.443809 -165.452032) (xy 427.448405 -165.482302) (xy 427.461761 -165.509852) (xy 427.47184 -165.521386)
			(xy 427.491156 -165.542674) (xy 427.523723 -165.590042) (xy 427.548814 -165.64176) (xy 427.565863 -165.696657)
			(xy 427.574482 -165.75349) (xy 427.574477 -165.810974) (xy 427.565849 -165.867806) (xy 427.548791 -165.9227)
			(xy 427.52369 -165.974413) (xy 427.491116 -166.021776) (xy 427.47184 -166.043102) (xy 427.461724 -166.054601)
			(xy 427.448385 -166.08216) (xy 427.443809 -166.112432) (xy 427.448405 -166.142702) (xy 427.461761 -166.170252)
			(xy 427.47184 -166.181786) (xy 427.491128 -166.203098) (xy 427.523693 -166.250464) (xy 427.548782 -166.302179)
			(xy 427.565829 -166.357073) (xy 427.574446 -166.413904) (xy 427.57457 -166.4208) (xy 430.96942 -166.4208)
			(xy 430.969965 -166.392062) (xy 430.978586 -166.335237) (xy 430.995632 -166.280347) (xy 431.020718 -166.228635)
			(xy 431.053277 -166.181271) (xy 431.072544 -166.159942) (xy 431.082618 -166.148409) (xy 431.095963 -166.120863)
			(xy 431.100549 -166.0906) (xy 431.095963 -166.060337) (xy 431.082618 -166.032791) (xy 431.072544 -166.021258)
			(xy 431.053272 -165.999932) (xy 431.020705 -165.95257) (xy 430.995612 -165.900858) (xy 430.978561 -165.845967)
			(xy 430.969938 -165.789139) (xy 430.969938 -165.731661) (xy 430.978561 -165.674833) (xy 430.995612 -165.619942)
			(xy 431.020705 -165.56823) (xy 431.053272 -165.520868) (xy 431.072544 -165.499542) (xy 431.082618 -165.488009)
			(xy 431.095963 -165.460463) (xy 431.100549 -165.4302) (xy 431.095963 -165.399937) (xy 431.082618 -165.372391)
			(xy 431.072544 -165.360858) (xy 431.053272 -165.339532) (xy 431.020705 -165.29217) (xy 430.995612 -165.240458)
			(xy 430.978561 -165.185567) (xy 430.969938 -165.128739) (xy 430.969938 -165.071261) (xy 430.978561 -165.014433)
			(xy 430.995612 -164.959542) (xy 431.020705 -164.90783) (xy 431.053272 -164.860468) (xy 431.072544 -164.839142)
			(xy 431.082618 -164.827609) (xy 431.095963 -164.800063) (xy 431.100549 -164.7698) (xy 431.095963 -164.739537)
			(xy 431.082618 -164.711991) (xy 431.072544 -164.700458) (xy 431.053272 -164.679132) (xy 431.020705 -164.63177)
			(xy 430.995612 -164.580058) (xy 430.978561 -164.525167) (xy 430.969938 -164.468339) (xy 430.969938 -164.410861)
			(xy 430.978561 -164.354033) (xy 430.995612 -164.299142) (xy 431.020705 -164.24743) (xy 431.053272 -164.200068)
			(xy 431.072544 -164.178742) (xy 431.082618 -164.167209) (xy 431.095963 -164.139663) (xy 431.100549 -164.1094)
			(xy 431.095963 -164.079137) (xy 431.082618 -164.051591) (xy 431.072544 -164.040058) (xy 431.053274 -164.01873)
			(xy 431.020708 -163.971368) (xy 430.995615 -163.919657) (xy 430.978564 -163.864766) (xy 430.969941 -163.807939)
			(xy 430.96942 -163.7792) (xy 430.96983 -163.753378) (xy 430.976782 -163.702204) (xy 430.990572 -163.652435)
			(xy 431.010949 -163.604981) (xy 431.037539 -163.560709) (xy 431.069858 -163.520427) (xy 431.088292 -163.50234)
			(xy 431.09798 -163.492559) (xy 431.112152 -163.468967) (xy 431.119503 -163.442447) (xy 431.1195 -163.414926)
			(xy 431.112141 -163.388407) (xy 431.097962 -163.36482) (xy 431.088292 -163.35502) (xy 431.069869 -163.336925)
			(xy 431.037565 -163.296636) (xy 431.010985 -163.252362) (xy 430.990611 -163.204911) (xy 430.976815 -163.155148)
			(xy 430.96985 -163.10398) (xy 430.96942 -163.07816) (xy 430.969941 -163.049421) (xy 430.978567 -162.992595)
			(xy 430.995619 -162.937705) (xy 431.020711 -162.885993) (xy 431.053274 -162.83863) (xy 431.072544 -162.817302)
			(xy 431.082657 -162.8058) (xy 431.095999 -162.778243) (xy 431.100577 -162.747971) (xy 431.095981 -162.717701)
			(xy 431.082624 -162.690151) (xy 431.072544 -162.678618) (xy 431.053255 -162.657306) (xy 431.020691 -162.60994)
			(xy 430.995602 -162.558225) (xy 430.978556 -162.503331) (xy 430.969938 -162.4465) (xy 430.96942 -162.41776)
			(xy 430.969841 -162.390506) (xy 430.977603 -162.336555) (xy 430.992965 -162.284257) (xy 431.015613 -162.234678)
			(xy 431.045086 -162.188827) (xy 431.080784 -162.147636) (xy 431.121981 -162.111945) (xy 431.167838 -162.08248)
			(xy 431.217421 -162.059841) (xy 431.269722 -162.044489) (xy 431.323674 -162.036736) (xy 431.350928 -162.036252)
			(xy 431.379073 -162.036771) (xy 431.434754 -162.04504) (xy 431.488617 -162.061394) (xy 431.539495 -162.085478)
			(xy 431.586286 -162.116772) (xy 431.607468 -162.135312) (xy 431.619251 -162.145371) (xy 431.647348 -162.158396)
			(xy 431.678057 -162.16241) (xy 431.708558 -162.157044) (xy 431.736054 -162.142792) (xy 431.747422 -162.132264)
			(xy 431.76902 -162.111621) (xy 431.817422 -162.076604) (xy 431.870692 -162.049563) (xy 431.927528 -162.031161)
			(xy 431.986538 -162.021846) (xy 432.016408 -162.021266) (xy 432.045147 -162.021794) (xy 432.101973 -162.030417)
			(xy 432.156864 -162.047466) (xy 432.208576 -162.072557) (xy 432.255939 -162.10512) (xy 432.277266 -162.12439)
			(xy 432.2888 -162.134462) (xy 432.316346 -162.147804) (xy 432.346608 -162.152389) (xy 432.37687 -162.147804)
			(xy 432.404416 -162.134462) (xy 432.41595 -162.12439) (xy 432.437282 -162.105124) (xy 432.484642 -162.072556)
			(xy 432.536352 -162.047461) (xy 432.591242 -162.03041) (xy 432.648069 -162.021787) (xy 432.676808 -162.021266)
			(xy 432.704058 -162.02177) (xy 432.758004 -162.029527) (xy 432.810297 -162.044882) (xy 432.859872 -162.067522)
			(xy 432.905721 -162.096987) (xy 432.946911 -162.132676) (xy 432.982602 -162.173864) (xy 433.012069 -162.219712)
			(xy 433.034712 -162.269286) (xy 433.050069 -162.321578) (xy 433.057828 -162.375524) (xy 433.058316 -162.402774)
			(xy 433.057772 -162.431512) (xy 433.049154 -162.488338) (xy 433.032108 -162.543229) (xy 433.007021 -162.594941)
			(xy 432.974461 -162.642304) (xy 432.955192 -162.663632) (xy 432.945149 -162.675188) (xy 432.931809 -162.702727)
			(xy 432.927221 -162.732981) (xy 432.931798 -162.763237) (xy 432.945127 -162.790781) (xy 432.955192 -162.802316)
			(xy 432.974455 -162.823649) (xy 433.007022 -162.87101) (xy 433.032115 -162.92272) (xy 433.049167 -162.977609)
			(xy 433.057793 -163.034436) (xy 433.058316 -163.063174) (xy 433.057878 -163.088995) (xy 433.05093 -163.140167)
			(xy 433.037145 -163.189935) (xy 433.016773 -163.237389) (xy 432.990188 -163.281662) (xy 432.957875 -163.321945)
			(xy 432.939444 -163.340034) (xy 432.92978 -163.349838) (xy 432.915601 -163.373422) (xy 432.908243 -163.399937)
			(xy 432.908242 -163.427455) (xy 432.915598 -163.453971) (xy 432.929774 -163.477556) (xy 432.939444 -163.487354)
			(xy 432.957891 -163.505427) (xy 432.990194 -163.545719) (xy 433.016773 -163.589997) (xy 433.037143 -163.637453)
			(xy 433.050933 -163.68722) (xy 433.05789 -163.738393) (xy 433.058316 -163.764214) (xy 433.057796 -163.792953)
			(xy 433.049172 -163.84978) (xy 433.032121 -163.904671) (xy 433.007029 -163.956383) (xy 432.974463 -164.003745)
			(xy 432.955192 -164.025072) (xy 432.94511 -164.036597) (xy 432.931774 -164.064147) (xy 432.927194 -164.09441)
			(xy 432.93178 -164.124673) (xy 432.945121 -164.15222) (xy 432.955192 -164.163756) (xy 432.974476 -164.185071)
			(xy 433.007039 -164.232436) (xy 433.032129 -164.28415) (xy 433.049177 -164.339042) (xy 433.057798 -164.395871)
			(xy 433.057797 -164.45335) (xy 433.049173 -164.510178) (xy 433.032122 -164.565069) (xy 433.007029 -164.616782)
			(xy 432.974463 -164.664145) (xy 432.955192 -164.685472) (xy 432.94511 -164.696997) (xy 432.931774 -164.724547)
			(xy 432.927194 -164.75481) (xy 432.93178 -164.785073) (xy 432.945121 -164.81262) (xy 432.955192 -164.824156)
			(xy 432.974476 -164.845471) (xy 433.007039 -164.892836) (xy 433.032129 -164.94455) (xy 433.049177 -164.999442)
			(xy 433.057798 -165.056271) (xy 433.057797 -165.11375) (xy 433.049173 -165.170578) (xy 433.032122 -165.225469)
			(xy 433.007029 -165.277182) (xy 432.974463 -165.324545) (xy 432.955192 -165.345872) (xy 432.94511 -165.357397)
			(xy 432.931774 -165.384947) (xy 432.927194 -165.41521) (xy 432.93178 -165.445473) (xy 432.945121 -165.47302)
			(xy 432.955192 -165.484556) (xy 432.974474 -165.505873) (xy 433.007038 -165.553238) (xy 433.032128 -165.604952)
			(xy 433.049176 -165.659845) (xy 433.057796 -165.716674) (xy 433.058316 -165.745414) (xy 433.057835 -165.772665)
			(xy 433.050077 -165.826613) (xy 433.034721 -165.878907) (xy 433.012078 -165.928484) (xy 432.982611 -165.974334)
			(xy 432.946919 -166.015524) (xy 432.905729 -166.051215) (xy 432.859879 -166.080681) (xy 432.810301 -166.103323)
			(xy 432.758007 -166.118678) (xy 432.704059 -166.126436) (xy 432.676808 -166.126922) (xy 432.649163 -166.126403)
			(xy 432.594453 -166.118406) (xy 432.541471 -166.102593) (xy 432.491328 -166.079296) (xy 432.445074 -166.049002)
			(xy 432.40368 -166.012347) (xy 432.38547 -165.99154) (xy 432.377861 -165.983437) (xy 432.35771 -165.974116)
			(xy 432.335506 -165.974116) (xy 432.315355 -165.983437) (xy 432.307746 -165.99154) (xy 432.294792 -166.006272)
			(xy 432.28471 -166.017797) (xy 432.271374 -166.045347) (xy 432.266794 -166.07561) (xy 432.27138 -166.105873)
			(xy 432.284721 -166.13342) (xy 432.294792 -166.144956) (xy 432.314074 -166.166273) (xy 432.346638 -166.213638)
			(xy 432.371728 -166.265352) (xy 432.388776 -166.320245) (xy 432.397396 -166.377074) (xy 432.397916 -166.405814)
			(xy 432.397371 -166.4341) (xy 432.389016 -166.490053) (xy 432.372492 -166.544159) (xy 432.34816 -166.595232)
			(xy 432.316555 -166.642153) (xy 432.29784 -166.66337) (xy 432.28775 -166.675307) (xy 432.274637 -166.703659)
			(xy 432.270696 -166.734646) (xy 432.276295 -166.765378) (xy 432.290912 -166.792984) (xy 432.30165 -166.80434)
			(xy 432.322827 -166.826023) (xy 432.358792 -166.874803) (xy 432.386591 -166.928657) (xy 432.405522 -166.98623)
			(xy 432.415111 -167.046071) (xy 432.415696 -167.076374) (xy 432.41522 -167.103627) (xy 432.407467 -167.157578)
			(xy 432.392113 -167.209876) (xy 432.369473 -167.259457) (xy 432.340007 -167.305311) (xy 432.304314 -167.346504)
			(xy 432.263122 -167.382198) (xy 432.217269 -167.411666) (xy 432.167689 -167.434308) (xy 432.115392 -167.449664)
			(xy 432.061441 -167.457419) (xy 432.034188 -167.457882) (xy 432.006043 -167.457345) (xy 431.950364 -167.449079)
			(xy 431.896502 -167.432729) (xy 431.845623 -167.408649) (xy 431.798831 -167.37736) (xy 431.777648 -167.358822)
			(xy 431.765855 -167.348775) (xy 431.737762 -167.335744) (xy 431.707055 -167.331725) (xy 431.676555 -167.337089)
			(xy 431.649061 -167.351341) (xy 431.637694 -167.36187) (xy 431.616095 -167.382511) (xy 431.567692 -167.417527)
			(xy 431.514422 -167.444567) (xy 431.457587 -167.462971) (xy 431.398578 -167.472287) (xy 431.368708 -167.472868)
			(xy 431.341454 -167.472437) (xy 431.287499 -167.46468) (xy 431.235198 -167.449323) (xy 431.185616 -167.426679)
			(xy 431.139761 -167.397208) (xy 431.098567 -167.361511) (xy 431.062873 -167.320314) (xy 431.033406 -167.274456)
			(xy 431.010766 -167.224872) (xy 430.995413 -167.172569) (xy 430.987661 -167.118615) (xy 430.9872 -167.09136)
			(xy 430.987726 -167.063073) (xy 430.996085 -167.007119) (xy 431.012613 -166.953013) (xy 431.036949 -166.90194)
			(xy 431.068559 -166.85502) (xy 431.087276 -166.833804) (xy 431.09739 -166.821886) (xy 431.110498 -166.793527)
			(xy 431.114434 -166.762534) (xy 431.108828 -166.7318) (xy 431.094206 -166.704191) (xy 431.083466 -166.692834)
			(xy 431.062279 -166.67116) (xy 431.026315 -166.622378) (xy 430.998518 -166.568521) (xy 430.979589 -166.510947)
			(xy 430.970003 -166.451103) (xy 430.96942 -166.4208) (xy 427.57457 -166.4208) (xy 427.574964 -166.442644)
			(xy 427.574563 -166.469898) (xy 427.566799 -166.523851) (xy 427.551436 -166.57615) (xy 427.528787 -166.625731)
			(xy 427.499312 -166.671583) (xy 427.463612 -166.712774) (xy 427.422412 -166.748465) (xy 427.376553 -166.777929)
			(xy 427.326968 -166.800567) (xy 427.274665 -166.815918) (xy 427.22071 -166.823669) (xy 427.193456 -166.824152)
			(xy 427.16531 -166.823641) (xy 427.10963 -166.815371) (xy 427.055766 -166.799015) (xy 427.004888 -166.774928)
			(xy 426.958098 -166.743633) (xy 426.936916 -166.725092) (xy 426.925069 -166.715116) (xy 426.896995 -166.702081)
			(xy 426.866306 -166.698051) (xy 426.835818 -166.703395) (xy 426.80833 -166.717624) (xy 426.796962 -166.72814)
			(xy 426.775372 -166.748791) (xy 426.726968 -166.783807) (xy 426.673695 -166.810846) (xy 426.616858 -166.829247)
			(xy 426.557847 -166.838559) (xy 426.527976 -166.839138) (xy 426.499237 -166.838619) (xy 426.44241 -166.829993)
			(xy 426.38752 -166.812942) (xy 426.335808 -166.78785) (xy 426.288445 -166.755284) (xy 426.267118 -166.736014)
			(xy 426.255584 -166.725942) (xy 426.228038 -166.7126) (xy 426.197776 -166.708015) (xy 426.167514 -166.7126)
			(xy 426.139968 -166.725942) (xy 426.128434 -166.736014) (xy 426.10711 -166.755288) (xy 426.059748 -166.787856)
			(xy 426.008036 -166.812948) (xy 425.953144 -166.829998) (xy 425.896315 -166.838619) (xy 425.867576 -166.839138)
			(xy 425.840326 -166.838645) (xy 425.78638 -166.830886) (xy 425.734087 -166.815529) (xy 425.684512 -166.792887)
			(xy 425.638663 -166.763421) (xy 425.597474 -166.727731) (xy 425.561782 -166.686542) (xy 425.532316 -166.640694)
			(xy 425.509673 -166.591119) (xy 425.494316 -166.538826) (xy 425.486556 -166.48488) (xy 425.486068 -166.45763)
			(xy 425.486619 -166.428892) (xy 425.495236 -166.372066) (xy 425.51228 -166.317176) (xy 425.537366 -166.265464)
			(xy 425.569924 -166.2181) (xy 425.589192 -166.196772) (xy 425.599232 -166.185214) (xy 425.612575 -166.157676)
			(xy 425.617164 -166.127422) (xy 425.612588 -166.097166) (xy 425.599257 -166.069623) (xy 425.589192 -166.058088)
			(xy 425.569952 -166.036735) (xy 425.537389 -165.989376) (xy 425.512298 -165.937668) (xy 425.495247 -165.882782)
			(xy 425.486622 -165.825959) (xy 425.486619 -165.768485) (xy 425.495237 -165.711661) (xy 425.512282 -165.656773)
			(xy 425.537367 -165.605062) (xy 425.569925 -165.557699) (xy 425.589192 -165.536372) (xy 425.599232 -165.524814)
			(xy 425.612575 -165.497276) (xy 425.617164 -165.467022) (xy 425.612588 -165.436766) (xy 425.599257 -165.409223)
			(xy 425.589192 -165.397688) (xy 425.569952 -165.376335) (xy 425.537389 -165.328976) (xy 425.512298 -165.277268)
			(xy 425.495247 -165.222382) (xy 425.486622 -165.165559) (xy 425.486619 -165.108085) (xy 425.495237 -165.051261)
			(xy 425.512282 -164.996373) (xy 425.537367 -164.944662) (xy 425.569925 -164.897299) (xy 425.589192 -164.875972)
			(xy 425.599232 -164.864414) (xy 425.612575 -164.836876) (xy 425.617164 -164.806622) (xy 425.612588 -164.776366)
			(xy 425.599257 -164.748823) (xy 425.589192 -164.737288) (xy 425.569952 -164.715935) (xy 425.537389 -164.668576)
			(xy 425.512298 -164.616868) (xy 425.495247 -164.561982) (xy 425.486622 -164.505159) (xy 425.486619 -164.447685)
			(xy 425.495237 -164.390861) (xy 425.512282 -164.335973) (xy 425.537367 -164.284262) (xy 425.569925 -164.236899)
			(xy 425.589192 -164.215572) (xy 425.599232 -164.204014) (xy 425.612575 -164.176476) (xy 425.617164 -164.146222)
			(xy 425.612588 -164.115966) (xy 425.599257 -164.088423) (xy 425.589192 -164.076888) (xy 425.569945 -164.05554)
			(xy 425.537373 -164.008185) (xy 425.512276 -163.956479) (xy 425.49522 -163.901592) (xy 425.486592 -163.844768)
			(xy 425.486068 -163.81603) (xy 425.486068 -163.815522) (xy 425.486572 -163.787944) (xy 425.494554 -163.733368)
			(xy 425.510312 -163.68051) (xy 425.533517 -163.630472) (xy 425.563685 -163.584297) (xy 425.581572 -163.5633)
			(xy 425.590996 -163.551771) (xy 425.603448 -163.524742) (xy 425.607576 -163.495271) (xy 425.603028 -163.465862)
			(xy 425.590191 -163.439014) (xy 425.580556 -163.427664) (xy 425.561911 -163.406478) (xy 425.530459 -163.35962)
			(xy 425.506249 -163.308641) (xy 425.489809 -163.254654) (xy 425.481497 -163.198834) (xy 425.480988 -163.170616)
			(xy 424.201844 -163.170616) (xy 423.37482 -163.99764) (xy 423.3567 -164.01487) (xy 423.315165 -164.042687)
			(xy 423.269001 -164.061868) (xy 423.219982 -164.071675) (xy 423.194988 -164.072316) (xy 421.90289 -164.072316)
			(xy 421.116252 -164.8587) (xy 421.09817 -164.875972) (xy 421.056621 -164.903779) (xy 421.010445 -164.922948)
			(xy 420.961418 -164.932742) (xy 420.93642 -164.933376) (xy 420.271448 -164.933376) (xy 420.246453 -164.932711)
			(xy 420.197432 -164.922916) (xy 420.151262 -164.903751) (xy 420.109714 -164.875951) (xy 420.091616 -164.8587)
			(xy 419.777418 -164.544502) (xy 419.756082 -164.544502) (xy 419.728805 -164.544104) (xy 419.674797 -164.536402)
			(xy 419.622437 -164.521086) (xy 419.572793 -164.498469) (xy 419.526876 -164.469012) (xy 419.485622 -164.433315)
			(xy 419.449874 -164.392106) (xy 419.420359 -164.346226) (xy 419.39768 -164.296609) (xy 419.382299 -164.244269)
			(xy 419.37453 -164.190271) (xy 419.374066 -164.162994) (xy 419.374572 -164.135744) (xy 419.382329 -164.081798)
			(xy 419.397683 -164.029505) (xy 419.420323 -163.97993) (xy 419.449788 -163.934081) (xy 419.485477 -163.892891)
			(xy 419.526665 -163.8572) (xy 419.572512 -163.827733) (xy 419.622087 -163.80509) (xy 419.674379 -163.789733)
			(xy 419.728324 -163.781974) (xy 419.755574 -163.781486) (xy 419.785261 -163.782065) (xy 419.843919 -163.79126)
			(xy 419.900444 -163.809431) (xy 419.953471 -163.836139) (xy 420.001721 -163.870741) (xy 420.044027 -163.912399)
			(xy 420.062152 -163.935918) (xy 420.070578 -163.946525) (xy 420.091891 -163.963232) (xy 420.116845 -163.973751)
			(xy 420.143686 -163.977341) (xy 420.170527 -163.973751) (xy 420.195481 -163.963232) (xy 420.216794 -163.946525)
			(xy 420.22522 -163.935918) (xy 420.242997 -163.912769) (xy 420.284466 -163.871698) (xy 420.33171 -163.837426)
			(xy 420.383623 -163.810752) (xy 420.438995 -163.7923) (xy 420.496532 -163.7825) (xy 420.525702 -163.781486)
			(xy 420.546276 -163.781232) (xy 421.070532 -163.256976) (xy 421.088617 -163.239708) (xy 421.130166 -163.211901)
			(xy 421.17634 -163.192731) (xy 421.225367 -163.182935) (xy 421.250364 -163.1823) (xy 422.93159 -163.1823)
			(xy 424.898312 -161.215578) (xy 424.898312 -157.24378) (xy 424.898939 -157.218784) (xy 424.908747 -157.169761)
			(xy 424.927923 -157.12359) (xy 424.955732 -157.082044) (xy 424.972988 -157.063948) (xy 428.451772 -153.58491)
			(xy 428.451772 -146.334226) (xy 426.151802 -144.034256) (xy 416.68954 -144.034256) (xy 416.664545 -144.033602)
			(xy 416.615523 -144.023804) (xy 416.569352 -144.004636) (xy 416.527805 -143.976833) (xy 416.509708 -143.95958)
			(xy 415.066988 -142.51686) (xy 415.049718 -142.498777) (xy 415.021911 -142.457227) (xy 415.002742 -142.411052)
			(xy 414.992947 -142.362025) (xy 414.992312 -142.337028) (xy 413.909256 -142.337028) (xy 416.824668 -145.25244)
			(xy 426.6184 -145.25244) (xy 426.648377 -145.253036) (xy 426.707592 -145.262426) (xy 426.76461 -145.28096)
			(xy 426.818028 -145.308181) (xy 426.866534 -145.34342) (xy 426.888148 -145.3642) (xy 428.031148 -146.5072)
			(xy 428.051961 -146.528788) (xy 428.087215 -146.577291) (xy 428.114444 -146.630715) (xy 428.132976 -146.687742)
			(xy 428.142353 -146.746967) (xy 428.142908 -146.776948) (xy 428.142908 -153.363168) (xy 428.142307 -153.393145)
			(xy 428.132921 -153.45236) (xy 428.114389 -153.509379) (xy 428.087168 -153.562798) (xy 428.051928 -153.611302)
			(xy 428.031148 -153.632916) (xy 424.514518 -157.149546) (xy 424.492947 -157.170284) (xy 424.444517 -157.205423)
			(xy 424.391195 -157.232572) (xy 424.33429 -157.251064) (xy 424.275195 -157.260447) (xy 424.245278 -157.261052)
			(xy 423.90568 -157.261052) (xy 423.878448 -157.260569) (xy 423.824538 -157.252815) (xy 423.77228 -157.237469)
			(xy 423.722738 -157.214841) (xy 423.67692 -157.185394) (xy 423.63576 -157.149726) (xy 423.600094 -157.108563)
			(xy 423.570649 -157.062744) (xy 423.548024 -157.013201) (xy 423.53268 -156.960943) (xy 423.52493 -156.907032)
			(xy 423.52493 -156.852568) (xy 423.53268 -156.798657) (xy 423.548024 -156.746399) (xy 423.570649 -156.696856)
			(xy 423.600094 -156.651037) (xy 423.63576 -156.609874) (xy 423.67692 -156.574206) (xy 423.722738 -156.544759)
			(xy 423.77228 -156.522131) (xy 423.824538 -156.506785) (xy 423.878448 -156.499031) (xy 423.90568 -156.498544)
			(xy 424.086782 -156.498544) (xy 424.190414 -156.394658) (xy 424.135042 -156.339286) (xy 424.107864 -156.345128)
			(xy 424.087977 -156.34915) (xy 424.047633 -156.353479) (xy 424.027346 -156.353764) (xy 424.026838 -156.353764)
			(xy 423.99958 -156.353392) (xy 423.945619 -156.345638) (xy 423.89331 -156.330284) (xy 423.84372 -156.307641)
			(xy 423.797856 -156.27817) (xy 423.756654 -156.242472) (xy 423.720953 -156.201274) (xy 423.691478 -156.155414)
			(xy 423.66883 -156.105825) (xy 423.65347 -156.053518) (xy 423.645711 -155.999558) (xy 423.645711 -155.945042)
			(xy 423.65347 -155.891082) (xy 423.66883 -155.838775) (xy 423.691478 -155.789186) (xy 423.720953 -155.743326)
			(xy 423.756654 -155.702128) (xy 423.797856 -155.66643) (xy 423.84372 -155.636959) (xy 423.89331 -155.614316)
			(xy 423.945619 -155.598962) (xy 423.99958 -155.591208) (xy 424.026838 -155.590748) (xy 424.055273 -155.591308)
			(xy 424.111514 -155.599756) (xy 424.165877 -155.616458) (xy 424.217158 -155.641046) (xy 424.264221 -155.672973)
			(xy 424.306024 -155.711533) (xy 424.34164 -155.755871) (xy 424.370279 -155.805004) (xy 424.391307 -155.857845)
			(xy 424.404259 -155.913221) (xy 424.407076 -155.941522) (xy 424.408753 -155.955907) (xy 424.419142 -155.982927)
			(xy 424.43669 -156.005951) (xy 424.459988 -156.023132) (xy 424.487168 -156.033094) (xy 424.516051 -156.035037)
			(xy 424.544321 -156.028804) (xy 424.56971 -156.014897) (xy 424.580304 -156.005022) (xy 427.379892 -153.20518)
			(xy 427.379892 -146.934936) (xy 426.460412 -146.015456) (xy 416.66668 -146.015456) (xy 416.636702 -146.014874)
			(xy 416.577487 -146.005481) (xy 416.520469 -145.986944) (xy 416.46705 -145.959719) (xy 416.418546 -145.924477)
			(xy 416.396932 -145.903696) (xy 412.932372 -142.439136) (xy 412.91158 -142.417529) (xy 412.876322 -142.369031)
			(xy 412.849089 -142.315612) (xy 412.830553 -142.258589) (xy 412.82117 -142.199368) (xy 412.820612 -142.169388)
			(xy 411.584385 -142.169388) (xy 415.721292 -146.30654) (xy 425.475654 -146.30654) (xy 425.500636 -146.307055)
			(xy 425.549979 -146.314913) (xy 425.59749 -146.330381) (xy 425.642002 -146.353078) (xy 425.682423 -146.382449)
			(xy 425.700444 -146.399758) (xy 427.12259 -147.821904) (xy 427.139946 -147.839888) (xy 427.169352 -147.8803)
			(xy 427.192066 -147.924818) (xy 427.207528 -147.972344) (xy 427.215356 -148.021705) (xy 427.215808 -148.046694)
			(xy 427.215808 -152.281382) (xy 427.215291 -152.306363) (xy 427.20743 -152.355705) (xy 427.191961 -152.403214)
			(xy 427.169263 -152.447725) (xy 427.139894 -152.488146) (xy 427.12259 -152.506172) (xy 424.412664 -155.216098)
			(xy 424.394679 -155.233452) (xy 424.354266 -155.262853) (xy 424.309748 -155.285562) (xy 424.262222 -155.301018)
			(xy 424.212862 -155.308841) (xy 424.187874 -155.309316) (xy 423.915332 -155.309316) (xy 423.078148 -156.1465)
			(xy 423.078148 -156.748988) (xy 423.093161 -156.772511) (xy 423.116886 -156.823019) (xy 423.132993 -156.876447)
			(xy 423.141137 -156.931653) (xy 423.141648 -156.959554) (xy 423.141648 -156.960062) (xy 423.141162 -156.987313)
			(xy 423.133406 -157.041261) (xy 423.118051 -157.093556) (xy 423.095409 -157.143133) (xy 423.065943 -157.188983)
			(xy 423.030252 -157.230174) (xy 422.989061 -157.265865) (xy 422.943211 -157.295331) (xy 422.893634 -157.317973)
			(xy 422.841339 -157.333328) (xy 422.787391 -157.341084) (xy 422.732889 -157.341084) (xy 422.678941 -157.333328)
			(xy 422.626646 -157.317973) (xy 422.577069 -157.295331) (xy 422.531219 -157.265865) (xy 422.490028 -157.230174)
			(xy 422.454337 -157.188983) (xy 422.424871 -157.143133) (xy 422.402229 -157.093556) (xy 422.386874 -157.041261)
			(xy 422.379118 -156.987313) (xy 422.378632 -156.960062) (xy 422.378632 -156.959554) (xy 422.379166 -156.931656)
			(xy 422.387336 -156.876462) (xy 422.403451 -156.823044) (xy 422.427169 -156.77254) (xy 422.442132 -156.748988)
			(xy 422.442132 -156.014928) (xy 422.442649 -155.989947) (xy 422.450509 -155.940605) (xy 422.465978 -155.893096)
			(xy 422.488677 -155.848585) (xy 422.518048 -155.808166) (xy 422.53535 -155.790138) (xy 422.77284 -155.552648)
			(xy 423.558716 -154.766518) (xy 423.5767 -154.749162) (xy 423.617112 -154.719757) (xy 423.66163 -154.697044)
			(xy 423.709156 -154.681584) (xy 423.758517 -154.673758) (xy 423.783506 -154.6733) (xy 424.056048 -154.6733)
			(xy 426.579792 -152.149556) (xy 426.579792 -148.17852) (xy 425.343828 -146.942556) (xy 415.589466 -146.942556)
			(xy 415.564483 -146.942042) (xy 415.515139 -146.934187) (xy 415.467626 -146.918722) (xy 415.423112 -146.896026)
			(xy 415.382689 -146.866656) (xy 415.364676 -146.849338) (xy 411.074108 -142.558516) (xy 410.41574 -142.558516)
			(xy 410.41574 -147.992846) (xy 410.459936 -147.998688) (xy 410.486624 -148.002724) (xy 410.538448 -148.017802)
			(xy 410.587404 -148.040528) (xy 410.632369 -148.070382) (xy 410.672314 -148.106679) (xy 410.706324 -148.14859)
			(xy 410.733619 -148.195153) (xy 410.753574 -148.245302) (xy 410.765733 -148.297888) (xy 410.769816 -148.351706)
			(xy 410.765731 -148.405525) (xy 410.75357 -148.45811) (xy 410.733613 -148.508259) (xy 410.706316 -148.554821)
			(xy 410.672305 -148.59673) (xy 410.632359 -148.633026) (xy 410.587393 -148.662878) (xy 410.538437 -148.685603)
			(xy 410.486611 -148.700678) (xy 410.459936 -148.704808) (xy 410.41574 -148.71065) (xy 410.41574 -150.423949)
			(xy 420.30348 -150.423949) (xy 420.30348 -150.369451) (xy 420.311235 -150.315508) (xy 420.326587 -150.263217)
			(xy 420.349225 -150.213643) (xy 420.378687 -150.167796) (xy 420.414373 -150.126607) (xy 420.455557 -150.090915)
			(xy 420.501401 -150.061448) (xy 420.550972 -150.038804) (xy 420.603261 -150.023445) (xy 420.657203 -150.015683)
			(xy 420.684452 -150.015194) (xy 420.711821 -150.01569) (xy 420.765999 -150.023501) (xy 420.818502 -150.038983)
			(xy 420.868249 -150.061818) (xy 420.914217 -150.091536) (xy 420.93515 -150.109174) (xy 420.946478 -150.11841)
			(xy 420.973035 -150.130586) (xy 421.001952 -150.134759) (xy 421.030869 -150.130586) (xy 421.057426 -150.11841)
			(xy 421.068754 -150.109174) (xy 421.089687 -150.091533) (xy 421.135655 -150.061809) (xy 421.185401 -150.038963)
			(xy 421.237903 -150.023467) (xy 421.292081 -150.015638) (xy 421.346823 -150.015638) (xy 421.401001 -150.023467)
			(xy 421.453503 -150.038963) (xy 421.503249 -150.061809) (xy 421.549217 -150.091533) (xy 421.57015 -150.109174)
			(xy 421.581478 -150.11841) (xy 421.608035 -150.130586) (xy 421.636952 -150.134759) (xy 421.665869 -150.130586)
			(xy 421.692426 -150.11841) (xy 421.703754 -150.109174) (xy 421.724689 -150.091539) (xy 421.770662 -150.061827)
			(xy 421.820408 -150.038991) (xy 421.872908 -150.023499) (xy 421.927083 -150.015669) (xy 421.954452 -150.015194)
			(xy 421.981707 -150.01565) (xy 422.035664 -150.023402) (xy 422.087968 -150.038753) (xy 422.137554 -150.061393)
			(xy 422.183413 -150.09086) (xy 422.224612 -150.126554) (xy 422.260311 -150.167748) (xy 422.289784 -150.213604)
			(xy 422.31243 -150.263187) (xy 422.327788 -150.315489) (xy 422.335547 -150.369445) (xy 422.335547 -150.423955)
			(xy 422.327788 -150.477911) (xy 422.31243 -150.530213) (xy 422.289784 -150.579796) (xy 422.260311 -150.625652)
			(xy 422.224612 -150.666846) (xy 422.183413 -150.70254) (xy 422.137554 -150.732007) (xy 422.087968 -150.754647)
			(xy 422.035664 -150.769998) (xy 421.981707 -150.77775) (xy 421.954452 -150.77821) (xy 421.927083 -150.777711)
			(xy 421.872905 -150.769901) (xy 421.820403 -150.754419) (xy 421.770655 -150.731585) (xy 421.724687 -150.701868)
			(xy 421.703754 -150.68423) (xy 421.692426 -150.674994) (xy 421.665869 -150.662818) (xy 421.636952 -150.658645)
			(xy 421.608035 -150.662818) (xy 421.581478 -150.674994) (xy 421.57015 -150.68423) (xy 421.549217 -150.701871)
			(xy 421.503249 -150.731595) (xy 421.453503 -150.754441) (xy 421.401001 -150.769937) (xy 421.346823 -150.777766)
			(xy 421.292081 -150.777766) (xy 421.237903 -150.769937) (xy 421.185401 -150.754441) (xy 421.135655 -150.731595)
			(xy 421.089687 -150.701871) (xy 421.068754 -150.68423) (xy 421.057426 -150.674994) (xy 421.030869 -150.662818)
			(xy 421.001952 -150.658645) (xy 420.973035 -150.662818) (xy 420.946478 -150.674994) (xy 420.93515 -150.68423)
			(xy 420.914214 -150.701864) (xy 420.868242 -150.731575) (xy 420.818495 -150.754412) (xy 420.765996 -150.769904)
			(xy 420.711821 -150.777735) (xy 420.684452 -150.77821) (xy 420.657203 -150.777717) (xy 420.603261 -150.769955)
			(xy 420.550972 -150.754596) (xy 420.501401 -150.731952) (xy 420.455557 -150.702485) (xy 420.414373 -150.666793)
			(xy 420.378687 -150.625604) (xy 420.349225 -150.579757) (xy 420.326587 -150.530183) (xy 420.311235 -150.477892)
			(xy 420.30348 -150.423949) (xy 410.41574 -150.423949) (xy 410.41574 -151.116284) (xy 418.675564 -151.116284)
			(xy 418.679635 -151.060662) (xy 418.691761 -151.006225) (xy 418.711684 -150.954134) (xy 418.73898 -150.905499)
			(xy 418.773066 -150.861356) (xy 418.813215 -150.822647) (xy 418.858573 -150.790196) (xy 418.908173 -150.764695)
			(xy 418.960957 -150.746688) (xy 419.0158 -150.736558) (xy 419.071534 -150.734521) (xy 419.126971 -150.740621)
			(xy 419.180928 -150.754727) (xy 419.232257 -150.776539) (xy 419.279863 -150.805593) (xy 419.322731 -150.841268)
			(xy 419.359948 -150.882805) (xy 419.390721 -150.929318) (xy 419.414393 -150.979815) (xy 419.430461 -151.033222)
			(xy 419.438581 -151.088398) (xy 419.43909 -151.116284) (xy 419.439044 -151.118824) (xy 419.681658 -151.118824)
			(xy 419.685729 -151.063202) (xy 419.697855 -151.008765) (xy 419.717778 -150.956674) (xy 419.745074 -150.908039)
			(xy 419.77916 -150.863896) (xy 419.819309 -150.825187) (xy 419.864667 -150.792736) (xy 419.914267 -150.767235)
			(xy 419.967051 -150.749228) (xy 420.021894 -150.739098) (xy 420.077628 -150.737061) (xy 420.133065 -150.743161)
			(xy 420.187022 -150.757267) (xy 420.238351 -150.779079) (xy 420.285957 -150.808133) (xy 420.328825 -150.843808)
			(xy 420.366042 -150.885345) (xy 420.396815 -150.931858) (xy 420.420487 -150.982355) (xy 420.431436 -151.018748)
			(xy 423.976292 -151.018748) (xy 423.976778 -150.991497) (xy 423.984534 -150.937549) (xy 423.999889 -150.885254)
			(xy 424.022531 -150.835677) (xy 424.051997 -150.789827) (xy 424.087688 -150.748636) (xy 424.128879 -150.712945)
			(xy 424.174729 -150.683479) (xy 424.224306 -150.660837) (xy 424.276601 -150.645482) (xy 424.330549 -150.637726)
			(xy 424.385051 -150.637726) (xy 424.438999 -150.645482) (xy 424.491294 -150.660837) (xy 424.540871 -150.683479)
			(xy 424.586721 -150.712945) (xy 424.627912 -150.748636) (xy 424.663603 -150.789827) (xy 424.693069 -150.835677)
			(xy 424.715711 -150.885254) (xy 424.731066 -150.937549) (xy 424.738822 -150.991497) (xy 424.739308 -151.018748)
			(xy 424.739308 -151.019002) (xy 424.739877 -151.034449) (xy 424.749157 -151.063917) (xy 424.766809 -151.089273)
			(xy 424.791224 -151.108204) (xy 424.820177 -151.118986) (xy 424.835574 -151.120348) (xy 424.864452 -151.122457)
			(xy 424.921128 -151.134291) (xy 424.975366 -151.154551) (xy 425.025922 -151.182773) (xy 425.071634 -151.218307)
			(xy 425.111453 -151.26034) (xy 425.144465 -151.307905) (xy 425.169913 -151.359911) (xy 425.187213 -151.415165)
			(xy 425.195968 -151.472399) (xy 425.196508 -151.501348) (xy 425.196022 -151.528599) (xy 425.188266 -151.582547)
			(xy 425.172911 -151.634842) (xy 425.150269 -151.684419) (xy 425.120803 -151.730269) (xy 425.085112 -151.77146)
			(xy 425.043921 -151.807151) (xy 424.998071 -151.836617) (xy 424.948494 -151.859259) (xy 424.896199 -151.874614)
			(xy 424.842251 -151.88237) (xy 424.787749 -151.88237) (xy 424.733801 -151.874614) (xy 424.681506 -151.859259)
			(xy 424.631929 -151.836617) (xy 424.586079 -151.807151) (xy 424.544888 -151.77146) (xy 424.509197 -151.730269)
			(xy 424.479731 -151.684419) (xy 424.457089 -151.634842) (xy 424.441734 -151.582547) (xy 424.433978 -151.528599)
			(xy 424.433492 -151.501348) (xy 424.433492 -151.501094) (xy 424.432927 -151.485647) (xy 424.423646 -151.456178)
			(xy 424.405993 -151.430823) (xy 424.381577 -151.411891) (xy 424.352623 -151.40111) (xy 424.337226 -151.399748)
			(xy 424.308348 -151.397643) (xy 424.251671 -151.385809) (xy 424.197432 -151.365548) (xy 424.146877 -151.337326)
			(xy 424.101165 -151.301791) (xy 424.061346 -151.259758) (xy 424.028333 -151.212193) (xy 424.002885 -151.160186)
			(xy 423.985586 -151.104931) (xy 423.976832 -151.047698) (xy 423.976292 -151.018748) (xy 420.431436 -151.018748)
			(xy 420.436555 -151.035762) (xy 420.444675 -151.090938) (xy 420.445184 -151.118824) (xy 420.444675 -151.14671)
			(xy 420.436555 -151.201886) (xy 420.420487 -151.255293) (xy 420.396815 -151.30579) (xy 420.366042 -151.352303)
			(xy 420.328825 -151.39384) (xy 420.285957 -151.429515) (xy 420.238351 -151.458569) (xy 420.187022 -151.480381)
			(xy 420.133065 -151.494487) (xy 420.077628 -151.500587) (xy 420.021894 -151.49855) (xy 419.967051 -151.48842)
			(xy 419.914267 -151.470413) (xy 419.864667 -151.444912) (xy 419.819309 -151.412461) (xy 419.77916 -151.373752)
			(xy 419.745074 -151.329609) (xy 419.717778 -151.280974) (xy 419.697855 -151.228883) (xy 419.685729 -151.174446)
			(xy 419.681658 -151.118824) (xy 419.439044 -151.118824) (xy 419.438581 -151.14417) (xy 419.430461 -151.199346)
			(xy 419.414393 -151.252753) (xy 419.390721 -151.30325) (xy 419.359948 -151.349763) (xy 419.322731 -151.3913)
			(xy 419.279863 -151.426975) (xy 419.232257 -151.456029) (xy 419.180928 -151.477841) (xy 419.126971 -151.491947)
			(xy 419.071534 -151.498047) (xy 419.0158 -151.49601) (xy 418.960957 -151.48588) (xy 418.908173 -151.467873)
			(xy 418.858573 -151.442372) (xy 418.813215 -151.409921) (xy 418.773066 -151.371212) (xy 418.73898 -151.327069)
			(xy 418.711684 -151.278434) (xy 418.691761 -151.226343) (xy 418.679635 -151.171906) (xy 418.675564 -151.116284)
			(xy 410.41574 -151.116284) (xy 410.41574 -152.03297) (xy 418.678358 -152.03297) (xy 418.682429 -151.977348)
			(xy 418.694555 -151.922911) (xy 418.714478 -151.87082) (xy 418.741774 -151.822185) (xy 418.77586 -151.778042)
			(xy 418.816009 -151.739333) (xy 418.861367 -151.706882) (xy 418.910967 -151.681381) (xy 418.963751 -151.663374)
			(xy 419.018594 -151.653244) (xy 419.074328 -151.651207) (xy 419.129765 -151.657307) (xy 419.183722 -151.671413)
			(xy 419.235051 -151.693225) (xy 419.282657 -151.722279) (xy 419.325525 -151.757954) (xy 419.362742 -151.799491)
			(xy 419.393515 -151.846004) (xy 419.417187 -151.896501) (xy 419.433255 -151.949908) (xy 419.441375 -152.005084)
			(xy 419.441884 -152.03297) (xy 419.441787 -152.038304) (xy 419.676578 -152.038304) (xy 419.680649 -151.982682)
			(xy 419.692775 -151.928245) (xy 419.712698 -151.876154) (xy 419.739994 -151.827519) (xy 419.77408 -151.783376)
			(xy 419.814229 -151.744667) (xy 419.859587 -151.712216) (xy 419.909187 -151.686715) (xy 419.961971 -151.668708)
			(xy 420.016814 -151.658578) (xy 420.072548 -151.656541) (xy 420.127985 -151.662641) (xy 420.181942 -151.676747)
			(xy 420.233271 -151.698559) (xy 420.280877 -151.727613) (xy 420.323745 -151.763288) (xy 420.360962 -151.804825)
			(xy 420.391735 -151.851338) (xy 420.415407 -151.901835) (xy 420.431475 -151.955242) (xy 420.439595 -152.010418)
			(xy 420.440104 -152.038304) (xy 420.439595 -152.06619) (xy 420.431475 -152.121366) (xy 420.415407 -152.174773)
			(xy 420.391735 -152.22527) (xy 420.360962 -152.271783) (xy 420.323745 -152.31332) (xy 420.280877 -152.348995)
			(xy 420.233271 -152.378049) (xy 420.181942 -152.399861) (xy 420.127985 -152.413967) (xy 420.072548 -152.420067)
			(xy 420.016814 -152.41803) (xy 419.961971 -152.4079) (xy 419.909187 -152.389893) (xy 419.859587 -152.364392)
			(xy 419.814229 -152.331941) (xy 419.77408 -152.293232) (xy 419.739994 -152.249089) (xy 419.712698 -152.200454)
			(xy 419.692775 -152.148363) (xy 419.680649 -152.093926) (xy 419.676578 -152.038304) (xy 419.441787 -152.038304)
			(xy 419.441375 -152.060856) (xy 419.433255 -152.116032) (xy 419.417187 -152.169439) (xy 419.393515 -152.219936)
			(xy 419.362742 -152.266449) (xy 419.325525 -152.307986) (xy 419.282657 -152.343661) (xy 419.235051 -152.372715)
			(xy 419.183722 -152.394527) (xy 419.129765 -152.408633) (xy 419.074328 -152.414733) (xy 419.018594 -152.412696)
			(xy 418.963751 -152.402566) (xy 418.910967 -152.384559) (xy 418.861367 -152.359058) (xy 418.816009 -152.326607)
			(xy 418.77586 -152.287898) (xy 418.741774 -152.243755) (xy 418.714478 -152.19512) (xy 418.694555 -152.143029)
			(xy 418.682429 -152.088592) (xy 418.678358 -152.03297) (xy 410.41574 -152.03297) (xy 410.41574 -152.977342)
			(xy 421.425622 -152.977342) (xy 421.429693 -152.92172) (xy 421.441819 -152.867283) (xy 421.461742 -152.815192)
			(xy 421.489038 -152.766557) (xy 421.523124 -152.722414) (xy 421.563273 -152.683705) (xy 421.608631 -152.651254)
			(xy 421.658231 -152.625753) (xy 421.711015 -152.607746) (xy 421.765858 -152.597616) (xy 421.821592 -152.595579)
			(xy 421.877029 -152.601679) (xy 421.930986 -152.615785) (xy 421.982315 -152.637597) (xy 422.029921 -152.666651)
			(xy 422.072789 -152.702326) (xy 422.110006 -152.743863) (xy 422.140779 -152.790376) (xy 422.164451 -152.840873)
			(xy 422.180519 -152.89428) (xy 422.188639 -152.949456) (xy 422.188768 -152.956514) (xy 422.32402 -152.956514)
			(xy 422.328091 -152.900892) (xy 422.340217 -152.846455) (xy 422.36014 -152.794364) (xy 422.387436 -152.745729)
			(xy 422.421522 -152.701586) (xy 422.461671 -152.662877) (xy 422.507029 -152.630426) (xy 422.556629 -152.604925)
			(xy 422.609413 -152.586918) (xy 422.664256 -152.576788) (xy 422.71999 -152.574751) (xy 422.775427 -152.580851)
			(xy 422.829384 -152.594957) (xy 422.880713 -152.616769) (xy 422.928319 -152.645823) (xy 422.971187 -152.681498)
			(xy 423.008404 -152.723035) (xy 423.039177 -152.769548) (xy 423.062849 -152.820045) (xy 423.078917 -152.873452)
			(xy 423.087037 -152.928628) (xy 423.087546 -152.956514) (xy 423.087037 -152.9844) (xy 423.078917 -153.039576)
			(xy 423.062849 -153.092983) (xy 423.039177 -153.14348) (xy 423.008404 -153.189993) (xy 422.971187 -153.23153)
			(xy 422.928319 -153.267205) (xy 422.880713 -153.296259) (xy 422.829384 -153.318071) (xy 422.775427 -153.332177)
			(xy 422.71999 -153.338277) (xy 422.664256 -153.33624) (xy 422.609413 -153.32611) (xy 422.556629 -153.308103)
			(xy 422.507029 -153.282602) (xy 422.461671 -153.250151) (xy 422.421522 -153.211442) (xy 422.387436 -153.167299)
			(xy 422.36014 -153.118664) (xy 422.340217 -153.066573) (xy 422.328091 -153.012136) (xy 422.32402 -152.956514)
			(xy 422.188768 -152.956514) (xy 422.189148 -152.977342) (xy 422.188639 -153.005228) (xy 422.180519 -153.060404)
			(xy 422.164451 -153.113811) (xy 422.140779 -153.164308) (xy 422.110006 -153.210821) (xy 422.072789 -153.252358)
			(xy 422.029921 -153.288033) (xy 421.982315 -153.317087) (xy 421.930986 -153.338899) (xy 421.877029 -153.353005)
			(xy 421.821592 -153.359105) (xy 421.765858 -153.357068) (xy 421.711015 -153.346938) (xy 421.658231 -153.328931)
			(xy 421.608631 -153.30343) (xy 421.563273 -153.270979) (xy 421.523124 -153.23227) (xy 421.489038 -153.188127)
			(xy 421.461742 -153.139492) (xy 421.441819 -153.087401) (xy 421.429693 -153.032964) (xy 421.425622 -152.977342)
			(xy 410.41574 -152.977342) (xy 410.41574 -153.54046) (xy 423.60037 -153.54046) (xy 423.604441 -153.484838)
			(xy 423.616567 -153.430401) (xy 423.63649 -153.37831) (xy 423.663786 -153.329675) (xy 423.697872 -153.285532)
			(xy 423.738021 -153.246823) (xy 423.783379 -153.214372) (xy 423.832979 -153.188871) (xy 423.885763 -153.170864)
			(xy 423.940606 -153.160734) (xy 423.99634 -153.158697) (xy 424.051777 -153.164797) (xy 424.105734 -153.178903)
			(xy 424.157063 -153.200715) (xy 424.204669 -153.229769) (xy 424.247537 -153.265444) (xy 424.284754 -153.306981)
			(xy 424.315527 -153.353494) (xy 424.339199 -153.403991) (xy 424.355267 -153.457398) (xy 424.363387 -153.512574)
			(xy 424.363896 -153.54046) (xy 424.363387 -153.568346) (xy 424.355267 -153.623522) (xy 424.339199 -153.676929)
			(xy 424.315527 -153.727426) (xy 424.284754 -153.773939) (xy 424.247537 -153.815476) (xy 424.204669 -153.851151)
			(xy 424.157063 -153.880205) (xy 424.105734 -153.902017) (xy 424.051777 -153.916123) (xy 423.99634 -153.922223)
			(xy 423.940606 -153.920186) (xy 423.885763 -153.910056) (xy 423.832979 -153.892049) (xy 423.783379 -153.866548)
			(xy 423.738021 -153.834097) (xy 423.697872 -153.795388) (xy 423.663786 -153.751245) (xy 423.63649 -153.70261)
			(xy 423.616567 -153.650519) (xy 423.604441 -153.596082) (xy 423.60037 -153.54046) (xy 410.41574 -153.54046)
			(xy 410.41574 -155.499308) (xy 417.524182 -155.499308) (xy 417.528253 -155.443686) (xy 417.540379 -155.389249)
			(xy 417.560302 -155.337158) (xy 417.587598 -155.288523) (xy 417.621684 -155.24438) (xy 417.661833 -155.205671)
			(xy 417.707191 -155.17322) (xy 417.756791 -155.147719) (xy 417.809575 -155.129712) (xy 417.864418 -155.119582)
			(xy 417.920152 -155.117545) (xy 417.975589 -155.123645) (xy 418.029546 -155.137751) (xy 418.080875 -155.159563)
			(xy 418.128481 -155.188617) (xy 418.162419 -155.21686) (xy 420.484552 -155.21686) (xy 420.488623 -155.161238)
			(xy 420.500749 -155.106801) (xy 420.520672 -155.05471) (xy 420.547968 -155.006075) (xy 420.582054 -154.961932)
			(xy 420.622203 -154.923223) (xy 420.667561 -154.890772) (xy 420.717161 -154.865271) (xy 420.769945 -154.847264)
			(xy 420.824788 -154.837134) (xy 420.880522 -154.835097) (xy 420.935959 -154.841197) (xy 420.989916 -154.855303)
			(xy 421.041245 -154.877115) (xy 421.088851 -154.906169) (xy 421.112505 -154.925854) (xy 421.450453 -154.925854)
			(xy 421.450453 -154.871346) (xy 421.458211 -154.817394) (xy 421.473568 -154.765094) (xy 421.496212 -154.715513)
			(xy 421.525681 -154.669659) (xy 421.561377 -154.628465) (xy 421.602572 -154.592772) (xy 421.648427 -154.563304)
			(xy 421.698009 -154.540662) (xy 421.750309 -154.525307) (xy 421.804262 -154.517552) (xy 421.831516 -154.51709)
			(xy 421.861892 -154.517675) (xy 421.921876 -154.527306) (xy 421.979575 -154.54632) (xy 422.033532 -154.574239)
			(xy 422.082383 -154.610355) (xy 422.104058 -154.631644) (xy 422.113809 -154.640955) (xy 422.137082 -154.65455)
			(xy 422.163099 -154.661592) (xy 422.190051 -154.661592) (xy 422.216068 -154.65455) (xy 422.239341 -154.640955)
			(xy 422.249092 -154.631644) (xy 422.270748 -154.610335) (xy 422.319604 -154.574222) (xy 422.373566 -154.546308)
			(xy 422.43127 -154.527299) (xy 422.491257 -154.517676) (xy 422.521634 -154.51709) (xy 422.548884 -154.517582)
			(xy 422.602827 -154.525342) (xy 422.655118 -154.5407) (xy 422.70469 -154.563343) (xy 422.750536 -154.592811)
			(xy 422.791722 -154.628502) (xy 422.82741 -154.669691) (xy 422.856873 -154.71554) (xy 422.879511 -154.765114)
			(xy 422.894865 -154.817406) (xy 422.90262 -154.87135) (xy 422.90262 -154.92585) (xy 422.894865 -154.979794)
			(xy 422.879511 -155.032086) (xy 422.856873 -155.08166) (xy 422.82741 -155.127509) (xy 422.791722 -155.168698)
			(xy 422.750536 -155.204389) (xy 422.70469 -155.233857) (xy 422.655118 -155.2565) (xy 422.602827 -155.271858)
			(xy 422.548884 -155.279618) (xy 422.521634 -155.280106) (xy 422.491257 -155.279554) (xy 422.431272 -155.269915)
			(xy 422.373572 -155.250893) (xy 422.319615 -155.222967) (xy 422.270766 -155.186844) (xy 422.249092 -155.165552)
			(xy 422.239364 -155.156194) (xy 422.216103 -155.142518) (xy 422.190067 -155.135431) (xy 422.163083 -155.135431)
			(xy 422.137047 -155.142518) (xy 422.113786 -155.156194) (xy 422.104058 -155.165552) (xy 422.082379 -155.186837)
			(xy 422.033529 -155.222953) (xy 421.979573 -155.250871) (xy 421.921874 -155.269886) (xy 421.861891 -155.279516)
			(xy 421.831516 -155.280106) (xy 421.804262 -155.279648) (xy 421.750309 -155.271893) (xy 421.698009 -155.256538)
			(xy 421.648427 -155.233896) (xy 421.602572 -155.204428) (xy 421.561377 -155.168735) (xy 421.525681 -155.127541)
			(xy 421.496212 -155.081687) (xy 421.473568 -155.032106) (xy 421.458211 -154.979806) (xy 421.450453 -154.925854)
			(xy 421.112505 -154.925854) (xy 421.131719 -154.941844) (xy 421.168936 -154.983381) (xy 421.199709 -155.029894)
			(xy 421.223381 -155.080391) (xy 421.239449 -155.133798) (xy 421.247569 -155.188974) (xy 421.248078 -155.21686)
			(xy 421.247569 -155.244746) (xy 421.239449 -155.299922) (xy 421.223381 -155.353329) (xy 421.199709 -155.403826)
			(xy 421.168936 -155.450339) (xy 421.131719 -155.491876) (xy 421.088851 -155.527551) (xy 421.041245 -155.556605)
			(xy 420.989916 -155.578417) (xy 420.935959 -155.592523) (xy 420.880522 -155.598623) (xy 420.824788 -155.596586)
			(xy 420.769945 -155.586456) (xy 420.717161 -155.568449) (xy 420.667561 -155.542948) (xy 420.622203 -155.510497)
			(xy 420.582054 -155.471788) (xy 420.547968 -155.427645) (xy 420.520672 -155.37901) (xy 420.500749 -155.326919)
			(xy 420.488623 -155.272482) (xy 420.484552 -155.21686) (xy 418.162419 -155.21686) (xy 418.171349 -155.224292)
			(xy 418.208566 -155.265829) (xy 418.239339 -155.312342) (xy 418.263011 -155.362839) (xy 418.279079 -155.416246)
			(xy 418.287199 -155.471422) (xy 418.287708 -155.499308) (xy 418.287199 -155.527194) (xy 418.279079 -155.58237)
			(xy 418.263011 -155.635777) (xy 418.239339 -155.686274) (xy 418.208566 -155.732787) (xy 418.171349 -155.774324)
			(xy 418.128481 -155.809999) (xy 418.080875 -155.839053) (xy 418.029546 -155.860865) (xy 417.975589 -155.874971)
			(xy 417.920152 -155.881071) (xy 417.864418 -155.879034) (xy 417.809575 -155.868904) (xy 417.756791 -155.850897)
			(xy 417.707191 -155.825396) (xy 417.661833 -155.792945) (xy 417.621684 -155.754236) (xy 417.587598 -155.710093)
			(xy 417.560302 -155.661458) (xy 417.540379 -155.609367) (xy 417.528253 -155.55493) (xy 417.524182 -155.499308)
			(xy 410.41574 -155.499308) (xy 410.41574 -157.648148) (xy 419.535862 -157.648148) (xy 419.539933 -157.592526)
			(xy 419.552059 -157.538089) (xy 419.571982 -157.485998) (xy 419.599278 -157.437363) (xy 419.633364 -157.39322)
			(xy 419.673513 -157.354511) (xy 419.718871 -157.32206) (xy 419.768471 -157.296559) (xy 419.821255 -157.278552)
			(xy 419.876098 -157.268422) (xy 419.931832 -157.266385) (xy 419.987269 -157.272485) (xy 420.041226 -157.286591)
			(xy 420.092555 -157.308403) (xy 420.140161 -157.337457) (xy 420.183029 -157.373132) (xy 420.220246 -157.414669)
			(xy 420.251019 -157.461182) (xy 420.274691 -157.511679) (xy 420.290759 -157.565086) (xy 420.298879 -157.620262)
			(xy 420.299388 -157.648148) (xy 420.298879 -157.676034) (xy 420.290759 -157.73121) (xy 420.274691 -157.784617)
			(xy 420.251019 -157.835114) (xy 420.220246 -157.881627) (xy 420.183029 -157.923164) (xy 420.140161 -157.958839)
			(xy 420.092555 -157.987893) (xy 420.041226 -158.009705) (xy 419.987269 -158.023811) (xy 419.931832 -158.029911)
			(xy 419.876098 -158.027874) (xy 419.821255 -158.017744) (xy 419.768471 -157.999737) (xy 419.718871 -157.974236)
			(xy 419.673513 -157.941785) (xy 419.633364 -157.903076) (xy 419.599278 -157.858933) (xy 419.571982 -157.810298)
			(xy 419.552059 -157.758207) (xy 419.539933 -157.70377) (xy 419.535862 -157.648148) (xy 410.41574 -157.648148)
			(xy 410.41574 -161.520378) (xy 417.4998 -161.520378) (xy 417.500317 -161.493048) (xy 417.50828 -161.438971)
			(xy 417.524061 -161.386638) (xy 417.547322 -161.337175) (xy 417.577563 -161.291642) (xy 417.614133 -161.251018)
			(xy 417.656249 -161.216176) (xy 417.679378 -161.201608) (xy 417.691578 -161.19365) (xy 417.711251 -161.172189)
			(xy 417.724061 -161.146045) (xy 417.728962 -161.117347) (xy 417.725556 -161.088434) (xy 417.720272 -161.074862)
			(xy 417.710777 -161.051654) (xy 417.697428 -161.00332) (xy 417.690702 -160.95363) (xy 417.6903 -160.928558)
			(xy 417.690724 -160.903489) (xy 417.697474 -160.853806) (xy 417.710806 -160.805471) (xy 417.720272 -160.782254)
			(xy 417.725563 -160.768687) (xy 417.728937 -160.739773) (xy 417.724027 -160.711079) (xy 417.711231 -160.68493)
			(xy 417.691587 -160.663447) (xy 417.679378 -160.655508) (xy 417.656281 -160.640887) (xy 417.61416 -160.60605)
			(xy 417.57758 -160.565433) (xy 417.547327 -160.519907) (xy 417.52405 -160.470451) (xy 417.508247 -160.418124)
			(xy 417.500259 -160.36405) (xy 417.500256 -160.309389) (xy 417.508238 -160.255314) (xy 417.524036 -160.202986)
			(xy 417.547308 -160.153527) (xy 417.577556 -160.107998) (xy 417.614131 -160.067377) (xy 417.656249 -160.032536)
			(xy 417.679378 -160.017968) (xy 417.691605 -160.010048) (xy 417.711279 -159.988577) (xy 417.724084 -159.962423)
			(xy 417.728979 -159.933716) (xy 417.725563 -159.904796) (xy 417.720272 -159.891222) (xy 417.710796 -159.868007)
			(xy 417.69744 -159.819677) (xy 417.690706 -159.769989) (xy 417.6903 -159.744918) (xy 417.690766 -159.718075)
			(xy 417.698468 -159.664945) (xy 417.713716 -159.61347) (xy 417.736193 -159.564717) (xy 417.765435 -159.519694)
			(xy 417.800836 -159.479334) (xy 417.841662 -159.444472) (xy 417.887069 -159.415831) (xy 417.936117 -159.394002)
			(xy 417.961826 -159.38627) (xy 417.976329 -159.38162) (xy 418.0019 -159.365103) (xy 418.021469 -159.341785)
			(xy 418.033299 -159.313737) (xy 418.03634 -159.283448) (xy 418.030322 -159.253608) (xy 418.023548 -159.239966)
			(xy 418.00892 -159.211818) (xy 417.988191 -159.151868) (xy 417.977691 -159.08931) (xy 417.977066 -159.057594)
			(xy 417.977291 -159.039575) (xy 417.980722 -159.0037) (xy 417.983924 -158.985966) (xy 417.986322 -158.970764)
			(xy 417.982784 -158.940201) (xy 417.97031 -158.912077) (xy 417.95003 -158.888941) (xy 417.923782 -158.872889)
			(xy 417.908994 -158.868618) (xy 417.881967 -158.861164) (xy 417.830242 -158.839542) (xy 417.782237 -158.810585)
			(xy 417.738984 -158.774917) (xy 417.701416 -158.733305) (xy 417.670339 -158.686645) (xy 417.646423 -158.63594)
			(xy 417.630183 -158.582282) (xy 417.621967 -158.526825) (xy 417.621466 -158.498794) (xy 417.621972 -158.471544)
			(xy 417.629729 -158.417598) (xy 417.645083 -158.365305) (xy 417.667723 -158.31573) (xy 417.697188 -158.269881)
			(xy 417.732877 -158.228691) (xy 417.774065 -158.193) (xy 417.819912 -158.163533) (xy 417.869487 -158.14089)
			(xy 417.921779 -158.125533) (xy 417.975724 -158.117774) (xy 418.002974 -158.117286) (xy 418.030548 -158.117774)
			(xy 418.085119 -158.125723) (xy 418.137979 -158.141444) (xy 418.188024 -158.16461) (xy 418.234215 -158.194738)
			(xy 418.275587 -158.231201) (xy 418.293804 -158.251906) (xy 418.303702 -158.262804) (xy 418.328352 -158.278879)
			(xy 418.35656 -158.287263) (xy 418.385988 -158.287263) (xy 418.414196 -158.278879) (xy 418.438846 -158.262804)
			(xy 418.448744 -158.251906) (xy 418.466959 -158.2312) (xy 418.50833 -158.194735) (xy 418.55452 -158.164608)
			(xy 418.604567 -158.141445) (xy 418.657428 -158.125729) (xy 418.712 -158.117789) (xy 418.767148 -158.117789)
			(xy 418.82172 -158.125729) (xy 418.874581 -158.141445) (xy 418.924628 -158.164608) (xy 418.970818 -158.194735)
			(xy 419.012189 -158.2312) (xy 419.030404 -158.251906) (xy 419.040302 -158.262804) (xy 419.064952 -158.278879)
			(xy 419.09316 -158.287263) (xy 419.122588 -158.287263) (xy 419.150796 -158.278879) (xy 419.175446 -158.262804)
			(xy 419.185344 -158.251906) (xy 419.203582 -158.23122) (xy 419.244945 -158.194747) (xy 419.291129 -158.164612)
			(xy 419.341172 -158.141442) (xy 419.39403 -158.12572) (xy 419.448601 -158.117775) (xy 419.476174 -158.117286)
			(xy 419.503426 -158.117779) (xy 419.557375 -158.125533) (xy 419.609672 -158.140885) (xy 419.659252 -158.163524)
			(xy 419.705105 -158.192989) (xy 419.746298 -158.22868) (xy 419.781992 -158.269869) (xy 419.81146 -158.31572)
			(xy 419.834104 -158.365298) (xy 419.84946 -158.417593) (xy 419.857218 -158.471542) (xy 419.857682 -158.498794)
			(xy 419.857167 -158.52665) (xy 419.849043 -158.581766) (xy 419.832998 -158.635117) (xy 419.80937 -158.685571)
			(xy 419.778663 -158.732056) (xy 419.741526 -158.773585) (xy 419.69875 -158.809278) (xy 419.651241 -158.838376)
			(xy 419.600008 -158.860262) (xy 419.573202 -158.867856) (xy 419.559077 -158.872105) (xy 419.53393 -158.887501)
			(xy 419.514215 -158.909425) (xy 419.501566 -158.93606) (xy 419.497034 -158.965195) (xy 419.498526 -158.97987)
			(xy 419.5002 -158.992886) (xy 419.501977 -159.019071) (xy 419.502082 -159.032194) (xy 419.501988 -159.046343)
			(xy 419.499954 -159.074566) (xy 419.498018 -159.088582) (xy 419.496394 -159.101927) (xy 419.4995 -159.128623)
			(xy 419.509476 -159.153579) (xy 419.525629 -159.17506) (xy 419.546835 -159.191572) (xy 419.57162 -159.201966)
			(xy 419.584886 -159.204152) (xy 419.612039 -159.208237) (xy 419.664868 -159.223214) (xy 419.715004 -159.245609)
			(xy 419.761412 -159.274958) (xy 419.803135 -159.310656) (xy 419.839311 -159.351965) (xy 419.869192 -159.398033)
			(xy 419.892162 -159.447908) (xy 419.907746 -159.500561) (xy 419.915622 -159.554903) (xy 419.916102 -159.582358)
			(xy 419.915606 -159.60961) (xy 419.907854 -159.66356) (xy 419.892503 -159.715858) (xy 419.869865 -159.765438)
			(xy 419.840401 -159.811292) (xy 419.804711 -159.852485) (xy 419.763521 -159.888179) (xy 419.71767 -159.917648)
			(xy 419.668092 -159.940291) (xy 419.615795 -159.955647) (xy 419.561846 -159.963403) (xy 419.534594 -159.963866)
			(xy 419.507019 -159.963416) (xy 419.452445 -159.955462) (xy 419.399584 -159.939735) (xy 419.349538 -159.916562)
			(xy 419.303349 -159.886426) (xy 419.261979 -159.849955) (xy 419.243764 -159.829246) (xy 419.233866 -159.818348)
			(xy 419.209216 -159.802273) (xy 419.181008 -159.793889) (xy 419.15158 -159.793889) (xy 419.123372 -159.802273)
			(xy 419.098722 -159.818348) (xy 419.088824 -159.829246) (xy 419.070614 -159.849958) (xy 419.029244 -159.886426)
			(xy 418.983053 -159.916557) (xy 418.933005 -159.939722) (xy 418.880143 -159.955439) (xy 418.825569 -159.96338)
			(xy 418.797994 -159.963866) (xy 418.771493 -159.963405) (xy 418.719002 -159.956063) (xy 418.668034 -159.941521)
			(xy 418.619572 -159.920059) (xy 418.574549 -159.892091) (xy 418.5539 -159.875474) (xy 418.541717 -159.866082)
			(xy 418.51333 -159.854285) (xy 418.482719 -159.851451) (xy 418.452648 -159.857838) (xy 418.425831 -159.872868)
			(xy 418.404689 -159.895186) (xy 418.397436 -159.908748) (xy 418.385321 -159.93243) (xy 418.355402 -159.976413)
			(xy 418.319535 -160.015696) (xy 418.278448 -160.049482) (xy 418.255958 -160.063688) (xy 418.243751 -160.071635)
			(xy 418.224085 -160.093102) (xy 418.211281 -160.119249) (xy 418.206381 -160.147947) (xy 418.209783 -160.176861)
			(xy 418.215064 -160.190434) (xy 418.22456 -160.213641) (xy 418.237908 -160.261976) (xy 418.244633 -160.311666)
			(xy 418.245036 -160.336738) (xy 418.244615 -160.361807) (xy 418.237865 -160.411491) (xy 418.224531 -160.459825)
			(xy 418.215064 -160.483042) (xy 418.209854 -160.496631) (xy 418.206485 -160.525525) (xy 418.211389 -160.554198)
			(xy 418.224168 -160.58033) (xy 418.243789 -160.601805) (xy 418.255958 -160.609788) (xy 418.27905 -160.624416)
			(xy 418.321167 -160.659255) (xy 418.357742 -160.699872) (xy 418.387993 -160.745397) (xy 418.411268 -160.794852)
			(xy 418.427069 -160.847177) (xy 418.435057 -160.901249) (xy 418.43506 -160.955908) (xy 418.427078 -161.00998)
			(xy 418.411283 -161.062307) (xy 418.388014 -161.111765) (xy 418.357769 -161.157294) (xy 418.321198 -161.197915)
			(xy 418.279085 -161.232759) (xy 418.255958 -161.247328) (xy 418.243724 -161.255237) (xy 418.224058 -161.276714)
			(xy 418.211257 -161.302871) (xy 418.206364 -161.331578) (xy 418.209777 -161.360499) (xy 418.215064 -161.374074)
			(xy 418.224541 -161.397289) (xy 418.237896 -161.445619) (xy 418.244629 -161.495307) (xy 418.245036 -161.520378)
			(xy 418.244515 -161.548263) (xy 418.236203 -161.60341) (xy 418.219765 -161.656702) (xy 418.195567 -161.706948)
			(xy 418.164151 -161.753027) (xy 418.126218 -161.793909) (xy 418.082616 -161.828681) (xy 418.034318 -161.856566)
			(xy 417.982403 -161.876941) (xy 417.928032 -161.889351) (xy 417.872418 -161.893519) (xy 417.816804 -161.889351)
			(xy 417.762433 -161.876941) (xy 417.710518 -161.856566) (xy 417.66222 -161.828681) (xy 417.618618 -161.793909)
			(xy 417.580685 -161.753027) (xy 417.549269 -161.706948) (xy 417.525071 -161.656702) (xy 417.508633 -161.60341)
			(xy 417.500321 -161.548263) (xy 417.4998 -161.520378) (xy 410.41574 -161.520378) (xy 410.41574 -162.451542)
			(xy 419.315646 -162.451542) (xy 419.316217 -162.424294) (xy 419.323967 -162.370352) (xy 419.339314 -162.318061)
			(xy 419.361947 -162.268487) (xy 419.391405 -162.222639) (xy 419.427087 -162.18145) (xy 419.468269 -162.145757)
			(xy 419.51411 -162.116289) (xy 419.563679 -162.093645) (xy 419.615966 -162.078285) (xy 419.669906 -162.070523)
			(xy 419.697154 -162.070034) (xy 419.697408 -162.070034) (xy 419.727247 -162.070617) (xy 419.786193 -162.079927)
			(xy 419.814756 -162.088576) (xy 419.82866 -162.09263) (xy 419.857597 -162.09354) (xy 419.885621 -162.086274)
			(xy 419.910469 -162.071418) (xy 419.930134 -162.050171) (xy 419.943028 -162.024251) (xy 419.946074 -162.01009)
			(xy 419.951204 -161.984008) (xy 419.967775 -161.933501) (xy 419.991201 -161.885784) (xy 420.021027 -161.841784)
			(xy 420.056674 -161.802352) (xy 420.097452 -161.768253) (xy 420.142571 -161.740148) (xy 420.191156 -161.718581)
			(xy 420.242265 -161.703971) (xy 420.294908 -161.696601) (xy 420.321486 -161.696146) (xy 420.348736 -161.6967)
			(xy 420.402682 -161.704455) (xy 420.454975 -161.719808) (xy 420.504551 -161.742447) (xy 420.550401 -161.771911)
			(xy 420.59159 -161.8076) (xy 420.627281 -161.848788) (xy 420.656747 -161.894636) (xy 420.679387 -161.944211)
			(xy 420.694742 -161.996504) (xy 420.702499 -162.05045) (xy 420.702499 -162.10495) (xy 420.694742 -162.158896)
			(xy 420.679387 -162.211189) (xy 420.656747 -162.260764) (xy 420.627281 -162.306612) (xy 420.59159 -162.3478)
			(xy 420.550401 -162.383489) (xy 420.504551 -162.412953) (xy 420.454975 -162.435592) (xy 420.402682 -162.450945)
			(xy 420.348736 -162.4587) (xy 420.321486 -162.459162) (xy 420.321232 -162.459162) (xy 420.291393 -162.458593)
			(xy 420.232447 -162.449273) (xy 420.203884 -162.44062) (xy 420.189967 -162.436614) (xy 420.161038 -162.435695)
			(xy 420.133019 -162.442952) (xy 420.108173 -162.457799) (xy 420.088508 -162.479036) (xy 420.075613 -162.504949)
			(xy 420.072566 -162.519106) (xy 420.06599 -162.551947) (xy 420.042863 -162.614798) (xy 420.026592 -162.644074)
			(xy 420.019587 -162.657057) (xy 420.012541 -162.685688) (xy 420.013975 -162.715137) (xy 420.023771 -162.742948)
			(xy 420.04111 -162.766795) (xy 420.064544 -162.78469) (xy 420.078154 -162.790378) (xy 420.104942 -162.801047)
			(xy 420.155182 -162.829341) (xy 420.20059 -162.864876) (xy 420.240131 -162.906842) (xy 420.272903 -162.954283)
			(xy 420.298159 -163.006117) (xy 420.315323 -163.061162) (xy 420.324005 -163.118164) (xy 420.324534 -163.146994)
			(xy 420.324048 -163.174245) (xy 420.316292 -163.228193) (xy 420.300937 -163.280488) (xy 420.278295 -163.330065)
			(xy 420.248829 -163.375915) (xy 420.213138 -163.417106) (xy 420.171947 -163.452797) (xy 420.126097 -163.482263)
			(xy 420.07652 -163.504905) (xy 420.024225 -163.52026) (xy 419.970277 -163.528016) (xy 419.915775 -163.528016)
			(xy 419.861827 -163.52026) (xy 419.809532 -163.504905) (xy 419.759955 -163.482263) (xy 419.714105 -163.452797)
			(xy 419.672914 -163.417106) (xy 419.637223 -163.375915) (xy 419.607757 -163.330065) (xy 419.585115 -163.280488)
			(xy 419.56976 -163.228193) (xy 419.562004 -163.174245) (xy 419.561518 -163.146994) (xy 419.561518 -163.14674)
			(xy 419.561938 -163.121537) (xy 419.568572 -163.07157) (xy 419.581743 -163.022915) (xy 419.601219 -162.976425)
			(xy 419.613588 -162.954462) (xy 419.620627 -162.941499) (xy 419.627653 -162.912862) (xy 419.626205 -162.883412)
			(xy 419.616403 -162.855603) (xy 419.599064 -162.831754) (xy 419.575634 -162.813852) (xy 419.562026 -162.808158)
			(xy 419.535269 -162.797416) (xy 419.485027 -162.769136) (xy 419.439617 -162.733613) (xy 419.400072 -162.691658)
			(xy 419.367296 -162.644228) (xy 419.342035 -162.592402) (xy 419.324865 -162.537365) (xy 419.316178 -162.480369)
			(xy 419.315646 -162.451542) (xy 410.41574 -162.451542) (xy 410.41574 -164.7698) (xy 410.452824 -164.780214)
			(xy 410.478928 -164.788017) (xy 410.528576 -164.810447) (xy 410.574231 -164.840175) (xy 410.614826 -164.876509)
			(xy 410.649416 -164.9186) (xy 410.663258 -164.941953) (xy 418.557175 -164.941953) (xy 418.564931 -164.888006)
			(xy 418.580286 -164.835711) (xy 418.602926 -164.786133) (xy 418.632392 -164.740282) (xy 418.668083 -164.699091)
			(xy 418.709272 -164.663399) (xy 418.755122 -164.633932) (xy 418.804699 -164.61129) (xy 418.856994 -164.595934)
			(xy 418.910941 -164.588176) (xy 418.965444 -164.588175) (xy 419.019392 -164.595931) (xy 419.071687 -164.611285)
			(xy 419.121265 -164.633925) (xy 419.167116 -164.66339) (xy 419.208307 -164.699081) (xy 419.243999 -164.74027)
			(xy 419.273467 -164.78612) (xy 419.296109 -164.835697) (xy 419.311466 -164.887991) (xy 419.319224 -164.941939)
			(xy 419.31971 -164.96919) (xy 419.319282 -164.994581) (xy 419.312524 -165.044913) (xy 419.306248 -165.06952)
			(xy 419.302808 -165.084167) (xy 419.303729 -165.114225) (xy 419.31336 -165.142715) (xy 419.330866 -165.167167)
			(xy 419.354731 -165.185465) (xy 419.38289 -165.196023) (xy 419.412902 -165.197929) (xy 419.42766 -165.194996)
			(xy 419.449192 -165.190248) (xy 419.492989 -165.185151) (xy 419.515036 -165.184836) (xy 419.51529 -165.184836)
			(xy 419.542541 -165.185267) (xy 419.59649 -165.193022) (xy 419.648785 -165.208376) (xy 419.698364 -165.231015)
			(xy 419.744216 -165.26048) (xy 419.785408 -165.29617) (xy 419.821101 -165.337359) (xy 419.85057 -165.383209)
			(xy 419.873213 -165.432785) (xy 419.888571 -165.48508) (xy 419.896331 -165.539027) (xy 419.896334 -165.59353)
			(xy 419.88858 -165.647479) (xy 419.873228 -165.699775) (xy 419.85059 -165.749354) (xy 419.821127 -165.795207)
			(xy 419.785438 -165.8364) (xy 419.74425 -165.872094) (xy 419.698401 -165.901564) (xy 419.648825 -165.924209)
			(xy 419.596532 -165.939569) (xy 419.542584 -165.94733) (xy 419.488081 -165.947335) (xy 419.434132 -165.939583)
			(xy 419.381836 -165.924232) (xy 419.332256 -165.901596) (xy 419.286403 -165.872134) (xy 419.245208 -165.836446)
			(xy 419.209512 -165.795259) (xy 419.180041 -165.749411) (xy 419.157395 -165.699836) (xy 419.142034 -165.647543)
			(xy 419.134271 -165.593595) (xy 419.133782 -165.566344) (xy 419.134216 -165.540953) (xy 419.14097 -165.490622)
			(xy 419.147244 -165.466014) (xy 419.150657 -165.451361) (xy 419.149744 -165.421304) (xy 419.14012 -165.392815)
			(xy 419.122618 -165.368362) (xy 419.098755 -165.350064) (xy 419.070599 -165.339507) (xy 419.040588 -165.337604)
			(xy 419.025832 -165.340538) (xy 419.0043 -165.345286) (xy 418.960503 -165.350383) (xy 418.938456 -165.350698)
			(xy 418.938202 -165.350698) (xy 418.910951 -165.350224) (xy 418.857003 -165.342468) (xy 418.804708 -165.327113)
			(xy 418.755131 -165.304473) (xy 418.70928 -165.275007) (xy 418.668089 -165.239315) (xy 418.632397 -165.198125)
			(xy 418.602931 -165.152275) (xy 418.580289 -165.102698) (xy 418.564933 -165.050404) (xy 418.557176 -164.996456)
			(xy 418.557175 -164.941953) (xy 410.663258 -164.941953) (xy 410.677194 -164.965466) (xy 410.697511 -165.016016)
			(xy 410.709895 -165.06907) (xy 410.714056 -165.123391) (xy 410.709898 -165.177713) (xy 410.697517 -165.230767)
			(xy 410.677201 -165.281318) (xy 410.649426 -165.328186) (xy 410.614838 -165.370279) (xy 410.574244 -165.406614)
			(xy 410.528591 -165.436345) (xy 410.478944 -165.458777) (xy 410.452824 -165.466522) (xy 410.41574 -165.476936)
			(xy 410.41574 -165.787957) (xy 416.453709 -165.787957) (xy 416.453709 -165.733443) (xy 416.461468 -165.679483)
			(xy 416.476827 -165.627176) (xy 416.499474 -165.577588) (xy 416.528948 -165.531728) (xy 416.56465 -165.49053)
			(xy 416.605851 -165.454832) (xy 416.651713 -165.425361) (xy 416.701302 -165.402717) (xy 416.75361 -165.387362)
			(xy 416.807571 -165.379607) (xy 416.834828 -165.379146) (xy 416.862199 -165.379584) (xy 416.91638 -165.387407)
			(xy 416.968884 -165.402902) (xy 417.01863 -165.42575) (xy 417.064596 -165.455481) (xy 417.085526 -165.473126)
			(xy 417.096854 -165.482362) (xy 417.123411 -165.494538) (xy 417.152328 -165.498711) (xy 417.181245 -165.494538)
			(xy 417.207802 -165.482362) (xy 417.21913 -165.473126) (xy 417.240081 -165.45551) (xy 417.286048 -165.425794)
			(xy 417.335791 -165.402953) (xy 417.388287 -165.387457) (xy 417.44246 -165.379623) (xy 417.469828 -165.379146)
			(xy 417.497075 -165.379726) (xy 417.551013 -165.387485) (xy 417.603298 -165.402841) (xy 417.652865 -165.425481)
			(xy 417.698707 -165.454944) (xy 417.739889 -165.490631) (xy 417.775573 -165.531816) (xy 417.805033 -165.577659)
			(xy 417.827669 -165.627228) (xy 417.843021 -165.679515) (xy 417.850776 -165.733453) (xy 417.850776 -165.787947)
			(xy 417.843021 -165.841885) (xy 417.827669 -165.894172) (xy 417.805033 -165.943741) (xy 417.775573 -165.989584)
			(xy 417.739889 -166.030769) (xy 417.698707 -166.066456) (xy 417.652865 -166.095919) (xy 417.603298 -166.118559)
			(xy 417.551013 -166.133915) (xy 417.497075 -166.141674) (xy 417.469828 -166.142162) (xy 417.442458 -166.141689)
			(xy 417.388279 -166.133874) (xy 417.335775 -166.118387) (xy 417.286028 -166.095547) (xy 417.240062 -166.065823)
			(xy 417.21913 -166.048182) (xy 417.207802 -166.038946) (xy 417.181245 -166.02677) (xy 417.152328 -166.022597)
			(xy 417.123411 -166.02677) (xy 417.096854 -166.038946) (xy 417.085526 -166.048182) (xy 417.064593 -166.06582)
			(xy 417.01862 -166.095532) (xy 416.968873 -166.118369) (xy 416.916373 -166.13386) (xy 416.862197 -166.141688)
			(xy 416.834828 -166.142162) (xy 416.807571 -166.141793) (xy 416.75361 -166.134038) (xy 416.701302 -166.118683)
			(xy 416.651713 -166.096039) (xy 416.605851 -166.066568) (xy 416.56465 -166.03087) (xy 416.528948 -165.989672)
			(xy 416.499474 -165.943812) (xy 416.476827 -165.894224) (xy 416.461468 -165.841917) (xy 416.453709 -165.787957)
			(xy 410.41574 -165.787957) (xy 410.41574 -166.71798) (xy 410.452824 -166.728394) (xy 410.477484 -166.735725)
			(xy 410.524547 -166.756504) (xy 410.56813 -166.78384) (xy 410.607324 -166.817164) (xy 410.641314 -166.855782)
			(xy 410.669391 -166.89889) (xy 410.690972 -166.945591) (xy 410.705606 -166.994912) (xy 410.71299 -167.045825)
			(xy 410.713428 -167.071548) (xy 410.712852 -167.100576) (xy 410.70343 -167.157861) (xy 410.684844 -167.212861)
			(xy 410.657586 -167.264119) (xy 410.622377 -167.310278) (xy 410.601668 -167.330628) (xy 410.592769 -167.34031)
			(xy 410.579793 -167.363172) (xy 410.573087 -167.38859) (xy 410.573096 -167.414878) (xy 410.579819 -167.440292)
			(xy 410.592811 -167.463145) (xy 410.601668 -167.472868) (xy 410.622395 -167.493202) (xy 410.657613 -167.53936)
			(xy 410.684874 -167.590621) (xy 410.703458 -167.645627) (xy 410.71287 -167.702918) (xy 410.713428 -167.731948)
			(xy 410.713332 -167.744691) (xy 410.711554 -167.770116) (xy 410.709872 -167.782748) (xy 410.705747 -167.808171)
			(xy 410.691131 -167.857556) (xy 410.669555 -167.904321) (xy 410.64147 -167.947491) (xy 410.60746 -167.986168)
			(xy 410.568236 -168.019543) (xy 410.524613 -168.046921) (xy 410.477503 -168.067733) (xy 410.452824 -168.075102)
			(xy 410.41574 -168.085516) (xy 410.41574 -170.156378) (xy 417.4998 -170.156378) (xy 417.500317 -170.129048)
			(xy 417.50828 -170.074971) (xy 417.524061 -170.022638) (xy 417.547322 -169.973175) (xy 417.577563 -169.927642)
			(xy 417.614133 -169.887018) (xy 417.656249 -169.852176) (xy 417.679378 -169.837608) (xy 417.691578 -169.82965)
			(xy 417.711251 -169.808189) (xy 417.724061 -169.782045) (xy 417.728962 -169.753347) (xy 417.725556 -169.724434)
			(xy 417.720272 -169.710862) (xy 417.710777 -169.687654) (xy 417.697428 -169.63932) (xy 417.690702 -169.58963)
			(xy 417.6903 -169.564558) (xy 417.690724 -169.539489) (xy 417.697474 -169.489806) (xy 417.710806 -169.441471)
			(xy 417.720272 -169.418254) (xy 417.725563 -169.404687) (xy 417.728937 -169.375773) (xy 417.724027 -169.347079)
			(xy 417.711231 -169.32093) (xy 417.691587 -169.299447) (xy 417.679378 -169.291508) (xy 417.656281 -169.276887)
			(xy 417.61416 -169.24205) (xy 417.57758 -169.201433) (xy 417.547327 -169.155907) (xy 417.52405 -169.106451)
			(xy 417.508247 -169.054124) (xy 417.500259 -169.00005) (xy 417.500256 -168.945389) (xy 417.508238 -168.891314)
			(xy 417.524036 -168.838986) (xy 417.547308 -168.789527) (xy 417.577556 -168.743998) (xy 417.614131 -168.703377)
			(xy 417.656249 -168.668536) (xy 417.679378 -168.653968) (xy 417.691605 -168.646048) (xy 417.711279 -168.624577)
			(xy 417.724084 -168.598423) (xy 417.728979 -168.569716) (xy 417.725563 -168.540796) (xy 417.720272 -168.527222)
			(xy 417.710796 -168.504007) (xy 417.69744 -168.455677) (xy 417.690706 -168.405989) (xy 417.6903 -168.380918)
			(xy 417.690766 -168.354075) (xy 417.698468 -168.300945) (xy 417.713716 -168.24947) (xy 417.736193 -168.200717)
			(xy 417.765435 -168.155694) (xy 417.800836 -168.115334) (xy 417.841662 -168.080472) (xy 417.887069 -168.051831)
			(xy 417.936117 -168.030002) (xy 417.961826 -168.02227) (xy 417.976329 -168.01762) (xy 418.0019 -168.001103)
			(xy 418.021469 -167.977785) (xy 418.033299 -167.949737) (xy 418.03634 -167.919448) (xy 418.030322 -167.889608)
			(xy 418.023548 -167.875966) (xy 418.00892 -167.847818) (xy 417.988191 -167.787868) (xy 417.977691 -167.72531)
			(xy 417.977066 -167.693594) (xy 417.977291 -167.675575) (xy 417.980722 -167.6397) (xy 417.983924 -167.621966)
			(xy 417.986322 -167.606764) (xy 417.982784 -167.576201) (xy 417.97031 -167.548077) (xy 417.95003 -167.524941)
			(xy 417.923782 -167.508889) (xy 417.908994 -167.504618) (xy 417.881967 -167.497164) (xy 417.830242 -167.475542)
			(xy 417.782237 -167.446585) (xy 417.738984 -167.410917) (xy 417.701416 -167.369305) (xy 417.670339 -167.322645)
			(xy 417.646423 -167.27194) (xy 417.630183 -167.218282) (xy 417.621967 -167.162825) (xy 417.621466 -167.134794)
			(xy 417.621972 -167.107544) (xy 417.629729 -167.053598) (xy 417.645083 -167.001305) (xy 417.667723 -166.95173)
			(xy 417.697188 -166.905881) (xy 417.732877 -166.864691) (xy 417.774065 -166.829) (xy 417.819912 -166.799533)
			(xy 417.869487 -166.77689) (xy 417.921779 -166.761533) (xy 417.975724 -166.753774) (xy 418.002974 -166.753286)
			(xy 418.030548 -166.753774) (xy 418.085119 -166.761723) (xy 418.137979 -166.777444) (xy 418.188024 -166.80061)
			(xy 418.234215 -166.830738) (xy 418.275587 -166.867201) (xy 418.293804 -166.887906) (xy 418.303702 -166.898804)
			(xy 418.328352 -166.914879) (xy 418.35656 -166.923263) (xy 418.385988 -166.923263) (xy 418.414196 -166.914879)
			(xy 418.438846 -166.898804) (xy 418.448744 -166.887906) (xy 418.466959 -166.8672) (xy 418.50833 -166.830735)
			(xy 418.55452 -166.800608) (xy 418.604567 -166.777445) (xy 418.657428 -166.761729) (xy 418.712 -166.753789)
			(xy 418.767148 -166.753789) (xy 418.82172 -166.761729) (xy 418.874581 -166.777445) (xy 418.924628 -166.800608)
			(xy 418.970818 -166.830735) (xy 419.012189 -166.8672) (xy 419.030404 -166.887906) (xy 419.040302 -166.898804)
			(xy 419.064952 -166.914879) (xy 419.09316 -166.923263) (xy 419.122588 -166.923263) (xy 419.150796 -166.914879)
			(xy 419.175446 -166.898804) (xy 419.185344 -166.887906) (xy 419.203582 -166.86722) (xy 419.244945 -166.830747)
			(xy 419.291129 -166.800612) (xy 419.341172 -166.777442) (xy 419.39403 -166.76172) (xy 419.448601 -166.753775)
			(xy 419.476174 -166.753286) (xy 419.503426 -166.753779) (xy 419.557375 -166.761533) (xy 419.609672 -166.776885)
			(xy 419.659252 -166.799524) (xy 419.705105 -166.828989) (xy 419.746298 -166.86468) (xy 419.781992 -166.905869)
			(xy 419.81146 -166.95172) (xy 419.834104 -167.001298) (xy 419.84946 -167.053593) (xy 419.857218 -167.107542)
			(xy 419.857682 -167.134794) (xy 419.857167 -167.16265) (xy 419.849043 -167.217766) (xy 419.832998 -167.271117)
			(xy 419.80937 -167.321571) (xy 419.778663 -167.368056) (xy 419.741526 -167.409585) (xy 419.69875 -167.445278)
			(xy 419.651241 -167.474376) (xy 419.600008 -167.496262) (xy 419.573202 -167.503856) (xy 419.559077 -167.508105)
			(xy 419.53393 -167.523501) (xy 419.514215 -167.545425) (xy 419.501566 -167.57206) (xy 419.497034 -167.601195)
			(xy 419.498526 -167.61587) (xy 419.5002 -167.628886) (xy 419.501977 -167.655071) (xy 419.502082 -167.668194)
			(xy 419.501988 -167.682343) (xy 419.499954 -167.710566) (xy 419.498018 -167.724582) (xy 419.496394 -167.737927)
			(xy 419.4995 -167.764623) (xy 419.509476 -167.789579) (xy 419.525629 -167.81106) (xy 419.546835 -167.827572)
			(xy 419.57162 -167.837966) (xy 419.584886 -167.840152) (xy 419.612039 -167.844237) (xy 419.664868 -167.859214)
			(xy 419.715004 -167.881609) (xy 419.761412 -167.910958) (xy 419.803135 -167.946656) (xy 419.839311 -167.987965)
			(xy 419.869192 -168.034033) (xy 419.892162 -168.083908) (xy 419.907746 -168.136561) (xy 419.915622 -168.190903)
			(xy 419.916102 -168.218358) (xy 419.915606 -168.24561) (xy 419.907854 -168.29956) (xy 419.892503 -168.351858)
			(xy 419.869865 -168.401438) (xy 419.840401 -168.447292) (xy 419.804711 -168.488485) (xy 419.763521 -168.524179)
			(xy 419.71767 -168.553648) (xy 419.668092 -168.576291) (xy 419.615795 -168.591647) (xy 419.561846 -168.599403)
			(xy 419.534594 -168.599866) (xy 419.507019 -168.599416) (xy 419.452445 -168.591462) (xy 419.399584 -168.575735)
			(xy 419.349538 -168.552562) (xy 419.303349 -168.522426) (xy 419.261979 -168.485955) (xy 419.243764 -168.465246)
			(xy 419.233866 -168.454348) (xy 419.209216 -168.438273) (xy 419.181008 -168.429889) (xy 419.15158 -168.429889)
			(xy 419.123372 -168.438273) (xy 419.098722 -168.454348) (xy 419.088824 -168.465246) (xy 419.070614 -168.485958)
			(xy 419.029244 -168.522426) (xy 418.983053 -168.552557) (xy 418.933005 -168.575722) (xy 418.880143 -168.591439)
			(xy 418.825569 -168.59938) (xy 418.797994 -168.599866) (xy 418.771493 -168.599405) (xy 418.719002 -168.592063)
			(xy 418.668034 -168.577521) (xy 418.619572 -168.556059) (xy 418.574549 -168.528091) (xy 418.5539 -168.511474)
			(xy 418.541717 -168.502082) (xy 418.51333 -168.490285) (xy 418.482719 -168.487451) (xy 418.452648 -168.493838)
			(xy 418.425831 -168.508868) (xy 418.404689 -168.531186) (xy 418.397436 -168.544748) (xy 418.385321 -168.56843)
			(xy 418.355402 -168.612413) (xy 418.319535 -168.651696) (xy 418.278448 -168.685482) (xy 418.255958 -168.699688)
			(xy 418.243751 -168.707635) (xy 418.224085 -168.729102) (xy 418.211281 -168.755249) (xy 418.206381 -168.783947)
			(xy 418.209783 -168.812861) (xy 418.215064 -168.826434) (xy 418.22456 -168.849641) (xy 418.237908 -168.897976)
			(xy 418.244633 -168.947666) (xy 418.245036 -168.972738) (xy 418.244615 -168.997807) (xy 418.237865 -169.047491)
			(xy 418.224531 -169.095825) (xy 418.215064 -169.119042) (xy 418.209854 -169.132631) (xy 418.206485 -169.161525)
			(xy 418.211389 -169.190198) (xy 418.224168 -169.21633) (xy 418.243789 -169.237805) (xy 418.255958 -169.245788)
			(xy 418.27905 -169.260416) (xy 418.321167 -169.295255) (xy 418.357742 -169.335872) (xy 418.387993 -169.381397)
			(xy 418.411268 -169.430852) (xy 418.427069 -169.483177) (xy 418.435057 -169.537249) (xy 418.43506 -169.591908)
			(xy 418.427078 -169.64598) (xy 418.411283 -169.698307) (xy 418.388014 -169.747765) (xy 418.357769 -169.793294)
			(xy 418.321198 -169.833915) (xy 418.279085 -169.868759) (xy 418.255958 -169.883328) (xy 418.243724 -169.891237)
			(xy 418.224058 -169.912714) (xy 418.211257 -169.938871) (xy 418.208732 -169.953686) (xy 426.587415 -169.953686)
			(xy 426.591451 -169.870239) (xy 426.603523 -169.787571) (xy 426.623516 -169.706454) (xy 426.651245 -169.627645)
			(xy 426.686451 -169.55188) (xy 426.728805 -169.479867) (xy 426.777911 -169.412278) (xy 426.833312 -169.349744)
			(xy 426.894489 -169.292849) (xy 426.960872 -169.242123) (xy 427.03184 -169.198042) (xy 427.106732 -169.161016)
			(xy 427.184848 -169.13139) (xy 427.265458 -169.109442) (xy 427.34781 -169.095377) (xy 427.431136 -169.089325)
			(xy 427.514656 -169.091344) (xy 427.597592 -169.101414) (xy 427.679168 -169.119442) (xy 427.758624 -169.145259)
			(xy 427.835217 -169.178624) (xy 427.908233 -169.219225) (xy 427.976989 -169.266684) (xy 428.040843 -169.320557)
			(xy 428.0992 -169.380342) (xy 428.151515 -169.445479) (xy 428.197298 -169.515362) (xy 428.236123 -169.589337)
			(xy 428.267628 -169.666714) (xy 428.291517 -169.746771) (xy 428.307568 -169.828759) (xy 428.315631 -169.911914)
			(xy 428.316136 -169.953686) (xy 428.315631 -169.995458) (xy 428.307568 -170.078613) (xy 428.291517 -170.160601)
			(xy 428.267628 -170.240658) (xy 428.236123 -170.318035) (xy 428.197298 -170.39201) (xy 428.151515 -170.461893)
			(xy 428.0992 -170.52703) (xy 428.040843 -170.586815) (xy 427.976989 -170.640688) (xy 427.908233 -170.688147)
			(xy 427.835217 -170.728748) (xy 427.758624 -170.762113) (xy 427.679168 -170.78793) (xy 427.597592 -170.805958)
			(xy 427.514656 -170.816028) (xy 427.431136 -170.818047) (xy 427.34781 -170.811995) (xy 427.265458 -170.79793)
			(xy 427.184848 -170.775982) (xy 427.106732 -170.746356) (xy 427.03184 -170.70933) (xy 426.960872 -170.665249)
			(xy 426.894489 -170.614523) (xy 426.833312 -170.557628) (xy 426.777911 -170.495094) (xy 426.728805 -170.427505)
			(xy 426.686451 -170.355492) (xy 426.651245 -170.279727) (xy 426.623516 -170.200918) (xy 426.603523 -170.119801)
			(xy 426.591451 -170.037133) (xy 426.587415 -169.953686) (xy 418.208732 -169.953686) (xy 418.206364 -169.967578)
			(xy 418.209777 -169.996499) (xy 418.215064 -170.010074) (xy 418.224541 -170.033289) (xy 418.237896 -170.081619)
			(xy 418.244629 -170.131307) (xy 418.245036 -170.156378) (xy 418.244515 -170.184263) (xy 418.236203 -170.23941)
			(xy 418.219765 -170.292702) (xy 418.195567 -170.342948) (xy 418.164151 -170.389027) (xy 418.126218 -170.429909)
			(xy 418.082616 -170.464681) (xy 418.034318 -170.492566) (xy 417.982403 -170.512941) (xy 417.928032 -170.525351)
			(xy 417.872418 -170.529519) (xy 417.816804 -170.525351) (xy 417.762433 -170.512941) (xy 417.710518 -170.492566)
			(xy 417.66222 -170.464681) (xy 417.618618 -170.429909) (xy 417.580685 -170.389027) (xy 417.549269 -170.342948)
			(xy 417.525071 -170.292702) (xy 417.508633 -170.23941) (xy 417.500321 -170.184263) (xy 417.4998 -170.156378)
			(xy 410.41574 -170.156378) (xy 410.41574 -171.087542) (xy 419.315646 -171.087542) (xy 419.316217 -171.060294)
			(xy 419.323967 -171.006352) (xy 419.339314 -170.954061) (xy 419.361947 -170.904487) (xy 419.391405 -170.858639)
			(xy 419.427087 -170.81745) (xy 419.468269 -170.781757) (xy 419.51411 -170.752289) (xy 419.563679 -170.729645)
			(xy 419.615966 -170.714285) (xy 419.669906 -170.706523) (xy 419.697154 -170.706034) (xy 419.697408 -170.706034)
			(xy 419.727247 -170.706617) (xy 419.786193 -170.715927) (xy 419.814756 -170.724576) (xy 419.82866 -170.72863)
			(xy 419.857597 -170.72954) (xy 419.885621 -170.722274) (xy 419.910469 -170.707418) (xy 419.930134 -170.686171)
			(xy 419.943028 -170.660251) (xy 419.946074 -170.64609) (xy 419.951204 -170.620008) (xy 419.967775 -170.569501)
			(xy 419.991201 -170.521784) (xy 420.021027 -170.477784) (xy 420.056674 -170.438352) (xy 420.097452 -170.404253)
			(xy 420.142571 -170.376148) (xy 420.191156 -170.354581) (xy 420.242265 -170.339971) (xy 420.294908 -170.332601)
			(xy 420.321486 -170.332146) (xy 420.348736 -170.3327) (xy 420.402682 -170.340455) (xy 420.454975 -170.355808)
			(xy 420.504551 -170.378447) (xy 420.550401 -170.407911) (xy 420.59159 -170.4436) (xy 420.627281 -170.484788)
			(xy 420.656747 -170.530636) (xy 420.679387 -170.580211) (xy 420.694742 -170.632504) (xy 420.702499 -170.68645)
			(xy 420.702499 -170.74095) (xy 420.694742 -170.794896) (xy 420.679387 -170.847189) (xy 420.656747 -170.896764)
			(xy 420.627281 -170.942612) (xy 420.59159 -170.9838) (xy 420.550401 -171.019489) (xy 420.504551 -171.048953)
			(xy 420.454975 -171.071592) (xy 420.402682 -171.086945) (xy 420.348736 -171.0947) (xy 420.321486 -171.095162)
			(xy 420.321232 -171.095162) (xy 420.291393 -171.094593) (xy 420.232447 -171.085273) (xy 420.203884 -171.07662)
			(xy 420.189967 -171.072614) (xy 420.161038 -171.071695) (xy 420.133019 -171.078952) (xy 420.108173 -171.093799)
			(xy 420.088508 -171.115036) (xy 420.075613 -171.140949) (xy 420.072566 -171.155106) (xy 420.06599 -171.187947)
			(xy 420.042863 -171.250798) (xy 420.026592 -171.280074) (xy 420.019587 -171.293057) (xy 420.012541 -171.321688)
			(xy 420.013975 -171.351137) (xy 420.023771 -171.378948) (xy 420.04111 -171.402795) (xy 420.064544 -171.42069)
			(xy 420.078154 -171.426378) (xy 420.104942 -171.437047) (xy 420.155182 -171.465341) (xy 420.20059 -171.500876)
			(xy 420.240131 -171.542842) (xy 420.272903 -171.590283) (xy 420.298159 -171.642117) (xy 420.315323 -171.697162)
			(xy 420.324005 -171.754164) (xy 420.324534 -171.782994) (xy 420.324048 -171.810245) (xy 420.316292 -171.864193)
			(xy 420.300937 -171.916488) (xy 420.278295 -171.966065) (xy 420.248829 -172.011915) (xy 420.213138 -172.053106)
			(xy 420.171947 -172.088797) (xy 420.126097 -172.118263) (xy 420.07652 -172.140905) (xy 420.024225 -172.15626)
			(xy 419.970277 -172.164016) (xy 419.915775 -172.164016) (xy 419.861827 -172.15626) (xy 419.809532 -172.140905)
			(xy 419.759955 -172.118263) (xy 419.714105 -172.088797) (xy 419.672914 -172.053106) (xy 419.637223 -172.011915)
			(xy 419.607757 -171.966065) (xy 419.585115 -171.916488) (xy 419.56976 -171.864193) (xy 419.562004 -171.810245)
			(xy 419.561518 -171.782994) (xy 419.561518 -171.78274) (xy 419.561938 -171.757537) (xy 419.568572 -171.70757)
			(xy 419.581743 -171.658915) (xy 419.601219 -171.612425) (xy 419.613588 -171.590462) (xy 419.620627 -171.577499)
			(xy 419.627653 -171.548862) (xy 419.626205 -171.519412) (xy 419.616403 -171.491603) (xy 419.599064 -171.467754)
			(xy 419.575634 -171.449852) (xy 419.562026 -171.444158) (xy 419.535269 -171.433416) (xy 419.485027 -171.405136)
			(xy 419.439617 -171.369613) (xy 419.400072 -171.327658) (xy 419.367296 -171.280228) (xy 419.342035 -171.228402)
			(xy 419.324865 -171.173365) (xy 419.316178 -171.116369) (xy 419.315646 -171.087542) (xy 410.41574 -171.087542)
			(xy 410.41574 -172.82625) (xy 419.374572 -172.82625) (xy 419.374572 -172.77175) (xy 419.382328 -172.717803)
			(xy 419.397682 -172.66551) (xy 419.420321 -172.615933) (xy 419.449786 -172.570084) (xy 419.485475 -172.528893)
			(xy 419.526663 -172.493201) (xy 419.572511 -172.463734) (xy 419.622085 -172.441091) (xy 419.674378 -172.425733)
			(xy 419.728324 -172.417974) (xy 419.755574 -172.417486) (xy 419.78151 -172.417935) (xy 419.832905 -172.42496)
			(xy 419.882874 -172.438884) (xy 419.930495 -172.459451) (xy 419.97489 -172.48628) (xy 419.987115 -172.496156)
			(xy 426.563024 -172.496156) (xy 426.563024 -172.41146) (xy 426.571075 -172.327146) (xy 426.587104 -172.24398)
			(xy 426.610965 -172.162713) (xy 426.642444 -172.084083) (xy 426.681255 -172.008802) (xy 426.727045 -171.93755)
			(xy 426.779401 -171.870974) (xy 426.837849 -171.809676) (xy 426.901859 -171.754211) (xy 426.970851 -171.705082)
			(xy 427.044201 -171.662733) (xy 427.121244 -171.627549) (xy 427.201283 -171.599847) (xy 427.283592 -171.579879)
			(xy 427.367427 -171.567826) (xy 427.452028 -171.563796) (xy 427.536629 -171.567826) (xy 427.620464 -171.579879)
			(xy 427.702773 -171.599847) (xy 427.782812 -171.627549) (xy 427.859855 -171.662733) (xy 427.933205 -171.705082)
			(xy 428.002197 -171.754211) (xy 428.066207 -171.809676) (xy 428.124655 -171.870974) (xy 428.177011 -171.93755)
			(xy 428.222801 -172.008802) (xy 428.261612 -172.084083) (xy 428.293091 -172.162713) (xy 428.316952 -172.24398)
			(xy 428.332981 -172.327146) (xy 428.341032 -172.41146) (xy 428.341536 -172.453808) (xy 428.341032 -172.496156)
			(xy 428.332981 -172.58047) (xy 428.316952 -172.663636) (xy 428.293091 -172.744903) (xy 428.261612 -172.823533)
			(xy 428.222801 -172.898814) (xy 428.177011 -172.970066) (xy 428.124655 -173.036642) (xy 428.066207 -173.09794)
			(xy 428.002197 -173.153405) (xy 427.933205 -173.202534) (xy 427.859855 -173.244883) (xy 427.782812 -173.280067)
			(xy 427.702773 -173.307769) (xy 427.620464 -173.327737) (xy 427.536629 -173.33979) (xy 427.452028 -173.343821)
			(xy 427.367427 -173.33979) (xy 427.283592 -173.327737) (xy 427.201283 -173.307769) (xy 427.121244 -173.280067)
			(xy 427.044201 -173.244883) (xy 426.970851 -173.202534) (xy 426.901859 -173.153405) (xy 426.837849 -173.09794)
			(xy 426.779401 -173.036642) (xy 426.727045 -172.970066) (xy 426.681255 -172.898814) (xy 426.642444 -172.823533)
			(xy 426.610965 -172.744903) (xy 426.587104 -172.663636) (xy 426.571075 -172.58047) (xy 426.563024 -172.496156)
			(xy 419.987115 -172.496156) (xy 420.015241 -172.518878) (xy 420.050803 -172.556642) (xy 420.066216 -172.577506)
			(xy 420.075441 -172.589618) (xy 420.099609 -172.608114) (xy 420.128159 -172.618654) (xy 420.158548 -172.620298)
			(xy 420.188068 -172.6129) (xy 420.201344 -172.605446) (xy 420.22371 -172.592437) (xy 420.271218 -172.571938)
			(xy 420.321061 -172.55805) (xy 420.372323 -172.551028) (xy 420.398194 -172.550582) (xy 420.398702 -172.550582)
			(xy 420.425952 -172.551088) (xy 420.479898 -172.558845) (xy 420.532192 -172.5742) (xy 420.581767 -172.59684)
			(xy 420.627616 -172.626306) (xy 420.668805 -172.661997) (xy 420.704495 -172.703186) (xy 420.733961 -172.749035)
			(xy 420.756601 -172.79861) (xy 420.771956 -172.850904) (xy 420.779712 -172.90485) (xy 420.779712 -172.95935)
			(xy 420.771956 -173.013296) (xy 420.756601 -173.06559) (xy 420.733961 -173.115165) (xy 420.704495 -173.161014)
			(xy 420.668805 -173.202203) (xy 420.627616 -173.237894) (xy 420.581767 -173.26736) (xy 420.532192 -173.29)
			(xy 420.479898 -173.305355) (xy 420.425952 -173.313112) (xy 420.398702 -173.313598) (xy 420.372765 -173.313174)
			(xy 420.321369 -173.306145) (xy 420.271399 -173.292217) (xy 420.223778 -173.271647) (xy 420.179382 -173.244813)
			(xy 420.139033 -173.212212) (xy 420.103472 -173.174444) (xy 420.08806 -173.153578) (xy 420.07886 -173.141445)
			(xy 420.054684 -173.122952) (xy 420.026127 -173.112417) (xy 419.995733 -173.110778) (xy 419.966209 -173.118181)
			(xy 419.952932 -173.125638) (xy 419.930554 -173.138625) (xy 419.88305 -173.159127) (xy 419.833211 -173.173021)
			(xy 419.781951 -173.180051) (xy 419.756082 -173.180502) (xy 419.755574 -173.180502) (xy 419.728324 -173.180026)
			(xy 419.674378 -173.172267) (xy 419.622085 -173.156909) (xy 419.572511 -173.134266) (xy 419.526663 -173.104799)
			(xy 419.485475 -173.069107) (xy 419.449786 -173.027916) (xy 419.420321 -172.982067) (xy 419.397682 -172.93249)
			(xy 419.382328 -172.880197) (xy 419.374572 -172.82625) (xy 410.41574 -172.82625) (xy 410.41574 -173.4058)
			(xy 410.452824 -173.416214) (xy 410.478928 -173.424017) (xy 410.528576 -173.446447) (xy 410.574231 -173.476175)
			(xy 410.614826 -173.512509) (xy 410.649416 -173.5546) (xy 410.663258 -173.577953) (xy 418.557175 -173.577953)
			(xy 418.564931 -173.524006) (xy 418.580286 -173.471711) (xy 418.602926 -173.422133) (xy 418.632392 -173.376282)
			(xy 418.668083 -173.335091) (xy 418.709272 -173.299399) (xy 418.755122 -173.269932) (xy 418.804699 -173.24729)
			(xy 418.856994 -173.231934) (xy 418.910941 -173.224176) (xy 418.965444 -173.224175) (xy 419.019392 -173.231931)
			(xy 419.071687 -173.247285) (xy 419.121265 -173.269925) (xy 419.167116 -173.29939) (xy 419.208307 -173.335081)
			(xy 419.243999 -173.37627) (xy 419.273467 -173.42212) (xy 419.296109 -173.471697) (xy 419.311466 -173.523991)
			(xy 419.319224 -173.577939) (xy 419.31971 -173.60519) (xy 419.319282 -173.630581) (xy 419.312524 -173.680913)
			(xy 419.306248 -173.70552) (xy 419.302808 -173.720167) (xy 419.303729 -173.750225) (xy 419.31336 -173.778715)
			(xy 419.330866 -173.803167) (xy 419.354731 -173.821465) (xy 419.38289 -173.832023) (xy 419.412902 -173.833929)
			(xy 419.42766 -173.830996) (xy 419.449192 -173.826248) (xy 419.492989 -173.821151) (xy 419.515036 -173.820836)
			(xy 419.51529 -173.820836) (xy 419.542541 -173.821267) (xy 419.59649 -173.829022) (xy 419.648785 -173.844376)
			(xy 419.698364 -173.867015) (xy 419.744216 -173.89648) (xy 419.785408 -173.93217) (xy 419.821101 -173.973359)
			(xy 419.85057 -174.019209) (xy 419.873213 -174.068785) (xy 419.888571 -174.12108) (xy 419.896331 -174.175027)
			(xy 419.896334 -174.22953) (xy 419.88858 -174.283479) (xy 419.873228 -174.335775) (xy 419.85059 -174.385354)
			(xy 419.821127 -174.431207) (xy 419.785438 -174.4724) (xy 419.74425 -174.508094) (xy 419.698401 -174.537564)
			(xy 419.648825 -174.560209) (xy 419.596532 -174.575569) (xy 419.542584 -174.58333) (xy 419.488081 -174.583335)
			(xy 419.434132 -174.575583) (xy 419.381836 -174.560232) (xy 419.332256 -174.537596) (xy 419.286403 -174.508134)
			(xy 419.245208 -174.472446) (xy 419.209512 -174.431259) (xy 419.180041 -174.385411) (xy 419.157395 -174.335836)
			(xy 419.142034 -174.283543) (xy 419.134271 -174.229595) (xy 419.133782 -174.202344) (xy 419.134216 -174.176953)
			(xy 419.14097 -174.126622) (xy 419.147244 -174.102014) (xy 419.150657 -174.087361) (xy 419.149744 -174.057304)
			(xy 419.14012 -174.028815) (xy 419.122618 -174.004362) (xy 419.098755 -173.986064) (xy 419.070599 -173.975507)
			(xy 419.040588 -173.973604) (xy 419.025832 -173.976538) (xy 419.0043 -173.981286) (xy 418.960503 -173.986383)
			(xy 418.938456 -173.986698) (xy 418.938202 -173.986698) (xy 418.910951 -173.986224) (xy 418.857003 -173.978468)
			(xy 418.804708 -173.963113) (xy 418.755131 -173.940473) (xy 418.70928 -173.911007) (xy 418.668089 -173.875315)
			(xy 418.632397 -173.834125) (xy 418.602931 -173.788275) (xy 418.580289 -173.738698) (xy 418.564933 -173.686404)
			(xy 418.557176 -173.632456) (xy 418.557175 -173.577953) (xy 410.663258 -173.577953) (xy 410.677194 -173.601466)
			(xy 410.697511 -173.652016) (xy 410.709895 -173.70507) (xy 410.714056 -173.759391) (xy 410.709898 -173.813713)
			(xy 410.697517 -173.866767) (xy 410.677201 -173.917318) (xy 410.649426 -173.964186) (xy 410.614838 -174.006279)
			(xy 410.574244 -174.042614) (xy 410.528591 -174.072345) (xy 410.478944 -174.094777) (xy 410.452824 -174.102522)
			(xy 410.41574 -174.112936) (xy 410.41574 -174.423957) (xy 416.453709 -174.423957) (xy 416.453709 -174.369443)
			(xy 416.461468 -174.315483) (xy 416.476827 -174.263176) (xy 416.499474 -174.213588) (xy 416.528948 -174.167728)
			(xy 416.56465 -174.12653) (xy 416.605851 -174.090832) (xy 416.651713 -174.061361) (xy 416.701302 -174.038717)
			(xy 416.75361 -174.023362) (xy 416.807571 -174.015607) (xy 416.834828 -174.015146) (xy 416.862199 -174.015584)
			(xy 416.91638 -174.023407) (xy 416.968884 -174.038902) (xy 417.01863 -174.06175) (xy 417.064596 -174.091481)
			(xy 417.085526 -174.109126) (xy 417.096854 -174.118362) (xy 417.123411 -174.130538) (xy 417.152328 -174.134711)
			(xy 417.181245 -174.130538) (xy 417.207802 -174.118362) (xy 417.21913 -174.109126) (xy 417.240081 -174.09151)
			(xy 417.286048 -174.061794) (xy 417.335791 -174.038953) (xy 417.388287 -174.023457) (xy 417.44246 -174.015623)
			(xy 417.469828 -174.015146) (xy 417.497075 -174.015726) (xy 417.551013 -174.023485) (xy 417.603298 -174.038841)
			(xy 417.652865 -174.061481) (xy 417.698707 -174.090944) (xy 417.739889 -174.126631) (xy 417.775573 -174.167816)
			(xy 417.805033 -174.213659) (xy 417.827669 -174.263228) (xy 417.843021 -174.315515) (xy 417.850776 -174.369453)
			(xy 417.850776 -174.423947) (xy 417.843021 -174.477885) (xy 417.827669 -174.530172) (xy 417.805033 -174.579741)
			(xy 417.775573 -174.625584) (xy 417.739889 -174.666769) (xy 417.698707 -174.702456) (xy 417.652865 -174.731919)
			(xy 417.603298 -174.754559) (xy 417.551013 -174.769915) (xy 417.497075 -174.777674) (xy 417.469828 -174.778162)
			(xy 417.442458 -174.777689) (xy 417.388279 -174.769874) (xy 417.335775 -174.754387) (xy 417.286028 -174.731547)
			(xy 417.240062 -174.701823) (xy 417.21913 -174.684182) (xy 417.207802 -174.674946) (xy 417.181245 -174.66277)
			(xy 417.152328 -174.658597) (xy 417.123411 -174.66277) (xy 417.096854 -174.674946) (xy 417.085526 -174.684182)
			(xy 417.064593 -174.70182) (xy 417.01862 -174.731532) (xy 416.968873 -174.754369) (xy 416.916373 -174.76986)
			(xy 416.862197 -174.777688) (xy 416.834828 -174.778162) (xy 416.807571 -174.777793) (xy 416.75361 -174.770038)
			(xy 416.701302 -174.754683) (xy 416.651713 -174.732039) (xy 416.605851 -174.702568) (xy 416.56465 -174.66687)
			(xy 416.528948 -174.625672) (xy 416.499474 -174.579812) (xy 416.476827 -174.530224) (xy 416.461468 -174.477917)
			(xy 416.453709 -174.423957) (xy 410.41574 -174.423957) (xy 410.41574 -175.35398) (xy 410.452824 -175.364394)
			(xy 410.477484 -175.371725) (xy 410.524547 -175.392504) (xy 410.56813 -175.41984) (xy 410.607324 -175.453164)
			(xy 410.641314 -175.491782) (xy 410.669391 -175.53489) (xy 410.690972 -175.581591) (xy 410.705606 -175.630912)
			(xy 410.71299 -175.681825) (xy 410.713428 -175.707548) (xy 410.712852 -175.736576) (xy 410.70343 -175.793861)
			(xy 410.684844 -175.848861) (xy 410.657586 -175.900119) (xy 410.622377 -175.946278) (xy 410.601668 -175.966628)
			(xy 410.592769 -175.97631) (xy 410.579793 -175.999172) (xy 410.573087 -176.02459) (xy 410.573096 -176.050878)
			(xy 410.579819 -176.076292) (xy 410.592811 -176.099145) (xy 410.601668 -176.108868) (xy 410.622395 -176.129202)
			(xy 410.657613 -176.17536) (xy 410.684874 -176.226621) (xy 410.703458 -176.281627) (xy 410.71287 -176.338918)
			(xy 410.713428 -176.367948) (xy 410.713332 -176.380691) (xy 410.711554 -176.406116) (xy 410.709872 -176.418748)
			(xy 410.705747 -176.444171) (xy 410.691131 -176.493556) (xy 410.669555 -176.540321) (xy 410.64147 -176.583491)
			(xy 410.60746 -176.622168) (xy 410.568236 -176.655543) (xy 410.524613 -176.682921) (xy 410.477503 -176.703733)
			(xy 410.452824 -176.711102) (xy 410.41574 -176.721516) (xy 410.41574 -178.792378) (xy 417.4998 -178.792378)
			(xy 417.500317 -178.765048) (xy 417.50828 -178.710971) (xy 417.524061 -178.658638) (xy 417.547322 -178.609175)
			(xy 417.577563 -178.563642) (xy 417.614133 -178.523018) (xy 417.656249 -178.488176) (xy 417.679378 -178.473608)
			(xy 417.691578 -178.46565) (xy 417.711251 -178.444189) (xy 417.724061 -178.418045) (xy 417.728962 -178.389347)
			(xy 417.725556 -178.360434) (xy 417.720272 -178.346862) (xy 417.710777 -178.323654) (xy 417.697428 -178.27532)
			(xy 417.690702 -178.22563) (xy 417.6903 -178.200558) (xy 417.690724 -178.175489) (xy 417.697474 -178.125806)
			(xy 417.710806 -178.077471) (xy 417.720272 -178.054254) (xy 417.725563 -178.040687) (xy 417.728937 -178.011773)
			(xy 417.724027 -177.983079) (xy 417.711231 -177.95693) (xy 417.691587 -177.935447) (xy 417.679378 -177.927508)
			(xy 417.656281 -177.912887) (xy 417.61416 -177.87805) (xy 417.57758 -177.837433) (xy 417.547327 -177.791907)
			(xy 417.52405 -177.742451) (xy 417.508247 -177.690124) (xy 417.500259 -177.63605) (xy 417.500256 -177.581389)
			(xy 417.508238 -177.527314) (xy 417.524036 -177.474986) (xy 417.547308 -177.425527) (xy 417.577556 -177.379998)
			(xy 417.614131 -177.339377) (xy 417.656249 -177.304536) (xy 417.679378 -177.289968) (xy 417.691605 -177.282048)
			(xy 417.711279 -177.260577) (xy 417.724084 -177.234423) (xy 417.728979 -177.205716) (xy 417.725563 -177.176796)
			(xy 417.720272 -177.163222) (xy 417.710796 -177.140007) (xy 417.69744 -177.091677) (xy 417.690706 -177.041989)
			(xy 417.6903 -177.016918) (xy 417.690766 -176.990075) (xy 417.698468 -176.936945) (xy 417.713716 -176.88547)
			(xy 417.736193 -176.836717) (xy 417.765435 -176.791694) (xy 417.800836 -176.751334) (xy 417.841662 -176.716472)
			(xy 417.887069 -176.687831) (xy 417.936117 -176.666002) (xy 417.961826 -176.65827) (xy 417.976329 -176.65362)
			(xy 418.0019 -176.637103) (xy 418.021469 -176.613785) (xy 418.033299 -176.585737) (xy 418.03634 -176.555448)
			(xy 418.030322 -176.525608) (xy 418.023548 -176.511966) (xy 418.00892 -176.483818) (xy 417.988191 -176.423868)
			(xy 417.977691 -176.36131) (xy 417.977066 -176.329594) (xy 417.977291 -176.311575) (xy 417.980722 -176.2757)
			(xy 417.983924 -176.257966) (xy 417.986322 -176.242764) (xy 417.982784 -176.212201) (xy 417.97031 -176.184077)
			(xy 417.95003 -176.160941) (xy 417.923782 -176.144889) (xy 417.908994 -176.140618) (xy 417.881967 -176.133164)
			(xy 417.830242 -176.111542) (xy 417.782237 -176.082585) (xy 417.738984 -176.046917) (xy 417.701416 -176.005305)
			(xy 417.670339 -175.958645) (xy 417.646423 -175.90794) (xy 417.630183 -175.854282) (xy 417.621967 -175.798825)
			(xy 417.621466 -175.770794) (xy 417.621972 -175.743544) (xy 417.629729 -175.689598) (xy 417.645083 -175.637305)
			(xy 417.667723 -175.58773) (xy 417.697188 -175.541881) (xy 417.732877 -175.500691) (xy 417.774065 -175.465)
			(xy 417.819912 -175.435533) (xy 417.869487 -175.41289) (xy 417.921779 -175.397533) (xy 417.975724 -175.389774)
			(xy 418.002974 -175.389286) (xy 418.030548 -175.389774) (xy 418.085119 -175.397723) (xy 418.137979 -175.413444)
			(xy 418.188024 -175.43661) (xy 418.234215 -175.466738) (xy 418.275587 -175.503201) (xy 418.293804 -175.523906)
			(xy 418.303702 -175.534804) (xy 418.328352 -175.550879) (xy 418.35656 -175.559263) (xy 418.385988 -175.559263)
			(xy 418.414196 -175.550879) (xy 418.438846 -175.534804) (xy 418.448744 -175.523906) (xy 418.466959 -175.5032)
			(xy 418.50833 -175.466735) (xy 418.55452 -175.436608) (xy 418.604567 -175.413445) (xy 418.657428 -175.397729)
			(xy 418.712 -175.389789) (xy 418.767148 -175.389789) (xy 418.82172 -175.397729) (xy 418.874581 -175.413445)
			(xy 418.924628 -175.436608) (xy 418.970818 -175.466735) (xy 419.012189 -175.5032) (xy 419.030404 -175.523906)
			(xy 419.040302 -175.534804) (xy 419.064952 -175.550879) (xy 419.09316 -175.559263) (xy 419.122588 -175.559263)
			(xy 419.150796 -175.550879) (xy 419.175446 -175.534804) (xy 419.185344 -175.523906) (xy 419.203582 -175.50322)
			(xy 419.244945 -175.466747) (xy 419.291129 -175.436612) (xy 419.341172 -175.413442) (xy 419.39403 -175.39772)
			(xy 419.448601 -175.389775) (xy 419.476174 -175.389286) (xy 419.503426 -175.389779) (xy 419.557375 -175.397533)
			(xy 419.609672 -175.412885) (xy 419.659252 -175.435524) (xy 419.705105 -175.464989) (xy 419.746298 -175.50068)
			(xy 419.781992 -175.541869) (xy 419.81146 -175.58772) (xy 419.834104 -175.637298) (xy 419.84946 -175.689593)
			(xy 419.857218 -175.743542) (xy 419.857682 -175.770794) (xy 419.857167 -175.79865) (xy 419.849043 -175.853766)
			(xy 419.832998 -175.907117) (xy 419.80937 -175.957571) (xy 419.778663 -176.004056) (xy 419.741526 -176.045585)
			(xy 419.69875 -176.081278) (xy 419.651241 -176.110376) (xy 419.600008 -176.132262) (xy 419.573202 -176.139856)
			(xy 419.559077 -176.144105) (xy 419.53393 -176.159501) (xy 419.514215 -176.181425) (xy 419.501566 -176.20806)
			(xy 419.497034 -176.237195) (xy 419.498526 -176.25187) (xy 419.5002 -176.264886) (xy 419.501977 -176.291071)
			(xy 419.502082 -176.304194) (xy 419.501988 -176.318343) (xy 419.499954 -176.346566) (xy 419.498018 -176.360582)
			(xy 419.496394 -176.373927) (xy 419.4995 -176.400623) (xy 419.509476 -176.425579) (xy 419.525629 -176.44706)
			(xy 419.546835 -176.463572) (xy 419.57162 -176.473966) (xy 419.584886 -176.476152) (xy 419.612039 -176.480237)
			(xy 419.664868 -176.495214) (xy 419.715004 -176.517609) (xy 419.761412 -176.546958) (xy 419.803135 -176.582656)
			(xy 419.839311 -176.623965) (xy 419.869192 -176.670033) (xy 419.892162 -176.719908) (xy 419.907746 -176.772561)
			(xy 419.915622 -176.826903) (xy 419.916102 -176.854358) (xy 419.915606 -176.88161) (xy 419.907854 -176.93556)
			(xy 419.892503 -176.987858) (xy 419.869865 -177.037438) (xy 419.840401 -177.083292) (xy 419.804711 -177.124485)
			(xy 419.763521 -177.160179) (xy 419.71767 -177.189648) (xy 419.668092 -177.212291) (xy 419.615795 -177.227647)
			(xy 419.561846 -177.235403) (xy 419.534594 -177.235866) (xy 419.507019 -177.235416) (xy 419.452445 -177.227462)
			(xy 419.399584 -177.211735) (xy 419.349538 -177.188562) (xy 419.303349 -177.158426) (xy 419.261979 -177.121955)
			(xy 419.243764 -177.101246) (xy 419.233866 -177.090348) (xy 419.209216 -177.074273) (xy 419.181008 -177.065889)
			(xy 419.15158 -177.065889) (xy 419.123372 -177.074273) (xy 419.098722 -177.090348) (xy 419.088824 -177.101246)
			(xy 419.070614 -177.121958) (xy 419.029244 -177.158426) (xy 418.983053 -177.188557) (xy 418.933005 -177.211722)
			(xy 418.880143 -177.227439) (xy 418.825569 -177.23538) (xy 418.797994 -177.235866) (xy 418.771493 -177.235405)
			(xy 418.719002 -177.228063) (xy 418.668034 -177.213521) (xy 418.619572 -177.192059) (xy 418.574549 -177.164091)
			(xy 418.5539 -177.147474) (xy 418.541717 -177.138082) (xy 418.51333 -177.126285) (xy 418.482719 -177.123451)
			(xy 418.452648 -177.129838) (xy 418.425831 -177.144868) (xy 418.404689 -177.167186) (xy 418.397436 -177.180748)
			(xy 418.385321 -177.20443) (xy 418.355402 -177.248413) (xy 418.319535 -177.287696) (xy 418.278448 -177.321482)
			(xy 418.255958 -177.335688) (xy 418.243751 -177.343635) (xy 418.224085 -177.365102) (xy 418.211281 -177.391249)
			(xy 418.206381 -177.419947) (xy 418.209783 -177.448861) (xy 418.215064 -177.462434) (xy 418.22456 -177.485641)
			(xy 418.237908 -177.533976) (xy 418.244633 -177.583666) (xy 418.245036 -177.608738) (xy 418.244615 -177.633807)
			(xy 418.237865 -177.683491) (xy 418.224531 -177.731825) (xy 418.215064 -177.755042) (xy 418.209854 -177.768631)
			(xy 418.206485 -177.797525) (xy 418.211389 -177.826198) (xy 418.224168 -177.85233) (xy 418.243789 -177.873805)
			(xy 418.255958 -177.881788) (xy 418.27905 -177.896416) (xy 418.321167 -177.931255) (xy 418.357742 -177.971872)
			(xy 418.387993 -178.017397) (xy 418.411268 -178.066852) (xy 418.427069 -178.119177) (xy 418.435057 -178.173249)
			(xy 418.43506 -178.227908) (xy 418.427078 -178.28198) (xy 418.411283 -178.334307) (xy 418.388014 -178.383765)
			(xy 418.357769 -178.429294) (xy 418.321198 -178.469915) (xy 418.279085 -178.504759) (xy 418.255958 -178.519328)
			(xy 418.243724 -178.527237) (xy 418.224058 -178.548714) (xy 418.211257 -178.574871) (xy 418.206364 -178.603578)
			(xy 418.209777 -178.632499) (xy 418.215064 -178.646074) (xy 418.224541 -178.669289) (xy 418.237896 -178.717619)
			(xy 418.244629 -178.767307) (xy 418.245036 -178.792378) (xy 418.244515 -178.820263) (xy 418.236203 -178.87541)
			(xy 418.219765 -178.928702) (xy 418.195567 -178.978948) (xy 418.164151 -179.025027) (xy 418.126218 -179.065909)
			(xy 418.082616 -179.100681) (xy 418.034318 -179.128566) (xy 417.982403 -179.148941) (xy 417.928032 -179.161351)
			(xy 417.872418 -179.165519) (xy 417.816804 -179.161351) (xy 417.762433 -179.148941) (xy 417.710518 -179.128566)
			(xy 417.66222 -179.100681) (xy 417.618618 -179.065909) (xy 417.580685 -179.025027) (xy 417.549269 -178.978948)
			(xy 417.525071 -178.928702) (xy 417.508633 -178.87541) (xy 417.500321 -178.820263) (xy 417.4998 -178.792378)
			(xy 410.41574 -178.792378) (xy 410.41574 -179.723542) (xy 419.315646 -179.723542) (xy 419.316217 -179.696294)
			(xy 419.323967 -179.642352) (xy 419.339314 -179.590061) (xy 419.361947 -179.540487) (xy 419.391405 -179.494639)
			(xy 419.427087 -179.45345) (xy 419.468269 -179.417757) (xy 419.51411 -179.388289) (xy 419.563679 -179.365645)
			(xy 419.615966 -179.350285) (xy 419.669906 -179.342523) (xy 419.697154 -179.342034) (xy 419.697408 -179.342034)
			(xy 419.727247 -179.342617) (xy 419.786193 -179.351927) (xy 419.814756 -179.360576) (xy 419.82866 -179.36463)
			(xy 419.857597 -179.36554) (xy 419.885621 -179.358274) (xy 419.910469 -179.343418) (xy 419.930134 -179.322171)
			(xy 419.943028 -179.296251) (xy 419.946074 -179.28209) (xy 419.951204 -179.256008) (xy 419.967775 -179.205501)
			(xy 419.991201 -179.157784) (xy 420.021027 -179.113784) (xy 420.056674 -179.074352) (xy 420.097452 -179.040253)
			(xy 420.142571 -179.012148) (xy 420.191156 -178.990581) (xy 420.242265 -178.975971) (xy 420.294908 -178.968601)
			(xy 420.321486 -178.968146) (xy 420.348736 -178.9687) (xy 420.402682 -178.976455) (xy 420.454975 -178.991808)
			(xy 420.504551 -179.014447) (xy 420.550401 -179.043911) (xy 420.59159 -179.0796) (xy 420.627281 -179.120788)
			(xy 420.656747 -179.166636) (xy 420.679387 -179.216211) (xy 420.694742 -179.268504) (xy 420.702499 -179.32245)
			(xy 420.702499 -179.37695) (xy 420.694742 -179.430896) (xy 420.679387 -179.483189) (xy 420.656747 -179.532764)
			(xy 420.627281 -179.578612) (xy 420.59159 -179.6198) (xy 420.550401 -179.655489) (xy 420.504551 -179.684953)
			(xy 420.454975 -179.707592) (xy 420.402682 -179.722945) (xy 420.348736 -179.7307) (xy 420.321486 -179.731162)
			(xy 420.321232 -179.731162) (xy 420.291393 -179.730593) (xy 420.232447 -179.721273) (xy 420.203884 -179.71262)
			(xy 420.189967 -179.708614) (xy 420.161038 -179.707695) (xy 420.133019 -179.714952) (xy 420.108173 -179.729799)
			(xy 420.088508 -179.751036) (xy 420.075613 -179.776949) (xy 420.072566 -179.791106) (xy 420.06599 -179.823947)
			(xy 420.042863 -179.886798) (xy 420.026592 -179.916074) (xy 420.019587 -179.929057) (xy 420.012541 -179.957688)
			(xy 420.013975 -179.987137) (xy 420.023771 -180.014948) (xy 420.04111 -180.038795) (xy 420.064544 -180.05669)
			(xy 420.078154 -180.062378) (xy 420.104942 -180.073047) (xy 420.155182 -180.101341) (xy 420.20059 -180.136876)
			(xy 420.240131 -180.178842) (xy 420.272903 -180.226283) (xy 420.298159 -180.278117) (xy 420.315323 -180.333162)
			(xy 420.324005 -180.390164) (xy 420.324534 -180.418994) (xy 420.324048 -180.446245) (xy 420.316292 -180.500193)
			(xy 420.300937 -180.552488) (xy 420.278295 -180.602065) (xy 420.248829 -180.647915) (xy 420.213138 -180.689106)
			(xy 420.171947 -180.724797) (xy 420.126097 -180.754263) (xy 420.07652 -180.776905) (xy 420.024225 -180.79226)
			(xy 419.970277 -180.800016) (xy 419.915775 -180.800016) (xy 419.861827 -180.79226) (xy 419.809532 -180.776905)
			(xy 419.759955 -180.754263) (xy 419.714105 -180.724797) (xy 419.672914 -180.689106) (xy 419.637223 -180.647915)
			(xy 419.607757 -180.602065) (xy 419.585115 -180.552488) (xy 419.56976 -180.500193) (xy 419.562004 -180.446245)
			(xy 419.561518 -180.418994) (xy 419.561518 -180.41874) (xy 419.561938 -180.393537) (xy 419.568572 -180.34357)
			(xy 419.581743 -180.294915) (xy 419.601219 -180.248425) (xy 419.613588 -180.226462) (xy 419.620627 -180.213499)
			(xy 419.627653 -180.184862) (xy 419.626205 -180.155412) (xy 419.616403 -180.127603) (xy 419.599064 -180.103754)
			(xy 419.575634 -180.085852) (xy 419.562026 -180.080158) (xy 419.535269 -180.069416) (xy 419.485027 -180.041136)
			(xy 419.439617 -180.005613) (xy 419.400072 -179.963658) (xy 419.367296 -179.916228) (xy 419.342035 -179.864402)
			(xy 419.324865 -179.809365) (xy 419.316178 -179.752369) (xy 419.315646 -179.723542) (xy 410.41574 -179.723542)
			(xy 410.41574 -182.0418) (xy 410.452824 -182.052214) (xy 410.478928 -182.060017) (xy 410.528576 -182.082447)
			(xy 410.574231 -182.112175) (xy 410.614826 -182.148509) (xy 410.649416 -182.1906) (xy 410.663258 -182.213953)
			(xy 418.557175 -182.213953) (xy 418.564931 -182.160006) (xy 418.580286 -182.107711) (xy 418.602926 -182.058133)
			(xy 418.632392 -182.012282) (xy 418.668083 -181.971091) (xy 418.709272 -181.935399) (xy 418.755122 -181.905932)
			(xy 418.804699 -181.88329) (xy 418.856994 -181.867934) (xy 418.910941 -181.860176) (xy 418.965444 -181.860175)
			(xy 419.019392 -181.867931) (xy 419.071687 -181.883285) (xy 419.121265 -181.905925) (xy 419.167116 -181.93539)
			(xy 419.208307 -181.971081) (xy 419.243999 -182.01227) (xy 419.273467 -182.05812) (xy 419.296109 -182.107697)
			(xy 419.311466 -182.159991) (xy 419.319224 -182.213939) (xy 419.31971 -182.24119) (xy 419.319282 -182.266581)
			(xy 419.312524 -182.316913) (xy 419.306248 -182.34152) (xy 419.302808 -182.356167) (xy 419.303729 -182.386225)
			(xy 419.31336 -182.414715) (xy 419.330866 -182.439167) (xy 419.354731 -182.457465) (xy 419.38289 -182.468023)
			(xy 419.412902 -182.469929) (xy 419.42766 -182.466996) (xy 419.449192 -182.462248) (xy 419.492989 -182.457151)
			(xy 419.515036 -182.456836) (xy 419.51529 -182.456836) (xy 419.542541 -182.457267) (xy 419.59649 -182.465022)
			(xy 419.648785 -182.480376) (xy 419.698364 -182.503015) (xy 419.744216 -182.53248) (xy 419.785408 -182.56817)
			(xy 419.821101 -182.609359) (xy 419.85057 -182.655209) (xy 419.87006 -182.697882) (xy 433.914294 -182.697882)
			(xy 433.918365 -182.64226) (xy 433.930491 -182.587823) (xy 433.950414 -182.535732) (xy 433.97771 -182.487097)
			(xy 434.011796 -182.442954) (xy 434.051945 -182.404245) (xy 434.097303 -182.371794) (xy 434.146903 -182.346293)
			(xy 434.199687 -182.328286) (xy 434.25453 -182.318156) (xy 434.310264 -182.316119) (xy 434.365701 -182.322219)
			(xy 434.419658 -182.336325) (xy 434.470987 -182.358137) (xy 434.518593 -182.387191) (xy 434.561461 -182.422866)
			(xy 434.598678 -182.464403) (xy 434.629451 -182.510916) (xy 434.653123 -182.561413) (xy 434.669191 -182.61482)
			(xy 434.677311 -182.669996) (xy 434.67782 -182.697882) (xy 434.677311 -182.725768) (xy 434.669191 -182.780944)
			(xy 434.653123 -182.834351) (xy 434.629451 -182.884848) (xy 434.598678 -182.931361) (xy 434.561461 -182.972898)
			(xy 434.518593 -183.008573) (xy 434.470987 -183.037627) (xy 434.419658 -183.059439) (xy 434.365701 -183.073545)
			(xy 434.310264 -183.079645) (xy 434.25453 -183.077608) (xy 434.199687 -183.067478) (xy 434.146903 -183.049471)
			(xy 434.097303 -183.02397) (xy 434.051945 -182.991519) (xy 434.011796 -182.95281) (xy 433.97771 -182.908667)
			(xy 433.950414 -182.860032) (xy 433.930491 -182.807941) (xy 433.918365 -182.753504) (xy 433.914294 -182.697882)
			(xy 419.87006 -182.697882) (xy 419.873213 -182.704785) (xy 419.888571 -182.75708) (xy 419.896331 -182.811027)
			(xy 419.896334 -182.86553) (xy 419.88858 -182.919479) (xy 419.873228 -182.971775) (xy 419.85059 -183.021354)
			(xy 419.821127 -183.067207) (xy 419.785438 -183.1084) (xy 419.74425 -183.144094) (xy 419.698401 -183.173564)
			(xy 419.648825 -183.196209) (xy 419.596532 -183.211569) (xy 419.542584 -183.21933) (xy 419.488081 -183.219335)
			(xy 419.434132 -183.211583) (xy 419.381836 -183.196232) (xy 419.332256 -183.173596) (xy 419.286403 -183.144134)
			(xy 419.245208 -183.108446) (xy 419.209512 -183.067259) (xy 419.180041 -183.021411) (xy 419.157395 -182.971836)
			(xy 419.142034 -182.919543) (xy 419.134271 -182.865595) (xy 419.133782 -182.838344) (xy 419.134216 -182.812953)
			(xy 419.14097 -182.762622) (xy 419.147244 -182.738014) (xy 419.150657 -182.723361) (xy 419.149744 -182.693304)
			(xy 419.14012 -182.664815) (xy 419.122618 -182.640362) (xy 419.098755 -182.622064) (xy 419.070599 -182.611507)
			(xy 419.040588 -182.609604) (xy 419.025832 -182.612538) (xy 419.0043 -182.617286) (xy 418.960503 -182.622383)
			(xy 418.938456 -182.622698) (xy 418.938202 -182.622698) (xy 418.910951 -182.622224) (xy 418.857003 -182.614468)
			(xy 418.804708 -182.599113) (xy 418.755131 -182.576473) (xy 418.70928 -182.547007) (xy 418.668089 -182.511315)
			(xy 418.632397 -182.470125) (xy 418.602931 -182.424275) (xy 418.580289 -182.374698) (xy 418.564933 -182.322404)
			(xy 418.557176 -182.268456) (xy 418.557175 -182.213953) (xy 410.663258 -182.213953) (xy 410.677194 -182.237466)
			(xy 410.697511 -182.288016) (xy 410.709895 -182.34107) (xy 410.714056 -182.395391) (xy 410.709898 -182.449713)
			(xy 410.697517 -182.502767) (xy 410.677201 -182.553318) (xy 410.649426 -182.600186) (xy 410.614838 -182.642279)
			(xy 410.574244 -182.678614) (xy 410.528591 -182.708345) (xy 410.478944 -182.730777) (xy 410.452824 -182.738522)
			(xy 410.41574 -182.748936) (xy 410.41574 -182.934864) (xy 410.540833 -183.059957) (xy 416.453709 -183.059957)
			(xy 416.453709 -183.005443) (xy 416.461468 -182.951483) (xy 416.476827 -182.899176) (xy 416.499474 -182.849588)
			(xy 416.528948 -182.803728) (xy 416.56465 -182.76253) (xy 416.605851 -182.726832) (xy 416.651713 -182.697361)
			(xy 416.701302 -182.674717) (xy 416.75361 -182.659362) (xy 416.807571 -182.651607) (xy 416.834828 -182.651146)
			(xy 416.862199 -182.651584) (xy 416.91638 -182.659407) (xy 416.968884 -182.674902) (xy 417.01863 -182.69775)
			(xy 417.064596 -182.727481) (xy 417.085526 -182.745126) (xy 417.096854 -182.754362) (xy 417.123411 -182.766538)
			(xy 417.152328 -182.770711) (xy 417.181245 -182.766538) (xy 417.207802 -182.754362) (xy 417.21913 -182.745126)
			(xy 417.240081 -182.72751) (xy 417.286048 -182.697794) (xy 417.335791 -182.674953) (xy 417.388287 -182.659457)
			(xy 417.44246 -182.651623) (xy 417.469828 -182.651146) (xy 417.497075 -182.651726) (xy 417.551013 -182.659485)
			(xy 417.603298 -182.674841) (xy 417.652865 -182.697481) (xy 417.698707 -182.726944) (xy 417.739889 -182.762631)
			(xy 417.775573 -182.803816) (xy 417.805033 -182.849659) (xy 417.827669 -182.899228) (xy 417.843021 -182.951515)
			(xy 417.850776 -183.005453) (xy 417.850776 -183.059947) (xy 417.843021 -183.113885) (xy 417.827669 -183.166172)
			(xy 417.805033 -183.215741) (xy 417.775573 -183.261584) (xy 417.739889 -183.302769) (xy 417.698707 -183.338456)
			(xy 417.652865 -183.367919) (xy 417.603298 -183.390559) (xy 417.551013 -183.405915) (xy 417.497075 -183.413674)
			(xy 417.469828 -183.414162) (xy 417.442458 -183.413689) (xy 417.388279 -183.405874) (xy 417.335775 -183.390387)
			(xy 417.286028 -183.367547) (xy 417.240062 -183.337823) (xy 417.21913 -183.320182) (xy 417.207802 -183.310946)
			(xy 417.181245 -183.29877) (xy 417.152328 -183.294597) (xy 417.123411 -183.29877) (xy 417.096854 -183.310946)
			(xy 417.085526 -183.320182) (xy 417.064593 -183.33782) (xy 417.01862 -183.367532) (xy 416.968873 -183.390369)
			(xy 416.916373 -183.40586) (xy 416.862197 -183.413688) (xy 416.834828 -183.414162) (xy 416.807571 -183.413793)
			(xy 416.75361 -183.406038) (xy 416.701302 -183.390683) (xy 416.651713 -183.368039) (xy 416.605851 -183.338568)
			(xy 416.56465 -183.30287) (xy 416.528948 -183.261672) (xy 416.499474 -183.215812) (xy 416.476827 -183.166224)
			(xy 416.461468 -183.113917) (xy 416.453709 -183.059957) (xy 410.540833 -183.059957) (xy 411.302708 -183.821832)
			(xy 435.732174 -183.821832)
		)
		(stroke
			(width 0)
			(type solid)
		)
		(fill yes)
		(layer "In6.Cu")
		(net "GND")
	)
	(gr_poly
		(pts
			(xy 26.61412 -184.319418) (xy 26.629089 -184.318842) (xy 26.657719 -184.310074) (xy 26.682578 -184.293383)
			(xy 26.701533 -184.270205) (xy 26.712956 -184.242527) (xy 26.715866 -184.212726) (xy 26.710015 -184.183361)
			(xy 26.695903 -184.156953) (xy 26.685748 -184.145936) (xy 24.761698 -182.221886) (xy 24.752037 -182.212807)
			(xy 24.729116 -182.199508) (xy 24.703538 -182.192572) (xy 24.677038 -182.19247) (xy 24.651408 -182.199209)
			(xy 24.628385 -182.212332) (xy 24.618696 -182.221378) (xy 24.600679 -182.23924) (xy 24.560741 -182.270527)
			(xy 24.517009 -182.296245) (xy 24.470254 -182.31594) (xy 24.4213 -182.329263) (xy 24.371013 -182.335981)
			(xy 24.345646 -182.33644) (xy 24.31839 -182.33598) (xy 24.264432 -182.328229) (xy 24.212127 -182.312877)
			(xy 24.162539 -182.290238) (xy 24.116678 -182.260771) (xy 24.075477 -182.225078) (xy 24.039775 -182.183885)
			(xy 24.0103 -182.138029) (xy 23.98765 -182.088446) (xy 23.972288 -182.036144) (xy 23.964525 -181.982188)
			(xy 23.964138 -181.954932) (xy 23.964554 -181.929532) (xy 23.971291 -181.879182) (xy 23.984649 -181.830171)
			(xy 24.004392 -181.783365) (xy 24.030171 -181.739593) (xy 24.061531 -181.699629) (xy 24.079454 -181.681628)
			(xy 24.088368 -181.671874) (xy 24.101332 -181.648861) (xy 24.107968 -181.623295) (xy 24.107835 -181.596882)
			(xy 24.100941 -181.571384) (xy 24.087745 -181.548502) (xy 24.078692 -181.53888) (xy 22.34438 -179.804568)
			(xy 22.34438 -177.18532) (xy 23.30196 -176.22774) (xy 23.30196 -175.62068) (xy 23.56866 -175.35398)
			(xy 25.19172 -175.35398) (xy 25.376632 -175.538892) (xy 25.638506 -175.538892) (xy 25.656687 -175.519245)
			(xy 25.697598 -175.484725) (xy 25.742927 -175.456255) (xy 25.791787 -175.434392) (xy 25.843221 -175.419563)
			(xy 25.896222 -175.412061) (xy 25.922986 -175.411638) (xy 25.92324 -175.411638) (xy 25.950508 -175.412127)
			(xy 26.004487 -175.419893) (xy 26.056812 -175.435262) (xy 26.106417 -175.457921) (xy 26.152293 -175.487408)
			(xy 26.193505 -175.523123) (xy 26.229216 -175.56434) (xy 26.258698 -175.610218) (xy 26.281352 -175.659826)
			(xy 26.296715 -175.712152) (xy 26.304476 -175.766132) (xy 26.304476 -175.820668) (xy 26.296715 -175.874648)
			(xy 26.281352 -175.926974) (xy 26.258698 -175.976582) (xy 26.229216 -176.02246) (xy 26.193505 -176.063677)
			(xy 26.152293 -176.099392) (xy 26.106417 -176.128879) (xy 26.056812 -176.151538) (xy 26.004487 -176.166907)
			(xy 25.950508 -176.174673) (xy 25.92324 -176.175162) (xy 25.922986 -176.175162) (xy 25.89622 -176.174716)
			(xy 25.843213 -176.167244) (xy 25.791771 -176.152434) (xy 25.742904 -176.130578) (xy 25.697574 -176.102104)
			(xy 25.656669 -176.067573) (xy 25.638506 -176.047908) (xy 25.14473 -176.047908) (xy 24.087938 -177.104548)
			(xy 25.632662 -177.104548) (xy 25.636733 -177.048926) (xy 25.648859 -176.994489) (xy 25.668782 -176.942398)
			(xy 25.696078 -176.893763) (xy 25.730164 -176.84962) (xy 25.770313 -176.810911) (xy 25.815671 -176.77846)
			(xy 25.865271 -176.752959) (xy 25.918055 -176.734952) (xy 25.972898 -176.724822) (xy 26.028632 -176.722785)
			(xy 26.084069 -176.728885) (xy 26.138026 -176.742991) (xy 26.189355 -176.764803) (xy 26.236961 -176.793857)
			(xy 26.279829 -176.829532) (xy 26.317046 -176.871069) (xy 26.347819 -176.917582) (xy 26.371491 -176.968079)
			(xy 26.387559 -177.021486) (xy 26.395679 -177.076662) (xy 26.396188 -177.104548) (xy 26.395679 -177.132434)
			(xy 26.387559 -177.18761) (xy 26.371491 -177.241017) (xy 26.347819 -177.291514) (xy 26.317046 -177.338027)
			(xy 26.279829 -177.379564) (xy 26.236961 -177.415239) (xy 26.189355 -177.444293) (xy 26.138026 -177.466105)
			(xy 26.084069 -177.480211) (xy 26.028632 -177.486311) (xy 25.972898 -177.484274) (xy 25.918055 -177.474144)
			(xy 25.865271 -177.456137) (xy 25.815671 -177.430636) (xy 25.770313 -177.398185) (xy 25.730164 -177.359476)
			(xy 25.696078 -177.315333) (xy 25.668782 -177.266698) (xy 25.648859 -177.214607) (xy 25.636733 -177.16017)
			(xy 25.632662 -177.104548) (xy 24.087938 -177.104548) (xy 23.446749 -177.745644) (xy 24.330912 -177.745644)
			(xy 24.334983 -177.690022) (xy 24.347109 -177.635585) (xy 24.367032 -177.583494) (xy 24.394328 -177.534859)
			(xy 24.428414 -177.490716) (xy 24.468563 -177.452007) (xy 24.513921 -177.419556) (xy 24.563521 -177.394055)
			(xy 24.616305 -177.376048) (xy 24.671148 -177.365918) (xy 24.726882 -177.363881) (xy 24.782319 -177.369981)
			(xy 24.836276 -177.384087) (xy 24.887605 -177.405899) (xy 24.935211 -177.434953) (xy 24.978079 -177.470628)
			(xy 25.015296 -177.512165) (xy 25.046069 -177.558678) (xy 25.069741 -177.609175) (xy 25.085809 -177.662582)
			(xy 25.093929 -177.717758) (xy 25.094438 -177.745644) (xy 25.093929 -177.77353) (xy 25.085809 -177.828706)
			(xy 25.069741 -177.882113) (xy 25.046069 -177.93261) (xy 25.015296 -177.979123) (xy 24.978079 -178.02066)
			(xy 24.935211 -178.056335) (xy 24.887605 -178.085389) (xy 24.836276 -178.107201) (xy 24.782319 -178.121307)
			(xy 24.726882 -178.127407) (xy 24.671148 -178.12537) (xy 24.616305 -178.11524) (xy 24.563521 -178.097233)
			(xy 24.513921 -178.071732) (xy 24.468563 -178.039281) (xy 24.428414 -178.000572) (xy 24.394328 -177.956429)
			(xy 24.367032 -177.907794) (xy 24.347109 -177.855703) (xy 24.334983 -177.801266) (xy 24.330912 -177.745644)
			(xy 23.446749 -177.745644) (xy 23.382224 -177.81016) (xy 23.382224 -179.257706) (xy 28.443936 -184.319418)
			(xy 32.799274 -184.319418) (xy 33.40989 -183.708802) (xy 33.40989 -175.321214) (xy 34.405824 -174.32528)
			(xy 43.59021 -174.32528) (xy 43.805681 -174.540751) (xy 48.944772 -174.540751) (xy 48.944772 -174.486249)
			(xy 48.952528 -174.432302) (xy 48.967883 -174.380008) (xy 48.990523 -174.330431) (xy 49.019988 -174.28458)
			(xy 49.055678 -174.24339) (xy 49.096867 -174.207698) (xy 49.142717 -174.178231) (xy 49.192293 -174.155588)
			(xy 49.244586 -174.140231) (xy 49.298533 -174.132473) (xy 49.325784 -174.131986) (xy 49.350659 -174.132354)
			(xy 49.399986 -174.138825) (xy 49.448052 -174.151659) (xy 49.494039 -174.170637) (xy 49.537167 -174.195438)
			(xy 49.557178 -174.210218) (xy 49.569675 -174.219055) (xy 49.598406 -174.229566) (xy 49.62896 -174.231114)
			(xy 49.658606 -174.223559) (xy 49.684693 -174.207578) (xy 49.704889 -174.184599) (xy 49.71161 -174.170848)
			(xy 49.723254 -174.14601) (xy 49.752631 -174.099682) (xy 49.788337 -174.058036) (xy 49.829637 -174.021931)
			(xy 49.875681 -173.99211) (xy 49.925519 -173.969188) (xy 49.978125 -173.953636) (xy 50.032416 -173.945775)
			(xy 50.059844 -173.945296) (xy 50.087093 -173.945777) (xy 50.141037 -173.953538) (xy 50.193327 -173.968898)
			(xy 50.242899 -173.991541) (xy 50.288745 -174.021009) (xy 50.32993 -174.056701) (xy 50.365617 -174.097891)
			(xy 50.39508 -174.143739) (xy 50.417718 -174.193314) (xy 50.433071 -174.245606) (xy 50.440826 -174.29955)
			(xy 50.440826 -174.35405) (xy 50.433071 -174.407994) (xy 50.417718 -174.460286) (xy 50.39508 -174.509861)
			(xy 50.365617 -174.555709) (xy 50.32993 -174.596899) (xy 50.288745 -174.632591) (xy 50.242899 -174.662059)
			(xy 50.193327 -174.684702) (xy 50.141037 -174.700062) (xy 50.087093 -174.707823) (xy 50.059844 -174.708312)
			(xy 50.03497 -174.707929) (xy 49.985643 -174.701462) (xy 49.937577 -174.688631) (xy 49.89159 -174.669656)
			(xy 49.848462 -174.644859) (xy 49.82845 -174.63008) (xy 49.815931 -174.621277) (xy 49.787208 -174.610762)
			(xy 49.75666 -174.60921) (xy 49.72702 -174.616758) (xy 49.700935 -174.632732) (xy 49.68074 -174.655703)
			(xy 49.674018 -174.66945) (xy 49.662351 -174.694277) (xy 49.632977 -174.740604) (xy 49.597274 -174.78225)
			(xy 49.555977 -174.818355) (xy 49.509937 -174.848178) (xy 49.460103 -174.871102) (xy 49.407499 -174.886657)
			(xy 49.353211 -174.894521) (xy 49.325784 -174.895002) (xy 49.298533 -174.894527) (xy 49.244586 -174.886769)
			(xy 49.192293 -174.871412) (xy 49.142717 -174.848769) (xy 49.096867 -174.819302) (xy 49.055678 -174.78361)
			(xy 49.019988 -174.74242) (xy 48.990523 -174.696569) (xy 48.967883 -174.646992) (xy 48.952528 -174.594698)
			(xy 48.944772 -174.540751) (xy 43.805681 -174.540751) (xy 44.526454 -175.261524) (xy 51.230528 -175.261524)
			(xy 51.234599 -175.205902) (xy 51.246725 -175.151465) (xy 51.266648 -175.099374) (xy 51.293944 -175.050739)
			(xy 51.32803 -175.006596) (xy 51.368179 -174.967887) (xy 51.413537 -174.935436) (xy 51.463137 -174.909935)
			(xy 51.515921 -174.891928) (xy 51.570764 -174.881798) (xy 51.626498 -174.879761) (xy 51.681935 -174.885861)
			(xy 51.735892 -174.899967) (xy 51.787221 -174.921779) (xy 51.834827 -174.950833) (xy 51.877695 -174.986508)
			(xy 51.914912 -175.028045) (xy 51.945685 -175.074558) (xy 51.969357 -175.125055) (xy 51.985425 -175.178462)
			(xy 51.993545 -175.233638) (xy 51.994054 -175.261524) (xy 51.993957 -175.266858) (xy 52.228748 -175.266858)
			(xy 52.232819 -175.211236) (xy 52.244945 -175.156799) (xy 52.264868 -175.104708) (xy 52.292164 -175.056073)
			(xy 52.32625 -175.01193) (xy 52.366399 -174.973221) (xy 52.411757 -174.94077) (xy 52.461357 -174.915269)
			(xy 52.514141 -174.897262) (xy 52.568984 -174.887132) (xy 52.624718 -174.885095) (xy 52.680155 -174.891195)
			(xy 52.734112 -174.905301) (xy 52.785441 -174.927113) (xy 52.833047 -174.956167) (xy 52.875915 -174.991842)
			(xy 52.913132 -175.033379) (xy 52.943905 -175.079892) (xy 52.967577 -175.130389) (xy 52.983645 -175.183796)
			(xy 52.991765 -175.238972) (xy 52.992274 -175.266858) (xy 52.991765 -175.294744) (xy 52.983645 -175.34992)
			(xy 52.967577 -175.403327) (xy 52.943905 -175.453824) (xy 52.913132 -175.500337) (xy 52.875915 -175.541874)
			(xy 52.833047 -175.577549) (xy 52.785441 -175.606603) (xy 52.734112 -175.628415) (xy 52.680155 -175.642521)
			(xy 52.624718 -175.648621) (xy 52.568984 -175.646584) (xy 52.514141 -175.636454) (xy 52.461357 -175.618447)
			(xy 52.411757 -175.592946) (xy 52.366399 -175.560495) (xy 52.32625 -175.521786) (xy 52.292164 -175.477643)
			(xy 52.264868 -175.429008) (xy 52.244945 -175.376917) (xy 52.232819 -175.32248) (xy 52.228748 -175.266858)
			(xy 51.993957 -175.266858) (xy 51.993545 -175.28941) (xy 51.985425 -175.344586) (xy 51.969357 -175.397993)
			(xy 51.945685 -175.44849) (xy 51.914912 -175.495003) (xy 51.877695 -175.53654) (xy 51.834827 -175.572215)
			(xy 51.787221 -175.601269) (xy 51.735892 -175.623081) (xy 51.681935 -175.637187) (xy 51.626498 -175.643287)
			(xy 51.570764 -175.64125) (xy 51.515921 -175.63112) (xy 51.463137 -175.613113) (xy 51.413537 -175.587612)
			(xy 51.368179 -175.555161) (xy 51.32803 -175.516452) (xy 51.293944 -175.472309) (xy 51.266648 -175.423674)
			(xy 51.246725 -175.371583) (xy 51.234599 -175.317146) (xy 51.230528 -175.261524) (xy 44.526454 -175.261524)
			(xy 45.445934 -176.181004) (xy 51.225448 -176.181004) (xy 51.229519 -176.125382) (xy 51.241645 -176.070945)
			(xy 51.261568 -176.018854) (xy 51.288864 -175.970219) (xy 51.32295 -175.926076) (xy 51.363099 -175.887367)
			(xy 51.408457 -175.854916) (xy 51.458057 -175.829415) (xy 51.510841 -175.811408) (xy 51.565684 -175.801278)
			(xy 51.621418 -175.799241) (xy 51.676855 -175.805341) (xy 51.730812 -175.819447) (xy 51.782141 -175.841259)
			(xy 51.829747 -175.870313) (xy 51.872615 -175.905988) (xy 51.909832 -175.947525) (xy 51.940605 -175.994038)
			(xy 51.964277 -176.044535) (xy 51.980345 -176.097942) (xy 51.988465 -176.153118) (xy 51.988974 -176.181004)
			(xy 51.988928 -176.183544) (xy 52.231542 -176.183544) (xy 52.235613 -176.127922) (xy 52.247739 -176.073485)
			(xy 52.267662 -176.021394) (xy 52.294958 -175.972759) (xy 52.329044 -175.928616) (xy 52.369193 -175.889907)
			(xy 52.414551 -175.857456) (xy 52.464151 -175.831955) (xy 52.516935 -175.813948) (xy 52.571778 -175.803818)
			(xy 52.627512 -175.801781) (xy 52.682949 -175.807881) (xy 52.736906 -175.821987) (xy 52.788235 -175.843799)
			(xy 52.835841 -175.872853) (xy 52.878709 -175.908528) (xy 52.915926 -175.950065) (xy 52.946699 -175.996578)
			(xy 52.970371 -176.047075) (xy 52.986439 -176.100482) (xy 52.994559 -176.155658) (xy 52.995068 -176.183544)
			(xy 52.994559 -176.21143) (xy 52.986439 -176.266606) (xy 52.970371 -176.320013) (xy 52.946699 -176.37051)
			(xy 52.915926 -176.417023) (xy 52.878709 -176.45856) (xy 52.835841 -176.494235) (xy 52.788235 -176.523289)
			(xy 52.736906 -176.545101) (xy 52.682949 -176.559207) (xy 52.627512 -176.565307) (xy 52.571778 -176.56327)
			(xy 52.516935 -176.55314) (xy 52.464151 -176.535133) (xy 52.414551 -176.509632) (xy 52.369193 -176.477181)
			(xy 52.329044 -176.438472) (xy 52.294958 -176.394329) (xy 52.267662 -176.345694) (xy 52.247739 -176.293603)
			(xy 52.235613 -176.239166) (xy 52.231542 -176.183544) (xy 51.988928 -176.183544) (xy 51.988465 -176.20889)
			(xy 51.980345 -176.264066) (xy 51.964277 -176.317473) (xy 51.940605 -176.36797) (xy 51.909832 -176.414483)
			(xy 51.872615 -176.45602) (xy 51.829747 -176.491695) (xy 51.782141 -176.520749) (xy 51.730812 -176.542561)
			(xy 51.676855 -176.556667) (xy 51.621418 -176.562767) (xy 51.565684 -176.56073) (xy 51.510841 -176.5506)
			(xy 51.458057 -176.532593) (xy 51.408457 -176.507092) (xy 51.363099 -176.474641) (xy 51.32295 -176.435932)
			(xy 51.288864 -176.391789) (xy 51.261568 -176.343154) (xy 51.241645 -176.291063) (xy 51.229519 -176.236626)
			(xy 51.225448 -176.181004) (xy 45.445934 -176.181004) (xy 46.195279 -176.930349) (xy 49.335704 -176.930349)
			(xy 49.335704 -176.875851) (xy 49.34346 -176.821908) (xy 49.358813 -176.769618) (xy 49.381452 -176.720045)
			(xy 49.410916 -176.674198) (xy 49.446604 -176.633011) (xy 49.48779 -176.597322) (xy 49.533636 -176.567857)
			(xy 49.583208 -176.545217) (xy 49.635498 -176.529862) (xy 49.689441 -176.522105) (xy 49.71669 -176.521618)
			(xy 49.74406 -176.522086) (xy 49.798239 -176.529902) (xy 49.850743 -176.545391) (xy 49.90049 -176.568232)
			(xy 49.946456 -176.597957) (xy 49.967388 -176.615598) (xy 49.978716 -176.624834) (xy 50.005273 -176.63701)
			(xy 50.03419 -176.641183) (xy 50.063107 -176.63701) (xy 50.089664 -176.624834) (xy 50.100992 -176.615598)
			(xy 50.121925 -176.597957) (xy 50.167893 -176.568233) (xy 50.217639 -176.545387) (xy 50.270141 -176.529891)
			(xy 50.324319 -176.522062) (xy 50.379061 -176.522062) (xy 50.433239 -176.529891) (xy 50.485741 -176.545387)
			(xy 50.535487 -176.568233) (xy 50.581455 -176.597957) (xy 50.602388 -176.615598) (xy 50.613716 -176.624834)
			(xy 50.640273 -176.63701) (xy 50.66919 -176.641183) (xy 50.698107 -176.63701) (xy 50.724664 -176.624834)
			(xy 50.735992 -176.615598) (xy 50.756916 -176.597949) (xy 50.802891 -176.568239) (xy 50.852641 -176.545405)
			(xy 50.905143 -176.529916) (xy 50.95932 -176.52209) (xy 50.98669 -176.521618) (xy 51.013944 -176.522065)
			(xy 51.067897 -176.529821) (xy 51.120196 -176.545177) (xy 51.169778 -176.56782) (xy 51.215633 -176.59729)
			(xy 51.256826 -176.632985) (xy 51.29252 -176.67418) (xy 51.321987 -176.720036) (xy 51.344629 -176.769619)
			(xy 51.359982 -176.821919) (xy 51.367736 -176.875872) (xy 51.368198 -176.903126) (xy 51.367748 -176.930497)
			(xy 51.359926 -176.984677) (xy 51.344433 -177.03718) (xy 51.321588 -177.086926) (xy 51.291861 -177.132893)
			(xy 51.274218 -177.153824) (xy 51.264955 -177.165132) (xy 51.252778 -177.191696) (xy 51.24861 -177.22062)
			(xy 51.252789 -177.249541) (xy 51.264976 -177.276101) (xy 51.274218 -177.287428) (xy 51.29184 -177.308374)
			(xy 51.321553 -177.354343) (xy 51.344392 -177.404087) (xy 51.359888 -177.456585) (xy 51.367721 -177.510758)
			(xy 51.368198 -177.538126) (xy 51.367746 -177.565378) (xy 51.359986 -177.619328) (xy 51.344627 -177.671624)
			(xy 51.321982 -177.721202) (xy 51.292512 -177.767053) (xy 51.256817 -177.808243) (xy 51.215624 -177.843934)
			(xy 51.16977 -177.873399) (xy 51.12019 -177.89604) (xy 51.067893 -177.911394) (xy 51.013942 -177.919149)
			(xy 50.98669 -177.919634) (xy 50.959319 -177.91919) (xy 50.905138 -177.911369) (xy 50.852634 -177.895876)
			(xy 50.802888 -177.873029) (xy 50.756922 -177.843298) (xy 50.735992 -177.825654) (xy 50.724664 -177.816418)
			(xy 50.698107 -177.804242) (xy 50.66919 -177.800069) (xy 50.640273 -177.804242) (xy 50.613716 -177.816418)
			(xy 50.602388 -177.825654) (xy 50.581428 -177.843258) (xy 50.535463 -177.872977) (xy 50.485723 -177.89582)
			(xy 50.433228 -177.911319) (xy 50.379057 -177.919156) (xy 50.35169 -177.919634) (xy 50.32444 -177.919132)
			(xy 50.270494 -177.911374) (xy 50.218201 -177.896019) (xy 50.168626 -177.873379) (xy 50.122776 -177.843914)
			(xy 50.081587 -177.808224) (xy 50.045896 -177.767036) (xy 50.016429 -177.721189) (xy 49.993786 -177.671614)
			(xy 49.978429 -177.619322) (xy 49.97067 -177.565376) (xy 49.970182 -177.538126) (xy 49.970663 -177.511891)
			(xy 49.977854 -177.459916) (xy 49.992105 -177.409419) (xy 50.013145 -177.361352) (xy 50.040578 -177.316625)
			(xy 50.073885 -177.276082) (xy 50.092864 -177.257964) (xy 50.100207 -177.250412) (xy 50.108638 -177.231137)
			(xy 50.108646 -177.210098) (xy 50.100228 -177.190817) (xy 50.092864 -177.183288) (xy 50.071528 -177.161952)
			(xy 50.063999 -177.15458) (xy 50.044714 -177.146149) (xy 50.023666 -177.146149) (xy 50.004381 -177.15458)
			(xy 49.996852 -177.161952) (xy 49.978741 -177.180941) (xy 49.938201 -177.214257) (xy 49.893474 -177.241698)
			(xy 49.845406 -177.262746) (xy 49.794905 -177.277002) (xy 49.742927 -177.284197) (xy 49.71669 -177.284634)
			(xy 49.689441 -177.284095) (xy 49.635498 -177.276338) (xy 49.583208 -177.260983) (xy 49.533636 -177.238343)
			(xy 49.48779 -177.208878) (xy 49.446604 -177.173189) (xy 49.410916 -177.132002) (xy 49.381452 -177.086155)
			(xy 49.358813 -177.036582) (xy 49.34346 -176.984292) (xy 49.335704 -176.930349) (xy 46.195279 -176.930349)
			(xy 47.96536 -178.70043) (xy 58.735214 -178.70043) (xy 59.361324 -178.07432) (xy 59.361324 -169.222166)
			(xy 59.319922 -169.214292) (xy 59.293086 -169.208713) (xy 59.24142 -169.190413) (xy 59.193168 -169.164415)
			(xy 59.149468 -169.131332) (xy 59.111352 -169.091944) (xy 59.07972 -169.047182) (xy 59.055319 -168.998103)
			(xy 59.038724 -168.945865) (xy 59.030328 -168.891702) (xy 59.030329 -168.836891) (xy 59.038726 -168.782728)
			(xy 59.055322 -168.73049) (xy 59.079724 -168.681411) (xy 59.111357 -168.63665) (xy 59.149474 -168.597263)
			(xy 59.193174 -168.564181) (xy 59.241427 -168.538184) (xy 59.293093 -168.519885) (xy 59.319922 -168.514268)
			(xy 59.361324 -168.506394) (xy 59.361324 -160.586166) (xy 59.319922 -160.578292) (xy 59.293083 -160.572718)
			(xy 59.241411 -160.554426) (xy 59.193153 -160.52843) (xy 59.149448 -160.495347) (xy 59.111331 -160.455955)
			(xy 59.0797 -160.411188) (xy 59.055304 -160.362102) (xy 59.038719 -160.309857) (xy 59.030337 -160.255687)
			(xy 59.029854 -160.22828) (xy 59.030428 -160.199251) (xy 59.039845 -160.141963) (xy 59.058427 -160.08696)
			(xy 59.085682 -160.035698) (xy 59.120889 -159.989533) (xy 59.141614 -159.9692) (xy 59.150518 -159.959518)
			(xy 59.163503 -159.936655) (xy 59.170217 -159.911233) (xy 59.170213 -159.884939) (xy 59.163492 -159.859519)
			(xy 59.1505 -159.836659) (xy 59.141614 -159.82696) (xy 59.120892 -159.806624) (xy 59.085686 -159.760463)
			(xy 59.058436 -159.709201) (xy 59.039864 -159.654197) (xy 59.030464 -159.596908) (xy 59.029854 -159.56788)
			(xy 59.030359 -159.540476) (xy 59.038756 -159.486314) (xy 59.05535 -159.434078) (xy 59.079748 -159.384999)
			(xy 59.111376 -159.340236) (xy 59.149486 -159.300846) (xy 59.19318 -159.267757) (xy 59.241426 -159.241751)
			(xy 59.293086 -159.22344) (xy 59.319922 -159.217868) (xy 59.361324 -159.209994) (xy 59.361324 -151.950166)
			(xy 59.319922 -151.942292) (xy 59.293083 -151.936718) (xy 59.241411 -151.918426) (xy 59.193153 -151.89243)
			(xy 59.149448 -151.859347) (xy 59.111331 -151.819955) (xy 59.0797 -151.775188) (xy 59.055304 -151.726102)
			(xy 59.038719 -151.673857) (xy 59.030337 -151.619687) (xy 59.029854 -151.59228) (xy 59.030428 -151.563251)
			(xy 59.039845 -151.505963) (xy 59.058427 -151.45096) (xy 59.085682 -151.399698) (xy 59.120889 -151.353533)
			(xy 59.141614 -151.3332) (xy 59.150518 -151.323518) (xy 59.163503 -151.300655) (xy 59.170217 -151.275233)
			(xy 59.170213 -151.248939) (xy 59.163492 -151.223519) (xy 59.1505 -151.200659) (xy 59.141614 -151.19096)
			(xy 59.120892 -151.170624) (xy 59.085686 -151.124463) (xy 59.058436 -151.073201) (xy 59.039864 -151.018197)
			(xy 59.030464 -150.960908) (xy 59.029854 -150.93188) (xy 59.030359 -150.904476) (xy 59.038756 -150.850314)
			(xy 59.05535 -150.798078) (xy 59.079748 -150.748999) (xy 59.111376 -150.704236) (xy 59.149486 -150.664846)
			(xy 59.19318 -150.631757) (xy 59.241426 -150.605751) (xy 59.293086 -150.58744) (xy 59.319922 -150.581868)
			(xy 59.361324 -150.573994) (xy 59.361324 -143.321024) (xy 51.015392 -134.975092) (xy 42.5196 -134.975092)
			(xy 41.2242 -133.679692) (xy 41.2242 -133.447536) (xy 38.927024 -133.447536) (xy 38.897906 -133.447075)
			(xy 38.840169 -133.439463) (xy 38.78392 -133.424378) (xy 38.730122 -133.402079) (xy 38.679696 -133.372947)
			(xy 38.633504 -133.337482) (xy 38.612572 -133.317234) (xy 37.659564 -132.364226) (xy 37.639292 -132.343308)
			(xy 37.603799 -132.297119) (xy 37.574635 -132.246694) (xy 37.552298 -132.192896) (xy 37.53717 -132.136644)
			(xy 37.52951 -132.078899) (xy 37.529008 -132.049774) (xy 37.529008 -132.045456) (xy 37.529602 -132.019667)
			(xy 37.536014 -131.968479) (xy 37.548305 -131.918378) (xy 37.556948 -131.894072) (xy 37.557202 -131.893564)
			(xy 37.568839 -131.864109) (xy 37.599258 -131.808563) (xy 37.637255 -131.757897) (xy 37.682061 -131.71314)
			(xy 37.732767 -131.675198) (xy 37.788346 -131.644839) (xy 37.817806 -131.633214) (xy 37.842738 -131.624283)
			(xy 37.894192 -131.611737) (xy 37.946774 -131.605411) (xy 37.973254 -131.60502) (xy 37.974016 -131.60502)
			(xy 38.003136 -131.605477) (xy 38.060877 -131.613082) (xy 38.117132 -131.62816) (xy 38.170936 -131.650452)
			(xy 38.22137 -131.679577) (xy 38.267571 -131.715037) (xy 38.288468 -131.735322) (xy 38.787578 -132.234178)
			(xy 38.797738 -132.244338) (xy 38.807865 -132.253816) (xy 38.832018 -132.26743) (xy 38.858948 -132.274028)
			(xy 38.886658 -132.27312) (xy 38.913098 -132.264775) (xy 38.936309 -132.24961) (xy 38.94582 -132.239512)
			(xy 38.967019 -132.216189) (xy 39.014864 -132.175164) (xy 39.068021 -132.141304) (xy 39.125426 -132.115286)
			(xy 39.185929 -132.097633) (xy 39.248318 -132.088698) (xy 39.27983 -132.088128) (xy 40.931338 -132.088128)
			(xy 40.946329 -132.087591) (xy 40.975017 -132.07888) (xy 40.999943 -132.062219) (xy 41.018962 -132.039042)
			(xy 41.030437 -132.011342) (xy 41.03338 -131.981505) (xy 41.027538 -131.952098) (xy 41.013414 -131.925652)
			(xy 41.00322 -131.914646) (xy 40.990012 -131.901438) (xy 40.325548 -131.23672) (xy 40.305273 -131.215803)
			(xy 40.269775 -131.169616) (xy 40.240605 -131.119193) (xy 40.218265 -131.065394) (xy 40.203134 -131.009141)
			(xy 40.195473 -130.951394) (xy 40.194992 -130.922268) (xy 40.194992 -129.553208) (xy 40.195511 -129.522804)
			(xy 40.203791 -129.462563) (xy 40.220196 -129.40401) (xy 40.244422 -129.348236) (xy 40.276017 -129.296281)
			(xy 40.314392 -129.249111) (xy 40.358833 -129.207607) (xy 40.408511 -129.17254) (xy 40.462501 -129.144565)
			(xy 40.519798 -129.124201) (xy 40.579334 -129.11183) (xy 40.64 -129.10768) (xy 40.700666 -129.11183)
			(xy 40.760202 -129.124201) (xy 40.817499 -129.144565) (xy 40.871489 -129.17254) (xy 40.921167 -129.207607)
			(xy 40.965608 -129.249111) (xy 41.003983 -129.296281) (xy 41.035578 -129.348236) (xy 41.059804 -129.40401)
			(xy 41.076209 -129.462563) (xy 41.084489 -129.522804) (xy 41.085008 -129.553208) (xy 41.085008 -129.82067)
			(xy 41.0854 -129.829881) (xy 41.091918 -129.847111) (xy 41.104119 -129.860912) (xy 41.120419 -129.869494)
			(xy 41.138703 -129.871743) (xy 41.147746 -129.869946) (xy 41.159684 -129.867152) (xy 41.16578 -129.86385)
			(xy 41.174278 -129.859252) (xy 41.191686 -129.850865) (xy 41.200578 -129.847086) (xy 41.2242 -129.836672)
			(xy 41.2242 -128.253744) (xy 41.22372 -128.240135) (xy 41.21644 -128.213905) (xy 41.202494 -128.190527)
			(xy 41.18287 -128.171662) (xy 41.158961 -128.158648) (xy 41.132464 -128.152408) (xy 41.10526 -128.153386)
			(xy 41.09212 -128.15697) (xy 41.062675 -128.167013) (xy 41.001536 -128.1785) (xy 40.970454 -128.17983)
			(xy 40.95877 -128.17983) (xy 40.931659 -128.179139) (xy 40.878035 -128.171033) (xy 40.8261 -128.155416)
			(xy 40.7769 -128.132603) (xy 40.731426 -128.103053) (xy 40.690594 -128.067361) (xy 40.655227 -128.026247)
			(xy 40.626039 -127.98054) (xy 40.603617 -127.931159) (xy 40.588413 -127.879102) (xy 40.580734 -127.825416)
			(xy 40.580734 -127.771184) (xy 40.588413 -127.717498) (xy 40.603617 -127.665441) (xy 40.626039 -127.616061)
			(xy 40.655227 -127.570353) (xy 40.690594 -127.529239) (xy 40.731425 -127.493547) (xy 40.7769 -127.463997)
			(xy 40.8261 -127.441184) (xy 40.878035 -127.425567) (xy 40.931658 -127.417461) (xy 40.95877 -127.416814)
			(xy 40.962326 -127.416814) (xy 40.995461 -127.417546) (xy 41.060728 -127.429041) (xy 41.09212 -127.439674)
			(xy 41.105245 -127.443347) (xy 41.13247 -127.444355) (xy 41.158991 -127.438123) (xy 41.182918 -127.425096)
			(xy 41.202544 -127.406201) (xy 41.216472 -127.382787) (xy 41.223707 -127.356521) (xy 41.2242 -127.3429)
			(xy 41.2242 -126.29134) (xy 40.703754 -124.691902) (xy 37.6174 -121.605548) (xy 35.46094 -121.605548)
			(xy 35.447391 -121.605997) (xy 35.42126 -121.613179) (xy 35.397946 -121.626993) (xy 35.379095 -121.646463)
			(xy 35.366041 -121.670211) (xy 35.359707 -121.69656) (xy 35.360539 -121.723647) (xy 35.36848 -121.749557)
			(xy 35.375342 -121.76125) (xy 35.380168 -121.768616) (xy 35.382962 -121.772934) (xy 35.387788 -121.780554)
			(xy 35.401073 -121.803005) (xy 35.422054 -121.850765) (xy 35.43633 -121.90094) (xy 35.443634 -121.952593)
			(xy 35.444176 -121.978674) (xy 35.444176 -121.985786) (xy 35.443266 -122.014075) (xy 35.434123 -122.06993)
			(xy 35.416829 -122.123822) (xy 35.391764 -122.174568) (xy 35.359478 -122.221054) (xy 35.320678 -122.262261)
			(xy 35.276217 -122.297283) (xy 35.22707 -122.325354) (xy 35.174315 -122.345856) (xy 35.119111 -122.35834)
			(xy 35.062668 -122.362532) (xy 35.006225 -122.35834) (xy 34.951021 -122.345856) (xy 34.898266 -122.325354)
			(xy 34.849119 -122.297283) (xy 34.804658 -122.262261) (xy 34.765858 -122.221054) (xy 34.733572 -122.174568)
			(xy 34.708507 -122.123822) (xy 34.691213 -122.06993) (xy 34.68207 -122.014075) (xy 34.68116 -121.985786)
			(xy 34.68116 -121.979944) (xy 34.681692 -121.951313) (xy 34.69029 -121.894698) (xy 34.707254 -121.840005)
			(xy 34.732203 -121.788462) (xy 34.747962 -121.764552) (xy 34.755383 -121.752908) (xy 34.764315 -121.726794)
			(xy 34.765929 -121.699241) (xy 34.760107 -121.672263) (xy 34.747273 -121.647828) (xy 34.728366 -121.627722)
			(xy 34.704765 -121.613413) (xy 34.678195 -121.605945) (xy 34.664396 -121.605548) (xy 34.137854 -121.605548)
			(xy 34.124303 -121.605995) (xy 34.098169 -121.613175) (xy 34.074851 -121.626989) (xy 34.055998 -121.646459)
			(xy 34.042942 -121.670209) (xy 34.036607 -121.696561) (xy 34.03744 -121.723651) (xy 34.045383 -121.749563)
			(xy 34.052256 -121.76125) (xy 34.057082 -121.768616) (xy 34.059876 -121.772934) (xy 34.064702 -121.780554)
			(xy 34.077989 -121.803004) (xy 34.098976 -121.850764) (xy 34.113255 -121.900939) (xy 34.12056 -121.952592)
			(xy 34.12109 -121.978674) (xy 34.12109 -121.985786) (xy 34.12018 -122.014075) (xy 34.111037 -122.06993)
			(xy 34.093743 -122.123822) (xy 34.068678 -122.174568) (xy 34.036392 -122.221054) (xy 33.997592 -122.262261)
			(xy 33.953131 -122.297283) (xy 33.903984 -122.325354) (xy 33.851229 -122.345856) (xy 33.796025 -122.35834)
			(xy 33.739582 -122.362532) (xy 33.683139 -122.35834) (xy 33.627935 -122.345856) (xy 33.57518 -122.325354)
			(xy 33.526033 -122.297283) (xy 33.481572 -122.262261) (xy 33.442772 -122.221054) (xy 33.410486 -122.174568)
			(xy 33.385421 -122.123822) (xy 33.368127 -122.06993) (xy 33.358984 -122.014075) (xy 33.358074 -121.985786)
			(xy 33.358074 -121.979944) (xy 33.358607 -121.951313) (xy 33.367205 -121.894699) (xy 33.38417 -121.840006)
			(xy 33.409119 -121.788464) (xy 33.424876 -121.764552) (xy 33.432296 -121.752908) (xy 33.441227 -121.726792)
			(xy 33.442841 -121.699239) (xy 33.437018 -121.67226) (xy 33.424185 -121.647825) (xy 33.405279 -121.627718)
			(xy 33.381679 -121.613406) (xy 33.355109 -121.605935) (xy 33.34131 -121.605548) (xy 31.684214 -121.605548)
			(xy 30.786324 -122.503438) (xy 30.76834 -122.520793) (xy 30.727928 -122.550194) (xy 30.683409 -122.572902)
			(xy 30.635882 -122.588355) (xy 30.586522 -122.596173) (xy 30.561534 -122.596656) (xy 27.102562 -122.596656)
			(xy 26.498784 -123.200414) (xy 29.125416 -123.200414) (xy 29.129487 -123.144792) (xy 29.141613 -123.090355)
			(xy 29.161536 -123.038264) (xy 29.188832 -122.989629) (xy 29.222918 -122.945486) (xy 29.263067 -122.906777)
			(xy 29.308425 -122.874326) (xy 29.358025 -122.848825) (xy 29.410809 -122.830818) (xy 29.465652 -122.820688)
			(xy 29.521386 -122.818651) (xy 29.576823 -122.824751) (xy 29.63078 -122.838857) (xy 29.682109 -122.860669)
			(xy 29.729715 -122.889723) (xy 29.772583 -122.925398) (xy 29.8098 -122.966935) (xy 29.840573 -123.013448)
			(xy 29.864245 -123.063945) (xy 29.880313 -123.117352) (xy 29.888433 -123.172528) (xy 29.888942 -123.200414)
			(xy 29.888433 -123.2283) (xy 29.880313 -123.283476) (xy 29.864245 -123.336883) (xy 29.840573 -123.38738)
			(xy 29.8098 -123.433893) (xy 29.772583 -123.47543) (xy 29.729715 -123.511105) (xy 29.682109 -123.540159)
			(xy 29.63078 -123.561971) (xy 29.576823 -123.576077) (xy 29.521386 -123.582177) (xy 29.465652 -123.58014)
			(xy 29.410809 -123.57001) (xy 29.358025 -123.552003) (xy 29.308425 -123.526502) (xy 29.263067 -123.494051)
			(xy 29.222918 -123.455342) (xy 29.188832 -123.411199) (xy 29.161536 -123.362564) (xy 29.141613 -123.310473)
			(xy 29.129487 -123.256036) (xy 29.125416 -123.200414) (xy 26.498784 -123.200414) (xy 25.796197 -123.902978)
			(xy 26.902408 -123.902978) (xy 26.906479 -123.847356) (xy 26.918605 -123.792919) (xy 26.938528 -123.740828)
			(xy 26.965824 -123.692193) (xy 26.99991 -123.64805) (xy 27.040059 -123.609341) (xy 27.085417 -123.57689)
			(xy 27.135017 -123.551389) (xy 27.187801 -123.533382) (xy 27.242644 -123.523252) (xy 27.298378 -123.521215)
			(xy 27.353815 -123.527315) (xy 27.407772 -123.541421) (xy 27.459101 -123.563233) (xy 27.506707 -123.592287)
			(xy 27.549575 -123.627962) (xy 27.552247 -123.630944) (xy 31.385762 -123.630944) (xy 31.389833 -123.575322)
			(xy 31.401959 -123.520885) (xy 31.421882 -123.468794) (xy 31.449178 -123.420159) (xy 31.483264 -123.376016)
			(xy 31.523413 -123.337307) (xy 31.568771 -123.304856) (xy 31.618371 -123.279355) (xy 31.671155 -123.261348)
			(xy 31.725998 -123.251218) (xy 31.781732 -123.249181) (xy 31.837169 -123.255281) (xy 31.891126 -123.269387)
			(xy 31.942455 -123.291199) (xy 31.990061 -123.320253) (xy 32.032929 -123.355928) (xy 32.070146 -123.397465)
			(xy 32.100919 -123.443978) (xy 32.124591 -123.494475) (xy 32.140659 -123.547882) (xy 32.148779 -123.603058)
			(xy 32.149288 -123.630944) (xy 32.148779 -123.65883) (xy 32.140659 -123.714006) (xy 32.124591 -123.767413)
			(xy 32.100919 -123.81791) (xy 32.070146 -123.864423) (xy 32.032929 -123.90596) (xy 32.031934 -123.906788)
			(xy 32.966912 -123.906788) (xy 32.970983 -123.851166) (xy 32.983109 -123.796729) (xy 33.003032 -123.744638)
			(xy 33.030328 -123.696003) (xy 33.064414 -123.65186) (xy 33.104563 -123.613151) (xy 33.149921 -123.5807)
			(xy 33.199521 -123.555199) (xy 33.252305 -123.537192) (xy 33.307148 -123.527062) (xy 33.362882 -123.525025)
			(xy 33.418319 -123.531125) (xy 33.472276 -123.545231) (xy 33.523605 -123.567043) (xy 33.571211 -123.596097)
			(xy 33.614079 -123.631772) (xy 33.651296 -123.673309) (xy 33.682069 -123.719822) (xy 33.705741 -123.770319)
			(xy 33.721809 -123.823726) (xy 33.729929 -123.878902) (xy 33.730118 -123.889262) (xy 33.909506 -123.889262)
			(xy 33.913577 -123.83364) (xy 33.925703 -123.779203) (xy 33.945626 -123.727112) (xy 33.972922 -123.678477)
			(xy 34.007008 -123.634334) (xy 34.047157 -123.595625) (xy 34.092515 -123.563174) (xy 34.142115 -123.537673)
			(xy 34.194899 -123.519666) (xy 34.249742 -123.509536) (xy 34.305476 -123.507499) (xy 34.360913 -123.513599)
			(xy 34.41487 -123.527705) (xy 34.466199 -123.549517) (xy 34.513805 -123.578571) (xy 34.556673 -123.614246)
			(xy 34.59389 -123.655783) (xy 34.624663 -123.702296) (xy 34.648335 -123.752793) (xy 34.664403 -123.8062)
			(xy 34.672523 -123.861376) (xy 34.673032 -123.889262) (xy 34.672523 -123.917148) (xy 34.664403 -123.972324)
			(xy 34.648335 -124.025731) (xy 34.624911 -124.075698) (xy 37.74643 -124.075698) (xy 37.750503 -124.020039)
			(xy 37.762638 -123.965566) (xy 37.782574 -123.91344) (xy 37.809888 -123.864772) (xy 37.843996 -123.8206)
			(xy 37.884173 -123.781865) (xy 37.929561 -123.749393) (xy 37.979193 -123.723875) (xy 38.032013 -123.705856)
			(xy 38.086892 -123.695719) (xy 38.142663 -123.693681) (xy 38.198137 -123.699784) (xy 38.25213 -123.7139)
			(xy 38.303493 -123.735727) (xy 38.351131 -123.7648) (xy 38.394027 -123.800499) (xy 38.431269 -123.842063)
			(xy 38.462063 -123.888607) (xy 38.485751 -123.939138) (xy 38.501829 -123.99258) (xy 38.509955 -124.047794)
			(xy 38.510464 -124.075698) (xy 38.509955 -124.103602) (xy 38.501829 -124.158816) (xy 38.485751 -124.212258)
			(xy 38.462063 -124.262789) (xy 38.431269 -124.309333) (xy 38.394027 -124.350897) (xy 38.351131 -124.386596)
			(xy 38.303493 -124.415669) (xy 38.25213 -124.437496) (xy 38.198137 -124.451612) (xy 38.142663 -124.457715)
			(xy 38.086892 -124.455677) (xy 38.032013 -124.44554) (xy 37.979193 -124.427521) (xy 37.929561 -124.402003)
			(xy 37.884173 -124.369531) (xy 37.843996 -124.330796) (xy 37.809888 -124.286624) (xy 37.782574 -124.237956)
			(xy 37.762638 -124.18583) (xy 37.750503 -124.131357) (xy 37.74643 -124.075698) (xy 34.624911 -124.075698)
			(xy 34.624663 -124.076228) (xy 34.59389 -124.122741) (xy 34.556673 -124.164278) (xy 34.513805 -124.199953)
			(xy 34.466199 -124.229007) (xy 34.41487 -124.250819) (xy 34.360913 -124.264925) (xy 34.305476 -124.271025)
			(xy 34.249742 -124.268988) (xy 34.194899 -124.258858) (xy 34.142115 -124.240851) (xy 34.092515 -124.21535)
			(xy 34.047157 -124.182899) (xy 34.007008 -124.14419) (xy 33.972922 -124.100047) (xy 33.945626 -124.051412)
			(xy 33.925703 -123.999321) (xy 33.913577 -123.944884) (xy 33.909506 -123.889262) (xy 33.730118 -123.889262)
			(xy 33.730438 -123.906788) (xy 33.729929 -123.934674) (xy 33.721809 -123.98985) (xy 33.705741 -124.043257)
			(xy 33.682069 -124.093754) (xy 33.651296 -124.140267) (xy 33.614079 -124.181804) (xy 33.571211 -124.217479)
			(xy 33.523605 -124.246533) (xy 33.472276 -124.268345) (xy 33.418319 -124.282451) (xy 33.362882 -124.288551)
			(xy 33.307148 -124.286514) (xy 33.252305 -124.276384) (xy 33.199521 -124.258377) (xy 33.149921 -124.232876)
			(xy 33.104563 -124.200425) (xy 33.064414 -124.161716) (xy 33.030328 -124.117573) (xy 33.003032 -124.068938)
			(xy 32.983109 -124.016847) (xy 32.970983 -123.96241) (xy 32.966912 -123.906788) (xy 32.031934 -123.906788)
			(xy 31.990061 -123.941635) (xy 31.942455 -123.970689) (xy 31.891126 -123.992501) (xy 31.837169 -124.006607)
			(xy 31.781732 -124.012707) (xy 31.725998 -124.01067) (xy 31.671155 -124.00054) (xy 31.618371 -123.982533)
			(xy 31.568771 -123.957032) (xy 31.523413 -123.924581) (xy 31.483264 -123.885872) (xy 31.449178 -123.841729)
			(xy 31.421882 -123.793094) (xy 31.401959 -123.741003) (xy 31.389833 -123.686566) (xy 31.385762 -123.630944)
			(xy 27.552247 -123.630944) (xy 27.586792 -123.669499) (xy 27.617565 -123.716012) (xy 27.641237 -123.766509)
			(xy 27.657305 -123.819916) (xy 27.665425 -123.875092) (xy 27.665934 -123.902978) (xy 27.665425 -123.930864)
			(xy 27.657305 -123.98604) (xy 27.641237 -124.039447) (xy 27.617565 -124.089944) (xy 27.586792 -124.136457)
			(xy 27.549575 -124.177994) (xy 27.506707 -124.213669) (xy 27.459101 -124.242723) (xy 27.407772 -124.264535)
			(xy 27.353815 -124.278641) (xy 27.298378 -124.284741) (xy 27.242644 -124.282704) (xy 27.187801 -124.272574)
			(xy 27.135017 -124.254567) (xy 27.085417 -124.229066) (xy 27.040059 -124.196615) (xy 26.99991 -124.157906)
			(xy 26.965824 -124.113763) (xy 26.938528 -124.065128) (xy 26.918605 -124.013037) (xy 26.906479 -123.9586)
			(xy 26.902408 -123.902978) (xy 25.796197 -123.902978) (xy 24.990228 -124.70892) (xy 26.256232 -124.70892)
			(xy 26.260303 -124.653298) (xy 26.272429 -124.598861) (xy 26.292352 -124.54677) (xy 26.319648 -124.498135)
			(xy 26.353734 -124.453992) (xy 26.393883 -124.415283) (xy 26.439241 -124.382832) (xy 26.488841 -124.357331)
			(xy 26.541625 -124.339324) (xy 26.596468 -124.329194) (xy 26.652202 -124.327157) (xy 26.707639 -124.333257)
			(xy 26.761596 -124.347363) (xy 26.812925 -124.369175) (xy 26.860531 -124.398229) (xy 26.903399 -124.433904)
			(xy 26.940616 -124.475441) (xy 26.971389 -124.521954) (xy 26.995061 -124.572451) (xy 27.011129 -124.625858)
			(xy 27.019249 -124.681034) (xy 27.019758 -124.70892) (xy 27.019249 -124.736806) (xy 27.011129 -124.791982)
			(xy 26.995061 -124.845389) (xy 26.971389 -124.895886) (xy 26.952414 -124.924566) (xy 31.371284 -124.924566)
			(xy 31.375355 -124.868944) (xy 31.387481 -124.814507) (xy 31.407404 -124.762416) (xy 31.4347 -124.713781)
			(xy 31.468786 -124.669638) (xy 31.508935 -124.630929) (xy 31.554293 -124.598478) (xy 31.603893 -124.572977)
			(xy 31.656677 -124.55497) (xy 31.71152 -124.54484) (xy 31.767254 -124.542803) (xy 31.822691 -124.548903)
			(xy 31.876648 -124.563009) (xy 31.927977 -124.584821) (xy 31.975583 -124.613875) (xy 32.018451 -124.64955)
			(xy 32.055668 -124.691087) (xy 32.086441 -124.7376) (xy 32.110113 -124.788097) (xy 32.126181 -124.841504)
			(xy 32.134301 -124.89668) (xy 32.13481 -124.924566) (xy 32.134301 -124.952452) (xy 32.126181 -125.007628)
			(xy 32.110113 -125.061035) (xy 32.086441 -125.111532) (xy 32.055668 -125.158045) (xy 32.018451 -125.199582)
			(xy 31.975583 -125.235257) (xy 31.927977 -125.264311) (xy 31.876648 -125.286123) (xy 31.822691 -125.300229)
			(xy 31.767254 -125.306329) (xy 31.71152 -125.304292) (xy 31.656677 -125.294162) (xy 31.603893 -125.276155)
			(xy 31.554293 -125.250654) (xy 31.508935 -125.218203) (xy 31.468786 -125.179494) (xy 31.4347 -125.135351)
			(xy 31.407404 -125.086716) (xy 31.387481 -125.034625) (xy 31.375355 -124.980188) (xy 31.371284 -124.924566)
			(xy 26.952414 -124.924566) (xy 26.940616 -124.942399) (xy 26.903399 -124.983936) (xy 26.860531 -125.019611)
			(xy 26.812925 -125.048665) (xy 26.761596 -125.070477) (xy 26.707639 -125.084583) (xy 26.652202 -125.090683)
			(xy 26.596468 -125.088646) (xy 26.541625 -125.078516) (xy 26.488841 -125.060509) (xy 26.439241 -125.035008)
			(xy 26.393883 -125.002557) (xy 26.353734 -124.963848) (xy 26.319648 -124.919705) (xy 26.292352 -124.87107)
			(xy 26.272429 -124.818979) (xy 26.260303 -124.764542) (xy 26.256232 -124.70892) (xy 24.990228 -124.70892)
			(xy 23.744825 -125.954282) (xy 31.145478 -125.954282) (xy 31.149549 -125.89866) (xy 31.161675 -125.844223)
			(xy 31.181598 -125.792132) (xy 31.208894 -125.743497) (xy 31.24298 -125.699354) (xy 31.283129 -125.660645)
			(xy 31.328487 -125.628194) (xy 31.378087 -125.602693) (xy 31.430871 -125.584686) (xy 31.485714 -125.574556)
			(xy 31.541448 -125.572519) (xy 31.596885 -125.578619) (xy 31.650842 -125.592725) (xy 31.651379 -125.592953)
			(xy 37.60644 -125.592953) (xy 37.60644 -125.538447) (xy 37.614197 -125.484496) (xy 37.629552 -125.432198)
			(xy 37.652194 -125.382617) (xy 37.681661 -125.336763) (xy 37.717354 -125.295569) (xy 37.758545 -125.259874)
			(xy 37.804398 -125.230404) (xy 37.853977 -125.20776) (xy 37.906274 -125.192401) (xy 37.960225 -125.184641)
			(xy 37.987478 -125.184154) (xy 38.014784 -125.184653) (xy 38.068836 -125.192463) (xy 38.121222 -125.207899)
			(xy 38.170873 -125.230644) (xy 38.216775 -125.260235) (xy 38.257989 -125.296067) (xy 38.293675 -125.337409)
			(xy 38.323104 -125.383415) (xy 38.345673 -125.433146) (xy 38.353746 -125.459236) (xy 38.358068 -125.472334)
			(xy 38.372585 -125.495772) (xy 38.392846 -125.514469) (xy 38.417371 -125.527061) (xy 38.444372 -125.53263)
			(xy 38.471878 -125.530769) (xy 38.497883 -125.521615) (xy 38.509448 -125.5141) (xy 38.533577 -125.497991)
			(xy 38.58567 -125.472456) (xy 38.641027 -125.455098) (xy 38.698373 -125.446316) (xy 38.72738 -125.445774)
			(xy 38.754633 -125.446272) (xy 38.808583 -125.454026) (xy 38.860881 -125.46938) (xy 38.910461 -125.49202)
			(xy 38.956315 -125.521486) (xy 38.997508 -125.557178) (xy 39.033202 -125.598369) (xy 39.06267 -125.644221)
			(xy 39.085313 -125.6938) (xy 39.10067 -125.746097) (xy 39.108427 -125.800048) (xy 39.108427 -125.854552)
			(xy 39.10067 -125.908503) (xy 39.085313 -125.9608) (xy 39.06267 -126.010379) (xy 39.033202 -126.056231)
			(xy 38.997508 -126.097422) (xy 38.956315 -126.133114) (xy 38.910461 -126.16258) (xy 38.860881 -126.18522)
			(xy 38.808583 -126.200574) (xy 38.754633 -126.208328) (xy 38.72738 -126.20879) (xy 38.700074 -126.208297)
			(xy 38.646024 -126.200482) (xy 38.593639 -126.185043) (xy 38.543989 -126.162295) (xy 38.498089 -126.132703)
			(xy 38.456875 -126.096871) (xy 38.421189 -126.055531) (xy 38.391759 -126.009527) (xy 38.369187 -125.959797)
			(xy 38.361112 -125.933708) (xy 38.356831 -125.920593) (xy 38.342313 -125.897145) (xy 38.322046 -125.87844)
			(xy 38.297511 -125.865846) (xy 38.2705 -125.86028) (xy 38.242985 -125.862151) (xy 38.216975 -125.87132)
			(xy 38.20541 -125.878844) (xy 38.181288 -125.894965) (xy 38.129193 -125.920499) (xy 38.073834 -125.937854)
			(xy 38.016486 -125.946631) (xy 37.987478 -125.94717) (xy 37.960225 -125.946759) (xy 37.906274 -125.938999)
			(xy 37.853977 -125.92364) (xy 37.804398 -125.900996) (xy 37.758545 -125.871526) (xy 37.717354 -125.835831)
			(xy 37.681661 -125.794637) (xy 37.652194 -125.748783) (xy 37.629552 -125.699202) (xy 37.614197 -125.646904)
			(xy 37.60644 -125.592953) (xy 31.651379 -125.592953) (xy 31.702171 -125.614537) (xy 31.749777 -125.643591)
			(xy 31.792645 -125.679266) (xy 31.829862 -125.720803) (xy 31.860635 -125.767316) (xy 31.884307 -125.817813)
			(xy 31.900375 -125.87122) (xy 31.908495 -125.926396) (xy 31.909004 -125.954282) (xy 31.908495 -125.982168)
			(xy 31.900375 -126.037344) (xy 31.893881 -126.05893) (xy 33.07918 -126.05893) (xy 33.083251 -126.003308)
			(xy 33.095377 -125.948871) (xy 33.1153 -125.89678) (xy 33.142596 -125.848145) (xy 33.176682 -125.804002)
			(xy 33.216831 -125.765293) (xy 33.262189 -125.732842) (xy 33.311789 -125.707341) (xy 33.364573 -125.689334)
			(xy 33.419416 -125.679204) (xy 33.47515 -125.677167) (xy 33.530587 -125.683267) (xy 33.584544 -125.697373)
			(xy 33.635873 -125.719185) (xy 33.683479 -125.748239) (xy 33.726347 -125.783914) (xy 33.763564 -125.825451)
			(xy 33.794337 -125.871964) (xy 33.818009 -125.922461) (xy 33.834077 -125.975868) (xy 33.842197 -126.031044)
			(xy 33.842706 -126.05893) (xy 33.842197 -126.086816) (xy 33.834077 -126.141992) (xy 33.818009 -126.195399)
			(xy 33.794337 -126.245896) (xy 33.784437 -126.26086) (xy 34.41141 -126.26086) (xy 34.415481 -126.205238)
			(xy 34.427607 -126.150801) (xy 34.44753 -126.09871) (xy 34.474826 -126.050075) (xy 34.508912 -126.005932)
			(xy 34.549061 -125.967223) (xy 34.594419 -125.934772) (xy 34.644019 -125.909271) (xy 34.696803 -125.891264)
			(xy 34.751646 -125.881134) (xy 34.80738 -125.879097) (xy 34.862817 -125.885197) (xy 34.916774 -125.899303)
			(xy 34.968103 -125.921115) (xy 35.015709 -125.950169) (xy 35.058577 -125.985844) (xy 35.095794 -126.027381)
			(xy 35.126567 -126.073894) (xy 35.150239 -126.124391) (xy 35.166307 -126.177798) (xy 35.174427 -126.232974)
			(xy 35.174936 -126.26086) (xy 35.174427 -126.288746) (xy 35.166307 -126.343922) (xy 35.150239 -126.397329)
			(xy 35.126567 -126.447826) (xy 35.095794 -126.494339) (xy 35.058577 -126.535876) (xy 35.015709 -126.571551)
			(xy 34.968103 -126.600605) (xy 34.916774 -126.622417) (xy 34.862817 -126.636523) (xy 34.80738 -126.642623)
			(xy 34.751646 -126.640586) (xy 34.696803 -126.630456) (xy 34.644019 -126.612449) (xy 34.594419 -126.586948)
			(xy 34.549061 -126.554497) (xy 34.508912 -126.515788) (xy 34.474826 -126.471645) (xy 34.44753 -126.42301)
			(xy 34.427607 -126.370919) (xy 34.415481 -126.316482) (xy 34.41141 -126.26086) (xy 33.784437 -126.26086)
			(xy 33.763564 -126.292409) (xy 33.726347 -126.333946) (xy 33.683479 -126.369621) (xy 33.635873 -126.398675)
			(xy 33.584544 -126.420487) (xy 33.530587 -126.434593) (xy 33.47515 -126.440693) (xy 33.419416 -126.438656)
			(xy 33.364573 -126.428526) (xy 33.311789 -126.410519) (xy 33.262189 -126.385018) (xy 33.216831 -126.352567)
			(xy 33.176682 -126.313858) (xy 33.142596 -126.269715) (xy 33.1153 -126.22108) (xy 33.095377 -126.168989)
			(xy 33.083251 -126.114552) (xy 33.07918 -126.05893) (xy 31.893881 -126.05893) (xy 31.884307 -126.090751)
			(xy 31.860635 -126.141248) (xy 31.829862 -126.187761) (xy 31.792645 -126.229298) (xy 31.749777 -126.264973)
			(xy 31.702171 -126.294027) (xy 31.650842 -126.315839) (xy 31.596885 -126.329945) (xy 31.541448 -126.336045)
			(xy 31.485714 -126.334008) (xy 31.430871 -126.323878) (xy 31.378087 -126.305871) (xy 31.328487 -126.28037)
			(xy 31.283129 -126.247919) (xy 31.24298 -126.20921) (xy 31.208894 -126.165067) (xy 31.181598 -126.116432)
			(xy 31.161675 -126.064341) (xy 31.149549 -126.009904) (xy 31.145478 -125.954282) (xy 23.744825 -125.954282)
			(xy 23.138253 -126.560834) (xy 27.732988 -126.560834) (xy 27.737059 -126.505212) (xy 27.749185 -126.450775)
			(xy 27.769108 -126.398684) (xy 27.796404 -126.350049) (xy 27.83049 -126.305906) (xy 27.870639 -126.267197)
			(xy 27.915997 -126.234746) (xy 27.965597 -126.209245) (xy 28.018381 -126.191238) (xy 28.073224 -126.181108)
			(xy 28.128958 -126.179071) (xy 28.184395 -126.185171) (xy 28.238352 -126.199277) (xy 28.289681 -126.221089)
			(xy 28.337287 -126.250143) (xy 28.380155 -126.285818) (xy 28.417372 -126.327355) (xy 28.448145 -126.373868)
			(xy 28.471817 -126.424365) (xy 28.487885 -126.477772) (xy 28.496005 -126.532948) (xy 28.496514 -126.560834)
			(xy 28.496005 -126.58872) (xy 28.487885 -126.643896) (xy 28.471817 -126.697303) (xy 28.448145 -126.7478)
			(xy 28.417372 -126.794313) (xy 28.380155 -126.83585) (xy 28.337287 -126.871525) (xy 28.289681 -126.900579)
			(xy 28.238352 -126.922391) (xy 28.184395 -126.936497) (xy 28.128958 -126.942597) (xy 28.073224 -126.94056)
			(xy 28.018381 -126.93043) (xy 27.965597 -126.912423) (xy 27.915997 -126.886922) (xy 27.870639 -126.854471)
			(xy 27.83049 -126.815762) (xy 27.796404 -126.771619) (xy 27.769108 -126.722984) (xy 27.749185 -126.670893)
			(xy 27.737059 -126.616456) (xy 27.732988 -126.560834) (xy 23.138253 -126.560834) (xy 21.306771 -128.392255)
			(xy 25.624451 -128.392255) (xy 25.624451 -128.337745) (xy 25.632209 -128.283791) (xy 25.647567 -128.231489)
			(xy 25.670213 -128.181906) (xy 25.699684 -128.136051) (xy 25.735382 -128.094857) (xy 25.77658 -128.059163)
			(xy 25.822438 -128.029696) (xy 25.872023 -128.007055) (xy 25.924326 -127.991702) (xy 25.978281 -127.983949)
			(xy 26.005536 -127.983488) (xy 26.032292 -127.983992) (xy 26.085278 -127.991474) (xy 26.136699 -128.006285)
			(xy 26.185546 -128.028136) (xy 26.230861 -128.056598) (xy 26.271755 -128.091112) (xy 26.307425 -128.131001)
			(xy 26.337172 -128.175483) (xy 26.349198 -128.199388) (xy 26.355493 -128.211541) (xy 26.373493 -128.23215)
			(xy 26.396314 -128.247247) (xy 26.422322 -128.255749) (xy 26.449654 -128.257049) (xy 26.476351 -128.251053)
			(xy 26.500502 -128.23819) (xy 26.510742 -128.229106) (xy 26.526998 -128.213612) (xy 26.543486 -128.197241)
			(xy 26.570089 -128.159155) (xy 26.588454 -128.116481) (xy 26.597824 -128.070979) (xy 26.598372 -128.04775)
			(xy 26.598372 -127.625094) (xy 27.281124 -126.942596) (xy 27.281124 -126.942342) (xy 27.296597 -126.927626)
			(xy 27.33186 -126.903557) (xy 27.370969 -126.886434) (xy 27.412572 -126.876847) (xy 27.455232 -126.875129)
			(xy 27.497471 -126.88134) (xy 27.537831 -126.895263) (xy 27.574915 -126.916418) (xy 27.60744 -126.944074)
			(xy 27.62123 -126.960376) (xy 27.64383 -126.987581) (xy 27.694144 -127.03729) (xy 27.749669 -127.081102)
			(xy 27.809719 -127.118473) (xy 27.873549 -127.14894) (xy 27.940369 -127.172127) (xy 28.009351 -127.187746)
			(xy 28.079642 -127.195604) (xy 28.115006 -127.196088) (xy 28.150652 -127.19556) (xy 28.221496 -127.187578)
			(xy 28.291 -127.171714) (xy 28.358291 -127.148168) (xy 28.422523 -127.117236) (xy 28.482888 -127.079307)
			(xy 28.538627 -127.034858) (xy 28.58904 -126.984448) (xy 28.633491 -126.928711) (xy 28.671422 -126.868348)
			(xy 28.702357 -126.804117) (xy 28.725906 -126.736827) (xy 28.741773 -126.667323) (xy 28.749759 -126.59648)
			(xy 28.75026 -126.560834) (xy 28.749784 -126.526901) (xy 28.742492 -126.459426) (xy 28.72803 -126.393118)
			(xy 28.706565 -126.328734) (xy 28.692856 -126.29769) (xy 28.684673 -126.278548) (xy 28.674575 -126.238167)
			(xy 28.671935 -126.196627) (xy 28.67684 -126.155293) (xy 28.689129 -126.115524) (xy 28.708398 -126.078628)
			(xy 28.734012 -126.045818) (xy 28.76513 -126.018173) (xy 28.800729 -125.996602) (xy 28.839638 -125.981814)
			(xy 28.880578 -125.974296) (xy 28.90139 -125.97384) (xy 29.621734 -125.97384) (xy 29.711396 -126.063756)
			(xy 29.720286 -126.067566) (xy 29.746406 -126.079481) (xy 29.795052 -126.109964) (xy 29.838582 -126.147392)
			(xy 29.876014 -126.190918) (xy 29.906502 -126.239561) (xy 29.918406 -126.265686) (xy 29.922216 -126.274576)
			(xy 29.997908 -126.350014) (xy 29.997908 -126.69774) (xy 35.487862 -126.69774) (xy 35.491933 -126.642118)
			(xy 35.504059 -126.587681) (xy 35.523982 -126.53559) (xy 35.551278 -126.486955) (xy 35.585364 -126.442812)
			(xy 35.625513 -126.404103) (xy 35.670871 -126.371652) (xy 35.720471 -126.346151) (xy 35.773255 -126.328144)
			(xy 35.828098 -126.318014) (xy 35.883832 -126.315977) (xy 35.939269 -126.322077) (xy 35.993226 -126.336183)
			(xy 36.044555 -126.357995) (xy 36.092161 -126.387049) (xy 36.135029 -126.422724) (xy 36.172246 -126.464261)
			(xy 36.203019 -126.510774) (xy 36.226691 -126.561271) (xy 36.242759 -126.614678) (xy 36.250879 -126.669854)
			(xy 36.251388 -126.69774) (xy 36.250879 -126.725626) (xy 36.242759 -126.780802) (xy 36.226691 -126.834209)
			(xy 36.203019 -126.884706) (xy 36.172246 -126.931219) (xy 36.135029 -126.972756) (xy 36.092161 -127.008431)
			(xy 36.044555 -127.037485) (xy 35.993226 -127.059297) (xy 35.939269 -127.073403) (xy 35.883832 -127.079503)
			(xy 35.828098 -127.077466) (xy 35.773255 -127.067336) (xy 35.720471 -127.049329) (xy 35.670871 -127.023828)
			(xy 35.625513 -126.991377) (xy 35.585364 -126.952668) (xy 35.551278 -126.908525) (xy 35.523982 -126.85989)
			(xy 35.504059 -126.807799) (xy 35.491933 -126.753362) (xy 35.487862 -126.69774) (xy 29.997908 -126.69774)
			(xy 29.997908 -127.966724) (xy 35.514532 -127.966724) (xy 35.518603 -127.911102) (xy 35.530729 -127.856665)
			(xy 35.550652 -127.804574) (xy 35.577948 -127.755939) (xy 35.612034 -127.711796) (xy 35.652183 -127.673087)
			(xy 35.697541 -127.640636) (xy 35.747141 -127.615135) (xy 35.799925 -127.597128) (xy 35.854768 -127.586998)
			(xy 35.910502 -127.584961) (xy 35.965939 -127.591061) (xy 36.019896 -127.605167) (xy 36.071225 -127.626979)
			(xy 36.118831 -127.656033) (xy 36.161699 -127.691708) (xy 36.198916 -127.733245) (xy 36.229689 -127.779758)
			(xy 36.253361 -127.830255) (xy 36.269429 -127.883662) (xy 36.277549 -127.938838) (xy 36.278058 -127.966724)
			(xy 36.277549 -127.99461) (xy 36.269429 -128.049786) (xy 36.253361 -128.103193) (xy 36.229689 -128.15369)
			(xy 36.198916 -128.200203) (xy 36.161699 -128.24174) (xy 36.118831 -128.277415) (xy 36.071225 -128.306469)
			(xy 36.019896 -128.328281) (xy 35.965939 -128.342387) (xy 35.910502 -128.348487) (xy 35.854768 -128.34645)
			(xy 35.799925 -128.33632) (xy 35.747141 -128.318313) (xy 35.697541 -128.292812) (xy 35.652183 -128.260361)
			(xy 35.612034 -128.221652) (xy 35.577948 -128.177509) (xy 35.550652 -128.128874) (xy 35.530729 -128.076783)
			(xy 35.518603 -128.022346) (xy 35.514532 -127.966724) (xy 29.997908 -127.966724) (xy 29.997908 -128.898257)
			(xy 34.774519 -128.898257) (xy 34.774519 -128.843743) (xy 34.782278 -128.789784) (xy 34.797637 -128.737479)
			(xy 34.820284 -128.687892) (xy 34.849757 -128.642033) (xy 34.885458 -128.600835) (xy 34.926658 -128.565138)
			(xy 34.97252 -128.535668) (xy 35.022109 -128.513025) (xy 35.074416 -128.497671) (xy 35.128375 -128.489917)
			(xy 35.155632 -128.489456) (xy 35.183235 -128.48994) (xy 35.237867 -128.497876) (xy 35.290784 -128.513608)
			(xy 35.340879 -128.536805) (xy 35.387106 -128.566983) (xy 35.428498 -128.603512) (xy 35.46419 -128.645628)
			(xy 35.479228 -128.66878) (xy 35.486745 -128.680134) (xy 35.506723 -128.698627) (xy 35.530881 -128.711177)
			(xy 35.557498 -128.716889) (xy 35.584678 -128.715357) (xy 35.610485 -128.70669) (xy 35.633079 -128.691506)
			(xy 35.642296 -128.68148) (xy 35.660491 -128.661057) (xy 35.701733 -128.625128) (xy 35.747683 -128.595458)
			(xy 35.7974 -128.572655) (xy 35.849864 -128.557185) (xy 35.904 -128.549366) (xy 35.931348 -128.548892)
			(xy 35.9586 -128.549333) (xy 36.01255 -128.557096) (xy 36.064845 -128.572457) (xy 36.114423 -128.595104)
			(xy 36.160273 -128.624575) (xy 36.201463 -128.660271) (xy 36.237153 -128.701466) (xy 36.255322 -128.72974)
			(xy 37.58387 -128.72974) (xy 37.587941 -128.674118) (xy 37.600067 -128.619681) (xy 37.61999 -128.56759)
			(xy 37.647286 -128.518955) (xy 37.681372 -128.474812) (xy 37.721521 -128.436103) (xy 37.766879 -128.403652)
			(xy 37.816479 -128.378151) (xy 37.869263 -128.360144) (xy 37.924106 -128.350014) (xy 37.97984 -128.347977)
			(xy 38.035277 -128.354077) (xy 38.089234 -128.368183) (xy 38.140563 -128.389995) (xy 38.188169 -128.419049)
			(xy 38.231037 -128.454724) (xy 38.268254 -128.496261) (xy 38.299027 -128.542774) (xy 38.322699 -128.593271)
			(xy 38.338767 -128.646678) (xy 38.346887 -128.701854) (xy 38.347396 -128.72974) (xy 38.346887 -128.757626)
			(xy 38.338767 -128.812802) (xy 38.322699 -128.866209) (xy 38.299027 -128.916706) (xy 38.268254 -128.963219)
			(xy 38.231037 -129.004756) (xy 38.188169 -129.040431) (xy 38.140563 -129.069485) (xy 38.089234 -129.091297)
			(xy 38.035277 -129.105403) (xy 37.97984 -129.111503) (xy 37.924106 -129.109466) (xy 37.869263 -129.099336)
			(xy 37.816479 -129.081329) (xy 37.766879 -129.055828) (xy 37.721521 -129.023377) (xy 37.681372 -128.984668)
			(xy 37.647286 -128.940525) (xy 37.61999 -128.89189) (xy 37.600067 -128.839799) (xy 37.587941 -128.785362)
			(xy 37.58387 -128.72974) (xy 36.255322 -128.72974) (xy 36.266619 -128.747319) (xy 36.289259 -128.7969)
			(xy 36.304614 -128.849197) (xy 36.31237 -128.903148) (xy 36.312856 -128.9304) (xy 36.312354 -128.959318)
			(xy 36.303624 -129.01649) (xy 36.286364 -129.07169) (xy 36.260969 -129.123652) (xy 36.228022 -129.171186)
			(xy 36.188277 -129.213201) (xy 36.16579 -129.23139) (xy 36.154505 -129.240742) (xy 36.137427 -129.264546)
			(xy 36.127817 -129.292223) (xy 36.12647 -129.321489) (xy 36.133495 -129.349931) (xy 36.148314 -129.375205)
			(xy 36.158678 -129.385568) (xy 36.177306 -129.403687) (xy 36.210021 -129.444059) (xy 36.236951 -129.4885)
			(xy 36.257598 -129.536186) (xy 36.271578 -129.586234) (xy 36.278634 -129.637716) (xy 36.279074 -129.663698)
			(xy 36.278643 -129.690952) (xy 36.270885 -129.744906) (xy 36.255528 -129.797207) (xy 36.232883 -129.846789)
			(xy 36.203412 -129.892644) (xy 36.167715 -129.933837) (xy 36.126518 -129.969531) (xy 36.080661 -129.998998)
			(xy 36.031077 -130.021639) (xy 35.978775 -130.036992) (xy 35.92482 -130.044745) (xy 35.897566 -130.045206)
			(xy 35.868794 -130.044675) (xy 35.811906 -130.035999) (xy 35.784282 -130.027934) (xy 35.770239 -130.023972)
			(xy 35.741071 -130.023495) (xy 35.712955 -130.031276) (xy 35.688183 -130.046681) (xy 35.66877 -130.068456)
			(xy 35.656298 -130.094827) (xy 35.651782 -130.123647) (xy 35.653218 -130.13817) (xy 35.654756 -130.150495)
			(xy 35.656405 -130.17528) (xy 35.65652 -130.1877) (xy 35.656045 -130.214953) (xy 35.648288 -130.268904)
			(xy 35.632931 -130.321202) (xy 35.610289 -130.370783) (xy 35.58082 -130.416636) (xy 35.545126 -130.457829)
			(xy 35.503933 -130.493523) (xy 35.458079 -130.52299) (xy 35.408499 -130.545633) (xy 35.3562 -130.560988)
			(xy 35.302249 -130.568745) (xy 35.247743 -130.568744) (xy 35.193792 -130.560987) (xy 35.141494 -130.54563)
			(xy 35.091914 -130.522987) (xy 35.046061 -130.493518) (xy 35.004868 -130.457823) (xy 34.969175 -130.41663)
			(xy 34.939708 -130.370776) (xy 34.917066 -130.321195) (xy 34.901711 -130.268896) (xy 34.893955 -130.214945)
			(xy 34.893956 -130.160439) (xy 34.901714 -130.106488) (xy 34.917071 -130.05419) (xy 34.939715 -130.00461)
			(xy 34.969185 -129.958757) (xy 35.00488 -129.917565) (xy 35.046073 -129.881873) (xy 35.091928 -129.852406)
			(xy 35.141509 -129.829764) (xy 35.193807 -129.81441) (xy 35.247759 -129.806654) (xy 35.275012 -129.806192)
			(xy 35.303784 -129.806728) (xy 35.360672 -129.815401) (xy 35.388296 -129.823464) (xy 35.402345 -129.827403)
			(xy 35.431511 -129.827886) (xy 35.459625 -129.820109) (xy 35.484397 -129.804708) (xy 35.50381 -129.782936)
			(xy 35.516281 -129.756567) (xy 35.520797 -129.72775) (xy 35.51936 -129.713228) (xy 35.517822 -129.700903)
			(xy 35.516173 -129.676118) (xy 35.516058 -129.663698) (xy 35.516553 -129.63478) (xy 35.525284 -129.577607)
			(xy 35.542545 -129.522406) (xy 35.567941 -129.470444) (xy 35.600889 -129.422911) (xy 35.640636 -129.380897)
			(xy 35.663124 -129.362708) (xy 35.67441 -129.353358) (xy 35.691486 -129.329553) (xy 35.701094 -129.301876)
			(xy 35.702441 -129.27261) (xy 35.695417 -129.244168) (xy 35.680599 -129.218894) (xy 35.670236 -129.20853)
			(xy 35.65251 -129.191376) (xy 35.62117 -129.153283) (xy 35.607752 -129.132584) (xy 35.600137 -129.121302)
			(xy 35.580177 -129.102818) (xy 35.556041 -129.09027) (xy 35.529445 -129.084551) (xy 35.502284 -129.086069)
			(xy 35.47649 -129.094714) (xy 35.453901 -129.109872) (xy 35.444684 -129.119884) (xy 35.426492 -129.14031)
			(xy 35.38525 -129.176239) (xy 35.339299 -129.20591) (xy 35.289582 -129.228714) (xy 35.237117 -129.244183)
			(xy 35.182981 -129.251999) (xy 35.155632 -129.252472) (xy 35.128375 -129.252083) (xy 35.074416 -129.244329)
			(xy 35.022109 -129.228975) (xy 34.97252 -129.206332) (xy 34.926658 -129.176862) (xy 34.885458 -129.141165)
			(xy 34.849757 -129.099967) (xy 34.820284 -129.054108) (xy 34.797637 -129.004521) (xy 34.782278 -128.952216)
			(xy 34.774519 -128.898257) (xy 29.997908 -128.898257) (xy 29.997908 -130.76174) (xy 37.59454 -130.76174)
			(xy 37.595112 -130.732636) (xy 37.60397 -130.675106) (xy 37.621457 -130.619587) (xy 37.647168 -130.567366)
			(xy 37.680507 -130.519651) (xy 37.720701 -130.477549) (xy 37.76682 -130.442035) (xy 37.817794 -130.413932)
			(xy 37.872443 -130.393892) (xy 37.900864 -130.387598) (xy 37.914157 -130.384444) (xy 37.938548 -130.372167)
			(xy 37.95881 -130.35386) (xy 37.973489 -130.330834) (xy 37.981534 -130.30474) (xy 37.982369 -130.277446)
			(xy 37.975935 -130.250908) (xy 37.969698 -130.238754) (xy 37.95827 -130.217443) (xy 37.940305 -130.172547)
			(xy 37.92817 -130.125737) (xy 37.922061 -130.077767) (xy 37.921692 -130.053588) (xy 37.921692 -130.053334)
			(xy 37.922178 -130.026083) (xy 37.929934 -129.972135) (xy 37.945289 -129.91984) (xy 37.967931 -129.870263)
			(xy 37.997397 -129.824413) (xy 38.033088 -129.783222) (xy 38.074279 -129.747531) (xy 38.120129 -129.718065)
			(xy 38.169706 -129.695423) (xy 38.222001 -129.680068) (xy 38.275949 -129.672312) (xy 38.330451 -129.672312)
			(xy 38.384399 -129.680068) (xy 38.436694 -129.695423) (xy 38.486271 -129.718065) (xy 38.532121 -129.747531)
			(xy 38.573312 -129.783222) (xy 38.609003 -129.824413) (xy 38.638469 -129.870263) (xy 38.661111 -129.91984)
			(xy 38.676466 -129.972135) (xy 38.684222 -130.026083) (xy 38.684708 -130.053334) (xy 38.684075 -130.082435)
			(xy 38.675221 -130.13996) (xy 38.65774 -130.195476) (xy 38.632037 -130.247695) (xy 38.598705 -130.295408)
			(xy 38.558519 -130.337511) (xy 38.512409 -130.373027) (xy 38.461443 -130.401133) (xy 38.406801 -130.421179)
			(xy 38.378384 -130.427476) (xy 38.365068 -130.430554) (xy 38.340661 -130.442834) (xy 38.320388 -130.461152)
			(xy 38.305705 -130.484193) (xy 38.297664 -130.510306) (xy 38.296843 -130.537616) (xy 38.3033 -130.564164)
			(xy 38.30955 -130.57632) (xy 38.320972 -130.597634) (xy 38.338938 -130.642529) (xy 38.351074 -130.689339)
			(xy 38.357186 -130.737308) (xy 38.357556 -130.761486) (xy 38.357556 -130.76174) (xy 38.35718 -130.782822)
			(xy 38.66718 -130.782822) (xy 38.671251 -130.7272) (xy 38.683377 -130.672763) (xy 38.7033 -130.620672)
			(xy 38.730596 -130.572037) (xy 38.764682 -130.527894) (xy 38.804831 -130.489185) (xy 38.850189 -130.456734)
			(xy 38.899789 -130.431233) (xy 38.952573 -130.413226) (xy 39.007416 -130.403096) (xy 39.06315 -130.401059)
			(xy 39.118587 -130.407159) (xy 39.172544 -130.421265) (xy 39.223873 -130.443077) (xy 39.271479 -130.472131)
			(xy 39.314347 -130.507806) (xy 39.351564 -130.549343) (xy 39.382337 -130.595856) (xy 39.406009 -130.646353)
			(xy 39.422077 -130.69976) (xy 39.430197 -130.754936) (xy 39.430706 -130.782822) (xy 39.430197 -130.810708)
			(xy 39.422077 -130.865884) (xy 39.406009 -130.919291) (xy 39.382337 -130.969788) (xy 39.351564 -131.016301)
			(xy 39.314347 -131.057838) (xy 39.271479 -131.093513) (xy 39.223873 -131.122567) (xy 39.172544 -131.144379)
			(xy 39.118587 -131.158485) (xy 39.06315 -131.164585) (xy 39.007416 -131.162548) (xy 38.952573 -131.152418)
			(xy 38.899789 -131.134411) (xy 38.850189 -131.10891) (xy 38.804831 -131.076459) (xy 38.764682 -131.03775)
			(xy 38.730596 -130.993607) (xy 38.7033 -130.944972) (xy 38.683377 -130.892881) (xy 38.671251 -130.838444)
			(xy 38.66718 -130.782822) (xy 38.35718 -130.782822) (xy 38.35707 -130.788991) (xy 38.349314 -130.842939)
			(xy 38.333959 -130.895234) (xy 38.311317 -130.944811) (xy 38.281851 -130.990661) (xy 38.24616 -131.031852)
			(xy 38.204969 -131.067543) (xy 38.159119 -131.097009) (xy 38.109542 -131.119651) (xy 38.057247 -131.135006)
			(xy 38.003299 -131.142762) (xy 37.948797 -131.142762) (xy 37.894849 -131.135006) (xy 37.842554 -131.119651)
			(xy 37.792977 -131.097009) (xy 37.747127 -131.067543) (xy 37.705936 -131.031852) (xy 37.670245 -130.990661)
			(xy 37.640779 -130.944811) (xy 37.618137 -130.895234) (xy 37.602782 -130.842939) (xy 37.595026 -130.788991)
			(xy 37.59454 -130.76174) (xy 29.997908 -130.76174) (xy 29.997908 -131.179062) (xy 34.962844 -131.179062)
			(xy 34.966915 -131.12344) (xy 34.979041 -131.069003) (xy 34.998964 -131.016912) (xy 35.02626 -130.968277)
			(xy 35.060346 -130.924134) (xy 35.100495 -130.885425) (xy 35.145853 -130.852974) (xy 35.195453 -130.827473)
			(xy 35.248237 -130.809466) (xy 35.30308 -130.799336) (xy 35.358814 -130.797299) (xy 35.414251 -130.803399)
			(xy 35.468208 -130.817505) (xy 35.519537 -130.839317) (xy 35.567143 -130.868371) (xy 35.610011 -130.904046)
			(xy 35.647228 -130.945583) (xy 35.678001 -130.992096) (xy 35.701673 -131.042593) (xy 35.717741 -131.096)
			(xy 35.725861 -131.151176) (xy 35.72637 -131.179062) (xy 35.725861 -131.206948) (xy 35.717741 -131.262124)
			(xy 35.701673 -131.315531) (xy 35.678001 -131.366028) (xy 35.647228 -131.412541) (xy 35.610011 -131.454078)
			(xy 35.567143 -131.489753) (xy 35.519537 -131.518807) (xy 35.468208 -131.540619) (xy 35.414251 -131.554725)
			(xy 35.358814 -131.560825) (xy 35.30308 -131.558788) (xy 35.248237 -131.548658) (xy 35.195453 -131.530651)
			(xy 35.145853 -131.50515) (xy 35.100495 -131.472699) (xy 35.060346 -131.43399) (xy 35.02626 -131.389847)
			(xy 34.998964 -131.341212) (xy 34.979041 -131.289121) (xy 34.966915 -131.234684) (xy 34.962844 -131.179062)
			(xy 29.997908 -131.179062) (xy 29.997908 -131.282694) (xy 30.29077 -131.575556) (xy 33.412938 -131.575556)
			(xy 33.89122 -132.054346) (xy 33.89122 -133.838696) (xy 38.067994 -133.838696) (xy 38.072065 -133.783074)
			(xy 38.084191 -133.728637) (xy 38.104114 -133.676546) (xy 38.13141 -133.627911) (xy 38.165496 -133.583768)
			(xy 38.205645 -133.545059) (xy 38.251003 -133.512608) (xy 38.300603 -133.487107) (xy 38.353387 -133.4691)
			(xy 38.40823 -133.45897) (xy 38.463964 -133.456933) (xy 38.519401 -133.463033) (xy 38.573358 -133.477139)
			(xy 38.624687 -133.498951) (xy 38.672293 -133.528005) (xy 38.715161 -133.56368) (xy 38.752378 -133.605217)
			(xy 38.783151 -133.65173) (xy 38.806823 -133.702227) (xy 38.822891 -133.755634) (xy 38.831011 -133.81081)
			(xy 38.83152 -133.838696) (xy 38.831011 -133.866582) (xy 38.822891 -133.921758) (xy 38.806823 -133.975165)
			(xy 38.783151 -134.025662) (xy 38.752378 -134.072175) (xy 38.715161 -134.113712) (xy 38.672293 -134.149387)
			(xy 38.624687 -134.178441) (xy 38.573358 -134.200253) (xy 38.519401 -134.214359) (xy 38.463964 -134.220459)
			(xy 38.40823 -134.218422) (xy 38.353387 -134.208292) (xy 38.300603 -134.190285) (xy 38.251003 -134.164784)
			(xy 38.205645 -134.132333) (xy 38.165496 -134.093624) (xy 38.13141 -134.049481) (xy 38.104114 -134.000846)
			(xy 38.084191 -133.948755) (xy 38.072065 -133.894318) (xy 38.067994 -133.838696) (xy 33.89122 -133.838696)
			(xy 33.89122 -133.906514) (xy 34.01822 -134.033768) (xy 34.01822 -134.088124) (xy 37.639498 -137.709402)
			(xy 37.646502 -137.716558) (xy 37.659472 -137.731816) (xy 37.665406 -137.739882) (xy 37.667946 -137.74293)
			(xy 42.676572 -142.751556) (xy 47.613316 -142.751556) (xy 47.638313 -142.752173) (xy 47.687337 -142.761982)
			(xy 47.733508 -142.781161) (xy 47.775053 -142.808974) (xy 47.793148 -142.826232) (xy 49.455636 -144.48872)
			(xy 51.012924 -144.48872) (xy 51.012928 -144.434227) (xy 51.020687 -144.380288) (xy 51.036042 -144.328003)
			(xy 51.058683 -144.278435) (xy 51.088146 -144.232593) (xy 51.123834 -144.191411) (xy 51.165019 -144.155727)
			(xy 51.210863 -144.126267) (xy 51.260433 -144.103631) (xy 51.312719 -144.08828) (xy 51.366659 -144.080526)
			(xy 51.421152 -144.080526) (xy 51.475091 -144.088282) (xy 51.527377 -144.103635) (xy 51.576946 -144.126272)
			(xy 51.62279 -144.155734) (xy 51.663974 -144.191419) (xy 51.69966 -144.232602) (xy 51.729122 -144.278444)
			(xy 51.751761 -144.328013) (xy 51.767116 -144.380299) (xy 51.774873 -144.434237) (xy 51.77536 -144.461484)
			(xy 51.77493 -144.486875) (xy 51.768173 -144.537207) (xy 51.761898 -144.561814) (xy 51.758525 -144.576472)
			(xy 51.759445 -144.606518) (xy 51.769069 -144.634996) (xy 51.786564 -144.65944) (xy 51.810415 -144.677736)
			(xy 51.838559 -144.688299) (xy 51.868558 -144.690215) (xy 51.88331 -144.68729) (xy 51.90484 -144.682535)
			(xy 51.948639 -144.677442) (xy 51.970686 -144.67713) (xy 51.97094 -144.67713) (xy 51.998187 -144.677621)
			(xy 52.052126 -144.685382) (xy 52.104412 -144.700739) (xy 52.153979 -144.723381) (xy 52.199821 -144.752847)
			(xy 52.241002 -144.788536) (xy 52.276686 -144.829723) (xy 52.306145 -144.875568) (xy 52.32878 -144.925139)
			(xy 52.34413 -144.977427) (xy 52.351883 -145.031367) (xy 52.351881 -145.085861) (xy 52.344124 -145.139801)
			(xy 52.32877 -145.192087) (xy 52.306131 -145.241657) (xy 52.276669 -145.2875) (xy 52.240982 -145.328684)
			(xy 52.199798 -145.36437) (xy 52.153955 -145.393832) (xy 52.104385 -145.416471) (xy 52.052099 -145.431824)
			(xy 51.998159 -145.439581) (xy 51.943665 -145.439583) (xy 51.889725 -145.431829) (xy 51.837437 -145.416479)
			(xy 51.787866 -145.393844) (xy 51.742021 -145.364384) (xy 51.700835 -145.328701) (xy 51.665146 -145.287519)
			(xy 51.63568 -145.241678) (xy 51.613039 -145.19211) (xy 51.597681 -145.139824) (xy 51.589921 -145.085885)
			(xy 51.589432 -145.058638) (xy 51.589867 -145.033247) (xy 51.596621 -144.982916) (xy 51.602894 -144.958308)
			(xy 51.606253 -144.943646) (xy 51.605338 -144.913601) (xy 51.595718 -144.885123) (xy 51.578225 -144.860677)
			(xy 51.554375 -144.842382) (xy 51.526232 -144.83182) (xy 51.496234 -144.829906) (xy 51.481482 -144.832832)
			(xy 51.459952 -144.837589) (xy 51.416153 -144.84268) (xy 51.394106 -144.842992) (xy 51.393852 -144.842992)
			(xy 51.366605 -144.84247) (xy 51.312667 -144.834709) (xy 51.260383 -144.81935) (xy 51.210816 -144.796707)
			(xy 51.164976 -144.767241) (xy 51.123796 -144.731551) (xy 51.088114 -144.690364) (xy 51.058657 -144.644518)
			(xy 51.036024 -144.594947) (xy 51.020675 -144.54266) (xy 51.012924 -144.48872) (xy 49.455636 -144.48872)
			(xy 50.458878 -145.491962) (xy 50.47234 -145.495264) (xy 50.497425 -145.502184) (xy 50.545584 -145.521898)
			(xy 50.590622 -145.547964) (xy 50.631706 -145.5799) (xy 50.668077 -145.617116) (xy 50.683922 -145.637758)
			(xy 50.692348 -145.648365) (xy 50.713661 -145.665072) (xy 50.738615 -145.675591) (xy 50.765456 -145.679181)
			(xy 50.792297 -145.675591) (xy 50.817251 -145.665072) (xy 50.838564 -145.648365) (xy 50.84699 -145.637758)
			(xy 50.86512 -145.614243) (xy 50.907427 -145.572585) (xy 50.955675 -145.537982) (xy 51.008701 -145.511271)
			(xy 51.065225 -145.493095) (xy 51.123881 -145.483893) (xy 51.153568 -145.483326) (xy 51.180822 -145.483785)
			(xy 51.234774 -145.491539) (xy 51.287074 -145.506892) (xy 51.336657 -145.529534) (xy 51.382512 -145.559001)
			(xy 51.423706 -145.594696) (xy 51.4594 -145.63589) (xy 51.488867 -145.681745) (xy 51.511508 -145.731327)
			(xy 51.526862 -145.783627) (xy 51.534615 -145.83758) (xy 51.535076 -145.864834) (xy 51.534582 -145.893708)
			(xy 51.525897 -145.950799) (xy 51.5087 -146.005926) (xy 51.483384 -146.057829) (xy 51.45053 -146.10532)
			(xy 51.410888 -146.147312) (xy 51.365366 -146.182844) (xy 51.315006 -146.211104) (xy 51.260959 -146.231444)
			(xy 51.204462 -146.2434) (xy 51.175666 -146.24558) (xy 51.156362 -146.24685) (xy 51.051206 -146.352006)
			(xy 51.041177 -146.362791) (xy 51.027192 -146.388694) (xy 51.021169 -146.417509) (xy 51.023606 -146.446845)
			(xy 51.034303 -146.474271) (xy 51.052371 -146.497511) (xy 51.076313 -146.514638) (xy 51.090068 -146.5199)
			(xy 51.114791 -146.528871) (xy 51.161707 -146.552636) (xy 51.204915 -146.582618) (xy 51.243597 -146.61825)
			(xy 51.27702 -146.658856) (xy 51.304551 -146.703667) (xy 51.325667 -146.751833) (xy 51.339969 -146.802443)
			(xy 51.347186 -146.854538) (xy 51.347624 -146.880834) (xy 51.347624 -146.881088) (xy 51.347224 -146.906292)
			(xy 51.340585 -146.95626) (xy 51.327409 -147.004914) (xy 51.307926 -147.051404) (xy 51.295554 -147.073366)
			(xy 51.28846 -147.086303) (xy 51.281434 -147.114951) (xy 51.282888 -147.144412) (xy 51.292701 -147.172229)
			(xy 51.310054 -147.196081) (xy 51.3335 -147.21398) (xy 51.347116 -147.21967) (xy 51.373892 -147.230366)
			(xy 51.424134 -147.258654) (xy 51.469543 -147.294184) (xy 51.509085 -147.336146) (xy 51.541859 -147.383583)
			(xy 51.567117 -147.435414) (xy 51.584283 -147.490457) (xy 51.592966 -147.547457) (xy 51.593496 -147.576286)
			(xy 51.593032 -147.603539) (xy 51.585276 -147.657491) (xy 51.569921 -147.709789) (xy 51.54728 -147.75937)
			(xy 51.517812 -147.805224) (xy 51.482118 -147.846417) (xy 51.440925 -147.882111) (xy 51.395072 -147.911579)
			(xy 51.345491 -147.934221) (xy 51.293193 -147.949576) (xy 51.239241 -147.957331) (xy 51.211988 -147.957794)
			(xy 51.211734 -147.957794) (xy 51.181895 -147.957227) (xy 51.122949 -147.947906) (xy 51.094386 -147.939252)
			(xy 51.080457 -147.935302) (xy 51.051539 -147.934385) (xy 51.02353 -147.941636) (xy 50.998691 -147.956471)
			(xy 50.979026 -147.977693) (xy 50.966122 -148.003589) (xy 50.963068 -148.017738) (xy 50.957919 -148.043816)
			(xy 50.941346 -148.09432) (xy 50.917921 -148.142034) (xy 50.888096 -148.186032) (xy 50.852451 -148.225463)
			(xy 50.811676 -148.259561) (xy 50.76656 -148.287667) (xy 50.717979 -148.309236) (xy 50.666873 -148.323849)
			(xy 50.614233 -148.331225) (xy 50.587656 -148.331682) (xy 50.560405 -148.331245) (xy 50.506458 -148.323483)
			(xy 50.454165 -148.308123) (xy 50.40459 -148.285478) (xy 50.358742 -148.256008) (xy 50.317554 -148.220314)
			(xy 50.281865 -148.179123) (xy 50.252401 -148.133271) (xy 50.229762 -148.083693) (xy 50.214408 -148.031399)
			(xy 50.206652 -147.977451) (xy 50.206652 -147.922949) (xy 50.214408 -147.869001) (xy 50.229762 -147.816707)
			(xy 50.252401 -147.767129) (xy 50.281865 -147.721277) (xy 50.317554 -147.680086) (xy 50.358742 -147.644392)
			(xy 50.40459 -147.614922) (xy 50.454165 -147.592277) (xy 50.506458 -147.576917) (xy 50.560405 -147.569155)
			(xy 50.587656 -147.568666) (xy 50.58791 -147.568666) (xy 50.617749 -147.569247) (xy 50.676695 -147.578559)
			(xy 50.705258 -147.587208) (xy 50.719167 -147.591239) (xy 50.748099 -147.592148) (xy 50.776118 -147.584883)
			(xy 50.800963 -147.570032) (xy 50.820629 -147.548792) (xy 50.833527 -147.522879) (xy 50.836576 -147.508722)
			(xy 50.843165 -147.475884) (xy 50.866284 -147.413031) (xy 50.88255 -147.383754) (xy 50.889618 -147.370804)
			(xy 50.896647 -147.342161) (xy 50.895197 -147.312704) (xy 50.885389 -147.28489) (xy 50.868042 -147.261039)
			(xy 50.844601 -147.243141) (xy 50.830988 -147.23745) (xy 50.80422 -147.226735) (xy 50.753979 -147.19845)
			(xy 50.70857 -147.162922) (xy 50.669027 -147.120963) (xy 50.636253 -147.073528) (xy 50.610993 -147.0217)
			(xy 50.593825 -146.96666) (xy 50.585139 -146.909662) (xy 50.584608 -146.880834) (xy 50.584897 -146.860222)
			(xy 50.589351 -146.819239) (xy 50.593498 -146.799046) (xy 50.596201 -146.784156) (xy 50.593683 -146.754011)
			(xy 50.582452 -146.725924) (xy 50.563493 -146.702353) (xy 50.538466 -146.685363) (xy 50.509561 -146.676443)
			(xy 50.494438 -146.675856) (xy 50.1396 -146.675856) (xy 50.114604 -146.675226) (xy 50.06558 -146.665421)
			(xy 50.01941 -146.646245) (xy 49.977864 -146.618436) (xy 49.959768 -146.60118) (xy 49.578768 -146.22018)
			(xy 49.561521 -146.202076) (xy 49.533706 -146.160535) (xy 49.51453 -146.114367) (xy 49.504729 -146.065344)
			(xy 49.504092 -146.040348) (xy 49.504092 -145.795746) (xy 47.349918 -143.641572) (xy 42.413174 -143.641572)
			(xy 42.388177 -143.640953) (xy 42.339154 -143.631144) (xy 42.292983 -143.611965) (xy 42.251438 -143.584153)
			(xy 42.233342 -143.566896) (xy 34.079942 -135.413496) (xy 34.04489 -135.438642) (xy 34.020457 -135.455485)
			(xy 33.967442 -135.482147) (xy 33.91094 -135.500283) (xy 33.852311 -135.509458) (xy 33.82264 -135.510016)
			(xy 33.795859 -135.509561) (xy 33.742826 -135.502055) (xy 33.691361 -135.487213) (xy 33.642475 -135.465326)
			(xy 33.597127 -135.436823) (xy 33.556206 -135.402264) (xy 33.520515 -135.362326) (xy 33.490754 -135.317793)
			(xy 33.478724 -135.293862) (xy 33.472219 -135.281399) (xy 33.453623 -135.260331) (xy 33.429984 -135.245139)
			(xy 33.403095 -135.236976) (xy 33.374999 -135.236462) (xy 33.347829 -135.243636) (xy 33.32365 -135.257954)
			(xy 33.304296 -135.278328) (xy 33.297368 -135.29056) (xy 33.284896 -135.313346) (xy 33.254737 -135.355638)
			(xy 33.21912 -135.393447) (xy 33.178703 -135.426076) (xy 33.134233 -135.452919) (xy 33.086533 -135.473483)
			(xy 33.036484 -135.487385) (xy 32.985012 -135.494369) (xy 32.95904 -135.494776) (xy 32.937704 -135.494776)
			(xy 32.636968 -135.795766) (xy 32.636968 -137.279888) (xy 33.298892 -137.279888) (xy 33.299358 -137.253509)
			(xy 33.306612 -137.201253) (xy 33.320994 -137.150494) (xy 33.34223 -137.102199) (xy 33.369914 -137.057289)
			(xy 33.403521 -137.01662) (xy 33.442408 -136.980967) (xy 33.485835 -136.95101) (xy 33.509204 -136.938766)
			(xy 33.521569 -136.932079) (xy 33.542292 -136.913098) (xy 33.557047 -136.889181) (xy 33.564715 -136.862146)
			(xy 33.564714 -136.834044) (xy 33.557043 -136.807009) (xy 33.542285 -136.783094) (xy 33.52156 -136.764115)
			(xy 33.509204 -136.75741) (xy 33.48583 -136.745175) (xy 33.442405 -136.715213) (xy 33.403519 -136.679557)
			(xy 33.369913 -136.638886) (xy 33.342226 -136.593976) (xy 33.320987 -136.545682) (xy 33.306599 -136.494923)
			(xy 33.299336 -136.442667) (xy 33.298892 -136.416288) (xy 33.299378 -136.389037) (xy 33.307134 -136.335089)
			(xy 33.322489 -136.282794) (xy 33.345131 -136.233217) (xy 33.374597 -136.187367) (xy 33.410288 -136.146176)
			(xy 33.451479 -136.110485) (xy 33.497329 -136.081019) (xy 33.546906 -136.058377) (xy 33.599201 -136.043022)
			(xy 33.653149 -136.035266) (xy 33.707651 -136.035266) (xy 33.761599 -136.043022) (xy 33.813894 -136.058377)
			(xy 33.863471 -136.081019) (xy 33.909321 -136.110485) (xy 33.950512 -136.146176) (xy 33.986203 -136.187367)
			(xy 34.015669 -136.233217) (xy 34.038311 -136.282794) (xy 34.053666 -136.335089) (xy 34.061422 -136.389037)
			(xy 34.061908 -136.416288) (xy 34.061505 -136.442669) (xy 34.05424 -136.494928) (xy 34.039849 -136.545689)
			(xy 34.018604 -136.593984) (xy 33.99091 -136.638893) (xy 33.957296 -136.679561) (xy 33.918402 -136.715212)
			(xy 33.874968 -136.745168) (xy 33.851596 -136.75741) (xy 33.839252 -136.764132) (xy 33.818532 -136.783108)
			(xy 33.803777 -136.807018) (xy 33.796107 -136.834047) (xy 33.796106 -136.862143) (xy 33.803772 -136.889173)
			(xy 33.818525 -136.913084) (xy 33.839243 -136.932062) (xy 33.851596 -136.938766) (xy 33.87496 -136.951019)
			(xy 33.918385 -136.980979) (xy 33.957271 -137.016632) (xy 33.990878 -137.0573) (xy 34.018565 -137.102207)
			(xy 34.039807 -137.150499) (xy 34.054197 -137.201255) (xy 34.061462 -137.25351) (xy 34.061908 -137.279888)
			(xy 34.061422 -137.307139) (xy 34.053666 -137.361087) (xy 34.038311 -137.413382) (xy 34.015669 -137.462959)
			(xy 33.986203 -137.508809) (xy 33.950512 -137.55) (xy 33.909321 -137.585691) (xy 33.863471 -137.615157)
			(xy 33.813894 -137.637799) (xy 33.761599 -137.653154) (xy 33.707651 -137.66091) (xy 33.653149 -137.66091)
			(xy 33.599201 -137.653154) (xy 33.546906 -137.637799) (xy 33.497329 -137.615157) (xy 33.451479 -137.585691)
			(xy 33.410288 -137.55) (xy 33.374597 -137.508809) (xy 33.345131 -137.462959) (xy 33.322489 -137.413382)
			(xy 33.307134 -137.361087) (xy 33.299378 -137.307139) (xy 33.298892 -137.279888) (xy 32.636968 -137.279888)
			(xy 32.636968 -137.827258) (xy 32.76219 -137.95248) (xy 33.930336 -137.95248) (xy 33.955331 -137.953139)
			(xy 34.004353 -137.962934) (xy 34.050525 -137.9821) (xy 34.092071 -138.009903) (xy 34.110168 -138.027156)
			(xy 36.024312 -139.9413) (xy 36.041563 -139.9594) (xy 36.069374 -140.000944) (xy 36.088548 -140.047113)
			(xy 36.09835 -140.096136) (xy 36.098988 -140.121132) (xy 36.098988 -146.75866) (xy 43.126914 -146.75866)
			(xy 43.127436 -146.729921) (xy 43.136063 -146.673095) (xy 43.153114 -146.618205) (xy 43.178206 -146.566493)
			(xy 43.210769 -146.51913) (xy 43.230038 -146.497802) (xy 43.240134 -146.486238) (xy 43.253567 -146.458655)
			(xy 43.258189 -146.428324) (xy 43.253582 -146.397991) (xy 43.240162 -146.370401) (xy 43.230038 -146.358864)
			(xy 43.21077 -146.337534) (xy 43.178203 -146.290173) (xy 43.15311 -146.238462) (xy 43.136059 -146.183572)
			(xy 43.127435 -146.126745) (xy 43.126914 -146.098006) (xy 43.12738 -146.070636) (xy 43.135197 -146.016457)
			(xy 43.150686 -145.963953) (xy 43.173528 -145.914206) (xy 43.203253 -145.86824) (xy 43.220894 -145.847308)
			(xy 43.230126 -145.835977) (xy 43.242304 -145.80942) (xy 43.246478 -145.780505) (xy 43.242307 -145.751588)
			(xy 43.23013 -145.725031) (xy 43.220894 -145.713704) (xy 43.203242 -145.692782) (xy 43.173533 -145.646806)
			(xy 43.150699 -145.597056) (xy 43.135211 -145.544553) (xy 43.127386 -145.490376) (xy 43.126914 -145.463006)
			(xy 43.127361 -145.435752) (xy 43.135118 -145.3818) (xy 43.150474 -145.3295) (xy 43.173117 -145.279919)
			(xy 43.202587 -145.234064) (xy 43.238282 -145.192871) (xy 43.279477 -145.157177) (xy 43.325333 -145.12771)
			(xy 43.374915 -145.105068) (xy 43.427215 -145.089714) (xy 43.481168 -145.08196) (xy 43.508422 -145.081498)
			(xy 43.535793 -145.081952) (xy 43.589972 -145.089773) (xy 43.642476 -145.105265) (xy 43.692222 -145.128109)
			(xy 43.738189 -145.157836) (xy 43.75912 -145.175478) (xy 43.770448 -145.184714) (xy 43.797005 -145.19689)
			(xy 43.825922 -145.201063) (xy 43.854839 -145.19689) (xy 43.881396 -145.184714) (xy 43.892724 -145.175478)
			(xy 43.913671 -145.157858) (xy 43.95964 -145.128144) (xy 44.009384 -145.105305) (xy 44.061881 -145.089809)
			(xy 44.116054 -145.081975) (xy 44.143422 -145.081498) (xy 44.172161 -145.082009) (xy 44.228989 -145.090635)
			(xy 44.28388 -145.107688) (xy 44.335592 -145.132782) (xy 44.382954 -145.16535) (xy 44.40428 -145.184622)
			(xy 44.415814 -145.194694) (xy 44.44336 -145.208036) (xy 44.473622 -145.212621) (xy 44.503884 -145.208036)
			(xy 44.53143 -145.194694) (xy 44.542964 -145.184622) (xy 44.564291 -145.165352) (xy 44.611654 -145.132787)
			(xy 44.663365 -145.107696) (xy 44.718256 -145.090646) (xy 44.775083 -145.082024) (xy 44.832561 -145.082024)
			(xy 44.889388 -145.090646) (xy 44.944279 -145.107696) (xy 44.99599 -145.132787) (xy 45.043353 -145.165352)
			(xy 45.06468 -145.184622) (xy 45.076214 -145.194694) (xy 45.10376 -145.208036) (xy 45.134022 -145.212621)
			(xy 45.164284 -145.208036) (xy 45.19183 -145.194694) (xy 45.203364 -145.184622) (xy 45.224691 -145.165352)
			(xy 45.272054 -145.132787) (xy 45.323765 -145.107696) (xy 45.378656 -145.090646) (xy 45.435483 -145.082024)
			(xy 45.492961 -145.082024) (xy 45.549788 -145.090646) (xy 45.604679 -145.107696) (xy 45.65639 -145.132787)
			(xy 45.703753 -145.165352) (xy 45.72508 -145.184622) (xy 45.736614 -145.194694) (xy 45.76416 -145.208036)
			(xy 45.794422 -145.212621) (xy 45.824684 -145.208036) (xy 45.85223 -145.194694) (xy 45.863764 -145.184622)
			(xy 45.885091 -145.165352) (xy 45.932454 -145.132787) (xy 45.984165 -145.107696) (xy 46.039056 -145.090646)
			(xy 46.095883 -145.082024) (xy 46.153361 -145.082024) (xy 46.210188 -145.090646) (xy 46.265079 -145.107696)
			(xy 46.31679 -145.132787) (xy 46.364153 -145.165352) (xy 46.38548 -145.184622) (xy 46.397014 -145.194694)
			(xy 46.42456 -145.208036) (xy 46.454822 -145.212621) (xy 46.485084 -145.208036) (xy 46.51263 -145.194694)
			(xy 46.524164 -145.184622) (xy 46.545491 -145.165352) (xy 46.592854 -145.132787) (xy 46.644565 -145.107696)
			(xy 46.699456 -145.090646) (xy 46.756283 -145.082024) (xy 46.813761 -145.082024) (xy 46.870588 -145.090646)
			(xy 46.925479 -145.107696) (xy 46.97719 -145.132787) (xy 47.024553 -145.165352) (xy 47.04588 -145.184622)
			(xy 47.057414 -145.194694) (xy 47.08496 -145.208036) (xy 47.115222 -145.212621) (xy 47.145484 -145.208036)
			(xy 47.17303 -145.194694) (xy 47.184564 -145.184622) (xy 47.20588 -145.165338) (xy 47.253245 -145.132774)
			(xy 47.30496 -145.107685) (xy 47.359853 -145.090637) (xy 47.416682 -145.082017) (xy 47.445422 -145.081498)
			(xy 47.472674 -145.081957) (xy 47.526623 -145.089717) (xy 47.578919 -145.105075) (xy 47.628496 -145.127719)
			(xy 47.674347 -145.157189) (xy 47.715537 -145.192883) (xy 47.751228 -145.234076) (xy 47.780694 -145.279928)
			(xy 47.803335 -145.329508) (xy 47.818689 -145.381804) (xy 47.826445 -145.435754) (xy 47.82693 -145.463006)
			(xy 47.826467 -145.489242) (xy 47.819271 -145.541217) (xy 47.805017 -145.591715) (xy 47.783973 -145.639781)
			(xy 47.756538 -145.684508) (xy 47.723228 -145.725051) (xy 47.704248 -145.743168) (xy 47.696871 -145.750692)
			(xy 47.688442 -145.769979) (xy 47.688444 -145.791029) (xy 47.696876 -145.810315) (xy 47.704248 -145.817844)
			(xy 47.725584 -145.83918) (xy 47.733113 -145.846552) (xy 47.752398 -145.854983) (xy 47.773446 -145.854983)
			(xy 47.792731 -145.846552) (xy 47.80026 -145.83918) (xy 47.818371 -145.820192) (xy 47.858911 -145.786874)
			(xy 47.903638 -145.759432) (xy 47.951706 -145.738384) (xy 48.002206 -145.724128) (xy 48.054185 -145.716934)
			(xy 48.080422 -145.716498) (xy 48.107674 -145.716957) (xy 48.161623 -145.724717) (xy 48.213919 -145.740075)
			(xy 48.263496 -145.762719) (xy 48.309347 -145.792189) (xy 48.350537 -145.827883) (xy 48.386228 -145.869076)
			(xy 48.415694 -145.914928) (xy 48.438335 -145.964508) (xy 48.453689 -146.016804) (xy 48.461445 -146.070754)
			(xy 48.46193 -146.098006) (xy 48.461402 -146.126745) (xy 48.452779 -146.183571) (xy 48.43573 -146.238462)
			(xy 48.410639 -146.290174) (xy 48.378076 -146.337537) (xy 48.358806 -146.358864) (xy 48.348699 -146.3704)
			(xy 48.335361 -146.398008) (xy 48.330783 -146.428324) (xy 48.335375 -146.458639) (xy 48.348727 -146.48624)
			(xy 48.358806 -146.497802) (xy 48.378048 -146.519154) (xy 48.41062 -146.566508) (xy 48.435719 -146.618213)
			(xy 48.452776 -146.673099) (xy 48.461405 -146.729923) (xy 48.46193 -146.75866) (xy 48.461408 -146.785911)
			(xy 48.453657 -146.839859) (xy 48.438307 -146.892154) (xy 48.415671 -146.941732) (xy 48.386209 -146.987585)
			(xy 48.350521 -147.028777) (xy 48.309334 -147.064472) (xy 48.263487 -147.093941) (xy 48.213912 -147.116585)
			(xy 48.161619 -147.131943) (xy 48.107673 -147.139703) (xy 48.080422 -147.140168) (xy 48.053052 -147.139697)
			(xy 47.998873 -147.131881) (xy 47.946369 -147.116394) (xy 47.896622 -147.093553) (xy 47.850656 -147.063829)
			(xy 47.829724 -147.046188) (xy 47.818396 -147.036952) (xy 47.791839 -147.024776) (xy 47.762922 -147.020603)
			(xy 47.734005 -147.024776) (xy 47.707448 -147.036952) (xy 47.69612 -147.046188) (xy 47.67519 -147.063829)
			(xy 47.629217 -147.093541) (xy 47.579469 -147.116377) (xy 47.526968 -147.131867) (xy 47.472791 -147.139695)
			(xy 47.445422 -147.140168) (xy 47.416685 -147.139613) (xy 47.359859 -147.130995) (xy 47.30497 -147.113951)
			(xy 47.253257 -147.088867) (xy 47.205893 -147.05631) (xy 47.184564 -147.037044) (xy 47.17303 -147.026972)
			(xy 47.145484 -147.01363) (xy 47.115222 -147.009045) (xy 47.08496 -147.01363) (xy 47.057414 -147.026972)
			(xy 47.04588 -147.037044) (xy 47.024553 -147.056314) (xy 46.97719 -147.088879) (xy 46.925479 -147.11397)
			(xy 46.870588 -147.13102) (xy 46.813761 -147.139642) (xy 46.756283 -147.139642) (xy 46.699456 -147.13102)
			(xy 46.644565 -147.11397) (xy 46.592854 -147.088879) (xy 46.545491 -147.056314) (xy 46.524164 -147.037044)
			(xy 46.51263 -147.026972) (xy 46.485084 -147.01363) (xy 46.454822 -147.009045) (xy 46.42456 -147.01363)
			(xy 46.397014 -147.026972) (xy 46.38548 -147.037044) (xy 46.364153 -147.056314) (xy 46.31679 -147.088879)
			(xy 46.265079 -147.11397) (xy 46.210188 -147.13102) (xy 46.153361 -147.139642) (xy 46.095883 -147.139642)
			(xy 46.039056 -147.13102) (xy 45.984165 -147.11397) (xy 45.932454 -147.088879) (xy 45.885091 -147.056314)
			(xy 45.863764 -147.037044) (xy 45.85223 -147.026972) (xy 45.824684 -147.01363) (xy 45.794422 -147.009045)
			(xy 45.76416 -147.01363) (xy 45.736614 -147.026972) (xy 45.72508 -147.037044) (xy 45.703753 -147.056314)
			(xy 45.65639 -147.088879) (xy 45.604679 -147.11397) (xy 45.549788 -147.13102) (xy 45.492961 -147.139642)
			(xy 45.435483 -147.139642) (xy 45.378656 -147.13102) (xy 45.323765 -147.11397) (xy 45.272054 -147.088879)
			(xy 45.224691 -147.056314) (xy 45.203364 -147.037044) (xy 45.19183 -147.026972) (xy 45.164284 -147.01363)
			(xy 45.134022 -147.009045) (xy 45.10376 -147.01363) (xy 45.076214 -147.026972) (xy 45.06468 -147.037044)
			(xy 45.043353 -147.056314) (xy 44.99599 -147.088879) (xy 44.944279 -147.11397) (xy 44.889388 -147.13102)
			(xy 44.832561 -147.139642) (xy 44.775083 -147.139642) (xy 44.718256 -147.13102) (xy 44.663365 -147.11397)
			(xy 44.611654 -147.088879) (xy 44.564291 -147.056314) (xy 44.542964 -147.037044) (xy 44.53143 -147.026972)
			(xy 44.503884 -147.01363) (xy 44.473622 -147.009045) (xy 44.44336 -147.01363) (xy 44.415814 -147.026972)
			(xy 44.40428 -147.037044) (xy 44.382941 -147.056301) (xy 44.335583 -147.08887) (xy 44.283874 -147.113965)
			(xy 44.228986 -147.131019) (xy 44.17216 -147.139645) (xy 44.143422 -147.140168) (xy 44.116052 -147.139697)
			(xy 44.061873 -147.131881) (xy 44.009369 -147.116394) (xy 43.959622 -147.093553) (xy 43.913656 -147.063829)
			(xy 43.892724 -147.046188) (xy 43.881396 -147.036952) (xy 43.854839 -147.024776) (xy 43.825922 -147.020603)
			(xy 43.797005 -147.024776) (xy 43.770448 -147.036952) (xy 43.75912 -147.046188) (xy 43.73819 -147.063829)
			(xy 43.692217 -147.093541) (xy 43.642469 -147.116377) (xy 43.589968 -147.131867) (xy 43.535791 -147.139695)
			(xy 43.508422 -147.140168) (xy 43.481168 -147.139724) (xy 43.427214 -147.131969) (xy 43.374914 -147.116614)
			(xy 43.325331 -147.093971) (xy 43.279476 -147.064502) (xy 43.238282 -147.028806) (xy 43.202588 -146.98761)
			(xy 43.17312 -146.941753) (xy 43.15048 -146.89217) (xy 43.135127 -146.839868) (xy 43.127375 -146.785914)
			(xy 43.126914 -146.75866) (xy 36.098988 -146.75866) (xy 36.098988 -148.963634) (xy 37.580824 -150.44547)
			(xy 50.99304 -150.44547) (xy 50.993427 -150.418214) (xy 51.001189 -150.364258) (xy 51.016552 -150.311956)
			(xy 51.039201 -150.262372) (xy 51.068677 -150.216517) (xy 51.104379 -150.175323) (xy 51.145579 -150.13963)
			(xy 51.191441 -150.110164) (xy 51.241029 -150.087524) (xy 51.293334 -150.072173) (xy 51.347292 -150.064422)
			(xy 51.374548 -150.063962) (xy 51.402122 -150.064442) (xy 51.456695 -150.072388) (xy 51.509556 -150.088109)
			(xy 51.559603 -150.111276) (xy 51.605792 -150.141408) (xy 51.647163 -150.177875) (xy 51.665378 -150.198582)
			(xy 51.675276 -150.20948) (xy 51.699926 -150.225555) (xy 51.728134 -150.233939) (xy 51.757562 -150.233939)
			(xy 51.78577 -150.225555) (xy 51.81042 -150.20948) (xy 51.820318 -150.198582) (xy 51.838512 -150.177855)
			(xy 51.879885 -150.141387) (xy 51.926079 -150.111257) (xy 51.97613 -150.088094) (xy 52.028995 -150.072381)
			(xy 52.083572 -150.064445) (xy 52.111148 -150.063962) (xy 52.137649 -150.064415) (xy 52.19014 -150.071762)
			(xy 52.241107 -150.086307) (xy 52.289569 -150.10777) (xy 52.334592 -150.135737) (xy 52.355242 -150.152354)
			(xy 52.367396 -150.161784) (xy 52.395794 -150.173573) (xy 52.426411 -150.176397) (xy 52.456486 -150.170003)
			(xy 52.483306 -150.154967) (xy 52.504451 -150.132645) (xy 52.511706 -150.11908) (xy 52.523817 -150.095395)
			(xy 52.553737 -150.051413) (xy 52.589605 -150.01213) (xy 52.630693 -149.978345) (xy 52.653184 -149.96414)
			(xy 52.665431 -149.956248) (xy 52.685104 -149.934769) (xy 52.697907 -149.908607) (xy 52.702796 -149.879894)
			(xy 52.699373 -149.850969) (xy 52.694078 -149.837394) (xy 52.684593 -149.814182) (xy 52.671241 -149.76585)
			(xy 52.664511 -149.716161) (xy 52.664106 -149.69109) (xy 52.66454 -149.666021) (xy 52.671286 -149.616338)
			(xy 52.684614 -149.568004) (xy 52.694078 -149.544786) (xy 52.699333 -149.531207) (xy 52.702713 -149.502299)
			(xy 52.697811 -149.47361) (xy 52.685024 -149.447464) (xy 52.665389 -149.42598) (xy 52.653184 -149.41804)
			(xy 52.630024 -149.403514) (xy 52.587899 -149.368668) (xy 52.551317 -149.328041) (xy 52.521063 -149.282506)
			(xy 52.497786 -149.233039) (xy 52.481986 -149.180703) (xy 52.474001 -149.126619) (xy 52.474003 -149.07195)
			(xy 52.481993 -149.017867) (xy 52.497797 -148.965532) (xy 52.521079 -148.916067) (xy 52.551336 -148.870534)
			(xy 52.587922 -148.829911) (xy 52.630049 -148.795068) (xy 52.653184 -148.7805) (xy 52.66539 -148.772551)
			(xy 52.685063 -148.751088) (xy 52.697871 -148.724941) (xy 52.702771 -148.696241) (xy 52.699363 -148.667326)
			(xy 52.694078 -148.653754) (xy 52.684581 -148.630547) (xy 52.671233 -148.582213) (xy 52.664508 -148.532522)
			(xy 52.664106 -148.50745) (xy 52.664627 -148.479565) (xy 52.672939 -148.424418) (xy 52.689377 -148.371126)
			(xy 52.713575 -148.32088) (xy 52.744991 -148.274801) (xy 52.782924 -148.233919) (xy 52.826526 -148.199147)
			(xy 52.874824 -148.171262) (xy 52.926739 -148.150887) (xy 52.98111 -148.138477) (xy 53.036724 -148.13431)
			(xy 53.092338 -148.138477) (xy 53.146709 -148.150887) (xy 53.198624 -148.171262) (xy 53.246922 -148.199147)
			(xy 53.290524 -148.233919) (xy 53.328457 -148.274801) (xy 53.359873 -148.32088) (xy 53.384071 -148.371126)
			(xy 53.400509 -148.424418) (xy 53.408821 -148.479565) (xy 53.409342 -148.50745) (xy 53.408875 -148.534782)
			(xy 53.400906 -148.588863) (xy 53.385118 -148.641198) (xy 53.36185 -148.690662) (xy 53.331601 -148.736195)
			(xy 53.295022 -148.776817) (xy 53.252897 -148.811655) (xy 53.229764 -148.82622) (xy 53.217537 -148.834138)
			(xy 53.19787 -148.855612) (xy 53.185068 -148.881767) (xy 53.180173 -148.910472) (xy 53.183584 -148.939392)
			(xy 53.18887 -148.952966) (xy 53.198345 -148.976181) (xy 53.211701 -149.024512) (xy 53.218435 -149.074199)
			(xy 53.218842 -149.09927) (xy 53.218431 -149.12434) (xy 53.211677 -149.174023) (xy 53.198339 -149.222357)
			(xy 53.18887 -149.245574) (xy 53.183624 -149.259151) (xy 53.180262 -149.288051) (xy 53.185173 -149.316729)
			(xy 53.197961 -149.342863) (xy 53.217591 -149.364338) (xy 53.229764 -149.37232) (xy 53.252885 -149.386903)
			(xy 53.295003 -149.421747) (xy 53.331579 -149.462369) (xy 53.361829 -149.507898) (xy 53.385103 -149.557358)
			(xy 53.400902 -149.609688) (xy 53.408888 -149.663764) (xy 53.408889 -149.718426) (xy 53.400905 -149.772502)
			(xy 53.385107 -149.824832) (xy 53.361834 -149.874292) (xy 53.331585 -149.919823) (xy 53.29501 -149.960446)
			(xy 53.252893 -149.995291) (xy 53.229764 -150.00986) (xy 53.217509 -150.017739) (xy 53.197842 -150.039225)
			(xy 53.185043 -150.06539) (xy 53.180156 -150.094104) (xy 53.183577 -150.12303) (xy 53.18887 -150.136606)
			(xy 53.198357 -150.159817) (xy 53.211708 -150.208149) (xy 53.218438 -150.257838) (xy 53.218842 -150.28291)
			(xy 53.21837 -150.309752) (xy 53.210665 -150.362881) (xy 53.195416 -150.414354) (xy 53.172938 -150.463106)
			(xy 53.143697 -150.508127) (xy 53.108298 -150.548487) (xy 53.067473 -150.583349) (xy 53.022069 -150.611993)
			(xy 52.973024 -150.633824) (xy 52.947316 -150.641558) (xy 52.932841 -150.646276) (xy 52.907286 -150.662788)
			(xy 52.887726 -150.686092) (xy 52.875894 -150.714122) (xy 52.87284 -150.744393) (xy 52.878835 -150.774222)
			(xy 52.885594 -150.787862) (xy 52.900228 -150.816008) (xy 52.920955 -150.875959) (xy 52.931453 -150.938517)
			(xy 52.932076 -150.970234) (xy 52.931855 -150.988253) (xy 52.928421 -151.024128) (xy 52.925218 -151.041862)
			(xy 52.922936 -151.057077) (xy 52.926453 -151.087622) (xy 52.938901 -151.115736) (xy 52.959153 -151.138871)
			(xy 52.985373 -151.154931) (xy 53.000148 -151.15921) (xy 53.027191 -151.166611) (xy 53.078917 -151.188241)
			(xy 53.126922 -151.217205) (xy 53.170174 -151.25288) (xy 53.207741 -151.294499) (xy 53.238815 -151.341165)
			(xy 53.262728 -151.391876) (xy 53.278965 -151.44554) (xy 53.287177 -151.501001) (xy 53.287676 -151.529034)
			(xy 53.287254 -151.556288) (xy 53.279492 -151.610239) (xy 53.264131 -151.662537) (xy 53.241483 -151.712117)
			(xy 53.21201 -151.757968) (xy 53.176312 -151.799159) (xy 53.135115 -151.83485) (xy 53.089259 -151.864315)
			(xy 53.039675 -151.886954) (xy 52.987375 -151.902306) (xy 52.933422 -151.910058) (xy 52.906168 -151.910542)
			(xy 52.878594 -151.91005) (xy 52.824022 -151.902105) (xy 52.771161 -151.886387) (xy 52.721115 -151.863222)
			(xy 52.674925 -151.833093) (xy 52.633554 -151.796628) (xy 52.615338 -151.775922) (xy 52.60544 -151.765024)
			(xy 52.58079 -151.748949) (xy 52.552582 -151.740565) (xy 52.523154 -151.740565) (xy 52.494946 -151.748949)
			(xy 52.470296 -151.765024) (xy 52.460398 -151.775922) (xy 52.442183 -151.796628) (xy 52.400812 -151.833093)
			(xy 52.354622 -151.86322) (xy 52.304575 -151.886383) (xy 52.251714 -151.902099) (xy 52.197142 -151.910039)
			(xy 52.141994 -151.910039) (xy 52.087422 -151.902099) (xy 52.034561 -151.886383) (xy 51.984514 -151.86322)
			(xy 51.938324 -151.833093) (xy 51.896953 -151.796628) (xy 51.878738 -151.775922) (xy 51.86884 -151.765024)
			(xy 51.84419 -151.748949) (xy 51.815982 -151.740565) (xy 51.786554 -151.740565) (xy 51.758346 -151.748949)
			(xy 51.733696 -151.765024) (xy 51.723798 -151.775922) (xy 51.705596 -151.796642) (xy 51.664225 -151.83311)
			(xy 51.618033 -151.863241) (xy 51.567983 -151.886405) (xy 51.515119 -151.90212) (xy 51.460543 -151.910058)
			(xy 51.432968 -151.910542) (xy 51.405718 -151.910052) (xy 51.351772 -151.902292) (xy 51.299479 -151.886935)
			(xy 51.249904 -151.864292) (xy 51.204055 -151.834826) (xy 51.162866 -151.799135) (xy 51.127175 -151.757946)
			(xy 51.097709 -151.712098) (xy 51.075066 -151.662523) (xy 51.059708 -151.61023) (xy 51.051948 -151.556284)
			(xy 51.05146 -151.529034) (xy 51.052043 -151.501181) (xy 51.060161 -151.44607) (xy 51.0762 -151.392722)
			(xy 51.09982 -151.342272) (xy 51.130519 -151.295788) (xy 51.167647 -151.254258) (xy 51.210414 -151.218563)
			(xy 51.257914 -151.189461) (xy 51.309138 -151.167569) (xy 51.33594 -151.159972) (xy 51.350063 -151.155719)
			(xy 51.375204 -151.14032) (xy 51.394916 -151.118396) (xy 51.407566 -151.091764) (xy 51.412104 -151.062632)
			(xy 51.410616 -151.047958) (xy 51.408945 -151.034942) (xy 51.407166 -151.008757) (xy 51.40706 -150.995634)
			(xy 51.407158 -150.981485) (xy 51.409189 -150.953262) (xy 51.411124 -150.939246) (xy 51.412683 -150.925896)
			(xy 51.409585 -150.899209) (xy 51.39962 -150.874259) (xy 51.38348 -150.852781) (xy 51.362288 -150.836267)
			(xy 51.337516 -150.825867) (xy 51.324256 -150.823676) (xy 51.297113 -150.81953) (xy 51.244287 -150.804561)
			(xy 51.194152 -150.782174) (xy 51.147744 -150.752832) (xy 51.106021 -150.717141) (xy 51.069844 -150.675838)
			(xy 51.039961 -150.629777) (xy 51.016989 -150.579907) (xy 51.001402 -150.52726) (xy 50.993522 -150.472923)
			(xy 50.99304 -150.44547) (xy 37.580824 -150.44547) (xy 38.780225 -151.644871) (xy 43.782962 -151.644871)
			(xy 43.786968 -151.589723) (xy 43.798892 -151.535731) (xy 43.818485 -151.484026) (xy 43.845337 -151.435691)
			(xy 43.878885 -151.391738) (xy 43.898312 -151.372062) (xy 43.907656 -151.362295) (xy 43.921334 -151.338994)
			(xy 43.928423 -151.312922) (xy 43.928426 -151.285903) (xy 43.921344 -151.259829) (xy 43.907671 -151.236525)
			(xy 43.898312 -151.226774) (xy 43.880473 -151.208774) (xy 43.849246 -151.16886) (xy 43.823579 -151.125162)
			(xy 43.803922 -151.078452) (xy 43.790624 -151.029549) (xy 43.783917 -150.979317) (xy 43.783504 -150.953978)
			(xy 43.783957 -150.926726) (xy 43.791717 -150.872776) (xy 43.807076 -150.82048) (xy 43.82972 -150.770902)
			(xy 43.85919 -150.725051) (xy 43.894885 -150.683861) (xy 43.936078 -150.64817) (xy 43.981932 -150.618704)
			(xy 44.031512 -150.596064) (xy 44.083809 -150.58071) (xy 44.13776 -150.572955) (xy 44.165012 -150.57247)
			(xy 44.194271 -150.573037) (xy 44.252103 -150.581981) (xy 44.307894 -150.599642) (xy 44.360337 -150.625607)
			(xy 44.408206 -150.659268) (xy 44.42968 -150.67915) (xy 44.439987 -150.688465) (xy 44.464413 -150.701673)
			(xy 44.491499 -150.707794) (xy 44.519231 -150.706373) (xy 44.545549 -150.697515) (xy 44.568497 -150.681879)
			(xy 44.577762 -150.67153) (xy 44.596006 -150.650711) (xy 44.637408 -150.613972) (xy 44.683688 -150.583606)
			(xy 44.733873 -150.560253) (xy 44.786908 -150.544404) (xy 44.841678 -150.536392) (xy 44.869354 -150.535894)
			(xy 44.896723 -150.536388) (xy 44.950901 -150.5442) (xy 45.003404 -150.559682) (xy 45.053151 -150.582518)
			(xy 45.099119 -150.612236) (xy 45.120052 -150.629874) (xy 45.13138 -150.63911) (xy 45.157937 -150.651286)
			(xy 45.186854 -150.655459) (xy 45.215771 -150.651286) (xy 45.242328 -150.63911) (xy 45.253656 -150.629874)
			(xy 45.274589 -150.612233) (xy 45.320557 -150.582509) (xy 45.370303 -150.559663) (xy 45.422805 -150.544167)
			(xy 45.476983 -150.536338) (xy 45.531725 -150.536338) (xy 45.585903 -150.544167) (xy 45.638405 -150.559663)
			(xy 45.688151 -150.582509) (xy 45.734119 -150.612233) (xy 45.755052 -150.629874) (xy 45.76638 -150.63911)
			(xy 45.792937 -150.651286) (xy 45.821854 -150.655459) (xy 45.850771 -150.651286) (xy 45.877328 -150.63911)
			(xy 45.888656 -150.629874) (xy 45.909589 -150.612233) (xy 45.955557 -150.582509) (xy 46.005303 -150.559663)
			(xy 46.057805 -150.544167) (xy 46.111983 -150.536338) (xy 46.166725 -150.536338) (xy 46.220903 -150.544167)
			(xy 46.273405 -150.559663) (xy 46.323151 -150.582509) (xy 46.369119 -150.612233) (xy 46.390052 -150.629874)
			(xy 46.40138 -150.63911) (xy 46.427937 -150.651286) (xy 46.456854 -150.655459) (xy 46.485771 -150.651286)
			(xy 46.512328 -150.63911) (xy 46.523656 -150.629874) (xy 46.54459 -150.612238) (xy 46.590563 -150.582527)
			(xy 46.64031 -150.55969) (xy 46.69281 -150.544199) (xy 46.746985 -150.536369) (xy 46.774354 -150.535894)
			(xy 46.804152 -150.536484) (xy 46.863022 -150.545758) (xy 46.919734 -150.56407) (xy 46.972911 -150.590976)
			(xy 47.021258 -150.625822) (xy 47.042832 -150.646384) (xy 47.054372 -150.657021) (xy 47.082273 -150.671355)
			(xy 47.113206 -150.676557) (xy 47.144261 -150.672139) (xy 47.172516 -150.658516) (xy 47.18431 -150.648162)
			(xy 47.205669 -150.628715) (xy 47.25316 -150.595835) (xy 47.305067 -150.570493) (xy 47.360201 -150.553269)
			(xy 47.417303 -150.544556) (xy 47.446184 -150.544022) (xy 47.473438 -150.54447) (xy 47.527391 -150.552226)
			(xy 47.579691 -150.567581) (xy 47.629273 -150.590224) (xy 47.675128 -150.619693) (xy 47.716321 -150.655389)
			(xy 47.752015 -150.696584) (xy 47.781483 -150.742439) (xy 47.804124 -150.792022) (xy 47.819477 -150.844323)
			(xy 47.827231 -150.898276) (xy 47.827692 -150.92553) (xy 47.827299 -150.950869) (xy 47.820586 -151.001101)
			(xy 47.807281 -151.050002) (xy 47.787619 -151.096711) (xy 47.761946 -151.140406) (xy 47.730715 -151.180317)
			(xy 47.712884 -151.198326) (xy 47.703553 -151.208104) (xy 47.689874 -151.231402) (xy 47.682784 -151.257471)
			(xy 47.682779 -151.284487) (xy 47.689858 -151.310559) (xy 47.703527 -151.333863) (xy 47.712884 -151.343614)
			(xy 47.732318 -151.363281) (xy 47.76586 -151.407234) (xy 47.792706 -151.455569) (xy 47.812293 -151.507273)
			(xy 47.824211 -151.561262) (xy 47.828212 -151.616407) (xy 47.824209 -151.671552) (xy 47.812289 -151.725541)
			(xy 47.7927 -151.777244) (xy 47.765852 -151.825578) (xy 47.732309 -151.86953) (xy 47.712884 -151.889206)
			(xy 47.703473 -151.898913) (xy 47.6898 -151.922231) (xy 47.68272 -151.948319) (xy 47.682729 -151.975351)
			(xy 47.689827 -152.001433) (xy 47.703516 -152.024742) (xy 47.712884 -152.034494) (xy 47.730707 -152.05251)
			(xy 47.761935 -152.09242) (xy 47.787605 -152.136114) (xy 47.807264 -152.182822) (xy 47.820566 -152.231722)
			(xy 47.827277 -152.281952) (xy 47.827692 -152.30729) (xy 47.827235 -152.334543) (xy 47.819479 -152.388495)
			(xy 47.804124 -152.440794) (xy 47.781481 -152.490375) (xy 47.752013 -152.536229) (xy 47.716318 -152.577423)
			(xy 47.675125 -152.613116) (xy 47.62927 -152.642584) (xy 47.579689 -152.665226) (xy 47.527389 -152.680581)
			(xy 47.473437 -152.688336) (xy 47.446184 -152.688798) (xy 47.416385 -152.688249) (xy 47.357513 -152.678966)
			(xy 47.300799 -152.660644) (xy 47.247624 -152.633728) (xy 47.199279 -152.598874) (xy 47.177706 -152.578308)
			(xy 47.166217 -152.567611) (xy 47.138297 -152.553284) (xy 47.107349 -152.548094) (xy 47.076284 -152.552527)
			(xy 47.048023 -152.566167) (xy 47.036228 -152.57653) (xy 47.014852 -152.595958) (xy 46.967366 -152.628841)
			(xy 46.915463 -152.654186) (xy 46.860333 -152.671415) (xy 46.803234 -152.680133) (xy 46.774354 -152.68067)
			(xy 46.746985 -152.68018) (xy 46.692806 -152.672369) (xy 46.640303 -152.656886) (xy 46.590556 -152.634049)
			(xy 46.544588 -152.604329) (xy 46.523656 -152.58669) (xy 46.512328 -152.577454) (xy 46.485771 -152.565278)
			(xy 46.456854 -152.561105) (xy 46.427937 -152.565278) (xy 46.40138 -152.577454) (xy 46.390052 -152.58669)
			(xy 46.369119 -152.604331) (xy 46.323151 -152.634055) (xy 46.273405 -152.656901) (xy 46.220903 -152.672397)
			(xy 46.166725 -152.680226) (xy 46.111983 -152.680226) (xy 46.057805 -152.672397) (xy 46.005303 -152.656901)
			(xy 45.955557 -152.634055) (xy 45.909589 -152.604331) (xy 45.888656 -152.58669) (xy 45.877328 -152.577454)
			(xy 45.850771 -152.565278) (xy 45.821854 -152.561105) (xy 45.792937 -152.565278) (xy 45.76638 -152.577454)
			(xy 45.755052 -152.58669) (xy 45.734119 -152.604331) (xy 45.688151 -152.634055) (xy 45.638405 -152.656901)
			(xy 45.585903 -152.672397) (xy 45.531725 -152.680226) (xy 45.476983 -152.680226) (xy 45.422805 -152.672397)
			(xy 45.370303 -152.656901) (xy 45.320557 -152.634055) (xy 45.274589 -152.604331) (xy 45.253656 -152.58669)
			(xy 45.242328 -152.577454) (xy 45.215771 -152.565278) (xy 45.186854 -152.561105) (xy 45.157937 -152.565278)
			(xy 45.13138 -152.577454) (xy 45.120052 -152.58669) (xy 45.09911 -152.604317) (xy 45.05314 -152.634031)
			(xy 45.003395 -152.656869) (xy 44.950897 -152.672363) (xy 44.896723 -152.680194) (xy 44.869354 -152.68067)
			(xy 44.840094 -152.680113) (xy 44.782263 -152.671165) (xy 44.726473 -152.653501) (xy 44.674029 -152.627534)
			(xy 44.62616 -152.593872) (xy 44.604686 -152.57399) (xy 44.594404 -152.564648) (xy 44.569969 -152.551451)
			(xy 44.542878 -152.545339) (xy 44.515144 -152.546766) (xy 44.488824 -152.555626) (xy 44.465872 -152.571261)
			(xy 44.456604 -152.58161) (xy 44.438387 -152.602453) (xy 44.396978 -152.639189) (xy 44.350692 -152.669551)
			(xy 44.300502 -152.692899) (xy 44.247463 -152.708743) (xy 44.19269 -152.71675) (xy 44.165012 -152.717246)
			(xy 44.137763 -152.716711) (xy 44.083819 -152.708957) (xy 44.031527 -152.693605) (xy 43.981953 -152.670968)
			(xy 43.936104 -152.641507) (xy 43.894915 -152.60582) (xy 43.859223 -152.564636) (xy 43.829756 -152.518791)
			(xy 43.807112 -152.469219) (xy 43.791754 -152.41693) (xy 43.783993 -152.362987) (xy 43.783504 -152.335738)
			(xy 43.783942 -152.3104) (xy 43.790646 -152.26017) (xy 43.803942 -152.21127) (xy 43.823596 -152.164561)
			(xy 43.849261 -152.120865) (xy 43.880485 -152.080952) (xy 43.898312 -152.062942) (xy 43.907675 -152.053192)
			(xy 43.921352 -152.029887) (xy 43.928439 -152.00381) (xy 43.928438 -151.976787) (xy 43.921351 -151.950711)
			(xy 43.907674 -151.927405) (xy 43.898312 -151.917654) (xy 43.878846 -151.898018) (xy 43.845305 -151.85406)
			(xy 43.818461 -151.805721) (xy 43.798875 -151.754012) (xy 43.786959 -151.700019) (xy 43.782962 -151.644871)
			(xy 38.780225 -151.644871) (xy 40.260074 -153.12472) (xy 51.012924 -153.12472) (xy 51.012928 -153.070227)
			(xy 51.020687 -153.016288) (xy 51.036042 -152.964003) (xy 51.058683 -152.914435) (xy 51.088146 -152.868593)
			(xy 51.123834 -152.827411) (xy 51.165019 -152.791727) (xy 51.210863 -152.762267) (xy 51.260433 -152.739631)
			(xy 51.312719 -152.72428) (xy 51.366659 -152.716526) (xy 51.421152 -152.716526) (xy 51.475091 -152.724282)
			(xy 51.527377 -152.739635) (xy 51.576946 -152.762272) (xy 51.62279 -152.791734) (xy 51.663974 -152.827419)
			(xy 51.69966 -152.868602) (xy 51.729122 -152.914444) (xy 51.751761 -152.964013) (xy 51.767116 -153.016299)
			(xy 51.774873 -153.070237) (xy 51.77536 -153.097484) (xy 51.77493 -153.122875) (xy 51.768173 -153.173207)
			(xy 51.761898 -153.197814) (xy 51.758525 -153.212472) (xy 51.759445 -153.242518) (xy 51.769069 -153.270996)
			(xy 51.786564 -153.29544) (xy 51.810415 -153.313736) (xy 51.838559 -153.324299) (xy 51.868558 -153.326215)
			(xy 51.88331 -153.32329) (xy 51.90484 -153.318535) (xy 51.948639 -153.313442) (xy 51.970686 -153.31313)
			(xy 51.97094 -153.31313) (xy 51.998187 -153.313621) (xy 52.052126 -153.321382) (xy 52.104412 -153.336739)
			(xy 52.153979 -153.359381) (xy 52.199821 -153.388847) (xy 52.241002 -153.424536) (xy 52.276686 -153.465723)
			(xy 52.306145 -153.511568) (xy 52.32878 -153.561139) (xy 52.34413 -153.613427) (xy 52.351883 -153.667367)
			(xy 52.351881 -153.721861) (xy 52.344124 -153.775801) (xy 52.32877 -153.828087) (xy 52.306131 -153.877657)
			(xy 52.276669 -153.9235) (xy 52.240982 -153.964684) (xy 52.199798 -154.00037) (xy 52.153955 -154.029832)
			(xy 52.104385 -154.052471) (xy 52.052099 -154.067824) (xy 51.998159 -154.075581) (xy 51.943665 -154.075583)
			(xy 51.889725 -154.067829) (xy 51.837437 -154.052479) (xy 51.787866 -154.029844) (xy 51.742021 -154.000384)
			(xy 51.700835 -153.964701) (xy 51.665146 -153.923519) (xy 51.63568 -153.877678) (xy 51.613039 -153.82811)
			(xy 51.597681 -153.775824) (xy 51.589921 -153.721885) (xy 51.589432 -153.694638) (xy 51.589867 -153.669247)
			(xy 51.596621 -153.618916) (xy 51.602894 -153.594308) (xy 51.606253 -153.579646) (xy 51.605338 -153.549601)
			(xy 51.595718 -153.521123) (xy 51.578225 -153.496677) (xy 51.554375 -153.478382) (xy 51.526232 -153.46782)
			(xy 51.496234 -153.465906) (xy 51.481482 -153.468832) (xy 51.459952 -153.473589) (xy 51.416153 -153.47868)
			(xy 51.394106 -153.478992) (xy 51.393852 -153.478992) (xy 51.366605 -153.47847) (xy 51.312667 -153.470709)
			(xy 51.260383 -153.45535) (xy 51.210816 -153.432707) (xy 51.164976 -153.403241) (xy 51.123796 -153.367551)
			(xy 51.088114 -153.326364) (xy 51.058657 -153.280518) (xy 51.036024 -153.230947) (xy 51.020675 -153.17866)
			(xy 51.012924 -153.12472) (xy 40.260074 -153.12472) (xy 41.592754 -154.4574) (xy 48.98263 -154.4574)
			(xy 49.680368 -153.759916) (xy 49.698444 -153.742637) (xy 49.739995 -153.714831) (xy 49.786172 -153.695663)
			(xy 49.835202 -153.685872) (xy 49.8602 -153.68524) (xy 50.592482 -153.68524) (xy 50.617478 -153.685882)
			(xy 50.6665 -153.695684) (xy 50.712671 -153.714856) (xy 50.754218 -153.742662) (xy 50.772314 -153.759916)
			(xy 51.131724 -154.119326) (xy 51.15306 -154.119326) (xy 51.180337 -154.119751) (xy 51.234345 -154.127446)
			(xy 51.286706 -154.142755) (xy 51.336352 -154.165368) (xy 51.382271 -154.194821) (xy 51.423526 -154.230516)
			(xy 51.459275 -154.271723) (xy 51.48879 -154.317603) (xy 51.511468 -154.367219) (xy 51.526847 -154.41956)
			(xy 51.534613 -154.473557) (xy 51.535076 -154.500834) (xy 51.534654 -154.528088) (xy 51.526892 -154.582039)
			(xy 51.511531 -154.634337) (xy 51.488883 -154.683917) (xy 51.45941 -154.729768) (xy 51.423712 -154.770959)
			(xy 51.382515 -154.80665) (xy 51.336659 -154.836115) (xy 51.287075 -154.858754) (xy 51.234775 -154.874106)
			(xy 51.180822 -154.881858) (xy 51.153568 -154.882342) (xy 51.123881 -154.88176) (xy 51.065222 -154.87257)
			(xy 51.008695 -154.854402) (xy 50.955667 -154.827694) (xy 50.907418 -154.793091) (xy 50.865114 -154.75143)
			(xy 50.84699 -154.72791) (xy 50.838564 -154.717303) (xy 50.817251 -154.700596) (xy 50.792297 -154.690077)
			(xy 50.765456 -154.686487) (xy 50.738615 -154.690077) (xy 50.713661 -154.700596) (xy 50.692348 -154.717303)
			(xy 50.683922 -154.72791) (xy 50.665776 -154.751412) (xy 50.623474 -154.793073) (xy 50.575229 -154.827678)
			(xy 50.522206 -154.854392) (xy 50.465685 -154.87257) (xy 50.40703 -154.881774) (xy 50.377344 -154.882342)
			(xy 50.347294 -154.881749) (xy 50.287937 -154.87232) (xy 50.230792 -154.853703) (xy 50.177271 -154.826358)
			(xy 50.128699 -154.790963) (xy 50.107088 -154.770074) (xy 50.092356 -154.755088) (xy 49.981104 -154.755088)
			(xy 49.436782 -155.29941) (xy 49.418686 -155.316648) (xy 49.377123 -155.344388) (xy 49.330948 -155.363492)
			(xy 49.281935 -155.373226) (xy 49.25695 -155.373832) (xy 41.318434 -155.373832) (xy 41.293449 -155.373248)
			(xy 41.244439 -155.363497) (xy 41.19827 -155.344381) (xy 41.156711 -155.316635) (xy 41.138602 -155.29941)
			(xy 35.283648 -149.444456) (xy 35.266386 -149.426365) (xy 35.238575 -149.38482) (xy 35.219403 -149.338647)
			(xy 35.209607 -149.289621) (xy 35.208972 -149.264624) (xy 35.208972 -140.38453) (xy 33.666938 -138.842496)
			(xy 32.498792 -138.842496) (xy 32.473796 -138.841859) (xy 32.424774 -138.832054) (xy 32.378604 -138.812881)
			(xy 32.337057 -138.785074) (xy 32.31896 -138.76782) (xy 31.821628 -138.270488) (xy 31.804378 -138.252387)
			(xy 31.776565 -138.210844) (xy 31.75739 -138.164675) (xy 31.747589 -138.115652) (xy 31.746952 -138.090656)
			(xy 31.746952 -135.279892) (xy 31.42996 -135.279892) (xy 31.289244 -135.139176) (xy 31.289244 -133.561074)
			(xy 31.170626 -133.442456) (xy 27.106626 -133.442456) (xy 26.598372 -132.934202) (xy 26.598372 -132.575808)
			(xy 26.575776 -132.559256) (xy 26.535324 -132.520514) (xy 26.50097 -132.476274) (xy 26.473455 -132.427486)
			(xy 26.453368 -132.375199) (xy 26.441142 -132.320537) (xy 26.43704 -132.264676) (xy 26.441149 -132.208814)
			(xy 26.453382 -132.154154) (xy 26.473476 -132.10187) (xy 26.500997 -132.053086) (xy 26.535356 -132.00885)
			(xy 26.575814 -131.970113) (xy 26.598372 -131.953508) (xy 26.598372 -128.682242) (xy 26.59784 -128.659015)
			(xy 26.588435 -128.613522) (xy 26.570063 -128.570854) (xy 26.543477 -128.532759) (xy 26.526998 -128.51638)
			(xy 26.510742 -128.500886) (xy 26.500556 -128.491723) (xy 26.476402 -128.478803) (xy 26.449682 -128.472777)
			(xy 26.422321 -128.474077) (xy 26.396292 -128.482611) (xy 26.373473 -128.497763) (xy 26.355508 -128.51844)
			(xy 26.349198 -128.530604) (xy 26.337199 -128.554527) (xy 26.307461 -128.599025) (xy 26.271794 -128.638928)
			(xy 26.230898 -128.673453) (xy 26.185578 -128.701921) (xy 26.136723 -128.723775) (xy 26.085292 -128.738584)
			(xy 26.032296 -128.746057) (xy 26.005536 -128.746504) (xy 25.978281 -128.746051) (xy 25.924326 -128.738298)
			(xy 25.872023 -128.722945) (xy 25.822438 -128.700304) (xy 25.77658 -128.670837) (xy 25.735382 -128.635143)
			(xy 25.699684 -128.593949) (xy 25.670213 -128.548094) (xy 25.647567 -128.498511) (xy 25.632209 -128.446209)
			(xy 25.624451 -128.392255) (xy 21.306771 -128.392255) (xy 19.433286 -130.265678) (xy 19.433286 -130.936663)
			(xy 24.961212 -130.936663) (xy 24.968967 -130.882704) (xy 24.984323 -130.830398) (xy 25.006967 -130.780809)
			(xy 25.036438 -130.734948) (xy 25.072136 -130.693749) (xy 25.113334 -130.658049) (xy 25.159193 -130.628576)
			(xy 25.208781 -130.60593) (xy 25.261086 -130.590571) (xy 25.315045 -130.582813) (xy 25.369559 -130.582813)
			(xy 25.423518 -130.590572) (xy 25.475823 -130.605931) (xy 25.52541 -130.628578) (xy 25.571269 -130.658051)
			(xy 25.612467 -130.693752) (xy 25.648164 -130.734952) (xy 25.677635 -130.780813) (xy 25.700278 -130.830401)
			(xy 25.715634 -130.882708) (xy 25.723389 -130.936667) (xy 25.72385 -130.963924) (xy 25.72318 -130.996583)
			(xy 25.712073 -131.060948) (xy 25.701752 -131.09194) (xy 25.697687 -131.10491) (xy 25.695635 -131.131995)
			(xy 25.700795 -131.158664) (xy 25.712802 -131.183029) (xy 25.730807 -131.203368) (xy 25.753536 -131.218241)
			(xy 25.779382 -131.226598) (xy 25.806516 -131.227846) (xy 25.819862 -131.22529) (xy 25.840537 -131.220891)
			(xy 25.882546 -131.216187) (xy 25.903682 -131.215892) (xy 25.930936 -131.216336) (xy 25.984891 -131.224091)
			(xy 26.037192 -131.239445) (xy 26.086776 -131.262087) (xy 26.132633 -131.291555) (xy 26.17383 -131.327249)
			(xy 26.209527 -131.368442) (xy 26.238999 -131.414297) (xy 26.261644 -131.463879) (xy 26.277003 -131.51618)
			(xy 26.284762 -131.570134) (xy 26.284764 -131.624642) (xy 26.277008 -131.678597) (xy 26.261653 -131.730898)
			(xy 26.23901 -131.780482) (xy 26.209542 -131.826338) (xy 26.173847 -131.867534) (xy 26.132653 -131.903231)
			(xy 26.086798 -131.932702) (xy 26.037215 -131.955346) (xy 25.984914 -131.970704) (xy 25.93096 -131.978463)
			(xy 25.876452 -131.978464) (xy 25.822497 -131.970707) (xy 25.770196 -131.955351) (xy 25.720613 -131.932707)
			(xy 25.674757 -131.903238) (xy 25.633562 -131.867543) (xy 25.597865 -131.826348) (xy 25.568396 -131.780492)
			(xy 25.545751 -131.730909) (xy 25.530394 -131.678608) (xy 25.522637 -131.624654) (xy 25.522174 -131.5974)
			(xy 25.522829 -131.564741) (xy 25.533946 -131.500375) (xy 25.544272 -131.469384) (xy 25.548512 -131.456463)
			(xy 25.550554 -131.429351) (xy 25.545376 -131.40266) (xy 25.533345 -131.378277) (xy 25.515313 -131.357929)
			(xy 25.492555 -131.343053) (xy 25.46668 -131.334703) (xy 25.439519 -131.333468) (xy 25.426162 -131.336034)
			(xy 25.405486 -131.340428) (xy 25.363478 -131.345136) (xy 25.342342 -131.345432) (xy 25.315085 -131.34499)
			(xy 25.261125 -131.337238) (xy 25.208818 -131.321884) (xy 25.159229 -131.299243) (xy 25.113366 -131.269775)
			(xy 25.072164 -131.23408) (xy 25.036462 -131.192884) (xy 25.006986 -131.147026) (xy 24.984337 -131.09744)
			(xy 24.968976 -131.045135) (xy 24.961214 -130.991177) (xy 24.961212 -130.936663) (xy 19.433286 -130.936663)
			(xy 19.433286 -133.6802) (xy 24.987502 -133.6802) (xy 24.991573 -133.624578) (xy 25.003699 -133.570141)
			(xy 25.023622 -133.51805) (xy 25.050918 -133.469415) (xy 25.085004 -133.425272) (xy 25.125153 -133.386563)
			(xy 25.170511 -133.354112) (xy 25.220111 -133.328611) (xy 25.272895 -133.310604) (xy 25.327738 -133.300474)
			(xy 25.383472 -133.298437) (xy 25.438909 -133.304537) (xy 25.492866 -133.318643) (xy 25.544195 -133.340455)
			(xy 25.591801 -133.369509) (xy 25.634669 -133.405184) (xy 25.671886 -133.446721) (xy 25.702659 -133.493234)
			(xy 25.726331 -133.543731) (xy 25.742399 -133.597138) (xy 25.750519 -133.652314) (xy 25.751028 -133.6802)
			(xy 25.750519 -133.708086) (xy 25.742399 -133.763262) (xy 25.726331 -133.816669) (xy 25.702659 -133.867166)
			(xy 25.671886 -133.913679) (xy 25.634669 -133.955216) (xy 25.591801 -133.990891) (xy 25.544195 -134.019945)
			(xy 25.492866 -134.041757) (xy 25.438909 -134.055863) (xy 25.383472 -134.061963) (xy 25.327738 -134.059926)
			(xy 25.272895 -134.049796) (xy 25.220111 -134.031789) (xy 25.170511 -134.006288) (xy 25.125153 -133.973837)
			(xy 25.085004 -133.935128) (xy 25.050918 -133.890985) (xy 25.023622 -133.84235) (xy 25.003699 -133.790259)
			(xy 24.991573 -133.735822) (xy 24.987502 -133.6802) (xy 19.433286 -133.6802) (xy 19.433286 -134.187057)
			(xy 28.166707 -134.187057) (xy 28.166707 -134.132543) (xy 28.174466 -134.078583) (xy 28.189825 -134.026277)
			(xy 28.212472 -133.976689) (xy 28.241945 -133.930829) (xy 28.277646 -133.88963) (xy 28.318846 -133.853932)
			(xy 28.364708 -133.824461) (xy 28.414297 -133.801817) (xy 28.466605 -133.786461) (xy 28.520565 -133.778705)
			(xy 28.547822 -133.778244) (xy 28.5742 -133.778728) (xy 28.626454 -133.785982) (xy 28.677212 -133.800363)
			(xy 28.725505 -133.821597) (xy 28.770415 -133.84928) (xy 28.811084 -133.882882) (xy 28.846739 -133.921766)
			(xy 28.876699 -133.965189) (xy 28.888944 -133.988556) (xy 28.895646 -134.000915) (xy 28.914621 -134.021643)
			(xy 28.938535 -134.036405) (xy 28.965571 -134.044077) (xy 28.993673 -134.044077) (xy 29.020709 -134.036405)
			(xy 29.044623 -134.021643) (xy 29.063598 -134.000915) (xy 29.0703 -133.988556) (xy 29.082506 -133.965166)
			(xy 29.112475 -133.921743) (xy 29.148136 -133.88286) (xy 29.188811 -133.849256) (xy 29.233725 -133.821571)
			(xy 29.282022 -133.800334) (xy 29.332783 -133.785948) (xy 29.385042 -133.778688) (xy 29.411422 -133.778244)
			(xy 29.437962 -133.778742) (xy 29.490529 -133.786115) (xy 29.541566 -133.800702) (xy 29.59009 -133.822221)
			(xy 29.635162 -133.850258) (xy 29.675915 -133.884271) (xy 29.71156 -133.923603) (xy 29.741411 -133.967495)
			(xy 29.75356 -133.991096) (xy 29.760607 -134.004333) (xy 29.781101 -134.026212) (xy 29.807058 -134.04121)
			(xy 29.836249 -134.048038) (xy 29.866165 -134.04611) (xy 29.894238 -134.035592) (xy 29.906468 -134.02691)
			(xy 29.931543 -134.008577) (xy 29.986405 -133.979453) (xy 30.045259 -133.9596) (xy 30.106552 -133.949541)
			(xy 30.137608 -133.948932) (xy 30.164862 -133.949338) (xy 30.218814 -133.957097) (xy 30.271114 -133.972454)
			(xy 30.320695 -133.995098) (xy 30.366549 -134.024568) (xy 30.407743 -134.060263) (xy 30.443437 -134.101457)
			(xy 30.472906 -134.147312) (xy 30.495549 -134.196894) (xy 30.510905 -134.249194) (xy 30.518662 -134.303146)
			(xy 30.518662 -134.357654) (xy 30.510905 -134.411606) (xy 30.495549 -134.463906) (xy 30.472906 -134.513488)
			(xy 30.443437 -134.559343) (xy 30.407743 -134.600537) (xy 30.366549 -134.636232) (xy 30.320695 -134.665702)
			(xy 30.271114 -134.688346) (xy 30.218814 -134.703703) (xy 30.164862 -134.711462) (xy 30.137608 -134.711948)
			(xy 30.111066 -134.711513) (xy 30.058496 -134.70413) (xy 30.007457 -134.689533) (xy 29.958933 -134.668005)
			(xy 29.913861 -134.639959) (xy 29.873109 -134.605939) (xy 29.837466 -134.566599) (xy 29.807618 -134.5227)
			(xy 29.79547 -134.499096) (xy 29.788388 -134.48588) (xy 29.767901 -134.464005) (xy 29.741952 -134.449007)
			(xy 29.71277 -134.442176) (xy 29.68286 -134.444097) (xy 29.654792 -134.454606) (xy 29.642562 -134.463282)
			(xy 29.617477 -134.4816) (xy 29.562619 -134.510728) (xy 29.503768 -134.530585) (xy 29.442477 -134.540648)
			(xy 29.411422 -134.54126) (xy 29.38504 -134.540875) (xy 29.332779 -134.533611) (xy 29.282017 -134.519218)
			(xy 29.23372 -134.497972) (xy 29.18881 -134.470275) (xy 29.148143 -134.436658) (xy 29.112493 -134.39776)
			(xy 29.082541 -134.354322) (xy 29.0703 -134.330948) (xy 29.063598 -134.318589) (xy 29.044623 -134.297861)
			(xy 29.020709 -134.283099) (xy 28.993673 -134.275427) (xy 28.965571 -134.275427) (xy 28.938535 -134.283099)
			(xy 28.914621 -134.297861) (xy 28.895646 -134.318589) (xy 28.888944 -134.330948) (xy 28.876706 -134.35432)
			(xy 28.846742 -134.397742) (xy 28.811085 -134.436626) (xy 28.770415 -134.470231) (xy 28.725505 -134.497917)
			(xy 28.677213 -134.519158) (xy 28.626456 -134.533548) (xy 28.574201 -134.540813) (xy 28.547822 -134.54126)
			(xy 28.520565 -134.540895) (xy 28.466605 -134.533139) (xy 28.414297 -134.517783) (xy 28.364708 -134.495139)
			(xy 28.318847 -134.465668) (xy 28.277646 -134.42997) (xy 28.241945 -134.388771) (xy 28.212472 -134.342911)
			(xy 28.189825 -134.293323) (xy 28.174466 -134.241017) (xy 28.166707 -134.187057) (xy 19.433286 -134.187057)
			(xy 19.433286 -153.766012) (xy 24.446484 -153.766012) (xy 24.446981 -153.661335) (xy 24.454935 -153.452132)
			(xy 24.470832 -153.243382) (xy 24.494648 -153.035387) (xy 24.52635 -152.828446) (xy 24.565891 -152.62286)
			(xy 24.613215 -152.418925) (xy 24.668252 -152.216934) (xy 24.730925 -152.017181) (xy 24.801141 -151.819953)
			(xy 24.8788 -151.625535) (xy 24.96379 -151.434208) (xy 25.055987 -151.246248) (xy 25.15526 -151.061927)
			(xy 25.261463 -150.881511) (xy 25.374445 -150.70526) (xy 25.494041 -150.533429) (xy 25.62008 -150.366266)
			(xy 25.752378 -150.204012) (xy 25.890746 -150.046902) (xy 26.034983 -149.895162) (xy 26.184881 -149.749012)
			(xy 26.340224 -149.608663) (xy 26.500787 -149.474317) (xy 26.666338 -149.346169) (xy 26.836638 -149.224403)
			(xy 27.011442 -149.109195) (xy 27.190497 -149.000712) (xy 27.373544 -148.89911) (xy 27.560319 -148.804536)
			(xy 27.750553 -148.717126) (xy 27.94397 -148.637007) (xy 28.140292 -148.564295) (xy 28.339234 -148.499094)
			(xy 28.54051 -148.441499) (xy 28.743829 -148.391593) (xy 28.948897 -148.349448) (xy 29.155419 -148.315124)
			(xy 29.363095 -148.288671) (xy 29.571627 -148.270128) (xy 29.780712 -148.259522) (xy 29.99005 -148.256866)
			(xy 30.199337 -148.262167) (xy 30.408272 -148.275415) (xy 30.616552 -148.296591) (xy 30.823878 -148.325666)
			(xy 31.029949 -148.362597) (xy 31.234468 -148.40733) (xy 31.43714 -148.459802) (xy 31.637672 -148.519936)
			(xy 31.835775 -148.587645) (xy 32.031162 -148.662832) (xy 32.223551 -148.745389) (xy 32.412665 -148.835195)
			(xy 32.598231 -148.932122) (xy 32.779979 -149.036029) (xy 32.957649 -149.146766) (xy 33.130983 -149.264174)
			(xy 33.299731 -149.388082) (xy 33.46365 -149.518312) (xy 33.622502 -149.654676) (xy 33.776059 -149.796977)
			(xy 33.924098 -149.94501) (xy 34.066406 -150.09856) (xy 34.202777 -150.257406) (xy 34.333015 -150.421319)
			(xy 34.456931 -150.590061) (xy 34.574347 -150.76339) (xy 34.685092 -150.941054) (xy 34.789007 -151.122798)
			(xy 34.885942 -151.308359) (xy 34.975757 -151.497469) (xy 35.058323 -151.689854) (xy 35.133519 -151.885238)
			(xy 35.201237 -152.083338) (xy 35.26138 -152.283867) (xy 35.313861 -152.486537) (xy 35.358604 -152.691054)
			(xy 35.395544 -152.897124) (xy 35.424628 -153.104448) (xy 35.445815 -153.312727) (xy 35.459072 -153.521661)
			(xy 35.464382 -153.730948) (xy 35.461736 -153.940286) (xy 35.451139 -154.149372) (xy 35.432606 -154.357904)
			(xy 35.406163 -154.565582) (xy 35.371848 -154.772105) (xy 35.329712 -154.977175) (xy 35.279815 -155.180496)
			(xy 35.222229 -155.381775) (xy 35.157038 -155.58072) (xy 35.084335 -155.777045) (xy 35.004225 -155.970466)
			(xy 34.916824 -156.160704) (xy 34.822259 -156.347483) (xy 34.720665 -156.530535) (xy 34.670434 -156.613451)
			(xy 50.206652 -156.613451) (xy 50.206652 -156.558949) (xy 50.214408 -156.505001) (xy 50.229762 -156.452707)
			(xy 50.252401 -156.403129) (xy 50.281865 -156.357277) (xy 50.317554 -156.316086) (xy 50.358742 -156.280392)
			(xy 50.40459 -156.250922) (xy 50.454165 -156.228277) (xy 50.506458 -156.212917) (xy 50.560405 -156.205155)
			(xy 50.587656 -156.204666) (xy 50.58791 -156.204666) (xy 50.617749 -156.205247) (xy 50.676695 -156.214559)
			(xy 50.705258 -156.223208) (xy 50.719167 -156.227239) (xy 50.748099 -156.228148) (xy 50.776118 -156.220883)
			(xy 50.800963 -156.206032) (xy 50.820629 -156.184792) (xy 50.833527 -156.158879) (xy 50.836576 -156.144722)
			(xy 50.843165 -156.111884) (xy 50.866284 -156.049031) (xy 50.88255 -156.019754) (xy 50.889618 -156.006804)
			(xy 50.896647 -155.978161) (xy 50.895197 -155.948704) (xy 50.885389 -155.92089) (xy 50.868042 -155.897039)
			(xy 50.844601 -155.879141) (xy 50.830988 -155.87345) (xy 50.80422 -155.862735) (xy 50.753979 -155.83445)
			(xy 50.70857 -155.798922) (xy 50.669027 -155.756963) (xy 50.636253 -155.709528) (xy 50.610993 -155.6577)
			(xy 50.593825 -155.60266) (xy 50.585139 -155.545662) (xy 50.584608 -155.516834) (xy 50.585094 -155.489583)
			(xy 50.59285 -155.435635) (xy 50.608205 -155.38334) (xy 50.630847 -155.333763) (xy 50.660313 -155.287913)
			(xy 50.696004 -155.246722) (xy 50.737195 -155.211031) (xy 50.783045 -155.181565) (xy 50.832622 -155.158923)
			(xy 50.884917 -155.143568) (xy 50.938865 -155.135812) (xy 50.993367 -155.135812) (xy 51.047315 -155.143568)
			(xy 51.09961 -155.158923) (xy 51.149187 -155.181565) (xy 51.195037 -155.211031) (xy 51.236228 -155.246722)
			(xy 51.271919 -155.287913) (xy 51.301385 -155.333763) (xy 51.324027 -155.38334) (xy 51.339382 -155.435635)
			(xy 51.347138 -155.489583) (xy 51.347624 -155.516834) (xy 51.347624 -155.517088) (xy 51.347224 -155.542292)
			(xy 51.340585 -155.59226) (xy 51.327409 -155.640914) (xy 51.307926 -155.687404) (xy 51.295554 -155.709366)
			(xy 51.28846 -155.722303) (xy 51.281434 -155.750951) (xy 51.282888 -155.780412) (xy 51.292701 -155.808229)
			(xy 51.310054 -155.832081) (xy 51.3335 -155.84998) (xy 51.347116 -155.85567) (xy 51.373892 -155.866366)
			(xy 51.424134 -155.894654) (xy 51.469543 -155.930184) (xy 51.509085 -155.972146) (xy 51.541859 -156.019583)
			(xy 51.567117 -156.071414) (xy 51.584283 -156.126457) (xy 51.592966 -156.183457) (xy 51.593496 -156.212286)
			(xy 51.593032 -156.239539) (xy 51.585276 -156.293491) (xy 51.569921 -156.345789) (xy 51.54728 -156.39537)
			(xy 51.517812 -156.441224) (xy 51.482118 -156.482417) (xy 51.440925 -156.518111) (xy 51.395072 -156.547579)
			(xy 51.345491 -156.570221) (xy 51.293193 -156.585576) (xy 51.239241 -156.593331) (xy 51.211988 -156.593794)
			(xy 51.211734 -156.593794) (xy 51.181895 -156.593227) (xy 51.122949 -156.583906) (xy 51.094386 -156.575252)
			(xy 51.080457 -156.571302) (xy 51.051539 -156.570385) (xy 51.02353 -156.577636) (xy 50.998691 -156.592471)
			(xy 50.979026 -156.613693) (xy 50.966122 -156.639589) (xy 50.963068 -156.653738) (xy 50.957919 -156.679816)
			(xy 50.941346 -156.73032) (xy 50.917921 -156.778034) (xy 50.888096 -156.822032) (xy 50.852451 -156.861463)
			(xy 50.811676 -156.895561) (xy 50.76656 -156.923667) (xy 50.717979 -156.945236) (xy 50.666873 -156.959849)
			(xy 50.614233 -156.967225) (xy 50.587656 -156.967682) (xy 50.560405 -156.967245) (xy 50.506458 -156.959483)
			(xy 50.454165 -156.944123) (xy 50.40459 -156.921478) (xy 50.358742 -156.892008) (xy 50.317554 -156.856314)
			(xy 50.281865 -156.815123) (xy 50.252401 -156.769271) (xy 50.229762 -156.719693) (xy 50.214408 -156.667399)
			(xy 50.206652 -156.613451) (xy 34.670434 -156.613451) (xy 34.61219 -156.709595) (xy 34.49699 -156.884404)
			(xy 34.375232 -157.05471) (xy 34.247091 -157.220267) (xy 34.112752 -157.380836) (xy 33.97241 -157.536185)
			(xy 33.826267 -157.68609) (xy 33.674534 -157.830334) (xy 33.51743 -157.968709) (xy 33.355182 -158.101015)
			(xy 33.188025 -158.227061) (xy 33.016199 -158.346665) (xy 32.839954 -158.459655) (xy 32.659542 -158.565867)
			(xy 32.475226 -158.665147) (xy 32.28727 -158.757353) (xy 32.095947 -158.842352) (xy 31.901533 -158.92002)
			(xy 31.704308 -158.990245) (xy 31.504558 -159.052927) (xy 31.30257 -159.107974) (xy 31.098636 -159.155307)
			(xy 30.893052 -159.194857) (xy 30.686113 -159.226568) (xy 30.478119 -159.250394) (xy 30.26937 -159.266301)
			(xy 30.060167 -159.274264) (xy 29.95549 -159.274764) (xy 29.954982 -159.274764) (xy 29.841305 -159.274176)
			(xy 29.614145 -159.264786) (xy 29.387565 -159.246032) (xy 29.161953 -159.217944) (xy 29.049726 -159.199834)
			(xy 29.034995 -159.197897) (xy 29.00553 -159.201582) (xy 28.97837 -159.213587) (xy 28.955811 -159.232899)
			(xy 28.939762 -159.257883) (xy 28.931579 -159.286429) (xy 28.931954 -159.316122) (xy 28.940855 -159.344451)
			(xy 28.957529 -159.369023) (xy 28.980568 -159.387759) (xy 28.9941 -159.39389) (xy 29.125164 -159.447992)
			(xy 34.374074 -159.447992) (xy 34.39907 -159.448624) (xy 34.448094 -159.458427) (xy 34.494265 -159.477601)
			(xy 34.535811 -159.505411) (xy 34.553906 -159.522668) (xy 35.416744 -160.385506) (xy 35.433987 -160.403614)
			(xy 35.461802 -160.445154) (xy 35.480979 -160.491321) (xy 35.490782 -160.540343) (xy 35.49142 -160.565338)
			(xy 35.49142 -163.277804) (xy 35.911028 -163.697412) (xy 38.726618 -163.697412) (xy 42.492168 -159.932116)
			(xy 42.510244 -159.914837) (xy 42.551795 -159.887031) (xy 42.597972 -159.867863) (xy 42.647002 -159.858072)
			(xy 42.672 -159.85744) (xy 45.339 -159.85744) (xy 45.363996 -159.858071) (xy 45.413019 -159.867876)
			(xy 45.45919 -159.887051) (xy 45.500736 -159.91486) (xy 45.518832 -159.932116) (xy 47.347592 -161.76072)
			(xy 51.012924 -161.76072) (xy 51.012928 -161.706227) (xy 51.020687 -161.652288) (xy 51.036042 -161.600003)
			(xy 51.058683 -161.550435) (xy 51.088146 -161.504593) (xy 51.123834 -161.463411) (xy 51.165019 -161.427727)
			(xy 51.210863 -161.398267) (xy 51.260433 -161.375631) (xy 51.312719 -161.36028) (xy 51.366659 -161.352526)
			(xy 51.421152 -161.352526) (xy 51.475091 -161.360282) (xy 51.527377 -161.375635) (xy 51.576946 -161.398272)
			(xy 51.62279 -161.427734) (xy 51.663974 -161.463419) (xy 51.69966 -161.504602) (xy 51.729122 -161.550444)
			(xy 51.751761 -161.600013) (xy 51.767116 -161.652299) (xy 51.774873 -161.706237) (xy 51.77536 -161.733484)
			(xy 51.77493 -161.758875) (xy 51.768173 -161.809207) (xy 51.761898 -161.833814) (xy 51.758525 -161.848472)
			(xy 51.759445 -161.878518) (xy 51.769069 -161.906996) (xy 51.786564 -161.93144) (xy 51.810415 -161.949736)
			(xy 51.838559 -161.960299) (xy 51.868558 -161.962215) (xy 51.88331 -161.95929) (xy 51.90484 -161.954535)
			(xy 51.948639 -161.949442) (xy 51.970686 -161.94913) (xy 51.97094 -161.94913) (xy 51.998187 -161.949621)
			(xy 52.052126 -161.957382) (xy 52.104412 -161.972739) (xy 52.153979 -161.995381) (xy 52.199821 -162.024847)
			(xy 52.241002 -162.060536) (xy 52.276686 -162.101723) (xy 52.306145 -162.147568) (xy 52.32878 -162.197139)
			(xy 52.34413 -162.249427) (xy 52.351883 -162.303367) (xy 52.351881 -162.357861) (xy 52.344124 -162.411801)
			(xy 52.32877 -162.464087) (xy 52.306131 -162.513657) (xy 52.276669 -162.5595) (xy 52.240982 -162.600684)
			(xy 52.199798 -162.63637) (xy 52.153955 -162.665832) (xy 52.104385 -162.688471) (xy 52.052099 -162.703824)
			(xy 51.998159 -162.711581) (xy 51.943665 -162.711583) (xy 51.889725 -162.703829) (xy 51.837437 -162.688479)
			(xy 51.787866 -162.665844) (xy 51.742021 -162.636384) (xy 51.700835 -162.600701) (xy 51.665146 -162.559519)
			(xy 51.63568 -162.513678) (xy 51.613039 -162.46411) (xy 51.597681 -162.411824) (xy 51.589921 -162.357885)
			(xy 51.589432 -162.330638) (xy 51.589867 -162.305247) (xy 51.596621 -162.254916) (xy 51.602894 -162.230308)
			(xy 51.606253 -162.215646) (xy 51.605338 -162.185601) (xy 51.595718 -162.157123) (xy 51.578225 -162.132677)
			(xy 51.554375 -162.114382) (xy 51.526232 -162.10382) (xy 51.496234 -162.101906) (xy 51.481482 -162.104832)
			(xy 51.459952 -162.109589) (xy 51.416153 -162.11468) (xy 51.394106 -162.114992) (xy 51.393852 -162.114992)
			(xy 51.366605 -162.11447) (xy 51.312667 -162.106709) (xy 51.260383 -162.09135) (xy 51.210816 -162.068707)
			(xy 51.164976 -162.039241) (xy 51.123796 -162.003551) (xy 51.088114 -161.962364) (xy 51.058657 -161.916518)
			(xy 51.036024 -161.866947) (xy 51.020675 -161.81466) (xy 51.012924 -161.76072) (xy 47.347592 -161.76072)
			(xy 48.49241 -162.90544) (xy 49.17059 -162.90544) (xy 49.731168 -162.345116) (xy 49.749244 -162.327837)
			(xy 49.790795 -162.300031) (xy 49.836972 -162.280863) (xy 49.886002 -162.271072) (xy 49.911 -162.27044)
			(xy 50.541682 -162.27044) (xy 50.566678 -162.271082) (xy 50.6157 -162.280884) (xy 50.661871 -162.300056)
			(xy 50.703418 -162.327862) (xy 50.721514 -162.345116) (xy 51.131724 -162.755326) (xy 51.15306 -162.755326)
			(xy 51.180337 -162.755751) (xy 51.234345 -162.763446) (xy 51.286706 -162.778755) (xy 51.336352 -162.801368)
			(xy 51.382271 -162.830821) (xy 51.423526 -162.866516) (xy 51.459275 -162.907723) (xy 51.48879 -162.953603)
			(xy 51.511468 -163.003219) (xy 51.526847 -163.05556) (xy 51.534613 -163.109557) (xy 51.535076 -163.136834)
			(xy 51.534654 -163.164088) (xy 51.526892 -163.218039) (xy 51.511531 -163.270337) (xy 51.488883 -163.319917)
			(xy 51.45941 -163.365768) (xy 51.423712 -163.406959) (xy 51.382515 -163.44265) (xy 51.336659 -163.472115)
			(xy 51.287075 -163.494754) (xy 51.234775 -163.510106) (xy 51.180822 -163.517858) (xy 51.153568 -163.518342)
			(xy 51.123881 -163.51776) (xy 51.065222 -163.50857) (xy 51.008695 -163.490402) (xy 50.955667 -163.463694)
			(xy 50.907418 -163.429091) (xy 50.865114 -163.38743) (xy 50.84699 -163.36391) (xy 50.838564 -163.353303)
			(xy 50.817251 -163.336596) (xy 50.792297 -163.326077) (xy 50.765456 -163.322487) (xy 50.738615 -163.326077)
			(xy 50.713661 -163.336596) (xy 50.692348 -163.353303) (xy 50.683922 -163.36391) (xy 50.665776 -163.387412)
			(xy 50.623474 -163.429073) (xy 50.575229 -163.463678) (xy 50.522206 -163.490392) (xy 50.465685 -163.50857)
			(xy 50.40703 -163.517774) (xy 50.377344 -163.518342) (xy 50.350599 -163.517896) (xy 50.297637 -163.5104)
			(xy 50.246242 -163.495576) (xy 50.197422 -163.473716) (xy 50.152137 -163.445248) (xy 50.111274 -163.410732)
			(xy 50.093118 -163.391088) (xy 49.943512 -163.391088) (xy 49.61382 -163.72078) (xy 49.595707 -163.738016)
			(xy 49.554168 -163.765831) (xy 49.508002 -163.78501) (xy 49.458983 -163.794816) (xy 49.433988 -163.795456)
			(xy 48.229012 -163.795456) (xy 48.204016 -163.794819) (xy 48.154993 -163.785016) (xy 48.108822 -163.765843)
			(xy 48.067276 -163.738035) (xy 48.04918 -163.72078) (xy 45.075602 -160.747456) (xy 42.935398 -160.747456)
			(xy 41.791559 -161.891218) (xy 43.505377 -161.891218) (xy 43.509413 -161.807771) (xy 43.521485 -161.725103)
			(xy 43.541478 -161.643986) (xy 43.569207 -161.565177) (xy 43.604413 -161.489412) (xy 43.646767 -161.417399)
			(xy 43.695873 -161.34981) (xy 43.751274 -161.287276) (xy 43.812451 -161.230381) (xy 43.878834 -161.179655)
			(xy 43.949802 -161.135574) (xy 44.024694 -161.098548) (xy 44.10281 -161.068922) (xy 44.18342 -161.046974)
			(xy 44.265772 -161.032909) (xy 44.349098 -161.026857) (xy 44.432618 -161.028876) (xy 44.515554 -161.038946)
			(xy 44.59713 -161.056974) (xy 44.676586 -161.082791) (xy 44.753179 -161.116156) (xy 44.826195 -161.156757)
			(xy 44.894951 -161.204216) (xy 44.958805 -161.258089) (xy 45.017162 -161.317874) (xy 45.069477 -161.383011)
			(xy 45.11526 -161.452894) (xy 45.154085 -161.526869) (xy 45.18559 -161.604246) (xy 45.209479 -161.684303)
			(xy 45.22553 -161.766291) (xy 45.233593 -161.849446) (xy 45.234098 -161.891218) (xy 45.233593 -161.93299)
			(xy 45.22553 -162.016145) (xy 45.209479 -162.098133) (xy 45.18559 -162.17819) (xy 45.154085 -162.255567)
			(xy 45.11526 -162.329542) (xy 45.069477 -162.399425) (xy 45.017162 -162.464562) (xy 44.958805 -162.524347)
			(xy 44.894951 -162.57822) (xy 44.826195 -162.625679) (xy 44.753179 -162.66628) (xy 44.676586 -162.699645)
			(xy 44.59713 -162.725462) (xy 44.515554 -162.74349) (xy 44.432618 -162.75356) (xy 44.349098 -162.755579)
			(xy 44.265772 -162.749527) (xy 44.18342 -162.735462) (xy 44.10281 -162.713514) (xy 44.024694 -162.683888)
			(xy 43.949802 -162.646862) (xy 43.878834 -162.602781) (xy 43.812451 -162.552055) (xy 43.751274 -162.49516)
			(xy 43.695873 -162.432626) (xy 43.646767 -162.365037) (xy 43.604413 -162.293024) (xy 43.569207 -162.217259)
			(xy 43.541478 -162.13845) (xy 43.521485 -162.057333) (xy 43.509413 -161.974665) (xy 43.505377 -161.891218)
			(xy 41.791559 -161.891218) (xy 39.248917 -164.433688) (xy 43.480986 -164.433688) (xy 43.480986 -164.348992)
			(xy 43.489037 -164.264678) (xy 43.505066 -164.181512) (xy 43.528927 -164.100245) (xy 43.560406 -164.021615)
			(xy 43.599217 -163.946334) (xy 43.645007 -163.875082) (xy 43.697363 -163.808506) (xy 43.755811 -163.747208)
			(xy 43.819821 -163.691743) (xy 43.888813 -163.642614) (xy 43.962163 -163.600265) (xy 44.039206 -163.565081)
			(xy 44.119245 -163.537379) (xy 44.201554 -163.517411) (xy 44.285389 -163.505358) (xy 44.36999 -163.501328)
			(xy 44.454591 -163.505358) (xy 44.538426 -163.517411) (xy 44.620735 -163.537379) (xy 44.700774 -163.565081)
			(xy 44.777817 -163.600265) (xy 44.851167 -163.642614) (xy 44.920159 -163.691743) (xy 44.984169 -163.747208)
			(xy 45.042617 -163.808506) (xy 45.094973 -163.875082) (xy 45.140763 -163.946334) (xy 45.179574 -164.021615)
			(xy 45.211053 -164.100245) (xy 45.234914 -164.181512) (xy 45.250943 -164.264678) (xy 45.258994 -164.348992)
			(xy 45.259498 -164.39134) (xy 45.258994 -164.433688) (xy 45.250943 -164.518002) (xy 45.234914 -164.601168)
			(xy 45.211053 -164.682435) (xy 45.179574 -164.761065) (xy 45.140763 -164.836346) (xy 45.094973 -164.907598)
			(xy 45.042617 -164.974174) (xy 44.984169 -165.035472) (xy 44.920159 -165.090937) (xy 44.851167 -165.140066)
			(xy 44.777817 -165.182415) (xy 44.700774 -165.217599) (xy 44.620735 -165.245301) (xy 44.538426 -165.265269)
			(xy 44.454591 -165.277322) (xy 44.36999 -165.281353) (xy 44.285389 -165.277322) (xy 44.201554 -165.265269)
			(xy 44.119245 -165.245301) (xy 44.039206 -165.217599) (xy 43.962163 -165.182415) (xy 43.888813 -165.140066)
			(xy 43.819821 -165.090937) (xy 43.755811 -165.035472) (xy 43.697363 -164.974174) (xy 43.645007 -164.907598)
			(xy 43.599217 -164.836346) (xy 43.560406 -164.761065) (xy 43.528927 -164.682435) (xy 43.505066 -164.601168)
			(xy 43.489037 -164.518002) (xy 43.480986 -164.433688) (xy 39.248917 -164.433688) (xy 39.169848 -164.512752)
			(xy 39.151761 -164.530018) (xy 39.110214 -164.557828) (xy 39.06404 -164.576999) (xy 39.015013 -164.586794)
			(xy 38.990016 -164.587428) (xy 35.5981 -164.587428) (xy 35.573103 -164.586806) (xy 35.524079 -164.577)
			(xy 35.477908 -164.557822) (xy 35.436363 -164.53001) (xy 35.418268 -164.512752) (xy 34.675572 -163.770056)
			(xy 34.658297 -163.751977) (xy 34.630492 -163.710426) (xy 34.611324 -163.66425) (xy 34.60153 -163.615222)
			(xy 34.600896 -163.590224) (xy 34.600896 -162.660838) (xy 34.289746 -162.349688) (xy 34.058352 -162.349688)
			(xy 33.909508 -162.498532) (xy 33.909508 -166.958518) (xy 32.878268 -167.989758) (xy 32.890479 -168.014921)
			(xy 32.907779 -168.068105) (xy 32.916561 -168.123339) (xy 32.91713 -168.151302) (xy 32.91713 -168.15181)
			(xy 32.916568 -168.179792) (xy 32.907813 -168.235068) (xy 32.890518 -168.288293) (xy 32.865111 -168.338158)
			(xy 32.832216 -168.383434) (xy 32.792643 -168.423008) (xy 32.747368 -168.455904) (xy 32.697504 -168.481313)
			(xy 32.644279 -168.49861) (xy 32.589004 -168.507367) (xy 32.561022 -168.507918) (xy 32.560514 -168.507918)
			(xy 32.532547 -168.507399) (xy 32.477305 -168.498619) (xy 32.424118 -168.481304) (xy 32.39897 -168.469056)
			(xy 32.28721 -168.580816) (xy 29.177996 -168.580816) (xy 28.932632 -168.335198) (xy 28.932632 -166.854378)
			(xy 29.344112 -166.442644) (xy 29.344112 -163.202112) (xy 28.932632 -162.790378) (xy 28.932632 -162.095688)
			(xy 28.933141 -162.069038) (xy 28.942395 -162.016548) (xy 28.960636 -161.966468) (xy 28.987309 -161.920322)
			(xy 29.021599 -161.879518) (xy 29.062464 -161.845299) (xy 29.085286 -161.831528) (xy 29.111743 -161.815786)
			(xy 29.161031 -161.778898) (xy 29.205507 -161.73633) (xy 29.244519 -161.688704) (xy 29.277498 -161.636718)
			(xy 29.30396 -161.581131) (xy 29.323518 -161.522756) (xy 29.330142 -161.492692) (xy 29.345382 -161.417762)
			(xy 29.53893 -161.22396) (xy 29.632148 -161.22396) (xy 29.66466 -161.134298) (xy 29.646515 -161.11873)
			(xy 29.613846 -161.08382) (xy 29.5858 -161.045099) (xy 29.573982 -161.024316) (xy 29.566526 -161.011692)
			(xy 29.545759 -160.991013) (xy 29.519977 -160.977081) (xy 29.491299 -160.971041) (xy 29.462087 -160.973391)
			(xy 29.434744 -160.983937) (xy 29.41152 -161.001811) (xy 29.402532 -161.013394) (xy 29.387061 -161.03402)
			(xy 29.351535 -161.071385) (xy 29.311301 -161.103626) (xy 29.267092 -161.130155) (xy 29.219712 -161.150488)
			(xy 29.170026 -161.164256) (xy 29.118939 -161.171207) (xy 29.09316 -161.171636) (xy 29.067638 -161.171269)
			(xy 29.017049 -161.164468) (xy 28.967819 -161.15098) (xy 28.920828 -161.131046) (xy 28.876916 -161.105023)
			(xy 28.836868 -161.073374) (xy 28.81884 -161.055304) (xy 28.807683 -161.044552) (xy 28.780455 -161.02979)
			(xy 28.750059 -161.02384) (xy 28.719275 -161.027244) (xy 28.690915 -161.039693) (xy 28.678886 -161.049462)
			(xy 28.657945 -161.067146) (xy 28.611944 -161.096946) (xy 28.562148 -161.119849) (xy 28.509585 -161.135382)
			(xy 28.455339 -161.143225) (xy 28.427934 -161.143696) (xy 28.42768 -161.143696) (xy 28.400428 -161.143241)
			(xy 28.346478 -161.135481) (xy 28.294182 -161.120123) (xy 28.244604 -161.097479) (xy 28.198753 -161.068009)
			(xy 28.157563 -161.032314) (xy 28.121872 -160.991121) (xy 28.092406 -160.945268) (xy 28.069766 -160.895688)
			(xy 28.054412 -160.84339) (xy 28.046657 -160.78944) (xy 28.046172 -160.762188) (xy 28.047696 -160.72739)
			(xy 28.048492 -160.712374) (xy 28.042378 -160.682951) (xy 28.027959 -160.656584) (xy 28.006486 -160.635559)
			(xy 27.97982 -160.6217) (xy 27.965146 -160.618424) (xy 27.94033 -160.613351) (xy 27.892202 -160.597564)
			(xy 27.846588 -160.575544) (xy 27.804291 -160.54768) (xy 27.766054 -160.514462) (xy 27.748992 -160.495742)
			(xy 27.738999 -160.485052) (xy 27.714238 -160.469473) (xy 27.686077 -160.461554) (xy 27.656825 -160.461945)
			(xy 27.628885 -160.470613) (xy 27.604549 -160.486847) (xy 27.594814 -160.497774) (xy 27.576613 -160.51873)
			(xy 27.535206 -160.555693) (xy 27.48888 -160.586264) (xy 27.438613 -160.6098) (xy 27.385466 -160.625802)
			(xy 27.358086 -160.630362) (xy 27.344215 -160.632826) (xy 27.318551 -160.644429) (xy 27.297027 -160.662594)
			(xy 27.281276 -160.685943) (xy 27.272494 -160.712704) (xy 27.271346 -160.740845) (xy 27.277921 -160.768232)
			(xy 27.284426 -160.78073) (xy 27.296071 -160.802211) (xy 27.314383 -160.847515) (xy 27.326773 -160.894782)
			(xy 27.33304 -160.943242) (xy 27.333448 -160.967674) (xy 27.333448 -160.967928) (xy 27.332962 -160.995179)
			(xy 27.325206 -161.049127) (xy 27.309851 -161.101422) (xy 27.287209 -161.150999) (xy 27.257743 -161.196849)
			(xy 27.222052 -161.23804) (xy 27.180861 -161.273731) (xy 27.135011 -161.303197) (xy 27.085434 -161.325839)
			(xy 27.033139 -161.341194) (xy 26.979191 -161.34895) (xy 26.924689 -161.34895) (xy 26.870741 -161.341194)
			(xy 26.818446 -161.325839) (xy 26.768869 -161.303197) (xy 26.723019 -161.273731) (xy 26.681828 -161.23804)
			(xy 26.646137 -161.196849) (xy 26.616671 -161.150999) (xy 26.594029 -161.101422) (xy 26.578674 -161.049127)
			(xy 26.570918 -160.995179) (xy 26.570432 -160.967928) (xy 26.570946 -160.940755) (xy 26.578642 -160.886956)
			(xy 26.593896 -160.834795) (xy 26.6164 -160.785326) (xy 26.645697 -160.739553) (xy 26.681194 -160.698402)
			(xy 26.722173 -160.662705) (xy 26.767804 -160.633187) (xy 26.817163 -160.610444) (xy 26.86925 -160.594938)
			(xy 26.89606 -160.590484) (xy 26.90991 -160.587923) (xy 26.935569 -160.576339) (xy 26.957091 -160.558192)
			(xy 26.972845 -160.53486) (xy 26.981632 -160.508114) (xy 26.982786 -160.479985) (xy 26.97622 -160.45261)
			(xy 26.96972 -160.440116) (xy 26.958096 -160.418623) (xy 26.939779 -160.373325) (xy 26.927382 -160.326061)
			(xy 26.921109 -160.277603) (xy 26.920698 -160.253172) (xy 26.920698 -160.252918) (xy 26.921172 -160.225665)
			(xy 26.928927 -160.171714) (xy 26.944281 -160.119416) (xy 26.966922 -160.069836) (xy 26.996388 -160.023982)
			(xy 27.032081 -159.982789) (xy 27.073273 -159.947096) (xy 27.119125 -159.917627) (xy 27.168705 -159.894985)
			(xy 27.221003 -159.879629) (xy 27.274953 -159.871873) (xy 27.302206 -159.87141) (xy 27.329163 -159.871906)
			(xy 27.38254 -159.879496) (xy 27.434317 -159.894525) (xy 27.483463 -159.916692) (xy 27.528999 -159.945556)
			(xy 27.570019 -159.980543) (xy 27.58821 -160.000442) (xy 27.5982 -160.011136) (xy 27.622961 -160.026717)
			(xy 27.651124 -160.034637) (xy 27.680377 -160.034246) (xy 27.708318 -160.025576) (xy 27.732653 -160.009339)
			(xy 27.742388 -159.99841) (xy 27.760611 -159.977409) (xy 27.802113 -159.940408) (xy 27.848545 -159.909821)
			(xy 27.898924 -159.886295) (xy 27.952183 -159.870329) (xy 28.007195 -159.86226) (xy 28.034996 -159.861758)
			(xy 28.062246 -159.862281) (xy 28.11619 -159.870036) (xy 28.168482 -159.885389) (xy 28.218057 -159.908028)
			(xy 28.263906 -159.93749) (xy 28.305095 -159.973178) (xy 28.340787 -160.014364) (xy 28.370254 -160.060209)
			(xy 28.392897 -160.109782) (xy 28.408255 -160.162073) (xy 28.416016 -160.216016) (xy 28.416504 -160.243266)
			(xy 28.41498 -160.278064) (xy 28.414165 -160.293081) (xy 28.420272 -160.322513) (xy 28.434692 -160.348886)
			(xy 28.456174 -160.369911) (xy 28.482851 -160.383762) (xy 28.49753 -160.38703) (xy 28.526432 -160.392984)
			(xy 28.582076 -160.412623) (xy 28.634041 -160.440578) (xy 28.681095 -160.476185) (xy 28.702 -160.497012)
			(xy 28.713208 -160.507706) (xy 28.740419 -160.522471) (xy 28.770798 -160.528431) (xy 28.801571 -160.525042)
			(xy 28.829926 -160.512612) (xy 28.841954 -160.502854) (xy 28.862882 -160.485154) (xy 28.908886 -160.455355)
			(xy 28.958685 -160.432455) (xy 29.011251 -160.416926) (xy 29.0655 -160.409088) (xy 29.092906 -160.40862)
			(xy 29.09316 -160.40862) (xy 29.122313 -160.409181) (xy 29.179938 -160.41806) (xy 29.235541 -160.435603)
			(xy 29.287829 -160.4614) (xy 29.335584 -160.494852) (xy 29.377693 -160.535179) (xy 29.413177 -160.581443)
			(xy 29.427678 -160.60674) (xy 29.435187 -160.619327) (xy 29.455948 -160.639992) (xy 29.481718 -160.653918)
			(xy 29.510381 -160.659958) (xy 29.53958 -160.657617) (xy 29.566914 -160.647087) (xy 29.590137 -160.629234)
			(xy 29.599128 -160.617662) (xy 29.61455 -160.596998) (xy 29.650085 -160.559636) (xy 29.690329 -160.5274)
			(xy 29.734547 -160.500876) (xy 29.781933 -160.480549) (xy 29.831626 -160.466789) (xy 29.882719 -160.459845)
			(xy 29.9085 -160.45942) (xy 29.934856 -160.459881) (xy 29.987065 -160.467149) (xy 30.037778 -160.481532)
			(xy 30.086028 -160.502757) (xy 30.130899 -160.53042) (xy 30.171536 -160.563994) (xy 30.189678 -160.583118)
			(xy 30.198948 -160.592739) (xy 30.221445 -160.607141) (xy 30.246909 -160.615206) (xy 30.273594 -160.616381)
			(xy 30.299669 -160.610586) (xy 30.323344 -160.598219) (xy 30.333442 -160.589468) (xy 30.354685 -160.570621)
			(xy 30.4017 -160.53877) (xy 30.452918 -160.514243) (xy 30.507207 -160.497582) (xy 30.563366 -160.489155)
			(xy 30.59176 -160.48863) (xy 30.620823 -160.489143) (xy 30.678279 -160.49795) (xy 30.733735 -160.515366)
			(xy 30.785909 -160.54099) (xy 30.833595 -160.574228) (xy 30.87569 -160.614312) (xy 30.911221 -160.660315)
			(xy 30.92577 -160.68548) (xy 32.27705 -160.68548) (xy 32.854392 -161.262822) (xy 32.874907 -161.251265)
			(xy 32.91832 -161.233035) (xy 32.963758 -161.220692) (xy 33.010428 -161.21445) (xy 33.03397 -161.214054)
			(xy 33.034478 -161.214054) (xy 33.060556 -161.214522) (xy 33.112156 -161.222116) (xy 33.162095 -161.237159)
			(xy 33.209304 -161.259329) (xy 33.252773 -161.288151) (xy 33.272476 -161.30524) (xy 33.41878 -161.30524)
			(xy 33.432645 -161.304694) (xy 33.459335 -161.297155) (xy 33.48301 -161.28271) (xy 33.501924 -161.262426)
			(xy 33.514679 -161.2378) (xy 33.520335 -161.210649) (xy 33.519872 -161.196782) (xy 33.51911 -161.170874)
			(xy 33.519596 -161.143623) (xy 33.527352 -161.089675) (xy 33.542707 -161.03738) (xy 33.565349 -160.987803)
			(xy 33.594815 -160.941953) (xy 33.630506 -160.900762) (xy 33.671697 -160.865071) (xy 33.717547 -160.835605)
			(xy 33.767124 -160.812963) (xy 33.819419 -160.797608) (xy 33.873367 -160.789852) (xy 33.927869 -160.789852)
			(xy 33.981817 -160.797608) (xy 34.034112 -160.812963) (xy 34.083689 -160.835605) (xy 34.129539 -160.865071)
			(xy 34.17073 -160.900762) (xy 34.206421 -160.941953) (xy 34.235887 -160.987803) (xy 34.258529 -161.03738)
			(xy 34.273884 -161.089675) (xy 34.28164 -161.143623) (xy 34.282126 -161.170874) (xy 34.281694 -161.19822)
			(xy 34.273901 -161.252353) (xy 34.258457 -161.304819) (xy 34.235678 -161.354541) (xy 34.206032 -161.4005)
			(xy 34.170125 -161.441754) (xy 34.128695 -161.477457) (xy 34.082591 -161.506877) (xy 34.032758 -161.529411)
			(xy 33.980217 -161.544597) (xy 33.953196 -161.548826) (xy 33.909508 -161.554922) (xy 33.909508 -161.840672)
			(xy 34.395156 -161.840672) (xy 34.420152 -161.841321) (xy 34.469174 -161.851119) (xy 34.515345 -161.870289)
			(xy 34.556892 -161.898094) (xy 34.574988 -161.915348) (xy 34.809176 -162.149282) (xy 34.820116 -162.159507)
			(xy 34.846515 -162.173612) (xy 34.875871 -162.179454) (xy 34.90566 -162.176529) (xy 34.933319 -162.16509)
			(xy 34.956472 -162.14612) (xy 34.973127 -162.121251) (xy 34.981852 -162.092619) (xy 34.982404 -162.077654)
			(xy 34.982404 -160.670748) (xy 34.268664 -159.957008) (xy 29.074618 -159.957008) (xy 29.049632 -159.956342)
			(xy 29.000639 -159.946488) (xy 28.977336 -159.93745) (xy 28.120086 -159.582612) (xy 27.041856 -159.582612)
			(xy 26.23058 -160.393634) (xy 26.23058 -160.870138) (xy 26.250202 -160.888314) (xy 26.284702 -160.929183)
			(xy 26.31316 -160.974467) (xy 26.335018 -161.023281) (xy 26.349849 -161.074668) (xy 26.357361 -161.127622)
			(xy 26.357834 -161.154364) (xy 26.357348 -161.181615) (xy 26.349592 -161.235563) (xy 26.334237 -161.287858)
			(xy 26.311595 -161.337435) (xy 26.282129 -161.383285) (xy 26.246438 -161.424476) (xy 26.205247 -161.460167)
			(xy 26.159397 -161.489633) (xy 26.10982 -161.512275) (xy 26.057525 -161.52763) (xy 26.003577 -161.535386)
			(xy 25.949075 -161.535386) (xy 25.895127 -161.52763) (xy 25.842832 -161.512275) (xy 25.793255 -161.489633)
			(xy 25.747405 -161.460167) (xy 25.706214 -161.424476) (xy 25.670523 -161.383285) (xy 25.641057 -161.337435)
			(xy 25.618415 -161.287858) (xy 25.60306 -161.235563) (xy 25.595304 -161.181615) (xy 25.594818 -161.154364)
			(xy 25.595291 -161.12762) (xy 25.602783 -161.07466) (xy 25.617603 -161.023266) (xy 25.639458 -160.974447)
			(xy 25.66792 -160.92916) (xy 25.702431 -160.888295) (xy 25.722072 -160.870138) (xy 25.722072 -160.288224)
			(xy 25.722649 -160.263239) (xy 25.732402 -160.214229) (xy 25.75152 -160.168059) (xy 25.779268 -160.1265)
			(xy 25.796494 -160.108392) (xy 26.756614 -159.148272) (xy 26.774706 -159.131012) (xy 26.816252 -159.103204)
			(xy 26.862425 -159.084032) (xy 26.911449 -159.074233) (xy 26.936446 -159.073596) (xy 27.864308 -159.073596)
			(xy 27.878348 -159.073107) (xy 27.905365 -159.065454) (xy 27.929274 -159.05073) (xy 27.948267 -159.030048)
			(xy 27.960906 -159.004973) (xy 27.966235 -158.977404) (xy 27.963851 -158.949425) (xy 27.953934 -158.923155)
			(xy 27.937234 -158.900581) (xy 27.915015 -158.883411) (xy 27.902154 -158.877762) (xy 27.804314 -158.837933)
			(xy 27.611427 -158.751737) (xy 27.421986 -158.658209) (xy 27.236271 -158.557486) (xy 27.054555 -158.449716)
			(xy 26.877104 -158.335059) (xy 26.70418 -158.213682) (xy 26.536037 -158.085764) (xy 26.372922 -157.951493)
			(xy 26.215075 -157.811066) (xy 26.062728 -157.664691) (xy 25.916106 -157.512582) (xy 25.775424 -157.354963)
			(xy 25.640888 -157.192066) (xy 25.512698 -157.024131) (xy 25.39104 -156.851404) (xy 25.276095 -156.674139)
			(xy 25.168031 -156.492598) (xy 25.067007 -156.307046) (xy 24.973171 -156.117758) (xy 24.886663 -155.925011)
			(xy 24.807608 -155.729088) (xy 24.736123 -155.530279) (xy 24.672314 -155.328875) (xy 24.616274 -155.125173)
			(xy 24.568085 -154.919471) (xy 24.527819 -154.712074) (xy 24.495534 -154.503285) (xy 24.471279 -154.293411)
			(xy 24.455088 -154.082762) (xy 24.446986 -153.871647) (xy 24.446484 -153.766012) (xy 19.433286 -153.766012)
			(xy 19.433286 -159.601752) (xy 21.579562 -159.601752) (xy 21.579562 -159.547248) (xy 21.587318 -159.493299)
			(xy 21.602673 -159.441004) (xy 21.625314 -159.391425) (xy 21.654781 -159.345574) (xy 21.690472 -159.304382)
			(xy 21.731662 -159.268689) (xy 21.777513 -159.239221) (xy 21.827091 -159.216578) (xy 21.879386 -159.201221)
			(xy 21.933334 -159.193463) (xy 21.960586 -159.192976) (xy 21.986966 -159.19339) (xy 22.039225 -159.200653)
			(xy 22.089985 -159.215044) (xy 22.138279 -159.236288) (xy 22.183189 -159.26398) (xy 22.223857 -159.297592)
			(xy 22.259509 -159.336485) (xy 22.289465 -159.379917) (xy 22.301708 -159.403288) (xy 22.30841 -159.415647)
			(xy 22.327385 -159.436375) (xy 22.351299 -159.451137) (xy 22.378335 -159.458809) (xy 22.406437 -159.458809)
			(xy 22.433473 -159.451137) (xy 22.457387 -159.436375) (xy 22.476362 -159.415647) (xy 22.483064 -159.403288)
			(xy 22.495311 -159.379921) (xy 22.525273 -159.336497) (xy 22.560928 -159.297612) (xy 22.601596 -159.264006)
			(xy 22.646504 -159.236318) (xy 22.694796 -159.215077) (xy 22.745553 -159.200687) (xy 22.797807 -159.193422)
			(xy 22.824186 -159.192976) (xy 22.851438 -159.19347) (xy 22.905389 -159.201225) (xy 22.957686 -159.21658)
			(xy 23.007266 -159.23922) (xy 23.053119 -159.268687) (xy 23.094311 -159.304379) (xy 23.130005 -159.34557)
			(xy 23.159473 -159.391422) (xy 23.182116 -159.441001) (xy 23.197472 -159.493298) (xy 23.205229 -159.547248)
			(xy 23.205229 -159.601752) (xy 23.197472 -159.655702) (xy 23.182116 -159.707999) (xy 23.159473 -159.757578)
			(xy 23.130005 -159.80343) (xy 23.094311 -159.844621) (xy 23.053119 -159.880313) (xy 23.007266 -159.90978)
			(xy 22.957686 -159.93242) (xy 22.905389 -159.947775) (xy 22.851438 -159.95553) (xy 22.824186 -159.955992)
			(xy 22.797807 -159.955536) (xy 22.74555 -159.948282) (xy 22.69479 -159.933899) (xy 22.646494 -159.912662)
			(xy 22.601584 -159.884976) (xy 22.560916 -159.851368) (xy 22.525263 -159.812479) (xy 22.495307 -159.76905)
			(xy 22.483064 -159.74568) (xy 22.476362 -159.733321) (xy 22.457387 -159.712593) (xy 22.433473 -159.697831)
			(xy 22.406437 -159.690159) (xy 22.378335 -159.690159) (xy 22.351299 -159.697831) (xy 22.327385 -159.712593)
			(xy 22.30841 -159.733321) (xy 22.301708 -159.74568) (xy 22.289468 -159.769052) (xy 22.259507 -159.812477)
			(xy 22.223852 -159.851363) (xy 22.183183 -159.88497) (xy 22.138273 -159.912657) (xy 22.089979 -159.933897)
			(xy 22.039221 -159.948285) (xy 21.986965 -159.955548) (xy 21.960586 -159.955992) (xy 21.933334 -159.955537)
			(xy 21.879386 -159.947779) (xy 21.827091 -159.932422) (xy 21.777513 -159.909779) (xy 21.731662 -159.880311)
			(xy 21.690472 -159.844618) (xy 21.654781 -159.803426) (xy 21.625314 -159.757575) (xy 21.602673 -159.707996)
			(xy 21.587318 -159.655701) (xy 21.579562 -159.601752) (xy 19.433286 -159.601752) (xy 19.433286 -163.032948)
			(xy 20.014182 -163.032948) (xy 20.018253 -162.977326) (xy 20.030379 -162.922889) (xy 20.050302 -162.870798)
			(xy 20.077598 -162.822163) (xy 20.111684 -162.77802) (xy 20.151833 -162.739311) (xy 20.197191 -162.70686)
			(xy 20.246791 -162.681359) (xy 20.299575 -162.663352) (xy 20.354418 -162.653222) (xy 20.410152 -162.651185)
			(xy 20.465589 -162.657285) (xy 20.519546 -162.671391) (xy 20.570875 -162.693203) (xy 20.618481 -162.722257)
			(xy 20.661349 -162.757932) (xy 20.698566 -162.799469) (xy 20.729339 -162.845982) (xy 20.753011 -162.896479)
			(xy 20.769079 -162.949886) (xy 20.777199 -163.005062) (xy 20.777708 -163.032948) (xy 20.777199 -163.060834)
			(xy 20.769079 -163.11601) (xy 20.753011 -163.169417) (xy 20.729339 -163.219914) (xy 20.698566 -163.266427)
			(xy 20.661349 -163.307964) (xy 20.618481 -163.343639) (xy 20.570875 -163.372693) (xy 20.525196 -163.392104)
			(xy 22.73884 -163.392104) (xy 22.742911 -163.336482) (xy 22.755037 -163.282045) (xy 22.77496 -163.229954)
			(xy 22.802256 -163.181319) (xy 22.836342 -163.137176) (xy 22.876491 -163.098467) (xy 22.921849 -163.066016)
			(xy 22.971449 -163.040515) (xy 23.024233 -163.022508) (xy 23.079076 -163.012378) (xy 23.13481 -163.010341)
			(xy 23.190247 -163.016441) (xy 23.244204 -163.030547) (xy 23.295533 -163.052359) (xy 23.343139 -163.081413)
			(xy 23.386007 -163.117088) (xy 23.423224 -163.158625) (xy 23.453997 -163.205138) (xy 23.477669 -163.255635)
			(xy 23.493737 -163.309042) (xy 23.501857 -163.364218) (xy 23.502366 -163.392104) (xy 23.501857 -163.41999)
			(xy 23.493737 -163.475166) (xy 23.477669 -163.528573) (xy 23.453997 -163.57907) (xy 23.423224 -163.625583)
			(xy 23.386007 -163.66712) (xy 23.343139 -163.702795) (xy 23.295533 -163.731849) (xy 23.244204 -163.753661)
			(xy 23.190247 -163.767767) (xy 23.13481 -163.773867) (xy 23.079076 -163.77183) (xy 23.024233 -163.7617)
			(xy 22.971449 -163.743693) (xy 22.921849 -163.718192) (xy 22.876491 -163.685741) (xy 22.836342 -163.647032)
			(xy 22.802256 -163.602889) (xy 22.77496 -163.554254) (xy 22.755037 -163.502163) (xy 22.742911 -163.447726)
			(xy 22.73884 -163.392104) (xy 20.525196 -163.392104) (xy 20.519546 -163.394505) (xy 20.465589 -163.408611)
			(xy 20.410152 -163.414711) (xy 20.354418 -163.412674) (xy 20.299575 -163.402544) (xy 20.246791 -163.384537)
			(xy 20.197191 -163.359036) (xy 20.151833 -163.326585) (xy 20.111684 -163.287876) (xy 20.077598 -163.243733)
			(xy 20.050302 -163.195098) (xy 20.030379 -163.143007) (xy 20.018253 -163.08857) (xy 20.014182 -163.032948)
			(xy 19.433286 -163.032948) (xy 19.433286 -164.194744) (xy 20.752814 -164.194744) (xy 20.756885 -164.139122)
			(xy 20.769011 -164.084685) (xy 20.788934 -164.032594) (xy 20.81623 -163.983959) (xy 20.850316 -163.939816)
			(xy 20.890465 -163.901107) (xy 20.935823 -163.868656) (xy 20.985423 -163.843155) (xy 21.038207 -163.825148)
			(xy 21.09305 -163.815018) (xy 21.148784 -163.812981) (xy 21.204221 -163.819081) (xy 21.258178 -163.833187)
			(xy 21.309507 -163.854999) (xy 21.357113 -163.884053) (xy 21.399981 -163.919728) (xy 21.437198 -163.961265)
			(xy 21.467971 -164.007778) (xy 21.491643 -164.058275) (xy 21.507711 -164.111682) (xy 21.515831 -164.166858)
			(xy 21.51634 -164.194744) (xy 21.515831 -164.22263) (xy 21.507711 -164.277806) (xy 21.491643 -164.331213)
			(xy 21.467971 -164.38171) (xy 21.437198 -164.428223) (xy 21.399981 -164.46976) (xy 21.357113 -164.505435)
			(xy 21.309507 -164.534489) (xy 21.258178 -164.556301) (xy 21.204221 -164.570407) (xy 21.148784 -164.576507)
			(xy 21.09305 -164.57447) (xy 21.038207 -164.56434) (xy 20.985423 -164.546333) (xy 20.935823 -164.520832)
			(xy 20.890465 -164.488381) (xy 20.850316 -164.449672) (xy 20.81623 -164.405529) (xy 20.788934 -164.356894)
			(xy 20.769011 -164.304803) (xy 20.756885 -164.250366) (xy 20.752814 -164.194744) (xy 19.433286 -164.194744)
			(xy 19.433286 -164.994336) (xy 22.751794 -164.994336) (xy 22.755865 -164.938714) (xy 22.767991 -164.884277)
			(xy 22.787914 -164.832186) (xy 22.81521 -164.783551) (xy 22.849296 -164.739408) (xy 22.889445 -164.700699)
			(xy 22.934803 -164.668248) (xy 22.984403 -164.642747) (xy 23.037187 -164.62474) (xy 23.09203 -164.61461)
			(xy 23.147764 -164.612573) (xy 23.203201 -164.618673) (xy 23.257158 -164.632779) (xy 23.308487 -164.654591)
			(xy 23.356093 -164.683645) (xy 23.398961 -164.71932) (xy 23.436178 -164.760857) (xy 23.466951 -164.80737)
			(xy 23.490623 -164.857867) (xy 23.506691 -164.911274) (xy 23.514811 -164.96645) (xy 23.51532 -164.994336)
			(xy 23.514811 -165.022222) (xy 23.506691 -165.077398) (xy 23.490623 -165.130805) (xy 23.466951 -165.181302)
			(xy 23.436178 -165.227815) (xy 23.398961 -165.269352) (xy 23.356093 -165.305027) (xy 23.308487 -165.334081)
			(xy 23.257158 -165.355893) (xy 23.203201 -165.369999) (xy 23.147764 -165.376099) (xy 23.09203 -165.374062)
			(xy 23.037187 -165.363932) (xy 22.984403 -165.345925) (xy 22.934803 -165.320424) (xy 22.889445 -165.287973)
			(xy 22.849296 -165.249264) (xy 22.81521 -165.205121) (xy 22.787914 -165.156486) (xy 22.767991 -165.104395)
			(xy 22.755865 -165.049958) (xy 22.751794 -164.994336) (xy 19.433286 -164.994336) (xy 19.433286 -165.751256)
			(xy 20.741892 -165.751256) (xy 20.745963 -165.695634) (xy 20.758089 -165.641197) (xy 20.778012 -165.589106)
			(xy 20.805308 -165.540471) (xy 20.839394 -165.496328) (xy 20.879543 -165.457619) (xy 20.924901 -165.425168)
			(xy 20.974501 -165.399667) (xy 21.027285 -165.38166) (xy 21.082128 -165.37153) (xy 21.137862 -165.369493)
			(xy 21.193299 -165.375593) (xy 21.247256 -165.389699) (xy 21.298585 -165.411511) (xy 21.346191 -165.440565)
			(xy 21.389059 -165.47624) (xy 21.426276 -165.517777) (xy 21.457049 -165.56429) (xy 21.480721 -165.614787)
			(xy 21.496789 -165.668194) (xy 21.504909 -165.72337) (xy 21.505418 -165.751256) (xy 21.504909 -165.779142)
			(xy 21.496789 -165.834318) (xy 21.480721 -165.887725) (xy 21.457049 -165.938222) (xy 21.426276 -165.984735)
			(xy 21.389059 -166.026272) (xy 21.346191 -166.061947) (xy 21.298585 -166.091001) (xy 21.247256 -166.112813)
			(xy 21.193299 -166.126919) (xy 21.137862 -166.133019) (xy 21.082128 -166.130982) (xy 21.027285 -166.120852)
			(xy 20.974501 -166.102845) (xy 20.924901 -166.077344) (xy 20.879543 -166.044893) (xy 20.839394 -166.006184)
			(xy 20.805308 -165.962041) (xy 20.778012 -165.913406) (xy 20.758089 -165.861315) (xy 20.745963 -165.806878)
			(xy 20.741892 -165.751256) (xy 19.433286 -165.751256) (xy 19.433286 -166.25316) (xy 23.932132 -166.25316)
			(xy 23.936203 -166.197538) (xy 23.948329 -166.143101) (xy 23.968252 -166.09101) (xy 23.995548 -166.042375)
			(xy 24.029634 -165.998232) (xy 24.069783 -165.959523) (xy 24.115141 -165.927072) (xy 24.164741 -165.901571)
			(xy 24.217525 -165.883564) (xy 24.272368 -165.873434) (xy 24.328102 -165.871397) (xy 24.383539 -165.877497)
			(xy 24.437496 -165.891603) (xy 24.488825 -165.913415) (xy 24.536431 -165.942469) (xy 24.579299 -165.978144)
			(xy 24.616516 -166.019681) (xy 24.647289 -166.066194) (xy 24.670961 -166.116691) (xy 24.687029 -166.170098)
			(xy 24.695149 -166.225274) (xy 24.695658 -166.25316) (xy 24.695149 -166.281046) (xy 24.687029 -166.336222)
			(xy 24.670961 -166.389629) (xy 24.647289 -166.440126) (xy 24.616516 -166.486639) (xy 24.579299 -166.528176)
			(xy 24.536431 -166.563851) (xy 24.488825 -166.592905) (xy 24.437496 -166.614717) (xy 24.383539 -166.628823)
			(xy 24.328102 -166.634923) (xy 24.272368 -166.632886) (xy 24.217525 -166.622756) (xy 24.164741 -166.604749)
			(xy 24.115141 -166.579248) (xy 24.069783 -166.546797) (xy 24.029634 -166.508088) (xy 23.995548 -166.463945)
			(xy 23.968252 -166.41531) (xy 23.948329 -166.363219) (xy 23.936203 -166.308782) (xy 23.932132 -166.25316)
			(xy 19.433286 -166.25316) (xy 19.433286 -167.416046) (xy 20.000149 -167.416046) (xy 20.00015 -167.361539)
			(xy 20.007908 -167.307587) (xy 20.023266 -167.255288) (xy 20.04591 -167.205707) (xy 20.07538 -167.159853)
			(xy 20.111076 -167.118661) (xy 20.152271 -167.082967) (xy 20.198126 -167.0535) (xy 20.247708 -167.030858)
			(xy 20.300008 -167.015504) (xy 20.35396 -167.007748) (xy 20.381214 -167.007286) (xy 20.409833 -167.007814)
			(xy 20.46642 -167.016427) (xy 20.52109 -167.033384) (xy 20.547076 -167.045386) (xy 20.559384 -167.050937)
			(xy 20.585915 -167.055914) (xy 20.612823 -167.053761) (xy 20.638225 -167.044628) (xy 20.660345 -167.029155)
			(xy 20.677633 -167.008425) (xy 20.688882 -166.983886) (xy 20.693304 -166.957257) (xy 20.692364 -166.943786)
			(xy 20.690586 -166.906194) (xy 20.691062 -166.878942) (xy 20.698819 -166.824992) (xy 20.714176 -166.772695)
			(xy 20.736819 -166.723116) (xy 20.766287 -166.677264) (xy 20.801981 -166.636072) (xy 20.843174 -166.60038)
			(xy 20.889026 -166.570913) (xy 20.938606 -166.548272) (xy 20.990903 -166.532917) (xy 21.044854 -166.525161)
			(xy 21.099358 -166.525162) (xy 21.153308 -166.532919) (xy 21.205605 -166.548276) (xy 21.255184 -166.570919)
			(xy 21.301036 -166.600387) (xy 21.342228 -166.636081) (xy 21.37792 -166.677274) (xy 21.407387 -166.723126)
			(xy 21.430028 -166.772706) (xy 21.445383 -166.825003) (xy 21.453139 -166.878954) (xy 21.453138 -166.933458)
			(xy 21.445381 -166.987408) (xy 21.430024 -167.039705) (xy 21.407381 -167.089284) (xy 21.377913 -167.135136)
			(xy 21.342219 -167.176328) (xy 21.301026 -167.21202) (xy 21.255174 -167.241487) (xy 21.205594 -167.264128)
			(xy 21.153297 -167.279483) (xy 21.099346 -167.287239) (xy 21.072094 -167.287702) (xy 21.043475 -167.287173)
			(xy 20.986888 -167.27856) (xy 20.932218 -167.261604) (xy 20.906232 -167.249602) (xy 20.893916 -167.244072)
			(xy 20.867388 -167.239095) (xy 20.840484 -167.241247) (xy 20.815084 -167.250377) (xy 20.792967 -167.265846)
			(xy 20.775679 -167.286573) (xy 20.764429 -167.311108) (xy 20.760005 -167.337733) (xy 20.760944 -167.351202)
			(xy 20.762722 -167.388794) (xy 20.762251 -167.416048) (xy 20.754495 -167.47) (xy 20.739139 -167.522299)
			(xy 20.729234 -167.543988) (xy 23.966422 -167.543988) (xy 23.970493 -167.488366) (xy 23.982619 -167.433929)
			(xy 24.002542 -167.381838) (xy 24.029838 -167.333203) (xy 24.063924 -167.28906) (xy 24.104073 -167.250351)
			(xy 24.149431 -167.2179) (xy 24.199031 -167.192399) (xy 24.251815 -167.174392) (xy 24.306658 -167.164262)
			(xy 24.362392 -167.162225) (xy 24.417829 -167.168325) (xy 24.471786 -167.182431) (xy 24.523115 -167.204243)
			(xy 24.570721 -167.233297) (xy 24.613589 -167.268972) (xy 24.650806 -167.310509) (xy 24.681579 -167.357022)
			(xy 24.705251 -167.407519) (xy 24.721319 -167.460926) (xy 24.729439 -167.516102) (xy 24.729948 -167.543988)
			(xy 24.729439 -167.571874) (xy 24.721319 -167.62705) (xy 24.705251 -167.680457) (xy 24.681579 -167.730954)
			(xy 24.650806 -167.777467) (xy 24.613589 -167.819004) (xy 24.570721 -167.854679) (xy 24.523115 -167.883733)
			(xy 24.471786 -167.905545) (xy 24.417829 -167.919651) (xy 24.362392 -167.925751) (xy 24.306658 -167.923714)
			(xy 24.251815 -167.913584) (xy 24.199031 -167.895577) (xy 24.149431 -167.870076) (xy 24.104073 -167.837625)
			(xy 24.063924 -167.798916) (xy 24.029838 -167.754773) (xy 24.002542 -167.706138) (xy 23.982619 -167.654047)
			(xy 23.970493 -167.59961) (xy 23.966422 -167.543988) (xy 20.729234 -167.543988) (xy 20.716496 -167.571881)
			(xy 20.687028 -167.617736) (xy 20.651334 -167.65893) (xy 20.61014 -167.694625) (xy 20.564286 -167.724094)
			(xy 20.514704 -167.746737) (xy 20.462405 -167.762094) (xy 20.408453 -167.769851) (xy 20.353946 -167.769851)
			(xy 20.299993 -167.762093) (xy 20.247694 -167.746737) (xy 20.198113 -167.724093) (xy 20.152259 -167.694624)
			(xy 20.111065 -167.658929) (xy 20.075371 -167.617735) (xy 20.045903 -167.57188) (xy 20.023261 -167.522298)
			(xy 20.007905 -167.469999) (xy 20.000149 -167.416046) (xy 19.433286 -167.416046) (xy 19.433286 -168.126918)
			(xy 26.807922 -168.126918) (xy 26.808408 -168.099667) (xy 26.816164 -168.045719) (xy 26.831519 -167.993424)
			(xy 26.854161 -167.943847) (xy 26.883627 -167.897997) (xy 26.919318 -167.856806) (xy 26.960509 -167.821115)
			(xy 27.006359 -167.791649) (xy 27.055936 -167.769007) (xy 27.108231 -167.753652) (xy 27.162179 -167.745896)
			(xy 27.216681 -167.745896) (xy 27.270629 -167.753652) (xy 27.322924 -167.769007) (xy 27.372501 -167.791649)
			(xy 27.418351 -167.821115) (xy 27.459542 -167.856806) (xy 27.495233 -167.897997) (xy 27.524699 -167.943847)
			(xy 27.547341 -167.993424) (xy 27.562696 -168.045719) (xy 27.570452 -168.099667) (xy 27.570938 -168.126918)
			(xy 27.570638 -168.147792) (xy 27.566061 -168.189287) (xy 27.561794 -168.209722) (xy 27.56312 -168.219191)
			(xy 27.564519 -168.238261) (xy 27.564588 -168.247822) (xy 27.564588 -169.09796) (xy 32.975802 -169.09796)
			(xy 32.979873 -169.042338) (xy 32.991999 -168.987901) (xy 33.011922 -168.93581) (xy 33.039218 -168.887175)
			(xy 33.073304 -168.843032) (xy 33.113453 -168.804323) (xy 33.158811 -168.771872) (xy 33.208411 -168.746371)
			(xy 33.261195 -168.728364) (xy 33.316038 -168.718234) (xy 33.371772 -168.716197) (xy 33.427209 -168.722297)
			(xy 33.481166 -168.736403) (xy 33.532495 -168.758215) (xy 33.580101 -168.787269) (xy 33.622969 -168.822944)
			(xy 33.660186 -168.864481) (xy 33.690959 -168.910994) (xy 33.714631 -168.961491) (xy 33.730699 -169.014898)
			(xy 33.738819 -169.070074) (xy 33.739328 -169.09796) (xy 33.738819 -169.125846) (xy 33.730699 -169.181022)
			(xy 33.714631 -169.234429) (xy 33.690959 -169.284926) (xy 33.660186 -169.331439) (xy 33.622969 -169.372976)
			(xy 33.580101 -169.408651) (xy 33.532495 -169.437705) (xy 33.481166 -169.459517) (xy 33.427209 -169.473623)
			(xy 33.371772 -169.479723) (xy 33.316038 -169.477686) (xy 33.261195 -169.467556) (xy 33.208411 -169.449549)
			(xy 33.158811 -169.424048) (xy 33.113453 -169.391597) (xy 33.073304 -169.352888) (xy 33.039218 -169.308745)
			(xy 33.011922 -169.26011) (xy 32.991999 -169.208019) (xy 32.979873 -169.153582) (xy 32.975802 -169.09796)
			(xy 27.564588 -169.09796) (xy 27.564588 -170.67022) (xy 30.752032 -170.67022) (xy 30.756103 -170.614598)
			(xy 30.768229 -170.560161) (xy 30.788152 -170.50807) (xy 30.815448 -170.459435) (xy 30.849534 -170.415292)
			(xy 30.889683 -170.376583) (xy 30.935041 -170.344132) (xy 30.984641 -170.318631) (xy 31.037425 -170.300624)
			(xy 31.092268 -170.290494) (xy 31.148002 -170.288457) (xy 31.203439 -170.294557) (xy 31.257396 -170.308663)
			(xy 31.308725 -170.330475) (xy 31.356331 -170.359529) (xy 31.399199 -170.395204) (xy 31.436416 -170.436741)
			(xy 31.467189 -170.483254) (xy 31.490861 -170.533751) (xy 31.506929 -170.587158) (xy 31.515049 -170.642334)
			(xy 31.515558 -170.67022) (xy 31.515049 -170.698106) (xy 31.506929 -170.753282) (xy 31.490861 -170.806689)
			(xy 31.467189 -170.857186) (xy 31.436416 -170.903699) (xy 31.399199 -170.945236) (xy 31.356331 -170.980911)
			(xy 31.308725 -171.009965) (xy 31.257396 -171.031777) (xy 31.203439 -171.045883) (xy 31.148002 -171.051983)
			(xy 31.092268 -171.049946) (xy 31.037425 -171.039816) (xy 30.984641 -171.021809) (xy 30.935041 -170.996308)
			(xy 30.889683 -170.963857) (xy 30.849534 -170.925148) (xy 30.815448 -170.881005) (xy 30.788152 -170.83237)
			(xy 30.768229 -170.780279) (xy 30.756103 -170.725842) (xy 30.752032 -170.67022) (xy 27.564588 -170.67022)
			(xy 27.564588 -170.762422) (xy 28.25242 -171.450254) (xy 28.265215 -171.463478) (xy 28.287278 -171.492926)
			(xy 28.296362 -171.508928) (xy 28.299918 -171.515532) (xy 29.039566 -172.25518) (xy 39.976298 -172.25518)
			(xy 41.556432 -170.675046) (xy 41.556432 -169.46626) (xy 41.556975 -169.442499) (xy 41.566247 -169.39589)
			(xy 41.584445 -169.351991) (xy 41.610869 -169.312492) (xy 41.627298 -169.295318) (xy 44.66209 -166.260526)
			(xy 44.67929 -166.244126) (xy 44.718783 -166.217704) (xy 44.762674 -166.199499) (xy 44.809274 -166.190211)
			(xy 44.833032 -166.18966) (xy 49.278286 -166.18966) (xy 50.207418 -165.260528) (xy 50.206402 -165.23843)
			(xy 50.206148 -165.222174) (xy 50.206653 -165.194924) (xy 50.214412 -165.140979) (xy 50.229769 -165.088688)
			(xy 50.25241 -165.039113) (xy 50.281874 -164.993265) (xy 50.317564 -164.952076) (xy 50.358751 -164.916385)
			(xy 50.404597 -164.886918) (xy 50.454171 -164.864275) (xy 50.506462 -164.848916) (xy 50.560406 -164.841155)
			(xy 50.587656 -164.840666) (xy 50.58791 -164.840666) (xy 50.617749 -164.841247) (xy 50.676695 -164.850559)
			(xy 50.705258 -164.859208) (xy 50.719167 -164.863239) (xy 50.748099 -164.864148) (xy 50.776118 -164.856883)
			(xy 50.800963 -164.842032) (xy 50.820629 -164.820792) (xy 50.833527 -164.794879) (xy 50.836576 -164.780722)
			(xy 50.843165 -164.747884) (xy 50.866284 -164.685031) (xy 50.88255 -164.655754) (xy 50.889618 -164.642804)
			(xy 50.896647 -164.614161) (xy 50.895197 -164.584704) (xy 50.885389 -164.55689) (xy 50.868042 -164.533039)
			(xy 50.844601 -164.515141) (xy 50.830988 -164.50945) (xy 50.80422 -164.498735) (xy 50.753979 -164.47045)
			(xy 50.70857 -164.434922) (xy 50.669027 -164.392963) (xy 50.636253 -164.345528) (xy 50.610993 -164.2937)
			(xy 50.593825 -164.23866) (xy 50.585139 -164.181662) (xy 50.584608 -164.152834) (xy 50.585094 -164.125583)
			(xy 50.59285 -164.071635) (xy 50.608205 -164.01934) (xy 50.630847 -163.969763) (xy 50.660313 -163.923913)
			(xy 50.696004 -163.882722) (xy 50.737195 -163.847031) (xy 50.783045 -163.817565) (xy 50.832622 -163.794923)
			(xy 50.884917 -163.779568) (xy 50.938865 -163.771812) (xy 50.993367 -163.771812) (xy 51.047315 -163.779568)
			(xy 51.09961 -163.794923) (xy 51.149187 -163.817565) (xy 51.195037 -163.847031) (xy 51.236228 -163.882722)
			(xy 51.271919 -163.923913) (xy 51.301385 -163.969763) (xy 51.324027 -164.01934) (xy 51.339382 -164.071635)
			(xy 51.347138 -164.125583) (xy 51.347624 -164.152834) (xy 51.347624 -164.153088) (xy 51.347224 -164.178292)
			(xy 51.340585 -164.22826) (xy 51.327409 -164.276914) (xy 51.307926 -164.323404) (xy 51.295554 -164.345366)
			(xy 51.28846 -164.358303) (xy 51.281434 -164.386951) (xy 51.282888 -164.416412) (xy 51.292701 -164.444229)
			(xy 51.310054 -164.468081) (xy 51.3335 -164.48598) (xy 51.347116 -164.49167) (xy 51.373892 -164.502366)
			(xy 51.424134 -164.530654) (xy 51.469543 -164.566184) (xy 51.509085 -164.608146) (xy 51.541859 -164.655583)
			(xy 51.567117 -164.707414) (xy 51.584283 -164.762457) (xy 51.592966 -164.819457) (xy 51.593496 -164.848286)
			(xy 51.593032 -164.875539) (xy 51.585276 -164.929491) (xy 51.569921 -164.981789) (xy 51.54728 -165.03137)
			(xy 51.517812 -165.077224) (xy 51.482118 -165.118417) (xy 51.440925 -165.154111) (xy 51.395072 -165.183579)
			(xy 51.345491 -165.206221) (xy 51.293193 -165.221576) (xy 51.239241 -165.229331) (xy 51.211988 -165.229794)
			(xy 51.211734 -165.229794) (xy 51.181895 -165.229227) (xy 51.122949 -165.219906) (xy 51.094386 -165.211252)
			(xy 51.080457 -165.207302) (xy 51.051539 -165.206385) (xy 51.02353 -165.213636) (xy 50.998691 -165.228471)
			(xy 50.979026 -165.249693) (xy 50.966122 -165.275589) (xy 50.963068 -165.289738) (xy 50.957919 -165.315816)
			(xy 50.941346 -165.36632) (xy 50.917921 -165.414034) (xy 50.888096 -165.458032) (xy 50.852451 -165.497463)
			(xy 50.811676 -165.531561) (xy 50.76656 -165.559667) (xy 50.717979 -165.581236) (xy 50.666873 -165.595849)
			(xy 50.614233 -165.603225) (xy 50.587656 -165.603682) (xy 50.5714 -165.603428) (xy 50.549302 -165.602412)
			(xy 49.549304 -166.60241) (xy 49.532112 -166.618818) (xy 49.492615 -166.645237) (xy 49.448722 -166.663439)
			(xy 49.402121 -166.672725) (xy 49.378362 -166.673276) (xy 44.933108 -166.673276) (xy 42.040048 -169.566336)
			(xy 42.040048 -169.801794) (xy 43.431209 -169.801794) (xy 43.435245 -169.718347) (xy 43.447317 -169.635679)
			(xy 43.46731 -169.554562) (xy 43.495039 -169.475753) (xy 43.530245 -169.399988) (xy 43.572599 -169.327975)
			(xy 43.621705 -169.260386) (xy 43.677106 -169.197852) (xy 43.738283 -169.140957) (xy 43.804666 -169.090231)
			(xy 43.875634 -169.04615) (xy 43.950526 -169.009124) (xy 44.028642 -168.979498) (xy 44.109252 -168.95755)
			(xy 44.191604 -168.943485) (xy 44.27493 -168.937433) (xy 44.35845 -168.939452) (xy 44.441386 -168.949522)
			(xy 44.522962 -168.96755) (xy 44.602418 -168.993367) (xy 44.679011 -169.026732) (xy 44.752027 -169.067333)
			(xy 44.820783 -169.114792) (xy 44.884637 -169.168665) (xy 44.942994 -169.22845) (xy 44.995309 -169.293587)
			(xy 45.041092 -169.36347) (xy 45.079917 -169.437445) (xy 45.111422 -169.514822) (xy 45.135311 -169.594879)
			(xy 45.151362 -169.676867) (xy 45.159425 -169.760022) (xy 45.15993 -169.801794) (xy 45.159425 -169.843566)
			(xy 45.151362 -169.926721) (xy 45.135311 -170.008709) (xy 45.111422 -170.088766) (xy 45.079917 -170.166143)
			(xy 45.041092 -170.240118) (xy 44.995309 -170.310001) (xy 44.942994 -170.375138) (xy 44.884637 -170.434923)
			(xy 44.820783 -170.488796) (xy 44.752027 -170.536255) (xy 44.679011 -170.576856) (xy 44.602418 -170.610221)
			(xy 44.522962 -170.636038) (xy 44.441386 -170.654066) (xy 44.35845 -170.664136) (xy 44.27493 -170.666155)
			(xy 44.191604 -170.660103) (xy 44.109252 -170.646038) (xy 44.028642 -170.62409) (xy 43.950526 -170.594464)
			(xy 43.875634 -170.557438) (xy 43.804666 -170.513357) (xy 43.738283 -170.462631) (xy 43.677106 -170.405736)
			(xy 43.621705 -170.343202) (xy 43.572599 -170.275613) (xy 43.530245 -170.2036) (xy 43.495039 -170.127835)
			(xy 43.46731 -170.049026) (xy 43.447317 -169.967909) (xy 43.435245 -169.885241) (xy 43.431209 -169.801794)
			(xy 42.040048 -169.801794) (xy 42.040048 -170.703748) (xy 49.415192 -170.703748) (xy 49.415192 -169.357548)
			(xy 49.415678 -169.33256) (xy 49.423498 -169.283201) (xy 49.438952 -169.235675) (xy 49.461658 -169.191156)
			(xy 49.491057 -169.150743) (xy 49.50841 -169.132758) (xy 50.050192 -168.590976) (xy 50.050192 -167.020748)
			(xy 50.050678 -166.99576) (xy 50.058498 -166.946401) (xy 50.073952 -166.898875) (xy 50.096658 -166.854356)
			(xy 50.126057 -166.813943) (xy 50.14341 -166.795958) (xy 51.777392 -165.161976) (xy 51.777392 -163.591748)
			(xy 51.777878 -163.56676) (xy 51.785698 -163.517401) (xy 51.801152 -163.469875) (xy 51.823858 -163.425356)
			(xy 51.853257 -163.384943) (xy 51.87061 -163.366958) (xy 52.83581 -162.401758) (xy 52.853808 -162.384423)
			(xy 52.894235 -162.355056) (xy 52.938753 -162.332363) (xy 52.986269 -162.316902) (xy 53.035616 -162.309051)
			(xy 53.0606 -162.30854) (xy 53.640228 -162.30854) (xy 53.733192 -162.215576) (xy 53.733192 -161.98215)
			(xy 53.73266 -161.967778) (xy 53.72458 -161.940189) (xy 53.70913 -161.915946) (xy 53.687535 -161.89697)
			(xy 53.661507 -161.884765) (xy 53.633109 -161.880299) (xy 53.604591 -161.883924) (xy 53.591206 -161.889186)
			(xy 53.567169 -161.899114) (xy 53.517088 -161.913124) (xy 53.46557 -161.92022) (xy 53.439568 -161.920682)
			(xy 53.439314 -161.920682) (xy 53.412059 -161.920272) (xy 53.358102 -161.912516) (xy 53.305799 -161.89716)
			(xy 53.256214 -161.874517) (xy 53.210356 -161.845047) (xy 53.169159 -161.809351) (xy 53.133461 -161.768155)
			(xy 53.10399 -161.722298) (xy 53.081345 -161.672714) (xy 53.065987 -161.620411) (xy 53.058229 -161.566455)
			(xy 53.058229 -161.511945) (xy 53.065987 -161.457989) (xy 53.081345 -161.405686) (xy 53.10399 -161.356102)
			(xy 53.133461 -161.310245) (xy 53.169159 -161.269049) (xy 53.210356 -161.233353) (xy 53.256214 -161.203883)
			(xy 53.305799 -161.18124) (xy 53.358102 -161.165884) (xy 53.412059 -161.158128) (xy 53.439314 -161.157666)
			(xy 53.439568 -161.157666) (xy 53.463462 -161.158038) (xy 53.510874 -161.164026) (xy 53.557164 -161.175898)
			(xy 53.579522 -161.184336) (xy 53.592887 -161.189017) (xy 53.62105 -161.191798) (xy 53.648893 -161.186739)
			(xy 53.674279 -161.17423) (xy 53.695254 -161.155233) (xy 53.710207 -161.131206) (xy 53.71799 -161.103998)
			(xy 53.71846 -161.089848) (xy 53.71846 -157.158436) (xy 53.58003 -157.020006) (xy 53.569937 -157.010334)
			(xy 53.545606 -156.99658) (xy 53.518457 -156.989939) (xy 53.490525 -156.990909) (xy 53.463902 -156.999416)
			(xy 53.440584 -157.014825) (xy 53.422317 -157.03598) (xy 53.410472 -157.061295) (xy 53.405936 -157.088873)
			(xy 53.407056 -157.10281) (xy 53.408116 -157.112937) (xy 53.40926 -157.133268) (xy 53.409342 -157.14345)
			(xy 53.408875 -157.170782) (xy 53.400906 -157.224863) (xy 53.385118 -157.277198) (xy 53.36185 -157.326662)
			(xy 53.331601 -157.372195) (xy 53.295022 -157.412817) (xy 53.252897 -157.447655) (xy 53.229764 -157.46222)
			(xy 53.217537 -157.470138) (xy 53.19787 -157.491612) (xy 53.185068 -157.517767) (xy 53.180173 -157.546472)
			(xy 53.183584 -157.575392) (xy 53.18887 -157.588966) (xy 53.198345 -157.612181) (xy 53.211701 -157.660512)
			(xy 53.218435 -157.710199) (xy 53.218842 -157.73527) (xy 53.218431 -157.76034) (xy 53.211677 -157.810023)
			(xy 53.198339 -157.858357) (xy 53.18887 -157.881574) (xy 53.183624 -157.895151) (xy 53.180262 -157.924051)
			(xy 53.185173 -157.952729) (xy 53.197961 -157.978863) (xy 53.217591 -158.000338) (xy 53.229764 -158.00832)
			(xy 53.252885 -158.022903) (xy 53.295003 -158.057747) (xy 53.331579 -158.098369) (xy 53.361829 -158.143898)
			(xy 53.385103 -158.193358) (xy 53.400902 -158.245688) (xy 53.408888 -158.299764) (xy 53.408889 -158.354426)
			(xy 53.400905 -158.408502) (xy 53.385107 -158.460832) (xy 53.361834 -158.510292) (xy 53.331585 -158.555823)
			(xy 53.29501 -158.596446) (xy 53.252893 -158.631291) (xy 53.229764 -158.64586) (xy 53.217509 -158.653739)
			(xy 53.197842 -158.675225) (xy 53.185043 -158.70139) (xy 53.180156 -158.730104) (xy 53.183577 -158.75903)
			(xy 53.18887 -158.772606) (xy 53.198357 -158.795817) (xy 53.211708 -158.844149) (xy 53.218438 -158.893838)
			(xy 53.218842 -158.91891) (xy 53.21837 -158.945752) (xy 53.210665 -158.998881) (xy 53.195416 -159.050354)
			(xy 53.172938 -159.099106) (xy 53.143697 -159.144127) (xy 53.108298 -159.184487) (xy 53.067473 -159.219349)
			(xy 53.022069 -159.247993) (xy 52.973024 -159.269824) (xy 52.947316 -159.277558) (xy 52.932841 -159.282276)
			(xy 52.907286 -159.298788) (xy 52.887726 -159.322092) (xy 52.875894 -159.350122) (xy 52.87284 -159.380393)
			(xy 52.878835 -159.410222) (xy 52.885594 -159.423862) (xy 52.900228 -159.452008) (xy 52.920955 -159.511959)
			(xy 52.931453 -159.574517) (xy 52.932076 -159.606234) (xy 52.931855 -159.624253) (xy 52.928421 -159.660128)
			(xy 52.925218 -159.677862) (xy 52.922936 -159.693077) (xy 52.926453 -159.723622) (xy 52.938901 -159.751736)
			(xy 52.959153 -159.774871) (xy 52.985373 -159.790931) (xy 53.000148 -159.79521) (xy 53.027191 -159.802611)
			(xy 53.078917 -159.824241) (xy 53.126922 -159.853205) (xy 53.170174 -159.88888) (xy 53.207741 -159.930499)
			(xy 53.238815 -159.977165) (xy 53.262728 -160.027876) (xy 53.278965 -160.08154) (xy 53.287177 -160.137001)
			(xy 53.287676 -160.165034) (xy 53.287254 -160.192288) (xy 53.279492 -160.246239) (xy 53.264131 -160.298537)
			(xy 53.241483 -160.348117) (xy 53.21201 -160.393968) (xy 53.176312 -160.435159) (xy 53.135115 -160.47085)
			(xy 53.089259 -160.500315) (xy 53.039675 -160.522954) (xy 52.987375 -160.538306) (xy 52.933422 -160.546058)
			(xy 52.906168 -160.546542) (xy 52.878594 -160.54605) (xy 52.824022 -160.538105) (xy 52.771161 -160.522387)
			(xy 52.721115 -160.499222) (xy 52.674925 -160.469093) (xy 52.633554 -160.432628) (xy 52.615338 -160.411922)
			(xy 52.60544 -160.401024) (xy 52.58079 -160.384949) (xy 52.552582 -160.376565) (xy 52.523154 -160.376565)
			(xy 52.494946 -160.384949) (xy 52.470296 -160.401024) (xy 52.460398 -160.411922) (xy 52.442183 -160.432628)
			(xy 52.400812 -160.469093) (xy 52.354622 -160.49922) (xy 52.304575 -160.522383) (xy 52.251714 -160.538099)
			(xy 52.197142 -160.546039) (xy 52.141994 -160.546039) (xy 52.087422 -160.538099) (xy 52.034561 -160.522383)
			(xy 51.984514 -160.49922) (xy 51.938324 -160.469093) (xy 51.896953 -160.432628) (xy 51.878738 -160.411922)
			(xy 51.86884 -160.401024) (xy 51.84419 -160.384949) (xy 51.815982 -160.376565) (xy 51.786554 -160.376565)
			(xy 51.758346 -160.384949) (xy 51.733696 -160.401024) (xy 51.723798 -160.411922) (xy 51.705596 -160.432642)
			(xy 51.664225 -160.46911) (xy 51.618033 -160.499241) (xy 51.567983 -160.522405) (xy 51.515119 -160.53812)
			(xy 51.460543 -160.546058) (xy 51.432968 -160.546542) (xy 51.405718 -160.546052) (xy 51.351772 -160.538292)
			(xy 51.299479 -160.522935) (xy 51.249904 -160.500292) (xy 51.204055 -160.470826) (xy 51.162866 -160.435135)
			(xy 51.127175 -160.393946) (xy 51.097709 -160.348098) (xy 51.075066 -160.298523) (xy 51.059708 -160.24623)
			(xy 51.051948 -160.192284) (xy 51.05146 -160.165034) (xy 51.052043 -160.137181) (xy 51.060161 -160.08207)
			(xy 51.0762 -160.028722) (xy 51.09982 -159.978272) (xy 51.130519 -159.931788) (xy 51.167647 -159.890258)
			(xy 51.210414 -159.854563) (xy 51.257914 -159.825461) (xy 51.309138 -159.803569) (xy 51.33594 -159.795972)
			(xy 51.350063 -159.791719) (xy 51.375204 -159.77632) (xy 51.394916 -159.754396) (xy 51.407566 -159.727764)
			(xy 51.412104 -159.698632) (xy 51.410616 -159.683958) (xy 51.408945 -159.670942) (xy 51.407166 -159.644757)
			(xy 51.40706 -159.631634) (xy 51.407158 -159.617485) (xy 51.409189 -159.589262) (xy 51.411124 -159.575246)
			(xy 51.412683 -159.561896) (xy 51.409585 -159.535209) (xy 51.39962 -159.510259) (xy 51.38348 -159.488781)
			(xy 51.362288 -159.472267) (xy 51.337516 -159.461867) (xy 51.324256 -159.459676) (xy 51.297113 -159.45553)
			(xy 51.244287 -159.440561) (xy 51.194152 -159.418174) (xy 51.147744 -159.388832) (xy 51.106021 -159.353141)
			(xy 51.069844 -159.311838) (xy 51.039961 -159.265777) (xy 51.016989 -159.215907) (xy 51.001402 -159.16326)
			(xy 50.993522 -159.108923) (xy 50.99304 -159.08147) (xy 50.993427 -159.054214) (xy 51.001189 -159.000258)
			(xy 51.016552 -158.947956) (xy 51.039201 -158.898372) (xy 51.068677 -158.852517) (xy 51.104379 -158.811323)
			(xy 51.145579 -158.77563) (xy 51.191441 -158.746164) (xy 51.241029 -158.723524) (xy 51.293334 -158.708173)
			(xy 51.347292 -158.700422) (xy 51.374548 -158.699962) (xy 51.402122 -158.700442) (xy 51.456695 -158.708388)
			(xy 51.509556 -158.724109) (xy 51.559603 -158.747276) (xy 51.605792 -158.777408) (xy 51.647163 -158.813875)
			(xy 51.665378 -158.834582) (xy 51.675276 -158.84548) (xy 51.699926 -158.861555) (xy 51.728134 -158.869939)
			(xy 51.757562 -158.869939) (xy 51.78577 -158.861555) (xy 51.81042 -158.84548) (xy 51.820318 -158.834582)
			(xy 51.838512 -158.813855) (xy 51.879885 -158.777387) (xy 51.926079 -158.747257) (xy 51.97613 -158.724094)
			(xy 52.028995 -158.708381) (xy 52.083572 -158.700445) (xy 52.111148 -158.699962) (xy 52.137649 -158.700415)
			(xy 52.19014 -158.707762) (xy 52.241107 -158.722307) (xy 52.289569 -158.74377) (xy 52.334592 -158.771737)
			(xy 52.355242 -158.788354) (xy 52.367396 -158.797784) (xy 52.395794 -158.809573) (xy 52.426411 -158.812397)
			(xy 52.456486 -158.806003) (xy 52.483306 -158.790967) (xy 52.504451 -158.768645) (xy 52.511706 -158.75508)
			(xy 52.523817 -158.731395) (xy 52.553737 -158.687413) (xy 52.589605 -158.64813) (xy 52.630693 -158.614345)
			(xy 52.653184 -158.60014) (xy 52.665431 -158.592248) (xy 52.685104 -158.570769) (xy 52.697907 -158.544607)
			(xy 52.702796 -158.515894) (xy 52.699373 -158.486969) (xy 52.694078 -158.473394) (xy 52.684593 -158.450182)
			(xy 52.671241 -158.40185) (xy 52.664511 -158.352161) (xy 52.664106 -158.32709) (xy 52.66454 -158.302021)
			(xy 52.671286 -158.252338) (xy 52.684614 -158.204004) (xy 52.694078 -158.180786) (xy 52.699333 -158.167207)
			(xy 52.702713 -158.138299) (xy 52.697811 -158.10961) (xy 52.685024 -158.083464) (xy 52.665389 -158.06198)
			(xy 52.653184 -158.05404) (xy 52.630024 -158.039514) (xy 52.587899 -158.004668) (xy 52.551317 -157.964041)
			(xy 52.521063 -157.918506) (xy 52.497786 -157.869039) (xy 52.481986 -157.816703) (xy 52.474001 -157.762619)
			(xy 52.474003 -157.70795) (xy 52.481993 -157.653867) (xy 52.497797 -157.601532) (xy 52.521079 -157.552067)
			(xy 52.551336 -157.506534) (xy 52.587922 -157.465911) (xy 52.630049 -157.431068) (xy 52.653184 -157.4165)
			(xy 52.66539 -157.408551) (xy 52.685063 -157.387088) (xy 52.697871 -157.360941) (xy 52.702771 -157.332241)
			(xy 52.699363 -157.303326) (xy 52.694078 -157.289754) (xy 52.684581 -157.266547) (xy 52.671233 -157.218213)
			(xy 52.664508 -157.168522) (xy 52.664106 -157.14345) (xy 52.664581 -157.116832) (xy 52.672151 -157.064138)
			(xy 52.687144 -157.013058) (xy 52.709255 -156.964632) (xy 52.738033 -156.919845) (xy 52.772893 -156.879611)
			(xy 52.813125 -156.844749) (xy 52.857909 -156.815967) (xy 52.906333 -156.793853) (xy 52.957413 -156.778856)
			(xy 53.010106 -156.771283) (xy 53.036724 -156.770832) (xy 53.070029 -156.771603) (xy 53.135573 -156.783477)
			(xy 53.167026 -156.794454) (xy 53.180226 -156.79895) (xy 53.208004 -156.801285) (xy 53.235381 -156.79603)
			(xy 53.26032 -156.783574) (xy 53.280967 -156.764844) (xy 53.295787 -156.741233) (xy 53.303677 -156.714497)
			(xy 53.304052 -156.686622) (xy 53.300884 -156.673042) (xy 53.295234 -156.650539) (xy 53.289117 -156.604546)
			(xy 53.288692 -156.581348) (xy 53.288692 -154.269948) (xy 53.289223 -154.241967) (xy 53.297992 -154.186696)
			(xy 53.315305 -154.13348) (xy 53.340735 -154.083629) (xy 53.373655 -154.038374) (xy 53.393086 -154.018234)
			(xy 53.71846 -153.69286) (xy 53.71846 -153.3525) (xy 53.718048 -153.338338) (xy 53.71027 -153.311104)
			(xy 53.69531 -153.287052) (xy 53.674321 -153.268035) (xy 53.648916 -153.255513) (xy 53.621048 -153.250449)
			(xy 53.592862 -153.253234) (xy 53.579522 -153.258012) (xy 53.557157 -153.266426) (xy 53.510867 -153.278289)
			(xy 53.46346 -153.28429) (xy 53.439568 -153.284682) (xy 53.439314 -153.284682) (xy 53.412059 -153.284272)
			(xy 53.358102 -153.276516) (xy 53.305799 -153.26116) (xy 53.256214 -153.238517) (xy 53.210356 -153.209047)
			(xy 53.169159 -153.173351) (xy 53.133461 -153.132155) (xy 53.10399 -153.086298) (xy 53.081345 -153.036714)
			(xy 53.065987 -152.984411) (xy 53.058229 -152.930455) (xy 53.058229 -152.875945) (xy 53.065987 -152.821989)
			(xy 53.081345 -152.769686) (xy 53.10399 -152.720102) (xy 53.133461 -152.674245) (xy 53.169159 -152.633049)
			(xy 53.210356 -152.597353) (xy 53.256214 -152.567883) (xy 53.305799 -152.54524) (xy 53.358102 -152.529884)
			(xy 53.412059 -152.522128) (xy 53.439314 -152.521666) (xy 53.439568 -152.521666) (xy 53.463462 -152.522038)
			(xy 53.510874 -152.528026) (xy 53.557164 -152.539898) (xy 53.579522 -152.548336) (xy 53.592887 -152.553017)
			(xy 53.62105 -152.555798) (xy 53.648893 -152.550739) (xy 53.674279 -152.53823) (xy 53.695254 -152.519233)
			(xy 53.710207 -152.495206) (xy 53.71799 -152.467998) (xy 53.71846 -152.453848) (xy 53.71846 -148.370036)
			(xy 53.316886 -147.968462) (xy 53.297509 -147.948276) (xy 53.264609 -147.90302) (xy 53.239186 -147.853179)
			(xy 53.221863 -147.799978) (xy 53.213066 -147.744723) (xy 53.212492 -147.716748) (xy 53.212492 -145.329148)
			(xy 53.213023 -145.301167) (xy 53.221792 -145.245896) (xy 53.239105 -145.19268) (xy 53.264535 -145.142829)
			(xy 53.297455 -145.097574) (xy 53.316886 -145.077434) (xy 53.71846 -144.67586) (xy 53.71846 -144.634204)
			(xy 53.71801 -144.623338) (xy 53.708969 -144.603572) (xy 53.69258 -144.589294) (xy 53.671761 -144.583048)
			(xy 53.650219 -144.585945) (xy 53.640736 -144.591278) (xy 53.617998 -144.604899) (xy 53.569535 -144.626364)
			(xy 53.518564 -144.640903) (xy 53.46607 -144.648234) (xy 53.439568 -144.648682) (xy 53.439314 -144.648682)
			(xy 53.412059 -144.648272) (xy 53.358102 -144.640516) (xy 53.305799 -144.62516) (xy 53.256214 -144.602517)
			(xy 53.210356 -144.573047) (xy 53.169159 -144.537351) (xy 53.133461 -144.496155) (xy 53.10399 -144.450298)
			(xy 53.081345 -144.400714) (xy 53.065987 -144.348411) (xy 53.058229 -144.294455) (xy 53.058229 -144.239945)
			(xy 53.065987 -144.185989) (xy 53.081345 -144.133686) (xy 53.10399 -144.084102) (xy 53.133461 -144.038245)
			(xy 53.169159 -143.997049) (xy 53.210356 -143.961353) (xy 53.256214 -143.931883) (xy 53.305799 -143.90924)
			(xy 53.358102 -143.893884) (xy 53.412059 -143.886128) (xy 53.439314 -143.885666) (xy 53.439822 -143.885666)
			(xy 53.472957 -143.886408) (xy 53.538223 -143.8979) (xy 53.569616 -143.908526) (xy 53.583198 -143.913028)
			(xy 53.611739 -143.914958) (xy 53.639697 -143.908906) (xy 53.664884 -143.895343) (xy 53.685327 -143.875334)
			(xy 53.699426 -143.850443) (xy 53.70322 -143.836644) (xy 53.710286 -143.809161) (xy 53.73138 -143.756484)
			(xy 53.760045 -143.707514) (xy 53.795649 -143.663332) (xy 53.837407 -143.624912) (xy 53.884396 -143.593104)
			(xy 53.93558 -143.568608) (xy 53.989828 -143.551967) (xy 54.045943 -143.543547) (xy 54.074314 -143.54302)
			(xy 54.101569 -143.543442) (xy 54.155522 -143.551202) (xy 54.207823 -143.566561) (xy 54.257405 -143.589207)
			(xy 54.303259 -143.618679) (xy 54.344453 -143.654377) (xy 54.380146 -143.695574) (xy 54.409613 -143.741432)
			(xy 54.432254 -143.791017) (xy 54.447607 -143.843319) (xy 54.455361 -143.897273) (xy 54.455822 -143.924528)
			(xy 54.455092 -143.957461) (xy 54.443724 -144.02234) (xy 54.433216 -144.05356) (xy 54.430168 -144.061942)
			(xy 54.430168 -144.823688) (xy 54.429593 -144.851629) (xy 54.420836 -144.90682) (xy 54.403566 -144.959967)
			(xy 54.378208 -145.009764) (xy 54.345384 -145.05499) (xy 54.326028 -145.075148) (xy 53.924708 -145.476722)
			(xy 53.924708 -147.569174) (xy 54.326028 -147.970748) (xy 54.345437 -147.990863) (xy 54.37829 -148.036084)
			(xy 54.403661 -148.085889) (xy 54.420925 -148.139051) (xy 54.429656 -148.19426) (xy 54.430168 -148.222208)
			(xy 54.430168 -152.76576) (xy 54.433216 -152.774142) (xy 54.443753 -152.805354) (xy 54.455113 -152.870239)
			(xy 54.455822 -152.903174) (xy 54.455078 -152.936106) (xy 54.44372 -153.000985) (xy 54.433216 -153.032206)
			(xy 54.430168 -153.040588) (xy 54.430168 -153.840688) (xy 54.429593 -153.868629) (xy 54.420836 -153.92382)
			(xy 54.403566 -153.976967) (xy 54.378208 -154.026764) (xy 54.345384 -154.07199) (xy 54.326028 -154.092148)
			(xy 54.000908 -154.417522) (xy 54.000908 -156.433774) (xy 54.326028 -156.759148) (xy 54.345437 -156.779263)
			(xy 54.37829 -156.824484) (xy 54.403661 -156.874289) (xy 54.420925 -156.927451) (xy 54.429656 -156.98266)
			(xy 54.430168 -157.010608) (xy 54.430168 -161.40176) (xy 54.433216 -161.410142) (xy 54.443753 -161.441354)
			(xy 54.455113 -161.506239) (xy 54.455822 -161.539174) (xy 54.455822 -161.539682) (xy 54.455359 -161.56589)
			(xy 54.448157 -161.617808) (xy 54.433912 -161.668252) (xy 54.412895 -161.716269) (xy 54.3855 -161.760957)
			(xy 54.369208 -161.78149) (xy 54.369208 -162.347148) (xy 54.368719 -162.372136) (xy 54.3609 -162.421495)
			(xy 54.345447 -162.469021) (xy 54.322741 -162.51354) (xy 54.293343 -162.553953) (xy 54.27599 -162.571938)
			(xy 53.99659 -162.851338) (xy 53.978592 -162.868672) (xy 53.938165 -162.89804) (xy 53.893647 -162.920733)
			(xy 53.846131 -162.936194) (xy 53.796784 -162.944045) (xy 53.7718 -162.944556) (xy 53.192172 -162.944556)
			(xy 52.413408 -163.72332) (xy 52.413408 -165.293548) (xy 52.412919 -165.318536) (xy 52.4051 -165.367895)
			(xy 52.389647 -165.415421) (xy 52.366941 -165.45994) (xy 52.337543 -165.500353) (xy 52.32019 -165.518338)
			(xy 50.686208 -167.15232) (xy 50.686208 -167.71747) (xy 50.99304 -167.71747) (xy 50.993427 -167.690214)
			(xy 51.001189 -167.636258) (xy 51.016552 -167.583956) (xy 51.039201 -167.534372) (xy 51.068677 -167.488517)
			(xy 51.104379 -167.447323) (xy 51.145579 -167.41163) (xy 51.191441 -167.382164) (xy 51.241029 -167.359524)
			(xy 51.293334 -167.344173) (xy 51.347292 -167.336422) (xy 51.374548 -167.335962) (xy 51.402122 -167.336442)
			(xy 51.456695 -167.344388) (xy 51.509556 -167.360109) (xy 51.559603 -167.383276) (xy 51.605792 -167.413408)
			(xy 51.647163 -167.449875) (xy 51.665378 -167.470582) (xy 51.675276 -167.48148) (xy 51.699926 -167.497555)
			(xy 51.728134 -167.505939) (xy 51.757562 -167.505939) (xy 51.78577 -167.497555) (xy 51.81042 -167.48148)
			(xy 51.820318 -167.470582) (xy 51.838512 -167.449855) (xy 51.879885 -167.413387) (xy 51.926079 -167.383257)
			(xy 51.97613 -167.360094) (xy 52.028995 -167.344381) (xy 52.083572 -167.336445) (xy 52.111148 -167.335962)
			(xy 52.137649 -167.336415) (xy 52.19014 -167.343762) (xy 52.241107 -167.358307) (xy 52.289569 -167.37977)
			(xy 52.334592 -167.407737) (xy 52.355242 -167.424354) (xy 52.367396 -167.433784) (xy 52.395794 -167.445573)
			(xy 52.426411 -167.448397) (xy 52.456486 -167.442003) (xy 52.483306 -167.426967) (xy 52.504451 -167.404645)
			(xy 52.511706 -167.39108) (xy 52.523817 -167.367395) (xy 52.553737 -167.323413) (xy 52.589605 -167.28413)
			(xy 52.630693 -167.250345) (xy 52.653184 -167.23614) (xy 52.665431 -167.228248) (xy 52.685104 -167.206769)
			(xy 52.697907 -167.180607) (xy 52.702796 -167.151894) (xy 52.699373 -167.122969) (xy 52.694078 -167.109394)
			(xy 52.684593 -167.086182) (xy 52.671241 -167.03785) (xy 52.664511 -166.988161) (xy 52.664106 -166.96309)
			(xy 52.66454 -166.938021) (xy 52.671286 -166.888338) (xy 52.684614 -166.840004) (xy 52.694078 -166.816786)
			(xy 52.699333 -166.803207) (xy 52.702713 -166.774299) (xy 52.697811 -166.74561) (xy 52.685024 -166.719464)
			(xy 52.665389 -166.69798) (xy 52.653184 -166.69004) (xy 52.630024 -166.675514) (xy 52.587899 -166.640668)
			(xy 52.551317 -166.600041) (xy 52.521063 -166.554506) (xy 52.497786 -166.505039) (xy 52.481986 -166.452703)
			(xy 52.474001 -166.398619) (xy 52.474003 -166.34395) (xy 52.481993 -166.289867) (xy 52.497797 -166.237532)
			(xy 52.521079 -166.188067) (xy 52.551336 -166.142534) (xy 52.587922 -166.101911) (xy 52.630049 -166.067068)
			(xy 52.653184 -166.0525) (xy 52.66539 -166.044551) (xy 52.685063 -166.023088) (xy 52.697871 -165.996941)
			(xy 52.702771 -165.968241) (xy 52.699363 -165.939326) (xy 52.694078 -165.925754) (xy 52.684581 -165.902547)
			(xy 52.671233 -165.854213) (xy 52.664508 -165.804522) (xy 52.664106 -165.77945) (xy 52.664627 -165.751565)
			(xy 52.672939 -165.696418) (xy 52.689377 -165.643126) (xy 52.713575 -165.59288) (xy 52.744991 -165.546801)
			(xy 52.782924 -165.505919) (xy 52.826526 -165.471147) (xy 52.874824 -165.443262) (xy 52.926739 -165.422887)
			(xy 52.98111 -165.410477) (xy 53.036724 -165.40631) (xy 53.092338 -165.410477) (xy 53.146709 -165.422887)
			(xy 53.198624 -165.443262) (xy 53.246922 -165.471147) (xy 53.290524 -165.505919) (xy 53.328457 -165.546801)
			(xy 53.359873 -165.59288) (xy 53.384071 -165.643126) (xy 53.400509 -165.696418) (xy 53.408821 -165.751565)
			(xy 53.409342 -165.77945) (xy 53.408875 -165.806782) (xy 53.400906 -165.860863) (xy 53.385118 -165.913198)
			(xy 53.36185 -165.962662) (xy 53.331601 -166.008195) (xy 53.295022 -166.048817) (xy 53.252897 -166.083655)
			(xy 53.229764 -166.09822) (xy 53.217537 -166.106138) (xy 53.19787 -166.127612) (xy 53.185068 -166.153767)
			(xy 53.180173 -166.182472) (xy 53.183584 -166.211392) (xy 53.18887 -166.224966) (xy 53.198345 -166.248181)
			(xy 53.211701 -166.296512) (xy 53.218435 -166.346199) (xy 53.218842 -166.37127) (xy 53.218431 -166.39634)
			(xy 53.211677 -166.446023) (xy 53.198339 -166.494357) (xy 53.18887 -166.517574) (xy 53.183624 -166.531151)
			(xy 53.180262 -166.560051) (xy 53.185173 -166.588729) (xy 53.197961 -166.614863) (xy 53.217591 -166.636338)
			(xy 53.229764 -166.64432) (xy 53.252885 -166.658903) (xy 53.295003 -166.693747) (xy 53.331579 -166.734369)
			(xy 53.361829 -166.779898) (xy 53.385103 -166.829358) (xy 53.400902 -166.881688) (xy 53.408888 -166.935764)
			(xy 53.408889 -166.990426) (xy 53.400905 -167.044502) (xy 53.385107 -167.096832) (xy 53.361834 -167.146292)
			(xy 53.331585 -167.191823) (xy 53.29501 -167.232446) (xy 53.252893 -167.267291) (xy 53.229764 -167.28186)
			(xy 53.217509 -167.289739) (xy 53.197842 -167.311225) (xy 53.185043 -167.33739) (xy 53.180156 -167.366104)
			(xy 53.183577 -167.39503) (xy 53.18887 -167.408606) (xy 53.198357 -167.431817) (xy 53.211708 -167.480149)
			(xy 53.218438 -167.529838) (xy 53.218842 -167.55491) (xy 53.21837 -167.581752) (xy 53.210665 -167.634881)
			(xy 53.195416 -167.686354) (xy 53.172938 -167.735106) (xy 53.143697 -167.780127) (xy 53.108298 -167.820487)
			(xy 53.067473 -167.855349) (xy 53.022069 -167.883993) (xy 52.973024 -167.905824) (xy 52.947316 -167.913558)
			(xy 52.932841 -167.918276) (xy 52.907286 -167.934788) (xy 52.887726 -167.958092) (xy 52.875894 -167.986122)
			(xy 52.87284 -168.016393) (xy 52.878835 -168.046222) (xy 52.885594 -168.059862) (xy 52.900228 -168.088008)
			(xy 52.920955 -168.147959) (xy 52.931453 -168.210517) (xy 52.932076 -168.242234) (xy 52.931855 -168.260253)
			(xy 52.928421 -168.296128) (xy 52.925218 -168.313862) (xy 52.922936 -168.329077) (xy 52.926453 -168.359622)
			(xy 52.938901 -168.387736) (xy 52.959153 -168.410871) (xy 52.985373 -168.426931) (xy 53.000148 -168.43121)
			(xy 53.027191 -168.438611) (xy 53.078917 -168.460241) (xy 53.126922 -168.489205) (xy 53.170174 -168.52488)
			(xy 53.207741 -168.566499) (xy 53.238815 -168.613165) (xy 53.262728 -168.663876) (xy 53.278965 -168.71754)
			(xy 53.287177 -168.773001) (xy 53.287676 -168.801034) (xy 53.287254 -168.828288) (xy 53.279492 -168.882239)
			(xy 53.264131 -168.934537) (xy 53.241483 -168.984117) (xy 53.21201 -169.029968) (xy 53.176312 -169.071159)
			(xy 53.135115 -169.10685) (xy 53.089259 -169.136315) (xy 53.039675 -169.158954) (xy 52.987375 -169.174306)
			(xy 52.933422 -169.182058) (xy 52.906168 -169.182542) (xy 52.878594 -169.18205) (xy 52.824022 -169.174105)
			(xy 52.771161 -169.158387) (xy 52.721115 -169.135222) (xy 52.674925 -169.105093) (xy 52.633554 -169.068628)
			(xy 52.615338 -169.047922) (xy 52.60544 -169.037024) (xy 52.58079 -169.020949) (xy 52.552582 -169.012565)
			(xy 52.523154 -169.012565) (xy 52.494946 -169.020949) (xy 52.470296 -169.037024) (xy 52.460398 -169.047922)
			(xy 52.442183 -169.068628) (xy 52.400812 -169.105093) (xy 52.354622 -169.13522) (xy 52.304575 -169.158383)
			(xy 52.251714 -169.174099) (xy 52.197142 -169.182039) (xy 52.141994 -169.182039) (xy 52.087422 -169.174099)
			(xy 52.034561 -169.158383) (xy 51.984514 -169.13522) (xy 51.938324 -169.105093) (xy 51.896953 -169.068628)
			(xy 51.878738 -169.047922) (xy 51.86884 -169.037024) (xy 51.84419 -169.020949) (xy 51.815982 -169.012565)
			(xy 51.786554 -169.012565) (xy 51.758346 -169.020949) (xy 51.733696 -169.037024) (xy 51.723798 -169.047922)
			(xy 51.705596 -169.068642) (xy 51.664225 -169.10511) (xy 51.618033 -169.135241) (xy 51.567983 -169.158405)
			(xy 51.515119 -169.17412) (xy 51.460543 -169.182058) (xy 51.432968 -169.182542) (xy 51.405718 -169.182052)
			(xy 51.351772 -169.174292) (xy 51.299479 -169.158935) (xy 51.249904 -169.136292) (xy 51.204055 -169.106826)
			(xy 51.162866 -169.071135) (xy 51.127175 -169.029946) (xy 51.097709 -168.984098) (xy 51.075066 -168.934523)
			(xy 51.059708 -168.88223) (xy 51.051948 -168.828284) (xy 51.05146 -168.801034) (xy 51.052043 -168.773181)
			(xy 51.060161 -168.71807) (xy 51.0762 -168.664722) (xy 51.09982 -168.614272) (xy 51.130519 -168.567788)
			(xy 51.167647 -168.526258) (xy 51.210414 -168.490563) (xy 51.257914 -168.461461) (xy 51.309138 -168.439569)
			(xy 51.33594 -168.431972) (xy 51.350063 -168.427719) (xy 51.375204 -168.41232) (xy 51.394916 -168.390396)
			(xy 51.407566 -168.363764) (xy 51.412104 -168.334632) (xy 51.410616 -168.319958) (xy 51.408945 -168.306942)
			(xy 51.407166 -168.280757) (xy 51.40706 -168.267634) (xy 51.407158 -168.253485) (xy 51.409189 -168.225262)
			(xy 51.411124 -168.211246) (xy 51.412683 -168.197896) (xy 51.409585 -168.171209) (xy 51.39962 -168.146259)
			(xy 51.38348 -168.124781) (xy 51.362288 -168.108267) (xy 51.337516 -168.097867) (xy 51.324256 -168.095676)
			(xy 51.297113 -168.09153) (xy 51.244287 -168.076561) (xy 51.194152 -168.054174) (xy 51.147744 -168.024832)
			(xy 51.106021 -167.989141) (xy 51.069844 -167.947838) (xy 51.039961 -167.901777) (xy 51.016989 -167.851907)
			(xy 51.001402 -167.79926) (xy 50.993522 -167.744923) (xy 50.99304 -167.71747) (xy 50.686208 -167.71747)
			(xy 50.686208 -168.722548) (xy 50.685719 -168.747536) (xy 50.6779 -168.796895) (xy 50.662447 -168.844421)
			(xy 50.639741 -168.88894) (xy 50.610343 -168.929353) (xy 50.59299 -168.947338) (xy 50.051208 -169.48912)
			(xy 50.051208 -169.645838) (xy 50.051694 -169.659503) (xy 50.058984 -169.685843) (xy 50.073004 -169.709304)
			(xy 50.092748 -169.728202) (xy 50.116799 -169.741182) (xy 50.143434 -169.747313) (xy 50.17074 -169.746155)
			(xy 50.196759 -169.73779) (xy 50.208434 -169.730674) (xy 50.231863 -169.715884) (xy 50.282108 -169.692531)
			(xy 50.335201 -169.676687) (xy 50.390027 -169.668682) (xy 50.41773 -169.66819) (xy 50.444982 -169.66865)
			(xy 50.49893 -169.67641) (xy 50.551226 -169.691769) (xy 50.600803 -169.714414) (xy 50.646653 -169.743883)
			(xy 50.687843 -169.779577) (xy 50.723534 -169.82077) (xy 50.753 -169.866622) (xy 50.775641 -169.916201)
			(xy 50.790996 -169.968497) (xy 50.798752 -170.022446) (xy 50.799238 -170.049698) (xy 50.798792 -170.077273)
			(xy 50.790838 -170.131847) (xy 50.775111 -170.184707) (xy 50.751938 -170.234752) (xy 50.721802 -170.280941)
			(xy 50.685331 -170.32231) (xy 50.643284 -170.357997) (xy 50.620168 -170.37304) (xy 50.608219 -170.381053)
			(xy 50.58903 -170.402473) (xy 50.576576 -170.428395) (xy 50.571846 -170.456762) (xy 50.575216 -170.485322)
			(xy 50.586418 -170.51181) (xy 50.599378 -170.527747) (xy 52.354526 -170.527747) (xy 52.354526 -170.473253)
			(xy 52.362281 -170.419314) (xy 52.377633 -170.367027) (xy 52.40027 -170.317458) (xy 52.429731 -170.271614)
			(xy 52.465416 -170.23043) (xy 52.506598 -170.194743) (xy 52.55244 -170.16528) (xy 52.602009 -170.14264)
			(xy 52.654294 -170.127285) (xy 52.708233 -170.119528) (xy 52.73548 -170.11904) (xy 52.765603 -170.119626)
			(xy 52.825098 -170.129104) (xy 52.882366 -170.147811) (xy 52.935983 -170.175284) (xy 52.984619 -170.210839)
			(xy 53.006244 -170.231816) (xy 53.015966 -170.241034) (xy 53.039128 -170.254479) (xy 53.064989 -170.261441)
			(xy 53.091771 -170.261441) (xy 53.117632 -170.254479) (xy 53.140794 -170.241034) (xy 53.150516 -170.231816)
			(xy 53.172113 -170.210806) (xy 53.220749 -170.175241) (xy 53.274373 -170.147766) (xy 53.331649 -170.129065)
			(xy 53.391154 -170.119603) (xy 53.42128 -170.11904) (xy 53.448537 -170.119406) (xy 53.502497 -170.127161)
			(xy 53.554804 -170.142517) (xy 53.604393 -170.165162) (xy 53.650254 -170.194633) (xy 53.691455 -170.230331)
			(xy 53.727155 -170.27153) (xy 53.756629 -170.317389) (xy 53.779276 -170.366977) (xy 53.794635 -170.419283)
			(xy 53.802393 -170.473243) (xy 53.802393 -170.527757) (xy 53.794635 -170.581717) (xy 53.779276 -170.634023)
			(xy 53.756629 -170.683611) (xy 53.727155 -170.72947) (xy 53.691455 -170.770669) (xy 53.650254 -170.806367)
			(xy 53.604393 -170.835838) (xy 53.554804 -170.858483) (xy 53.502497 -170.873839) (xy 53.448537 -170.881594)
			(xy 53.42128 -170.882056) (xy 53.391156 -170.881496) (xy 53.331659 -170.872012) (xy 53.274391 -170.853299)
			(xy 53.220775 -170.82582) (xy 53.172141 -170.79026) (xy 53.150516 -170.76928) (xy 53.140794 -170.760062)
			(xy 53.117632 -170.746617) (xy 53.091771 -170.739655) (xy 53.064989 -170.739655) (xy 53.039128 -170.746617)
			(xy 53.015966 -170.760062) (xy 53.006244 -170.76928) (xy 52.98462 -170.790261) (xy 52.935991 -170.82583)
			(xy 52.882375 -170.85331) (xy 52.825104 -170.872018) (xy 52.765604 -170.881488) (xy 52.73548 -170.882056)
			(xy 52.708233 -170.881472) (xy 52.654294 -170.873715) (xy 52.602009 -170.85836) (xy 52.55244 -170.83572)
			(xy 52.506598 -170.806257) (xy 52.465416 -170.77057) (xy 52.429731 -170.729386) (xy 52.40027 -170.683542)
			(xy 52.377633 -170.633973) (xy 52.362281 -170.581686) (xy 52.354526 -170.527747) (xy 50.599378 -170.527747)
			(xy 50.604562 -170.534121) (xy 50.616104 -170.542712) (xy 50.637453 -170.558059) (xy 50.676141 -170.593663)
			(xy 50.709571 -170.634245) (xy 50.737107 -170.679036) (xy 50.758228 -170.727185) (xy 50.772533 -170.777779)
			(xy 50.779751 -170.829859) (xy 50.780188 -170.856148) (xy 50.779767 -170.883401) (xy 50.772003 -170.937352)
			(xy 50.756641 -170.98965) (xy 50.733993 -171.039228) (xy 50.70452 -171.085079) (xy 50.668821 -171.12627)
			(xy 50.627625 -171.16196) (xy 50.581769 -171.191425) (xy 50.532186 -171.214065) (xy 50.479886 -171.229418)
			(xy 50.425933 -171.237172) (xy 50.39868 -171.237656) (xy 50.375388 -171.237275) (xy 50.329157 -171.231547)
			(xy 50.306478 -171.226226) (xy 50.300382 -171.224956) (xy 49.9364 -171.224956) (xy 49.91141 -171.224515)
			(xy 49.862048 -171.216687) (xy 49.814521 -171.201223) (xy 49.770003 -171.178506) (xy 49.729593 -171.149096)
			(xy 49.71161 -171.131738) (xy 49.50841 -170.928538) (xy 49.49109 -170.910527) (xy 49.461722 -170.870102)
			(xy 49.439028 -170.825588) (xy 49.423563 -170.778075) (xy 49.415707 -170.72873) (xy 49.415192 -170.703748)
			(xy 42.040048 -170.703748) (xy 42.040048 -170.775122) (xy 42.0395 -170.798883) (xy 42.030231 -170.845492)
			(xy 42.012034 -170.889391) (xy 41.985611 -170.92889) (xy 41.969182 -170.946064) (xy 40.570982 -172.344264)
			(xy 43.406818 -172.344264) (xy 43.406818 -172.259568) (xy 43.414869 -172.175254) (xy 43.430898 -172.092088)
			(xy 43.454759 -172.010821) (xy 43.486238 -171.932191) (xy 43.525049 -171.85691) (xy 43.570839 -171.785658)
			(xy 43.623195 -171.719082) (xy 43.681643 -171.657784) (xy 43.745653 -171.602319) (xy 43.814645 -171.55319)
			(xy 43.887995 -171.510841) (xy 43.965038 -171.475657) (xy 44.045077 -171.447955) (xy 44.127386 -171.427987)
			(xy 44.211221 -171.415934) (xy 44.295822 -171.411904) (xy 44.380423 -171.415934) (xy 44.464258 -171.427987)
			(xy 44.546567 -171.447955) (xy 44.626606 -171.475657) (xy 44.703649 -171.510841) (xy 44.776999 -171.55319)
			(xy 44.845991 -171.602319) (xy 44.910001 -171.657784) (xy 44.968449 -171.719082) (xy 45.020805 -171.785658)
			(xy 45.066595 -171.85691) (xy 45.105406 -171.932191) (xy 45.136885 -172.010821) (xy 45.160746 -172.092088)
			(xy 45.176775 -172.175254) (xy 45.184826 -172.259568) (xy 45.185173 -172.288752) (xy 48.725285 -172.288752)
			(xy 48.725285 -172.234248) (xy 48.733042 -172.180299) (xy 48.748399 -172.128003) (xy 48.771041 -172.078425)
			(xy 48.80051 -172.032574) (xy 48.836204 -171.991384) (xy 48.877396 -171.955693) (xy 48.923249 -171.926228)
			(xy 48.972829 -171.903589) (xy 49.025126 -171.888236) (xy 49.079076 -171.880483) (xy 49.106328 -171.880022)
			(xy 49.136703 -171.88062) (xy 49.196685 -171.89025) (xy 49.254384 -171.909263) (xy 49.308341 -171.937178)
			(xy 49.357193 -171.97329) (xy 49.37887 -171.994576) (xy 49.388621 -172.003887) (xy 49.411894 -172.017482)
			(xy 49.437911 -172.024524) (xy 49.464863 -172.024524) (xy 49.49088 -172.017482) (xy 49.514153 -172.003887)
			(xy 49.523904 -171.994576) (xy 49.54556 -171.973266) (xy 49.594415 -171.937152) (xy 49.648377 -171.909238)
			(xy 49.706081 -171.890229) (xy 49.766069 -171.880607) (xy 49.796446 -171.880022) (xy 49.823697 -171.880451)
			(xy 49.877644 -171.888213) (xy 49.929938 -171.903574) (xy 49.979513 -171.926219) (xy 50.025361 -171.955689)
			(xy 50.066549 -171.991383) (xy 50.102238 -172.032576) (xy 50.131703 -172.078428) (xy 50.133776 -172.082968)
			(xy 50.422554 -172.082968) (xy 50.426625 -172.027346) (xy 50.438751 -171.972909) (xy 50.458674 -171.920818)
			(xy 50.48597 -171.872183) (xy 50.520056 -171.82804) (xy 50.560205 -171.789331) (xy 50.605563 -171.75688)
			(xy 50.655163 -171.731379) (xy 50.707947 -171.713372) (xy 50.76279 -171.703242) (xy 50.818524 -171.701205)
			(xy 50.873961 -171.707305) (xy 50.927918 -171.721411) (xy 50.979247 -171.743223) (xy 51.026853 -171.772277)
			(xy 51.069721 -171.807952) (xy 51.106938 -171.849489) (xy 51.137711 -171.896002) (xy 51.161383 -171.946499)
			(xy 51.177451 -171.999906) (xy 51.185571 -172.055082) (xy 51.18608 -172.082968) (xy 51.185571 -172.110854)
			(xy 51.177451 -172.16603) (xy 51.161383 -172.219437) (xy 51.137711 -172.269934) (xy 51.106938 -172.316447)
			(xy 51.069721 -172.357984) (xy 51.026853 -172.393659) (xy 50.979247 -172.422713) (xy 50.927918 -172.444525)
			(xy 50.873961 -172.458631) (xy 50.818524 -172.464731) (xy 50.76279 -172.462694) (xy 50.707947 -172.452564)
			(xy 50.655163 -172.434557) (xy 50.605563 -172.409056) (xy 50.560205 -172.376605) (xy 50.520056 -172.337896)
			(xy 50.48597 -172.293753) (xy 50.458674 -172.245118) (xy 50.438751 -172.193027) (xy 50.426625 -172.13859)
			(xy 50.422554 -172.082968) (xy 50.133776 -172.082968) (xy 50.154342 -172.128006) (xy 50.169696 -172.180301)
			(xy 50.177452 -172.234249) (xy 50.177452 -172.288751) (xy 50.169696 -172.342699) (xy 50.154342 -172.394994)
			(xy 50.131703 -172.444572) (xy 50.102238 -172.490424) (xy 50.066549 -172.531617) (xy 50.025361 -172.567311)
			(xy 49.979513 -172.596781) (xy 49.929938 -172.619426) (xy 49.877644 -172.634787) (xy 49.823697 -172.642549)
			(xy 49.796446 -172.643038) (xy 49.76607 -172.642468) (xy 49.706086 -172.632833) (xy 49.648386 -172.613814)
			(xy 49.59443 -172.585893) (xy 49.545579 -172.549774) (xy 49.523904 -172.528484) (xy 49.514176 -172.519126)
			(xy 49.490915 -172.50545) (xy 49.464879 -172.498363) (xy 49.437895 -172.498363) (xy 49.411859 -172.50545)
			(xy 49.388598 -172.519126) (xy 49.37887 -172.528484) (xy 49.357174 -172.549751) (xy 49.30833 -172.585872)
			(xy 49.254379 -172.613795) (xy 49.196683 -172.632814) (xy 49.136703 -172.642447) (xy 49.106328 -172.643038)
			(xy 49.079076 -172.642517) (xy 49.025126 -172.634764) (xy 48.972829 -172.619411) (xy 48.923249 -172.596772)
			(xy 48.877396 -172.567307) (xy 48.836204 -172.531616) (xy 48.80051 -172.490426) (xy 48.771041 -172.444575)
			(xy 48.748399 -172.394997) (xy 48.733042 -172.342701) (xy 48.725285 -172.288752) (xy 45.185173 -172.288752)
			(xy 45.18533 -172.301916) (xy 45.184826 -172.344264) (xy 45.176775 -172.428578) (xy 45.160746 -172.511744)
			(xy 45.136885 -172.593011) (xy 45.105406 -172.671641) (xy 45.066595 -172.746922) (xy 45.020805 -172.818174)
			(xy 44.968449 -172.88475) (xy 44.910001 -172.946048) (xy 44.845991 -173.001513) (xy 44.776999 -173.050642)
			(xy 44.703649 -173.092991) (xy 44.626606 -173.128175) (xy 44.546567 -173.155877) (xy 44.464258 -173.175845)
			(xy 44.380423 -173.187898) (xy 44.295822 -173.191929) (xy 44.211221 -173.187898) (xy 44.127386 -173.175845)
			(xy 44.045077 -173.155877) (xy 43.965038 -173.128175) (xy 43.887995 -173.092991) (xy 43.814645 -173.050642)
			(xy 43.745653 -173.001513) (xy 43.681643 -172.946048) (xy 43.623195 -172.88475) (xy 43.570839 -172.818174)
			(xy 43.525049 -172.746922) (xy 43.486238 -172.671641) (xy 43.454759 -172.593011) (xy 43.430898 -172.511744)
			(xy 43.414869 -172.428578) (xy 43.406818 -172.344264) (xy 40.570982 -172.344264) (xy 40.247316 -172.66793)
			(xy 40.230164 -172.684383) (xy 40.190653 -172.710793) (xy 40.146748 -172.728983) (xy 40.100136 -172.738254)
			(xy 40.076374 -172.738796) (xy 28.93949 -172.738796) (xy 28.91573 -172.738227) (xy 28.869123 -172.728962)
			(xy 28.825224 -172.710771) (xy 28.785724 -172.684355) (xy 28.768548 -172.66793) (xy 27.958034 -171.857416)
			(xy 27.95143 -171.85386) (xy 27.935421 -171.844786) (xy 27.905968 -171.822727) (xy 27.892756 -171.809918)
			(xy 27.130502 -171.047664) (xy 27.113305 -171.029532) (xy 27.085556 -170.987981) (xy 27.066442 -170.941818)
			(xy 27.056694 -170.892814) (xy 27.05608 -170.867832) (xy 27.05608 -168.48582) (xy 27.02687 -168.472104)
			(xy 27.002652 -168.460218) (xy 26.95758 -168.430573) (xy 26.917132 -168.394877) (xy 26.882112 -168.35384)
			(xy 26.853221 -168.308282) (xy 26.831032 -168.259109) (xy 26.815988 -168.207301) (xy 26.808389 -168.153892)
			(xy 26.807922 -168.126918) (xy 19.433286 -168.126918) (xy 19.433286 -168.663874) (xy 19.969224 -168.663874)
			(xy 19.973295 -168.608252) (xy 19.985421 -168.553815) (xy 20.005344 -168.501724) (xy 20.03264 -168.453089)
			(xy 20.066726 -168.408946) (xy 20.106875 -168.370237) (xy 20.152233 -168.337786) (xy 20.201833 -168.312285)
			(xy 20.254617 -168.294278) (xy 20.30946 -168.284148) (xy 20.365194 -168.282111) (xy 20.420631 -168.288211)
			(xy 20.474588 -168.302317) (xy 20.525917 -168.324129) (xy 20.573523 -168.353183) (xy 20.616391 -168.388858)
			(xy 20.653608 -168.430395) (xy 20.684381 -168.476908) (xy 20.708053 -168.527405) (xy 20.724121 -168.580812)
			(xy 20.725168 -168.587928) (xy 24.769316 -168.587928) (xy 24.773387 -168.532306) (xy 24.785513 -168.477869)
			(xy 24.805436 -168.425778) (xy 24.832732 -168.377143) (xy 24.866818 -168.333) (xy 24.906967 -168.294291)
			(xy 24.952325 -168.26184) (xy 25.001925 -168.236339) (xy 25.054709 -168.218332) (xy 25.109552 -168.208202)
			(xy 25.165286 -168.206165) (xy 25.220723 -168.212265) (xy 25.27468 -168.226371) (xy 25.326009 -168.248183)
			(xy 25.373615 -168.277237) (xy 25.416483 -168.312912) (xy 25.4537 -168.354449) (xy 25.484473 -168.400962)
			(xy 25.508145 -168.451459) (xy 25.524213 -168.504866) (xy 25.532333 -168.560042) (xy 25.532842 -168.587928)
			(xy 25.532333 -168.615814) (xy 25.524213 -168.67099) (xy 25.508145 -168.724397) (xy 25.484473 -168.774894)
			(xy 25.4537 -168.821407) (xy 25.416483 -168.862944) (xy 25.373615 -168.898619) (xy 25.326009 -168.927673)
			(xy 25.27468 -168.949485) (xy 25.220723 -168.963591) (xy 25.165286 -168.969691) (xy 25.109552 -168.967654)
			(xy 25.054709 -168.957524) (xy 25.001925 -168.939517) (xy 24.952325 -168.914016) (xy 24.906967 -168.881565)
			(xy 24.866818 -168.842856) (xy 24.832732 -168.798713) (xy 24.805436 -168.750078) (xy 24.785513 -168.697987)
			(xy 24.773387 -168.64355) (xy 24.769316 -168.587928) (xy 20.725168 -168.587928) (xy 20.732241 -168.635988)
			(xy 20.73275 -168.663874) (xy 20.732241 -168.69176) (xy 20.724121 -168.746936) (xy 20.708053 -168.800343)
			(xy 20.684381 -168.85084) (xy 20.653608 -168.897353) (xy 20.616391 -168.93889) (xy 20.573523 -168.974565)
			(xy 20.525917 -169.003619) (xy 20.490399 -169.018712) (xy 20.763482 -169.018712) (xy 20.767553 -168.96309)
			(xy 20.779679 -168.908653) (xy 20.799602 -168.856562) (xy 20.826898 -168.807927) (xy 20.860984 -168.763784)
			(xy 20.901133 -168.725075) (xy 20.946491 -168.692624) (xy 20.996091 -168.667123) (xy 21.048875 -168.649116)
			(xy 21.103718 -168.638986) (xy 21.159452 -168.636949) (xy 21.214889 -168.643049) (xy 21.268846 -168.657155)
			(xy 21.320175 -168.678967) (xy 21.367781 -168.708021) (xy 21.410649 -168.743696) (xy 21.447866 -168.785233)
			(xy 21.478639 -168.831746) (xy 21.502311 -168.882243) (xy 21.518379 -168.93565) (xy 21.526499 -168.990826)
			(xy 21.527008 -169.018712) (xy 21.526499 -169.046598) (xy 21.518379 -169.101774) (xy 21.502311 -169.155181)
			(xy 21.478639 -169.205678) (xy 21.447866 -169.252191) (xy 21.410649 -169.293728) (xy 21.367781 -169.329403)
			(xy 21.320175 -169.358457) (xy 21.268846 -169.380269) (xy 21.214889 -169.394375) (xy 21.159452 -169.400475)
			(xy 21.103718 -169.398438) (xy 21.048875 -169.388308) (xy 20.996091 -169.370301) (xy 20.946491 -169.3448)
			(xy 20.901133 -169.312349) (xy 20.860984 -169.27364) (xy 20.826898 -169.229497) (xy 20.799602 -169.180862)
			(xy 20.779679 -169.128771) (xy 20.767553 -169.074334) (xy 20.763482 -169.018712) (xy 20.490399 -169.018712)
			(xy 20.474588 -169.025431) (xy 20.420631 -169.039537) (xy 20.365194 -169.045637) (xy 20.30946 -169.0436)
			(xy 20.254617 -169.03347) (xy 20.201833 -169.015463) (xy 20.152233 -168.989962) (xy 20.106875 -168.957511)
			(xy 20.066726 -168.918802) (xy 20.03264 -168.874659) (xy 20.005344 -168.826024) (xy 19.985421 -168.773933)
			(xy 19.973295 -168.719496) (xy 19.969224 -168.663874) (xy 19.433286 -168.663874) (xy 19.433286 -169.654982)
			(xy 19.972272 -169.654982) (xy 19.976343 -169.59936) (xy 19.988469 -169.544923) (xy 20.008392 -169.492832)
			(xy 20.035688 -169.444197) (xy 20.069774 -169.400054) (xy 20.109923 -169.361345) (xy 20.155281 -169.328894)
			(xy 20.204881 -169.303393) (xy 20.257665 -169.285386) (xy 20.312508 -169.275256) (xy 20.368242 -169.273219)
			(xy 20.423679 -169.279319) (xy 20.477636 -169.293425) (xy 20.528965 -169.315237) (xy 20.576571 -169.344291)
			(xy 20.619439 -169.379966) (xy 20.656656 -169.421503) (xy 20.687429 -169.468016) (xy 20.711101 -169.518513)
			(xy 20.727169 -169.57192) (xy 20.735289 -169.627096) (xy 20.735798 -169.654982) (xy 20.735289 -169.682868)
			(xy 20.727169 -169.738044) (xy 20.711101 -169.791451) (xy 20.687429 -169.841948) (xy 20.681898 -169.850308)
			(xy 21.073362 -169.850308) (xy 21.077433 -169.794686) (xy 21.089559 -169.740249) (xy 21.109482 -169.688158)
			(xy 21.136778 -169.639523) (xy 21.170864 -169.59538) (xy 21.211013 -169.556671) (xy 21.256371 -169.52422)
			(xy 21.305971 -169.498719) (xy 21.358755 -169.480712) (xy 21.413598 -169.470582) (xy 21.469332 -169.468545)
			(xy 21.524769 -169.474645) (xy 21.572365 -169.487088) (xy 25.88082 -169.487088) (xy 25.884891 -169.431466)
			(xy 25.897017 -169.377029) (xy 25.91694 -169.324938) (xy 25.944236 -169.276303) (xy 25.978322 -169.23216)
			(xy 26.018471 -169.193451) (xy 26.063829 -169.161) (xy 26.113429 -169.135499) (xy 26.166213 -169.117492)
			(xy 26.221056 -169.107362) (xy 26.27679 -169.105325) (xy 26.332227 -169.111425) (xy 26.386184 -169.125531)
			(xy 26.437513 -169.147343) (xy 26.485119 -169.176397) (xy 26.527987 -169.212072) (xy 26.565204 -169.253609)
			(xy 26.595977 -169.300122) (xy 26.619649 -169.350619) (xy 26.635717 -169.404026) (xy 26.643837 -169.459202)
			(xy 26.644346 -169.487088) (xy 26.643837 -169.514974) (xy 26.635717 -169.57015) (xy 26.619649 -169.623557)
			(xy 26.595977 -169.674054) (xy 26.565204 -169.720567) (xy 26.527987 -169.762104) (xy 26.485119 -169.797779)
			(xy 26.437513 -169.826833) (xy 26.386184 -169.848645) (xy 26.332227 -169.862751) (xy 26.27679 -169.868851)
			(xy 26.221056 -169.866814) (xy 26.166213 -169.856684) (xy 26.113429 -169.838677) (xy 26.063829 -169.813176)
			(xy 26.018471 -169.780725) (xy 25.978322 -169.742016) (xy 25.944236 -169.697873) (xy 25.91694 -169.649238)
			(xy 25.897017 -169.597147) (xy 25.884891 -169.54271) (xy 25.88082 -169.487088) (xy 21.572365 -169.487088)
			(xy 21.578726 -169.488751) (xy 21.630055 -169.510563) (xy 21.677661 -169.539617) (xy 21.720529 -169.575292)
			(xy 21.757746 -169.616829) (xy 21.788519 -169.663342) (xy 21.812191 -169.713839) (xy 21.828259 -169.767246)
			(xy 21.836379 -169.822422) (xy 21.836888 -169.850308) (xy 21.836379 -169.878194) (xy 21.828259 -169.93337)
			(xy 21.812191 -169.986777) (xy 21.788519 -170.037274) (xy 21.757746 -170.083787) (xy 21.720529 -170.125324)
			(xy 21.677661 -170.160999) (xy 21.630055 -170.190053) (xy 21.578726 -170.211865) (xy 21.524769 -170.225971)
			(xy 21.469332 -170.232071) (xy 21.413598 -170.230034) (xy 21.358755 -170.219904) (xy 21.305971 -170.201897)
			(xy 21.256371 -170.176396) (xy 21.211013 -170.143945) (xy 21.170864 -170.105236) (xy 21.136778 -170.061093)
			(xy 21.109482 -170.012458) (xy 21.089559 -169.960367) (xy 21.077433 -169.90593) (xy 21.073362 -169.850308)
			(xy 20.681898 -169.850308) (xy 20.656656 -169.888461) (xy 20.619439 -169.929998) (xy 20.576571 -169.965673)
			(xy 20.528965 -169.994727) (xy 20.477636 -170.016539) (xy 20.423679 -170.030645) (xy 20.368242 -170.036745)
			(xy 20.312508 -170.034708) (xy 20.257665 -170.024578) (xy 20.204881 -170.006571) (xy 20.155281 -169.98107)
			(xy 20.109923 -169.948619) (xy 20.069774 -169.90991) (xy 20.035688 -169.865767) (xy 20.008392 -169.817132)
			(xy 19.988469 -169.765041) (xy 19.976343 -169.710604) (xy 19.972272 -169.654982) (xy 19.433286 -169.654982)
			(xy 19.433286 -174.79264) (xy 21.571964 -174.79264) (xy 21.576035 -174.737018) (xy 21.588161 -174.682581)
			(xy 21.608084 -174.63049) (xy 21.63538 -174.581855) (xy 21.669466 -174.537712) (xy 21.709615 -174.499003)
			(xy 21.754973 -174.466552) (xy 21.804573 -174.441051) (xy 21.857357 -174.423044) (xy 21.9122 -174.412914)
			(xy 21.967934 -174.410877) (xy 22.023371 -174.416977) (xy 22.077328 -174.431083) (xy 22.128657 -174.452895)
			(xy 22.176263 -174.481949) (xy 22.219131 -174.517624) (xy 22.256348 -174.559161) (xy 22.287121 -174.605674)
			(xy 22.310793 -174.656171) (xy 22.326861 -174.709578) (xy 22.334981 -174.764754) (xy 22.33549 -174.79264)
			(xy 22.334981 -174.820526) (xy 22.326861 -174.875702) (xy 22.314406 -174.9171) (xy 25.556462 -174.9171)
			(xy 25.560533 -174.861478) (xy 25.572659 -174.807041) (xy 25.592582 -174.75495) (xy 25.619878 -174.706315)
			(xy 25.653964 -174.662172) (xy 25.694113 -174.623463) (xy 25.739471 -174.591012) (xy 25.789071 -174.565511)
			(xy 25.841855 -174.547504) (xy 25.896698 -174.537374) (xy 25.952432 -174.535337) (xy 26.007869 -174.541437)
			(xy 26.061826 -174.555543) (xy 26.113155 -174.577355) (xy 26.160761 -174.606409) (xy 26.203629 -174.642084)
			(xy 26.240846 -174.683621) (xy 26.271619 -174.730134) (xy 26.295291 -174.780631) (xy 26.311359 -174.834038)
			(xy 26.319479 -174.889214) (xy 26.319988 -174.9171) (xy 26.319479 -174.944986) (xy 26.311359 -175.000162)
			(xy 26.295291 -175.053569) (xy 26.271619 -175.104066) (xy 26.240846 -175.150579) (xy 26.203629 -175.192116)
			(xy 26.160761 -175.227791) (xy 26.113155 -175.256845) (xy 26.061826 -175.278657) (xy 26.007869 -175.292763)
			(xy 25.952432 -175.298863) (xy 25.896698 -175.296826) (xy 25.841855 -175.286696) (xy 25.789071 -175.268689)
			(xy 25.739471 -175.243188) (xy 25.694113 -175.210737) (xy 25.653964 -175.172028) (xy 25.619878 -175.127885)
			(xy 25.592582 -175.07925) (xy 25.572659 -175.027159) (xy 25.560533 -174.972722) (xy 25.556462 -174.9171)
			(xy 22.314406 -174.9171) (xy 22.310793 -174.929109) (xy 22.287121 -174.979606) (xy 22.256348 -175.026119)
			(xy 22.219131 -175.067656) (xy 22.176263 -175.103331) (xy 22.128657 -175.132385) (xy 22.077328 -175.154197)
			(xy 22.023371 -175.168303) (xy 21.967934 -175.174403) (xy 21.9122 -175.172366) (xy 21.857357 -175.162236)
			(xy 21.804573 -175.144229) (xy 21.754973 -175.118728) (xy 21.709615 -175.086277) (xy 21.669466 -175.047568)
			(xy 21.63538 -175.003425) (xy 21.608084 -174.95479) (xy 21.588161 -174.902699) (xy 21.576035 -174.848262)
			(xy 21.571964 -174.79264) (xy 19.433286 -174.79264) (xy 19.433286 -175.210216) (xy 20.264372 -175.210216)
			(xy 20.268443 -175.154594) (xy 20.280569 -175.100157) (xy 20.300492 -175.048066) (xy 20.327788 -174.999431)
			(xy 20.361874 -174.955288) (xy 20.402023 -174.916579) (xy 20.447381 -174.884128) (xy 20.496981 -174.858627)
			(xy 20.549765 -174.84062) (xy 20.604608 -174.83049) (xy 20.660342 -174.828453) (xy 20.715779 -174.834553)
			(xy 20.769736 -174.848659) (xy 20.821065 -174.870471) (xy 20.868671 -174.899525) (xy 20.911539 -174.9352)
			(xy 20.948756 -174.976737) (xy 20.979529 -175.02325) (xy 21.003201 -175.073747) (xy 21.019269 -175.127154)
			(xy 21.027389 -175.18233) (xy 21.027898 -175.210216) (xy 21.027389 -175.238102) (xy 21.019269 -175.293278)
			(xy 21.003201 -175.346685) (xy 20.979529 -175.397182) (xy 20.948756 -175.443695) (xy 20.911539 -175.485232)
			(xy 20.868671 -175.520907) (xy 20.821065 -175.549961) (xy 20.769736 -175.571773) (xy 20.715779 -175.585879)
			(xy 20.660342 -175.591979) (xy 20.604608 -175.589942) (xy 20.549765 -175.579812) (xy 20.496981 -175.561805)
			(xy 20.447381 -175.536304) (xy 20.402023 -175.503853) (xy 20.361874 -175.465144) (xy 20.327788 -175.421001)
			(xy 20.300492 -175.372366) (xy 20.280569 -175.320275) (xy 20.268443 -175.265838) (xy 20.264372 -175.210216)
			(xy 19.433286 -175.210216) (xy 19.433286 -177.191416) (xy 20.962872 -177.191416) (xy 20.966943 -177.135794)
			(xy 20.979069 -177.081357) (xy 20.998992 -177.029266) (xy 21.026288 -176.980631) (xy 21.060374 -176.936488)
			(xy 21.100523 -176.897779) (xy 21.145881 -176.865328) (xy 21.195481 -176.839827) (xy 21.248265 -176.82182)
			(xy 21.303108 -176.81169) (xy 21.358842 -176.809653) (xy 21.414279 -176.815753) (xy 21.468236 -176.829859)
			(xy 21.519565 -176.851671) (xy 21.567171 -176.880725) (xy 21.610039 -176.9164) (xy 21.647256 -176.957937)
			(xy 21.678029 -177.00445) (xy 21.701701 -177.054947) (xy 21.717769 -177.108354) (xy 21.725889 -177.16353)
			(xy 21.726398 -177.191416) (xy 21.725889 -177.219302) (xy 21.717769 -177.274478) (xy 21.701701 -177.327885)
			(xy 21.678029 -177.378382) (xy 21.647256 -177.424895) (xy 21.610039 -177.466432) (xy 21.567171 -177.502107)
			(xy 21.519565 -177.531161) (xy 21.468236 -177.552973) (xy 21.414279 -177.567079) (xy 21.358842 -177.573179)
			(xy 21.303108 -177.571142) (xy 21.248265 -177.561012) (xy 21.195481 -177.543005) (xy 21.145881 -177.517504)
			(xy 21.100523 -177.485053) (xy 21.060374 -177.446344) (xy 21.026288 -177.402201) (xy 20.998992 -177.353566)
			(xy 20.979069 -177.301475) (xy 20.966943 -177.247038) (xy 20.962872 -177.191416) (xy 19.433286 -177.191416)
			(xy 19.433286 -177.25136) (xy 19.473164 -177.26025) (xy 19.499236 -177.266485) (xy 19.54927 -177.285723)
			(xy 19.595856 -177.312241) (xy 19.637942 -177.345442) (xy 19.674577 -177.384574) (xy 19.704935 -177.428754)
			(xy 19.728329 -177.476985) (xy 19.744231 -177.528177) (xy 19.752283 -177.581174) (xy 19.752818 -177.607976)
			(xy 19.752424 -177.631772) (xy 19.746096 -177.678942) (xy 19.733547 -177.724851) (xy 19.724624 -177.746914)
			(xy 19.720137 -177.760373) (xy 19.717981 -177.788651) (xy 19.723685 -177.816431) (xy 19.736809 -177.841572)
			(xy 19.756341 -177.862133) (xy 19.780775 -177.876531) (xy 19.808226 -177.883653) (xy 19.822414 -177.88382)
			(xy 19.83232 -177.88382) (xy 19.859568 -177.884308) (xy 19.91351 -177.892066) (xy 19.965798 -177.907422)
			(xy 20.015369 -177.930062) (xy 20.061214 -177.959527) (xy 20.102399 -177.995216) (xy 20.138085 -178.036402)
			(xy 20.167547 -178.082248) (xy 20.190185 -178.13182) (xy 20.205538 -178.18411) (xy 20.213294 -178.238052)
			(xy 20.213294 -178.292548) (xy 20.205538 -178.34649) (xy 20.190185 -178.39878) (xy 20.167547 -178.448352)
			(xy 20.138085 -178.494198) (xy 20.102399 -178.535384) (xy 20.061214 -178.571073) (xy 20.015369 -178.600538)
			(xy 19.965798 -178.623178) (xy 19.91351 -178.638534) (xy 19.859568 -178.646292) (xy 19.83232 -178.646836)
			(xy 19.8247 -178.646836) (xy 19.793815 -178.645617) (xy 19.733028 -178.634437) (xy 19.674835 -178.613614)
			(xy 19.620754 -178.583691) (xy 19.5961 -178.565048) (xy 19.584571 -178.556915) (xy 19.558272 -178.546727)
			(xy 19.530189 -178.544125) (xy 19.502466 -178.549305) (xy 19.477218 -178.561874) (xy 19.456373 -178.580872)
			(xy 19.441522 -178.604848) (xy 19.433798 -178.631973) (xy 19.433286 -178.646074) (xy 19.433286 -179.105814)
			(xy 20.700998 -179.105814) (xy 20.705069 -179.050192) (xy 20.717195 -178.995755) (xy 20.737118 -178.943664)
			(xy 20.764414 -178.895029) (xy 20.7985 -178.850886) (xy 20.838649 -178.812177) (xy 20.884007 -178.779726)
			(xy 20.933607 -178.754225) (xy 20.986391 -178.736218) (xy 21.041234 -178.726088) (xy 21.096968 -178.724051)
			(xy 21.152405 -178.730151) (xy 21.206362 -178.744257) (xy 21.257691 -178.766069) (xy 21.305297 -178.795123)
			(xy 21.348165 -178.830798) (xy 21.385382 -178.872335) (xy 21.416155 -178.918848) (xy 21.439827 -178.969345)
			(xy 21.455895 -179.022752) (xy 21.464015 -179.077928) (xy 21.464524 -179.105814) (xy 21.464015 -179.1337)
			(xy 21.455895 -179.188876) (xy 21.439827 -179.242283) (xy 21.416155 -179.29278) (xy 21.385382 -179.339293)
			(xy 21.348165 -179.38083) (xy 21.305297 -179.416505) (xy 21.257691 -179.445559) (xy 21.206362 -179.467371)
			(xy 21.152405 -179.481477) (xy 21.096968 -179.487577) (xy 21.041234 -179.48554) (xy 20.986391 -179.47541)
			(xy 20.933607 -179.457403) (xy 20.884007 -179.431902) (xy 20.838649 -179.399451) (xy 20.7985 -179.360742)
			(xy 20.764414 -179.316599) (xy 20.737118 -179.267964) (xy 20.717195 -179.215873) (xy 20.705069 -179.161436)
			(xy 20.700998 -179.105814) (xy 19.433286 -179.105814) (xy 19.433286 -181.101492) (xy 20.360386 -182.028592)
			(xy 20.369276 -182.032402) (xy 20.393621 -182.043506) (xy 20.438952 -182.071932) (xy 20.479522 -182.106818)
			(xy 20.514418 -182.14738) (xy 20.542855 -182.192704) (xy 20.553934 -182.21706) (xy 20.557744 -182.22595)
			(xy 21.427186 -183.095392) (xy 21.458936 -183.081168) (xy 21.48346 -183.070723) (xy 21.534694 -183.056013)
			(xy 21.587478 -183.04858) (xy 21.61413 -183.048148) (xy 21.641381 -183.048636) (xy 21.695328 -183.056396)
			(xy 21.747621 -183.071753) (xy 21.797198 -183.094395) (xy 21.843048 -183.123861) (xy 21.884238 -183.159552)
			(xy 21.91993 -183.200741) (xy 21.94462 -183.239156) (xy 22.886922 -183.239156) (xy 22.890993 -183.183534)
			(xy 22.903119 -183.129097) (xy 22.923042 -183.077006) (xy 22.950338 -183.028371) (xy 22.984424 -182.984228)
			(xy 23.024573 -182.945519) (xy 23.069931 -182.913068) (xy 23.119531 -182.887567) (xy 23.172315 -182.86956)
			(xy 23.227158 -182.85943) (xy 23.282892 -182.857393) (xy 23.338329 -182.863493) (xy 23.392286 -182.877599)
			(xy 23.443615 -182.899411) (xy 23.491221 -182.928465) (xy 23.534089 -182.96414) (xy 23.571306 -183.005677)
			(xy 23.602079 -183.05219) (xy 23.625751 -183.102687) (xy 23.641819 -183.156094) (xy 23.649939 -183.21127)
			(xy 23.650448 -183.239156) (xy 23.649939 -183.267042) (xy 23.641819 -183.322218) (xy 23.625751 -183.375625)
			(xy 23.602079 -183.426122) (xy 23.571306 -183.472635) (xy 23.534089 -183.514172) (xy 23.491221 -183.549847)
			(xy 23.443615 -183.578901) (xy 23.392286 -183.600713) (xy 23.338329 -183.614819) (xy 23.282892 -183.620919)
			(xy 23.227158 -183.618882) (xy 23.172315 -183.608752) (xy 23.119531 -183.590745) (xy 23.069931 -183.565244)
			(xy 23.024573 -183.532793) (xy 22.984424 -183.494084) (xy 22.950338 -183.449941) (xy 22.923042 -183.401306)
			(xy 22.903119 -183.349215) (xy 22.890993 -183.294778) (xy 22.886922 -183.239156) (xy 21.94462 -183.239156)
			(xy 21.949398 -183.24659) (xy 21.972042 -183.296165) (xy 21.987401 -183.348458) (xy 21.995163 -183.402405)
			(xy 21.995638 -183.429656) (xy 21.995196 -183.456308) (xy 21.987777 -183.509094) (xy 21.973077 -183.560332)
			(xy 21.962618 -183.58485) (xy 21.948394 -183.6166) (xy 22.651212 -184.319418)
		)
		(stroke
			(width 0)
			(type solid)
		)
		(fill yes)
		(layer "In6.Cu")
		(net "GND")
	)
	(gr_poly
		(pts
			(xy 104.411526 -236.0295) (xy 104.411526 -235.277152) (xy 104.392179 -235.261383) (xy 104.358001 -235.225011)
			(xy 104.329678 -235.183915) (xy 104.307854 -235.139029) (xy 104.293024 -235.091372) (xy 104.285526 -235.042028)
			(xy 104.285531 -234.992118) (xy 104.293036 -234.942775) (xy 104.307874 -234.89512) (xy 104.329705 -234.850238)
			(xy 104.358035 -234.809147) (xy 104.392219 -234.77278) (xy 104.411526 -234.75696) (xy 104.411526 -234.545378)
			(xy 104.411074 -234.530664) (xy 104.402759 -234.502437) (xy 104.386739 -234.477754) (xy 104.364344 -234.458665)
			(xy 104.337436 -234.446755) (xy 104.308248 -234.443015) (xy 104.279206 -234.447755) (xy 104.26573 -234.453684)
			(xy 104.243209 -234.464096) (xy 104.195824 -234.478798) (xy 104.146773 -234.486245) (xy 104.121966 -234.486704)
			(xy 104.095997 -234.486192) (xy 104.044698 -234.478062) (xy 103.995302 -234.462008) (xy 103.949026 -234.438425)
			(xy 103.907009 -234.407894) (xy 103.870284 -234.371165) (xy 103.839757 -234.329145) (xy 103.816179 -234.282866)
			(xy 103.80013 -234.233469) (xy 103.792005 -234.182169) (xy 103.792005 -234.130231) (xy 103.80013 -234.078931)
			(xy 103.816179 -234.029534) (xy 103.839757 -233.983255) (xy 103.870284 -233.941235) (xy 103.907009 -233.904506)
			(xy 103.949026 -233.873975) (xy 103.995302 -233.850392) (xy 104.044698 -233.834338) (xy 104.095997 -233.826208)
			(xy 104.121966 -233.825796) (xy 104.146772 -233.82626) (xy 104.195823 -233.833711) (xy 104.24321 -233.848405)
			(xy 104.26573 -233.858816) (xy 104.279191 -233.864768) (xy 104.308231 -233.869478) (xy 104.337409 -233.86572)
			(xy 104.364307 -233.853804) (xy 104.386697 -233.83472) (xy 104.402721 -233.810048) (xy 104.411053 -233.781833)
			(xy 104.411526 -233.767122) (xy 104.411526 -233.61904) (xy 104.390623 -233.604848) (xy 104.352986 -233.571147)
			(xy 104.320917 -233.532108) (xy 104.295166 -233.488642) (xy 104.276331 -233.441763) (xy 104.264852 -233.392563)
			(xy 104.260997 -233.342189) (xy 104.264856 -233.291815) (xy 104.276338 -233.242616) (xy 104.295175 -233.195738)
			(xy 104.32093 -233.152274) (xy 104.353001 -233.113238) (xy 104.390641 -233.079538) (xy 104.411526 -233.06532)
			(xy 104.411526 -232.917492) (xy 104.411076 -232.902776) (xy 104.402763 -232.874546) (xy 104.386743 -232.849859)
			(xy 104.364348 -232.830767) (xy 104.337437 -232.818856) (xy 104.308246 -232.815115) (xy 104.279202 -232.819856)
			(xy 104.26573 -232.825798) (xy 104.243209 -232.836209) (xy 104.195824 -232.850911) (xy 104.146773 -232.858358)
			(xy 104.121966 -232.858818) (xy 104.096003 -232.858306) (xy 104.044718 -232.850179) (xy 103.995335 -232.834129)
			(xy 103.949071 -232.810552) (xy 103.907065 -232.780028) (xy 103.87035 -232.74331) (xy 103.83983 -232.7013)
			(xy 103.816258 -232.655033) (xy 103.800213 -232.605649) (xy 103.792091 -232.554363) (xy 103.792091 -232.502437)
			(xy 103.800213 -232.451151) (xy 103.816258 -232.401767) (xy 103.83983 -232.3555) (xy 103.87035 -232.31349)
			(xy 103.907065 -232.276772) (xy 103.949071 -232.246248) (xy 103.995335 -232.222671) (xy 104.044718 -232.206621)
			(xy 104.096003 -232.198494) (xy 104.121966 -232.19791) (xy 104.146772 -232.198374) (xy 104.195822 -232.205825)
			(xy 104.243209 -232.22052) (xy 104.26573 -232.23093) (xy 104.279191 -232.236882) (xy 104.308232 -232.241591)
			(xy 104.337411 -232.237832) (xy 104.364311 -232.225917) (xy 104.386702 -232.206833) (xy 104.402729 -232.182162)
			(xy 104.411064 -232.153947) (xy 104.411526 -232.139236) (xy 104.411526 -231.991662) (xy 104.388834 -231.976279)
			(xy 104.348423 -231.939239) (xy 104.314679 -231.896037) (xy 104.288529 -231.847859) (xy 104.27069 -231.796025)
			(xy 104.26165 -231.741957) (xy 104.261158 -231.714548) (xy 104.261617 -231.689198) (xy 104.269358 -231.639091)
			(xy 104.284667 -231.590757) (xy 104.307184 -231.54533) (xy 104.336378 -231.503879) (xy 104.371566 -231.467376)
			(xy 104.39146 -231.451658) (xy 104.411526 -231.436418) (xy 104.411526 -231.42702) (xy 104.773222 -231.065324)
			(xy 104.759252 -231.033574) (xy 104.750404 -231.012514) (xy 104.737948 -230.968566) (xy 104.731682 -230.923318)
			(xy 104.731312 -230.900478) (xy 104.731856 -230.873307) (xy 104.740733 -230.819696) (xy 104.758261 -230.768259)
			(xy 104.783967 -230.720383) (xy 104.800146 -230.698548) (xy 104.800146 -229.93096) (xy 104.367838 -229.498652)
			(xy 104.332024 -229.527862) (xy 104.309673 -229.545522) (xy 104.260165 -229.573692) (xy 104.20656 -229.592952)
			(xy 104.150446 -229.602733) (xy 104.121966 -229.6033) (xy 104.094965 -229.602768) (xy 104.041681 -229.593994)
			(xy 103.990534 -229.57667) (xy 103.942886 -229.551256) (xy 103.900007 -229.51843) (xy 103.863039 -229.479066)
			(xy 103.832967 -229.434213) (xy 103.810591 -229.385066) (xy 103.796507 -229.332933) (xy 103.79329 -229.30612)
			(xy 103.791264 -229.291278) (xy 103.779758 -229.263637) (xy 103.760733 -229.240517) (xy 103.735824 -229.223905)
			(xy 103.707168 -229.215227) (xy 103.692198 -229.21468) (xy 103.611934 -229.21468) (xy 103.596958 -229.215204)
			(xy 103.56829 -229.223878) (xy 103.543368 -229.240492) (xy 103.524332 -229.263617) (xy 103.512819 -229.291267)
			(xy 103.510842 -229.30612) (xy 103.507587 -229.332925) (xy 103.493486 -229.385044) (xy 103.471101 -229.434178)
			(xy 103.441027 -229.479021) (xy 103.404065 -229.518379) (xy 103.361198 -229.551207) (xy 103.313565 -229.57663)
			(xy 103.262433 -229.593974) (xy 103.209162 -229.602776) (xy 103.182166 -229.6033) (xy 103.157115 -229.602835)
			(xy 103.107587 -229.595267) (xy 103.059768 -229.58031) (xy 103.014756 -229.558307) (xy 102.97358 -229.529762)
			(xy 102.937184 -229.495329) (xy 102.906403 -229.455797) (xy 102.881941 -229.412071) (xy 102.864359 -229.365155)
			(xy 102.854061 -229.316122) (xy 102.85222 -229.291134) (xy 102.851026 -229.277949) (xy 102.842754 -229.252812)
			(xy 102.828313 -229.230636) (xy 102.808668 -229.212905) (xy 102.785133 -229.200804) (xy 102.759282 -229.195143)
			(xy 102.746048 -229.195376) (xy 102.729164 -229.196056) (xy 102.695368 -229.196056) (xy 102.678484 -229.195376)
			(xy 102.665234 -229.195152) (xy 102.639335 -229.200721) (xy 102.61575 -229.212785) (xy 102.596078 -229.230526)
			(xy 102.581649 -229.252743) (xy 102.573443 -229.27793) (xy 102.572312 -229.291134) (xy 102.570459 -229.316118)
			(xy 102.560161 -229.365145) (xy 102.542579 -229.412056) (xy 102.518117 -229.455775) (xy 102.487335 -229.4953)
			(xy 102.45094 -229.529725) (xy 102.409765 -229.558262) (xy 102.364754 -229.580256) (xy 102.316938 -229.595203)
			(xy 102.267415 -229.60276) (xy 102.242366 -229.6033) (xy 102.216399 -229.602788) (xy 102.165106 -229.59466)
			(xy 102.115715 -229.578609) (xy 102.069442 -229.55503) (xy 102.027427 -229.524504) (xy 101.990704 -229.487782)
			(xy 101.960176 -229.445768) (xy 101.936596 -229.399496) (xy 101.920543 -229.350106) (xy 101.912413 -229.298813)
			(xy 101.911912 -229.272846) (xy 101.912479 -229.24552) (xy 101.921477 -229.191614) (xy 101.939218 -229.139922)
			(xy 101.965219 -229.091851) (xy 101.998772 -229.048712) (xy 102.038964 -229.011679) (xy 102.061518 -228.99624)
			(xy 102.072365 -228.988655) (xy 102.090053 -228.968979) (xy 102.102076 -228.945411) (xy 102.107623 -228.919541)
			(xy 102.106321 -228.893115) (xy 102.098256 -228.867916) (xy 102.09149 -228.85654) (xy 102.082396 -228.842218)
			(xy 102.065372 -228.81287) (xy 102.057454 -228.797866) (xy 102.05098 -228.786309) (xy 102.03315 -228.766731)
			(xy 102.010887 -228.752396) (xy 101.985685 -228.744267) (xy 101.959241 -228.74289) (xy 101.933332 -228.748359)
			(xy 101.92131 -228.753924) (xy 101.898066 -228.765121) (xy 101.848969 -228.780967) (xy 101.798007 -228.788996)
			(xy 101.772212 -228.789484) (xy 101.746243 -228.788976) (xy 101.694945 -228.780853) (xy 101.645549 -228.764806)
			(xy 101.599271 -228.741229) (xy 101.557251 -228.710704) (xy 101.520524 -228.673981) (xy 101.489993 -228.631965)
			(xy 101.46641 -228.58569) (xy 101.450357 -228.536296) (xy 101.442228 -228.484999) (xy 101.441758 -228.45903)
			(xy 101.442327 -228.431705) (xy 101.451327 -228.377802) (xy 101.469072 -228.326114) (xy 101.495076 -228.278048)
			(xy 101.528633 -228.234914) (xy 101.568828 -228.197888) (xy 101.591364 -228.182424) (xy 101.602205 -228.174837)
			(xy 101.619881 -228.155158) (xy 101.631895 -228.131593) (xy 101.637436 -228.105729) (xy 101.636132 -228.07931)
			(xy 101.62807 -228.054117) (xy 101.621336 -228.042724) (xy 101.612301 -228.028402) (xy 101.595404 -227.999054)
			(xy 101.587554 -227.98405) (xy 101.581118 -227.972454) (xy 101.563333 -227.952794) (xy 101.541079 -227.938387)
			(xy 101.515862 -227.930208) (xy 101.489388 -227.92881) (xy 101.46345 -227.934289) (xy 101.45141 -227.939854)
			(xy 101.428206 -227.951037) (xy 101.379194 -227.966872) (xy 101.328319 -227.974916) (xy 101.302566 -227.975414)
			(xy 101.2766 -227.974929) (xy 101.225307 -227.966799) (xy 101.175917 -227.950746) (xy 101.129647 -227.927164)
			(xy 101.087636 -227.896634) (xy 101.050918 -227.859907) (xy 101.020398 -227.817889) (xy 100.996826 -227.771614)
			(xy 100.980784 -227.722221) (xy 100.972666 -227.670927) (xy 100.972112 -227.64496) (xy 100.972629 -227.6188)
			(xy 100.980907 -227.567138) (xy 100.997221 -227.517425) (xy 101.021161 -227.470902) (xy 101.05213 -227.428731)
			(xy 101.07041 -227.41001) (xy 101.079635 -227.400296) (xy 101.093106 -227.37715) (xy 101.100109 -227.351302)
			(xy 101.100165 -227.324522) (xy 101.09327 -227.298644) (xy 101.079896 -227.275443) (xy 101.070664 -227.265738)
			(xy 100.947474 -227.142548) (xy 100.919026 -227.150168) (xy 100.897838 -227.155517) (xy 100.854516 -227.161245)
			(xy 100.832666 -227.161598) (xy 100.806699 -227.161086) (xy 100.755406 -227.152958) (xy 100.706015 -227.136907)
			(xy 100.659743 -227.113328) (xy 100.617728 -227.082802) (xy 100.581005 -227.04608) (xy 100.550477 -227.004066)
			(xy 100.526897 -226.957794) (xy 100.510844 -226.908404) (xy 100.502715 -226.857111) (xy 100.502212 -226.831144)
			(xy 100.502779 -226.803818) (xy 100.511777 -226.749912) (xy 100.529518 -226.69822) (xy 100.55552 -226.65015)
			(xy 100.589073 -226.607011) (xy 100.629265 -226.569978) (xy 100.651818 -226.554538) (xy 100.662665 -226.546953)
			(xy 100.680352 -226.527277) (xy 100.692375 -226.503709) (xy 100.697922 -226.477839) (xy 100.696619 -226.451414)
			(xy 100.688554 -226.426216) (xy 100.68179 -226.414838) (xy 100.672759 -226.400515) (xy 100.655863 -226.371165)
			(xy 100.648008 -226.356164) (xy 100.641535 -226.344602) (xy 100.623705 -226.325013) (xy 100.601438 -226.310666)
			(xy 100.576232 -226.302525) (xy 100.54978 -226.301138) (xy 100.52386 -226.306597) (xy 100.511864 -226.312222)
			(xy 100.48862 -226.323416) (xy 100.439522 -226.339255) (xy 100.38856 -226.347277) (xy 100.362766 -226.347782)
			(xy 100.3368 -226.34727) (xy 100.285507 -226.339142) (xy 100.236117 -226.323091) (xy 100.189846 -226.299511)
			(xy 100.147833 -226.268985) (xy 100.111111 -226.232263) (xy 100.080585 -226.190249) (xy 100.057007 -226.143977)
			(xy 100.040957 -226.094587) (xy 100.032829 -226.043294) (xy 100.032312 -226.017328) (xy 100.032881 -225.990003)
			(xy 100.041881 -225.936098) (xy 100.059624 -225.884408) (xy 100.085626 -225.83634) (xy 100.119181 -225.793203)
			(xy 100.159372 -225.756172) (xy 100.181918 -225.740722) (xy 100.192742 -225.733117) (xy 100.210379 -225.713414)
			(xy 100.222349 -225.689835) (xy 100.227848 -225.66397) (xy 100.226504 -225.637561) (xy 100.218407 -225.612387)
			(xy 100.211636 -225.601022) (xy 100.2026 -225.586636) (xy 100.185702 -225.557161) (xy 100.177854 -225.542094)
			(xy 100.171375 -225.530544) (xy 100.153542 -225.51098) (xy 100.131279 -225.496655) (xy 100.106084 -225.488532)
			(xy 100.079647 -225.487156) (xy 100.053744 -225.492619) (xy 100.04171 -225.498152) (xy 100.018467 -225.509351)
			(xy 99.96937 -225.5252) (xy 99.918408 -225.533231) (xy 99.892612 -225.533712) (xy 99.866643 -225.53323)
			(xy 99.815345 -225.525106) (xy 99.76595 -225.509057) (xy 99.719673 -225.485477) (xy 99.677656 -225.454948)
			(xy 99.640933 -225.418221) (xy 99.610407 -225.376201) (xy 99.586832 -225.329923) (xy 99.570787 -225.280526)
			(xy 99.562668 -225.229227) (xy 99.562158 -225.203258) (xy 99.562724 -225.175932) (xy 99.571721 -225.122026)
			(xy 99.589462 -225.070334) (xy 99.615465 -225.022265) (xy 99.649021 -224.979128) (xy 99.689215 -224.942098)
			(xy 99.711764 -224.926652) (xy 99.722626 -224.919045) (xy 99.740336 -224.899321) (xy 99.752375 -224.875704)
			(xy 99.757934 -224.849786) (xy 99.756638 -224.823309) (xy 99.748575 -224.798057) (xy 99.741736 -224.786698)
			(xy 99.732772 -224.772435) (xy 99.716 -224.743214) (xy 99.708208 -224.728278) (xy 99.701729 -224.716724)
			(xy 99.683894 -224.697152) (xy 99.66163 -224.682818) (xy 99.63643 -224.674684) (xy 99.609987 -224.673297)
			(xy 99.584075 -224.67875) (xy 99.572064 -224.684336) (xy 99.54882 -224.695532) (xy 99.499723 -224.711375)
			(xy 99.448761 -224.719399) (xy 99.422966 -224.719896) (xy 99.396999 -224.719384) (xy 99.345706 -224.711256)
			(xy 99.296315 -224.695205) (xy 99.250043 -224.671626) (xy 99.208028 -224.6411) (xy 99.171305 -224.604378)
			(xy 99.140778 -224.562364) (xy 99.117198 -224.516092) (xy 99.101146 -224.466702) (xy 99.093016 -224.415409)
			(xy 99.092512 -224.389442) (xy 99.092985 -224.363995) (xy 99.100793 -224.313704) (xy 99.116217 -224.265204)
			(xy 99.138892 -224.219641) (xy 99.168281 -224.178091) (xy 99.203691 -224.141535) (xy 99.244286 -224.110839)
			(xy 99.289105 -224.086727) (xy 99.337089 -224.069768) (xy 99.362006 -224.064576) (xy 99.384866 -224.060258)
			(xy 99.588574 -223.707198) (xy 99.580954 -223.685354) (xy 99.572157 -223.65878) (xy 99.562701 -223.603612)
			(xy 99.562158 -223.575626) (xy 99.562558 -223.552275) (xy 99.569124 -223.506038) (xy 99.582128 -223.461184)
			(xy 99.591368 -223.439736) (xy 99.59594 -223.429576) (xy 99.59594 -223.258888) (xy 99.42957 -223.092518)
			(xy 99.409758 -223.091756) (xy 99.384177 -223.090277) (xy 99.333899 -223.080399) (xy 99.285751 -223.062874)
			(xy 99.240887 -223.038122) (xy 99.200385 -223.006737) (xy 99.165218 -222.969472) (xy 99.136228 -222.927222)
			(xy 99.12477 -222.904304) (xy 99.111054 -222.875348) (xy 98.795078 -222.875348) (xy 98.781362 -222.904304)
			(xy 98.769402 -222.928022) (xy 98.739075 -222.971628) (xy 98.702169 -223.009826) (xy 98.659631 -223.041635)
			(xy 98.612557 -223.066236) (xy 98.562156 -223.082996) (xy 98.509724 -223.091486) (xy 98.456608 -223.091486)
			(xy 98.404176 -223.082996) (xy 98.353775 -223.066236) (xy 98.306701 -223.041635) (xy 98.264163 -223.009826)
			(xy 98.227257 -222.971628) (xy 98.19693 -222.928022) (xy 98.18497 -222.904304) (xy 98.171254 -222.875348)
			(xy 97.855278 -222.875348) (xy 97.841562 -222.904304) (xy 97.829601 -222.92802) (xy 97.799273 -222.971623)
			(xy 97.762366 -223.009817) (xy 97.719828 -223.041621) (xy 97.672754 -223.066217) (xy 97.622353 -223.082973)
			(xy 97.569922 -223.091457) (xy 97.543366 -223.09201) (xy 97.5174 -223.091525) (xy 97.466107 -223.083395)
			(xy 97.416718 -223.067342) (xy 97.370448 -223.04376) (xy 97.328437 -223.013229) (xy 97.29172 -222.976503)
			(xy 97.2612 -222.934485) (xy 97.237628 -222.88821) (xy 97.221587 -222.838817) (xy 97.213469 -222.787522)
			(xy 97.212912 -222.761556) (xy 97.213417 -222.735539) (xy 97.221607 -222.684154) (xy 97.237745 -222.634686)
			(xy 97.261434 -222.588356) (xy 97.292087 -222.54631) (xy 97.310194 -222.527622) (xy 97.06102 -222.278448)
			(xy 97.042732 -222.27667) (xy 97.017432 -222.273855) (xy 96.968065 -222.261442) (xy 96.921186 -222.241604)
			(xy 96.877905 -222.214809) (xy 96.839246 -222.181694) (xy 96.806124 -222.14304) (xy 96.779322 -222.099764)
			(xy 96.759476 -222.052889) (xy 96.747054 -222.003524) (xy 96.744282 -221.97822) (xy 96.742504 -221.959932)
			(xy 96.63684 -221.854268) (xy 96.626909 -221.844937) (xy 96.603251 -221.831433) (xy 96.576866 -221.824663)
			(xy 96.549629 -221.825108) (xy 96.523479 -221.832736) (xy 96.500274 -221.847004) (xy 96.481667 -221.866898)
			(xy 96.468979 -221.891004) (xy 96.463114 -221.917605) (xy 96.463358 -221.93123) (xy 96.463866 -221.94774)
			(xy 96.463354 -221.973708) (xy 96.455223 -222.025003) (xy 96.439168 -222.074394) (xy 96.415585 -222.120666)
			(xy 96.385054 -222.16268) (xy 96.348326 -222.1994) (xy 96.306306 -222.229922) (xy 96.260029 -222.253496)
			(xy 96.210634 -222.26954) (xy 96.159337 -222.277659) (xy 96.107402 -222.277654) (xy 96.056106 -222.269525)
			(xy 96.006714 -222.253472) (xy 95.960442 -222.22989) (xy 95.918427 -222.19936) (xy 95.881707 -222.162633)
			(xy 95.851183 -222.120614) (xy 95.827608 -222.074338) (xy 95.811563 -222.024943) (xy 95.803442 -221.973646)
			(xy 95.803445 -221.921711) (xy 95.811573 -221.870416) (xy 95.827624 -221.821023) (xy 95.851205 -221.77475)
			(xy 95.881734 -221.732735) (xy 95.91846 -221.696013) (xy 95.960478 -221.665488) (xy 96.006754 -221.641912)
			(xy 96.056148 -221.625865) (xy 96.107444 -221.617742) (xy 96.133412 -221.617286) (xy 96.149922 -221.617794)
			(xy 96.163569 -221.618092) (xy 96.190231 -221.612289) (xy 96.214401 -221.599627) (xy 96.234351 -221.581012)
			(xy 96.248653 -221.557774) (xy 96.256284 -221.531577) (xy 96.256699 -221.504294) (xy 96.249867 -221.477877)
			(xy 96.236277 -221.454216) (xy 96.226884 -221.444312) (xy 96.09074 -221.308168) (xy 96.079871 -221.298034)
			(xy 96.053708 -221.283972) (xy 96.024607 -221.278023) (xy 95.995025 -221.280691) (xy 95.967457 -221.291749)
			(xy 95.944232 -221.310265) (xy 95.935292 -221.322138) (xy 95.919728 -221.343689) (xy 95.882862 -221.381983)
			(xy 95.840336 -221.413874) (xy 95.793248 -221.438538) (xy 95.742816 -221.455335) (xy 95.690344 -221.463833)
			(xy 95.663766 -221.464378) (xy 95.6378 -221.463866) (xy 95.586508 -221.455738) (xy 95.537118 -221.439686)
			(xy 95.490847 -221.416107) (xy 95.448834 -221.385581) (xy 95.412113 -221.348859) (xy 95.381587 -221.306844)
			(xy 95.35801 -221.260573) (xy 95.34196 -221.211183) (xy 95.333833 -221.15989) (xy 95.333312 -221.133924)
			(xy 95.333849 -221.107348) (xy 95.342371 -221.054884) (xy 95.359182 -221.004461) (xy 95.383849 -220.957379)
			(xy 95.415735 -220.914854) (xy 95.454018 -220.877982) (xy 95.475552 -220.862398) (xy 95.487484 -220.853517)
			(xy 95.506031 -220.83028) (xy 95.517107 -220.802689) (xy 95.519777 -220.773078) (xy 95.513815 -220.743951)
			(xy 95.499724 -220.717771) (xy 95.489522 -220.70695) (xy 95.378778 -220.596206) (xy 95.345758 -220.613224)
			(xy 95.322156 -220.624894) (xy 95.272168 -220.64142) (xy 95.22019 -220.649803) (xy 95.193866 -220.650308)
			(xy 95.1679 -220.649823) (xy 95.116607 -220.641693) (xy 95.067218 -220.62564) (xy 95.020949 -220.602057)
			(xy 94.978938 -220.571527) (xy 94.942221 -220.534801) (xy 94.911701 -220.492783) (xy 94.88813 -220.446508)
			(xy 94.872088 -220.397115) (xy 94.863971 -220.34582) (xy 94.863412 -220.319854) (xy 94.863412 -220.264228)
			(xy 94.584266 -220.264228) (xy 94.584266 -220.31579) (xy 94.584266 -220.319854) (xy 94.583794 -220.345303)
			(xy 94.575986 -220.395598) (xy 94.560564 -220.444102) (xy 94.537892 -220.489671) (xy 94.508505 -220.531228)
			(xy 94.473097 -220.56779) (xy 94.432505 -220.598496) (xy 94.387687 -220.622618) (xy 94.339702 -220.639589)
			(xy 94.314772 -220.64472) (xy 94.291912 -220.649038) (xy 94.088204 -221.002098) (xy 94.095824 -221.024196)
			(xy 94.104615 -221.050771) (xy 94.11406 -221.105938) (xy 94.11462 -221.133924) (xy 94.393512 -221.133924)
			(xy 94.394021 -221.107957) (xy 94.402146 -221.056662) (xy 94.418194 -221.007269) (xy 94.441772 -220.960995)
			(xy 94.472298 -220.918979) (xy 94.509021 -220.882256) (xy 94.551037 -220.85173) (xy 94.597311 -220.828152)
			(xy 94.646704 -220.812104) (xy 94.697999 -220.803979) (xy 94.749933 -220.803979) (xy 94.801228 -220.812104)
			(xy 94.850621 -220.828152) (xy 94.896895 -220.85173) (xy 94.938911 -220.882256) (xy 94.975634 -220.918979)
			(xy 95.00616 -220.960995) (xy 95.029738 -221.007269) (xy 95.045786 -221.056662) (xy 95.053911 -221.107957)
			(xy 95.05442 -221.133924) (xy 95.053872 -221.16191) (xy 95.044419 -221.217078) (xy 95.035624 -221.243652)
			(xy 95.028004 -221.26575) (xy 95.231712 -221.618556) (xy 95.254572 -221.622874) (xy 95.2795 -221.628011)
			(xy 95.327485 -221.644981) (xy 95.372303 -221.669103) (xy 95.412895 -221.699808) (xy 95.448303 -221.736369)
			(xy 95.47769 -221.777925) (xy 95.500363 -221.823493) (xy 95.515785 -221.871997) (xy 95.523593 -221.922292)
			(xy 95.524066 -221.94774) (xy 95.523557 -221.973707) (xy 95.515432 -222.025002) (xy 95.499384 -222.074395)
			(xy 95.475806 -222.120669) (xy 95.44528 -222.162685) (xy 95.408557 -222.199408) (xy 95.366541 -222.229934)
			(xy 95.320267 -222.253512) (xy 95.270874 -222.26956) (xy 95.219579 -222.277685) (xy 95.167645 -222.277685)
			(xy 95.11635 -222.26956) (xy 95.066957 -222.253512) (xy 95.020683 -222.229934) (xy 94.978667 -222.199408)
			(xy 94.941944 -222.162685) (xy 94.911418 -222.120669) (xy 94.88784 -222.074395) (xy 94.871792 -222.025002)
			(xy 94.863667 -221.973707) (xy 94.863158 -221.94774) (xy 94.863718 -221.919754) (xy 94.873163 -221.864587)
			(xy 94.881954 -221.838012) (xy 94.889574 -221.815914) (xy 94.685866 -221.463108) (xy 94.663006 -221.45879)
			(xy 94.638082 -221.45363) (xy 94.590095 -221.436669) (xy 94.545274 -221.412553) (xy 94.504679 -221.381853)
			(xy 94.469268 -221.345294) (xy 94.43988 -221.303739) (xy 94.417207 -221.258171) (xy 94.401787 -221.209667)
			(xy 94.393982 -221.159372) (xy 94.393512 -221.133924) (xy 94.11462 -221.133924) (xy 94.114111 -221.159891)
			(xy 94.105986 -221.211186) (xy 94.089938 -221.260579) (xy 94.06636 -221.306853) (xy 94.035834 -221.348869)
			(xy 93.999111 -221.385592) (xy 93.957095 -221.416118) (xy 93.910821 -221.439696) (xy 93.861428 -221.455744)
			(xy 93.810133 -221.463869) (xy 93.758199 -221.463869) (xy 93.706904 -221.455744) (xy 93.657511 -221.439696)
			(xy 93.611237 -221.416118) (xy 93.569221 -221.385592) (xy 93.532498 -221.348869) (xy 93.501972 -221.306853)
			(xy 93.478394 -221.260579) (xy 93.462346 -221.211186) (xy 93.454221 -221.159891) (xy 93.453712 -221.133924)
			(xy 93.454186 -221.108478) (xy 93.461997 -221.058189) (xy 93.477422 -221.009691) (xy 93.500098 -220.96413)
			(xy 93.529488 -220.922582) (xy 93.564898 -220.886029) (xy 93.605492 -220.855335) (xy 93.65031 -220.831224)
			(xy 93.698293 -220.814267) (xy 93.723206 -220.809058) (xy 93.746066 -220.80474) (xy 93.949774 -220.45168)
			(xy 93.942154 -220.429582) (xy 93.933363 -220.403007) (xy 93.923919 -220.347839) (xy 93.923358 -220.319854)
			(xy 93.923358 -220.264228) (xy 93.64472 -220.264228) (xy 93.64472 -220.31579) (xy 93.64472 -220.319854)
			(xy 93.644211 -220.345821) (xy 93.636086 -220.397116) (xy 93.620038 -220.446509) (xy 93.59646 -220.492783)
			(xy 93.565934 -220.534799) (xy 93.529211 -220.571522) (xy 93.487195 -220.602048) (xy 93.440921 -220.625626)
			(xy 93.391528 -220.641674) (xy 93.340233 -220.649799) (xy 93.288299 -220.649799) (xy 93.237004 -220.641674)
			(xy 93.187611 -220.625626) (xy 93.141337 -220.602048) (xy 93.099321 -220.571522) (xy 93.062598 -220.534799)
			(xy 93.032072 -220.492783) (xy 93.008494 -220.446509) (xy 92.992446 -220.397116) (xy 92.984321 -220.345821)
			(xy 92.983812 -220.319854) (xy 92.983812 -220.264228) (xy 92.704666 -220.264228) (xy 92.704666 -220.31579)
			(xy 92.704666 -220.319854) (xy 92.704194 -220.345303) (xy 92.696386 -220.395598) (xy 92.680964 -220.444102)
			(xy 92.658292 -220.489671) (xy 92.628905 -220.531228) (xy 92.593497 -220.56779) (xy 92.552905 -220.598496)
			(xy 92.508087 -220.622618) (xy 92.460102 -220.639589) (xy 92.435172 -220.64472) (xy 92.412312 -220.649038)
			(xy 92.208604 -221.002098) (xy 92.216224 -221.024196) (xy 92.225015 -221.050771) (xy 92.23446 -221.105938)
			(xy 92.23502 -221.133924) (xy 92.513912 -221.133924) (xy 92.514421 -221.107957) (xy 92.522546 -221.056662)
			(xy 92.538594 -221.007269) (xy 92.562172 -220.960995) (xy 92.592698 -220.918979) (xy 92.629421 -220.882256)
			(xy 92.671437 -220.85173) (xy 92.717711 -220.828152) (xy 92.767104 -220.812104) (xy 92.818399 -220.803979)
			(xy 92.870333 -220.803979) (xy 92.921628 -220.812104) (xy 92.971021 -220.828152) (xy 93.017295 -220.85173)
			(xy 93.059311 -220.882256) (xy 93.096034 -220.918979) (xy 93.12656 -220.960995) (xy 93.150138 -221.007269)
			(xy 93.166186 -221.056662) (xy 93.174311 -221.107957) (xy 93.17482 -221.133924) (xy 93.174272 -221.16191)
			(xy 93.164819 -221.217078) (xy 93.156024 -221.243652) (xy 93.148404 -221.26575) (xy 93.352112 -221.618556)
			(xy 93.374972 -221.622874) (xy 93.3999 -221.628011) (xy 93.447885 -221.644981) (xy 93.492703 -221.669103)
			(xy 93.533295 -221.699808) (xy 93.568703 -221.736369) (xy 93.59809 -221.777925) (xy 93.620763 -221.823493)
			(xy 93.636185 -221.871997) (xy 93.643993 -221.922292) (xy 93.644466 -221.94774) (xy 93.643957 -221.973707)
			(xy 93.923867 -221.973707) (xy 93.923867 -221.921773) (xy 93.931992 -221.870478) (xy 93.94804 -221.821085)
			(xy 93.971618 -221.774811) (xy 94.002144 -221.732795) (xy 94.038867 -221.696072) (xy 94.080883 -221.665546)
			(xy 94.127157 -221.641968) (xy 94.17655 -221.62592) (xy 94.227845 -221.617795) (xy 94.279779 -221.617795)
			(xy 94.331074 -221.62592) (xy 94.380467 -221.641968) (xy 94.426741 -221.665546) (xy 94.468757 -221.696072)
			(xy 94.50548 -221.732795) (xy 94.536006 -221.774811) (xy 94.559584 -221.821085) (xy 94.575632 -221.870478)
			(xy 94.583757 -221.921773) (xy 94.584266 -221.94774) (xy 94.583757 -221.973707) (xy 94.575632 -222.025002)
			(xy 94.559584 -222.074395) (xy 94.536006 -222.120669) (xy 94.50548 -222.162685) (xy 94.468757 -222.199408)
			(xy 94.426741 -222.229934) (xy 94.380467 -222.253512) (xy 94.331074 -222.26956) (xy 94.279779 -222.277685)
			(xy 94.227845 -222.277685) (xy 94.17655 -222.26956) (xy 94.127157 -222.253512) (xy 94.080883 -222.229934)
			(xy 94.038867 -222.199408) (xy 94.002144 -222.162685) (xy 93.971618 -222.120669) (xy 93.94804 -222.074395)
			(xy 93.931992 -222.025002) (xy 93.923867 -221.973707) (xy 93.643957 -221.973707) (xy 93.635832 -222.025002)
			(xy 93.619784 -222.074395) (xy 93.596206 -222.120669) (xy 93.56568 -222.162685) (xy 93.528957 -222.199408)
			(xy 93.486941 -222.229934) (xy 93.440667 -222.253512) (xy 93.391274 -222.26956) (xy 93.339979 -222.277685)
			(xy 93.288045 -222.277685) (xy 93.23675 -222.26956) (xy 93.187357 -222.253512) (xy 93.141083 -222.229934)
			(xy 93.099067 -222.199408) (xy 93.062344 -222.162685) (xy 93.031818 -222.120669) (xy 93.00824 -222.074395)
			(xy 92.992192 -222.025002) (xy 92.984067 -221.973707) (xy 92.983558 -221.94774) (xy 92.984118 -221.919754)
			(xy 92.993563 -221.864587) (xy 93.002354 -221.838012) (xy 93.009974 -221.815914) (xy 92.806266 -221.463108)
			(xy 92.783406 -221.45879) (xy 92.758482 -221.45363) (xy 92.710495 -221.436669) (xy 92.665674 -221.412553)
			(xy 92.625079 -221.381853) (xy 92.589668 -221.345294) (xy 92.56028 -221.303739) (xy 92.537607 -221.258171)
			(xy 92.522187 -221.209667) (xy 92.514382 -221.159372) (xy 92.513912 -221.133924) (xy 92.23502 -221.133924)
			(xy 92.234511 -221.159891) (xy 92.226386 -221.211186) (xy 92.210338 -221.260579) (xy 92.18676 -221.306853)
			(xy 92.156234 -221.348869) (xy 92.119511 -221.385592) (xy 92.077495 -221.416118) (xy 92.031221 -221.439696)
			(xy 91.981828 -221.455744) (xy 91.930533 -221.463869) (xy 91.878599 -221.463869) (xy 91.827304 -221.455744)
			(xy 91.777911 -221.439696) (xy 91.731637 -221.416118) (xy 91.689621 -221.385592) (xy 91.652898 -221.348869)
			(xy 91.622372 -221.306853) (xy 91.598794 -221.260579) (xy 91.582746 -221.211186) (xy 91.574621 -221.159891)
			(xy 91.574112 -221.133924) (xy 91.574586 -221.108478) (xy 91.582397 -221.058189) (xy 91.597822 -221.009691)
			(xy 91.620498 -220.96413) (xy 91.649888 -220.922582) (xy 91.685298 -220.886029) (xy 91.725892 -220.855335)
			(xy 91.77071 -220.831224) (xy 91.818693 -220.814267) (xy 91.843606 -220.809058) (xy 91.866466 -220.80474)
			(xy 92.070174 -220.45168) (xy 92.062554 -220.429582) (xy 92.053763 -220.403007) (xy 92.044319 -220.347839)
			(xy 92.043758 -220.319854) (xy 92.043758 -220.264228) (xy 91.76512 -220.264228) (xy 91.76512 -220.31579)
			(xy 91.76512 -220.319854) (xy 91.764611 -220.345821) (xy 91.756486 -220.397116) (xy 91.740438 -220.446509)
			(xy 91.71686 -220.492783) (xy 91.686334 -220.534799) (xy 91.649611 -220.571522) (xy 91.607595 -220.602048)
			(xy 91.561321 -220.625626) (xy 91.511928 -220.641674) (xy 91.460633 -220.649799) (xy 91.408699 -220.649799)
			(xy 91.357404 -220.641674) (xy 91.308011 -220.625626) (xy 91.261737 -220.602048) (xy 91.219721 -220.571522)
			(xy 91.182998 -220.534799) (xy 91.152472 -220.492783) (xy 91.128894 -220.446509) (xy 91.112846 -220.397116)
			(xy 91.104721 -220.345821) (xy 91.104212 -220.319854) (xy 91.104212 -220.264228) (xy 90.825066 -220.264228)
			(xy 90.825066 -220.31579) (xy 90.825066 -220.319854) (xy 90.824594 -220.345303) (xy 90.816786 -220.395598)
			(xy 90.801364 -220.444102) (xy 90.778692 -220.489671) (xy 90.749305 -220.531228) (xy 90.713897 -220.56779)
			(xy 90.673305 -220.598496) (xy 90.628487 -220.622618) (xy 90.580502 -220.639589) (xy 90.555572 -220.64472)
			(xy 90.532712 -220.649038) (xy 90.329004 -221.002098) (xy 90.336624 -221.024196) (xy 90.345415 -221.050771)
			(xy 90.35486 -221.105938) (xy 90.35542 -221.133924) (xy 90.634312 -221.133924) (xy 90.634821 -221.107957)
			(xy 90.642946 -221.056662) (xy 90.658994 -221.007269) (xy 90.682572 -220.960995) (xy 90.713098 -220.918979)
			(xy 90.749821 -220.882256) (xy 90.791837 -220.85173) (xy 90.838111 -220.828152) (xy 90.887504 -220.812104)
			(xy 90.938799 -220.803979) (xy 90.990733 -220.803979) (xy 91.042028 -220.812104) (xy 91.091421 -220.828152)
			(xy 91.137695 -220.85173) (xy 91.179711 -220.882256) (xy 91.216434 -220.918979) (xy 91.24696 -220.960995)
			(xy 91.270538 -221.007269) (xy 91.286586 -221.056662) (xy 91.294711 -221.107957) (xy 91.29522 -221.133924)
			(xy 91.294672 -221.16191) (xy 91.285219 -221.217078) (xy 91.276424 -221.243652) (xy 91.268804 -221.26575)
			(xy 91.472512 -221.618556) (xy 91.495372 -221.622874) (xy 91.5203 -221.628011) (xy 91.568285 -221.644981)
			(xy 91.613103 -221.669103) (xy 91.653695 -221.699808) (xy 91.689103 -221.736369) (xy 91.71849 -221.777925)
			(xy 91.741163 -221.823493) (xy 91.756585 -221.871997) (xy 91.764393 -221.922292) (xy 91.764866 -221.94774)
			(xy 91.764357 -221.973707) (xy 92.044267 -221.973707) (xy 92.044267 -221.921773) (xy 92.052392 -221.870478)
			(xy 92.06844 -221.821085) (xy 92.092018 -221.774811) (xy 92.122544 -221.732795) (xy 92.159267 -221.696072)
			(xy 92.201283 -221.665546) (xy 92.247557 -221.641968) (xy 92.29695 -221.62592) (xy 92.348245 -221.617795)
			(xy 92.400179 -221.617795) (xy 92.451474 -221.62592) (xy 92.500867 -221.641968) (xy 92.547141 -221.665546)
			(xy 92.589157 -221.696072) (xy 92.62588 -221.732795) (xy 92.656406 -221.774811) (xy 92.679984 -221.821085)
			(xy 92.696032 -221.870478) (xy 92.704157 -221.921773) (xy 92.704666 -221.94774) (xy 92.704157 -221.973707)
			(xy 92.696032 -222.025002) (xy 92.679984 -222.074395) (xy 92.656406 -222.120669) (xy 92.62588 -222.162685)
			(xy 92.589157 -222.199408) (xy 92.547141 -222.229934) (xy 92.500867 -222.253512) (xy 92.451474 -222.26956)
			(xy 92.400179 -222.277685) (xy 92.348245 -222.277685) (xy 92.29695 -222.26956) (xy 92.247557 -222.253512)
			(xy 92.201283 -222.229934) (xy 92.159267 -222.199408) (xy 92.122544 -222.162685) (xy 92.092018 -222.120669)
			(xy 92.06844 -222.074395) (xy 92.052392 -222.025002) (xy 92.044267 -221.973707) (xy 91.764357 -221.973707)
			(xy 91.756232 -222.025002) (xy 91.740184 -222.074395) (xy 91.716606 -222.120669) (xy 91.68608 -222.162685)
			(xy 91.649357 -222.199408) (xy 91.607341 -222.229934) (xy 91.561067 -222.253512) (xy 91.511674 -222.26956)
			(xy 91.460379 -222.277685) (xy 91.408445 -222.277685) (xy 91.35715 -222.26956) (xy 91.307757 -222.253512)
			(xy 91.261483 -222.229934) (xy 91.219467 -222.199408) (xy 91.182744 -222.162685) (xy 91.152218 -222.120669)
			(xy 91.12864 -222.074395) (xy 91.112592 -222.025002) (xy 91.104467 -221.973707) (xy 91.103958 -221.94774)
			(xy 91.104518 -221.919754) (xy 91.113963 -221.864587) (xy 91.122754 -221.838012) (xy 91.130374 -221.815914)
			(xy 90.926666 -221.463108) (xy 90.903806 -221.45879) (xy 90.878882 -221.45363) (xy 90.830895 -221.436669)
			(xy 90.786074 -221.412553) (xy 90.745479 -221.381853) (xy 90.710068 -221.345294) (xy 90.68068 -221.303739)
			(xy 90.658007 -221.258171) (xy 90.642587 -221.209667) (xy 90.634782 -221.159372) (xy 90.634312 -221.133924)
			(xy 90.35542 -221.133924) (xy 90.354911 -221.159891) (xy 90.346786 -221.211186) (xy 90.330738 -221.260579)
			(xy 90.30716 -221.306853) (xy 90.276634 -221.348869) (xy 90.239911 -221.385592) (xy 90.197895 -221.416118)
			(xy 90.151621 -221.439696) (xy 90.102228 -221.455744) (xy 90.050933 -221.463869) (xy 89.998999 -221.463869)
			(xy 89.947704 -221.455744) (xy 89.898311 -221.439696) (xy 89.852037 -221.416118) (xy 89.810021 -221.385592)
			(xy 89.773298 -221.348869) (xy 89.742772 -221.306853) (xy 89.719194 -221.260579) (xy 89.703146 -221.211186)
			(xy 89.695021 -221.159891) (xy 89.694512 -221.133924) (xy 89.694986 -221.108478) (xy 89.702797 -221.058189)
			(xy 89.718222 -221.009691) (xy 89.740898 -220.96413) (xy 89.770288 -220.922582) (xy 89.805698 -220.886029)
			(xy 89.846292 -220.855335) (xy 89.89111 -220.831224) (xy 89.939093 -220.814267) (xy 89.964006 -220.809058)
			(xy 89.986866 -220.80474) (xy 90.190574 -220.45168) (xy 90.182954 -220.429582) (xy 90.174163 -220.403007)
			(xy 90.164719 -220.347839) (xy 90.164158 -220.319854) (xy 90.164158 -220.264228) (xy 89.88552 -220.264228)
			(xy 89.88552 -220.31579) (xy 89.88552 -220.319854) (xy 89.885011 -220.345821) (xy 89.876886 -220.397116)
			(xy 89.860838 -220.446509) (xy 89.83726 -220.492783) (xy 89.806734 -220.534799) (xy 89.770011 -220.571522)
			(xy 89.727995 -220.602048) (xy 89.681721 -220.625626) (xy 89.632328 -220.641674) (xy 89.581033 -220.649799)
			(xy 89.529099 -220.649799) (xy 89.477804 -220.641674) (xy 89.428411 -220.625626) (xy 89.382137 -220.602048)
			(xy 89.340121 -220.571522) (xy 89.303398 -220.534799) (xy 89.272872 -220.492783) (xy 89.249294 -220.446509)
			(xy 89.233246 -220.397116) (xy 89.225121 -220.345821) (xy 89.224612 -220.319854) (xy 89.224612 -220.264228)
			(xy 88.94572 -220.264228) (xy 88.94572 -220.31579) (xy 88.94572 -220.319854) (xy 88.945211 -220.345821)
			(xy 88.937086 -220.397116) (xy 88.921038 -220.446509) (xy 88.89746 -220.492783) (xy 88.866934 -220.534799)
			(xy 88.830211 -220.571522) (xy 88.788195 -220.602048) (xy 88.741921 -220.625626) (xy 88.692528 -220.641674)
			(xy 88.641233 -220.649799) (xy 88.589299 -220.649799) (xy 88.538004 -220.641674) (xy 88.488611 -220.625626)
			(xy 88.442337 -220.602048) (xy 88.400321 -220.571522) (xy 88.363598 -220.534799) (xy 88.333072 -220.492783)
			(xy 88.309494 -220.446509) (xy 88.293446 -220.397116) (xy 88.285321 -220.345821) (xy 88.284812 -220.319854)
			(xy 88.284812 -220.264228) (xy 87.161116 -220.264228) (xy 87.10168 -220.204792) (xy 87.04834 -220.258132)
			(xy 87.051134 -220.282516) (xy 87.05219 -220.291815) (xy 87.053336 -220.310496) (xy 87.05342 -220.319854)
			(xy 87.05293 -220.344823) (xy 87.045118 -220.394147) (xy 87.029687 -220.441641) (xy 87.007015 -220.486137)
			(xy 86.977662 -220.526538) (xy 86.94235 -220.56185) (xy 86.901949 -220.591203) (xy 86.857453 -220.613875)
			(xy 86.809959 -220.629306) (xy 86.760635 -220.637118) (xy 86.710697 -220.637118) (xy 86.661373 -220.629306)
			(xy 86.613879 -220.613875) (xy 86.569383 -220.591203) (xy 86.528982 -220.56185) (xy 86.49367 -220.526538)
			(xy 86.464317 -220.486137) (xy 86.441645 -220.441641) (xy 86.426214 -220.394147) (xy 86.418402 -220.344823)
			(xy 86.417912 -220.319854) (xy 86.418373 -220.295288) (xy 86.42594 -220.246741) (xy 86.440886 -220.199937)
			(xy 86.462855 -220.15599) (xy 86.491324 -220.115946) (xy 86.525616 -220.08076) (xy 86.564913 -220.051268)
			(xy 86.608279 -220.028174) (xy 86.654683 -220.012027) (xy 86.67877 -220.00718) (xy 86.692286 -220.004227)
			(xy 86.717147 -219.992116) (xy 86.737847 -219.973779) (xy 86.75287 -219.950561) (xy 86.761113 -219.924165)
			(xy 86.761972 -219.896524) (xy 86.755385 -219.869666) (xy 86.741833 -219.84556) (xy 86.732364 -219.835476)
			(xy 85.249258 -218.35237) (xy 85.189822 -218.180666) (xy 85.172042 -218.171522) (xy 85.149422 -218.159189)
			(xy 85.107972 -218.128592) (xy 85.071775 -218.091932) (xy 85.041708 -218.050098) (xy 85.018499 -218.004102)
			(xy 85.002712 -217.955062) (xy 84.994729 -217.904166) (xy 84.994242 -217.878406) (xy 84.994644 -217.855056)
			(xy 85.001214 -217.80882) (xy 85.014224 -217.763969) (xy 85.023452 -217.742516) (xy 85.031834 -217.723974)
			(xy 84.450682 -216.045034) (xy 84.22386 -215.817958) (xy 84.215343 -215.80929) (xy 84.199822 -215.790589)
			(xy 84.192872 -215.78062) (xy 84.190078 -215.776556) (xy 78.534768 -210.120992) (xy 78.526637 -210.112712)
			(xy 78.511759 -210.094901) (xy 78.50505 -210.085432) (xy 78.502256 -210.081368) (xy 77.832458 -209.41157)
			(xy 71.453756 -194.89547) (xy 68.08724 -191.529208) (xy 67.47002 -191.529208) (xy 67.445025 -191.528568)
			(xy 67.396006 -191.518762) (xy 67.349841 -191.499582) (xy 67.308306 -191.471764) (xy 67.290188 -191.454532)
			(xy 65.921636 -190.08598) (xy 61.918088 -190.08598) (xy 60.506102 -188.673994) (xy 57.874662 -188.673994)
			(xy 54.817772 -185.617104) (xy 53.719476 -185.617104) (xy 53.705378 -185.617563) (xy 53.678259 -185.62528)
			(xy 53.654284 -185.640118) (xy 53.635281 -185.660948) (xy 53.622698 -185.68618) (xy 53.617495 -185.713891)
			(xy 53.620068 -185.741969) (xy 53.624734 -185.75528) (xy 53.632855 -185.777314) (xy 53.644275 -185.822864)
			(xy 53.650038 -185.869468) (xy 53.650388 -185.892948) (xy 53.649898 -185.920196) (xy 53.642136 -185.974138)
			(xy 53.626777 -186.026426) (xy 53.604133 -186.075995) (xy 53.574665 -186.121838) (xy 53.538973 -186.163021)
			(xy 53.497784 -186.198706) (xy 53.451936 -186.228165) (xy 53.402362 -186.250801) (xy 53.350071 -186.266151)
			(xy 53.296129 -186.273903) (xy 53.26888 -186.274456) (xy 53.239964 -186.27392) (xy 53.182796 -186.26519)
			(xy 53.1276 -186.247932) (xy 53.07564 -186.222543) (xy 53.028107 -186.189603) (xy 52.986089 -186.149867)
			(xy 52.96789 -186.12739) (xy 52.957993 -186.115585) (xy 52.932669 -186.098066) (xy 52.903276 -186.08889)
			(xy 52.872484 -186.08889) (xy 52.843091 -186.098066) (xy 52.817767 -186.115585) (xy 52.80787 -186.12739)
			(xy 52.789681 -186.149876) (xy 52.747665 -186.189619) (xy 52.700131 -186.222564) (xy 52.648169 -186.247956)
			(xy 52.592969 -186.265213) (xy 52.535797 -186.27394) (xy 52.50688 -186.274456) (xy 52.480852 -186.274013)
			(xy 52.42928 -186.266935) (xy 52.379148 -186.252913) (xy 52.331387 -186.232207) (xy 52.286884 -186.205202)
			(xy 52.246465 -186.172399) (xy 52.210879 -186.134406) (xy 52.195476 -186.11342) (xy 52.187272 -186.102595)
			(xy 52.166281 -186.085372) (xy 52.141492 -186.074292) (xy 52.114659 -186.070139) (xy 52.087681 -186.073206)
			(xy 52.062465 -186.083277) (xy 52.040797 -186.099639) (xy 52.032154 -186.110118) (xy 52.013971 -186.132875)
			(xy 51.97187 -186.173129) (xy 51.92414 -186.206517) (xy 51.871891 -186.232263) (xy 51.816335 -186.249769)
			(xy 51.758764 -186.258627) (xy 51.72964 -186.259216) (xy 51.702385 -186.258755) (xy 51.648429 -186.251003)
			(xy 51.596126 -186.235651) (xy 51.546541 -186.213011) (xy 51.500682 -186.183544) (xy 51.459484 -186.14785)
			(xy 51.423785 -186.106657) (xy 51.394313 -186.060802) (xy 51.371666 -186.011219) (xy 51.356307 -185.958918)
			(xy 51.348548 -185.904963) (xy 51.348132 -185.877708) (xy 51.348803 -185.845719) (xy 51.359528 -185.782645)
			(xy 51.369468 -185.752232) (xy 51.373604 -185.738986) (xy 51.375372 -185.711305) (xy 51.369621 -185.684171)
			(xy 51.356775 -185.659588) (xy 51.337783 -185.639372) (xy 51.314048 -185.625019) (xy 51.287325 -185.617587)
			(xy 51.273456 -185.617104) (xy 23.385272 -185.617104) (xy 23.385272 -185.670698) (xy 23.385526 -185.673238)
			(xy 23.387304 -185.707274) (xy 23.387304 -186.146948) (xy 50.346862 -186.146948) (xy 50.350933 -186.091326)
			(xy 50.363059 -186.036889) (xy 50.382982 -185.984798) (xy 50.410278 -185.936163) (xy 50.444364 -185.89202)
			(xy 50.484513 -185.853311) (xy 50.529871 -185.82086) (xy 50.579471 -185.795359) (xy 50.632255 -185.777352)
			(xy 50.687098 -185.767222) (xy 50.742832 -185.765185) (xy 50.798269 -185.771285) (xy 50.852226 -185.785391)
			(xy 50.903555 -185.807203) (xy 50.951161 -185.836257) (xy 50.994029 -185.871932) (xy 51.031246 -185.913469)
			(xy 51.062019 -185.959982) (xy 51.085691 -186.010479) (xy 51.101759 -186.063886) (xy 51.109879 -186.119062)
			(xy 51.110388 -186.146948) (xy 51.109879 -186.174834) (xy 51.101759 -186.23001) (xy 51.085691 -186.283417)
			(xy 51.062019 -186.333914) (xy 51.031246 -186.380427) (xy 50.994029 -186.421964) (xy 50.951161 -186.457639)
			(xy 50.903555 -186.486693) (xy 50.852226 -186.508505) (xy 50.798269 -186.522611) (xy 50.742832 -186.528711)
			(xy 50.687098 -186.526674) (xy 50.632255 -186.516544) (xy 50.579471 -186.498537) (xy 50.529871 -186.473036)
			(xy 50.484513 -186.440585) (xy 50.444364 -186.401876) (xy 50.410278 -186.357733) (xy 50.382982 -186.309098)
			(xy 50.363059 -186.257007) (xy 50.350933 -186.20257) (xy 50.346862 -186.146948) (xy 23.387304 -186.146948)
			(xy 23.387304 -186.741816) (xy 23.38686 -186.766794) (xy 23.379082 -186.81614) (xy 23.363672 -186.863659)
			(xy 23.341011 -186.908178) (xy 23.311657 -186.9486) (xy 23.29434 -186.966606) (xy 22.435802 -187.825144)
			(xy 50.220926 -187.825144) (xy 50.220926 -187.770651) (xy 50.228682 -187.716712) (xy 50.244034 -187.664426)
			(xy 50.266671 -187.614856) (xy 50.296132 -187.569013) (xy 50.331817 -187.527829) (xy 50.372999 -187.492142)
			(xy 50.418841 -187.462679) (xy 50.468409 -187.44004) (xy 50.520695 -187.424685) (xy 50.574633 -187.416928)
			(xy 50.60188 -187.41644) (xy 50.61616 -187.416594) (xy 50.644637 -187.418753) (xy 50.658776 -187.420758)
			(xy 50.672463 -187.422461) (xy 50.699839 -187.419145) (xy 50.725325 -187.408615) (xy 50.747058 -187.391641)
			(xy 50.763448 -187.369464) (xy 50.773297 -187.343707) (xy 50.775884 -187.316253) (xy 50.771021 -187.289109)
			(xy 50.765456 -187.276486) (xy 50.753743 -187.250691) (xy 50.737209 -187.196507) (xy 50.72887 -187.140474)
			(xy 50.728372 -187.112148) (xy 50.728804 -187.084891) (xy 50.736555 -187.03093) (xy 50.751908 -186.978622)
			(xy 50.774549 -186.929031) (xy 50.804017 -186.883167) (xy 50.839712 -186.841964) (xy 50.880908 -186.806261)
			(xy 50.926766 -186.776784) (xy 50.976353 -186.754134) (xy 51.028658 -186.738771) (xy 51.082617 -186.731009)
			(xy 51.137132 -186.731005) (xy 51.191092 -186.73876) (xy 51.2434 -186.754116) (xy 51.292989 -186.77676)
			(xy 51.338851 -186.80623) (xy 51.380052 -186.841928) (xy 51.415753 -186.883127) (xy 51.445227 -186.928986)
			(xy 51.467874 -186.978574) (xy 51.483234 -187.03088) (xy 51.490993 -187.08484) (xy 51.490993 -187.113947)
			(xy 51.744926 -187.113947) (xy 51.744926 -187.059453) (xy 51.752681 -187.005514) (xy 51.768033 -186.953227)
			(xy 51.79067 -186.903658) (xy 51.820131 -186.857814) (xy 51.855816 -186.81663) (xy 51.896998 -186.780943)
			(xy 51.94284 -186.75148) (xy 51.992409 -186.72884) (xy 52.044694 -186.713485) (xy 52.098633 -186.705728)
			(xy 52.12588 -186.70524) (xy 52.153121 -186.705696) (xy 52.20705 -186.713445) (xy 52.259328 -186.728787)
			(xy 52.308892 -186.751411) (xy 52.354732 -186.780856) (xy 52.395917 -186.816523) (xy 52.431609 -186.857687)
			(xy 52.461081 -186.90351) (xy 52.483734 -186.95306) (xy 52.499107 -187.005329) (xy 52.506888 -187.059253)
			(xy 52.507388 -187.086494) (xy 52.507798 -187.099882) (xy 52.514833 -187.125718) (xy 52.528343 -187.148838)
			(xy 52.547397 -187.167651) (xy 52.570688 -187.180864) (xy 52.596612 -187.187569) (xy 52.610004 -187.18784)
			(xy 52.61356 -187.18784) (xy 52.640818 -187.188204) (xy 52.69478 -187.195958) (xy 52.74709 -187.211312)
			(xy 52.796681 -187.233955) (xy 52.842545 -187.263426) (xy 52.883748 -187.299124) (xy 52.91945 -187.340323)
			(xy 52.948926 -187.386184) (xy 52.971574 -187.435773) (xy 52.986934 -187.488081) (xy 52.994693 -187.542042)
			(xy 52.994693 -187.596558) (xy 52.986934 -187.650519) (xy 52.971574 -187.702827) (xy 52.948926 -187.752416)
			(xy 52.91945 -187.798277) (xy 52.883748 -187.839476) (xy 52.842545 -187.875174) (xy 52.796681 -187.904645)
			(xy 52.74709 -187.927288) (xy 52.69478 -187.942642) (xy 52.640818 -187.950396) (xy 52.61356 -187.950856)
			(xy 52.586321 -187.95036) (xy 52.532399 -187.942606) (xy 52.480128 -187.927261) (xy 52.43057 -187.904638)
			(xy 52.384735 -187.875195) (xy 52.343553 -187.839533) (xy 52.307862 -187.798375) (xy 52.278388 -187.75256)
			(xy 52.25573 -187.703018) (xy 52.24035 -187.650757) (xy 52.232558 -187.59684) (xy 52.232052 -187.569602)
			(xy 52.231618 -187.556214) (xy 52.224601 -187.530372) (xy 52.2111 -187.507245) (xy 52.192048 -187.488428)
			(xy 52.168756 -187.475217) (xy 52.142829 -187.468521) (xy 52.129436 -187.468256) (xy 52.12588 -187.468256)
			(xy 52.098633 -187.467672) (xy 52.044694 -187.459915) (xy 51.992409 -187.44456) (xy 51.94284 -187.42192)
			(xy 51.896998 -187.392457) (xy 51.855816 -187.35677) (xy 51.820131 -187.315586) (xy 51.79067 -187.269742)
			(xy 51.768033 -187.220173) (xy 51.752681 -187.167886) (xy 51.744926 -187.113947) (xy 51.490993 -187.113947)
			(xy 51.490993 -187.139355) (xy 51.483235 -187.193314) (xy 51.467876 -187.245621) (xy 51.44523 -187.295209)
			(xy 51.415756 -187.341069) (xy 51.380056 -187.382268) (xy 51.338855 -187.417966) (xy 51.292994 -187.447438)
			(xy 51.243405 -187.470082) (xy 51.191098 -187.485439) (xy 51.137137 -187.493194) (xy 51.10988 -187.493656)
			(xy 51.0956 -187.493507) (xy 51.067123 -187.491345) (xy 51.052984 -187.489338) (xy 51.03929 -187.487695)
			(xy 51.011917 -187.490998) (xy 50.986432 -187.501517) (xy 50.964698 -187.518481) (xy 50.948307 -187.540651)
			(xy 50.938458 -187.566403) (xy 50.935872 -187.593852) (xy 50.940737 -187.62099) (xy 50.946304 -187.63361)
			(xy 50.958019 -187.659404) (xy 50.974551 -187.713589) (xy 50.98289 -187.769622) (xy 50.983388 -187.797948)
			(xy 50.98287 -187.825195) (xy 50.975109 -187.879133) (xy 50.95975 -187.931417) (xy 50.937107 -187.980984)
			(xy 50.907641 -188.026823) (xy 50.885866 -188.051948) (xy 53.267862 -188.051948) (xy 53.271933 -187.996326)
			(xy 53.284059 -187.941889) (xy 53.303982 -187.889798) (xy 53.331278 -187.841163) (xy 53.365364 -187.79702)
			(xy 53.405513 -187.758311) (xy 53.450871 -187.72586) (xy 53.500471 -187.700359) (xy 53.553255 -187.682352)
			(xy 53.608098 -187.672222) (xy 53.663832 -187.670185) (xy 53.719269 -187.676285) (xy 53.773226 -187.690391)
			(xy 53.824555 -187.712203) (xy 53.872161 -187.741257) (xy 53.915029 -187.776932) (xy 53.952246 -187.818469)
			(xy 53.983019 -187.864982) (xy 54.006691 -187.915479) (xy 54.022759 -187.968886) (xy 54.030879 -188.024062)
			(xy 54.031388 -188.051948) (xy 54.030879 -188.079834) (xy 54.022759 -188.13501) (xy 54.006691 -188.188417)
			(xy 53.983019 -188.238914) (xy 53.952246 -188.285427) (xy 53.915029 -188.326964) (xy 53.872161 -188.362639)
			(xy 53.824555 -188.391693) (xy 53.773226 -188.413505) (xy 53.719269 -188.427611) (xy 53.663832 -188.433711)
			(xy 53.608098 -188.431674) (xy 53.553255 -188.421544) (xy 53.500471 -188.403537) (xy 53.450871 -188.378036)
			(xy 53.405513 -188.345585) (xy 53.365364 -188.306876) (xy 53.331278 -188.262733) (xy 53.303982 -188.214098)
			(xy 53.284059 -188.162007) (xy 53.271933 -188.10757) (xy 53.267862 -188.051948) (xy 50.885866 -188.051948)
			(xy 50.871951 -188.068003) (xy 50.830765 -188.103685) (xy 50.784919 -188.133142) (xy 50.735348 -188.155776)
			(xy 50.683061 -188.171124) (xy 50.629121 -188.178876) (xy 50.574628 -188.178872) (xy 50.52069 -188.171114)
			(xy 50.468404 -188.155758) (xy 50.418836 -188.133118) (xy 50.372995 -188.103655) (xy 50.331813 -188.067967)
			(xy 50.296129 -188.026783) (xy 50.266668 -187.980939) (xy 50.244032 -187.931369) (xy 50.22868 -187.879083)
			(xy 50.220926 -187.825144) (xy 22.435802 -187.825144) (xy 21.852636 -188.40831) (xy 21.848826 -188.417962)
			(xy 21.837838 -188.444218) (xy 21.809214 -188.493413) (xy 21.7736 -188.53781) (xy 21.731786 -188.576424)
			(xy 21.6847 -188.608398) (xy 21.633386 -188.633022) (xy 21.578984 -188.64975) (xy 21.5227 -188.658212)
			(xy 21.494242 -188.658754) (xy 21.466988 -188.658271) (xy 21.413033 -188.65052) (xy 21.36073 -188.635169)
			(xy 21.311145 -188.612531) (xy 21.265286 -188.583066) (xy 21.224087 -188.547375) (xy 21.188387 -188.506185)
			(xy 21.158912 -188.460332) (xy 21.136262 -188.410752) (xy 21.120899 -188.358453) (xy 21.113135 -188.3045)
			(xy 21.112734 -188.277246) (xy 21.11323 -188.249588) (xy 21.121225 -188.194852) (xy 21.137041 -188.141844)
			(xy 21.160345 -188.091676) (xy 21.190648 -188.045399) (xy 21.227317 -188.003982) (xy 21.269582 -187.968295)
			(xy 21.316557 -187.939084) (xy 21.367258 -187.916963) (xy 21.420622 -187.902395) (xy 21.448014 -187.898532)
			(xy 21.465286 -187.8965) (xy 22.309074 -187.052712) (xy 22.252686 -186.996324) (xy 22.224492 -187.00369)
			(xy 22.205199 -187.008306) (xy 22.165841 -187.013274) (xy 22.146006 -187.013596) (xy 21.236432 -187.013596)
			(xy 21.236432 -187.190634) (xy 21.244052 -187.202826) (xy 21.257365 -187.225397) (xy 21.278354 -187.273413)
			(xy 21.292568 -187.323851) (xy 21.299738 -187.375761) (xy 21.300186 -187.401962) (xy 21.2997 -187.429213)
			(xy 21.291944 -187.483161) (xy 21.276589 -187.535456) (xy 21.253947 -187.585033) (xy 21.224481 -187.630883)
			(xy 21.18879 -187.672074) (xy 21.147599 -187.707765) (xy 21.101749 -187.737231) (xy 21.052172 -187.759873)
			(xy 20.999877 -187.775228) (xy 20.945929 -187.782984) (xy 20.891427 -187.782984) (xy 20.837479 -187.775228)
			(xy 20.785184 -187.759873) (xy 20.735607 -187.737231) (xy 20.689757 -187.707765) (xy 20.648566 -187.672074)
			(xy 20.612875 -187.630883) (xy 20.583409 -187.585033) (xy 20.560767 -187.535456) (xy 20.545412 -187.483161)
			(xy 20.537656 -187.429213) (xy 20.53717 -187.401962) (xy 20.537664 -187.373988) (xy 20.545845 -187.318641)
			(xy 20.562025 -187.265083) (xy 20.585858 -187.214464) (xy 20.600924 -187.190888) (xy 20.600924 -186.858148)
			(xy 20.60137 -186.833171) (xy 20.609152 -186.783826) (xy 20.624564 -186.736309) (xy 20.647224 -186.69179)
			(xy 20.676575 -186.651368) (xy 20.693888 -186.633358) (xy 20.856448 -186.470798) (xy 20.874433 -186.453445)
			(xy 20.914846 -186.424046) (xy 20.959365 -186.401339) (xy 21.006891 -186.385884) (xy 21.05625 -186.378063)
			(xy 21.081238 -186.37758) (xy 22.014434 -186.37758) (xy 22.112732 -186.279282) (xy 22.112732 -186.270646)
			(xy 21.45919 -185.617104) (xy 16.728948 -185.617104) (xy 16.728948 -185.925968) (xy 17.03959 -186.23661)
			(xy 17.056946 -186.254594) (xy 17.086351 -186.295006) (xy 17.109064 -186.339524) (xy 17.124525 -186.38705)
			(xy 17.132352 -186.436411) (xy 17.132808 -186.4614) (xy 17.132808 -187.20562) (xy 17.132296 -187.230603)
			(xy 17.124443 -187.27995) (xy 17.108981 -187.327465) (xy 17.086289 -187.371983) (xy 17.056924 -187.412411)
			(xy 17.03959 -187.43041) (xy 16.612616 -187.857384) (xy 16.60906 -187.871354) (xy 16.601966 -187.898763)
			(xy 16.580782 -187.951266) (xy 16.552065 -188.000058) (xy 16.516446 -188.044065) (xy 16.47471 -188.082319)
			(xy 16.427773 -188.113978) (xy 16.37667 -188.138346) (xy 16.322525 -188.154886) (xy 16.266528 -188.163235)
			(xy 16.23822 -188.163708) (xy 16.210966 -188.163246) (xy 16.157013 -188.155491) (xy 16.104713 -188.140137)
			(xy 16.05513 -188.117496) (xy 16.009275 -188.088028) (xy 15.96808 -188.052335) (xy 15.932384 -188.011141)
			(xy 15.902914 -187.965287) (xy 15.88027 -187.915706) (xy 15.864913 -187.863406) (xy 15.857155 -187.809454)
			(xy 15.856712 -187.7822) (xy 15.857234 -187.753899) (xy 15.865612 -187.69792) (xy 15.88217 -187.643793)
			(xy 15.906544 -187.592707) (xy 15.938198 -187.545783) (xy 15.976438 -187.504051) (xy 16.020425 -187.468428)
			(xy 16.069193 -187.439695) (xy 16.121671 -187.418483) (xy 16.149066 -187.41136) (xy 16.163036 -187.407804)
			(xy 16.496792 -187.074048) (xy 16.496792 -186.592972) (xy 16.18615 -186.28233) (xy 16.168796 -186.264346)
			(xy 16.139395 -186.223933) (xy 16.116687 -186.179414) (xy 16.101233 -186.131888) (xy 16.093414 -186.082528)
			(xy 16.092932 -186.05754) (xy 16.092932 -184.768236) (xy 13.379704 -182.054754) (xy 13.379704 -167.29837)
			(xy 11.679428 -165.598094) (xy 11.651488 -165.60546) (xy 11.544349 -165.63238) (xy 11.328241 -165.678313)
			(xy 11.110399 -165.715149) (xy 10.891204 -165.742825) (xy 10.671042 -165.761292) (xy 10.4503 -165.770518)
			(xy 10.339832 -165.771068) (xy 10.231897 -165.770526) (xy 10.016207 -165.761704) (xy 9.801059 -165.744062)
			(xy 9.586814 -165.717628) (xy 9.373829 -165.682448) (xy 9.162464 -165.63858) (xy 8.95307 -165.586098)
			(xy 8.746001 -165.525089) (xy 8.64362 -165.490906) (xy 8.635746 -165.488112) (xy 8.168132 -165.488112)
			(xy 7.7978 -165.11778) (xy 7.79145 -165.114224) (xy 7.700595 -165.063454) (xy 7.522505 -164.955698)
			(xy 7.348807 -164.840995) (xy 7.179772 -164.719525) (xy 7.015665 -164.591477) (xy 6.85674 -164.45705)
			(xy 6.703246 -164.316454) (xy 6.555422 -164.169908) (xy 6.413498 -164.017641) (xy 6.277695 -163.85989)
			(xy 6.148226 -163.696901) (xy 6.025292 -163.528928) (xy 5.909085 -163.356233) (xy 5.799786 -163.179085)
			(xy 5.697565 -162.997761) (xy 5.602582 -162.812542) (xy 5.514985 -162.623719) (xy 5.43491 -162.431584)
			(xy 5.362483 -162.236438) (xy 5.297815 -162.038585) (xy 5.241009 -161.838334) (xy 5.192151 -161.635996)
			(xy 5.15132 -161.431887) (xy 5.118578 -161.226325) (xy 5.093976 -161.019631) (xy 5.077553 -160.812127)
			(xy 5.069334 -160.604136) (xy 5.068824 -160.50006) (xy 5.069295 -160.399523) (xy 5.076954 -160.198594)
			(xy 5.092271 -159.998103) (xy 5.115222 -159.798343) (xy 5.145774 -159.599603) (xy 5.183884 -159.402172)
			(xy 5.229495 -159.206339) (xy 5.282541 -159.012388) (xy 5.342945 -158.8206) (xy 5.410619 -158.631256)
			(xy 5.485465 -158.44463) (xy 5.567373 -158.260995) (xy 5.656225 -158.080616) (xy 5.751891 -157.903757)
			(xy 5.854232 -157.730675) (xy 5.963099 -157.561622) (xy 6.078335 -157.396844) (xy 6.138672 -157.316424)
			(xy 6.138672 -133.068314) (xy 25.612852 -113.594134) (xy 26.32583 -113.594134) (xy 26.32583 -113.045494)
			(xy 22.27199 -108.991654) (xy 22.261059 -108.981448) (xy 22.234717 -108.96732) (xy 22.205411 -108.961436)
			(xy 22.175658 -108.964299) (xy 22.148012 -108.975665) (xy 22.124848 -108.994557) (xy 22.116034 -109.00664)
			(xy 22.100734 -109.02844) (xy 22.065056 -109.067984) (xy 22.024229 -109.102185) (xy 21.979043 -109.130379)
			(xy 21.930378 -109.152017) (xy 21.879176 -109.166681) (xy 21.826434 -109.174085) (xy 21.799804 -109.174534)
			(xy 21.772552 -109.174049) (xy 21.718602 -109.166293) (xy 21.666306 -109.150938) (xy 21.616726 -109.128298)
			(xy 21.570873 -109.098832) (xy 21.529681 -109.063141) (xy 21.493986 -109.021951) (xy 21.464517 -108.9761)
			(xy 21.441872 -108.926523) (xy 21.426514 -108.874227) (xy 21.418754 -108.820278) (xy 21.418296 -108.793026)
			(xy 21.418757 -108.766395) (xy 21.426156 -108.713651) (xy 21.440814 -108.662447) (xy 21.462447 -108.613777)
			(xy 21.490635 -108.568586) (xy 21.52483 -108.527752) (xy 21.564369 -108.492066) (xy 21.58619 -108.476796)
			(xy 21.598258 -108.467983) (xy 21.617085 -108.444793) (xy 21.62841 -108.417154) (xy 21.63127 -108.387422)
			(xy 21.625419 -108.358131) (xy 21.611357 -108.331778) (xy 21.601176 -108.32084) (xy 21.059648 -107.779312)
			(xy 19.539966 -107.779312) (xy 19.534124 -107.823508) (xy 19.530104 -107.850213) (xy 19.515052 -107.902075)
			(xy 19.492343 -107.951069) (xy 19.462495 -107.996073) (xy 19.426195 -108.036055) (xy 19.384275 -108.070097)
			(xy 19.337695 -108.09742) (xy 19.287523 -108.117396) (xy 19.234911 -108.129568) (xy 19.181064 -108.133657)
			(xy 19.127217 -108.129568) (xy 19.074605 -108.117396) (xy 19.024433 -108.09742) (xy 18.977853 -108.070097)
			(xy 18.935933 -108.036055) (xy 18.899633 -107.996073) (xy 18.869785 -107.951069) (xy 18.847076 -107.902075)
			(xy 18.832024 -107.850213) (xy 18.828004 -107.823508) (xy 18.822162 -107.779312) (xy 6.687312 -107.779312)
			(xy 6.183884 -108.28274) (xy 11.09472 -108.28274) (xy 11.095206 -108.255489) (xy 11.102962 -108.201541)
			(xy 11.118317 -108.149246) (xy 11.140959 -108.099669) (xy 11.170425 -108.053819) (xy 11.206116 -108.012628)
			(xy 11.247307 -107.976937) (xy 11.293157 -107.947471) (xy 11.342734 -107.924829) (xy 11.395029 -107.909474)
			(xy 11.448977 -107.901718) (xy 11.503479 -107.901718) (xy 11.557427 -107.909474) (xy 11.609722 -107.924829)
			(xy 11.659299 -107.947471) (xy 11.705149 -107.976937) (xy 11.74634 -108.012628) (xy 11.782031 -108.053819)
			(xy 11.811497 -108.099669) (xy 11.834139 -108.149246) (xy 11.849494 -108.201541) (xy 11.85725 -108.255489)
			(xy 11.857736 -108.28274) (xy 11.857156 -108.313045) (xy 11.847592 -108.372894) (xy 11.838686 -108.401866)
			(xy 11.834807 -108.415044) (xy 11.833493 -108.442473) (xy 11.839537 -108.469259) (xy 11.852501 -108.493467)
			(xy 11.871449 -108.513343) (xy 11.895009 -108.527449) (xy 11.921476 -108.534767) (xy 11.935206 -108.535216)
			(xy 12.276074 -108.535216) (xy 12.289801 -108.534732) (xy 12.316263 -108.52742) (xy 12.339819 -108.51332)
			(xy 12.358764 -108.49345) (xy 12.371727 -108.469249) (xy 12.37777 -108.442469) (xy 12.376455 -108.415046)
			(xy 12.372594 -108.401866) (xy 12.363691 -108.372893) (xy 12.354126 -108.313044) (xy 12.353544 -108.28274)
			(xy 12.35403 -108.255489) (xy 12.361786 -108.201541) (xy 12.377141 -108.149246) (xy 12.399783 -108.099669)
			(xy 12.429249 -108.053819) (xy 12.46494 -108.012628) (xy 12.506131 -107.976937) (xy 12.551981 -107.947471)
			(xy 12.601558 -107.924829) (xy 12.653853 -107.909474) (xy 12.707801 -107.901718) (xy 12.762303 -107.901718)
			(xy 12.816251 -107.909474) (xy 12.868546 -107.924829) (xy 12.918123 -107.947471) (xy 12.963973 -107.976937)
			(xy 13.005164 -108.012628) (xy 13.040855 -108.053819) (xy 13.070321 -108.099669) (xy 13.092963 -108.149246)
			(xy 13.108318 -108.201541) (xy 13.116074 -108.255489) (xy 13.11656 -108.28274) (xy 14.958314 -108.28274)
			(xy 14.9588 -108.255489) (xy 14.966556 -108.201541) (xy 14.981911 -108.149246) (xy 15.004553 -108.099669)
			(xy 15.034019 -108.053819) (xy 15.06971 -108.012628) (xy 15.110901 -107.976937) (xy 15.156751 -107.947471)
			(xy 15.206328 -107.924829) (xy 15.258623 -107.909474) (xy 15.312571 -107.901718) (xy 15.367073 -107.901718)
			(xy 15.421021 -107.909474) (xy 15.473316 -107.924829) (xy 15.522893 -107.947471) (xy 15.568743 -107.976937)
			(xy 15.609934 -108.012628) (xy 15.645625 -108.053819) (xy 15.675091 -108.099669) (xy 15.697733 -108.149246)
			(xy 15.713088 -108.201541) (xy 15.720844 -108.255489) (xy 15.72133 -108.28274) (xy 15.72075 -108.313045)
			(xy 15.711186 -108.372894) (xy 15.70228 -108.401866) (xy 15.698407 -108.415045) (xy 15.697093 -108.442473)
			(xy 15.703136 -108.469259) (xy 15.7161 -108.493465) (xy 15.735046 -108.513341) (xy 15.758605 -108.527448)
			(xy 15.78507 -108.534766) (xy 15.7988 -108.535216) (xy 16.139668 -108.535216) (xy 16.153395 -108.534727)
			(xy 16.179857 -108.527417) (xy 16.203413 -108.513317) (xy 16.222358 -108.493448) (xy 16.235321 -108.469248)
			(xy 16.241364 -108.442468) (xy 16.240049 -108.415046) (xy 16.236188 -108.401866) (xy 16.227285 -108.372893)
			(xy 16.21772 -108.313044) (xy 16.217138 -108.28274) (xy 16.217624 -108.255489) (xy 16.22538 -108.201541)
			(xy 16.240735 -108.149246) (xy 16.263377 -108.099669) (xy 16.292843 -108.053819) (xy 16.328534 -108.012628)
			(xy 16.369725 -107.976937) (xy 16.415575 -107.947471) (xy 16.465152 -107.924829) (xy 16.517447 -107.909474)
			(xy 16.571395 -107.901718) (xy 16.625897 -107.901718) (xy 16.679845 -107.909474) (xy 16.73214 -107.924829)
			(xy 16.781717 -107.947471) (xy 16.827567 -107.976937) (xy 16.868758 -108.012628) (xy 16.904449 -108.053819)
			(xy 16.933915 -108.099669) (xy 16.956557 -108.149246) (xy 16.971912 -108.201541) (xy 16.979668 -108.255489)
			(xy 16.980154 -108.28274) (xy 16.979629 -108.311628) (xy 16.970924 -108.368746) (xy 16.953706 -108.423897)
			(xy 16.928367 -108.475821) (xy 16.895488 -108.52333) (xy 16.855819 -108.565337) (xy 16.81027 -108.600881)
			(xy 16.785336 -108.61548) (xy 16.772105 -108.623467) (xy 16.750866 -108.645898) (xy 16.737304 -108.673654)
			(xy 16.732661 -108.704194) (xy 16.73736 -108.734726) (xy 16.74368 -108.74883) (xy 16.755977 -108.775094)
			(xy 16.773373 -108.830416) (xy 16.782216 -108.887729) (xy 16.782796 -108.916724) (xy 16.782367 -108.94399)
			(xy 16.7746 -108.997965) (xy 16.759227 -109.050284) (xy 16.736562 -109.099882) (xy 16.707067 -109.145748)
			(xy 16.671342 -109.186948) (xy 16.630116 -109.222641) (xy 16.584227 -109.252101) (xy 16.534612 -109.274728)
			(xy 16.482281 -109.290061) (xy 16.4283 -109.297787) (xy 16.401034 -109.298232) (xy 15.537434 -109.298232)
			(xy 15.510176 -109.297745) (xy 15.456213 -109.289993) (xy 15.403902 -109.274644) (xy 15.354307 -109.252008)
			(xy 15.308436 -109.222546) (xy 15.267224 -109.186859) (xy 15.231508 -109.14567) (xy 15.202016 -109.09982)
			(xy 15.179347 -109.05024) (xy 15.163961 -108.99794) (xy 15.156174 -108.943982) (xy 15.155672 -108.916724)
			(xy 15.156252 -108.887728) (xy 15.165077 -108.830411) (xy 15.182483 -108.775091) (xy 15.194788 -108.74883)
			(xy 15.201061 -108.734711) (xy 15.205755 -108.704191) (xy 15.201116 -108.673663) (xy 15.187566 -108.645916)
			(xy 15.166345 -108.623485) (xy 15.153132 -108.61548) (xy 15.128213 -108.600859) (xy 15.082671 -108.565312)
			(xy 15.043007 -108.523306) (xy 15.01013 -108.475801) (xy 14.984789 -108.423883) (xy 14.967564 -108.368738)
			(xy 14.958849 -108.311626) (xy 14.958314 -108.28274) (xy 13.11656 -108.28274) (xy 13.116032 -108.311628)
			(xy 13.107327 -108.368745) (xy 13.090109 -108.423897) (xy 13.064771 -108.47582) (xy 13.031892 -108.523329)
			(xy 12.992225 -108.565337) (xy 12.946676 -108.600881) (xy 12.921742 -108.61548) (xy 12.908497 -108.623443)
			(xy 12.88727 -108.645887) (xy 12.873717 -108.673648) (xy 12.869076 -108.70419) (xy 12.873771 -108.734723)
			(xy 12.880086 -108.74883) (xy 12.892347 -108.775103) (xy 12.909684 -108.830425) (xy 12.918429 -108.887736)
			(xy 12.918948 -108.916724) (xy 12.918445 -108.943974) (xy 12.910686 -108.997919) (xy 12.89533 -109.050211)
			(xy 12.872689 -109.099786) (xy 12.843224 -109.145634) (xy 12.807534 -109.186823) (xy 12.766347 -109.222514)
			(xy 12.7205 -109.251981) (xy 12.670926 -109.274624) (xy 12.618635 -109.289983) (xy 12.56469 -109.297744)
			(xy 12.53744 -109.298232) (xy 11.67384 -109.298232) (xy 11.646589 -109.297708) (xy 11.592642 -109.289957)
			(xy 11.540346 -109.274607) (xy 11.490768 -109.251971) (xy 11.444916 -109.222509) (xy 11.403723 -109.186822)
			(xy 11.368029 -109.145635) (xy 11.33856 -109.099788) (xy 11.315915 -109.050214) (xy 11.300557 -108.997921)
			(xy 11.292797 -108.943975) (xy 11.292332 -108.916724) (xy 11.292877 -108.887738) (xy 11.301637 -108.830433)
			(xy 11.318945 -108.775106) (xy 11.331194 -108.74883) (xy 11.337465 -108.73471) (xy 11.342159 -108.704191)
			(xy 11.337519 -108.673663) (xy 11.323971 -108.645916) (xy 11.302751 -108.623485) (xy 11.289538 -108.61548)
			(xy 11.26462 -108.600857) (xy 11.219078 -108.565311) (xy 11.179414 -108.523305) (xy 11.146536 -108.475801)
			(xy 11.121195 -108.423882) (xy 11.10397 -108.368738) (xy 11.095255 -108.311626) (xy 11.09472 -108.28274)
			(xy 6.183884 -108.28274) (xy 4.606798 -109.859826) (xy 18.792442 -109.859826) (xy 18.796513 -109.804204)
			(xy 18.808639 -109.749767) (xy 18.828562 -109.697676) (xy 18.855858 -109.649041) (xy 18.889944 -109.604898)
			(xy 18.930093 -109.566189) (xy 18.975451 -109.533738) (xy 19.025051 -109.508237) (xy 19.077835 -109.49023)
			(xy 19.132678 -109.4801) (xy 19.188412 -109.478063) (xy 19.243849 -109.484163) (xy 19.297806 -109.498269)
			(xy 19.349135 -109.520081) (xy 19.396741 -109.549135) (xy 19.439609 -109.58481) (xy 19.476826 -109.626347)
			(xy 19.507599 -109.67286) (xy 19.531271 -109.723357) (xy 19.547339 -109.776764) (xy 19.555459 -109.83194)
			(xy 19.555968 -109.859826) (xy 19.555459 -109.887712) (xy 19.547339 -109.942888) (xy 19.531271 -109.996295)
			(xy 19.507599 -110.046792) (xy 19.476826 -110.093305) (xy 19.439609 -110.134842) (xy 19.396741 -110.170517)
			(xy 19.349135 -110.199571) (xy 19.297806 -110.221383) (xy 19.243849 -110.235489) (xy 19.188412 -110.241589)
			(xy 19.132678 -110.239552) (xy 19.077835 -110.229422) (xy 19.025051 -110.211415) (xy 18.975451 -110.185914)
			(xy 18.930093 -110.153463) (xy 18.889944 -110.114754) (xy 18.855858 -110.070611) (xy 18.828562 -110.021976)
			(xy 18.808639 -109.969885) (xy 18.796513 -109.915448) (xy 18.792442 -109.859826) (xy 4.606798 -109.859826)
			(xy 3.86207 -110.604554) (xy 13.283182 -110.604554) (xy 13.287253 -110.548932) (xy 13.299379 -110.494495)
			(xy 13.319302 -110.442404) (xy 13.346598 -110.393769) (xy 13.380684 -110.349626) (xy 13.420833 -110.310917)
			(xy 13.466191 -110.278466) (xy 13.515791 -110.252965) (xy 13.568575 -110.234958) (xy 13.623418 -110.224828)
			(xy 13.679152 -110.222791) (xy 13.734589 -110.228891) (xy 13.788546 -110.242997) (xy 13.839875 -110.264809)
			(xy 13.887481 -110.293863) (xy 13.930349 -110.329538) (xy 13.967566 -110.371075) (xy 13.998339 -110.417588)
			(xy 14.022011 -110.468085) (xy 14.026465 -110.482888) (xy 15.912082 -110.482888) (xy 15.916153 -110.427266)
			(xy 15.928279 -110.372829) (xy 15.948202 -110.320738) (xy 15.975498 -110.272103) (xy 16.009584 -110.22796)
			(xy 16.049733 -110.189251) (xy 16.095091 -110.1568) (xy 16.144691 -110.131299) (xy 16.197475 -110.113292)
			(xy 16.252318 -110.103162) (xy 16.308052 -110.101125) (xy 16.363489 -110.107225) (xy 16.417446 -110.121331)
			(xy 16.468775 -110.143143) (xy 16.516381 -110.172197) (xy 16.559249 -110.207872) (xy 16.596466 -110.249409)
			(xy 16.627239 -110.295922) (xy 16.650911 -110.346419) (xy 16.666979 -110.399826) (xy 16.675099 -110.455002)
			(xy 16.675608 -110.482888) (xy 16.675099 -110.510774) (xy 16.666979 -110.56595) (xy 16.650911 -110.619357)
			(xy 16.627239 -110.669854) (xy 16.596466 -110.716367) (xy 16.559249 -110.757904) (xy 16.516381 -110.793579)
			(xy 16.468775 -110.822633) (xy 16.417446 -110.844445) (xy 16.363489 -110.858551) (xy 16.308052 -110.864651)
			(xy 16.252318 -110.862614) (xy 16.197475 -110.852484) (xy 16.144691 -110.834477) (xy 16.095091 -110.808976)
			(xy 16.049733 -110.776525) (xy 16.009584 -110.737816) (xy 15.975498 -110.693673) (xy 15.948202 -110.645038)
			(xy 15.928279 -110.592947) (xy 15.916153 -110.53851) (xy 15.912082 -110.482888) (xy 14.026465 -110.482888)
			(xy 14.038079 -110.521492) (xy 14.046199 -110.576668) (xy 14.046708 -110.604554) (xy 14.046199 -110.63244)
			(xy 14.038079 -110.687616) (xy 14.022011 -110.741023) (xy 13.998339 -110.79152) (xy 13.967566 -110.838033)
			(xy 13.933704 -110.875826) (xy 18.799046 -110.875826) (xy 18.803117 -110.820204) (xy 18.815243 -110.765767)
			(xy 18.835166 -110.713676) (xy 18.862462 -110.665041) (xy 18.896548 -110.620898) (xy 18.936697 -110.582189)
			(xy 18.982055 -110.549738) (xy 19.031655 -110.524237) (xy 19.084439 -110.50623) (xy 19.139282 -110.4961)
			(xy 19.195016 -110.494063) (xy 19.250453 -110.500163) (xy 19.30441 -110.514269) (xy 19.355739 -110.536081)
			(xy 19.403345 -110.565135) (xy 19.446213 -110.60081) (xy 19.48343 -110.642347) (xy 19.514203 -110.68886)
			(xy 19.537875 -110.739357) (xy 19.553943 -110.792764) (xy 19.562063 -110.84794) (xy 19.562572 -110.875826)
			(xy 19.562063 -110.903712) (xy 19.553943 -110.958888) (xy 19.537875 -111.012295) (xy 19.514203 -111.062792)
			(xy 19.48343 -111.109305) (xy 19.446213 -111.150842) (xy 19.403345 -111.186517) (xy 19.355739 -111.215571)
			(xy 19.30441 -111.237383) (xy 19.250453 -111.251489) (xy 19.195016 -111.257589) (xy 19.139282 -111.255552)
			(xy 19.084439 -111.245422) (xy 19.031655 -111.227415) (xy 18.982055 -111.201914) (xy 18.936697 -111.169463)
			(xy 18.896548 -111.130754) (xy 18.862462 -111.086611) (xy 18.835166 -111.037976) (xy 18.815243 -110.985885)
			(xy 18.803117 -110.931448) (xy 18.799046 -110.875826) (xy 13.933704 -110.875826) (xy 13.930349 -110.87957)
			(xy 13.887481 -110.915245) (xy 13.839875 -110.944299) (xy 13.788546 -110.966111) (xy 13.734589 -110.980217)
			(xy 13.679152 -110.986317) (xy 13.623418 -110.98428) (xy 13.568575 -110.97415) (xy 13.515791 -110.956143)
			(xy 13.466191 -110.930642) (xy 13.420833 -110.898191) (xy 13.380684 -110.859482) (xy 13.346598 -110.815339)
			(xy 13.319302 -110.766704) (xy 13.299379 -110.714613) (xy 13.287253 -110.660176) (xy 13.283182 -110.604554)
			(xy 3.86207 -110.604554) (xy 3.45059 -111.016034) (xy 3.45059 -111.288068) (xy 7.410702 -111.288068)
			(xy 7.414773 -111.232446) (xy 7.426899 -111.178009) (xy 7.446822 -111.125918) (xy 7.474118 -111.077283)
			(xy 7.508204 -111.03314) (xy 7.548353 -110.994431) (xy 7.593711 -110.96198) (xy 7.643311 -110.936479)
			(xy 7.696095 -110.918472) (xy 7.750938 -110.908342) (xy 7.806672 -110.906305) (xy 7.862109 -110.912405)
			(xy 7.916066 -110.926511) (xy 7.967395 -110.948323) (xy 8.015001 -110.977377) (xy 8.057869 -111.013052)
			(xy 8.095086 -111.054589) (xy 8.125859 -111.101102) (xy 8.149531 -111.151599) (xy 8.165599 -111.205006)
			(xy 8.173719 -111.260182) (xy 8.174228 -111.288068) (xy 8.173719 -111.315954) (xy 8.165599 -111.37113)
			(xy 8.161779 -111.383826) (xy 21.058122 -111.383826) (xy 21.062193 -111.328204) (xy 21.074319 -111.273767)
			(xy 21.094242 -111.221676) (xy 21.121538 -111.173041) (xy 21.155624 -111.128898) (xy 21.195773 -111.090189)
			(xy 21.241131 -111.057738) (xy 21.290731 -111.032237) (xy 21.343515 -111.01423) (xy 21.398358 -111.0041)
			(xy 21.454092 -111.002063) (xy 21.509529 -111.008163) (xy 21.563486 -111.022269) (xy 21.614815 -111.044081)
			(xy 21.662421 -111.073135) (xy 21.705289 -111.10881) (xy 21.742506 -111.150347) (xy 21.773279 -111.19686)
			(xy 21.796951 -111.247357) (xy 21.813019 -111.300764) (xy 21.821139 -111.35594) (xy 21.821648 -111.383826)
			(xy 21.821139 -111.411712) (xy 21.813019 -111.466888) (xy 21.796951 -111.520295) (xy 21.773279 -111.570792)
			(xy 21.742506 -111.617305) (xy 21.705289 -111.658842) (xy 21.662421 -111.694517) (xy 21.614815 -111.723571)
			(xy 21.563486 -111.745383) (xy 21.509529 -111.759489) (xy 21.454092 -111.765589) (xy 21.398358 -111.763552)
			(xy 21.343515 -111.753422) (xy 21.290731 -111.735415) (xy 21.241131 -111.709914) (xy 21.195773 -111.677463)
			(xy 21.155624 -111.638754) (xy 21.121538 -111.594611) (xy 21.094242 -111.545976) (xy 21.074319 -111.493885)
			(xy 21.062193 -111.439448) (xy 21.058122 -111.383826) (xy 8.161779 -111.383826) (xy 8.149531 -111.424537)
			(xy 8.125859 -111.475034) (xy 8.095086 -111.521547) (xy 8.057869 -111.563084) (xy 8.015001 -111.598759)
			(xy 7.967395 -111.627813) (xy 7.916066 -111.649625) (xy 7.862109 -111.663731) (xy 7.806672 -111.669831)
			(xy 7.750938 -111.667794) (xy 7.696095 -111.657664) (xy 7.643311 -111.639657) (xy 7.593711 -111.614156)
			(xy 7.548353 -111.581705) (xy 7.508204 -111.542996) (xy 7.474118 -111.498853) (xy 7.446822 -111.450218)
			(xy 7.426899 -111.398127) (xy 7.414773 -111.34369) (xy 7.410702 -111.288068) (xy 3.45059 -111.288068)
			(xy 3.45059 -113.028222) (xy 13.52753 -113.028222) (xy 13.531601 -112.9726) (xy 13.543727 -112.918163)
			(xy 13.56365 -112.866072) (xy 13.590946 -112.817437) (xy 13.625032 -112.773294) (xy 13.665181 -112.734585)
			(xy 13.710539 -112.702134) (xy 13.760139 -112.676633) (xy 13.812923 -112.658626) (xy 13.867766 -112.648496)
			(xy 13.9235 -112.646459) (xy 13.978937 -112.652559) (xy 14.032894 -112.666665) (xy 14.084223 -112.688477)
			(xy 14.093204 -112.693958) (xy 16.982692 -112.693958) (xy 16.986763 -112.638336) (xy 16.998889 -112.583899)
			(xy 17.018812 -112.531808) (xy 17.046108 -112.483173) (xy 17.080194 -112.43903) (xy 17.120343 -112.400321)
			(xy 17.165701 -112.36787) (xy 17.215301 -112.342369) (xy 17.268085 -112.324362) (xy 17.322928 -112.314232)
			(xy 17.378662 -112.312195) (xy 17.434099 -112.318295) (xy 17.488056 -112.332401) (xy 17.539385 -112.354213)
			(xy 17.586991 -112.383267) (xy 17.629859 -112.418942) (xy 17.667076 -112.460479) (xy 17.697849 -112.506992)
			(xy 17.721521 -112.557489) (xy 17.737589 -112.610896) (xy 17.745709 -112.666072) (xy 17.746218 -112.693958)
			(xy 17.745709 -112.721844) (xy 17.737589 -112.77702) (xy 17.721521 -112.830427) (xy 17.697849 -112.880924)
			(xy 17.667076 -112.927437) (xy 17.629859 -112.968974) (xy 17.586991 -113.004649) (xy 17.539385 -113.033703)
			(xy 17.488056 -113.055515) (xy 17.434099 -113.069621) (xy 17.378662 -113.075721) (xy 17.322928 -113.073684)
			(xy 17.268085 -113.063554) (xy 17.215301 -113.045547) (xy 17.165701 -113.020046) (xy 17.120343 -112.987595)
			(xy 17.080194 -112.948886) (xy 17.046108 -112.904743) (xy 17.018812 -112.856108) (xy 16.998889 -112.804017)
			(xy 16.986763 -112.74958) (xy 16.982692 -112.693958) (xy 14.093204 -112.693958) (xy 14.131829 -112.717531)
			(xy 14.174697 -112.753206) (xy 14.211914 -112.794743) (xy 14.242687 -112.841256) (xy 14.266359 -112.891753)
			(xy 14.282427 -112.94516) (xy 14.290547 -113.000336) (xy 14.291056 -113.028222) (xy 14.290547 -113.056108)
			(xy 14.282427 -113.111284) (xy 14.266359 -113.164691) (xy 14.242687 -113.215188) (xy 14.211914 -113.261701)
			(xy 14.174697 -113.303238) (xy 14.131829 -113.338913) (xy 14.084223 -113.367967) (xy 14.032894 -113.389779)
			(xy 13.978937 -113.403885) (xy 13.9235 -113.409985) (xy 13.867766 -113.407948) (xy 13.812923 -113.397818)
			(xy 13.760139 -113.379811) (xy 13.710539 -113.35431) (xy 13.665181 -113.321859) (xy 13.625032 -113.28315)
			(xy 13.590946 -113.239007) (xy 13.56365 -113.190372) (xy 13.543727 -113.138281) (xy 13.531601 -113.083844)
			(xy 13.52753 -113.028222) (xy 3.45059 -113.028222) (xy 3.45059 -113.633758) (xy 20.320762 -113.633758)
			(xy 20.321222 -113.607132) (xy 20.328633 -113.554398) (xy 20.343306 -113.503207) (xy 20.364955 -113.454553)
			(xy 20.393159 -113.409383) (xy 20.42737 -113.368574) (xy 20.466924 -113.332919) (xy 20.511052 -113.30311)
			(xy 20.558897 -113.279728) (xy 20.609528 -113.263226) (xy 20.661962 -113.253926) (xy 20.688554 -113.252504)
			(xy 20.702729 -113.251584) (xy 20.729727 -113.242771) (xy 20.753259 -113.226874) (xy 20.771513 -113.205118)
			(xy 20.78308 -113.179181) (xy 20.787068 -113.151063) (xy 20.785582 -113.136934) (xy 20.783825 -113.123732)
			(xy 20.781916 -113.097165) (xy 20.781772 -113.083848) (xy 20.782258 -113.056597) (xy 20.790014 -113.002649)
			(xy 20.805369 -112.950354) (xy 20.828011 -112.900777) (xy 20.857477 -112.854927) (xy 20.893168 -112.813736)
			(xy 20.934359 -112.778045) (xy 20.980209 -112.748579) (xy 21.029786 -112.725937) (xy 21.082081 -112.710582)
			(xy 21.136029 -112.702826) (xy 21.190531 -112.702826) (xy 21.244479 -112.710582) (xy 21.296774 -112.725937)
			(xy 21.346351 -112.748579) (xy 21.392201 -112.778045) (xy 21.433392 -112.813736) (xy 21.469083 -112.854927)
			(xy 21.498549 -112.900777) (xy 21.521191 -112.950354) (xy 21.536546 -113.002649) (xy 21.544302 -113.056597)
			(xy 21.544788 -113.083848) (xy 21.544381 -113.110476) (xy 21.536968 -113.163215) (xy 21.522293 -113.21441)
			(xy 21.50064 -113.263067) (xy 21.472431 -113.308239) (xy 21.438213 -113.349049) (xy 21.398653 -113.384705)
			(xy 21.354519 -113.414511) (xy 21.306668 -113.437891) (xy 21.25603 -113.454388) (xy 21.203591 -113.463683)
			(xy 21.176996 -113.465102) (xy 21.162837 -113.466167) (xy 21.135856 -113.474957) (xy 21.112332 -113.490827)
			(xy 21.094079 -113.512553) (xy 21.082502 -113.538461) (xy 21.078495 -113.566553) (xy 21.079968 -113.580672)
			(xy 21.081726 -113.593874) (xy 21.083634 -113.620441) (xy 21.083778 -113.633758) (xy 21.08341 -113.656788)
			(xy 21.077803 -113.702506) (xy 21.072602 -113.724944) (xy 21.06956 -113.739327) (xy 21.070981 -113.76868)
			(xy 21.080672 -113.796424) (xy 21.097836 -113.820279) (xy 21.121063 -113.838283) (xy 21.134578 -113.84407)
			(xy 21.161014 -113.854984) (xy 21.210601 -113.883475) (xy 21.255376 -113.919052) (xy 21.294337 -113.960917)
			(xy 21.326608 -114.008131) (xy 21.351466 -114.059635) (xy 21.368354 -114.114273) (xy 21.376892 -114.170821)
			(xy 21.377402 -114.199416) (xy 21.376916 -114.226667) (xy 21.36916 -114.280615) (xy 21.357427 -114.320574)
			(xy 23.605488 -114.320574) (xy 23.609559 -114.264952) (xy 23.621685 -114.210515) (xy 23.641608 -114.158424)
			(xy 23.668904 -114.109789) (xy 23.70299 -114.065646) (xy 23.743139 -114.026937) (xy 23.788497 -113.994486)
			(xy 23.838097 -113.968985) (xy 23.890881 -113.950978) (xy 23.945724 -113.940848) (xy 24.001458 -113.938811)
			(xy 24.056895 -113.944911) (xy 24.110852 -113.959017) (xy 24.162181 -113.980829) (xy 24.209787 -114.009883)
			(xy 24.252655 -114.045558) (xy 24.289872 -114.087095) (xy 24.320645 -114.133608) (xy 24.344317 -114.184105)
			(xy 24.360385 -114.237512) (xy 24.368505 -114.292688) (xy 24.369014 -114.320574) (xy 24.368505 -114.34846)
			(xy 24.360385 -114.403636) (xy 24.344317 -114.457043) (xy 24.320645 -114.50754) (xy 24.289872 -114.554053)
			(xy 24.252655 -114.59559) (xy 24.209787 -114.631265) (xy 24.162181 -114.660319) (xy 24.110852 -114.682131)
			(xy 24.056895 -114.696237) (xy 24.001458 -114.702337) (xy 23.945724 -114.7003) (xy 23.890881 -114.69017)
			(xy 23.838097 -114.672163) (xy 23.788497 -114.646662) (xy 23.743139 -114.614211) (xy 23.70299 -114.575502)
			(xy 23.668904 -114.531359) (xy 23.641608 -114.482724) (xy 23.621685 -114.430633) (xy 23.609559 -114.376196)
			(xy 23.605488 -114.320574) (xy 21.357427 -114.320574) (xy 21.353805 -114.33291) (xy 21.331163 -114.382487)
			(xy 21.301697 -114.428337) (xy 21.266006 -114.469528) (xy 21.224815 -114.505219) (xy 21.178965 -114.534685)
			(xy 21.129388 -114.557327) (xy 21.077093 -114.572682) (xy 21.023145 -114.580438) (xy 20.968643 -114.580438)
			(xy 20.914695 -114.572682) (xy 20.8624 -114.557327) (xy 20.812823 -114.534685) (xy 20.766973 -114.505219)
			(xy 20.725782 -114.469528) (xy 20.690091 -114.428337) (xy 20.660625 -114.382487) (xy 20.637983 -114.33291)
			(xy 20.622628 -114.280615) (xy 20.614872 -114.226667) (xy 20.614386 -114.199416) (xy 20.614752 -114.176386)
			(xy 20.620351 -114.130666) (xy 20.625562 -114.10823) (xy 20.628551 -114.093837) (xy 20.627148 -114.064489)
			(xy 20.617472 -114.036746) (xy 20.600318 -114.012892) (xy 20.577098 -113.99489) (xy 20.563586 -113.989104)
			(xy 20.537133 -113.978231) (xy 20.487546 -113.949733) (xy 20.442771 -113.914149) (xy 20.403813 -113.872278)
			(xy 20.371544 -113.825058) (xy 20.346689 -113.773549) (xy 20.329805 -113.718906) (xy 20.32127 -113.662354)
			(xy 20.320762 -113.633758) (xy 3.45059 -113.633758) (xy 3.45059 -114.072924) (xy 11.057128 -114.072924)
			(xy 11.057614 -114.045673) (xy 11.06537 -113.991725) (xy 11.080725 -113.93943) (xy 11.103367 -113.889853)
			(xy 11.132833 -113.844003) (xy 11.168524 -113.802812) (xy 11.209715 -113.767121) (xy 11.255565 -113.737655)
			(xy 11.305142 -113.715013) (xy 11.357437 -113.699658) (xy 11.411385 -113.691902) (xy 11.465887 -113.691902)
			(xy 11.519835 -113.699658) (xy 11.57213 -113.715013) (xy 11.621707 -113.737655) (xy 11.667557 -113.767121)
			(xy 11.708748 -113.802812) (xy 11.744439 -113.844003) (xy 11.773905 -113.889853) (xy 11.796547 -113.93943)
			(xy 11.811902 -113.991725) (xy 11.819658 -114.045673) (xy 11.820144 -114.072924) (xy 11.819583 -114.10323)
			(xy 11.810006 -114.163079) (xy 11.801094 -114.19205) (xy 11.797226 -114.205231) (xy 11.795908 -114.232659)
			(xy 11.801949 -114.259446) (xy 11.814911 -114.283653) (xy 11.833858 -114.303529) (xy 11.857417 -114.317636)
			(xy 11.883884 -114.324952) (xy 11.897614 -114.3254) (xy 12.238482 -114.3254) (xy 12.252211 -114.324943)
			(xy 12.278677 -114.317628) (xy 12.302235 -114.303523) (xy 12.32118 -114.283649) (xy 12.334143 -114.259443)
			(xy 12.340183 -114.232658) (xy 12.338865 -114.205232) (xy 12.335002 -114.19205) (xy 12.326096 -114.163078)
			(xy 12.316532 -114.103228) (xy 12.315952 -114.072924) (xy 12.316438 -114.045673) (xy 12.324194 -113.991725)
			(xy 12.339549 -113.93943) (xy 12.362191 -113.889853) (xy 12.391657 -113.844003) (xy 12.427348 -113.802812)
			(xy 12.468539 -113.767121) (xy 12.514389 -113.737655) (xy 12.563966 -113.715013) (xy 12.616261 -113.699658)
			(xy 12.670209 -113.691902) (xy 12.724711 -113.691902) (xy 12.778659 -113.699658) (xy 12.830954 -113.715013)
			(xy 12.880531 -113.737655) (xy 12.926381 -113.767121) (xy 12.967572 -113.802812) (xy 13.003263 -113.844003)
			(xy 13.032729 -113.889853) (xy 13.055371 -113.93943) (xy 13.070726 -113.991725) (xy 13.078482 -114.045673)
			(xy 13.078968 -114.072924) (xy 13.078423 -114.101812) (xy 13.069721 -114.158928) (xy 13.052506 -114.214078)
			(xy 13.02717 -114.266002) (xy 12.994294 -114.313511) (xy 12.954629 -114.355519) (xy 12.909083 -114.391065)
			(xy 12.88415 -114.405664) (xy 12.870918 -114.413645) (xy 12.84969 -114.436084) (xy 12.836134 -114.46384)
			(xy 12.83149 -114.494378) (xy 12.836181 -114.524908) (xy 12.842494 -114.539014) (xy 12.854784 -114.565274)
			(xy 12.87211 -114.620602) (xy 12.880843 -114.677919) (xy 12.881356 -114.706908) (xy 12.88083 -114.734157)
			(xy 12.873073 -114.788101) (xy 12.85772 -114.840392) (xy 12.835081 -114.889966) (xy 12.805619 -114.935814)
			(xy 12.769931 -114.977003) (xy 12.728746 -115.012695) (xy 12.682901 -115.042162) (xy 12.63333 -115.064806)
			(xy 12.58104 -115.080165) (xy 12.527097 -115.087927) (xy 12.499848 -115.088416) (xy 11.636248 -115.088416)
			(xy 11.608997 -115.0879) (xy 11.555048 -115.08015) (xy 11.502752 -115.0648) (xy 11.453172 -115.042164)
			(xy 11.407319 -115.012702) (xy 11.366126 -114.977013) (xy 11.330432 -114.935826) (xy 11.300963 -114.889977)
			(xy 11.278319 -114.840401) (xy 11.262962 -114.788107) (xy 11.255204 -114.734159) (xy 11.25474 -114.706908)
			(xy 11.255278 -114.677922) (xy 11.264041 -114.620616) (xy 11.281352 -114.565289) (xy 11.293602 -114.539014)
			(xy 11.299887 -114.5249) (xy 11.304577 -114.494378) (xy 11.299934 -114.463849) (xy 11.286382 -114.436101)
			(xy 11.26516 -114.413669) (xy 11.251946 -114.405664) (xy 11.227023 -114.391049) (xy 11.18148 -114.355502)
			(xy 11.141816 -114.313495) (xy 11.108939 -114.265989) (xy 11.083598 -114.21407) (xy 11.066375 -114.158923)
			(xy 11.057662 -114.101811) (xy 11.057128 -114.072924) (xy 3.45059 -114.072924) (xy 3.45059 -118.46179)
			(xy 18.155156 -118.46179) (xy 18.159227 -118.406168) (xy 18.171353 -118.351731) (xy 18.191276 -118.29964)
			(xy 18.218572 -118.251005) (xy 18.252658 -118.206862) (xy 18.292807 -118.168153) (xy 18.338165 -118.135702)
			(xy 18.387765 -118.110201) (xy 18.440549 -118.092194) (xy 18.495392 -118.082064) (xy 18.551126 -118.080027)
			(xy 18.606563 -118.086127) (xy 18.66052 -118.100233) (xy 18.711849 -118.122045) (xy 18.759455 -118.151099)
			(xy 18.802323 -118.186774) (xy 18.83954 -118.228311) (xy 18.870313 -118.274824) (xy 18.893985 -118.325321)
			(xy 18.910053 -118.378728) (xy 18.918173 -118.433904) (xy 18.918682 -118.46179) (xy 18.918173 -118.489676)
			(xy 18.910053 -118.544852) (xy 18.893985 -118.598259) (xy 18.870313 -118.648756) (xy 18.83954 -118.695269)
			(xy 18.802323 -118.736806) (xy 18.759455 -118.772481) (xy 18.711849 -118.801535) (xy 18.66052 -118.823347)
			(xy 18.606563 -118.837453) (xy 18.551126 -118.843553) (xy 18.495392 -118.841516) (xy 18.440549 -118.831386)
			(xy 18.387765 -118.813379) (xy 18.338165 -118.787878) (xy 18.292807 -118.755427) (xy 18.252658 -118.716718)
			(xy 18.218572 -118.672575) (xy 18.191276 -118.62394) (xy 18.171353 -118.571849) (xy 18.159227 -118.517412)
			(xy 18.155156 -118.46179) (xy 3.45059 -118.46179) (xy 3.45059 -167.023796) (xy 5.769175 -169.342381)
			(xy 7.592038 -169.342381) (xy 7.592038 -169.287879) (xy 7.599794 -169.233931) (xy 7.615149 -169.181636)
			(xy 7.637791 -169.132059) (xy 7.667257 -169.086209) (xy 7.702948 -169.045018) (xy 7.744139 -169.009327)
			(xy 7.789989 -168.979861) (xy 7.839566 -168.957219) (xy 7.891861 -168.941864) (xy 7.945809 -168.934108)
			(xy 7.97306 -168.933622) (xy 7.999441 -168.934032) (xy 8.0517 -168.941293) (xy 8.102462 -168.955682)
			(xy 8.150758 -168.976926) (xy 8.195667 -169.004619) (xy 8.236335 -169.038233) (xy 8.271986 -169.077127)
			(xy 8.30194 -169.120561) (xy 8.314182 -169.143934) (xy 8.320884 -169.156293) (xy 8.339859 -169.177021)
			(xy 8.363773 -169.191783) (xy 8.390809 -169.199455) (xy 8.418911 -169.199455) (xy 8.445947 -169.191783)
			(xy 8.469861 -169.177021) (xy 8.488836 -169.156293) (xy 8.495538 -169.143934) (xy 8.507781 -169.120565)
			(xy 8.537746 -169.077144) (xy 8.573402 -169.038261) (xy 8.614072 -169.004656) (xy 8.65898 -168.976969)
			(xy 8.707272 -168.955728) (xy 8.758028 -168.941337) (xy 8.810282 -168.934069) (xy 8.83666 -168.933622)
			(xy 8.863911 -168.934108) (xy 8.917859 -168.941864) (xy 8.970154 -168.957219) (xy 9.019731 -168.979861)
			(xy 9.065581 -169.009327) (xy 9.106772 -169.045018) (xy 9.142463 -169.086209) (xy 9.171929 -169.132059)
			(xy 9.194571 -169.181636) (xy 9.209926 -169.233931) (xy 9.217682 -169.287879) (xy 9.217682 -169.342381)
			(xy 9.209926 -169.396329) (xy 9.194571 -169.448624) (xy 9.171929 -169.498201) (xy 9.142463 -169.544051)
			(xy 9.106772 -169.585242) (xy 9.065581 -169.620933) (xy 9.019731 -169.650399) (xy 8.970154 -169.673041)
			(xy 8.917859 -169.688396) (xy 8.863911 -169.696152) (xy 8.83666 -169.696638) (xy 8.810281 -169.696179)
			(xy 8.758025 -169.688922) (xy 8.707267 -169.674537) (xy 8.658972 -169.6533) (xy 8.614063 -169.625614)
			(xy 8.573394 -169.592008) (xy 8.537741 -169.553121) (xy 8.507782 -169.509695) (xy 8.495538 -169.486326)
			(xy 8.488836 -169.473967) (xy 8.469861 -169.453239) (xy 8.445947 -169.438477) (xy 8.418911 -169.430805)
			(xy 8.390809 -169.430805) (xy 8.363773 -169.438477) (xy 8.339859 -169.453239) (xy 8.320884 -169.473967)
			(xy 8.314182 -169.486326) (xy 8.301906 -169.509677) (xy 8.271947 -169.5531) (xy 8.236297 -169.591985)
			(xy 8.195632 -169.625591) (xy 8.150728 -169.65328) (xy 8.102441 -169.674524) (xy 8.051688 -169.688918)
			(xy 7.999437 -169.696189) (xy 7.97306 -169.696638) (xy 7.945809 -169.696152) (xy 7.891861 -169.688396)
			(xy 7.839566 -169.673041) (xy 7.789989 -169.650399) (xy 7.744139 -169.620933) (xy 7.702948 -169.585242)
			(xy 7.667257 -169.544051) (xy 7.637791 -169.498201) (xy 7.615149 -169.448624) (xy 7.599794 -169.396329)
			(xy 7.592038 -169.342381) (xy 5.769175 -169.342381) (xy 6.346444 -169.91965) (xy 6.356175 -169.928765)
			(xy 6.379256 -169.942091) (xy 6.405 -169.948989) (xy 6.431652 -169.948989) (xy 6.457396 -169.942091)
			(xy 6.480477 -169.928765) (xy 6.490208 -169.91965) (xy 6.51181 -169.898804) (xy 6.560351 -169.863485)
			(xy 6.613823 -169.8362) (xy 6.670907 -169.817623) (xy 6.730195 -169.808211) (xy 6.76021 -169.807636)
			(xy 6.787461 -169.8081) (xy 6.841409 -169.815858) (xy 6.893703 -169.831216) (xy 6.943279 -169.853859)
			(xy 6.989128 -169.883328) (xy 7.030316 -169.919023) (xy 7.066004 -169.960216) (xy 7.095466 -170.006069)
			(xy 7.118103 -170.055648) (xy 7.133453 -170.107944) (xy 7.141204 -170.161893) (xy 7.141718 -170.189144)
			(xy 7.141162 -170.219162) (xy 7.131763 -170.278456) (xy 7.113189 -170.335546) (xy 7.085898 -170.389019)
			(xy 7.050566 -170.437556) (xy 7.029704 -170.459146) (xy 7.020593 -170.468877) (xy 7.007276 -170.491957)
			(xy 7.000385 -170.517697) (xy 7.000391 -170.544343) (xy 7.007291 -170.57008) (xy 7.020618 -170.593155)
			(xy 7.029704 -170.60291) (xy 8.113522 -171.686728) (xy 9.37514 -171.686728) (xy 10.25271 -172.564298)
			(xy 10.25271 -178.584606) (xy 7.564882 -181.272434) (xy 7.564882 -187.6298) (xy 14.730982 -187.6298)
			(xy 14.735053 -187.574178) (xy 14.747179 -187.519741) (xy 14.767102 -187.46765) (xy 14.794398 -187.419015)
			(xy 14.828484 -187.374872) (xy 14.868633 -187.336163) (xy 14.913991 -187.303712) (xy 14.963591 -187.278211)
			(xy 15.016375 -187.260204) (xy 15.071218 -187.250074) (xy 15.126952 -187.248037) (xy 15.182389 -187.254137)
			(xy 15.236346 -187.268243) (xy 15.287675 -187.290055) (xy 15.335281 -187.319109) (xy 15.378149 -187.354784)
			(xy 15.415366 -187.396321) (xy 15.446139 -187.442834) (xy 15.469811 -187.493331) (xy 15.485879 -187.546738)
			(xy 15.493999 -187.601914) (xy 15.494508 -187.6298) (xy 15.493999 -187.657686) (xy 15.485879 -187.712862)
			(xy 15.469811 -187.766269) (xy 15.446139 -187.816766) (xy 15.415366 -187.863279) (xy 15.378149 -187.904816)
			(xy 15.335281 -187.940491) (xy 15.287675 -187.969545) (xy 15.236346 -187.991357) (xy 15.182389 -188.005463)
			(xy 15.126952 -188.011563) (xy 15.071218 -188.009526) (xy 15.016375 -187.999396) (xy 14.963591 -187.981389)
			(xy 14.913991 -187.955888) (xy 14.868633 -187.923437) (xy 14.828484 -187.884728) (xy 14.794398 -187.840585)
			(xy 14.767102 -187.79195) (xy 14.747179 -187.739859) (xy 14.735053 -187.685422) (xy 14.730982 -187.6298)
			(xy 7.564882 -187.6298) (xy 7.564882 -189.158996) (xy 8.653756 -189.158996) (xy 8.653756 -189.074444)
			(xy 8.661558 -188.990252) (xy 8.677094 -188.907139) (xy 8.700233 -188.825814) (xy 8.730777 -188.746971)
			(xy 8.768466 -188.671282) (xy 8.812977 -188.599394) (xy 8.863931 -188.531919) (xy 8.920894 -188.469434)
			(xy 8.983379 -188.412471) (xy 9.050854 -188.361517) (xy 9.122742 -188.317006) (xy 9.198431 -188.279317)
			(xy 9.277274 -188.248773) (xy 9.358599 -188.225634) (xy 9.441712 -188.210098) (xy 9.525904 -188.202296)
			(xy 9.56818 -188.201808) (xy 10.81278 -188.201808) (xy 10.855056 -188.202304) (xy 10.939247 -188.210106)
			(xy 11.02236 -188.225642) (xy 11.103684 -188.248781) (xy 11.182526 -188.279325) (xy 11.258214 -188.317013)
			(xy 11.330102 -188.361523) (xy 11.397576 -188.412477) (xy 11.46006 -188.46944) (xy 11.517023 -188.531924)
			(xy 11.567977 -188.599398) (xy 11.612487 -188.671286) (xy 11.650175 -188.746974) (xy 11.680719 -188.825816)
			(xy 11.703858 -188.90714) (xy 11.719394 -188.990253) (xy 11.727196 -189.074444) (xy 11.727196 -189.158996)
			(xy 16.197556 -189.158996) (xy 16.197556 -189.074444) (xy 16.205358 -188.990252) (xy 16.220894 -188.907139)
			(xy 16.244033 -188.825814) (xy 16.274577 -188.746971) (xy 16.312266 -188.671282) (xy 16.356777 -188.599394)
			(xy 16.407731 -188.531919) (xy 16.464694 -188.469434) (xy 16.527179 -188.412471) (xy 16.594654 -188.361517)
			(xy 16.666542 -188.317006) (xy 16.742231 -188.279317) (xy 16.821074 -188.248773) (xy 16.902399 -188.225634)
			(xy 16.985512 -188.210098) (xy 17.069704 -188.202296) (xy 17.11198 -188.201808) (xy 18.35658 -188.201808)
			(xy 18.398856 -188.202304) (xy 18.483047 -188.210106) (xy 18.56616 -188.225642) (xy 18.647484 -188.248781)
			(xy 18.726326 -188.279325) (xy 18.802014 -188.317013) (xy 18.873902 -188.361523) (xy 18.941376 -188.412477)
			(xy 19.00386 -188.46944) (xy 19.060823 -188.531924) (xy 19.111777 -188.599398) (xy 19.156287 -188.671286)
			(xy 19.193975 -188.746974) (xy 19.224519 -188.825816) (xy 19.247658 -188.90714) (xy 19.263194 -188.990253)
			(xy 19.270996 -189.074444) (xy 19.270996 -189.158996) (xy 23.741356 -189.158996) (xy 23.741356 -189.074444)
			(xy 23.749158 -188.990252) (xy 23.764694 -188.907139) (xy 23.787833 -188.825814) (xy 23.818377 -188.746971)
			(xy 23.856066 -188.671282) (xy 23.900577 -188.599394) (xy 23.951531 -188.531919) (xy 24.008494 -188.469434)
			(xy 24.070979 -188.412471) (xy 24.138454 -188.361517) (xy 24.210342 -188.317006) (xy 24.286031 -188.279317)
			(xy 24.364874 -188.248773) (xy 24.446199 -188.225634) (xy 24.529312 -188.210098) (xy 24.613504 -188.202296)
			(xy 24.65578 -188.201808) (xy 25.90038 -188.201808) (xy 25.942658 -188.202248) (xy 26.026854 -188.210049)
			(xy 26.109971 -188.225584) (xy 26.1913 -188.248723) (xy 26.270147 -188.279267) (xy 26.345839 -188.316955)
			(xy 26.417731 -188.361468) (xy 26.485209 -188.412423) (xy 26.547698 -188.469388) (xy 26.604664 -188.531875)
			(xy 26.655621 -188.599352) (xy 26.700135 -188.671243) (xy 26.737825 -188.746935) (xy 26.768371 -188.825781)
			(xy 26.791511 -188.90711) (xy 26.807049 -188.990226) (xy 26.814851 -189.074422) (xy 26.814851 -189.158975)
			(xy 31.285196 -189.158975) (xy 31.285196 -189.074425) (xy 31.292997 -188.990236) (xy 31.308533 -188.907126)
			(xy 31.331671 -188.825804) (xy 31.362213 -188.746963) (xy 31.3999 -188.671277) (xy 31.444409 -188.599391)
			(xy 31.495361 -188.531919) (xy 31.552321 -188.469435) (xy 31.614803 -188.412474) (xy 31.682275 -188.36152)
			(xy 31.75416 -188.31701) (xy 31.829845 -188.279321) (xy 31.908685 -188.248777) (xy 31.990007 -188.225638)
			(xy 32.073116 -188.2101) (xy 32.157305 -188.202297) (xy 32.19958 -188.201808) (xy 33.44418 -188.201808)
			(xy 33.486458 -188.202248) (xy 33.570654 -188.210049) (xy 33.653771 -188.225584) (xy 33.7351 -188.248723)
			(xy 33.813947 -188.279267) (xy 33.889639 -188.316955) (xy 33.961531 -188.361468) (xy 34.029009 -188.412423)
			(xy 34.091498 -188.469388) (xy 34.148464 -188.531875) (xy 34.199421 -188.599352) (xy 34.243935 -188.671243)
			(xy 34.281625 -188.746935) (xy 34.312171 -188.825781) (xy 34.335311 -188.90711) (xy 34.350849 -188.990226)
			(xy 34.358651 -189.074422) (xy 34.358651 -189.158975) (xy 38.828996 -189.158975) (xy 38.828996 -189.074425)
			(xy 38.836797 -188.990236) (xy 38.852333 -188.907126) (xy 38.875471 -188.825804) (xy 38.906013 -188.746963)
			(xy 38.9437 -188.671277) (xy 38.988209 -188.599391) (xy 39.039161 -188.531919) (xy 39.096121 -188.469435)
			(xy 39.158603 -188.412474) (xy 39.226075 -188.36152) (xy 39.29796 -188.31701) (xy 39.373645 -188.279321)
			(xy 39.452485 -188.248777) (xy 39.533807 -188.225638) (xy 39.616916 -188.2101) (xy 39.701105 -188.202297)
			(xy 39.74338 -188.201808) (xy 40.98798 -188.201808) (xy 41.030258 -188.202248) (xy 41.114454 -188.210049)
			(xy 41.197571 -188.225584) (xy 41.2789 -188.248723) (xy 41.357747 -188.279267) (xy 41.433439 -188.316955)
			(xy 41.505331 -188.361468) (xy 41.572809 -188.412423) (xy 41.635298 -188.469388) (xy 41.692264 -188.531875)
			(xy 41.743221 -188.599352) (xy 41.787735 -188.671243) (xy 41.825425 -188.746935) (xy 41.855971 -188.825781)
			(xy 41.879111 -188.90711) (xy 41.894649 -188.990226) (xy 41.902451 -189.074422) (xy 41.902451 -189.158975)
			(xy 46.372796 -189.158975) (xy 46.372796 -189.074425) (xy 46.380597 -188.990236) (xy 46.396133 -188.907126)
			(xy 46.419271 -188.825804) (xy 46.449813 -188.746963) (xy 46.4875 -188.671277) (xy 46.532009 -188.599391)
			(xy 46.582961 -188.531919) (xy 46.639921 -188.469435) (xy 46.702403 -188.412474) (xy 46.769875 -188.36152)
			(xy 46.84176 -188.31701) (xy 46.917445 -188.279321) (xy 46.996285 -188.248777) (xy 47.077607 -188.225638)
			(xy 47.160716 -188.2101) (xy 47.244905 -188.202297) (xy 47.28718 -188.201808) (xy 48.53178 -188.201808)
			(xy 48.574058 -188.202248) (xy 48.658254 -188.210049) (xy 48.741371 -188.225584) (xy 48.8227 -188.248723)
			(xy 48.901547 -188.279267) (xy 48.977239 -188.316955) (xy 49.049131 -188.361468) (xy 49.116609 -188.412423)
			(xy 49.179098 -188.469388) (xy 49.236064 -188.531875) (xy 49.287021 -188.599352) (xy 49.331535 -188.671243)
			(xy 49.369225 -188.746935) (xy 49.399771 -188.825781) (xy 49.422911 -188.90711) (xy 49.438449 -188.990226)
			(xy 49.446251 -189.074422) (xy 49.446251 -189.158975) (xy 53.916596 -189.158975) (xy 53.916596 -189.074425)
			(xy 53.924397 -188.990236) (xy 53.939933 -188.907126) (xy 53.963071 -188.825804) (xy 53.993613 -188.746963)
			(xy 54.0313 -188.671277) (xy 54.075809 -188.599391) (xy 54.126761 -188.531919) (xy 54.183721 -188.469435)
			(xy 54.246203 -188.412474) (xy 54.313675 -188.36152) (xy 54.38556 -188.31701) (xy 54.461245 -188.279321)
			(xy 54.540085 -188.248777) (xy 54.621407 -188.225638) (xy 54.704516 -188.2101) (xy 54.788705 -188.202297)
			(xy 54.83098 -188.201808) (xy 56.07558 -188.201808) (xy 56.117858 -188.202248) (xy 56.202054 -188.210049)
			(xy 56.285171 -188.225584) (xy 56.3665 -188.248723) (xy 56.445347 -188.279267) (xy 56.521039 -188.316955)
			(xy 56.592931 -188.361468) (xy 56.660409 -188.412423) (xy 56.722898 -188.469388) (xy 56.779864 -188.531875)
			(xy 56.830821 -188.599352) (xy 56.875335 -188.671243) (xy 56.913025 -188.746935) (xy 56.943571 -188.825781)
			(xy 56.966711 -188.90711) (xy 56.982249 -188.990226) (xy 56.990051 -189.074422) (xy 56.990051 -189.158978)
			(xy 56.982249 -189.243174) (xy 56.966711 -189.32629) (xy 56.943571 -189.407619) (xy 56.913025 -189.486465)
			(xy 56.875335 -189.562157) (xy 56.830821 -189.634048) (xy 56.779864 -189.701525) (xy 56.722898 -189.764012)
			(xy 56.660409 -189.820977) (xy 56.592931 -189.871932) (xy 56.521039 -189.916445) (xy 56.445347 -189.954133)
			(xy 56.3665 -189.984677) (xy 56.285171 -190.007816) (xy 56.202054 -190.023351) (xy 56.117858 -190.031152)
			(xy 56.07558 -190.031624) (xy 54.83098 -190.031624) (xy 54.788705 -190.031103) (xy 54.704516 -190.0233)
			(xy 54.621407 -190.007762) (xy 54.540085 -189.984623) (xy 54.461245 -189.954079) (xy 54.38556 -189.91639)
			(xy 54.313675 -189.87188) (xy 54.246203 -189.820926) (xy 54.183721 -189.763965) (xy 54.126761 -189.701481)
			(xy 54.075809 -189.634009) (xy 54.0313 -189.562123) (xy 53.993613 -189.486437) (xy 53.963071 -189.407596)
			(xy 53.939933 -189.326274) (xy 53.924397 -189.243164) (xy 53.916596 -189.158975) (xy 49.446251 -189.158975)
			(xy 49.446251 -189.158978) (xy 49.438449 -189.243174) (xy 49.422911 -189.32629) (xy 49.399771 -189.407619)
			(xy 49.369225 -189.486465) (xy 49.331535 -189.562157) (xy 49.287021 -189.634048) (xy 49.236064 -189.701525)
			(xy 49.179098 -189.764012) (xy 49.116609 -189.820977) (xy 49.049131 -189.871932) (xy 48.977239 -189.916445)
			(xy 48.901547 -189.954133) (xy 48.8227 -189.984677) (xy 48.741371 -190.007816) (xy 48.658254 -190.023351)
			(xy 48.574058 -190.031152) (xy 48.53178 -190.031624) (xy 47.28718 -190.031624) (xy 47.244905 -190.031103)
			(xy 47.160716 -190.0233) (xy 47.077607 -190.007762) (xy 46.996285 -189.984623) (xy 46.917445 -189.954079)
			(xy 46.84176 -189.91639) (xy 46.769875 -189.87188) (xy 46.702403 -189.820926) (xy 46.639921 -189.763965)
			(xy 46.582961 -189.701481) (xy 46.532009 -189.634009) (xy 46.4875 -189.562123) (xy 46.449813 -189.486437)
			(xy 46.419271 -189.407596) (xy 46.396133 -189.326274) (xy 46.380597 -189.243164) (xy 46.372796 -189.158975)
			(xy 41.902451 -189.158975) (xy 41.902451 -189.158978) (xy 41.894649 -189.243174) (xy 41.879111 -189.32629)
			(xy 41.855971 -189.407619) (xy 41.825425 -189.486465) (xy 41.787735 -189.562157) (xy 41.743221 -189.634048)
			(xy 41.692264 -189.701525) (xy 41.635298 -189.764012) (xy 41.572809 -189.820977) (xy 41.505331 -189.871932)
			(xy 41.433439 -189.916445) (xy 41.357747 -189.954133) (xy 41.2789 -189.984677) (xy 41.197571 -190.007816)
			(xy 41.114454 -190.023351) (xy 41.030258 -190.031152) (xy 40.98798 -190.031624) (xy 39.74338 -190.031624)
			(xy 39.701105 -190.031103) (xy 39.616916 -190.0233) (xy 39.533807 -190.007762) (xy 39.452485 -189.984623)
			(xy 39.373645 -189.954079) (xy 39.29796 -189.91639) (xy 39.226075 -189.87188) (xy 39.158603 -189.820926)
			(xy 39.096121 -189.763965) (xy 39.039161 -189.701481) (xy 38.988209 -189.634009) (xy 38.9437 -189.562123)
			(xy 38.906013 -189.486437) (xy 38.875471 -189.407596) (xy 38.852333 -189.326274) (xy 38.836797 -189.243164)
			(xy 38.828996 -189.158975) (xy 34.358651 -189.158975) (xy 34.358651 -189.158978) (xy 34.350849 -189.243174)
			(xy 34.335311 -189.32629) (xy 34.312171 -189.407619) (xy 34.281625 -189.486465) (xy 34.243935 -189.562157)
			(xy 34.199421 -189.634048) (xy 34.148464 -189.701525) (xy 34.091498 -189.764012) (xy 34.029009 -189.820977)
			(xy 33.961531 -189.871932) (xy 33.889639 -189.916445) (xy 33.813947 -189.954133) (xy 33.7351 -189.984677)
			(xy 33.653771 -190.007816) (xy 33.570654 -190.023351) (xy 33.486458 -190.031152) (xy 33.44418 -190.031624)
			(xy 32.19958 -190.031624) (xy 32.157305 -190.031103) (xy 32.073116 -190.0233) (xy 31.990007 -190.007762)
			(xy 31.908685 -189.984623) (xy 31.829845 -189.954079) (xy 31.75416 -189.91639) (xy 31.682275 -189.87188)
			(xy 31.614803 -189.820926) (xy 31.552321 -189.763965) (xy 31.495361 -189.701481) (xy 31.444409 -189.634009)
			(xy 31.3999 -189.562123) (xy 31.362213 -189.486437) (xy 31.331671 -189.407596) (xy 31.308533 -189.326274)
			(xy 31.292997 -189.243164) (xy 31.285196 -189.158975) (xy 26.814851 -189.158975) (xy 26.814851 -189.158978)
			(xy 26.807049 -189.243174) (xy 26.791511 -189.32629) (xy 26.768371 -189.407619) (xy 26.737825 -189.486465)
			(xy 26.700135 -189.562157) (xy 26.655621 -189.634048) (xy 26.604664 -189.701525) (xy 26.547698 -189.764012)
			(xy 26.485209 -189.820977) (xy 26.417731 -189.871932) (xy 26.345839 -189.916445) (xy 26.270147 -189.954133)
			(xy 26.1913 -189.984677) (xy 26.109971 -190.007816) (xy 26.026854 -190.023351) (xy 25.942658 -190.031152)
			(xy 25.90038 -190.031624) (xy 24.65578 -190.031624) (xy 24.613504 -190.031144) (xy 24.529312 -190.023342)
			(xy 24.446199 -190.007806) (xy 24.364874 -189.984667) (xy 24.286031 -189.954123) (xy 24.210342 -189.916434)
			(xy 24.138454 -189.871923) (xy 24.070979 -189.820969) (xy 24.008494 -189.764006) (xy 23.951531 -189.701521)
			(xy 23.900577 -189.634046) (xy 23.856066 -189.562158) (xy 23.818377 -189.486469) (xy 23.787833 -189.407626)
			(xy 23.764694 -189.326301) (xy 23.749158 -189.243188) (xy 23.741356 -189.158996) (xy 19.270996 -189.158996)
			(xy 19.263194 -189.243187) (xy 19.247658 -189.3263) (xy 19.224519 -189.407624) (xy 19.193975 -189.486466)
			(xy 19.156287 -189.562154) (xy 19.111777 -189.634042) (xy 19.060823 -189.701516) (xy 19.00386 -189.764)
			(xy 18.941376 -189.820963) (xy 18.873902 -189.871917) (xy 18.802014 -189.916427) (xy 18.726326 -189.954115)
			(xy 18.647484 -189.984659) (xy 18.56616 -190.007798) (xy 18.483047 -190.023334) (xy 18.398856 -190.031136)
			(xy 18.35658 -190.031624) (xy 17.11198 -190.031624) (xy 17.069704 -190.031144) (xy 16.985512 -190.023342)
			(xy 16.902399 -190.007806) (xy 16.821074 -189.984667) (xy 16.742231 -189.954123) (xy 16.666542 -189.916434)
			(xy 16.594654 -189.871923) (xy 16.527179 -189.820969) (xy 16.464694 -189.764006) (xy 16.407731 -189.701521)
			(xy 16.356777 -189.634046) (xy 16.312266 -189.562158) (xy 16.274577 -189.486469) (xy 16.244033 -189.407626)
			(xy 16.220894 -189.326301) (xy 16.205358 -189.243188) (xy 16.197556 -189.158996) (xy 11.727196 -189.158996)
			(xy 11.719394 -189.243187) (xy 11.703858 -189.3263) (xy 11.680719 -189.407624) (xy 11.650175 -189.486466)
			(xy 11.612487 -189.562154) (xy 11.567977 -189.634042) (xy 11.517023 -189.701516) (xy 11.46006 -189.764)
			(xy 11.397576 -189.820963) (xy 11.330102 -189.871917) (xy 11.258214 -189.916427) (xy 11.182526 -189.954115)
			(xy 11.103684 -189.984659) (xy 11.02236 -190.007798) (xy 10.939247 -190.023334) (xy 10.855056 -190.031136)
			(xy 10.81278 -190.031624) (xy 9.56818 -190.031624) (xy 9.525904 -190.031144) (xy 9.441712 -190.023342)
			(xy 9.358599 -190.007806) (xy 9.277274 -189.984667) (xy 9.198431 -189.954123) (xy 9.122742 -189.916434)
			(xy 9.050854 -189.871923) (xy 8.983379 -189.820969) (xy 8.920894 -189.764006) (xy 8.863931 -189.701521)
			(xy 8.812977 -189.634046) (xy 8.768466 -189.562158) (xy 8.730777 -189.486469) (xy 8.700233 -189.407626)
			(xy 8.677094 -189.326301) (xy 8.661558 -189.243188) (xy 8.653756 -189.158996) (xy 7.564882 -189.158996)
			(xy 7.564882 -190.827152) (xy 8.29056 -191.55283) (xy 14.517114 -191.55283) (xy 14.521185 -191.497208)
			(xy 14.533311 -191.442771) (xy 14.553234 -191.39068) (xy 14.58053 -191.342045) (xy 14.614616 -191.297902)
			(xy 14.654765 -191.259193) (xy 14.700123 -191.226742) (xy 14.749723 -191.201241) (xy 14.802507 -191.183234)
			(xy 14.85735 -191.173104) (xy 14.913084 -191.171067) (xy 14.968521 -191.177167) (xy 15.022478 -191.191273)
			(xy 15.073807 -191.213085) (xy 15.121413 -191.242139) (xy 15.164281 -191.277814) (xy 15.201498 -191.319351)
			(xy 15.232271 -191.365864) (xy 15.255943 -191.416361) (xy 15.272011 -191.469768) (xy 15.280131 -191.524944)
			(xy 15.28064 -191.55283) (xy 15.280131 -191.580716) (xy 15.272011 -191.635892) (xy 15.255943 -191.689299)
			(xy 15.250737 -191.700404) (xy 18.352768 -191.700404) (xy 18.356839 -191.644782) (xy 18.368965 -191.590345)
			(xy 18.388888 -191.538254) (xy 18.416184 -191.489619) (xy 18.45027 -191.445476) (xy 18.490419 -191.406767)
			(xy 18.535777 -191.374316) (xy 18.585377 -191.348815) (xy 18.638161 -191.330808) (xy 18.693004 -191.320678)
			(xy 18.748738 -191.318641) (xy 18.804175 -191.324741) (xy 18.858132 -191.338847) (xy 18.909461 -191.360659)
			(xy 18.957067 -191.389713) (xy 18.999935 -191.425388) (xy 19.037152 -191.466925) (xy 19.067925 -191.513438)
			(xy 19.091597 -191.563935) (xy 19.107665 -191.617342) (xy 19.115785 -191.672518) (xy 19.116294 -191.700404)
			(xy 19.115785 -191.72829) (xy 19.107665 -191.783466) (xy 19.091597 -191.836873) (xy 19.067925 -191.88737)
			(xy 19.037152 -191.933883) (xy 18.999935 -191.97542) (xy 18.957067 -192.011095) (xy 18.909461 -192.040149)
			(xy 18.858132 -192.061961) (xy 18.804175 -192.076067) (xy 18.748738 -192.082167) (xy 18.693004 -192.08013)
			(xy 18.638161 -192.07) (xy 18.585377 -192.051993) (xy 18.535777 -192.026492) (xy 18.490419 -191.994041)
			(xy 18.45027 -191.955332) (xy 18.416184 -191.911189) (xy 18.388888 -191.862554) (xy 18.368965 -191.810463)
			(xy 18.356839 -191.756026) (xy 18.352768 -191.700404) (xy 15.250737 -191.700404) (xy 15.232271 -191.739796)
			(xy 15.201498 -191.786309) (xy 15.164281 -191.827846) (xy 15.121413 -191.863521) (xy 15.073807 -191.892575)
			(xy 15.022478 -191.914387) (xy 14.968521 -191.928493) (xy 14.913084 -191.934593) (xy 14.85735 -191.932556)
			(xy 14.802507 -191.922426) (xy 14.749723 -191.904419) (xy 14.700123 -191.878918) (xy 14.654765 -191.846467)
			(xy 14.614616 -191.807758) (xy 14.58053 -191.763615) (xy 14.553234 -191.71498) (xy 14.533311 -191.662889)
			(xy 14.521185 -191.608452) (xy 14.517114 -191.55283) (xy 8.29056 -191.55283) (xy 8.982456 -192.244726)
			(xy 8.982456 -192.848484) (xy 18.352768 -192.848484) (xy 18.356839 -192.792862) (xy 18.368965 -192.738425)
			(xy 18.388888 -192.686334) (xy 18.416184 -192.637699) (xy 18.45027 -192.593556) (xy 18.490419 -192.554847)
			(xy 18.535777 -192.522396) (xy 18.585377 -192.496895) (xy 18.638161 -192.478888) (xy 18.693004 -192.468758)
			(xy 18.748738 -192.466721) (xy 18.804175 -192.472821) (xy 18.858132 -192.486927) (xy 18.909461 -192.508739)
			(xy 18.957067 -192.537793) (xy 18.999935 -192.573468) (xy 19.037152 -192.615005) (xy 19.067925 -192.661518)
			(xy 19.091597 -192.712015) (xy 19.107665 -192.765422) (xy 19.115785 -192.820598) (xy 19.116294 -192.848484)
			(xy 20.437346 -192.848484) (xy 20.441417 -192.792862) (xy 20.453543 -192.738425) (xy 20.473466 -192.686334)
			(xy 20.500762 -192.637699) (xy 20.534848 -192.593556) (xy 20.574997 -192.554847) (xy 20.620355 -192.522396)
			(xy 20.669955 -192.496895) (xy 20.722739 -192.478888) (xy 20.777582 -192.468758) (xy 20.833316 -192.466721)
			(xy 20.888753 -192.472821) (xy 20.94271 -192.486927) (xy 20.994039 -192.508739) (xy 21.041645 -192.537793)
			(xy 21.084513 -192.573468) (xy 21.12173 -192.615005) (xy 21.152503 -192.661518) (xy 21.176175 -192.712015)
			(xy 21.192243 -192.765422) (xy 21.200363 -192.820598) (xy 21.200872 -192.848484) (xy 21.200738 -192.85585)
			(xy 21.43074 -192.85585) (xy 21.434811 -192.800228) (xy 21.446937 -192.745791) (xy 21.46686 -192.6937)
			(xy 21.494156 -192.645065) (xy 21.528242 -192.600922) (xy 21.568391 -192.562213) (xy 21.613749 -192.529762)
			(xy 21.663349 -192.504261) (xy 21.716133 -192.486254) (xy 21.770976 -192.476124) (xy 21.82671 -192.474087)
			(xy 21.882147 -192.480187) (xy 21.936104 -192.494293) (xy 21.987433 -192.516105) (xy 22.035039 -192.545159)
			(xy 22.077907 -192.580834) (xy 22.115124 -192.622371) (xy 22.145897 -192.668884) (xy 22.169569 -192.719381)
			(xy 22.179601 -192.752726) (xy 27.69184 -192.752726) (xy 27.695911 -192.697104) (xy 27.708037 -192.642667)
			(xy 27.72796 -192.590576) (xy 27.755256 -192.541941) (xy 27.789342 -192.497798) (xy 27.829491 -192.459089)
			(xy 27.874849 -192.426638) (xy 27.924449 -192.401137) (xy 27.977233 -192.38313) (xy 28.032076 -192.373)
			(xy 28.08781 -192.370963) (xy 28.143247 -192.377063) (xy 28.197204 -192.391169) (xy 28.248533 -192.412981)
			(xy 28.296139 -192.442035) (xy 28.339007 -192.47771) (xy 28.376224 -192.519247) (xy 28.406997 -192.56576)
			(xy 28.430669 -192.616257) (xy 28.446737 -192.669664) (xy 28.454857 -192.72484) (xy 28.455366 -192.752726)
			(xy 28.454857 -192.780612) (xy 28.446737 -192.835788) (xy 28.430669 -192.889195) (xy 28.406997 -192.939692)
			(xy 28.376224 -192.986205) (xy 28.339007 -193.027742) (xy 28.296139 -193.063417) (xy 28.248533 -193.092471)
			(xy 28.197204 -193.114283) (xy 28.143247 -193.128389) (xy 28.08781 -193.134489) (xy 28.032076 -193.132452)
			(xy 27.977233 -193.122322) (xy 27.924449 -193.104315) (xy 27.874849 -193.078814) (xy 27.829491 -193.046363)
			(xy 27.789342 -193.007654) (xy 27.755256 -192.963511) (xy 27.72796 -192.914876) (xy 27.708037 -192.862785)
			(xy 27.695911 -192.808348) (xy 27.69184 -192.752726) (xy 22.179601 -192.752726) (xy 22.185637 -192.772788)
			(xy 22.193757 -192.827964) (xy 22.194266 -192.85585) (xy 22.193757 -192.883736) (xy 22.185637 -192.938912)
			(xy 22.169569 -192.992319) (xy 22.145897 -193.042816) (xy 22.115124 -193.089329) (xy 22.077907 -193.130866)
			(xy 22.035039 -193.166541) (xy 21.987433 -193.195595) (xy 21.936104 -193.217407) (xy 21.882147 -193.231513)
			(xy 21.82671 -193.237613) (xy 21.770976 -193.235576) (xy 21.716133 -193.225446) (xy 21.663349 -193.207439)
			(xy 21.613749 -193.181938) (xy 21.568391 -193.149487) (xy 21.528242 -193.110778) (xy 21.494156 -193.066635)
			(xy 21.46686 -193.018) (xy 21.446937 -192.965909) (xy 21.434811 -192.911472) (xy 21.43074 -192.85585)
			(xy 21.200738 -192.85585) (xy 21.200363 -192.87637) (xy 21.192243 -192.931546) (xy 21.176175 -192.984953)
			(xy 21.152503 -193.03545) (xy 21.12173 -193.081963) (xy 21.084513 -193.1235) (xy 21.041645 -193.159175)
			(xy 20.994039 -193.188229) (xy 20.94271 -193.210041) (xy 20.888753 -193.224147) (xy 20.833316 -193.230247)
			(xy 20.777582 -193.22821) (xy 20.722739 -193.21808) (xy 20.669955 -193.200073) (xy 20.620355 -193.174572)
			(xy 20.574997 -193.142121) (xy 20.534848 -193.103412) (xy 20.500762 -193.059269) (xy 20.473466 -193.010634)
			(xy 20.453543 -192.958543) (xy 20.441417 -192.904106) (xy 20.437346 -192.848484) (xy 19.116294 -192.848484)
			(xy 19.115785 -192.87637) (xy 19.107665 -192.931546) (xy 19.091597 -192.984953) (xy 19.067925 -193.03545)
			(xy 19.037152 -193.081963) (xy 18.999935 -193.1235) (xy 18.957067 -193.159175) (xy 18.909461 -193.188229)
			(xy 18.858132 -193.210041) (xy 18.804175 -193.224147) (xy 18.748738 -193.230247) (xy 18.693004 -193.22821)
			(xy 18.638161 -193.21808) (xy 18.585377 -193.200073) (xy 18.535777 -193.174572) (xy 18.490419 -193.142121)
			(xy 18.45027 -193.103412) (xy 18.416184 -193.059269) (xy 18.388888 -193.010634) (xy 18.368965 -192.958543)
			(xy 18.356839 -192.904106) (xy 18.352768 -192.848484) (xy 8.982456 -192.848484) (xy 8.982456 -193.843656)
			(xy 18.379692 -193.843656) (xy 18.383763 -193.788034) (xy 18.395889 -193.733597) (xy 18.415812 -193.681506)
			(xy 18.443108 -193.632871) (xy 18.477194 -193.588728) (xy 18.517343 -193.550019) (xy 18.562701 -193.517568)
			(xy 18.612301 -193.492067) (xy 18.665085 -193.47406) (xy 18.719928 -193.46393) (xy 18.775662 -193.461893)
			(xy 18.831099 -193.467993) (xy 18.885056 -193.482099) (xy 18.936385 -193.503911) (xy 18.983991 -193.532965)
			(xy 19.007856 -193.552826) (xy 23.314912 -193.552826) (xy 23.318983 -193.497204) (xy 23.331109 -193.442767)
			(xy 23.351032 -193.390676) (xy 23.378328 -193.342041) (xy 23.412414 -193.297898) (xy 23.452563 -193.259189)
			(xy 23.497921 -193.226738) (xy 23.547521 -193.201237) (xy 23.600305 -193.18323) (xy 23.655148 -193.1731)
			(xy 23.710882 -193.171063) (xy 23.766319 -193.177163) (xy 23.820276 -193.191269) (xy 23.871605 -193.213081)
			(xy 23.919211 -193.242135) (xy 23.962079 -193.27781) (xy 23.999296 -193.319347) (xy 24.030069 -193.36586)
			(xy 24.053741 -193.416357) (xy 24.069809 -193.469764) (xy 24.077929 -193.52494) (xy 24.078438 -193.552826)
			(xy 24.077929 -193.580712) (xy 24.069809 -193.635888) (xy 24.053741 -193.689295) (xy 24.030069 -193.739792)
			(xy 23.999296 -193.786305) (xy 23.962079 -193.827842) (xy 23.919211 -193.863517) (xy 23.871605 -193.892571)
			(xy 23.820276 -193.914383) (xy 23.766319 -193.928489) (xy 23.710882 -193.934589) (xy 23.655148 -193.932552)
			(xy 23.600305 -193.922422) (xy 23.547521 -193.904415) (xy 23.497921 -193.878914) (xy 23.452563 -193.846463)
			(xy 23.412414 -193.807754) (xy 23.378328 -193.763611) (xy 23.351032 -193.714976) (xy 23.331109 -193.662885)
			(xy 23.318983 -193.608448) (xy 23.314912 -193.552826) (xy 19.007856 -193.552826) (xy 19.026859 -193.56864)
			(xy 19.064076 -193.610177) (xy 19.094849 -193.65669) (xy 19.118521 -193.707187) (xy 19.134589 -193.760594)
			(xy 19.142709 -193.81577) (xy 19.143218 -193.843656) (xy 19.142709 -193.871542) (xy 19.134589 -193.926718)
			(xy 19.118521 -193.980125) (xy 19.094849 -194.030622) (xy 19.064076 -194.077135) (xy 19.026859 -194.118672)
			(xy 18.983991 -194.154347) (xy 18.936385 -194.183401) (xy 18.885056 -194.205213) (xy 18.831099 -194.219319)
			(xy 18.775662 -194.225419) (xy 18.719928 -194.223382) (xy 18.665085 -194.213252) (xy 18.612301 -194.195245)
			(xy 18.562701 -194.169744) (xy 18.517343 -194.137293) (xy 18.477194 -194.098584) (xy 18.443108 -194.054441)
			(xy 18.415812 -194.005806) (xy 18.395889 -193.953715) (xy 18.383763 -193.899278) (xy 18.379692 -193.843656)
			(xy 8.982456 -193.843656) (xy 8.982456 -194.793341) (xy 10.780004 -194.793341) (xy 10.780004 -194.740043)
			(xy 10.787947 -194.687339) (xy 10.803657 -194.636409) (xy 10.826783 -194.588388) (xy 10.856807 -194.544351)
			(xy 10.893059 -194.50528) (xy 10.93473 -194.472049) (xy 10.980888 -194.4454) (xy 11.030502 -194.425928)
			(xy 11.082464 -194.414068) (xy 11.135614 -194.410085) (xy 11.188764 -194.414068) (xy 11.240726 -194.425928)
			(xy 11.29034 -194.4454) (xy 11.336498 -194.472049) (xy 11.378169 -194.50528) (xy 11.414421 -194.544351)
			(xy 11.444445 -194.588388) (xy 11.467571 -194.636409) (xy 11.483281 -194.687339) (xy 11.491224 -194.740043)
			(xy 11.491722 -194.766692) (xy 11.491224 -194.793341) (xy 12.989804 -194.793341) (xy 12.989804 -194.740043)
			(xy 12.997747 -194.687339) (xy 13.013457 -194.636409) (xy 13.036583 -194.588388) (xy 13.066607 -194.544351)
			(xy 13.102859 -194.50528) (xy 13.14453 -194.472049) (xy 13.190688 -194.4454) (xy 13.240302 -194.425928)
			(xy 13.292264 -194.414068) (xy 13.345414 -194.410085) (xy 13.398564 -194.414068) (xy 13.450526 -194.425928)
			(xy 13.50014 -194.4454) (xy 13.546298 -194.472049) (xy 13.587969 -194.50528) (xy 13.624221 -194.544351)
			(xy 13.654245 -194.588388) (xy 13.677371 -194.636409) (xy 13.693081 -194.687339) (xy 13.701024 -194.740043)
			(xy 13.701522 -194.766692) (xy 13.701024 -194.793341) (xy 14.198336 -194.793341) (xy 14.198336 -194.740043)
			(xy 14.206279 -194.687339) (xy 14.221989 -194.636409) (xy 14.245115 -194.588388) (xy 14.275139 -194.544351)
			(xy 14.311391 -194.50528) (xy 14.353062 -194.472049) (xy 14.39922 -194.4454) (xy 14.448834 -194.425928)
			(xy 14.500796 -194.414068) (xy 14.553946 -194.410085) (xy 14.607096 -194.414068) (xy 14.659058 -194.425928)
			(xy 14.708672 -194.4454) (xy 14.75483 -194.472049) (xy 14.763115 -194.478656) (xy 16.969992 -194.478656)
			(xy 16.974063 -194.423034) (xy 16.986189 -194.368597) (xy 17.006112 -194.316506) (xy 17.033408 -194.267871)
			(xy 17.067494 -194.223728) (xy 17.107643 -194.185019) (xy 17.153001 -194.152568) (xy 17.202601 -194.127067)
			(xy 17.255385 -194.10906) (xy 17.310228 -194.09893) (xy 17.365962 -194.096893) (xy 17.421399 -194.102993)
			(xy 17.475356 -194.117099) (xy 17.526685 -194.138911) (xy 17.574291 -194.167965) (xy 17.617159 -194.20364)
			(xy 17.654376 -194.245177) (xy 17.685149 -194.29169) (xy 17.708821 -194.342187) (xy 17.724889 -194.395594)
			(xy 17.733009 -194.45077) (xy 17.733518 -194.478656) (xy 17.733009 -194.506542) (xy 17.724889 -194.561718)
			(xy 17.708821 -194.615125) (xy 17.685149 -194.665622) (xy 17.654376 -194.712135) (xy 17.617159 -194.753672)
			(xy 17.574291 -194.789347) (xy 17.567747 -194.793341) (xy 18.323804 -194.793341) (xy 18.323804 -194.740043)
			(xy 18.331747 -194.687339) (xy 18.347457 -194.636409) (xy 18.370583 -194.588388) (xy 18.400607 -194.544351)
			(xy 18.436859 -194.50528) (xy 18.47853 -194.472049) (xy 18.524688 -194.4454) (xy 18.574302 -194.425928)
			(xy 18.626264 -194.414068) (xy 18.679414 -194.410085) (xy 18.732564 -194.414068) (xy 18.784526 -194.425928)
			(xy 18.83414 -194.4454) (xy 18.880298 -194.472049) (xy 18.921969 -194.50528) (xy 18.958221 -194.544351)
			(xy 18.988245 -194.588388) (xy 19.011371 -194.636409) (xy 19.027081 -194.687339) (xy 19.035024 -194.740043)
			(xy 19.035522 -194.766692) (xy 19.035024 -194.793341) (xy 20.533604 -194.793341) (xy 20.533604 -194.740043)
			(xy 20.541547 -194.687339) (xy 20.557257 -194.636409) (xy 20.580383 -194.588388) (xy 20.610407 -194.544351)
			(xy 20.646659 -194.50528) (xy 20.68833 -194.472049) (xy 20.734488 -194.4454) (xy 20.784102 -194.425928)
			(xy 20.836064 -194.414068) (xy 20.889214 -194.410085) (xy 20.942364 -194.414068) (xy 20.994326 -194.425928)
			(xy 21.04394 -194.4454) (xy 21.090098 -194.472049) (xy 21.131769 -194.50528) (xy 21.168021 -194.544351)
			(xy 21.198045 -194.588388) (xy 21.221171 -194.636409) (xy 21.236881 -194.687339) (xy 21.244824 -194.740043)
			(xy 21.245322 -194.766692) (xy 21.244824 -194.793341) (xy 21.742136 -194.793341) (xy 21.742136 -194.740043)
			(xy 21.750079 -194.687339) (xy 21.765789 -194.636409) (xy 21.788915 -194.588388) (xy 21.818939 -194.544351)
			(xy 21.855191 -194.50528) (xy 21.896862 -194.472049) (xy 21.94302 -194.4454) (xy 21.992634 -194.425928)
			(xy 22.044596 -194.414068) (xy 22.097746 -194.410085) (xy 22.150896 -194.414068) (xy 22.202858 -194.425928)
			(xy 22.252472 -194.4454) (xy 22.29863 -194.472049) (xy 22.340301 -194.50528) (xy 22.376553 -194.544351)
			(xy 22.406577 -194.588388) (xy 22.429703 -194.636409) (xy 22.445413 -194.687339) (xy 22.453356 -194.740043)
			(xy 22.453854 -194.766692) (xy 22.453356 -194.793341) (xy 25.867604 -194.793341) (xy 25.867604 -194.740043)
			(xy 25.875547 -194.687339) (xy 25.891257 -194.636409) (xy 25.914383 -194.588388) (xy 25.944407 -194.544351)
			(xy 25.980659 -194.50528) (xy 26.02233 -194.472049) (xy 26.068488 -194.4454) (xy 26.118102 -194.425928)
			(xy 26.170064 -194.414068) (xy 26.223214 -194.410085) (xy 26.276364 -194.414068) (xy 26.328326 -194.425928)
			(xy 26.37794 -194.4454) (xy 26.424098 -194.472049) (xy 26.465769 -194.50528) (xy 26.502021 -194.544351)
			(xy 26.532045 -194.588388) (xy 26.555171 -194.636409) (xy 26.570881 -194.687339) (xy 26.578824 -194.740043)
			(xy 26.579322 -194.766692) (xy 26.578824 -194.793341) (xy 28.077404 -194.793341) (xy 28.077404 -194.740043)
			(xy 28.085347 -194.687339) (xy 28.101057 -194.636409) (xy 28.124183 -194.588388) (xy 28.154207 -194.544351)
			(xy 28.190459 -194.50528) (xy 28.23213 -194.472049) (xy 28.278288 -194.4454) (xy 28.327902 -194.425928)
			(xy 28.379864 -194.414068) (xy 28.433014 -194.410085) (xy 28.486164 -194.414068) (xy 28.538126 -194.425928)
			(xy 28.58774 -194.4454) (xy 28.633898 -194.472049) (xy 28.675569 -194.50528) (xy 28.711821 -194.544351)
			(xy 28.741845 -194.588388) (xy 28.764971 -194.636409) (xy 28.780681 -194.687339) (xy 28.788624 -194.740043)
			(xy 28.789122 -194.766692) (xy 28.788733 -194.787499) (xy 29.252408 -194.787499) (xy 29.252408 -194.734201)
			(xy 29.260351 -194.681497) (xy 29.276061 -194.630567) (xy 29.299187 -194.582546) (xy 29.329211 -194.538509)
			(xy 29.365463 -194.499438) (xy 29.407134 -194.466207) (xy 29.453292 -194.439558) (xy 29.502906 -194.420086)
			(xy 29.554868 -194.408226) (xy 29.608018 -194.404243) (xy 29.661168 -194.408226) (xy 29.71313 -194.420086)
			(xy 29.762744 -194.439558) (xy 29.808902 -194.466207) (xy 29.850573 -194.499438) (xy 29.886825 -194.538509)
			(xy 29.916849 -194.582546) (xy 29.939975 -194.630567) (xy 29.955685 -194.681497) (xy 29.963628 -194.734201)
			(xy 29.964126 -194.76085) (xy 29.963628 -194.787499) (xy 29.955685 -194.840203) (xy 29.939975 -194.891133)
			(xy 29.916849 -194.939154) (xy 29.886825 -194.983191) (xy 29.850573 -195.022262) (xy 29.808902 -195.055493)
			(xy 29.762744 -195.082142) (xy 29.71313 -195.101614) (xy 29.661168 -195.113474) (xy 29.608018 -195.117458)
			(xy 29.554868 -195.113474) (xy 29.502906 -195.101614) (xy 29.453292 -195.082142) (xy 29.407134 -195.055493)
			(xy 29.365463 -195.022262) (xy 29.329211 -194.983191) (xy 29.299187 -194.939154) (xy 29.276061 -194.891133)
			(xy 29.260351 -194.840203) (xy 29.252408 -194.787499) (xy 28.788733 -194.787499) (xy 28.788624 -194.793341)
			(xy 28.780681 -194.846045) (xy 28.764971 -194.896975) (xy 28.741845 -194.944996) (xy 28.711821 -194.989033)
			(xy 28.675569 -195.028104) (xy 28.633898 -195.061335) (xy 28.58774 -195.087984) (xy 28.538126 -195.107456)
			(xy 28.486164 -195.119316) (xy 28.433014 -195.1233) (xy 28.379864 -195.119316) (xy 28.327902 -195.107456)
			(xy 28.278288 -195.087984) (xy 28.23213 -195.061335) (xy 28.190459 -195.028104) (xy 28.154207 -194.989033)
			(xy 28.124183 -194.944996) (xy 28.101057 -194.896975) (xy 28.085347 -194.846045) (xy 28.077404 -194.793341)
			(xy 26.578824 -194.793341) (xy 26.570881 -194.846045) (xy 26.555171 -194.896975) (xy 26.532045 -194.944996)
			(xy 26.502021 -194.989033) (xy 26.465769 -195.028104) (xy 26.424098 -195.061335) (xy 26.37794 -195.087984)
			(xy 26.328326 -195.107456) (xy 26.276364 -195.119316) (xy 26.223214 -195.1233) (xy 26.170064 -195.119316)
			(xy 26.118102 -195.107456) (xy 26.068488 -195.087984) (xy 26.02233 -195.061335) (xy 25.980659 -195.028104)
			(xy 25.944407 -194.989033) (xy 25.914383 -194.944996) (xy 25.891257 -194.896975) (xy 25.875547 -194.846045)
			(xy 25.867604 -194.793341) (xy 22.453356 -194.793341) (xy 22.445413 -194.846045) (xy 22.429703 -194.896975)
			(xy 22.406577 -194.944996) (xy 22.376553 -194.989033) (xy 22.340301 -195.028104) (xy 22.29863 -195.061335)
			(xy 22.252472 -195.087984) (xy 22.202858 -195.107456) (xy 22.150896 -195.119316) (xy 22.097746 -195.1233)
			(xy 22.044596 -195.119316) (xy 21.992634 -195.107456) (xy 21.94302 -195.087984) (xy 21.896862 -195.061335)
			(xy 21.855191 -195.028104) (xy 21.818939 -194.989033) (xy 21.788915 -194.944996) (xy 21.765789 -194.896975)
			(xy 21.750079 -194.846045) (xy 21.742136 -194.793341) (xy 21.244824 -194.793341) (xy 21.236881 -194.846045)
			(xy 21.221171 -194.896975) (xy 21.198045 -194.944996) (xy 21.168021 -194.989033) (xy 21.131769 -195.028104)
			(xy 21.090098 -195.061335) (xy 21.04394 -195.087984) (xy 20.994326 -195.107456) (xy 20.942364 -195.119316)
			(xy 20.889214 -195.1233) (xy 20.836064 -195.119316) (xy 20.784102 -195.107456) (xy 20.734488 -195.087984)
			(xy 20.68833 -195.061335) (xy 20.646659 -195.028104) (xy 20.610407 -194.989033) (xy 20.580383 -194.944996)
			(xy 20.557257 -194.896975) (xy 20.541547 -194.846045) (xy 20.533604 -194.793341) (xy 19.035024 -194.793341)
			(xy 19.027081 -194.846045) (xy 19.011371 -194.896975) (xy 18.988245 -194.944996) (xy 18.958221 -194.989033)
			(xy 18.921969 -195.028104) (xy 18.880298 -195.061335) (xy 18.83414 -195.087984) (xy 18.784526 -195.107456)
			(xy 18.732564 -195.119316) (xy 18.679414 -195.1233) (xy 18.626264 -195.119316) (xy 18.574302 -195.107456)
			(xy 18.524688 -195.087984) (xy 18.47853 -195.061335) (xy 18.436859 -195.028104) (xy 18.400607 -194.989033)
			(xy 18.370583 -194.944996) (xy 18.347457 -194.896975) (xy 18.331747 -194.846045) (xy 18.323804 -194.793341)
			(xy 17.567747 -194.793341) (xy 17.526685 -194.818401) (xy 17.475356 -194.840213) (xy 17.421399 -194.854319)
			(xy 17.365962 -194.860419) (xy 17.310228 -194.858382) (xy 17.255385 -194.848252) (xy 17.202601 -194.830245)
			(xy 17.153001 -194.804744) (xy 17.107643 -194.772293) (xy 17.067494 -194.733584) (xy 17.033408 -194.689441)
			(xy 17.006112 -194.640806) (xy 16.986189 -194.588715) (xy 16.974063 -194.534278) (xy 16.969992 -194.478656)
			(xy 14.763115 -194.478656) (xy 14.796501 -194.50528) (xy 14.832753 -194.544351) (xy 14.862777 -194.588388)
			(xy 14.885903 -194.636409) (xy 14.901613 -194.687339) (xy 14.909556 -194.740043) (xy 14.910054 -194.766692)
			(xy 14.909556 -194.793341) (xy 14.901613 -194.846045) (xy 14.885903 -194.896975) (xy 14.862777 -194.944996)
			(xy 14.832753 -194.989033) (xy 14.796501 -195.028104) (xy 14.75483 -195.061335) (xy 14.708672 -195.087984)
			(xy 14.659058 -195.107456) (xy 14.607096 -195.119316) (xy 14.553946 -195.1233) (xy 14.500796 -195.119316)
			(xy 14.448834 -195.107456) (xy 14.39922 -195.087984) (xy 14.353062 -195.061335) (xy 14.311391 -195.028104)
			(xy 14.275139 -194.989033) (xy 14.245115 -194.944996) (xy 14.221989 -194.896975) (xy 14.206279 -194.846045)
			(xy 14.198336 -194.793341) (xy 13.701024 -194.793341) (xy 13.693081 -194.846045) (xy 13.677371 -194.896975)
			(xy 13.654245 -194.944996) (xy 13.624221 -194.989033) (xy 13.587969 -195.028104) (xy 13.546298 -195.061335)
			(xy 13.50014 -195.087984) (xy 13.450526 -195.107456) (xy 13.398564 -195.119316) (xy 13.345414 -195.1233)
			(xy 13.292264 -195.119316) (xy 13.240302 -195.107456) (xy 13.190688 -195.087984) (xy 13.14453 -195.061335)
			(xy 13.102859 -195.028104) (xy 13.066607 -194.989033) (xy 13.036583 -194.944996) (xy 13.013457 -194.896975)
			(xy 12.997747 -194.846045) (xy 12.989804 -194.793341) (xy 11.491224 -194.793341) (xy 11.483281 -194.846045)
			(xy 11.467571 -194.896975) (xy 11.444445 -194.944996) (xy 11.414421 -194.989033) (xy 11.378169 -195.028104)
			(xy 11.336498 -195.061335) (xy 11.29034 -195.087984) (xy 11.240726 -195.107456) (xy 11.188764 -195.119316)
			(xy 11.135614 -195.1233) (xy 11.082464 -195.119316) (xy 11.030502 -195.107456) (xy 10.980888 -195.087984)
			(xy 10.93473 -195.061335) (xy 10.893059 -195.028104) (xy 10.856807 -194.989033) (xy 10.826783 -194.944996)
			(xy 10.803657 -194.896975) (xy 10.787947 -194.846045) (xy 10.780004 -194.793341) (xy 8.982456 -194.793341)
			(xy 8.982456 -195.188332) (xy 8.982896 -195.202378) (xy 8.990536 -195.229411) (xy 9.005256 -195.253337)
			(xy 9.025941 -195.272344) (xy 9.051024 -195.284992) (xy 9.078605 -195.290323) (xy 9.106595 -195.287934)
			(xy 9.11987 -195.283328) (xy 9.150134 -195.272655) (xy 9.213262 -195.261152) (xy 9.245346 -195.260468)
			(xy 9.271998 -195.260941) (xy 9.324706 -195.268885) (xy 9.375641 -195.284596) (xy 9.423666 -195.307723)
			(xy 9.467707 -195.337749) (xy 9.506781 -195.374005) (xy 9.540016 -195.415679) (xy 9.566667 -195.46184)
			(xy 9.586141 -195.511459) (xy 9.598003 -195.563426) (xy 9.601986 -195.61658) (xy 9.599989 -195.643225)
			(xy 14.223736 -195.643225) (xy 14.223736 -195.589927) (xy 14.231679 -195.537223) (xy 14.247389 -195.486293)
			(xy 14.270515 -195.438272) (xy 14.300539 -195.394235) (xy 14.336791 -195.355164) (xy 14.378462 -195.321933)
			(xy 14.42462 -195.295284) (xy 14.474234 -195.275812) (xy 14.526196 -195.263952) (xy 14.579346 -195.259969)
			(xy 14.632496 -195.263952) (xy 14.684458 -195.275812) (xy 14.734072 -195.295284) (xy 14.78023 -195.321933)
			(xy 14.821901 -195.355164) (xy 14.858153 -195.394235) (xy 14.888177 -195.438272) (xy 14.911303 -195.486293)
			(xy 14.927013 -195.537223) (xy 14.934956 -195.589927) (xy 14.935454 -195.616576) (xy 14.934956 -195.643225)
			(xy 16.433536 -195.643225) (xy 16.433536 -195.589927) (xy 16.441479 -195.537223) (xy 16.457189 -195.486293)
			(xy 16.480315 -195.438272) (xy 16.510339 -195.394235) (xy 16.546591 -195.355164) (xy 16.588262 -195.321933)
			(xy 16.63442 -195.295284) (xy 16.684034 -195.275812) (xy 16.735996 -195.263952) (xy 16.789146 -195.259969)
			(xy 16.842296 -195.263952) (xy 16.894258 -195.275812) (xy 16.943872 -195.295284) (xy 16.99003 -195.321933)
			(xy 17.031701 -195.355164) (xy 17.067953 -195.394235) (xy 17.097977 -195.438272) (xy 17.121103 -195.486293)
			(xy 17.136813 -195.537223) (xy 17.144756 -195.589927) (xy 17.145254 -195.616576) (xy 17.144756 -195.643225)
			(xy 20.533604 -195.643225) (xy 20.533604 -195.589927) (xy 20.541547 -195.537223) (xy 20.557257 -195.486293)
			(xy 20.580383 -195.438272) (xy 20.610407 -195.394235) (xy 20.646659 -195.355164) (xy 20.68833 -195.321933)
			(xy 20.734488 -195.295284) (xy 20.784102 -195.275812) (xy 20.836064 -195.263952) (xy 20.889214 -195.259969)
			(xy 20.942364 -195.263952) (xy 20.994326 -195.275812) (xy 21.04394 -195.295284) (xy 21.090098 -195.321933)
			(xy 21.131769 -195.355164) (xy 21.168021 -195.394235) (xy 21.198045 -195.438272) (xy 21.221171 -195.486293)
			(xy 21.236881 -195.537223) (xy 21.244824 -195.589927) (xy 21.245322 -195.616576) (xy 21.244824 -195.643225)
			(xy 21.767536 -195.643225) (xy 21.767536 -195.589927) (xy 21.775479 -195.537223) (xy 21.791189 -195.486293)
			(xy 21.814315 -195.438272) (xy 21.844339 -195.394235) (xy 21.880591 -195.355164) (xy 21.922262 -195.321933)
			(xy 21.96842 -195.295284) (xy 22.018034 -195.275812) (xy 22.069996 -195.263952) (xy 22.123146 -195.259969)
			(xy 22.176296 -195.263952) (xy 22.228258 -195.275812) (xy 22.277872 -195.295284) (xy 22.32403 -195.321933)
			(xy 22.365701 -195.355164) (xy 22.401953 -195.394235) (xy 22.431977 -195.438272) (xy 22.455103 -195.486293)
			(xy 22.470813 -195.537223) (xy 22.478756 -195.589927) (xy 22.479254 -195.616576) (xy 22.478756 -195.643225)
			(xy 23.977336 -195.643225) (xy 23.977336 -195.589927) (xy 23.985279 -195.537223) (xy 24.000989 -195.486293)
			(xy 24.024115 -195.438272) (xy 24.054139 -195.394235) (xy 24.090391 -195.355164) (xy 24.132062 -195.321933)
			(xy 24.17822 -195.295284) (xy 24.227834 -195.275812) (xy 24.279796 -195.263952) (xy 24.332946 -195.259969)
			(xy 24.386096 -195.263952) (xy 24.438058 -195.275812) (xy 24.487672 -195.295284) (xy 24.53383 -195.321933)
			(xy 24.575501 -195.355164) (xy 24.611753 -195.394235) (xy 24.641777 -195.438272) (xy 24.664903 -195.486293)
			(xy 24.680613 -195.537223) (xy 24.688556 -195.589927) (xy 24.689054 -195.616576) (xy 24.688556 -195.643225)
			(xy 24.680613 -195.695929) (xy 24.664903 -195.746859) (xy 24.641777 -195.79488) (xy 24.611753 -195.838917)
			(xy 24.575501 -195.877988) (xy 24.53383 -195.911219) (xy 24.487672 -195.937868) (xy 24.438058 -195.95734)
			(xy 24.386096 -195.9692) (xy 24.332946 -195.973184) (xy 24.279796 -195.9692) (xy 24.227834 -195.95734)
			(xy 24.17822 -195.937868) (xy 24.132062 -195.911219) (xy 24.090391 -195.877988) (xy 24.054139 -195.838917)
			(xy 24.024115 -195.79488) (xy 24.000989 -195.746859) (xy 23.985279 -195.695929) (xy 23.977336 -195.643225)
			(xy 22.478756 -195.643225) (xy 22.470813 -195.695929) (xy 22.455103 -195.746859) (xy 22.431977 -195.79488)
			(xy 22.401953 -195.838917) (xy 22.365701 -195.877988) (xy 22.32403 -195.911219) (xy 22.277872 -195.937868)
			(xy 22.228258 -195.95734) (xy 22.176296 -195.9692) (xy 22.123146 -195.973184) (xy 22.069996 -195.9692)
			(xy 22.018034 -195.95734) (xy 21.96842 -195.937868) (xy 21.922262 -195.911219) (xy 21.880591 -195.877988)
			(xy 21.844339 -195.838917) (xy 21.814315 -195.79488) (xy 21.791189 -195.746859) (xy 21.775479 -195.695929)
			(xy 21.767536 -195.643225) (xy 21.244824 -195.643225) (xy 21.236881 -195.695929) (xy 21.221171 -195.746859)
			(xy 21.198045 -195.79488) (xy 21.168021 -195.838917) (xy 21.131769 -195.877988) (xy 21.090098 -195.911219)
			(xy 21.04394 -195.937868) (xy 20.994326 -195.95734) (xy 20.942364 -195.9692) (xy 20.889214 -195.973184)
			(xy 20.836064 -195.9692) (xy 20.784102 -195.95734) (xy 20.734488 -195.937868) (xy 20.68833 -195.911219)
			(xy 20.646659 -195.877988) (xy 20.610407 -195.838917) (xy 20.580383 -195.79488) (xy 20.557257 -195.746859)
			(xy 20.541547 -195.695929) (xy 20.533604 -195.643225) (xy 17.144756 -195.643225) (xy 17.136813 -195.695929)
			(xy 17.121103 -195.746859) (xy 17.097977 -195.79488) (xy 17.067953 -195.838917) (xy 17.031701 -195.877988)
			(xy 16.99003 -195.911219) (xy 16.943872 -195.937868) (xy 16.894258 -195.95734) (xy 16.842296 -195.9692)
			(xy 16.789146 -195.973184) (xy 16.735996 -195.9692) (xy 16.684034 -195.95734) (xy 16.63442 -195.937868)
			(xy 16.588262 -195.911219) (xy 16.546591 -195.877988) (xy 16.510339 -195.838917) (xy 16.480315 -195.79488)
			(xy 16.457189 -195.746859) (xy 16.441479 -195.695929) (xy 16.433536 -195.643225) (xy 14.934956 -195.643225)
			(xy 14.927013 -195.695929) (xy 14.911303 -195.746859) (xy 14.888177 -195.79488) (xy 14.858153 -195.838917)
			(xy 14.821901 -195.877988) (xy 14.78023 -195.911219) (xy 14.734072 -195.937868) (xy 14.684458 -195.95734)
			(xy 14.632496 -195.9692) (xy 14.579346 -195.973184) (xy 14.526196 -195.9692) (xy 14.474234 -195.95734)
			(xy 14.42462 -195.937868) (xy 14.378462 -195.911219) (xy 14.336791 -195.877988) (xy 14.300539 -195.838917)
			(xy 14.270515 -195.79488) (xy 14.247389 -195.746859) (xy 14.231679 -195.695929) (xy 14.223736 -195.643225)
			(xy 9.599989 -195.643225) (xy 9.598003 -195.669734) (xy 9.586141 -195.721701) (xy 9.566667 -195.77132)
			(xy 9.540016 -195.817481) (xy 9.506781 -195.859155) (xy 9.467707 -195.895411) (xy 9.423666 -195.925437)
			(xy 9.375641 -195.948564) (xy 9.324706 -195.964275) (xy 9.271998 -195.972219) (xy 9.245346 -195.972684)
			(xy 9.217486 -195.972149) (xy 9.162446 -195.963479) (xy 9.109427 -195.946345) (xy 9.059722 -195.921164)
			(xy 9.014545 -195.888551) (xy 8.994394 -195.869306) (xy 8.984657 -195.860244) (xy 8.961591 -195.847019)
			(xy 8.935891 -195.840201) (xy 8.909303 -195.840255) (xy 8.883631 -195.847175) (xy 8.860618 -195.860493)
			(xy 8.850884 -195.86956) (xy 8.546592 -196.173852) (xy 8.546592 -196.493363) (xy 10.780004 -196.493363)
			(xy 10.780004 -196.440065) (xy 10.787947 -196.387361) (xy 10.803657 -196.336431) (xy 10.826783 -196.28841)
			(xy 10.856807 -196.244373) (xy 10.893059 -196.205302) (xy 10.93473 -196.172071) (xy 10.980888 -196.145422)
			(xy 11.030502 -196.12595) (xy 11.082464 -196.11409) (xy 11.135614 -196.110107) (xy 11.188764 -196.11409)
			(xy 11.240726 -196.12595) (xy 11.29034 -196.145422) (xy 11.336498 -196.172071) (xy 11.378169 -196.205302)
			(xy 11.414421 -196.244373) (xy 11.444445 -196.28841) (xy 11.467571 -196.336431) (xy 11.483281 -196.387361)
			(xy 11.491224 -196.440065) (xy 11.491722 -196.466714) (xy 11.491224 -196.493363) (xy 12.989804 -196.493363)
			(xy 12.989804 -196.440065) (xy 12.997747 -196.387361) (xy 13.013457 -196.336431) (xy 13.036583 -196.28841)
			(xy 13.066607 -196.244373) (xy 13.102859 -196.205302) (xy 13.14453 -196.172071) (xy 13.190688 -196.145422)
			(xy 13.240302 -196.12595) (xy 13.292264 -196.11409) (xy 13.345414 -196.110107) (xy 13.398564 -196.11409)
			(xy 13.450526 -196.12595) (xy 13.50014 -196.145422) (xy 13.546298 -196.172071) (xy 13.587969 -196.205302)
			(xy 13.624221 -196.244373) (xy 13.654245 -196.28841) (xy 13.677371 -196.336431) (xy 13.693081 -196.387361)
			(xy 13.701024 -196.440065) (xy 13.701522 -196.466714) (xy 13.701024 -196.493363) (xy 16.433536 -196.493363)
			(xy 16.433536 -196.440065) (xy 16.441479 -196.387361) (xy 16.457189 -196.336431) (xy 16.480315 -196.28841)
			(xy 16.510339 -196.244373) (xy 16.546591 -196.205302) (xy 16.588262 -196.172071) (xy 16.63442 -196.145422)
			(xy 16.684034 -196.12595) (xy 16.735996 -196.11409) (xy 16.789146 -196.110107) (xy 16.842296 -196.11409)
			(xy 16.894258 -196.12595) (xy 16.943872 -196.145422) (xy 16.99003 -196.172071) (xy 17.031701 -196.205302)
			(xy 17.067953 -196.244373) (xy 17.097977 -196.28841) (xy 17.121103 -196.336431) (xy 17.136813 -196.387361)
			(xy 17.144756 -196.440065) (xy 17.145254 -196.466714) (xy 17.144756 -196.493363) (xy 18.323804 -196.493363)
			(xy 18.323804 -196.440065) (xy 18.331747 -196.387361) (xy 18.347457 -196.336431) (xy 18.370583 -196.28841)
			(xy 18.400607 -196.244373) (xy 18.436859 -196.205302) (xy 18.47853 -196.172071) (xy 18.524688 -196.145422)
			(xy 18.574302 -196.12595) (xy 18.626264 -196.11409) (xy 18.679414 -196.110107) (xy 18.732564 -196.11409)
			(xy 18.784526 -196.12595) (xy 18.83414 -196.145422) (xy 18.880298 -196.172071) (xy 18.921969 -196.205302)
			(xy 18.958221 -196.244373) (xy 18.988245 -196.28841) (xy 19.011371 -196.336431) (xy 19.027081 -196.387361)
			(xy 19.035024 -196.440065) (xy 19.035522 -196.466714) (xy 19.035024 -196.493363) (xy 20.533604 -196.493363)
			(xy 20.533604 -196.440065) (xy 20.541547 -196.387361) (xy 20.557257 -196.336431) (xy 20.580383 -196.28841)
			(xy 20.610407 -196.244373) (xy 20.646659 -196.205302) (xy 20.68833 -196.172071) (xy 20.734488 -196.145422)
			(xy 20.784102 -196.12595) (xy 20.836064 -196.11409) (xy 20.889214 -196.110107) (xy 20.942364 -196.11409)
			(xy 20.994326 -196.12595) (xy 21.04394 -196.145422) (xy 21.090098 -196.172071) (xy 21.131769 -196.205302)
			(xy 21.168021 -196.244373) (xy 21.198045 -196.28841) (xy 21.221171 -196.336431) (xy 21.236881 -196.387361)
			(xy 21.244824 -196.440065) (xy 21.245322 -196.466714) (xy 21.244824 -196.493363) (xy 25.867604 -196.493363)
			(xy 25.867604 -196.440065) (xy 25.875547 -196.387361) (xy 25.891257 -196.336431) (xy 25.914383 -196.28841)
			(xy 25.944407 -196.244373) (xy 25.980659 -196.205302) (xy 26.02233 -196.172071) (xy 26.068488 -196.145422)
			(xy 26.118102 -196.12595) (xy 26.170064 -196.11409) (xy 26.223214 -196.110107) (xy 26.276364 -196.11409)
			(xy 26.328326 -196.12595) (xy 26.37794 -196.145422) (xy 26.424098 -196.172071) (xy 26.465769 -196.205302)
			(xy 26.502021 -196.244373) (xy 26.532045 -196.28841) (xy 26.555171 -196.336431) (xy 26.570881 -196.387361)
			(xy 26.578824 -196.440065) (xy 26.579322 -196.466714) (xy 26.578824 -196.493363) (xy 26.570881 -196.546067)
			(xy 26.555171 -196.596997) (xy 26.532045 -196.645018) (xy 26.502021 -196.689055) (xy 26.465769 -196.728126)
			(xy 26.424098 -196.761357) (xy 26.37794 -196.788006) (xy 26.328326 -196.807478) (xy 26.276364 -196.819338)
			(xy 26.223214 -196.823322) (xy 26.170064 -196.819338) (xy 26.118102 -196.807478) (xy 26.068488 -196.788006)
			(xy 26.02233 -196.761357) (xy 25.980659 -196.728126) (xy 25.944407 -196.689055) (xy 25.914383 -196.645018)
			(xy 25.891257 -196.596997) (xy 25.875547 -196.546067) (xy 25.867604 -196.493363) (xy 21.244824 -196.493363)
			(xy 21.236881 -196.546067) (xy 21.221171 -196.596997) (xy 21.198045 -196.645018) (xy 21.168021 -196.689055)
			(xy 21.131769 -196.728126) (xy 21.090098 -196.761357) (xy 21.04394 -196.788006) (xy 20.994326 -196.807478)
			(xy 20.942364 -196.819338) (xy 20.889214 -196.823322) (xy 20.836064 -196.819338) (xy 20.784102 -196.807478)
			(xy 20.734488 -196.788006) (xy 20.68833 -196.761357) (xy 20.646659 -196.728126) (xy 20.610407 -196.689055)
			(xy 20.580383 -196.645018) (xy 20.557257 -196.596997) (xy 20.541547 -196.546067) (xy 20.533604 -196.493363)
			(xy 19.035024 -196.493363) (xy 19.027081 -196.546067) (xy 19.011371 -196.596997) (xy 18.988245 -196.645018)
			(xy 18.958221 -196.689055) (xy 18.921969 -196.728126) (xy 18.880298 -196.761357) (xy 18.83414 -196.788006)
			(xy 18.784526 -196.807478) (xy 18.732564 -196.819338) (xy 18.679414 -196.823322) (xy 18.626264 -196.819338)
			(xy 18.574302 -196.807478) (xy 18.524688 -196.788006) (xy 18.47853 -196.761357) (xy 18.436859 -196.728126)
			(xy 18.400607 -196.689055) (xy 18.370583 -196.645018) (xy 18.347457 -196.596997) (xy 18.331747 -196.546067)
			(xy 18.323804 -196.493363) (xy 17.144756 -196.493363) (xy 17.136813 -196.546067) (xy 17.121103 -196.596997)
			(xy 17.097977 -196.645018) (xy 17.067953 -196.689055) (xy 17.031701 -196.728126) (xy 16.99003 -196.761357)
			(xy 16.943872 -196.788006) (xy 16.894258 -196.807478) (xy 16.842296 -196.819338) (xy 16.789146 -196.823322)
			(xy 16.735996 -196.819338) (xy 16.684034 -196.807478) (xy 16.63442 -196.788006) (xy 16.588262 -196.761357)
			(xy 16.546591 -196.728126) (xy 16.510339 -196.689055) (xy 16.480315 -196.645018) (xy 16.457189 -196.596997)
			(xy 16.441479 -196.546067) (xy 16.433536 -196.493363) (xy 13.701024 -196.493363) (xy 13.693081 -196.546067)
			(xy 13.677371 -196.596997) (xy 13.654245 -196.645018) (xy 13.624221 -196.689055) (xy 13.587969 -196.728126)
			(xy 13.546298 -196.761357) (xy 13.50014 -196.788006) (xy 13.450526 -196.807478) (xy 13.398564 -196.819338)
			(xy 13.345414 -196.823322) (xy 13.292264 -196.819338) (xy 13.240302 -196.807478) (xy 13.190688 -196.788006)
			(xy 13.14453 -196.761357) (xy 13.102859 -196.728126) (xy 13.066607 -196.689055) (xy 13.036583 -196.645018)
			(xy 13.013457 -196.596997) (xy 12.997747 -196.546067) (xy 12.989804 -196.493363) (xy 11.491224 -196.493363)
			(xy 11.483281 -196.546067) (xy 11.467571 -196.596997) (xy 11.444445 -196.645018) (xy 11.414421 -196.689055)
			(xy 11.378169 -196.728126) (xy 11.336498 -196.761357) (xy 11.29034 -196.788006) (xy 11.240726 -196.807478)
			(xy 11.188764 -196.819338) (xy 11.135614 -196.823322) (xy 11.082464 -196.819338) (xy 11.030502 -196.807478)
			(xy 10.980888 -196.788006) (xy 10.93473 -196.761357) (xy 10.893059 -196.728126) (xy 10.856807 -196.689055)
			(xy 10.826783 -196.645018) (xy 10.803657 -196.596997) (xy 10.787947 -196.546067) (xy 10.780004 -196.493363)
			(xy 8.546592 -196.493363) (xy 8.546592 -197.343247) (xy 8.889736 -197.343247) (xy 8.889736 -197.289949)
			(xy 8.897679 -197.237245) (xy 8.913389 -197.186315) (xy 8.936515 -197.138294) (xy 8.966539 -197.094257)
			(xy 9.002791 -197.055186) (xy 9.044462 -197.021955) (xy 9.09062 -196.995306) (xy 9.140234 -196.975834)
			(xy 9.192196 -196.963974) (xy 9.245346 -196.959991) (xy 9.298496 -196.963974) (xy 9.350458 -196.975834)
			(xy 9.400072 -196.995306) (xy 9.44623 -197.021955) (xy 9.487901 -197.055186) (xy 9.524153 -197.094257)
			(xy 9.554177 -197.138294) (xy 9.577303 -197.186315) (xy 9.593013 -197.237245) (xy 9.600956 -197.289949)
			(xy 9.601454 -197.316598) (xy 9.600956 -197.343247) (xy 14.223736 -197.343247) (xy 14.223736 -197.289949)
			(xy 14.231679 -197.237245) (xy 14.247389 -197.186315) (xy 14.270515 -197.138294) (xy 14.300539 -197.094257)
			(xy 14.336791 -197.055186) (xy 14.378462 -197.021955) (xy 14.42462 -196.995306) (xy 14.474234 -196.975834)
			(xy 14.526196 -196.963974) (xy 14.579346 -196.959991) (xy 14.632496 -196.963974) (xy 14.684458 -196.975834)
			(xy 14.734072 -196.995306) (xy 14.78023 -197.021955) (xy 14.821901 -197.055186) (xy 14.858153 -197.094257)
			(xy 14.888177 -197.138294) (xy 14.911303 -197.186315) (xy 14.927013 -197.237245) (xy 14.934956 -197.289949)
			(xy 14.935454 -197.316598) (xy 14.934956 -197.343247) (xy 16.433536 -197.343247) (xy 16.433536 -197.289949)
			(xy 16.441479 -197.237245) (xy 16.457189 -197.186315) (xy 16.480315 -197.138294) (xy 16.510339 -197.094257)
			(xy 16.546591 -197.055186) (xy 16.588262 -197.021955) (xy 16.63442 -196.995306) (xy 16.684034 -196.975834)
			(xy 16.735996 -196.963974) (xy 16.789146 -196.959991) (xy 16.842296 -196.963974) (xy 16.894258 -196.975834)
			(xy 16.943872 -196.995306) (xy 16.99003 -197.021955) (xy 17.031701 -197.055186) (xy 17.067953 -197.094257)
			(xy 17.097977 -197.138294) (xy 17.121103 -197.186315) (xy 17.136813 -197.237245) (xy 17.144756 -197.289949)
			(xy 17.145254 -197.316598) (xy 17.144756 -197.343247) (xy 20.533604 -197.343247) (xy 20.533604 -197.289949)
			(xy 20.541547 -197.237245) (xy 20.557257 -197.186315) (xy 20.580383 -197.138294) (xy 20.610407 -197.094257)
			(xy 20.646659 -197.055186) (xy 20.68833 -197.021955) (xy 20.734488 -196.995306) (xy 20.784102 -196.975834)
			(xy 20.836064 -196.963974) (xy 20.889214 -196.959991) (xy 20.942364 -196.963974) (xy 20.994326 -196.975834)
			(xy 21.04394 -196.995306) (xy 21.090098 -197.021955) (xy 21.131769 -197.055186) (xy 21.168021 -197.094257)
			(xy 21.198045 -197.138294) (xy 21.221171 -197.186315) (xy 21.236881 -197.237245) (xy 21.244824 -197.289949)
			(xy 21.245322 -197.316598) (xy 21.244824 -197.343247) (xy 21.767536 -197.343247) (xy 21.767536 -197.289949)
			(xy 21.775479 -197.237245) (xy 21.791189 -197.186315) (xy 21.814315 -197.138294) (xy 21.844339 -197.094257)
			(xy 21.880591 -197.055186) (xy 21.922262 -197.021955) (xy 21.96842 -196.995306) (xy 22.018034 -196.975834)
			(xy 22.069996 -196.963974) (xy 22.123146 -196.959991) (xy 22.176296 -196.963974) (xy 22.228258 -196.975834)
			(xy 22.277872 -196.995306) (xy 22.32403 -197.021955) (xy 22.365701 -197.055186) (xy 22.401953 -197.094257)
			(xy 22.431977 -197.138294) (xy 22.455103 -197.186315) (xy 22.470813 -197.237245) (xy 22.478756 -197.289949)
			(xy 22.479254 -197.316598) (xy 22.478756 -197.343247) (xy 23.977336 -197.343247) (xy 23.977336 -197.289949)
			(xy 23.985279 -197.237245) (xy 24.000989 -197.186315) (xy 24.024115 -197.138294) (xy 24.054139 -197.094257)
			(xy 24.090391 -197.055186) (xy 24.132062 -197.021955) (xy 24.17822 -196.995306) (xy 24.227834 -196.975834)
			(xy 24.279796 -196.963974) (xy 24.332946 -196.959991) (xy 24.386096 -196.963974) (xy 24.438058 -196.975834)
			(xy 24.487672 -196.995306) (xy 24.53383 -197.021955) (xy 24.575501 -197.055186) (xy 24.611753 -197.094257)
			(xy 24.641777 -197.138294) (xy 24.664903 -197.186315) (xy 24.680613 -197.237245) (xy 24.688556 -197.289949)
			(xy 24.689054 -197.316598) (xy 24.688556 -197.343247) (xy 24.680613 -197.395951) (xy 24.664903 -197.446881)
			(xy 24.641777 -197.494902) (xy 24.611753 -197.538939) (xy 24.575501 -197.57801) (xy 24.53383 -197.611241)
			(xy 24.487672 -197.63789) (xy 24.438058 -197.657362) (xy 24.386096 -197.669222) (xy 24.332946 -197.673206)
			(xy 24.279796 -197.669222) (xy 24.227834 -197.657362) (xy 24.17822 -197.63789) (xy 24.132062 -197.611241)
			(xy 24.090391 -197.57801) (xy 24.054139 -197.538939) (xy 24.024115 -197.494902) (xy 24.000989 -197.446881)
			(xy 23.985279 -197.395951) (xy 23.977336 -197.343247) (xy 22.478756 -197.343247) (xy 22.470813 -197.395951)
			(xy 22.455103 -197.446881) (xy 22.431977 -197.494902) (xy 22.401953 -197.538939) (xy 22.365701 -197.57801)
			(xy 22.32403 -197.611241) (xy 22.277872 -197.63789) (xy 22.228258 -197.657362) (xy 22.176296 -197.669222)
			(xy 22.123146 -197.673206) (xy 22.069996 -197.669222) (xy 22.018034 -197.657362) (xy 21.96842 -197.63789)
			(xy 21.922262 -197.611241) (xy 21.880591 -197.57801) (xy 21.844339 -197.538939) (xy 21.814315 -197.494902)
			(xy 21.791189 -197.446881) (xy 21.775479 -197.395951) (xy 21.767536 -197.343247) (xy 21.244824 -197.343247)
			(xy 21.236881 -197.395951) (xy 21.221171 -197.446881) (xy 21.198045 -197.494902) (xy 21.168021 -197.538939)
			(xy 21.131769 -197.57801) (xy 21.090098 -197.611241) (xy 21.04394 -197.63789) (xy 20.994326 -197.657362)
			(xy 20.942364 -197.669222) (xy 20.889214 -197.673206) (xy 20.836064 -197.669222) (xy 20.784102 -197.657362)
			(xy 20.734488 -197.63789) (xy 20.68833 -197.611241) (xy 20.646659 -197.57801) (xy 20.610407 -197.538939)
			(xy 20.580383 -197.494902) (xy 20.557257 -197.446881) (xy 20.541547 -197.395951) (xy 20.533604 -197.343247)
			(xy 17.144756 -197.343247) (xy 17.136813 -197.395951) (xy 17.121103 -197.446881) (xy 17.097977 -197.494902)
			(xy 17.067953 -197.538939) (xy 17.031701 -197.57801) (xy 16.99003 -197.611241) (xy 16.943872 -197.63789)
			(xy 16.894258 -197.657362) (xy 16.842296 -197.669222) (xy 16.789146 -197.673206) (xy 16.735996 -197.669222)
			(xy 16.684034 -197.657362) (xy 16.63442 -197.63789) (xy 16.588262 -197.611241) (xy 16.546591 -197.57801)
			(xy 16.510339 -197.538939) (xy 16.480315 -197.494902) (xy 16.457189 -197.446881) (xy 16.441479 -197.395951)
			(xy 16.433536 -197.343247) (xy 14.934956 -197.343247) (xy 14.927013 -197.395951) (xy 14.911303 -197.446881)
			(xy 14.888177 -197.494902) (xy 14.858153 -197.538939) (xy 14.821901 -197.57801) (xy 14.78023 -197.611241)
			(xy 14.734072 -197.63789) (xy 14.684458 -197.657362) (xy 14.632496 -197.669222) (xy 14.579346 -197.673206)
			(xy 14.526196 -197.669222) (xy 14.474234 -197.657362) (xy 14.42462 -197.63789) (xy 14.378462 -197.611241)
			(xy 14.336791 -197.57801) (xy 14.300539 -197.538939) (xy 14.270515 -197.494902) (xy 14.247389 -197.446881)
			(xy 14.231679 -197.395951) (xy 14.223736 -197.343247) (xy 9.600956 -197.343247) (xy 9.593013 -197.395951)
			(xy 9.577303 -197.446881) (xy 9.554177 -197.494902) (xy 9.524153 -197.538939) (xy 9.487901 -197.57801)
			(xy 9.44623 -197.611241) (xy 9.400072 -197.63789) (xy 9.350458 -197.657362) (xy 9.298496 -197.669222)
			(xy 9.245346 -197.673206) (xy 9.192196 -197.669222) (xy 9.140234 -197.657362) (xy 9.09062 -197.63789)
			(xy 9.044462 -197.611241) (xy 9.002791 -197.57801) (xy 8.966539 -197.538939) (xy 8.936515 -197.494902)
			(xy 8.913389 -197.446881) (xy 8.897679 -197.395951) (xy 8.889736 -197.343247) (xy 8.546592 -197.343247)
			(xy 8.546592 -197.83298) (xy 8.906997 -198.193385) (xy 10.780004 -198.193385) (xy 10.780004 -198.140087)
			(xy 10.787947 -198.087383) (xy 10.803657 -198.036453) (xy 10.826783 -197.988432) (xy 10.856807 -197.944395)
			(xy 10.893059 -197.905324) (xy 10.93473 -197.872093) (xy 10.980888 -197.845444) (xy 11.030502 -197.825972)
			(xy 11.082464 -197.814112) (xy 11.135614 -197.810129) (xy 11.188764 -197.814112) (xy 11.240726 -197.825972)
			(xy 11.29034 -197.845444) (xy 11.336498 -197.872093) (xy 11.378169 -197.905324) (xy 11.414421 -197.944395)
			(xy 11.444445 -197.988432) (xy 11.467571 -198.036453) (xy 11.483281 -198.087383) (xy 11.491224 -198.140087)
			(xy 11.491722 -198.166736) (xy 11.491224 -198.193385) (xy 12.989804 -198.193385) (xy 12.989804 -198.140087)
			(xy 12.997747 -198.087383) (xy 13.013457 -198.036453) (xy 13.036583 -197.988432) (xy 13.066607 -197.944395)
			(xy 13.102859 -197.905324) (xy 13.14453 -197.872093) (xy 13.190688 -197.845444) (xy 13.240302 -197.825972)
			(xy 13.292264 -197.814112) (xy 13.345414 -197.810129) (xy 13.398564 -197.814112) (xy 13.450526 -197.825972)
			(xy 13.50014 -197.845444) (xy 13.546298 -197.872093) (xy 13.587969 -197.905324) (xy 13.624221 -197.944395)
			(xy 13.654245 -197.988432) (xy 13.677371 -198.036453) (xy 13.693081 -198.087383) (xy 13.701024 -198.140087)
			(xy 13.701522 -198.166736) (xy 13.701024 -198.193385) (xy 16.433536 -198.193385) (xy 16.433536 -198.140087)
			(xy 16.441479 -198.087383) (xy 16.457189 -198.036453) (xy 16.480315 -197.988432) (xy 16.510339 -197.944395)
			(xy 16.546591 -197.905324) (xy 16.588262 -197.872093) (xy 16.63442 -197.845444) (xy 16.684034 -197.825972)
			(xy 16.735996 -197.814112) (xy 16.789146 -197.810129) (xy 16.842296 -197.814112) (xy 16.894258 -197.825972)
			(xy 16.943872 -197.845444) (xy 16.99003 -197.872093) (xy 17.031701 -197.905324) (xy 17.067953 -197.944395)
			(xy 17.097977 -197.988432) (xy 17.121103 -198.036453) (xy 17.136813 -198.087383) (xy 17.144756 -198.140087)
			(xy 17.145254 -198.166736) (xy 17.144756 -198.193385) (xy 18.323804 -198.193385) (xy 18.323804 -198.140087)
			(xy 18.331747 -198.087383) (xy 18.347457 -198.036453) (xy 18.370583 -197.988432) (xy 18.400607 -197.944395)
			(xy 18.436859 -197.905324) (xy 18.47853 -197.872093) (xy 18.524688 -197.845444) (xy 18.574302 -197.825972)
			(xy 18.626264 -197.814112) (xy 18.679414 -197.810129) (xy 18.732564 -197.814112) (xy 18.784526 -197.825972)
			(xy 18.83414 -197.845444) (xy 18.880298 -197.872093) (xy 18.921969 -197.905324) (xy 18.958221 -197.944395)
			(xy 18.988245 -197.988432) (xy 19.011371 -198.036453) (xy 19.027081 -198.087383) (xy 19.035024 -198.140087)
			(xy 19.035522 -198.166736) (xy 19.035024 -198.193385) (xy 20.533604 -198.193385) (xy 20.533604 -198.140087)
			(xy 20.541547 -198.087383) (xy 20.557257 -198.036453) (xy 20.580383 -197.988432) (xy 20.610407 -197.944395)
			(xy 20.646659 -197.905324) (xy 20.68833 -197.872093) (xy 20.734488 -197.845444) (xy 20.784102 -197.825972)
			(xy 20.836064 -197.814112) (xy 20.889214 -197.810129) (xy 20.942364 -197.814112) (xy 20.994326 -197.825972)
			(xy 21.04394 -197.845444) (xy 21.090098 -197.872093) (xy 21.131769 -197.905324) (xy 21.168021 -197.944395)
			(xy 21.198045 -197.988432) (xy 21.221171 -198.036453) (xy 21.236881 -198.087383) (xy 21.244824 -198.140087)
			(xy 21.245322 -198.166736) (xy 21.244824 -198.193385) (xy 25.867604 -198.193385) (xy 25.867604 -198.140087)
			(xy 25.875547 -198.087383) (xy 25.891257 -198.036453) (xy 25.914383 -197.988432) (xy 25.944407 -197.944395)
			(xy 25.980659 -197.905324) (xy 26.02233 -197.872093) (xy 26.068488 -197.845444) (xy 26.118102 -197.825972)
			(xy 26.170064 -197.814112) (xy 26.223214 -197.810129) (xy 26.276364 -197.814112) (xy 26.328326 -197.825972)
			(xy 26.37794 -197.845444) (xy 26.424098 -197.872093) (xy 26.465769 -197.905324) (xy 26.502021 -197.944395)
			(xy 26.532045 -197.988432) (xy 26.555171 -198.036453) (xy 26.570881 -198.087383) (xy 26.578824 -198.140087)
			(xy 26.579322 -198.166736) (xy 26.578824 -198.193385) (xy 26.570881 -198.246089) (xy 26.555171 -198.297019)
			(xy 26.532045 -198.34504) (xy 26.502021 -198.389077) (xy 26.465769 -198.428148) (xy 26.424098 -198.461379)
			(xy 26.37794 -198.488028) (xy 26.328326 -198.5075) (xy 26.276364 -198.51936) (xy 26.223214 -198.523344)
			(xy 26.170064 -198.51936) (xy 26.118102 -198.5075) (xy 26.068488 -198.488028) (xy 26.02233 -198.461379)
			(xy 25.980659 -198.428148) (xy 25.944407 -198.389077) (xy 25.914383 -198.34504) (xy 25.891257 -198.297019)
			(xy 25.875547 -198.246089) (xy 25.867604 -198.193385) (xy 21.244824 -198.193385) (xy 21.236881 -198.246089)
			(xy 21.221171 -198.297019) (xy 21.198045 -198.34504) (xy 21.168021 -198.389077) (xy 21.131769 -198.428148)
			(xy 21.090098 -198.461379) (xy 21.04394 -198.488028) (xy 20.994326 -198.5075) (xy 20.942364 -198.51936)
			(xy 20.889214 -198.523344) (xy 20.836064 -198.51936) (xy 20.784102 -198.5075) (xy 20.734488 -198.488028)
			(xy 20.68833 -198.461379) (xy 20.646659 -198.428148) (xy 20.610407 -198.389077) (xy 20.580383 -198.34504)
			(xy 20.557257 -198.297019) (xy 20.541547 -198.246089) (xy 20.533604 -198.193385) (xy 19.035024 -198.193385)
			(xy 19.027081 -198.246089) (xy 19.011371 -198.297019) (xy 18.988245 -198.34504) (xy 18.958221 -198.389077)
			(xy 18.921969 -198.428148) (xy 18.880298 -198.461379) (xy 18.83414 -198.488028) (xy 18.784526 -198.5075)
			(xy 18.732564 -198.51936) (xy 18.679414 -198.523344) (xy 18.626264 -198.51936) (xy 18.574302 -198.5075)
			(xy 18.524688 -198.488028) (xy 18.47853 -198.461379) (xy 18.436859 -198.428148) (xy 18.400607 -198.389077)
			(xy 18.370583 -198.34504) (xy 18.347457 -198.297019) (xy 18.331747 -198.246089) (xy 18.323804 -198.193385)
			(xy 17.144756 -198.193385) (xy 17.136813 -198.246089) (xy 17.121103 -198.297019) (xy 17.097977 -198.34504)
			(xy 17.067953 -198.389077) (xy 17.031701 -198.428148) (xy 16.99003 -198.461379) (xy 16.943872 -198.488028)
			(xy 16.894258 -198.5075) (xy 16.842296 -198.51936) (xy 16.789146 -198.523344) (xy 16.735996 -198.51936)
			(xy 16.684034 -198.5075) (xy 16.63442 -198.488028) (xy 16.588262 -198.461379) (xy 16.546591 -198.428148)
			(xy 16.510339 -198.389077) (xy 16.480315 -198.34504) (xy 16.457189 -198.297019) (xy 16.441479 -198.246089)
			(xy 16.433536 -198.193385) (xy 13.701024 -198.193385) (xy 13.693081 -198.246089) (xy 13.677371 -198.297019)
			(xy 13.654245 -198.34504) (xy 13.624221 -198.389077) (xy 13.587969 -198.428148) (xy 13.546298 -198.461379)
			(xy 13.50014 -198.488028) (xy 13.450526 -198.5075) (xy 13.398564 -198.51936) (xy 13.345414 -198.523344)
			(xy 13.292264 -198.51936) (xy 13.240302 -198.5075) (xy 13.190688 -198.488028) (xy 13.14453 -198.461379)
			(xy 13.102859 -198.428148) (xy 13.066607 -198.389077) (xy 13.036583 -198.34504) (xy 13.013457 -198.297019)
			(xy 12.997747 -198.246089) (xy 12.989804 -198.193385) (xy 11.491224 -198.193385) (xy 11.483281 -198.246089)
			(xy 11.467571 -198.297019) (xy 11.444445 -198.34504) (xy 11.414421 -198.389077) (xy 11.378169 -198.428148)
			(xy 11.336498 -198.461379) (xy 11.29034 -198.488028) (xy 11.240726 -198.5075) (xy 11.188764 -198.51936)
			(xy 11.135614 -198.523344) (xy 11.082464 -198.51936) (xy 11.030502 -198.5075) (xy 10.980888 -198.488028)
			(xy 10.93473 -198.461379) (xy 10.893059 -198.428148) (xy 10.856807 -198.389077) (xy 10.826783 -198.34504)
			(xy 10.803657 -198.297019) (xy 10.787947 -198.246089) (xy 10.780004 -198.193385) (xy 8.906997 -198.193385)
			(xy 9.41959 -198.705978) (xy 9.425178 -198.70928) (xy 9.451106 -198.725172) (xy 9.497608 -198.764356)
			(xy 9.53678 -198.810868) (xy 9.552686 -198.836788) (xy 9.555988 -198.842376) (xy 10.17016 -199.456548)
			(xy 14.27099 -199.456548) (xy 14.284588 -199.456144) (xy 14.310831 -199.449014) (xy 14.334258 -199.435205)
			(xy 14.353206 -199.415699) (xy 14.366327 -199.391879) (xy 14.37269 -199.36544) (xy 14.371843 -199.338259)
			(xy 14.363846 -199.312268) (xy 14.349266 -199.289312) (xy 14.33957 -199.279764) (xy 14.321593 -199.26283)
			(xy 14.290016 -199.224858) (xy 14.263992 -199.182885) (xy 14.244019 -199.137717) (xy 14.230481 -199.090223)
			(xy 14.223638 -199.041313) (xy 14.223238 -199.01662) (xy 14.223736 -198.989971) (xy 14.231679 -198.937267)
			(xy 14.247389 -198.886337) (xy 14.270515 -198.838316) (xy 14.300539 -198.794279) (xy 14.336791 -198.755208)
			(xy 14.378462 -198.721977) (xy 14.42462 -198.695328) (xy 14.474234 -198.675856) (xy 14.526196 -198.663996)
			(xy 14.579346 -198.660013) (xy 14.632496 -198.663996) (xy 14.684458 -198.675856) (xy 14.734072 -198.695328)
			(xy 14.78023 -198.721977) (xy 14.821901 -198.755208) (xy 14.858153 -198.794279) (xy 14.888177 -198.838316)
			(xy 14.911303 -198.886337) (xy 14.927013 -198.937267) (xy 14.934956 -198.989971) (xy 14.935454 -199.01662)
			(xy 14.93503 -199.041312) (xy 14.928197 -199.090221) (xy 14.914665 -199.137715) (xy 14.894693 -199.182881)
			(xy 14.868667 -199.224851) (xy 14.837086 -199.262817) (xy 14.819122 -199.279764) (xy 14.809356 -199.289236)
			(xy 14.79479 -199.312204) (xy 14.786805 -199.338202) (xy 14.78597 -199.365386) (xy 14.792344 -199.391826)
			(xy 14.805473 -199.415644) (xy 14.824426 -199.435149) (xy 14.847857 -199.448957) (xy 14.874103 -199.456087)
			(xy 14.887702 -199.456548) (xy 16.48079 -199.456548) (xy 16.494388 -199.456144) (xy 16.520631 -199.449014)
			(xy 16.544058 -199.435205) (xy 16.563006 -199.415699) (xy 16.576127 -199.391879) (xy 16.58249 -199.36544)
			(xy 16.581643 -199.338259) (xy 16.573646 -199.312268) (xy 16.559066 -199.289312) (xy 16.54937 -199.279764)
			(xy 16.531393 -199.26283) (xy 16.499816 -199.224858) (xy 16.473792 -199.182885) (xy 16.453819 -199.137717)
			(xy 16.440281 -199.090223) (xy 16.433438 -199.041313) (xy 16.433038 -199.01662) (xy 16.433536 -198.989971)
			(xy 16.441479 -198.937267) (xy 16.457189 -198.886337) (xy 16.480315 -198.838316) (xy 16.510339 -198.794279)
			(xy 16.546591 -198.755208) (xy 16.588262 -198.721977) (xy 16.63442 -198.695328) (xy 16.684034 -198.675856)
			(xy 16.735996 -198.663996) (xy 16.789146 -198.660013) (xy 16.842296 -198.663996) (xy 16.894258 -198.675856)
			(xy 16.943872 -198.695328) (xy 16.99003 -198.721977) (xy 17.031701 -198.755208) (xy 17.067953 -198.794279)
			(xy 17.097977 -198.838316) (xy 17.121103 -198.886337) (xy 17.136813 -198.937267) (xy 17.144756 -198.989971)
			(xy 17.145254 -199.01662) (xy 17.14483 -199.041312) (xy 17.137997 -199.090221) (xy 17.124465 -199.137715)
			(xy 17.104493 -199.182881) (xy 17.078467 -199.224851) (xy 17.046886 -199.262817) (xy 17.028922 -199.279764)
			(xy 17.019156 -199.289236) (xy 17.00459 -199.312204) (xy 16.996605 -199.338202) (xy 16.99577 -199.365386)
			(xy 17.002144 -199.391826) (xy 17.015273 -199.415644) (xy 17.034226 -199.435149) (xy 17.057657 -199.448957)
			(xy 17.083903 -199.456087) (xy 17.097502 -199.456548) (xy 20.580858 -199.456548) (xy 20.594459 -199.456147)
			(xy 20.62071 -199.449023) (xy 20.644145 -199.435216) (xy 20.6631 -199.415707) (xy 20.676226 -199.391883)
			(xy 20.68259 -199.365438) (xy 20.681742 -199.338251) (xy 20.67374 -199.312254) (xy 20.659153 -199.289296)
			(xy 20.649438 -199.279764) (xy 20.631462 -199.262829) (xy 20.599889 -199.224856) (xy 20.573866 -199.182882)
			(xy 20.553895 -199.137715) (xy 20.540359 -199.090222) (xy 20.533516 -199.041313) (xy 20.533106 -199.01662)
			(xy 20.533604 -198.989971) (xy 20.541547 -198.937267) (xy 20.557257 -198.886337) (xy 20.580383 -198.838316)
			(xy 20.610407 -198.794279) (xy 20.646659 -198.755208) (xy 20.68833 -198.721977) (xy 20.734488 -198.695328)
			(xy 20.784102 -198.675856) (xy 20.836064 -198.663996) (xy 20.889214 -198.660013) (xy 20.942364 -198.663996)
			(xy 20.994326 -198.675856) (xy 21.04394 -198.695328) (xy 21.090098 -198.721977) (xy 21.131769 -198.755208)
			(xy 21.168021 -198.794279) (xy 21.198045 -198.838316) (xy 21.221171 -198.886337) (xy 21.236881 -198.937267)
			(xy 21.244824 -198.989971) (xy 21.245322 -199.01662) (xy 21.244898 -199.041312) (xy 21.238064 -199.090221)
			(xy 21.224531 -199.137714) (xy 21.204559 -199.182879) (xy 21.178531 -199.224846) (xy 21.146948 -199.262811)
			(xy 21.12899 -199.279764) (xy 21.119219 -199.289232) (xy 21.104644 -199.312195) (xy 21.096653 -199.338192)
			(xy 21.095815 -199.365377) (xy 21.10219 -199.391817) (xy 21.115323 -199.415634) (xy 21.134282 -199.435135)
			(xy 21.157719 -199.448933) (xy 21.18397 -199.456049) (xy 21.19757 -199.456548) (xy 21.81479 -199.456548)
			(xy 21.828388 -199.456144) (xy 21.854631 -199.449014) (xy 21.878058 -199.435205) (xy 21.897006 -199.415699)
			(xy 21.910127 -199.391879) (xy 21.91649 -199.36544) (xy 21.915643 -199.338259) (xy 21.907646 -199.312268)
			(xy 21.893066 -199.289312) (xy 21.88337 -199.279764) (xy 21.865393 -199.26283) (xy 21.833816 -199.224858)
			(xy 21.807792 -199.182885) (xy 21.787819 -199.137717) (xy 21.774281 -199.090223) (xy 21.767438 -199.041313)
			(xy 21.767038 -199.01662) (xy 21.767536 -198.989971) (xy 21.775479 -198.937267) (xy 21.791189 -198.886337)
			(xy 21.814315 -198.838316) (xy 21.844339 -198.794279) (xy 21.880591 -198.755208) (xy 21.922262 -198.721977)
			(xy 21.96842 -198.695328) (xy 22.018034 -198.675856) (xy 22.069996 -198.663996) (xy 22.123146 -198.660013)
			(xy 22.176296 -198.663996) (xy 22.228258 -198.675856) (xy 22.277872 -198.695328) (xy 22.32403 -198.721977)
			(xy 22.365701 -198.755208) (xy 22.401953 -198.794279) (xy 22.431977 -198.838316) (xy 22.455103 -198.886337)
			(xy 22.470813 -198.937267) (xy 22.478756 -198.989971) (xy 22.479254 -199.01662) (xy 22.47883 -199.041312)
			(xy 22.471997 -199.090221) (xy 22.458465 -199.137715) (xy 22.438493 -199.182881) (xy 22.412467 -199.224851)
			(xy 22.380886 -199.262817) (xy 22.362922 -199.279764) (xy 22.353156 -199.289236) (xy 22.33859 -199.312204)
			(xy 22.330605 -199.338202) (xy 22.32977 -199.365386) (xy 22.336144 -199.391826) (xy 22.349273 -199.415644)
			(xy 22.368226 -199.435149) (xy 22.391657 -199.448957) (xy 22.417903 -199.456087) (xy 22.431502 -199.456548)
			(xy 24.02459 -199.456548) (xy 24.038188 -199.456144) (xy 24.064431 -199.449014) (xy 24.087858 -199.435205)
			(xy 24.106806 -199.415699) (xy 24.119927 -199.391879) (xy 24.12629 -199.36544) (xy 24.125443 -199.338259)
			(xy 24.117446 -199.312268) (xy 24.102866 -199.289312) (xy 24.09317 -199.279764) (xy 24.075193 -199.26283)
			(xy 24.043616 -199.224858) (xy 24.017592 -199.182885) (xy 23.997619 -199.137717) (xy 23.984081 -199.090223)
			(xy 23.977238 -199.041313) (xy 23.976838 -199.01662) (xy 23.977336 -198.989971) (xy 23.985279 -198.937267)
			(xy 24.000989 -198.886337) (xy 24.024115 -198.838316) (xy 24.054139 -198.794279) (xy 24.090391 -198.755208)
			(xy 24.132062 -198.721977) (xy 24.17822 -198.695328) (xy 24.227834 -198.675856) (xy 24.279796 -198.663996)
			(xy 24.332946 -198.660013) (xy 24.386096 -198.663996) (xy 24.438058 -198.675856) (xy 24.487672 -198.695328)
			(xy 24.53383 -198.721977) (xy 24.575501 -198.755208) (xy 24.611753 -198.794279) (xy 24.641777 -198.838316)
			(xy 24.664903 -198.886337) (xy 24.680613 -198.937267) (xy 24.688556 -198.989971) (xy 24.689054 -199.01662)
			(xy 24.68863 -199.041312) (xy 24.681797 -199.090221) (xy 24.668265 -199.137715) (xy 24.648293 -199.182881)
			(xy 24.622267 -199.224851) (xy 24.590686 -199.262817) (xy 24.572722 -199.279764) (xy 24.562956 -199.289236)
			(xy 24.54839 -199.312204) (xy 24.540405 -199.338202) (xy 24.53957 -199.365386) (xy 24.545944 -199.391826)
			(xy 24.559073 -199.415644) (xy 24.578026 -199.435149) (xy 24.601457 -199.448957) (xy 24.627703 -199.456087)
			(xy 24.641302 -199.456548) (xy 25.86228 -199.456548) (xy 28.349702 -196.969126) (xy 28.3597 -196.958456)
			(xy 28.373672 -196.932782) (xy 28.3798 -196.904202) (xy 28.377582 -196.875056) (xy 28.3672 -196.847733)
			(xy 28.349503 -196.824469) (xy 28.325942 -196.807171) (xy 28.312364 -196.80174) (xy 28.286873 -196.792008)
			(xy 28.238959 -196.76591) (xy 28.195587 -196.732808) (xy 28.157772 -196.693478) (xy 28.1264 -196.648839)
			(xy 28.102204 -196.599937) (xy 28.08575 -196.547916) (xy 28.077425 -196.493994) (xy 28.076906 -196.466714)
			(xy 28.077426 -196.438728) (xy 28.08618 -196.383446) (xy 28.103474 -196.330214) (xy 28.128884 -196.280342)
			(xy 28.161783 -196.23506) (xy 28.20136 -196.195483) (xy 28.246642 -196.162584) (xy 28.296514 -196.137174)
			(xy 28.349746 -196.11988) (xy 28.405028 -196.111126) (xy 28.433014 -196.110606) (xy 28.460294 -196.111128)
			(xy 28.514215 -196.119453) (xy 28.566236 -196.135906) (xy 28.615137 -196.160102) (xy 28.659776 -196.191474)
			(xy 28.699106 -196.229289) (xy 28.732208 -196.272661) (xy 28.758306 -196.320574) (xy 28.76804 -196.346064)
			(xy 28.773466 -196.359631) (xy 28.790786 -196.383152) (xy 28.81405 -196.400815) (xy 28.841359 -196.411178)
			(xy 28.870484 -196.413395) (xy 28.899047 -196.407284) (xy 28.924716 -196.393346) (xy 28.935426 -196.383402)
			(xy 29.431234 -195.887594) (xy 29.399738 -195.85178) (xy 29.383078 -195.832192) (xy 29.354986 -195.789123)
			(xy 29.333385 -195.742458) (xy 29.318726 -195.693171) (xy 29.311314 -195.642287) (xy 29.310838 -195.616576)
			(xy 29.31136 -195.588593) (xy 29.320119 -195.533317) (xy 29.337418 -195.480092) (xy 29.36283 -195.430229)
			(xy 29.39573 -195.384954) (xy 29.435308 -195.345385) (xy 29.480588 -195.312494) (xy 29.530457 -195.287091)
			(xy 29.583685 -195.269803) (xy 29.638963 -195.261055) (xy 29.666946 -195.260468) (xy 29.692654 -195.260944)
			(xy 29.743531 -195.268381) (xy 29.792811 -195.283052) (xy 29.839472 -195.304651) (xy 29.882544 -195.332731)
			(xy 29.90215 -195.349368) (xy 29.937964 -195.380864) (xy 33.459928 -191.8589) (xy 48.616616 -191.8589)
			(xy 48.619918 -191.858392) (xy 48.63162 -191.857066) (xy 48.655131 -191.85567) (xy 48.666908 -191.855598)
			(xy 48.678685 -191.855655) (xy 48.702197 -191.857055) (xy 48.713898 -191.858392) (xy 48.7172 -191.8589)
			(xy 49.632616 -191.8589) (xy 49.635918 -191.858392) (xy 49.64762 -191.857066) (xy 49.671131 -191.85567)
			(xy 49.682908 -191.855598) (xy 49.694685 -191.855655) (xy 49.718197 -191.857055) (xy 49.729898 -191.858392)
			(xy 49.7332 -191.8589) (xy 55.849012 -191.8589) (xy 55.851552 -191.858646) (xy 55.888382 -191.856868)
			(xy 55.925212 -191.858646) (xy 55.927752 -191.8589) (xy 59.021726 -191.8589) (xy 59.04329 -191.88049)
			(xy 61.97168 -191.88049) (xy 61.975751 -191.824868) (xy 61.987877 -191.770431) (xy 62.0078 -191.71834)
			(xy 62.035096 -191.669705) (xy 62.069182 -191.625562) (xy 62.109331 -191.586853) (xy 62.154689 -191.554402)
			(xy 62.204289 -191.528901) (xy 62.257073 -191.510894) (xy 62.311916 -191.500764) (xy 62.36765 -191.498727)
			(xy 62.423087 -191.504827) (xy 62.477044 -191.518933) (xy 62.528373 -191.540745) (xy 62.575979 -191.569799)
			(xy 62.618847 -191.605474) (xy 62.656064 -191.647011) (xy 62.686837 -191.693524) (xy 62.710509 -191.744021)
			(xy 62.726577 -191.797428) (xy 62.734697 -191.852604) (xy 62.734789 -191.85763) (xy 63.89446 -191.85763)
			(xy 63.898531 -191.802008) (xy 63.910657 -191.747571) (xy 63.93058 -191.69548) (xy 63.957876 -191.646845)
			(xy 63.991962 -191.602702) (xy 64.032111 -191.563993) (xy 64.077469 -191.531542) (xy 64.127069 -191.506041)
			(xy 64.179853 -191.488034) (xy 64.234696 -191.477904) (xy 64.29043 -191.475867) (xy 64.345867 -191.481967)
			(xy 64.399824 -191.496073) (xy 64.451153 -191.517885) (xy 64.498759 -191.546939) (xy 64.541627 -191.582614)
			(xy 64.578844 -191.624151) (xy 64.609617 -191.670664) (xy 64.633289 -191.721161) (xy 64.649357 -191.774568)
			(xy 64.657477 -191.829744) (xy 64.657986 -191.85763) (xy 64.657477 -191.885516) (xy 64.649357 -191.940692)
			(xy 64.633289 -191.994099) (xy 64.609617 -192.044596) (xy 64.578844 -192.091109) (xy 64.541627 -192.132646)
			(xy 64.498759 -192.168321) (xy 64.451153 -192.197375) (xy 64.399824 -192.219187) (xy 64.345867 -192.233293)
			(xy 64.29043 -192.239393) (xy 64.234696 -192.237356) (xy 64.179853 -192.227226) (xy 64.127069 -192.209219)
			(xy 64.077469 -192.183718) (xy 64.032111 -192.151267) (xy 63.991962 -192.112558) (xy 63.957876 -192.068415)
			(xy 63.93058 -192.01978) (xy 63.910657 -191.967689) (xy 63.898531 -191.913252) (xy 63.89446 -191.85763)
			(xy 62.734789 -191.85763) (xy 62.735206 -191.88049) (xy 62.734697 -191.908376) (xy 62.726577 -191.963552)
			(xy 62.710509 -192.016959) (xy 62.686837 -192.067456) (xy 62.656064 -192.113969) (xy 62.618847 -192.155506)
			(xy 62.575979 -192.191181) (xy 62.528373 -192.220235) (xy 62.477044 -192.242047) (xy 62.423087 -192.256153)
			(xy 62.36765 -192.262253) (xy 62.311916 -192.260216) (xy 62.257073 -192.250086) (xy 62.204289 -192.232079)
			(xy 62.154689 -192.206578) (xy 62.109331 -192.174127) (xy 62.069182 -192.135418) (xy 62.035096 -192.091275)
			(xy 62.0078 -192.04264) (xy 61.987877 -191.990549) (xy 61.975751 -191.936112) (xy 61.97168 -191.88049)
			(xy 59.04329 -191.88049) (xy 59.23153 -192.068958) (xy 60.261246 -192.068958) (xy 60.679076 -192.486788)
			(xy 65.533522 -192.486788) (xy 65.537593 -192.431166) (xy 65.549719 -192.376729) (xy 65.569642 -192.324638)
			(xy 65.596938 -192.276003) (xy 65.631024 -192.23186) (xy 65.671173 -192.193151) (xy 65.716531 -192.1607)
			(xy 65.766131 -192.135199) (xy 65.818915 -192.117192) (xy 65.873758 -192.107062) (xy 65.929492 -192.105025)
			(xy 65.984929 -192.111125) (xy 66.038886 -192.125231) (xy 66.090215 -192.147043) (xy 66.137821 -192.176097)
			(xy 66.180689 -192.211772) (xy 66.217906 -192.253309) (xy 66.248679 -192.299822) (xy 66.272351 -192.350319)
			(xy 66.288419 -192.403726) (xy 66.296539 -192.458902) (xy 66.297048 -192.486788) (xy 66.296539 -192.514674)
			(xy 66.288419 -192.56985) (xy 66.272351 -192.623257) (xy 66.248679 -192.673754) (xy 66.217906 -192.720267)
			(xy 66.180689 -192.761804) (xy 66.137821 -192.797479) (xy 66.090215 -192.826533) (xy 66.038886 -192.848345)
			(xy 65.984929 -192.862451) (xy 65.929492 -192.868551) (xy 65.873758 -192.866514) (xy 65.818915 -192.856384)
			(xy 65.766131 -192.838377) (xy 65.716531 -192.812876) (xy 65.671173 -192.780425) (xy 65.631024 -192.741716)
			(xy 65.596938 -192.697573) (xy 65.569642 -192.648938) (xy 65.549719 -192.596847) (xy 65.537593 -192.54241)
			(xy 65.533522 -192.486788) (xy 60.679076 -192.486788) (xy 62.985629 -194.793341) (xy 63.586604 -194.793341)
			(xy 63.586604 -194.740043) (xy 63.594547 -194.687339) (xy 63.610257 -194.636409) (xy 63.633383 -194.588388)
			(xy 63.663407 -194.544351) (xy 63.699659 -194.50528) (xy 63.74133 -194.472049) (xy 63.787488 -194.4454)
			(xy 63.837102 -194.425928) (xy 63.889064 -194.414068) (xy 63.942214 -194.410085) (xy 63.995364 -194.414068)
			(xy 64.047326 -194.425928) (xy 64.09694 -194.4454) (xy 64.143098 -194.472049) (xy 64.184769 -194.50528)
			(xy 64.221021 -194.544351) (xy 64.251045 -194.588388) (xy 64.274171 -194.636409) (xy 64.289881 -194.687339)
			(xy 64.297824 -194.740043) (xy 64.298322 -194.766692) (xy 64.297824 -194.793341) (xy 65.796404 -194.793341)
			(xy 65.796404 -194.740043) (xy 65.804347 -194.687339) (xy 65.820057 -194.636409) (xy 65.843183 -194.588388)
			(xy 65.873207 -194.544351) (xy 65.909459 -194.50528) (xy 65.95113 -194.472049) (xy 65.997288 -194.4454)
			(xy 66.046902 -194.425928) (xy 66.098864 -194.414068) (xy 66.152014 -194.410085) (xy 66.205164 -194.414068)
			(xy 66.257126 -194.425928) (xy 66.301517 -194.44335) (xy 68.46697 -194.44335) (xy 68.467366 -194.417373)
			(xy 68.474416 -194.3659) (xy 68.488392 -194.315861) (xy 68.509036 -194.268184) (xy 68.535963 -194.223753)
			(xy 68.568676 -194.183391) (xy 68.606568 -194.147847) (xy 68.627498 -194.132454) (xy 68.638464 -194.123987)
			(xy 68.655888 -194.102469) (xy 68.666887 -194.07706) (xy 68.670651 -194.049629) (xy 68.666903 -194.022196)
			(xy 68.655919 -193.996781) (xy 68.638507 -193.975253) (xy 68.627498 -193.966846) (xy 68.606575 -193.951449)
			(xy 68.5687 -193.915894) (xy 68.536002 -193.875528) (xy 68.509085 -193.831097) (xy 68.488446 -193.783424)
			(xy 68.474469 -193.733391) (xy 68.467412 -193.681924) (xy 68.46697 -193.65595) (xy 68.467456 -193.628699)
			(xy 68.475212 -193.574751) (xy 68.490567 -193.522456) (xy 68.513209 -193.472879) (xy 68.542675 -193.427029)
			(xy 68.578366 -193.385838) (xy 68.619557 -193.350147) (xy 68.665407 -193.320681) (xy 68.714984 -193.298039)
			(xy 68.767279 -193.282684) (xy 68.821227 -193.274928) (xy 68.875729 -193.274928) (xy 68.929677 -193.282684)
			(xy 68.981972 -193.298039) (xy 69.031549 -193.320681) (xy 69.077399 -193.350147) (xy 69.11859 -193.385838)
			(xy 69.154281 -193.427029) (xy 69.183747 -193.472879) (xy 69.206389 -193.522456) (xy 69.221744 -193.574751)
			(xy 69.2295 -193.628699) (xy 69.229986 -193.65595) (xy 69.229566 -193.681926) (xy 69.222517 -193.733397)
			(xy 69.208544 -193.783435) (xy 69.187904 -193.831111) (xy 69.16098 -193.875542) (xy 69.128272 -193.915905)
			(xy 69.090385 -193.951452) (xy 69.069458 -193.966846) (xy 69.058397 -193.975196) (xy 69.040979 -193.996743)
			(xy 69.029991 -194.022177) (xy 69.026241 -194.049629) (xy 69.030006 -194.077079) (xy 69.041009 -194.102507)
			(xy 69.05844 -194.124044) (xy 69.069458 -194.132454) (xy 69.090372 -194.147864) (xy 69.128248 -194.183415)
			(xy 69.160949 -194.223779) (xy 69.187868 -194.268207) (xy 69.208508 -194.315879) (xy 69.222486 -194.36591)
			(xy 69.229544 -194.417376) (xy 69.229986 -194.44335) (xy 69.229421 -194.473612) (xy 69.21987 -194.533378)
			(xy 69.200999 -194.590885) (xy 69.173284 -194.64469) (xy 69.155818 -194.66941) (xy 69.147611 -194.681461)
			(xy 69.13765 -194.708845) (xy 69.13583 -194.737928) (xy 69.142298 -194.766341) (xy 69.15653 -194.791769)
			(xy 69.177364 -194.812141) (xy 69.203105 -194.825799) (xy 69.217286 -194.829176) (xy 69.245618 -194.835556)
			(xy 69.30009 -194.855684) (xy 69.350883 -194.883835) (xy 69.396824 -194.919357) (xy 69.43685 -194.961431)
			(xy 69.470039 -195.009085) (xy 69.495623 -195.061217) (xy 69.513011 -195.116625) (xy 69.521802 -195.174028)
			(xy 69.52234 -195.203064) (xy 69.521854 -195.230315) (xy 69.514098 -195.284263) (xy 69.498743 -195.336558)
			(xy 69.476101 -195.386135) (xy 69.446635 -195.431985) (xy 69.410944 -195.473176) (xy 69.369753 -195.508867)
			(xy 69.323903 -195.538333) (xy 69.274326 -195.560975) (xy 69.222031 -195.57633) (xy 69.168083 -195.584086)
			(xy 69.113581 -195.584086) (xy 69.059633 -195.57633) (xy 69.007338 -195.560975) (xy 68.957761 -195.538333)
			(xy 68.911911 -195.508867) (xy 68.87072 -195.473176) (xy 68.835029 -195.431985) (xy 68.805563 -195.386135)
			(xy 68.782921 -195.336558) (xy 68.767566 -195.284263) (xy 68.75981 -195.230315) (xy 68.759324 -195.203064)
			(xy 68.759895 -195.172802) (xy 68.769444 -195.113037) (xy 68.788312 -195.055529) (xy 68.816027 -195.001724)
			(xy 68.833492 -194.977004) (xy 68.841735 -194.964971) (xy 68.851712 -194.93758) (xy 68.853539 -194.908486)
			(xy 68.847068 -194.880061) (xy 68.832825 -194.854625) (xy 68.811973 -194.834253) (xy 68.786213 -194.820606)
			(xy 68.772024 -194.817238) (xy 68.743697 -194.810837) (xy 68.689226 -194.790712) (xy 68.638433 -194.762564)
			(xy 68.592493 -194.727045) (xy 68.552466 -194.684973) (xy 68.519276 -194.637322) (xy 68.493692 -194.585192)
			(xy 68.476302 -194.529786) (xy 68.467509 -194.472385) (xy 68.46697 -194.44335) (xy 66.301517 -194.44335)
			(xy 66.30674 -194.4454) (xy 66.352898 -194.472049) (xy 66.394569 -194.50528) (xy 66.430821 -194.544351)
			(xy 66.460845 -194.588388) (xy 66.483971 -194.636409) (xy 66.499681 -194.687339) (xy 66.507624 -194.740043)
			(xy 66.508122 -194.766692) (xy 66.507624 -194.793341) (xy 66.499681 -194.846045) (xy 66.483971 -194.896975)
			(xy 66.460845 -194.944996) (xy 66.430821 -194.989033) (xy 66.394569 -195.028104) (xy 66.352898 -195.061335)
			(xy 66.30674 -195.087984) (xy 66.257126 -195.107456) (xy 66.205164 -195.119316) (xy 66.152014 -195.1233)
			(xy 66.098864 -195.119316) (xy 66.046902 -195.107456) (xy 65.997288 -195.087984) (xy 65.95113 -195.061335)
			(xy 65.909459 -195.028104) (xy 65.873207 -194.989033) (xy 65.843183 -194.944996) (xy 65.820057 -194.896975)
			(xy 65.804347 -194.846045) (xy 65.796404 -194.793341) (xy 64.297824 -194.793341) (xy 64.289881 -194.846045)
			(xy 64.274171 -194.896975) (xy 64.251045 -194.944996) (xy 64.221021 -194.989033) (xy 64.184769 -195.028104)
			(xy 64.143098 -195.061335) (xy 64.09694 -195.087984) (xy 64.047326 -195.107456) (xy 63.995364 -195.119316)
			(xy 63.942214 -195.1233) (xy 63.889064 -195.119316) (xy 63.837102 -195.107456) (xy 63.787488 -195.087984)
			(xy 63.74133 -195.061335) (xy 63.699659 -195.028104) (xy 63.663407 -194.989033) (xy 63.633383 -194.944996)
			(xy 63.610257 -194.896975) (xy 63.594547 -194.846045) (xy 63.586604 -194.793341) (xy 62.985629 -194.793341)
			(xy 64.172338 -195.98005) (xy 66.671698 -195.98005) (xy 73.209912 -202.518264) (xy 76.018898 -209.53095)
			(xy 83.986878 -217.37193) (xy 84.458048 -219.53982) (xy 86.078119 -221.159891) (xy 87.815421 -221.159891)
			(xy 87.815421 -221.107957) (xy 87.823546 -221.056662) (xy 87.839594 -221.007269) (xy 87.863172 -220.960995)
			(xy 87.893698 -220.918979) (xy 87.930421 -220.882256) (xy 87.972437 -220.85173) (xy 88.018711 -220.828152)
			(xy 88.068104 -220.812104) (xy 88.119399 -220.803979) (xy 88.171333 -220.803979) (xy 88.222628 -220.812104)
			(xy 88.272021 -220.828152) (xy 88.318295 -220.85173) (xy 88.360311 -220.882256) (xy 88.397034 -220.918979)
			(xy 88.42756 -220.960995) (xy 88.451138 -221.007269) (xy 88.467186 -221.056662) (xy 88.475311 -221.107957)
			(xy 88.47582 -221.133924) (xy 88.754712 -221.133924) (xy 88.755221 -221.107957) (xy 88.763346 -221.056662)
			(xy 88.779394 -221.007269) (xy 88.802972 -220.960995) (xy 88.833498 -220.918979) (xy 88.870221 -220.882256)
			(xy 88.912237 -220.85173) (xy 88.958511 -220.828152) (xy 89.007904 -220.812104) (xy 89.059199 -220.803979)
			(xy 89.111133 -220.803979) (xy 89.162428 -220.812104) (xy 89.211821 -220.828152) (xy 89.258095 -220.85173)
			(xy 89.300111 -220.882256) (xy 89.336834 -220.918979) (xy 89.36736 -220.960995) (xy 89.390938 -221.007269)
			(xy 89.406986 -221.056662) (xy 89.415111 -221.107957) (xy 89.41562 -221.133924) (xy 89.415072 -221.16191)
			(xy 89.405619 -221.217078) (xy 89.396824 -221.243652) (xy 89.389204 -221.26575) (xy 89.592912 -221.618556)
			(xy 89.615772 -221.622874) (xy 89.6407 -221.628011) (xy 89.688685 -221.644981) (xy 89.733503 -221.669103)
			(xy 89.774095 -221.699808) (xy 89.809503 -221.736369) (xy 89.83889 -221.777925) (xy 89.861563 -221.823493)
			(xy 89.876985 -221.871997) (xy 89.884793 -221.922292) (xy 89.885266 -221.94774) (xy 89.884757 -221.973707)
			(xy 90.164667 -221.973707) (xy 90.164667 -221.921773) (xy 90.172792 -221.870478) (xy 90.18884 -221.821085)
			(xy 90.212418 -221.774811) (xy 90.242944 -221.732795) (xy 90.279667 -221.696072) (xy 90.321683 -221.665546)
			(xy 90.367957 -221.641968) (xy 90.41735 -221.62592) (xy 90.468645 -221.617795) (xy 90.520579 -221.617795)
			(xy 90.571874 -221.62592) (xy 90.621267 -221.641968) (xy 90.667541 -221.665546) (xy 90.709557 -221.696072)
			(xy 90.74628 -221.732795) (xy 90.776806 -221.774811) (xy 90.800384 -221.821085) (xy 90.816432 -221.870478)
			(xy 90.824557 -221.921773) (xy 90.825066 -221.94774) (xy 90.824557 -221.973707) (xy 90.816432 -222.025002)
			(xy 90.800384 -222.074395) (xy 90.776806 -222.120669) (xy 90.74628 -222.162685) (xy 90.709557 -222.199408)
			(xy 90.667541 -222.229934) (xy 90.621267 -222.253512) (xy 90.571874 -222.26956) (xy 90.520579 -222.277685)
			(xy 90.468645 -222.277685) (xy 90.41735 -222.26956) (xy 90.367957 -222.253512) (xy 90.321683 -222.229934)
			(xy 90.279667 -222.199408) (xy 90.242944 -222.162685) (xy 90.212418 -222.120669) (xy 90.18884 -222.074395)
			(xy 90.172792 -222.025002) (xy 90.164667 -221.973707) (xy 89.884757 -221.973707) (xy 89.876632 -222.025002)
			(xy 89.860584 -222.074395) (xy 89.837006 -222.120669) (xy 89.80648 -222.162685) (xy 89.769757 -222.199408)
			(xy 89.727741 -222.229934) (xy 89.681467 -222.253512) (xy 89.632074 -222.26956) (xy 89.580779 -222.277685)
			(xy 89.528845 -222.277685) (xy 89.47755 -222.26956) (xy 89.428157 -222.253512) (xy 89.381883 -222.229934)
			(xy 89.339867 -222.199408) (xy 89.303144 -222.162685) (xy 89.272618 -222.120669) (xy 89.24904 -222.074395)
			(xy 89.232992 -222.025002) (xy 89.224867 -221.973707) (xy 89.224358 -221.94774) (xy 89.224918 -221.919754)
			(xy 89.234363 -221.864587) (xy 89.243154 -221.838012) (xy 89.250774 -221.815914) (xy 89.047066 -221.463108)
			(xy 89.024206 -221.45879) (xy 88.999282 -221.45363) (xy 88.951295 -221.436669) (xy 88.906474 -221.412553)
			(xy 88.865879 -221.381853) (xy 88.830468 -221.345294) (xy 88.80108 -221.303739) (xy 88.778407 -221.258171)
			(xy 88.762987 -221.209667) (xy 88.755182 -221.159372) (xy 88.754712 -221.133924) (xy 88.47582 -221.133924)
			(xy 88.475311 -221.159891) (xy 88.467186 -221.211186) (xy 88.451138 -221.260579) (xy 88.42756 -221.306853)
			(xy 88.397034 -221.348869) (xy 88.360311 -221.385592) (xy 88.318295 -221.416118) (xy 88.272021 -221.439696)
			(xy 88.222628 -221.455744) (xy 88.171333 -221.463869) (xy 88.119399 -221.463869) (xy 88.068104 -221.455744)
			(xy 88.018711 -221.439696) (xy 87.972437 -221.416118) (xy 87.930421 -221.385592) (xy 87.893698 -221.348869)
			(xy 87.863172 -221.306853) (xy 87.839594 -221.260579) (xy 87.823546 -221.211186) (xy 87.815421 -221.159891)
			(xy 86.078119 -221.159891) (xy 86.584536 -221.666308) (xy 86.615778 -221.653608) (xy 86.644531 -221.642639)
			(xy 86.704901 -221.630735) (xy 86.735666 -221.629986) (xy 86.760638 -221.630448) (xy 86.809967 -221.638256)
			(xy 86.857467 -221.653687) (xy 86.901968 -221.676359) (xy 86.942374 -221.705715) (xy 86.977689 -221.741031)
			(xy 87.007044 -221.781437) (xy 87.029715 -221.825938) (xy 87.045145 -221.873439) (xy 87.052953 -221.922768)
			(xy 87.05342 -221.94774) (xy 87.052795 -221.973707) (xy 87.345521 -221.973707) (xy 87.345521 -221.921773)
			(xy 87.353646 -221.870478) (xy 87.369694 -221.821085) (xy 87.393272 -221.774811) (xy 87.423798 -221.732795)
			(xy 87.460521 -221.696072) (xy 87.502537 -221.665546) (xy 87.548811 -221.641968) (xy 87.598204 -221.62592)
			(xy 87.649499 -221.617795) (xy 87.701433 -221.617795) (xy 87.752728 -221.62592) (xy 87.802121 -221.641968)
			(xy 87.848395 -221.665546) (xy 87.890411 -221.696072) (xy 87.927134 -221.732795) (xy 87.95766 -221.774811)
			(xy 87.981238 -221.821085) (xy 87.997286 -221.870478) (xy 88.005411 -221.921773) (xy 88.00592 -221.94774)
			(xy 88.005411 -221.973707) (xy 88.285321 -221.973707) (xy 88.285321 -221.921773) (xy 88.293446 -221.870478)
			(xy 88.309494 -221.821085) (xy 88.333072 -221.774811) (xy 88.363598 -221.732795) (xy 88.400321 -221.696072)
			(xy 88.442337 -221.665546) (xy 88.488611 -221.641968) (xy 88.538004 -221.62592) (xy 88.589299 -221.617795)
			(xy 88.641233 -221.617795) (xy 88.692528 -221.62592) (xy 88.741921 -221.641968) (xy 88.788195 -221.665546)
			(xy 88.830211 -221.696072) (xy 88.866934 -221.732795) (xy 88.89746 -221.774811) (xy 88.921038 -221.821085)
			(xy 88.937086 -221.870478) (xy 88.945211 -221.921773) (xy 88.94572 -221.94774) (xy 88.945211 -221.973707)
			(xy 88.937086 -222.025002) (xy 88.921038 -222.074395) (xy 88.89746 -222.120669) (xy 88.866934 -222.162685)
			(xy 88.830211 -222.199408) (xy 88.788195 -222.229934) (xy 88.741921 -222.253512) (xy 88.692528 -222.26956)
			(xy 88.641233 -222.277685) (xy 88.589299 -222.277685) (xy 88.538004 -222.26956) (xy 88.488611 -222.253512)
			(xy 88.442337 -222.229934) (xy 88.400321 -222.199408) (xy 88.363598 -222.162685) (xy 88.333072 -222.120669)
			(xy 88.309494 -222.074395) (xy 88.293446 -222.025002) (xy 88.285321 -221.973707) (xy 88.005411 -221.973707)
			(xy 87.997286 -222.025002) (xy 87.981238 -222.074395) (xy 87.95766 -222.120669) (xy 87.927134 -222.162685)
			(xy 87.890411 -222.199408) (xy 87.848395 -222.229934) (xy 87.802121 -222.253512) (xy 87.752728 -222.26956)
			(xy 87.701433 -222.277685) (xy 87.649499 -222.277685) (xy 87.598204 -222.26956) (xy 87.548811 -222.253512)
			(xy 87.502537 -222.229934) (xy 87.460521 -222.199408) (xy 87.423798 -222.162685) (xy 87.393272 -222.120669)
			(xy 87.369694 -222.074395) (xy 87.353646 -222.025002) (xy 87.345521 -221.973707) (xy 87.052795 -221.973707)
			(xy 87.05268 -221.978507) (xy 87.04079 -222.038882) (xy 87.029798 -222.067628) (xy 87.017098 -222.09887)
			(xy 87.385398 -222.46717) (xy 87.994744 -222.46717) (xy 88.005158 -222.462344) (xy 88.027198 -222.452471)
			(xy 88.073442 -222.438553) (xy 88.12122 -222.431519) (xy 88.169512 -222.431519) (xy 88.21729 -222.438553)
			(xy 88.263534 -222.452471) (xy 88.285574 -222.462344) (xy 88.295988 -222.46717) (xy 88.599518 -222.46717)
			(xy 88.684862 -222.552514) (xy 88.695053 -222.562101) (xy 88.719442 -222.575796) (xy 88.746631 -222.582363)
			(xy 88.774582 -222.581311) (xy 88.801201 -222.572719) (xy 88.824491 -222.557229) (xy 88.83396 -222.546926)
			(xy 88.849736 -222.52911) (xy 88.885524 -222.497746) (xy 88.925438 -222.471836) (xy 88.968655 -222.451915)
			(xy 89.01428 -222.438394) (xy 89.061373 -222.431554) (xy 89.085166 -222.431102) (xy 89.111136 -222.431609)
			(xy 89.162438 -222.439729) (xy 89.211838 -222.455774) (xy 89.25812 -222.479349) (xy 89.300144 -222.509874)
			(xy 89.336876 -222.546597) (xy 89.36741 -222.588614) (xy 89.390997 -222.63489) (xy 89.407053 -222.684286)
			(xy 89.415185 -222.735586) (xy 89.41562 -222.761556) (xy 89.415117 -222.787523) (xy 89.695021 -222.787523)
			(xy 89.695021 -222.735589) (xy 89.703146 -222.684294) (xy 89.719194 -222.634901) (xy 89.742772 -222.588627)
			(xy 89.773298 -222.546611) (xy 89.810021 -222.509888) (xy 89.852037 -222.479362) (xy 89.898311 -222.455784)
			(xy 89.947704 -222.439736) (xy 89.998999 -222.431611) (xy 90.050933 -222.431611) (xy 90.102228 -222.439736)
			(xy 90.151621 -222.455784) (xy 90.197895 -222.479362) (xy 90.239911 -222.509888) (xy 90.276634 -222.546611)
			(xy 90.30716 -222.588627) (xy 90.330738 -222.634901) (xy 90.346786 -222.684294) (xy 90.354911 -222.735589)
			(xy 90.35542 -222.761556) (xy 90.354911 -222.787523) (xy 90.634821 -222.787523) (xy 90.634821 -222.735589)
			(xy 90.642946 -222.684294) (xy 90.658994 -222.634901) (xy 90.682572 -222.588627) (xy 90.713098 -222.546611)
			(xy 90.749821 -222.509888) (xy 90.791837 -222.479362) (xy 90.838111 -222.455784) (xy 90.887504 -222.439736)
			(xy 90.938799 -222.431611) (xy 90.990733 -222.431611) (xy 91.042028 -222.439736) (xy 91.091421 -222.455784)
			(xy 91.137695 -222.479362) (xy 91.179711 -222.509888) (xy 91.216434 -222.546611) (xy 91.24696 -222.588627)
			(xy 91.270538 -222.634901) (xy 91.286586 -222.684294) (xy 91.294711 -222.735589) (xy 91.29522 -222.761556)
			(xy 91.294711 -222.787523) (xy 91.574621 -222.787523) (xy 91.574621 -222.735589) (xy 91.582746 -222.684294)
			(xy 91.598794 -222.634901) (xy 91.622372 -222.588627) (xy 91.652898 -222.546611) (xy 91.689621 -222.509888)
			(xy 91.731637 -222.479362) (xy 91.777911 -222.455784) (xy 91.827304 -222.439736) (xy 91.878599 -222.431611)
			(xy 91.930533 -222.431611) (xy 91.981828 -222.439736) (xy 92.031221 -222.455784) (xy 92.077495 -222.479362)
			(xy 92.119511 -222.509888) (xy 92.156234 -222.546611) (xy 92.18676 -222.588627) (xy 92.210338 -222.634901)
			(xy 92.226386 -222.684294) (xy 92.234511 -222.735589) (xy 92.23502 -222.761556) (xy 92.234511 -222.787523)
			(xy 92.514421 -222.787523) (xy 92.514421 -222.735589) (xy 92.522546 -222.684294) (xy 92.538594 -222.634901)
			(xy 92.562172 -222.588627) (xy 92.592698 -222.546611) (xy 92.629421 -222.509888) (xy 92.671437 -222.479362)
			(xy 92.717711 -222.455784) (xy 92.767104 -222.439736) (xy 92.818399 -222.431611) (xy 92.870333 -222.431611)
			(xy 92.921628 -222.439736) (xy 92.971021 -222.455784) (xy 93.017295 -222.479362) (xy 93.059311 -222.509888)
			(xy 93.096034 -222.546611) (xy 93.12656 -222.588627) (xy 93.150138 -222.634901) (xy 93.166186 -222.684294)
			(xy 93.174311 -222.735589) (xy 93.17482 -222.761556) (xy 93.174311 -222.787523) (xy 93.454221 -222.787523)
			(xy 93.454221 -222.735589) (xy 93.462346 -222.684294) (xy 93.478394 -222.634901) (xy 93.501972 -222.588627)
			(xy 93.532498 -222.546611) (xy 93.569221 -222.509888) (xy 93.611237 -222.479362) (xy 93.657511 -222.455784)
			(xy 93.706904 -222.439736) (xy 93.758199 -222.431611) (xy 93.810133 -222.431611) (xy 93.861428 -222.439736)
			(xy 93.910821 -222.455784) (xy 93.957095 -222.479362) (xy 93.999111 -222.509888) (xy 94.035834 -222.546611)
			(xy 94.06636 -222.588627) (xy 94.089938 -222.634901) (xy 94.105986 -222.684294) (xy 94.114111 -222.735589)
			(xy 94.11462 -222.761556) (xy 94.114111 -222.787523) (xy 94.394021 -222.787523) (xy 94.394021 -222.735589)
			(xy 94.402146 -222.684294) (xy 94.418194 -222.634901) (xy 94.441772 -222.588627) (xy 94.472298 -222.546611)
			(xy 94.509021 -222.509888) (xy 94.551037 -222.479362) (xy 94.597311 -222.455784) (xy 94.646704 -222.439736)
			(xy 94.697999 -222.431611) (xy 94.749933 -222.431611) (xy 94.801228 -222.439736) (xy 94.850621 -222.455784)
			(xy 94.896895 -222.479362) (xy 94.938911 -222.509888) (xy 94.975634 -222.546611) (xy 95.00616 -222.588627)
			(xy 95.029738 -222.634901) (xy 95.045786 -222.684294) (xy 95.053911 -222.735589) (xy 95.05442 -222.761556)
			(xy 95.053911 -222.787523) (xy 95.333821 -222.787523) (xy 95.333821 -222.735589) (xy 95.341946 -222.684294)
			(xy 95.357994 -222.634901) (xy 95.381572 -222.588627) (xy 95.412098 -222.546611) (xy 95.448821 -222.509888)
			(xy 95.490837 -222.479362) (xy 95.537111 -222.455784) (xy 95.586504 -222.439736) (xy 95.637799 -222.431611)
			(xy 95.689733 -222.431611) (xy 95.741028 -222.439736) (xy 95.790421 -222.455784) (xy 95.836695 -222.479362)
			(xy 95.878711 -222.509888) (xy 95.915434 -222.546611) (xy 95.94596 -222.588627) (xy 95.969538 -222.634901)
			(xy 95.985586 -222.684294) (xy 95.993711 -222.735589) (xy 95.99422 -222.761556) (xy 95.993711 -222.787523)
			(xy 96.273621 -222.787523) (xy 96.273621 -222.735589) (xy 96.281746 -222.684294) (xy 96.297794 -222.634901)
			(xy 96.321372 -222.588627) (xy 96.351898 -222.546611) (xy 96.388621 -222.509888) (xy 96.430637 -222.479362)
			(xy 96.476911 -222.455784) (xy 96.526304 -222.439736) (xy 96.577599 -222.431611) (xy 96.629533 -222.431611)
			(xy 96.680828 -222.439736) (xy 96.730221 -222.455784) (xy 96.776495 -222.479362) (xy 96.818511 -222.509888)
			(xy 96.855234 -222.546611) (xy 96.88576 -222.588627) (xy 96.909338 -222.634901) (xy 96.925386 -222.684294)
			(xy 96.933511 -222.735589) (xy 96.93402 -222.761556) (xy 96.933511 -222.787523) (xy 96.925386 -222.838818)
			(xy 96.909338 -222.888211) (xy 96.88576 -222.934485) (xy 96.855234 -222.976501) (xy 96.818511 -223.013224)
			(xy 96.776495 -223.04375) (xy 96.730221 -223.067328) (xy 96.680828 -223.083376) (xy 96.629533 -223.091501)
			(xy 96.577599 -223.091501) (xy 96.526304 -223.083376) (xy 96.476911 -223.067328) (xy 96.430637 -223.04375)
			(xy 96.388621 -223.013224) (xy 96.351898 -222.976501) (xy 96.321372 -222.934485) (xy 96.297794 -222.888211)
			(xy 96.281746 -222.838818) (xy 96.273621 -222.787523) (xy 95.993711 -222.787523) (xy 95.985586 -222.838818)
			(xy 95.969538 -222.888211) (xy 95.94596 -222.934485) (xy 95.915434 -222.976501) (xy 95.878711 -223.013224)
			(xy 95.836695 -223.04375) (xy 95.790421 -223.067328) (xy 95.741028 -223.083376) (xy 95.689733 -223.091501)
			(xy 95.637799 -223.091501) (xy 95.586504 -223.083376) (xy 95.537111 -223.067328) (xy 95.490837 -223.04375)
			(xy 95.448821 -223.013224) (xy 95.412098 -222.976501) (xy 95.381572 -222.934485) (xy 95.357994 -222.888211)
			(xy 95.341946 -222.838818) (xy 95.333821 -222.787523) (xy 95.053911 -222.787523) (xy 95.045786 -222.838818)
			(xy 95.029738 -222.888211) (xy 95.00616 -222.934485) (xy 94.975634 -222.976501) (xy 94.938911 -223.013224)
			(xy 94.896895 -223.04375) (xy 94.850621 -223.067328) (xy 94.801228 -223.083376) (xy 94.749933 -223.091501)
			(xy 94.697999 -223.091501) (xy 94.646704 -223.083376) (xy 94.597311 -223.067328) (xy 94.551037 -223.04375)
			(xy 94.509021 -223.013224) (xy 94.472298 -222.976501) (xy 94.441772 -222.934485) (xy 94.418194 -222.888211)
			(xy 94.402146 -222.838818) (xy 94.394021 -222.787523) (xy 94.114111 -222.787523) (xy 94.105986 -222.838818)
			(xy 94.089938 -222.888211) (xy 94.06636 -222.934485) (xy 94.035834 -222.976501) (xy 93.999111 -223.013224)
			(xy 93.957095 -223.04375) (xy 93.910821 -223.067328) (xy 93.861428 -223.083376) (xy 93.810133 -223.091501)
			(xy 93.758199 -223.091501) (xy 93.706904 -223.083376) (xy 93.657511 -223.067328) (xy 93.611237 -223.04375)
			(xy 93.569221 -223.013224) (xy 93.532498 -222.976501) (xy 93.501972 -222.934485) (xy 93.478394 -222.888211)
			(xy 93.462346 -222.838818) (xy 93.454221 -222.787523) (xy 93.174311 -222.787523) (xy 93.166186 -222.838818)
			(xy 93.150138 -222.888211) (xy 93.12656 -222.934485) (xy 93.096034 -222.976501) (xy 93.059311 -223.013224)
			(xy 93.017295 -223.04375) (xy 92.971021 -223.067328) (xy 92.921628 -223.083376) (xy 92.870333 -223.091501)
			(xy 92.818399 -223.091501) (xy 92.767104 -223.083376) (xy 92.717711 -223.067328) (xy 92.671437 -223.04375)
			(xy 92.629421 -223.013224) (xy 92.592698 -222.976501) (xy 92.562172 -222.934485) (xy 92.538594 -222.888211)
			(xy 92.522546 -222.838818) (xy 92.514421 -222.787523) (xy 92.234511 -222.787523) (xy 92.226386 -222.838818)
			(xy 92.210338 -222.888211) (xy 92.18676 -222.934485) (xy 92.156234 -222.976501) (xy 92.119511 -223.013224)
			(xy 92.077495 -223.04375) (xy 92.031221 -223.067328) (xy 91.981828 -223.083376) (xy 91.930533 -223.091501)
			(xy 91.878599 -223.091501) (xy 91.827304 -223.083376) (xy 91.777911 -223.067328) (xy 91.731637 -223.04375)
			(xy 91.689621 -223.013224) (xy 91.652898 -222.976501) (xy 91.622372 -222.934485) (xy 91.598794 -222.888211)
			(xy 91.582746 -222.838818) (xy 91.574621 -222.787523) (xy 91.294711 -222.787523) (xy 91.286586 -222.838818)
			(xy 91.270538 -222.888211) (xy 91.24696 -222.934485) (xy 91.216434 -222.976501) (xy 91.179711 -223.013224)
			(xy 91.137695 -223.04375) (xy 91.091421 -223.067328) (xy 91.042028 -223.083376) (xy 90.990733 -223.091501)
			(xy 90.938799 -223.091501) (xy 90.887504 -223.083376) (xy 90.838111 -223.067328) (xy 90.791837 -223.04375)
			(xy 90.749821 -223.013224) (xy 90.713098 -222.976501) (xy 90.682572 -222.934485) (xy 90.658994 -222.888211)
			(xy 90.642946 -222.838818) (xy 90.634821 -222.787523) (xy 90.354911 -222.787523) (xy 90.346786 -222.838818)
			(xy 90.330738 -222.888211) (xy 90.30716 -222.934485) (xy 90.276634 -222.976501) (xy 90.239911 -223.013224)
			(xy 90.197895 -223.04375) (xy 90.151621 -223.067328) (xy 90.102228 -223.083376) (xy 90.050933 -223.091501)
			(xy 89.998999 -223.091501) (xy 89.947704 -223.083376) (xy 89.898311 -223.067328) (xy 89.852037 -223.04375)
			(xy 89.810021 -223.013224) (xy 89.773298 -222.976501) (xy 89.742772 -222.934485) (xy 89.719194 -222.888211)
			(xy 89.703146 -222.838818) (xy 89.695021 -222.787523) (xy 89.415117 -222.787523) (xy 89.415111 -222.787812)
			(xy 89.406802 -222.839662) (xy 89.390401 -222.889547) (xy 89.366321 -222.936212) (xy 89.335167 -222.978484)
			(xy 89.316814 -222.997268) (xy 89.310556 -223.003895) (xy 89.302804 -223.020375) (xy 89.301335 -223.038528)
			(xy 89.306336 -223.05604) (xy 89.31148 -223.063562) (xy 89.339189 -223.102431) (xy 89.386794 -223.185174)
			(xy 89.406476 -223.228662) (xy 89.410503 -223.236835) (xy 89.423216 -223.249868) (xy 89.439674 -223.257656)
			(xy 89.457813 -223.259222) (xy 89.466674 -223.25711) (xy 89.488338 -223.251496) (xy 89.532689 -223.245501)
			(xy 89.555066 -223.245172) (xy 89.580296 -223.245653) (xy 89.630168 -223.253331) (xy 89.678295 -223.268497)
			(xy 89.723558 -223.2908) (xy 89.764907 -223.319722) (xy 89.801381 -223.354591) (xy 89.832132 -223.394597)
			(xy 89.856448 -223.438812) (xy 89.873763 -223.486208) (xy 89.87917 -223.510856) (xy 89.887298 -223.55175)
			(xy 90.16238 -223.55175) (xy 90.170508 -223.510856) (xy 90.17592 -223.486208) (xy 90.193219 -223.438803)
			(xy 90.217524 -223.39458) (xy 90.248272 -223.354567) (xy 90.284746 -223.319695) (xy 90.326099 -223.290775)
			(xy 90.371369 -223.26848) (xy 90.419503 -223.253328) (xy 90.469381 -223.245671) (xy 90.494612 -223.245172)
			(xy 90.521847 -223.24572) (xy 90.575582 -223.254637) (xy 90.627128 -223.272243) (xy 90.67509 -223.298061)
			(xy 90.718169 -223.331395) (xy 90.755201 -223.37134) (xy 90.785181 -223.416816) (xy 90.807301 -223.466593)
			(xy 90.814652 -223.492822) (xy 90.817272 -223.501526) (xy 90.827652 -223.516435) (xy 90.842585 -223.526778)
			(xy 90.86019 -223.531255) (xy 90.869262 -223.530668) (xy 90.916839 -223.526021) (xy 91.012439 -223.526021)
			(xy 91.060016 -223.530668) (xy 91.06908 -223.531245) (xy 91.086661 -223.526733) (xy 91.101577 -223.516391)
			(xy 91.111966 -223.501507) (xy 91.114626 -223.492822) (xy 91.122008 -223.466607) (xy 91.144149 -223.416853)
			(xy 91.17414 -223.371398) (xy 91.211171 -223.331468) (xy 91.254242 -223.298143) (xy 91.30219 -223.272323)
			(xy 91.353718 -223.254704) (xy 91.407437 -223.245763) (xy 91.434666 -223.245172) (xy 91.459896 -223.245653)
			(xy 91.509768 -223.253331) (xy 91.557895 -223.268497) (xy 91.603158 -223.2908) (xy 91.644507 -223.319722)
			(xy 91.680981 -223.354591) (xy 91.711732 -223.394597) (xy 91.736048 -223.438812) (xy 91.753363 -223.486208)
			(xy 91.75877 -223.510856) (xy 91.766898 -223.55175) (xy 92.04198 -223.55175) (xy 92.050108 -223.510856)
			(xy 92.05552 -223.486208) (xy 92.072819 -223.438803) (xy 92.097124 -223.39458) (xy 92.127872 -223.354567)
			(xy 92.164346 -223.319695) (xy 92.205699 -223.290775) (xy 92.250969 -223.26848) (xy 92.299103 -223.253328)
			(xy 92.348981 -223.245671) (xy 92.374212 -223.245172) (xy 92.401447 -223.24572) (xy 92.455182 -223.254637)
			(xy 92.506728 -223.272243) (xy 92.55469 -223.298061) (xy 92.597769 -223.331395) (xy 92.634801 -223.37134)
			(xy 92.664781 -223.416816) (xy 92.686901 -223.466593) (xy 92.694252 -223.492822) (xy 92.696872 -223.501526)
			(xy 92.707252 -223.516435) (xy 92.722185 -223.526778) (xy 92.73979 -223.531255) (xy 92.748862 -223.530668)
			(xy 92.796439 -223.526021) (xy 92.892039 -223.526021) (xy 92.939616 -223.530668) (xy 92.94868 -223.531245)
			(xy 92.966261 -223.526733) (xy 92.981177 -223.516391) (xy 92.991566 -223.501507) (xy 92.994226 -223.492822)
			(xy 93.001608 -223.466607) (xy 93.023749 -223.416853) (xy 93.05374 -223.371398) (xy 93.090771 -223.331468)
			(xy 93.133842 -223.298143) (xy 93.18179 -223.272323) (xy 93.233318 -223.254704) (xy 93.287037 -223.245763)
			(xy 93.314266 -223.245172) (xy 93.340236 -223.245652) (xy 93.391538 -223.253773) (xy 93.440937 -223.26982)
			(xy 93.487218 -223.293399) (xy 93.52924 -223.323927) (xy 93.565967 -223.360654) (xy 93.596497 -223.402675)
			(xy 93.620076 -223.448955) (xy 93.636125 -223.498354) (xy 93.644247 -223.549656) (xy 93.64472 -223.575626)
			(xy 93.644094 -223.606317) (xy 93.632841 -223.666658) (xy 93.622368 -223.695514) (xy 93.610176 -223.726248)
			(xy 93.724984 -223.841056) (xy 93.734677 -223.850208) (xy 93.757747 -223.863549) (xy 93.783486 -223.870454)
			(xy 93.810136 -223.870451) (xy 93.835874 -223.86354) (xy 93.858941 -223.850194) (xy 93.877759 -223.831325)
			(xy 93.88475 -223.819974) (xy 93.949774 -223.707198) (xy 93.942154 -223.685354) (xy 93.933357 -223.65878)
			(xy 93.923901 -223.603612) (xy 93.923358 -223.575626) (xy 93.923867 -223.549659) (xy 93.931992 -223.498364)
			(xy 93.94804 -223.448971) (xy 93.971618 -223.402697) (xy 94.002144 -223.360681) (xy 94.038867 -223.323958)
			(xy 94.080883 -223.293432) (xy 94.127157 -223.269854) (xy 94.17655 -223.253806) (xy 94.227845 -223.245681)
			(xy 94.279779 -223.245681) (xy 94.331074 -223.253806) (xy 94.380467 -223.269854) (xy 94.426741 -223.293432)
			(xy 94.468757 -223.323958) (xy 94.50548 -223.360681) (xy 94.536006 -223.402697) (xy 94.559584 -223.448971)
			(xy 94.575632 -223.498364) (xy 94.583757 -223.549659) (xy 94.584266 -223.575626) (xy 94.583796 -223.601076)
			(xy 94.583716 -223.601593) (xy 94.863921 -223.601593) (xy 94.863921 -223.549659) (xy 94.872046 -223.498364)
			(xy 94.888094 -223.448971) (xy 94.911672 -223.402697) (xy 94.942198 -223.360681) (xy 94.978921 -223.323958)
			(xy 95.020937 -223.293432) (xy 95.067211 -223.269854) (xy 95.116604 -223.253806) (xy 95.167899 -223.245681)
			(xy 95.219833 -223.245681) (xy 95.271128 -223.253806) (xy 95.320521 -223.269854) (xy 95.366795 -223.293432)
			(xy 95.408811 -223.323958) (xy 95.445534 -223.360681) (xy 95.47606 -223.402697) (xy 95.499638 -223.448971)
			(xy 95.515686 -223.498364) (xy 95.523811 -223.549659) (xy 95.52432 -223.575626) (xy 95.523811 -223.601593)
			(xy 95.515686 -223.652888) (xy 95.499638 -223.702281) (xy 95.47606 -223.748555) (xy 95.445534 -223.790571)
			(xy 95.408811 -223.827294) (xy 95.366795 -223.85782) (xy 95.320521 -223.881398) (xy 95.271128 -223.897446)
			(xy 95.219833 -223.905571) (xy 95.167899 -223.905571) (xy 95.116604 -223.897446) (xy 95.067211 -223.881398)
			(xy 95.020937 -223.85782) (xy 94.978921 -223.827294) (xy 94.942198 -223.790571) (xy 94.911672 -223.748555)
			(xy 94.888094 -223.702281) (xy 94.872046 -223.652888) (xy 94.863921 -223.601593) (xy 94.583716 -223.601593)
			(xy 94.575992 -223.651374) (xy 94.560572 -223.699882) (xy 94.537902 -223.745455) (xy 94.508515 -223.787015)
			(xy 94.473108 -223.823581) (xy 94.432514 -223.85429) (xy 94.387695 -223.878415) (xy 94.339708 -223.895387)
			(xy 94.314772 -223.900492) (xy 94.291658 -223.90481) (xy 94.088204 -224.257616) (xy 94.095824 -224.279714)
			(xy 94.104613 -224.306289) (xy 94.114056 -224.361457) (xy 94.11462 -224.389442) (xy 94.114012 -224.418027)
			(xy 94.104175 -224.474343) (xy 94.084801 -224.52813) (xy 94.071186 -224.553272) (xy 94.051882 -224.587054)
			(xy 94.352618 -224.88779) (xy 94.363286 -224.8916) (xy 94.386396 -224.900202) (xy 94.429972 -224.923276)
			(xy 94.469636 -224.952571) (xy 94.504504 -224.987435) (xy 94.533804 -225.027095) (xy 94.556883 -225.070669)
			(xy 94.56547 -225.093784) (xy 94.56928 -225.104452) (xy 94.618556 -225.153728) (xy 94.6912 -225.153728)
			(xy 94.692216 -225.153474) (xy 94.70815 -225.152954) (xy 94.740036 -225.152954) (xy 94.75597 -225.153474)
			(xy 94.756986 -225.153728) (xy 94.864682 -225.153728) (xy 94.874842 -225.116136) (xy 94.881954 -225.09353)
			(xy 94.889574 -225.071432) (xy 94.685866 -224.718626) (xy 94.663006 -224.714308) (xy 94.638078 -224.709156)
			(xy 94.59008 -224.692211) (xy 94.545249 -224.668105) (xy 94.504646 -224.637408) (xy 94.469231 -224.600846)
			(xy 94.439844 -224.559286) (xy 94.417178 -224.513709) (xy 94.401772 -224.465195) (xy 94.393989 -224.414893)
			(xy 94.393512 -224.389442) (xy 94.394021 -224.363475) (xy 94.402146 -224.31218) (xy 94.418194 -224.262787)
			(xy 94.441772 -224.216513) (xy 94.472298 -224.174497) (xy 94.509021 -224.137774) (xy 94.551037 -224.107248)
			(xy 94.597311 -224.08367) (xy 94.646704 -224.067622) (xy 94.697999 -224.059497) (xy 94.749933 -224.059497)
			(xy 94.801228 -224.067622) (xy 94.850621 -224.08367) (xy 94.896895 -224.107248) (xy 94.938911 -224.137774)
			(xy 94.975634 -224.174497) (xy 95.00616 -224.216513) (xy 95.029738 -224.262787) (xy 95.045786 -224.31218)
			(xy 95.053911 -224.363475) (xy 95.05442 -224.389442) (xy 95.333312 -224.389442) (xy 95.333774 -224.363991)
			(xy 95.34156 -224.313687) (xy 95.356968 -224.265174) (xy 95.379636 -224.219597) (xy 95.409025 -224.178036)
			(xy 95.444441 -224.141475) (xy 95.485046 -224.110778) (xy 95.529878 -224.086672) (xy 95.577877 -224.069728)
			(xy 95.602806 -224.064576) (xy 95.625666 -224.060258) (xy 95.829374 -223.707198) (xy 95.821754 -223.685354)
			(xy 95.813031 -223.658761) (xy 95.803574 -223.603606) (xy 95.802958 -223.575626) (xy 95.803467 -223.549659)
			(xy 95.811592 -223.498364) (xy 95.82764 -223.448971) (xy 95.851218 -223.402697) (xy 95.881744 -223.360681)
			(xy 95.918467 -223.323958) (xy 95.960483 -223.293432) (xy 96.006757 -223.269854) (xy 96.05615 -223.253806)
			(xy 96.107445 -223.245681) (xy 96.159379 -223.245681) (xy 96.210674 -223.253806) (xy 96.260067 -223.269854)
			(xy 96.306341 -223.293432) (xy 96.348357 -223.323958) (xy 96.38508 -223.360681) (xy 96.415606 -223.402697)
			(xy 96.439184 -223.448971) (xy 96.455232 -223.498364) (xy 96.463357 -223.549659) (xy 96.463866 -223.575626)
			(xy 96.463393 -223.601077) (xy 96.463313 -223.601593) (xy 96.743521 -223.601593) (xy 96.743521 -223.549659)
			(xy 96.751646 -223.498364) (xy 96.767694 -223.448971) (xy 96.791272 -223.402697) (xy 96.821798 -223.360681)
			(xy 96.858521 -223.323958) (xy 96.900537 -223.293432) (xy 96.946811 -223.269854) (xy 96.996204 -223.253806)
			(xy 97.047499 -223.245681) (xy 97.099433 -223.245681) (xy 97.150728 -223.253806) (xy 97.200121 -223.269854)
			(xy 97.246395 -223.293432) (xy 97.288411 -223.323958) (xy 97.325134 -223.360681) (xy 97.35566 -223.402697)
			(xy 97.379238 -223.448971) (xy 97.395286 -223.498364) (xy 97.403411 -223.549659) (xy 97.40392 -223.575626)
			(xy 97.403411 -223.601593) (xy 97.395286 -223.652888) (xy 97.379238 -223.702281) (xy 97.35566 -223.748555)
			(xy 97.325134 -223.790571) (xy 97.288411 -223.827294) (xy 97.246395 -223.85782) (xy 97.200121 -223.881398)
			(xy 97.150728 -223.897446) (xy 97.099433 -223.905571) (xy 97.047499 -223.905571) (xy 96.996204 -223.897446)
			(xy 96.946811 -223.881398) (xy 96.900537 -223.85782) (xy 96.858521 -223.827294) (xy 96.821798 -223.790571)
			(xy 96.791272 -223.748555) (xy 96.767694 -223.702281) (xy 96.751646 -223.652888) (xy 96.743521 -223.601593)
			(xy 96.463313 -223.601593) (xy 96.455611 -223.651381) (xy 96.440206 -223.699896) (xy 96.417541 -223.745473)
			(xy 96.388153 -223.787035) (xy 96.352737 -223.823597) (xy 96.312133 -223.854293) (xy 96.2673 -223.878398)
			(xy 96.219301 -223.895341) (xy 96.194372 -223.900492) (xy 96.171258 -223.90481) (xy 95.967804 -224.257616)
			(xy 95.975424 -224.279714) (xy 95.984166 -224.306301) (xy 95.99361 -224.361461) (xy 95.99422 -224.389442)
			(xy 96.273112 -224.389442) (xy 96.273621 -224.363475) (xy 96.281746 -224.31218) (xy 96.297794 -224.262787)
			(xy 96.321372 -224.216513) (xy 96.351898 -224.174497) (xy 96.388621 -224.137774) (xy 96.430637 -224.107248)
			(xy 96.476911 -224.08367) (xy 96.526304 -224.067622) (xy 96.577599 -224.059497) (xy 96.629533 -224.059497)
			(xy 96.680828 -224.067622) (xy 96.730221 -224.08367) (xy 96.776495 -224.107248) (xy 96.818511 -224.137774)
			(xy 96.855234 -224.174497) (xy 96.88576 -224.216513) (xy 96.909338 -224.262787) (xy 96.925386 -224.31218)
			(xy 96.933511 -224.363475) (xy 96.93402 -224.389442) (xy 97.212912 -224.389442) (xy 97.213374 -224.363991)
			(xy 97.22116 -224.313687) (xy 97.236568 -224.265174) (xy 97.259236 -224.219597) (xy 97.288625 -224.178036)
			(xy 97.324041 -224.141475) (xy 97.364646 -224.110778) (xy 97.409478 -224.086672) (xy 97.457477 -224.069728)
			(xy 97.482406 -224.064576) (xy 97.505266 -224.060258) (xy 97.708974 -223.707198) (xy 97.701354 -223.685354)
			(xy 97.692631 -223.658761) (xy 97.683174 -223.603606) (xy 97.682558 -223.575626) (xy 97.683067 -223.549659)
			(xy 97.691192 -223.498364) (xy 97.70724 -223.448971) (xy 97.730818 -223.402697) (xy 97.761344 -223.360681)
			(xy 97.798067 -223.323958) (xy 97.840083 -223.293432) (xy 97.886357 -223.269854) (xy 97.93575 -223.253806)
			(xy 97.987045 -223.245681) (xy 98.038979 -223.245681) (xy 98.090274 -223.253806) (xy 98.139667 -223.269854)
			(xy 98.185941 -223.293432) (xy 98.227957 -223.323958) (xy 98.26468 -223.360681) (xy 98.295206 -223.402697)
			(xy 98.318784 -223.448971) (xy 98.334832 -223.498364) (xy 98.342957 -223.549659) (xy 98.343466 -223.575626)
			(xy 98.342993 -223.601077) (xy 98.342913 -223.601593) (xy 98.623121 -223.601593) (xy 98.623121 -223.549659)
			(xy 98.631246 -223.498364) (xy 98.647294 -223.448971) (xy 98.670872 -223.402697) (xy 98.701398 -223.360681)
			(xy 98.738121 -223.323958) (xy 98.780137 -223.293432) (xy 98.826411 -223.269854) (xy 98.875804 -223.253806)
			(xy 98.927099 -223.245681) (xy 98.979033 -223.245681) (xy 99.030328 -223.253806) (xy 99.079721 -223.269854)
			(xy 99.125995 -223.293432) (xy 99.168011 -223.323958) (xy 99.204734 -223.360681) (xy 99.23526 -223.402697)
			(xy 99.258838 -223.448971) (xy 99.274886 -223.498364) (xy 99.283011 -223.549659) (xy 99.28352 -223.575626)
			(xy 99.283011 -223.601593) (xy 99.274886 -223.652888) (xy 99.258838 -223.702281) (xy 99.23526 -223.748555)
			(xy 99.204734 -223.790571) (xy 99.168011 -223.827294) (xy 99.125995 -223.85782) (xy 99.079721 -223.881398)
			(xy 99.030328 -223.897446) (xy 98.979033 -223.905571) (xy 98.927099 -223.905571) (xy 98.875804 -223.897446)
			(xy 98.826411 -223.881398) (xy 98.780137 -223.85782) (xy 98.738121 -223.827294) (xy 98.701398 -223.790571)
			(xy 98.670872 -223.748555) (xy 98.647294 -223.702281) (xy 98.631246 -223.652888) (xy 98.623121 -223.601593)
			(xy 98.342913 -223.601593) (xy 98.335211 -223.651381) (xy 98.319806 -223.699896) (xy 98.297141 -223.745473)
			(xy 98.267753 -223.787035) (xy 98.232337 -223.823597) (xy 98.191733 -223.854293) (xy 98.1469 -223.878398)
			(xy 98.098901 -223.895341) (xy 98.073972 -223.900492) (xy 98.050858 -223.90481) (xy 97.847404 -224.257616)
			(xy 97.855024 -224.279714) (xy 97.863766 -224.306301) (xy 97.87321 -224.361461) (xy 97.87382 -224.389442)
			(xy 98.152712 -224.389442) (xy 98.153221 -224.363475) (xy 98.161346 -224.31218) (xy 98.177394 -224.262787)
			(xy 98.200972 -224.216513) (xy 98.231498 -224.174497) (xy 98.268221 -224.137774) (xy 98.310237 -224.107248)
			(xy 98.356511 -224.08367) (xy 98.405904 -224.067622) (xy 98.457199 -224.059497) (xy 98.509133 -224.059497)
			(xy 98.560428 -224.067622) (xy 98.609821 -224.08367) (xy 98.656095 -224.107248) (xy 98.698111 -224.137774)
			(xy 98.734834 -224.174497) (xy 98.76536 -224.216513) (xy 98.788938 -224.262787) (xy 98.804986 -224.31218)
			(xy 98.813111 -224.363475) (xy 98.81362 -224.389442) (xy 98.813077 -224.417428) (xy 98.80362 -224.472596)
			(xy 98.794824 -224.49917) (xy 98.787204 -224.521268) (xy 98.990912 -224.874074) (xy 99.013772 -224.878392)
			(xy 99.038704 -224.883512) (xy 99.08669 -224.900483) (xy 99.131509 -224.924607) (xy 99.172102 -224.955314)
			(xy 99.207509 -224.991878) (xy 99.236896 -225.033436) (xy 99.259568 -225.079006) (xy 99.274989 -225.127512)
			(xy 99.282794 -225.177809) (xy 99.283266 -225.203258) (xy 99.282757 -225.229225) (xy 99.274632 -225.28052)
			(xy 99.258584 -225.329913) (xy 99.235006 -225.376187) (xy 99.20448 -225.418203) (xy 99.167757 -225.454926)
			(xy 99.125741 -225.485452) (xy 99.079467 -225.50903) (xy 99.030074 -225.525078) (xy 98.978779 -225.533203)
			(xy 98.926845 -225.533203) (xy 98.87555 -225.525078) (xy 98.826157 -225.50903) (xy 98.779883 -225.485452)
			(xy 98.737867 -225.454926) (xy 98.701144 -225.418203) (xy 98.670618 -225.376187) (xy 98.64704 -225.329913)
			(xy 98.630992 -225.28052) (xy 98.622867 -225.229225) (xy 98.622358 -225.203258) (xy 98.622897 -225.175271)
			(xy 98.632356 -225.120104) (xy 98.641154 -225.09353) (xy 98.648774 -225.071432) (xy 98.445066 -224.718626)
			(xy 98.422206 -224.714308) (xy 98.397286 -224.709131) (xy 98.3493 -224.692171) (xy 98.30448 -224.668057)
			(xy 98.263885 -224.637359) (xy 98.228475 -224.600802) (xy 98.199086 -224.55925) (xy 98.176412 -224.513684)
			(xy 98.16099 -224.465182) (xy 98.153184 -224.414889) (xy 98.152712 -224.389442) (xy 97.87382 -224.389442)
			(xy 97.873311 -224.415409) (xy 97.865186 -224.466704) (xy 97.849138 -224.516097) (xy 97.82556 -224.562371)
			(xy 97.795034 -224.604387) (xy 97.758311 -224.64111) (xy 97.716295 -224.671636) (xy 97.670021 -224.695214)
			(xy 97.620628 -224.711262) (xy 97.569333 -224.719387) (xy 97.517399 -224.719387) (xy 97.466104 -224.711262)
			(xy 97.416711 -224.695214) (xy 97.370437 -224.671636) (xy 97.328421 -224.64111) (xy 97.291698 -224.604387)
			(xy 97.261172 -224.562371) (xy 97.237594 -224.516097) (xy 97.221546 -224.466704) (xy 97.213421 -224.415409)
			(xy 97.212912 -224.389442) (xy 96.93402 -224.389442) (xy 96.933477 -224.417428) (xy 96.92402 -224.472596)
			(xy 96.915224 -224.49917) (xy 96.907604 -224.521268) (xy 97.111312 -224.874074) (xy 97.134172 -224.878392)
			(xy 97.159104 -224.883512) (xy 97.20709 -224.900483) (xy 97.251909 -224.924607) (xy 97.292502 -224.955314)
			(xy 97.327909 -224.991878) (xy 97.357296 -225.033436) (xy 97.379968 -225.079006) (xy 97.395389 -225.127512)
			(xy 97.403194 -225.177809) (xy 97.403666 -225.203258) (xy 97.403157 -225.229225) (xy 97.683067 -225.229225)
			(xy 97.683067 -225.177291) (xy 97.691192 -225.125996) (xy 97.70724 -225.076603) (xy 97.730818 -225.030329)
			(xy 97.761344 -224.988313) (xy 97.798067 -224.95159) (xy 97.840083 -224.921064) (xy 97.886357 -224.897486)
			(xy 97.93575 -224.881438) (xy 97.987045 -224.873313) (xy 98.038979 -224.873313) (xy 98.090274 -224.881438)
			(xy 98.139667 -224.897486) (xy 98.185941 -224.921064) (xy 98.227957 -224.95159) (xy 98.26468 -224.988313)
			(xy 98.295206 -225.030329) (xy 98.318784 -225.076603) (xy 98.334832 -225.125996) (xy 98.342957 -225.177291)
			(xy 98.343466 -225.203258) (xy 98.342957 -225.229225) (xy 98.334832 -225.28052) (xy 98.318784 -225.329913)
			(xy 98.295206 -225.376187) (xy 98.26468 -225.418203) (xy 98.227957 -225.454926) (xy 98.185941 -225.485452)
			(xy 98.139667 -225.50903) (xy 98.090274 -225.525078) (xy 98.038979 -225.533203) (xy 97.987045 -225.533203)
			(xy 97.93575 -225.525078) (xy 97.886357 -225.50903) (xy 97.840083 -225.485452) (xy 97.798067 -225.454926)
			(xy 97.761344 -225.418203) (xy 97.730818 -225.376187) (xy 97.70724 -225.329913) (xy 97.691192 -225.28052)
			(xy 97.683067 -225.229225) (xy 97.403157 -225.229225) (xy 97.395032 -225.28052) (xy 97.378984 -225.329913)
			(xy 97.355406 -225.376187) (xy 97.32488 -225.418203) (xy 97.288157 -225.454926) (xy 97.246141 -225.485452)
			(xy 97.199867 -225.50903) (xy 97.150474 -225.525078) (xy 97.099179 -225.533203) (xy 97.047245 -225.533203)
			(xy 96.99595 -225.525078) (xy 96.946557 -225.50903) (xy 96.900283 -225.485452) (xy 96.858267 -225.454926)
			(xy 96.821544 -225.418203) (xy 96.791018 -225.376187) (xy 96.76744 -225.329913) (xy 96.751392 -225.28052)
			(xy 96.743267 -225.229225) (xy 96.742758 -225.203258) (xy 96.743297 -225.175271) (xy 96.752756 -225.120104)
			(xy 96.761554 -225.09353) (xy 96.769174 -225.071432) (xy 96.565466 -224.718626) (xy 96.542606 -224.714308)
			(xy 96.517686 -224.709131) (xy 96.4697 -224.692171) (xy 96.42488 -224.668057) (xy 96.384285 -224.637359)
			(xy 96.348875 -224.600802) (xy 96.319486 -224.55925) (xy 96.296812 -224.513684) (xy 96.28139 -224.465182)
			(xy 96.273584 -224.414889) (xy 96.273112 -224.389442) (xy 95.99422 -224.389442) (xy 95.993711 -224.415409)
			(xy 95.985586 -224.466704) (xy 95.969538 -224.516097) (xy 95.94596 -224.562371) (xy 95.915434 -224.604387)
			(xy 95.878711 -224.64111) (xy 95.836695 -224.671636) (xy 95.790421 -224.695214) (xy 95.741028 -224.711262)
			(xy 95.689733 -224.719387) (xy 95.637799 -224.719387) (xy 95.586504 -224.711262) (xy 95.537111 -224.695214)
			(xy 95.490837 -224.671636) (xy 95.448821 -224.64111) (xy 95.412098 -224.604387) (xy 95.381572 -224.562371)
			(xy 95.357994 -224.516097) (xy 95.341946 -224.466704) (xy 95.333821 -224.415409) (xy 95.333312 -224.389442)
			(xy 95.05442 -224.389442) (xy 95.053812 -224.417423) (xy 95.04437 -224.472584) (xy 95.035624 -224.49917)
			(xy 95.028004 -224.521268) (xy 95.231712 -224.874074) (xy 95.254572 -224.878392) (xy 95.279501 -224.883543)
			(xy 95.327502 -224.900485) (xy 95.372336 -224.92459) (xy 95.412942 -224.955286) (xy 95.448359 -224.991848)
			(xy 95.477749 -225.033409) (xy 95.500416 -225.078987) (xy 95.515823 -225.127502) (xy 95.523607 -225.177806)
			(xy 95.524066 -225.203258) (xy 95.523564 -225.229081) (xy 95.523541 -225.229225) (xy 95.803467 -225.229225)
			(xy 95.803467 -225.177291) (xy 95.811592 -225.125996) (xy 95.82764 -225.076603) (xy 95.851218 -225.030329)
			(xy 95.881744 -224.988313) (xy 95.918467 -224.95159) (xy 95.960483 -224.921064) (xy 96.006757 -224.897486)
			(xy 96.05615 -224.881438) (xy 96.107445 -224.873313) (xy 96.159379 -224.873313) (xy 96.210674 -224.881438)
			(xy 96.260067 -224.897486) (xy 96.306341 -224.921064) (xy 96.348357 -224.95159) (xy 96.38508 -224.988313)
			(xy 96.415606 -225.030329) (xy 96.439184 -225.076603) (xy 96.455232 -225.125996) (xy 96.463357 -225.177291)
			(xy 96.463866 -225.203258) (xy 96.463357 -225.229225) (xy 96.455232 -225.28052) (xy 96.439184 -225.329913)
			(xy 96.415606 -225.376187) (xy 96.38508 -225.418203) (xy 96.348357 -225.454926) (xy 96.306341 -225.485452)
			(xy 96.260067 -225.50903) (xy 96.210674 -225.525078) (xy 96.159379 -225.533203) (xy 96.107445 -225.533203)
			(xy 96.05615 -225.525078) (xy 96.006757 -225.50903) (xy 95.960483 -225.485452) (xy 95.918467 -225.454926)
			(xy 95.881744 -225.418203) (xy 95.851218 -225.376187) (xy 95.82764 -225.329913) (xy 95.811592 -225.28052)
			(xy 95.803467 -225.229225) (xy 95.523541 -225.229225) (xy 95.515523 -225.280097) (xy 95.499646 -225.329242)
			(xy 95.476319 -225.37532) (xy 95.446111 -225.417209) (xy 95.428308 -225.435922) (xy 95.40113 -225.463354)
			(xy 95.453962 -225.555048) (xy 95.45447 -225.556064) (xy 95.473012 -225.586544) (xy 95.476314 -225.592386)
			(xy 95.580454 -225.696526) (xy 95.606362 -225.691954) (xy 95.620596 -225.689593) (xy 95.649339 -225.687051)
			(xy 95.663766 -225.686874) (xy 95.687924 -225.687292) (xy 95.735724 -225.694327) (xy 95.781989 -225.708253)
			(xy 95.825731 -225.728771) (xy 95.866017 -225.755445) (xy 95.901986 -225.787703) (xy 95.917766 -225.806)
			(xy 96.349566 -225.806) (xy 96.365356 -225.787715) (xy 96.401335 -225.755475) (xy 96.441622 -225.728814)
			(xy 96.48536 -225.7083) (xy 96.531618 -225.69437) (xy 96.579411 -225.68732) (xy 96.603566 -225.686874)
			(xy 96.6282 -225.687333) (xy 96.676922 -225.694657) (xy 96.724017 -225.709131) (xy 96.768442 -225.730436)
			(xy 96.809211 -225.758099) (xy 96.845423 -225.791508) (xy 96.876275 -225.829922) (xy 96.901082 -225.87249)
			(xy 96.919296 -225.918269) (xy 96.925384 -225.942144) (xy 96.928686 -225.956368) (xy 97.039938 -226.06762)
			(xy 97.050665 -226.077678) (xy 97.076488 -226.091715) (xy 97.105238 -226.097826) (xy 97.134539 -226.095505)
			(xy 97.161969 -226.084945) (xy 97.185261 -226.067017) (xy 97.20249 -226.043204) (xy 97.212233 -226.015473)
			(xy 97.21342 -226.000818) (xy 97.21515 -225.975739) (xy 97.225245 -225.926496) (xy 97.242682 -225.87935)
			(xy 97.267056 -225.835387) (xy 97.297808 -225.795623) (xy 97.334226 -225.760975) (xy 97.375471 -225.732241)
			(xy 97.420592 -225.710084) (xy 97.468548 -225.695016) (xy 97.518232 -225.687383) (xy 97.543366 -225.686874)
			(xy 97.569336 -225.687354) (xy 97.620638 -225.695475) (xy 97.670037 -225.711523) (xy 97.716317 -225.735101)
			(xy 97.758339 -225.765629) (xy 97.795067 -225.802356) (xy 97.825596 -225.844377) (xy 97.849175 -225.890657)
			(xy 97.865223 -225.940056) (xy 97.873345 -225.991358) (xy 97.87382 -226.017328) (xy 97.873355 -226.042468)
			(xy 97.873228 -226.043295) (xy 98.153221 -226.043295) (xy 98.153221 -225.991361) (xy 98.161346 -225.940066)
			(xy 98.177394 -225.890673) (xy 98.200972 -225.844399) (xy 98.231498 -225.802383) (xy 98.268221 -225.76566)
			(xy 98.310237 -225.735134) (xy 98.356511 -225.711556) (xy 98.405904 -225.695508) (xy 98.457199 -225.687383)
			(xy 98.509133 -225.687383) (xy 98.560428 -225.695508) (xy 98.609821 -225.711556) (xy 98.656095 -225.735134)
			(xy 98.698111 -225.76566) (xy 98.734834 -225.802383) (xy 98.76536 -225.844399) (xy 98.788938 -225.890673)
			(xy 98.804986 -225.940066) (xy 98.813111 -225.991361) (xy 98.81362 -226.017328) (xy 98.813111 -226.043295)
			(xy 99.093021 -226.043295) (xy 99.093021 -225.991361) (xy 99.101146 -225.940066) (xy 99.117194 -225.890673)
			(xy 99.140772 -225.844399) (xy 99.171298 -225.802383) (xy 99.208021 -225.76566) (xy 99.250037 -225.735134)
			(xy 99.296311 -225.711556) (xy 99.345704 -225.695508) (xy 99.396999 -225.687383) (xy 99.448933 -225.687383)
			(xy 99.500228 -225.695508) (xy 99.549621 -225.711556) (xy 99.595895 -225.735134) (xy 99.637911 -225.76566)
			(xy 99.674634 -225.802383) (xy 99.70516 -225.844399) (xy 99.728738 -225.890673) (xy 99.744786 -225.940066)
			(xy 99.752911 -225.991361) (xy 99.75342 -226.017328) (xy 99.752911 -226.043295) (xy 99.744786 -226.09459)
			(xy 99.728738 -226.143983) (xy 99.70516 -226.190257) (xy 99.674634 -226.232273) (xy 99.637911 -226.268996)
			(xy 99.595895 -226.299522) (xy 99.549621 -226.3231) (xy 99.500228 -226.339148) (xy 99.448933 -226.347273)
			(xy 99.396999 -226.347273) (xy 99.345704 -226.339148) (xy 99.296311 -226.3231) (xy 99.250037 -226.299522)
			(xy 99.208021 -226.268996) (xy 99.171298 -226.232273) (xy 99.140772 -226.190257) (xy 99.117194 -226.143983)
			(xy 99.101146 -226.09459) (xy 99.093021 -226.043295) (xy 98.813111 -226.043295) (xy 98.804986 -226.09459)
			(xy 98.788938 -226.143983) (xy 98.76536 -226.190257) (xy 98.734834 -226.232273) (xy 98.698111 -226.268996)
			(xy 98.656095 -226.299522) (xy 98.609821 -226.3231) (xy 98.560428 -226.339148) (xy 98.509133 -226.347273)
			(xy 98.457199 -226.347273) (xy 98.405904 -226.339148) (xy 98.356511 -226.3231) (xy 98.310237 -226.299522)
			(xy 98.268221 -226.268996) (xy 98.231498 -226.232273) (xy 98.200972 -226.190257) (xy 98.177394 -226.143983)
			(xy 98.161346 -226.09459) (xy 98.153221 -226.043295) (xy 97.873228 -226.043295) (xy 97.865745 -226.09217)
			(xy 97.850691 -226.140144) (xy 97.82854 -226.185283) (xy 97.799804 -226.226543) (xy 97.765147 -226.262971)
			(xy 97.725369 -226.293726) (xy 97.68139 -226.318097) (xy 97.634225 -226.335522) (xy 97.584964 -226.345597)
			(xy 97.559876 -226.347274) (xy 97.545203 -226.34845) (xy 97.517421 -226.358143) (xy 97.493557 -226.375356)
			(xy 97.475593 -226.39866) (xy 97.465019 -226.426118) (xy 97.462714 -226.455452) (xy 97.468869 -226.484225)
			(xy 97.482974 -226.510048) (xy 97.493074 -226.520756) (xy 97.595182 -226.622864) (xy 97.635147 -226.605202)
			(xy 97.717522 -226.576045) (xy 97.80211 -226.554121) (xy 97.845118 -226.54641) (xy 97.870748 -226.532058)
			(xy 97.925829 -226.511659) (xy 97.983644 -226.501298) (xy 98.013012 -226.50069) (xy 98.038979 -226.501174)
			(xy 98.090275 -226.509301) (xy 98.139667 -226.525352) (xy 98.185939 -226.548933) (xy 98.227953 -226.579463)
			(xy 98.264674 -226.616189) (xy 98.295196 -226.658208) (xy 98.318769 -226.704485) (xy 98.334813 -226.75388)
			(xy 98.342931 -226.805176) (xy 98.343466 -226.831144) (xy 98.343015 -226.855769) (xy 98.342814 -226.857111)
			(xy 98.623121 -226.857111) (xy 98.623121 -226.805177) (xy 98.631246 -226.753882) (xy 98.647294 -226.704489)
			(xy 98.670872 -226.658215) (xy 98.701398 -226.616199) (xy 98.738121 -226.579476) (xy 98.780137 -226.54895)
			(xy 98.826411 -226.525372) (xy 98.875804 -226.509324) (xy 98.927099 -226.501199) (xy 98.979033 -226.501199)
			(xy 99.030328 -226.509324) (xy 99.079721 -226.525372) (xy 99.125995 -226.54895) (xy 99.168011 -226.579476)
			(xy 99.204734 -226.616199) (xy 99.23526 -226.658215) (xy 99.258838 -226.704489) (xy 99.274886 -226.753882)
			(xy 99.283011 -226.805177) (xy 99.28352 -226.831144) (xy 99.283011 -226.857111) (xy 99.562921 -226.857111)
			(xy 99.562921 -226.805177) (xy 99.571046 -226.753882) (xy 99.587094 -226.704489) (xy 99.610672 -226.658215)
			(xy 99.641198 -226.616199) (xy 99.677921 -226.579476) (xy 99.719937 -226.54895) (xy 99.766211 -226.525372)
			(xy 99.815604 -226.509324) (xy 99.866899 -226.501199) (xy 99.918833 -226.501199) (xy 99.970128 -226.509324)
			(xy 100.019521 -226.525372) (xy 100.065795 -226.54895) (xy 100.107811 -226.579476) (xy 100.144534 -226.616199)
			(xy 100.17506 -226.658215) (xy 100.198638 -226.704489) (xy 100.214686 -226.753882) (xy 100.222811 -226.805177)
			(xy 100.22332 -226.831144) (xy 100.222811 -226.857111) (xy 100.214686 -226.908406) (xy 100.198638 -226.957799)
			(xy 100.17506 -227.004073) (xy 100.144534 -227.046089) (xy 100.107811 -227.082812) (xy 100.065795 -227.113338)
			(xy 100.019521 -227.136916) (xy 99.970128 -227.152964) (xy 99.918833 -227.161089) (xy 99.866899 -227.161089)
			(xy 99.815604 -227.152964) (xy 99.766211 -227.136916) (xy 99.719937 -227.113338) (xy 99.677921 -227.082812)
			(xy 99.641198 -227.046089) (xy 99.610672 -227.004073) (xy 99.587094 -226.957799) (xy 99.571046 -226.908406)
			(xy 99.562921 -226.857111) (xy 99.283011 -226.857111) (xy 99.274886 -226.908406) (xy 99.258838 -226.957799)
			(xy 99.23526 -227.004073) (xy 99.204734 -227.046089) (xy 99.168011 -227.082812) (xy 99.125995 -227.113338)
			(xy 99.079721 -227.136916) (xy 99.030328 -227.152964) (xy 98.979033 -227.161089) (xy 98.927099 -227.161089)
			(xy 98.875804 -227.152964) (xy 98.826411 -227.136916) (xy 98.780137 -227.113338) (xy 98.738121 -227.082812)
			(xy 98.701398 -227.046089) (xy 98.670872 -227.004073) (xy 98.647294 -226.957799) (xy 98.631246 -226.908406)
			(xy 98.623121 -226.857111) (xy 98.342814 -226.857111) (xy 98.335712 -226.904475) (xy 98.321259 -226.951557)
			(xy 98.299976 -226.995972) (xy 98.272336 -227.036735) (xy 98.23895 -227.072942) (xy 98.220022 -227.0887)
			(xy 98.209264 -227.098006) (xy 98.192934 -227.121284) (xy 98.183646 -227.148158) (xy 98.182117 -227.176551)
			(xy 98.188466 -227.204268) (xy 98.202201 -227.229165) (xy 98.211894 -227.239576) (xy 98.325178 -227.35286)
			(xy 98.35642 -227.339652) (xy 98.376583 -227.331664) (xy 98.418478 -227.320446) (xy 98.461481 -227.314813)
			(xy 98.483166 -227.314506) (xy 98.509136 -227.315013) (xy 98.560438 -227.323133) (xy 98.609837 -227.339178)
			(xy 98.656119 -227.362753) (xy 98.698143 -227.393278) (xy 98.734874 -227.430001) (xy 98.765408 -227.472018)
			(xy 98.788994 -227.518294) (xy 98.80505 -227.56769) (xy 98.813182 -227.61899) (xy 98.81362 -227.64496)
			(xy 98.813097 -227.670927) (xy 99.092767 -227.670927) (xy 99.092767 -227.618993) (xy 99.100892 -227.567698)
			(xy 99.11694 -227.518305) (xy 99.140518 -227.472031) (xy 99.171044 -227.430015) (xy 99.207767 -227.393292)
			(xy 99.249783 -227.362766) (xy 99.296057 -227.339188) (xy 99.34545 -227.32314) (xy 99.396745 -227.315015)
			(xy 99.448679 -227.315015) (xy 99.499974 -227.32314) (xy 99.549367 -227.339188) (xy 99.595641 -227.362766)
			(xy 99.637657 -227.393292) (xy 99.67438 -227.430015) (xy 99.704906 -227.472031) (xy 99.728484 -227.518305)
			(xy 99.744532 -227.567698) (xy 99.752657 -227.618993) (xy 99.753166 -227.64496) (xy 99.752657 -227.670927)
			(xy 100.032821 -227.670927) (xy 100.032821 -227.618993) (xy 100.040946 -227.567698) (xy 100.056994 -227.518305)
			(xy 100.080572 -227.472031) (xy 100.111098 -227.430015) (xy 100.147821 -227.393292) (xy 100.189837 -227.362766)
			(xy 100.236111 -227.339188) (xy 100.285504 -227.32314) (xy 100.336799 -227.315015) (xy 100.388733 -227.315015)
			(xy 100.440028 -227.32314) (xy 100.489421 -227.339188) (xy 100.535695 -227.362766) (xy 100.577711 -227.393292)
			(xy 100.614434 -227.430015) (xy 100.64496 -227.472031) (xy 100.668538 -227.518305) (xy 100.684586 -227.567698)
			(xy 100.692711 -227.618993) (xy 100.69322 -227.64496) (xy 100.692711 -227.670927) (xy 100.684586 -227.722222)
			(xy 100.668538 -227.771615) (xy 100.64496 -227.817889) (xy 100.614434 -227.859905) (xy 100.577711 -227.896628)
			(xy 100.535695 -227.927154) (xy 100.489421 -227.950732) (xy 100.440028 -227.96678) (xy 100.388733 -227.974905)
			(xy 100.336799 -227.974905) (xy 100.285504 -227.96678) (xy 100.236111 -227.950732) (xy 100.189837 -227.927154)
			(xy 100.147821 -227.896628) (xy 100.111098 -227.859905) (xy 100.080572 -227.817889) (xy 100.056994 -227.771615)
			(xy 100.040946 -227.722222) (xy 100.032821 -227.670927) (xy 99.752657 -227.670927) (xy 99.744532 -227.722222)
			(xy 99.728484 -227.771615) (xy 99.704906 -227.817889) (xy 99.67438 -227.859905) (xy 99.637657 -227.896628)
			(xy 99.595641 -227.927154) (xy 99.549367 -227.950732) (xy 99.499974 -227.96678) (xy 99.448679 -227.974905)
			(xy 99.396745 -227.974905) (xy 99.34545 -227.96678) (xy 99.296057 -227.950732) (xy 99.249783 -227.927154)
			(xy 99.207767 -227.896628) (xy 99.171044 -227.859905) (xy 99.140518 -227.817889) (xy 99.11694 -227.771615)
			(xy 99.100892 -227.722222) (xy 99.092767 -227.670927) (xy 98.813097 -227.670927) (xy 98.813052 -227.673149)
			(xy 98.803489 -227.728709) (xy 98.784636 -227.781841) (xy 98.757037 -227.831001) (xy 98.739706 -227.85324)
			(xy 98.739706 -228.041708) (xy 98.740091 -228.05502) (xy 98.746966 -228.08074) (xy 98.76027 -228.103801)
			(xy 98.779095 -228.122627) (xy 98.802156 -228.135933) (xy 98.827876 -228.142809) (xy 98.854499 -228.142786)
			(xy 98.867468 -228.139752) (xy 98.888418 -228.134536) (xy 98.931226 -228.128933) (xy 98.952812 -228.128576)
			(xy 98.978776 -228.129086) (xy 99.030065 -228.137211) (xy 99.079452 -228.153259) (xy 99.12572 -228.176836)
			(xy 99.16773 -228.207359) (xy 99.204448 -228.244079) (xy 99.234971 -228.286091) (xy 99.258545 -228.332359)
			(xy 99.274592 -228.381747) (xy 99.282715 -228.433036) (xy 99.282715 -228.484964) (xy 99.28271 -228.484997)
			(xy 99.562667 -228.484997) (xy 99.562667 -228.433063) (xy 99.570792 -228.381768) (xy 99.58684 -228.332375)
			(xy 99.610418 -228.286101) (xy 99.640944 -228.244085) (xy 99.677667 -228.207362) (xy 99.719683 -228.176836)
			(xy 99.765957 -228.153258) (xy 99.81535 -228.13721) (xy 99.866645 -228.129085) (xy 99.918579 -228.129085)
			(xy 99.969874 -228.13721) (xy 100.019267 -228.153258) (xy 100.065541 -228.176836) (xy 100.107557 -228.207362)
			(xy 100.14428 -228.244085) (xy 100.174806 -228.286101) (xy 100.198384 -228.332375) (xy 100.214432 -228.381768)
			(xy 100.222557 -228.433063) (xy 100.223066 -228.45903) (xy 100.222557 -228.484997) (xy 100.502467 -228.484997)
			(xy 100.502467 -228.433063) (xy 100.510592 -228.381768) (xy 100.52664 -228.332375) (xy 100.550218 -228.286101)
			(xy 100.580744 -228.244085) (xy 100.617467 -228.207362) (xy 100.659483 -228.176836) (xy 100.705757 -228.153258)
			(xy 100.75515 -228.13721) (xy 100.806445 -228.129085) (xy 100.858379 -228.129085) (xy 100.909674 -228.13721)
			(xy 100.959067 -228.153258) (xy 101.005341 -228.176836) (xy 101.047357 -228.207362) (xy 101.08408 -228.244085)
			(xy 101.114606 -228.286101) (xy 101.138184 -228.332375) (xy 101.154232 -228.381768) (xy 101.162357 -228.433063)
			(xy 101.162866 -228.45903) (xy 101.162357 -228.484997) (xy 101.154232 -228.536292) (xy 101.138184 -228.585685)
			(xy 101.114606 -228.631959) (xy 101.08408 -228.673975) (xy 101.047357 -228.710698) (xy 101.005341 -228.741224)
			(xy 100.959067 -228.764802) (xy 100.909674 -228.78085) (xy 100.858379 -228.788975) (xy 100.806445 -228.788975)
			(xy 100.75515 -228.78085) (xy 100.705757 -228.764802) (xy 100.659483 -228.741224) (xy 100.617467 -228.710698)
			(xy 100.580744 -228.673975) (xy 100.550218 -228.631959) (xy 100.52664 -228.585685) (xy 100.510592 -228.536292)
			(xy 100.502467 -228.484997) (xy 100.222557 -228.484997) (xy 100.214432 -228.536292) (xy 100.198384 -228.585685)
			(xy 100.174806 -228.631959) (xy 100.14428 -228.673975) (xy 100.107557 -228.710698) (xy 100.065541 -228.741224)
			(xy 100.019267 -228.764802) (xy 99.969874 -228.78085) (xy 99.918579 -228.788975) (xy 99.866645 -228.788975)
			(xy 99.81535 -228.78085) (xy 99.765957 -228.764802) (xy 99.719683 -228.741224) (xy 99.677667 -228.710698)
			(xy 99.640944 -228.673975) (xy 99.610418 -228.631959) (xy 99.58684 -228.585685) (xy 99.570792 -228.536292)
			(xy 99.562667 -228.484997) (xy 99.28271 -228.484997) (xy 99.274592 -228.536253) (xy 99.258545 -228.585641)
			(xy 99.234971 -228.631909) (xy 99.204448 -228.673921) (xy 99.16773 -228.710641) (xy 99.12572 -228.741164)
			(xy 99.079452 -228.764741) (xy 99.030065 -228.780789) (xy 98.978776 -228.788914) (xy 98.952812 -228.789484)
			(xy 98.928571 -228.789063) (xy 98.880609 -228.781979) (xy 98.834201 -228.767947) (xy 98.812096 -228.757988)
			(xy 98.801936 -228.753162) (xy 98.739706 -228.753162) (xy 98.739706 -228.84384) (xy 98.995484 -229.099618)
			(xy 99.006357 -229.109776) (xy 99.032548 -229.123869) (xy 99.06169 -229.129813) (xy 99.091308 -229.127103)
			(xy 99.118888 -229.11597) (xy 99.142087 -229.097359) (xy 99.150932 -229.085394) (xy 99.166461 -229.063722)
			(xy 99.203345 -229.025226) (xy 99.245934 -228.993158) (xy 99.293124 -228.96835) (xy 99.343687 -228.951448)
			(xy 99.396309 -228.942891) (xy 99.422966 -228.942392) (xy 99.448936 -228.942872) (xy 99.500236 -228.950993)
			(xy 99.549634 -228.967041) (xy 99.595913 -228.990619) (xy 99.637933 -229.021148) (xy 99.674659 -229.057876)
			(xy 99.705187 -229.099897) (xy 99.728764 -229.146177) (xy 99.744809 -229.195575) (xy 99.752929 -229.246876)
			(xy 99.75342 -229.272846) (xy 99.75292 -229.298813) (xy 100.032821 -229.298813) (xy 100.032821 -229.246879)
			(xy 100.040946 -229.195584) (xy 100.056994 -229.146191) (xy 100.080572 -229.099917) (xy 100.111098 -229.057901)
			(xy 100.147821 -229.021178) (xy 100.189837 -228.990652) (xy 100.236111 -228.967074) (xy 100.285504 -228.951026)
			(xy 100.336799 -228.942901) (xy 100.388733 -228.942901) (xy 100.440028 -228.951026) (xy 100.489421 -228.967074)
			(xy 100.535695 -228.990652) (xy 100.577711 -229.021178) (xy 100.614434 -229.057901) (xy 100.64496 -229.099917)
			(xy 100.668538 -229.146191) (xy 100.684586 -229.195584) (xy 100.692711 -229.246879) (xy 100.69322 -229.272846)
			(xy 100.692711 -229.298813) (xy 100.972367 -229.298813) (xy 100.972367 -229.246879) (xy 100.980492 -229.195584)
			(xy 100.99654 -229.146191) (xy 101.020118 -229.099917) (xy 101.050644 -229.057901) (xy 101.087367 -229.021178)
			(xy 101.129383 -228.990652) (xy 101.175657 -228.967074) (xy 101.22505 -228.951026) (xy 101.276345 -228.942901)
			(xy 101.328279 -228.942901) (xy 101.379574 -228.951026) (xy 101.428967 -228.967074) (xy 101.475241 -228.990652)
			(xy 101.517257 -229.021178) (xy 101.55398 -229.057901) (xy 101.584506 -229.099917) (xy 101.608084 -229.146191)
			(xy 101.624132 -229.195584) (xy 101.632257 -229.246879) (xy 101.632766 -229.272846) (xy 101.632257 -229.298813)
			(xy 101.624132 -229.350108) (xy 101.608084 -229.399501) (xy 101.584506 -229.445775) (xy 101.55398 -229.487791)
			(xy 101.517257 -229.524514) (xy 101.475241 -229.55504) (xy 101.428967 -229.578618) (xy 101.379574 -229.594666)
			(xy 101.328279 -229.602791) (xy 101.276345 -229.602791) (xy 101.22505 -229.594666) (xy 101.175657 -229.578618)
			(xy 101.129383 -229.55504) (xy 101.087367 -229.524514) (xy 101.050644 -229.487791) (xy 101.020118 -229.445775)
			(xy 100.99654 -229.399501) (xy 100.980492 -229.350108) (xy 100.972367 -229.298813) (xy 100.692711 -229.298813)
			(xy 100.684586 -229.350108) (xy 100.668538 -229.399501) (xy 100.64496 -229.445775) (xy 100.614434 -229.487791)
			(xy 100.577711 -229.524514) (xy 100.535695 -229.55504) (xy 100.489421 -229.578618) (xy 100.440028 -229.594666)
			(xy 100.388733 -229.602791) (xy 100.336799 -229.602791) (xy 100.285504 -229.594666) (xy 100.236111 -229.578618)
			(xy 100.189837 -229.55504) (xy 100.147821 -229.524514) (xy 100.111098 -229.487791) (xy 100.080572 -229.445775)
			(xy 100.056994 -229.399501) (xy 100.040946 -229.350108) (xy 100.032821 -229.298813) (xy 99.75292 -229.298813)
			(xy 99.752907 -229.299501) (xy 99.744339 -229.352117) (xy 99.727432 -229.402674) (xy 99.702627 -229.449861)
			(xy 99.670565 -229.492451) (xy 99.63208 -229.52934) (xy 99.610418 -229.54488) (xy 99.598487 -229.553746)
			(xy 99.579933 -229.576954) (xy 99.568838 -229.604517) (xy 99.566138 -229.634106) (xy 99.572062 -229.663222)
			(xy 99.58611 -229.689404) (xy 99.596194 -229.700328) (xy 99.706684 -229.810818) (xy 99.739704 -229.793546)
			(xy 99.763452 -229.781766) (xy 99.813771 -229.7651) (xy 99.866108 -229.756692) (xy 99.892612 -229.756208)
			(xy 99.91858 -229.756718) (xy 99.969875 -229.764844) (xy 100.019269 -229.780893) (xy 100.065544 -229.804471)
			(xy 100.107561 -229.834997) (xy 100.144287 -229.871719) (xy 100.174816 -229.913734) (xy 100.198397 -229.960007)
			(xy 100.21445 -230.009399) (xy 100.22258 -230.060694) (xy 100.223066 -230.086662) (xy 100.222562 -230.113165)
			(xy 100.214152 -230.165499) (xy 100.197508 -230.215824) (xy 100.185728 -230.23957) (xy 100.168456 -230.27259)
			(xy 100.306886 -230.41102) (xy 100.462334 -230.41102) (xy 100.475754 -230.410581) (xy 100.501651 -230.403526)
			(xy 100.524815 -230.389966) (xy 100.543644 -230.370837) (xy 100.556838 -230.347462) (xy 100.563483 -230.321457)
			(xy 100.563122 -230.294618) (xy 100.555779 -230.268801) (xy 100.549202 -230.257096) (xy 100.534377 -230.231166)
			(xy 100.513313 -230.175281) (xy 100.502612 -230.116524) (xy 100.501958 -230.086662) (xy 100.502467 -230.060695)
			(xy 100.510592 -230.0094) (xy 100.52664 -229.960007) (xy 100.550218 -229.913733) (xy 100.580744 -229.871717)
			(xy 100.617467 -229.834994) (xy 100.659483 -229.804468) (xy 100.705757 -229.78089) (xy 100.75515 -229.764842)
			(xy 100.806445 -229.756717) (xy 100.858379 -229.756717) (xy 100.909674 -229.764842) (xy 100.959067 -229.78089)
			(xy 101.005341 -229.804468) (xy 101.047357 -229.834994) (xy 101.08408 -229.871717) (xy 101.114606 -229.913733)
			(xy 101.138184 -229.960007) (xy 101.154232 -230.0094) (xy 101.162357 -230.060695) (xy 101.162866 -230.086662)
			(xy 101.162331 -230.112629) (xy 101.442267 -230.112629) (xy 101.442267 -230.060695) (xy 101.450392 -230.0094)
			(xy 101.46644 -229.960007) (xy 101.490018 -229.913733) (xy 101.520544 -229.871717) (xy 101.557267 -229.834994)
			(xy 101.599283 -229.804468) (xy 101.645557 -229.78089) (xy 101.69495 -229.764842) (xy 101.746245 -229.756717)
			(xy 101.798179 -229.756717) (xy 101.849474 -229.764842) (xy 101.898867 -229.78089) (xy 101.945141 -229.804468)
			(xy 101.987157 -229.834994) (xy 102.02388 -229.871717) (xy 102.054406 -229.913733) (xy 102.077984 -229.960007)
			(xy 102.094032 -230.0094) (xy 102.102157 -230.060695) (xy 102.102666 -230.086662) (xy 102.102157 -230.112629)
			(xy 102.382067 -230.112629) (xy 102.382067 -230.060695) (xy 102.390192 -230.0094) (xy 102.40624 -229.960007)
			(xy 102.429818 -229.913733) (xy 102.460344 -229.871717) (xy 102.497067 -229.834994) (xy 102.539083 -229.804468)
			(xy 102.585357 -229.78089) (xy 102.63475 -229.764842) (xy 102.686045 -229.756717) (xy 102.737979 -229.756717)
			(xy 102.789274 -229.764842) (xy 102.838667 -229.78089) (xy 102.884941 -229.804468) (xy 102.926957 -229.834994)
			(xy 102.96368 -229.871717) (xy 102.994206 -229.913733) (xy 103.017784 -229.960007) (xy 103.033832 -230.0094)
			(xy 103.041957 -230.060695) (xy 103.042466 -230.086662) (xy 103.041957 -230.112629) (xy 103.033832 -230.163924)
			(xy 103.017784 -230.213317) (xy 102.994206 -230.259591) (xy 102.96368 -230.301607) (xy 102.926957 -230.33833)
			(xy 102.884941 -230.368856) (xy 102.838667 -230.392434) (xy 102.789274 -230.408482) (xy 102.737979 -230.416607)
			(xy 102.686045 -230.416607) (xy 102.63475 -230.408482) (xy 102.585357 -230.392434) (xy 102.539083 -230.368856)
			(xy 102.497067 -230.33833) (xy 102.460344 -230.301607) (xy 102.429818 -230.259591) (xy 102.40624 -230.213317)
			(xy 102.390192 -230.163924) (xy 102.382067 -230.112629) (xy 102.102157 -230.112629) (xy 102.094032 -230.163924)
			(xy 102.077984 -230.213317) (xy 102.054406 -230.259591) (xy 102.02388 -230.301607) (xy 101.987157 -230.33833)
			(xy 101.945141 -230.368856) (xy 101.898867 -230.392434) (xy 101.849474 -230.408482) (xy 101.798179 -230.416607)
			(xy 101.746245 -230.416607) (xy 101.69495 -230.408482) (xy 101.645557 -230.392434) (xy 101.599283 -230.368856)
			(xy 101.557267 -230.33833) (xy 101.520544 -230.301607) (xy 101.490018 -230.259591) (xy 101.46644 -230.213317)
			(xy 101.450392 -230.163924) (xy 101.442267 -230.112629) (xy 101.162331 -230.112629) (xy 101.162251 -230.116528)
			(xy 101.151563 -230.175294) (xy 101.130474 -230.231178) (xy 101.115622 -230.257096) (xy 101.109063 -230.268808)
			(xy 101.10172 -230.294619) (xy 101.101358 -230.321451) (xy 101.108002 -230.34745) (xy 101.121194 -230.370819)
			(xy 101.140021 -230.389941) (xy 101.163181 -230.403494) (xy 101.189074 -230.410543) (xy 101.20249 -230.41102)
			(xy 101.259386 -230.41102) (xy 101.456236 -230.60787) (xy 101.462332 -230.611172) (xy 101.484151 -230.623756)
			(xy 101.524043 -230.654506) (xy 101.558804 -230.690955) (xy 101.58763 -230.732258) (xy 101.609851 -230.777459)
			(xy 101.624954 -230.825509) (xy 101.632588 -230.875294) (xy 101.63302 -230.900478) (xy 101.6325 -230.926445)
			(xy 101.912421 -230.926445) (xy 101.912421 -230.874511) (xy 101.920546 -230.823216) (xy 101.936594 -230.773823)
			(xy 101.960172 -230.727549) (xy 101.990698 -230.685533) (xy 102.027421 -230.64881) (xy 102.069437 -230.618284)
			(xy 102.115711 -230.594706) (xy 102.165104 -230.578658) (xy 102.216399 -230.570533) (xy 102.268333 -230.570533)
			(xy 102.319628 -230.578658) (xy 102.369021 -230.594706) (xy 102.415295 -230.618284) (xy 102.457311 -230.64881)
			(xy 102.494034 -230.685533) (xy 102.52456 -230.727549) (xy 102.548138 -230.773823) (xy 102.564186 -230.823216)
			(xy 102.572311 -230.874511) (xy 102.57282 -230.900478) (xy 102.572311 -230.926445) (xy 102.852221 -230.926445)
			(xy 102.852221 -230.874511) (xy 102.860346 -230.823216) (xy 102.876394 -230.773823) (xy 102.899972 -230.727549)
			(xy 102.930498 -230.685533) (xy 102.967221 -230.64881) (xy 103.009237 -230.618284) (xy 103.055511 -230.594706)
			(xy 103.104904 -230.578658) (xy 103.156199 -230.570533) (xy 103.208133 -230.570533) (xy 103.259428 -230.578658)
			(xy 103.308821 -230.594706) (xy 103.355095 -230.618284) (xy 103.397111 -230.64881) (xy 103.433834 -230.685533)
			(xy 103.46436 -230.727549) (xy 103.487938 -230.773823) (xy 103.503986 -230.823216) (xy 103.512111 -230.874511)
			(xy 103.51262 -230.900478) (xy 103.512111 -230.926445) (xy 103.792021 -230.926445) (xy 103.792021 -230.874511)
			(xy 103.800146 -230.823216) (xy 103.816194 -230.773823) (xy 103.839772 -230.727549) (xy 103.870298 -230.685533)
			(xy 103.907021 -230.64881) (xy 103.949037 -230.618284) (xy 103.995311 -230.594706) (xy 104.044704 -230.578658)
			(xy 104.095999 -230.570533) (xy 104.147933 -230.570533) (xy 104.199228 -230.578658) (xy 104.248621 -230.594706)
			(xy 104.294895 -230.618284) (xy 104.336911 -230.64881) (xy 104.373634 -230.685533) (xy 104.40416 -230.727549)
			(xy 104.427738 -230.773823) (xy 104.443786 -230.823216) (xy 104.451911 -230.874511) (xy 104.45242 -230.900478)
			(xy 104.451911 -230.926445) (xy 104.443786 -230.97774) (xy 104.427738 -231.027133) (xy 104.40416 -231.073407)
			(xy 104.373634 -231.115423) (xy 104.336911 -231.152146) (xy 104.294895 -231.182672) (xy 104.248621 -231.20625)
			(xy 104.199228 -231.222298) (xy 104.147933 -231.230423) (xy 104.095999 -231.230423) (xy 104.044704 -231.222298)
			(xy 103.995311 -231.20625) (xy 103.949037 -231.182672) (xy 103.907021 -231.152146) (xy 103.870298 -231.115423)
			(xy 103.839772 -231.073407) (xy 103.816194 -231.027133) (xy 103.800146 -230.97774) (xy 103.792021 -230.926445)
			(xy 103.512111 -230.926445) (xy 103.503986 -230.97774) (xy 103.487938 -231.027133) (xy 103.46436 -231.073407)
			(xy 103.433834 -231.115423) (xy 103.397111 -231.152146) (xy 103.355095 -231.182672) (xy 103.308821 -231.20625)
			(xy 103.259428 -231.222298) (xy 103.208133 -231.230423) (xy 103.156199 -231.230423) (xy 103.104904 -231.222298)
			(xy 103.055511 -231.20625) (xy 103.009237 -231.182672) (xy 102.967221 -231.152146) (xy 102.930498 -231.115423)
			(xy 102.899972 -231.073407) (xy 102.876394 -231.027133) (xy 102.860346 -230.97774) (xy 102.852221 -230.926445)
			(xy 102.572311 -230.926445) (xy 102.564186 -230.97774) (xy 102.548138 -231.027133) (xy 102.52456 -231.073407)
			(xy 102.494034 -231.115423) (xy 102.457311 -231.152146) (xy 102.415295 -231.182672) (xy 102.369021 -231.20625)
			(xy 102.319628 -231.222298) (xy 102.268333 -231.230423) (xy 102.216399 -231.230423) (xy 102.165104 -231.222298)
			(xy 102.115711 -231.20625) (xy 102.069437 -231.182672) (xy 102.027421 -231.152146) (xy 101.990698 -231.115423)
			(xy 101.960172 -231.073407) (xy 101.936594 -231.027133) (xy 101.920546 -230.97774) (xy 101.912421 -230.926445)
			(xy 101.6325 -230.926445) (xy 101.632486 -230.927126) (xy 101.623943 -230.979734) (xy 101.607073 -231.03029)
			(xy 101.582314 -231.077486) (xy 101.566726 -231.099106) (xy 101.566726 -231.295194) (xy 101.567258 -231.310576)
			(xy 101.576419 -231.339943) (xy 101.593911 -231.365249) (xy 101.618147 -231.384197) (xy 101.646926 -231.395066)
			(xy 101.677637 -231.39687) (xy 101.69271 -231.393746) (xy 101.712272 -231.389216) (xy 101.752134 -231.384372)
			(xy 101.772212 -231.384094) (xy 101.798175 -231.384604) (xy 101.849461 -231.392729) (xy 101.898845 -231.408776)
			(xy 101.94511 -231.432351) (xy 101.987118 -231.462873) (xy 102.023835 -231.499591) (xy 102.054355 -231.5416)
			(xy 102.077929 -231.587866) (xy 102.093974 -231.637251) (xy 102.102097 -231.688537) (xy 102.102097 -231.740463)
			(xy 102.102089 -231.740515) (xy 102.382067 -231.740515) (xy 102.382067 -231.688581) (xy 102.390192 -231.637286)
			(xy 102.40624 -231.587893) (xy 102.429818 -231.541619) (xy 102.460344 -231.499603) (xy 102.497067 -231.46288)
			(xy 102.539083 -231.432354) (xy 102.585357 -231.408776) (xy 102.63475 -231.392728) (xy 102.686045 -231.384603)
			(xy 102.737979 -231.384603) (xy 102.789274 -231.392728) (xy 102.838667 -231.408776) (xy 102.884941 -231.432354)
			(xy 102.926957 -231.46288) (xy 102.96368 -231.499603) (xy 102.994206 -231.541619) (xy 103.017784 -231.587893)
			(xy 103.033832 -231.637286) (xy 103.041957 -231.688581) (xy 103.042466 -231.714548) (xy 103.041957 -231.740515)
			(xy 103.321867 -231.740515) (xy 103.321867 -231.688581) (xy 103.329992 -231.637286) (xy 103.34604 -231.587893)
			(xy 103.369618 -231.541619) (xy 103.400144 -231.499603) (xy 103.436867 -231.46288) (xy 103.478883 -231.432354)
			(xy 103.525157 -231.408776) (xy 103.57455 -231.392728) (xy 103.625845 -231.384603) (xy 103.677779 -231.384603)
			(xy 103.729074 -231.392728) (xy 103.778467 -231.408776) (xy 103.824741 -231.432354) (xy 103.866757 -231.46288)
			(xy 103.90348 -231.499603) (xy 103.934006 -231.541619) (xy 103.957584 -231.587893) (xy 103.973632 -231.637286)
			(xy 103.981757 -231.688581) (xy 103.982266 -231.714548) (xy 103.981757 -231.740515) (xy 103.973632 -231.79181)
			(xy 103.957584 -231.841203) (xy 103.934006 -231.887477) (xy 103.90348 -231.929493) (xy 103.866757 -231.966216)
			(xy 103.824741 -231.996742) (xy 103.778467 -232.02032) (xy 103.729074 -232.036368) (xy 103.677779 -232.044493)
			(xy 103.625845 -232.044493) (xy 103.57455 -232.036368) (xy 103.525157 -232.02032) (xy 103.478883 -231.996742)
			(xy 103.436867 -231.966216) (xy 103.400144 -231.929493) (xy 103.369618 -231.887477) (xy 103.34604 -231.841203)
			(xy 103.329992 -231.79181) (xy 103.321867 -231.740515) (xy 103.041957 -231.740515) (xy 103.033832 -231.79181)
			(xy 103.017784 -231.841203) (xy 102.994206 -231.887477) (xy 102.96368 -231.929493) (xy 102.926957 -231.966216)
			(xy 102.884941 -231.996742) (xy 102.838667 -232.02032) (xy 102.789274 -232.036368) (xy 102.737979 -232.044493)
			(xy 102.686045 -232.044493) (xy 102.63475 -232.036368) (xy 102.585357 -232.02032) (xy 102.539083 -231.996742)
			(xy 102.497067 -231.966216) (xy 102.460344 -231.929493) (xy 102.429818 -231.887477) (xy 102.40624 -231.841203)
			(xy 102.390192 -231.79181) (xy 102.382067 -231.740515) (xy 102.102089 -231.740515) (xy 102.093974 -231.791749)
			(xy 102.077929 -231.841134) (xy 102.054355 -231.8874) (xy 102.023835 -231.929409) (xy 101.987118 -231.966127)
			(xy 101.94511 -231.996649) (xy 101.898845 -232.020224) (xy 101.849461 -232.036271) (xy 101.798175 -232.044396)
			(xy 101.772212 -232.045002) (xy 101.752134 -232.044723) (xy 101.712271 -232.039886) (xy 101.69271 -232.03535)
			(xy 101.677647 -232.032169) (xy 101.64693 -232.033999) (xy 101.618148 -232.044884) (xy 101.593907 -232.063839)
			(xy 101.576403 -232.089147) (xy 101.56722 -232.118517) (xy 101.566726 -232.133902) (xy 101.566726 -232.554331)
			(xy 101.912421 -232.554331) (xy 101.912421 -232.502397) (xy 101.920546 -232.451102) (xy 101.936594 -232.401709)
			(xy 101.960172 -232.355435) (xy 101.990698 -232.313419) (xy 102.027421 -232.276696) (xy 102.069437 -232.24617)
			(xy 102.115711 -232.222592) (xy 102.165104 -232.206544) (xy 102.216399 -232.198419) (xy 102.268333 -232.198419)
			(xy 102.319628 -232.206544) (xy 102.369021 -232.222592) (xy 102.415295 -232.24617) (xy 102.457311 -232.276696)
			(xy 102.494034 -232.313419) (xy 102.52456 -232.355435) (xy 102.548138 -232.401709) (xy 102.564186 -232.451102)
			(xy 102.572311 -232.502397) (xy 102.57282 -232.528364) (xy 102.572311 -232.554331) (xy 102.852221 -232.554331)
			(xy 102.852221 -232.502397) (xy 102.860346 -232.451102) (xy 102.876394 -232.401709) (xy 102.899972 -232.355435)
			(xy 102.930498 -232.313419) (xy 102.967221 -232.276696) (xy 103.009237 -232.24617) (xy 103.055511 -232.222592)
			(xy 103.104904 -232.206544) (xy 103.156199 -232.198419) (xy 103.208133 -232.198419) (xy 103.259428 -232.206544)
			(xy 103.308821 -232.222592) (xy 103.355095 -232.24617) (xy 103.397111 -232.276696) (xy 103.433834 -232.313419)
			(xy 103.46436 -232.355435) (xy 103.487938 -232.401709) (xy 103.503986 -232.451102) (xy 103.512111 -232.502397)
			(xy 103.51262 -232.528364) (xy 103.512111 -232.554331) (xy 103.503986 -232.605626) (xy 103.487938 -232.655019)
			(xy 103.46436 -232.701293) (xy 103.433834 -232.743309) (xy 103.397111 -232.780032) (xy 103.355095 -232.810558)
			(xy 103.308821 -232.834136) (xy 103.259428 -232.850184) (xy 103.208133 -232.858309) (xy 103.156199 -232.858309)
			(xy 103.104904 -232.850184) (xy 103.055511 -232.834136) (xy 103.009237 -232.810558) (xy 102.967221 -232.780032)
			(xy 102.930498 -232.743309) (xy 102.899972 -232.701293) (xy 102.876394 -232.655019) (xy 102.860346 -232.605626)
			(xy 102.852221 -232.554331) (xy 102.572311 -232.554331) (xy 102.564186 -232.605626) (xy 102.548138 -232.655019)
			(xy 102.52456 -232.701293) (xy 102.494034 -232.743309) (xy 102.457311 -232.780032) (xy 102.415295 -232.810558)
			(xy 102.369021 -232.834136) (xy 102.319628 -232.850184) (xy 102.268333 -232.858309) (xy 102.216399 -232.858309)
			(xy 102.165104 -232.850184) (xy 102.115711 -232.834136) (xy 102.069437 -232.810558) (xy 102.027421 -232.780032)
			(xy 101.990698 -232.743309) (xy 101.960172 -232.701293) (xy 101.936594 -232.655019) (xy 101.920546 -232.605626)
			(xy 101.912421 -232.554331) (xy 101.566726 -232.554331) (xy 101.566726 -233.368147) (xy 102.382067 -233.368147)
			(xy 102.382067 -233.316213) (xy 102.390192 -233.264918) (xy 102.40624 -233.215525) (xy 102.429818 -233.169251)
			(xy 102.460344 -233.127235) (xy 102.497067 -233.090512) (xy 102.539083 -233.059986) (xy 102.585357 -233.036408)
			(xy 102.63475 -233.02036) (xy 102.686045 -233.012235) (xy 102.737979 -233.012235) (xy 102.789274 -233.02036)
			(xy 102.838667 -233.036408) (xy 102.884941 -233.059986) (xy 102.926957 -233.090512) (xy 102.96368 -233.127235)
			(xy 102.994206 -233.169251) (xy 103.017784 -233.215525) (xy 103.033832 -233.264918) (xy 103.041957 -233.316213)
			(xy 103.042466 -233.34218) (xy 103.041957 -233.368147) (xy 103.321867 -233.368147) (xy 103.321867 -233.316213)
			(xy 103.329992 -233.264918) (xy 103.34604 -233.215525) (xy 103.369618 -233.169251) (xy 103.400144 -233.127235)
			(xy 103.436867 -233.090512) (xy 103.478883 -233.059986) (xy 103.525157 -233.036408) (xy 103.57455 -233.02036)
			(xy 103.625845 -233.012235) (xy 103.677779 -233.012235) (xy 103.729074 -233.02036) (xy 103.778467 -233.036408)
			(xy 103.824741 -233.059986) (xy 103.866757 -233.090512) (xy 103.90348 -233.127235) (xy 103.934006 -233.169251)
			(xy 103.957584 -233.215525) (xy 103.973632 -233.264918) (xy 103.981757 -233.316213) (xy 103.982266 -233.34218)
			(xy 103.981757 -233.368147) (xy 103.973632 -233.419442) (xy 103.957584 -233.468835) (xy 103.934006 -233.515109)
			(xy 103.90348 -233.557125) (xy 103.866757 -233.593848) (xy 103.824741 -233.624374) (xy 103.778467 -233.647952)
			(xy 103.729074 -233.664) (xy 103.677779 -233.672125) (xy 103.625845 -233.672125) (xy 103.57455 -233.664)
			(xy 103.525157 -233.647952) (xy 103.478883 -233.624374) (xy 103.436867 -233.593848) (xy 103.400144 -233.557125)
			(xy 103.369618 -233.515109) (xy 103.34604 -233.468835) (xy 103.329992 -233.419442) (xy 103.321867 -233.368147)
			(xy 103.041957 -233.368147) (xy 103.033832 -233.419442) (xy 103.017784 -233.468835) (xy 102.994206 -233.515109)
			(xy 102.96368 -233.557125) (xy 102.926957 -233.593848) (xy 102.884941 -233.624374) (xy 102.838667 -233.647952)
			(xy 102.789274 -233.664) (xy 102.737979 -233.672125) (xy 102.686045 -233.672125) (xy 102.63475 -233.664)
			(xy 102.585357 -233.647952) (xy 102.539083 -233.624374) (xy 102.497067 -233.593848) (xy 102.460344 -233.557125)
			(xy 102.429818 -233.515109) (xy 102.40624 -233.468835) (xy 102.390192 -233.419442) (xy 102.382067 -233.368147)
			(xy 101.566726 -233.368147) (xy 101.566726 -233.95813) (xy 101.582243 -233.979709) (xy 101.606904 -234.026786)
			(xy 101.623706 -234.077206) (xy 101.632214 -234.129667) (xy 101.632207 -234.182217) (xy 101.912421 -234.182217)
			(xy 101.912421 -234.130283) (xy 101.920546 -234.078988) (xy 101.936594 -234.029595) (xy 101.960172 -233.983321)
			(xy 101.990698 -233.941305) (xy 102.027421 -233.904582) (xy 102.069437 -233.874056) (xy 102.115711 -233.850478)
			(xy 102.165104 -233.83443) (xy 102.216399 -233.826305) (xy 102.268333 -233.826305) (xy 102.319628 -233.83443)
			(xy 102.369021 -233.850478) (xy 102.415295 -233.874056) (xy 102.457311 -233.904582) (xy 102.494034 -233.941305)
			(xy 102.52456 -233.983321) (xy 102.548138 -234.029595) (xy 102.564186 -234.078988) (xy 102.572311 -234.130283)
			(xy 102.57282 -234.15625) (xy 102.572311 -234.182217) (xy 102.852221 -234.182217) (xy 102.852221 -234.130283)
			(xy 102.860346 -234.078988) (xy 102.876394 -234.029595) (xy 102.899972 -233.983321) (xy 102.930498 -233.941305)
			(xy 102.967221 -233.904582) (xy 103.009237 -233.874056) (xy 103.055511 -233.850478) (xy 103.104904 -233.83443)
			(xy 103.156199 -233.826305) (xy 103.208133 -233.826305) (xy 103.259428 -233.83443) (xy 103.308821 -233.850478)
			(xy 103.355095 -233.874056) (xy 103.397111 -233.904582) (xy 103.433834 -233.941305) (xy 103.46436 -233.983321)
			(xy 103.487938 -234.029595) (xy 103.503986 -234.078988) (xy 103.512111 -234.130283) (xy 103.51262 -234.15625)
			(xy 103.512111 -234.182217) (xy 103.503986 -234.233512) (xy 103.487938 -234.282905) (xy 103.46436 -234.329179)
			(xy 103.433834 -234.371195) (xy 103.397111 -234.407918) (xy 103.355095 -234.438444) (xy 103.308821 -234.462022)
			(xy 103.259428 -234.47807) (xy 103.208133 -234.486195) (xy 103.156199 -234.486195) (xy 103.104904 -234.47807)
			(xy 103.055511 -234.462022) (xy 103.009237 -234.438444) (xy 102.967221 -234.407918) (xy 102.930498 -234.371195)
			(xy 102.899972 -234.329179) (xy 102.876394 -234.282905) (xy 102.860346 -234.233512) (xy 102.852221 -234.182217)
			(xy 102.572311 -234.182217) (xy 102.564186 -234.233512) (xy 102.548138 -234.282905) (xy 102.52456 -234.329179)
			(xy 102.494034 -234.371195) (xy 102.457311 -234.407918) (xy 102.415295 -234.438444) (xy 102.369021 -234.462022)
			(xy 102.319628 -234.47807) (xy 102.268333 -234.486195) (xy 102.216399 -234.486195) (xy 102.165104 -234.47807)
			(xy 102.115711 -234.462022) (xy 102.069437 -234.438444) (xy 102.027421 -234.407918) (xy 101.990698 -234.371195)
			(xy 101.960172 -234.329179) (xy 101.936594 -234.282905) (xy 101.920546 -234.233512) (xy 101.912421 -234.182217)
			(xy 101.632207 -234.182217) (xy 101.632207 -234.182813) (xy 101.623687 -234.235271) (xy 101.606873 -234.285688)
			(xy 101.5822 -234.332759) (xy 101.566726 -234.35437) (xy 101.566726 -234.550712) (xy 101.567247 -234.566103)
			(xy 101.576394 -234.595492) (xy 101.593884 -234.62082) (xy 101.618127 -234.639786) (xy 101.646921 -234.650665)
			(xy 101.677648 -234.652468) (xy 101.69271 -234.649264) (xy 101.712272 -234.644735) (xy 101.752134 -234.639892)
			(xy 101.772212 -234.639612) (xy 101.79818 -234.640122) (xy 101.849475 -234.648248) (xy 101.898868 -234.664297)
			(xy 101.945143 -234.687875) (xy 101.98716 -234.718401) (xy 102.023885 -234.755123) (xy 102.054414 -234.797138)
			(xy 102.077995 -234.843411) (xy 102.094047 -234.892803) (xy 102.102176 -234.944098) (xy 102.102666 -234.970066)
			(xy 102.102285 -234.993702) (xy 102.095591 -235.040497) (xy 102.082291 -235.085859) (xy 102.062658 -235.128861)
			(xy 102.037092 -235.168623) (xy 102.021894 -235.186728) (xy 102.291896 -235.45673) (xy 102.307136 -235.459778)
			(xy 102.330894 -235.464962) (xy 102.376667 -235.481369) (xy 102.419543 -235.504306) (xy 102.458596 -235.533277)
			(xy 102.492983 -235.567658) (xy 102.521961 -235.606705) (xy 102.544906 -235.649577) (xy 102.561321 -235.695347)
			(xy 102.56647 -235.719112) (xy 102.569518 -235.734352) (xy 102.93477 -236.099604) (xy 102.949756 -236.102652)
			(xy 102.975978 -236.108661) (xy 103.026161 -236.128037) (xy 103.072536 -236.155296) (xy 103.113877 -236.189715)
			(xy 103.149087 -236.230384) (xy 103.163624 -236.25302) (xy 104.188006 -236.25302)
		)
		(stroke
			(width 0)
			(type solid)
		)
		(fill yes)
		(layer "In6.Cu")
		(net "P3V3_AUX")
	)
	(gr_poly
		(pts
			(xy 108.876338 -236.82071) (xy 108.889804 -236.820264) (xy 108.915784 -236.813159) (xy 108.939001 -236.799508)
			(xy 108.95784 -236.780259) (xy 108.97099 -236.756754) (xy 108.977535 -236.730627) (xy 108.977019 -236.703698)
			(xy 108.97362 -236.690662) (xy 108.967428 -236.667922) (xy 108.960798 -236.621263) (xy 108.960412 -236.597698)
			(xy 108.960921 -236.57173) (xy 108.969046 -236.520433) (xy 108.985094 -236.471039) (xy 109.008671 -236.424763)
			(xy 109.039197 -236.382744) (xy 109.07592 -236.346018) (xy 109.117935 -236.315488) (xy 109.164209 -236.291906)
			(xy 109.213602 -236.275853) (xy 109.264898 -236.267724) (xy 109.290866 -236.267244) (xy 109.316145 -236.26773)
			(xy 109.366112 -236.275444) (xy 109.414319 -236.290681) (xy 109.459642 -236.313085) (xy 109.501023 -236.342134)
			(xy 109.537493 -236.377149) (xy 109.568203 -236.417312) (xy 109.592435 -236.461685) (xy 109.609622 -236.509232)
			(xy 109.61497 -236.533944) (xy 109.618047 -236.547385) (xy 109.630354 -236.572046) (xy 109.648817 -236.59251)
			(xy 109.672086 -236.607282) (xy 109.698461 -236.615282) (xy 109.726015 -236.615927) (xy 109.752735 -236.609168)
			(xy 109.776669 -236.5955) (xy 109.786674 -236.586014) (xy 109.951774 -236.420914) (xy 109.953298 -236.418374)
			(xy 109.953298 -236.206284) (xy 109.952745 -236.191165) (xy 109.94389 -236.162253) (xy 109.92696 -236.137199)
			(xy 109.903439 -236.118197) (xy 109.875386 -236.106912) (xy 109.845259 -236.104331) (xy 109.830362 -236.10697)
			(xy 109.813233 -236.110413) (xy 109.77849 -236.114103) (xy 109.76102 -236.114336) (xy 109.735051 -236.113855)
			(xy 109.683752 -236.105733) (xy 109.634356 -236.089685) (xy 109.588078 -236.066108) (xy 109.546058 -236.035581)
			(xy 109.509332 -235.998857) (xy 109.478802 -235.956839) (xy 109.455222 -235.910563) (xy 109.439172 -235.861167)
			(xy 109.431047 -235.809869) (xy 109.431047 -235.757931) (xy 109.439172 -235.706633) (xy 109.455222 -235.657237)
			(xy 109.478802 -235.610961) (xy 109.509332 -235.568943) (xy 109.546058 -235.532219) (xy 109.588078 -235.501692)
			(xy 109.634356 -235.478115) (xy 109.683752 -235.462067) (xy 109.735051 -235.453945) (xy 109.76102 -235.453428)
			(xy 109.77849 -235.453653) (xy 109.813236 -235.457338) (xy 109.830362 -235.460794) (xy 109.845257 -235.463431)
			(xy 109.875381 -235.460851) (xy 109.903429 -235.449565) (xy 109.926945 -235.430563) (xy 109.943867 -235.405508)
			(xy 109.952712 -235.376597) (xy 109.953298 -235.36148) (xy 109.953298 -235.14939) (xy 109.940787 -235.129254)
			(xy 109.921034 -235.086161) (xy 109.907637 -235.040688) (xy 109.900871 -234.993769) (xy 109.900466 -234.970066)
			(xy 109.900978 -234.944101) (xy 109.909106 -234.892811) (xy 109.925158 -234.843425) (xy 109.948738 -234.797157)
			(xy 109.979265 -234.755147) (xy 110.015988 -234.71843) (xy 110.058003 -234.68791) (xy 110.104275 -234.664338)
			(xy 110.153664 -234.648294) (xy 110.204955 -234.640174) (xy 110.23092 -234.639612) (xy 110.252969 -234.639978)
			(xy 110.296675 -234.645842) (xy 110.318042 -234.651296) (xy 110.34649 -234.658916) (xy 110.469426 -234.53598)
			(xy 110.478624 -234.526224) (xy 110.492004 -234.502996) (xy 110.498862 -234.477083) (xy 110.498724 -234.450278)
			(xy 110.4916 -234.424437) (xy 110.477982 -234.401349) (xy 110.468664 -234.391708) (xy 110.450335 -234.37295)
			(xy 110.419255 -234.33071) (xy 110.395241 -234.284089) (xy 110.378897 -234.234259) (xy 110.370632 -234.182471)
			(xy 110.370112 -234.15625) (xy 110.370625 -234.130284) (xy 110.378755 -234.078993) (xy 110.394808 -234.029605)
			(xy 110.418388 -233.983336) (xy 110.448914 -233.941324) (xy 110.485636 -233.904604) (xy 110.52765 -233.874079)
			(xy 110.57392 -233.850502) (xy 110.623309 -233.834452) (xy 110.6746 -233.826324) (xy 110.700566 -233.825796)
			(xy 110.730921 -233.826512) (xy 110.790604 -233.83764) (xy 110.819184 -233.847894) (xy 110.832503 -233.852505)
			(xy 110.860567 -233.855002) (xy 110.888245 -233.849736) (xy 110.913431 -233.837108) (xy 110.934208 -233.818079)
			(xy 110.948995 -233.794096) (xy 110.956666 -233.766986) (xy 110.957106 -233.752898) (xy 110.957106 -233.594656)
			(xy 110.937442 -233.577423) (xy 110.903284 -233.537841) (xy 110.875789 -233.493371) (xy 110.855645 -233.445125)
			(xy 110.843354 -233.394307) (xy 110.839224 -233.342187) (xy 110.843358 -233.290068) (xy 110.855653 -233.239251)
			(xy 110.875801 -233.191006) (xy 110.903299 -233.146538) (xy 110.937461 -233.106959) (xy 110.957106 -233.089704)
			(xy 110.957106 -232.931716) (xy 110.956644 -232.91764) (xy 110.948942 -232.89056) (xy 110.934146 -232.866609)
			(xy 110.913377 -232.847601) (xy 110.888212 -232.83498) (xy 110.860558 -232.829701) (xy 110.832513 -232.832166)
			(xy 110.819184 -232.83672) (xy 110.790612 -232.847) (xy 110.730923 -232.858118) (xy 110.700566 -232.858818)
			(xy 110.674603 -232.858306) (xy 110.623318 -232.850179) (xy 110.573935 -232.834129) (xy 110.527671 -232.810552)
			(xy 110.485665 -232.780028) (xy 110.44895 -232.74331) (xy 110.41843 -232.7013) (xy 110.394858 -232.655033)
			(xy 110.378813 -232.605649) (xy 110.370691 -232.554363) (xy 110.370691 -232.502437) (xy 110.378813 -232.451151)
			(xy 110.394858 -232.401767) (xy 110.41843 -232.3555) (xy 110.44895 -232.31349) (xy 110.485665 -232.276772)
			(xy 110.527671 -232.246248) (xy 110.573935 -232.222671) (xy 110.623318 -232.206621) (xy 110.674603 -232.198494)
			(xy 110.700566 -232.19791) (xy 110.730921 -232.198626) (xy 110.790604 -232.209754) (xy 110.819184 -232.220008)
			(xy 110.832504 -232.224619) (xy 110.860568 -232.227115) (xy 110.888247 -232.221849) (xy 110.913435 -232.209221)
			(xy 110.934214 -232.190192) (xy 110.949003 -232.16621) (xy 110.956677 -232.1391) (xy 110.957106 -232.125012)
			(xy 110.957106 -231.967024) (xy 110.937437 -231.949791) (xy 110.903268 -231.910208) (xy 110.875762 -231.865734)
			(xy 110.855608 -231.817483) (xy 110.843309 -231.766659) (xy 110.839171 -231.714531) (xy 110.843299 -231.662403)
			(xy 110.855589 -231.611576) (xy 110.875734 -231.563321) (xy 110.903231 -231.518842) (xy 110.937393 -231.479252)
			(xy 110.957106 -231.462072) (xy 110.957106 -231.30383) (xy 110.956645 -231.289752) (xy 110.948946 -231.26267)
			(xy 110.93415 -231.238714) (xy 110.913381 -231.219704) (xy 110.888213 -231.20708) (xy 110.860557 -231.201801)
			(xy 110.832509 -231.204267) (xy 110.819184 -231.208834) (xy 110.790612 -231.219113) (xy 110.730923 -231.230231)
			(xy 110.700566 -231.230932) (xy 110.674602 -231.23042) (xy 110.623315 -231.222292) (xy 110.57393 -231.206242)
			(xy 110.527664 -231.182664) (xy 110.485655 -231.152139) (xy 110.448939 -231.115419) (xy 110.418418 -231.073407)
			(xy 110.394845 -231.027139) (xy 110.3788 -230.977752) (xy 110.370677 -230.926464) (xy 110.370677 -230.874536)
			(xy 110.3788 -230.823248) (xy 110.394845 -230.773861) (xy 110.418418 -230.727593) (xy 110.448939 -230.685581)
			(xy 110.485655 -230.648861) (xy 110.527664 -230.618336) (xy 110.57393 -230.594758) (xy 110.623315 -230.578708)
			(xy 110.674602 -230.57058) (xy 110.700566 -230.570024) (xy 110.730921 -230.57074) (xy 110.790604 -230.581869)
			(xy 110.819184 -230.592122) (xy 110.8325 -230.596735) (xy 110.860559 -230.599235) (xy 110.888232 -230.593969)
			(xy 110.913412 -230.581339) (xy 110.93418 -230.562307) (xy 110.948953 -230.538322) (xy 110.956608 -230.511212)
			(xy 110.957106 -230.497126) (xy 110.957106 -230.338884) (xy 110.937485 -230.321656) (xy 110.903404 -230.282099)
			(xy 110.875975 -230.237671) (xy 110.85588 -230.18948) (xy 110.843621 -230.138726) (xy 110.839503 -230.086675)
			(xy 110.843628 -230.034625) (xy 110.855895 -229.983874) (xy 110.875997 -229.935685) (xy 110.903433 -229.891261)
			(xy 110.93752 -229.851709) (xy 110.957106 -229.83444) (xy 110.957106 -229.676198) (xy 110.956641 -229.662124)
			(xy 110.948937 -229.635049) (xy 110.93414 -229.611102) (xy 110.913372 -229.592098) (xy 110.88821 -229.579479)
			(xy 110.860559 -229.574201) (xy 110.832517 -229.576665) (xy 110.819184 -229.581202) (xy 110.790611 -229.59148)
			(xy 110.730923 -229.602595) (xy 110.700566 -229.6033) (xy 110.674597 -229.602788) (xy 110.623299 -229.594658)
			(xy 110.573904 -229.578605) (xy 110.527628 -229.555022) (xy 110.485611 -229.524491) (xy 110.448887 -229.487763)
			(xy 110.41836 -229.445743) (xy 110.394782 -229.399465) (xy 110.378734 -229.350068) (xy 110.370609 -229.298769)
			(xy 110.370609 -229.246831) (xy 110.378734 -229.195532) (xy 110.394782 -229.146135) (xy 110.41836 -229.099857)
			(xy 110.448887 -229.057837) (xy 110.485611 -229.021109) (xy 110.527628 -228.990578) (xy 110.573904 -228.966995)
			(xy 110.623299 -228.950942) (xy 110.674597 -228.942812) (xy 110.700566 -228.942392) (xy 110.730921 -228.943108)
			(xy 110.790604 -228.954236) (xy 110.819184 -228.96449) (xy 110.832503 -228.969101) (xy 110.860566 -228.971599)
			(xy 110.888244 -228.966333) (xy 110.91343 -228.953704) (xy 110.934206 -228.934675) (xy 110.948993 -228.910692)
			(xy 110.956663 -228.883582) (xy 110.957106 -228.869494) (xy 110.957106 -228.711252) (xy 110.937479 -228.694024)
			(xy 110.903388 -228.654465) (xy 110.875949 -228.610034) (xy 110.855844 -228.561838) (xy 110.843576 -228.511078)
			(xy 110.839451 -228.459019) (xy 110.84357 -228.406961) (xy 110.855832 -228.356199) (xy 110.875931 -228.308001)
			(xy 110.903366 -228.263566) (xy 110.937452 -228.224003) (xy 110.957106 -228.206808) (xy 110.957106 -228.048312)
			(xy 110.956643 -228.034236) (xy 110.948941 -228.007158) (xy 110.934144 -227.983207) (xy 110.913376 -227.964201)
			(xy 110.888211 -227.95158) (xy 110.860558 -227.946301) (xy 110.832514 -227.948766) (xy 110.819184 -227.953316)
			(xy 110.790612 -227.963596) (xy 110.730923 -227.974714) (xy 110.700566 -227.975414) (xy 110.674604 -227.974902)
			(xy 110.623319 -227.966775) (xy 110.573937 -227.950725) (xy 110.527673 -227.927148) (xy 110.485667 -227.896625)
			(xy 110.448953 -227.859907) (xy 110.418434 -227.817898) (xy 110.394862 -227.771632) (xy 110.378817 -227.722248)
			(xy 110.370695 -227.670962) (xy 110.370695 -227.619038) (xy 110.378817 -227.567752) (xy 110.394862 -227.518368)
			(xy 110.418434 -227.472102) (xy 110.448953 -227.430093) (xy 110.485667 -227.393375) (xy 110.527673 -227.362852)
			(xy 110.573937 -227.339275) (xy 110.623319 -227.323225) (xy 110.674604 -227.315098) (xy 110.700566 -227.314506)
			(xy 110.730921 -227.315222) (xy 110.790604 -227.32635) (xy 110.819184 -227.336604) (xy 110.832503 -227.341215)
			(xy 110.860568 -227.343712) (xy 110.888247 -227.338446) (xy 110.913434 -227.325818) (xy 110.934212 -227.306788)
			(xy 110.949001 -227.282806) (xy 110.956674 -227.255696) (xy 110.957106 -227.241608) (xy 110.957106 -227.08362)
			(xy 110.937437 -227.066387) (xy 110.903269 -227.026804) (xy 110.875764 -226.982331) (xy 110.85561 -226.934079)
			(xy 110.843312 -226.883255) (xy 110.839174 -226.831128) (xy 110.843303 -226.779001) (xy 110.855593 -226.728175)
			(xy 110.875738 -226.67992) (xy 110.903235 -226.635442) (xy 110.937397 -226.595853) (xy 110.957106 -226.578668)
			(xy 110.957106 -226.42068) (xy 110.956652 -226.406597) (xy 110.94896 -226.379502) (xy 110.934167 -226.355534)
			(xy 110.913394 -226.336513) (xy 110.88822 -226.323882) (xy 110.860554 -226.318601) (xy 110.832496 -226.32107)
			(xy 110.819184 -226.325684) (xy 110.790611 -226.335962) (xy 110.730923 -226.347078) (xy 110.700566 -226.347782)
			(xy 110.674598 -226.34727) (xy 110.623303 -226.339141) (xy 110.573911 -226.323088) (xy 110.527638 -226.299506)
			(xy 110.485623 -226.268977) (xy 110.448901 -226.232251) (xy 110.418376 -226.190233) (xy 110.394799 -226.143958)
			(xy 110.378751 -226.094564) (xy 110.370627 -226.043268) (xy 110.370627 -225.991332) (xy 110.378751 -225.940036)
			(xy 110.394799 -225.890642) (xy 110.418376 -225.844367) (xy 110.448901 -225.802349) (xy 110.485623 -225.765623)
			(xy 110.527638 -225.735094) (xy 110.573911 -225.711512) (xy 110.623303 -225.695459) (xy 110.674598 -225.68733)
			(xy 110.700566 -225.686874) (xy 110.730921 -225.687589) (xy 110.790604 -225.698716) (xy 110.819184 -225.708972)
			(xy 110.832502 -225.713584) (xy 110.860564 -225.716082) (xy 110.888241 -225.710816) (xy 110.913425 -225.698187)
			(xy 110.934199 -225.679157) (xy 110.948982 -225.655173) (xy 110.956648 -225.628063) (xy 110.957106 -225.613976)
			(xy 110.957106 -225.455734) (xy 110.937444 -225.438501) (xy 110.903289 -225.39892) (xy 110.875798 -225.354451)
			(xy 110.855656 -225.306206) (xy 110.843368 -225.25539) (xy 110.839241 -225.203273) (xy 110.843377 -225.151156)
			(xy 110.855673 -225.100342) (xy 110.875822 -225.052101) (xy 110.903321 -225.007637) (xy 110.937483 -224.968061)
			(xy 110.957106 -224.950782) (xy 110.957106 -224.792794) (xy 110.956641 -224.77872) (xy 110.948936 -224.751646)
			(xy 110.934138 -224.7277) (xy 110.913371 -224.708697) (xy 110.888209 -224.696079) (xy 110.860559 -224.690801)
			(xy 110.832518 -224.693265) (xy 110.819184 -224.697798) (xy 110.790611 -224.708076) (xy 110.730923 -224.719191)
			(xy 110.700566 -224.719896) (xy 110.674599 -224.719384) (xy 110.623306 -224.711256) (xy 110.573915 -224.695205)
			(xy 110.527643 -224.671626) (xy 110.485628 -224.6411) (xy 110.448905 -224.604378) (xy 110.418378 -224.562364)
			(xy 110.394798 -224.516092) (xy 110.378746 -224.466702) (xy 110.370616 -224.415409) (xy 110.370112 -224.389442)
			(xy 110.370585 -224.363995) (xy 110.378393 -224.313704) (xy 110.393817 -224.265204) (xy 110.416492 -224.219641)
			(xy 110.445881 -224.178091) (xy 110.481291 -224.141535) (xy 110.521886 -224.110839) (xy 110.566705 -224.086727)
			(xy 110.614689 -224.069768) (xy 110.639606 -224.064576) (xy 110.662466 -224.060258) (xy 110.866174 -223.707198)
			(xy 110.858554 -223.685354) (xy 110.849757 -223.65878) (xy 110.840301 -223.603612) (xy 110.839758 -223.575626)
			(xy 110.84019 -223.551667) (xy 110.847124 -223.504253) (xy 110.860836 -223.458338) (xy 110.881037 -223.414887)
			(xy 110.907305 -223.37481) (xy 110.939088 -223.338948) (xy 110.957106 -223.32315) (xy 110.957106 -223.164908)
			(xy 110.956643 -223.150833) (xy 110.94894 -223.123755) (xy 110.934143 -223.099806) (xy 110.913375 -223.0808)
			(xy 110.888211 -223.068179) (xy 110.860558 -223.062901) (xy 110.832515 -223.065365) (xy 110.819184 -223.069912)
			(xy 110.790612 -223.080192) (xy 110.730923 -223.09131) (xy 110.700566 -223.09201) (xy 110.6746 -223.091525)
			(xy 110.623307 -223.083395) (xy 110.573918 -223.067342) (xy 110.527648 -223.04376) (xy 110.485637 -223.013229)
			(xy 110.44892 -222.976503) (xy 110.4184 -222.934485) (xy 110.394828 -222.88821) (xy 110.378787 -222.838817)
			(xy 110.370669 -222.787522) (xy 110.370112 -222.761556) (xy 110.370594 -222.735264) (xy 110.378874 -222.683337)
			(xy 110.395282 -222.633379) (xy 110.419403 -222.586654) (xy 110.434628 -222.565214) (xy 110.442575 -222.553666)
			(xy 110.452424 -222.527431) (xy 110.45477 -222.499506) (xy 110.449437 -222.471995) (xy 110.436827 -222.44697)
			(xy 110.417889 -222.426315) (xy 110.39405 -222.411585) (xy 110.367104 -222.403889) (xy 110.353094 -222.403416)
			(xy 110.108238 -222.403416) (xy 110.094226 -222.403896) (xy 110.067275 -222.411585) (xy 110.04343 -222.426312)
			(xy 110.024488 -222.446968) (xy 110.011874 -222.471996) (xy 110.006541 -222.49951) (xy 110.008889 -222.527437)
			(xy 110.018742 -222.553675) (xy 110.026704 -222.565214) (xy 110.041894 -222.586676) (xy 110.066002 -222.633401)
			(xy 110.082417 -222.68335) (xy 110.090724 -222.735267) (xy 110.09122 -222.761556) (xy 110.090711 -222.787523)
			(xy 110.082586 -222.838818) (xy 110.066538 -222.888211) (xy 110.04296 -222.934485) (xy 110.012434 -222.976501)
			(xy 109.975711 -223.013224) (xy 109.933695 -223.04375) (xy 109.887421 -223.067328) (xy 109.838028 -223.083376)
			(xy 109.786733 -223.091501) (xy 109.734799 -223.091501) (xy 109.683504 -223.083376) (xy 109.634111 -223.067328)
			(xy 109.587837 -223.04375) (xy 109.545821 -223.013224) (xy 109.509098 -222.976501) (xy 109.478572 -222.934485)
			(xy 109.454994 -222.888211) (xy 109.438946 -222.838818) (xy 109.430821 -222.787523) (xy 109.430312 -222.761556)
			(xy 109.430794 -222.735264) (xy 109.439074 -222.683337) (xy 109.455482 -222.633379) (xy 109.479603 -222.586654)
			(xy 109.494828 -222.565214) (xy 109.502775 -222.553666) (xy 109.512624 -222.527431) (xy 109.51497 -222.499506)
			(xy 109.509637 -222.471995) (xy 109.497027 -222.44697) (xy 109.478089 -222.426315) (xy 109.45425 -222.411585)
			(xy 109.427304 -222.403889) (xy 109.413294 -222.403416) (xy 109.168438 -222.403416) (xy 109.154426 -222.403896)
			(xy 109.127475 -222.411585) (xy 109.10363 -222.426312) (xy 109.084688 -222.446968) (xy 109.072074 -222.471996)
			(xy 109.066741 -222.49951) (xy 109.069089 -222.527437) (xy 109.078942 -222.553675) (xy 109.086904 -222.565214)
			(xy 109.102094 -222.586676) (xy 109.126202 -222.633401) (xy 109.142617 -222.68335) (xy 109.150924 -222.735267)
			(xy 109.15142 -222.761556) (xy 109.150911 -222.787523) (xy 109.142786 -222.838818) (xy 109.126738 -222.888211)
			(xy 109.10316 -222.934485) (xy 109.072634 -222.976501) (xy 109.035911 -223.013224) (xy 108.993895 -223.04375)
			(xy 108.947621 -223.067328) (xy 108.898228 -223.083376) (xy 108.846933 -223.091501) (xy 108.794999 -223.091501)
			(xy 108.743704 -223.083376) (xy 108.694311 -223.067328) (xy 108.648037 -223.04375) (xy 108.606021 -223.013224)
			(xy 108.569298 -222.976501) (xy 108.538772 -222.934485) (xy 108.515194 -222.888211) (xy 108.499146 -222.838818)
			(xy 108.491021 -222.787523) (xy 108.490512 -222.761556) (xy 108.490994 -222.735264) (xy 108.499274 -222.683337)
			(xy 108.515682 -222.633379) (xy 108.539803 -222.586654) (xy 108.555028 -222.565214) (xy 108.562975 -222.553666)
			(xy 108.572824 -222.527431) (xy 108.57517 -222.499506) (xy 108.569837 -222.471995) (xy 108.557227 -222.44697)
			(xy 108.538289 -222.426315) (xy 108.51445 -222.411585) (xy 108.487504 -222.403889) (xy 108.473494 -222.403416)
			(xy 108.228638 -222.403416) (xy 108.214626 -222.403896) (xy 108.187675 -222.411585) (xy 108.16383 -222.426312)
			(xy 108.144888 -222.446968) (xy 108.132274 -222.471996) (xy 108.126941 -222.49951) (xy 108.129289 -222.527437)
			(xy 108.139142 -222.553675) (xy 108.147104 -222.565214) (xy 108.162294 -222.586676) (xy 108.186402 -222.633401)
			(xy 108.202817 -222.68335) (xy 108.211124 -222.735267) (xy 108.21162 -222.761556) (xy 108.211111 -222.787523)
			(xy 108.202986 -222.838818) (xy 108.186938 -222.888211) (xy 108.16336 -222.934485) (xy 108.132834 -222.976501)
			(xy 108.096111 -223.013224) (xy 108.054095 -223.04375) (xy 108.007821 -223.067328) (xy 107.958428 -223.083376)
			(xy 107.907133 -223.091501) (xy 107.855199 -223.091501) (xy 107.803904 -223.083376) (xy 107.754511 -223.067328)
			(xy 107.708237 -223.04375) (xy 107.666221 -223.013224) (xy 107.629498 -222.976501) (xy 107.598972 -222.934485)
			(xy 107.575394 -222.888211) (xy 107.559346 -222.838818) (xy 107.551221 -222.787523) (xy 107.550712 -222.761556)
			(xy 107.551194 -222.735264) (xy 107.559474 -222.683337) (xy 107.575882 -222.633379) (xy 107.600003 -222.586654)
			(xy 107.615228 -222.565214) (xy 107.623175 -222.553666) (xy 107.633024 -222.527431) (xy 107.63537 -222.499506)
			(xy 107.630037 -222.471995) (xy 107.617427 -222.44697) (xy 107.598489 -222.426315) (xy 107.57465 -222.411585)
			(xy 107.547704 -222.403889) (xy 107.533694 -222.403416) (xy 107.288838 -222.403416) (xy 107.274826 -222.403896)
			(xy 107.247875 -222.411585) (xy 107.22403 -222.426312) (xy 107.205088 -222.446968) (xy 107.192474 -222.471996)
			(xy 107.187141 -222.49951) (xy 107.189489 -222.527437) (xy 107.199342 -222.553675) (xy 107.207304 -222.565214)
			(xy 107.222494 -222.586676) (xy 107.246602 -222.633401) (xy 107.263017 -222.68335) (xy 107.271324 -222.735267)
			(xy 107.27182 -222.761556) (xy 107.271311 -222.787523) (xy 107.263186 -222.838818) (xy 107.247138 -222.888211)
			(xy 107.22356 -222.934485) (xy 107.193034 -222.976501) (xy 107.156311 -223.013224) (xy 107.114295 -223.04375)
			(xy 107.068021 -223.067328) (xy 107.018628 -223.083376) (xy 106.967333 -223.091501) (xy 106.915399 -223.091501)
			(xy 106.864104 -223.083376) (xy 106.814711 -223.067328) (xy 106.768437 -223.04375) (xy 106.726421 -223.013224)
			(xy 106.689698 -222.976501) (xy 106.659172 -222.934485) (xy 106.635594 -222.888211) (xy 106.619546 -222.838818)
			(xy 106.611421 -222.787523) (xy 106.610912 -222.761556) (xy 106.611394 -222.735264) (xy 106.619674 -222.683337)
			(xy 106.636082 -222.633379) (xy 106.660203 -222.586654) (xy 106.675428 -222.565214) (xy 106.683375 -222.553666)
			(xy 106.693224 -222.527431) (xy 106.69557 -222.499506) (xy 106.690237 -222.471995) (xy 106.677627 -222.44697)
			(xy 106.658689 -222.426315) (xy 106.63485 -222.411585) (xy 106.607904 -222.403889) (xy 106.593894 -222.403416)
			(xy 106.349038 -222.403416) (xy 106.335026 -222.403896) (xy 106.308075 -222.411585) (xy 106.28423 -222.426312)
			(xy 106.265288 -222.446968) (xy 106.252674 -222.471996) (xy 106.247341 -222.49951) (xy 106.249689 -222.527437)
			(xy 106.259542 -222.553675) (xy 106.267504 -222.565214) (xy 106.282694 -222.586676) (xy 106.306802 -222.633401)
			(xy 106.323217 -222.68335) (xy 106.331524 -222.735267) (xy 106.33202 -222.761556) (xy 106.331511 -222.787523)
			(xy 106.323386 -222.838818) (xy 106.307338 -222.888211) (xy 106.28376 -222.934485) (xy 106.253234 -222.976501)
			(xy 106.216511 -223.013224) (xy 106.174495 -223.04375) (xy 106.128221 -223.067328) (xy 106.078828 -223.083376)
			(xy 106.027533 -223.091501) (xy 105.975599 -223.091501) (xy 105.924304 -223.083376) (xy 105.874911 -223.067328)
			(xy 105.828637 -223.04375) (xy 105.786621 -223.013224) (xy 105.749898 -222.976501) (xy 105.719372 -222.934485)
			(xy 105.695794 -222.888211) (xy 105.679746 -222.838818) (xy 105.671621 -222.787523) (xy 105.671112 -222.761556)
			(xy 105.671594 -222.735264) (xy 105.679874 -222.683337) (xy 105.696282 -222.633379) (xy 105.720403 -222.586654)
			(xy 105.735628 -222.565214) (xy 105.743575 -222.553666) (xy 105.753424 -222.527431) (xy 105.75577 -222.499506)
			(xy 105.750437 -222.471995) (xy 105.737827 -222.44697) (xy 105.718889 -222.426315) (xy 105.69505 -222.411585)
			(xy 105.668104 -222.403889) (xy 105.654094 -222.403416) (xy 105.409238 -222.403416) (xy 105.395226 -222.403896)
			(xy 105.368275 -222.411585) (xy 105.34443 -222.426312) (xy 105.325488 -222.446968) (xy 105.312874 -222.471996)
			(xy 105.307541 -222.49951) (xy 105.309889 -222.527437) (xy 105.319742 -222.553675) (xy 105.327704 -222.565214)
			(xy 105.342894 -222.586676) (xy 105.367002 -222.633401) (xy 105.383417 -222.68335) (xy 105.391724 -222.735267)
			(xy 105.39222 -222.761556) (xy 105.391711 -222.787523) (xy 105.383586 -222.838818) (xy 105.367538 -222.888211)
			(xy 105.34396 -222.934485) (xy 105.313434 -222.976501) (xy 105.276711 -223.013224) (xy 105.234695 -223.04375)
			(xy 105.188421 -223.067328) (xy 105.139028 -223.083376) (xy 105.087733 -223.091501) (xy 105.035799 -223.091501)
			(xy 104.984504 -223.083376) (xy 104.935111 -223.067328) (xy 104.888837 -223.04375) (xy 104.846821 -223.013224)
			(xy 104.810098 -222.976501) (xy 104.779572 -222.934485) (xy 104.755994 -222.888211) (xy 104.739946 -222.838818)
			(xy 104.731821 -222.787523) (xy 104.731312 -222.761556) (xy 104.731794 -222.735264) (xy 104.740074 -222.683337)
			(xy 104.756482 -222.633379) (xy 104.780603 -222.586654) (xy 104.795828 -222.565214) (xy 104.803775 -222.553666)
			(xy 104.813624 -222.527431) (xy 104.81597 -222.499506) (xy 104.810637 -222.471995) (xy 104.798027 -222.44697)
			(xy 104.779089 -222.426315) (xy 104.75525 -222.411585) (xy 104.728304 -222.403889) (xy 104.714294 -222.403416)
			(xy 104.40543 -222.403416) (xy 104.096312 -222.094298) (xy 104.086625 -222.085206) (xy 104.063644 -222.071899)
			(xy 104.038005 -222.064981) (xy 104.011449 -222.064921) (xy 103.985779 -222.071724) (xy 103.962738 -222.084928)
			(xy 103.94389 -222.103636) (xy 103.9368 -222.114872) (xy 103.923996 -222.135843) (xy 103.893157 -222.174093)
			(xy 103.856987 -222.207348) (xy 103.816287 -222.234874) (xy 103.771956 -222.256061) (xy 103.724974 -222.270442)
			(xy 103.676379 -222.277698) (xy 103.651812 -222.278194) (xy 103.625843 -222.277686) (xy 103.574544 -222.269563)
			(xy 103.525147 -222.253516) (xy 103.478869 -222.22994) (xy 103.436848 -222.199414) (xy 103.40012 -222.162691)
			(xy 103.369588 -222.120675) (xy 103.346004 -222.074401) (xy 103.329949 -222.025006) (xy 103.321818 -221.973709)
			(xy 103.321358 -221.94774) (xy 103.321812 -221.923173) (xy 103.329096 -221.874582) (xy 103.343495 -221.827606)
			(xy 103.364692 -221.783279) (xy 103.392218 -221.742579) (xy 103.425467 -221.706404) (xy 103.463706 -221.675552)
			(xy 103.48468 -221.662752) (xy 103.497771 -221.654439) (xy 103.518586 -221.631474) (xy 103.531573 -221.603332)
			(xy 103.535544 -221.572592) (xy 103.530132 -221.542074) (xy 103.515836 -221.514573) (xy 103.505254 -221.50324)
			(xy 103.39324 -221.391226) (xy 103.35895 -221.41307) (xy 103.33903 -221.425219) (xy 103.296498 -221.444399)
			(xy 103.251688 -221.457401) (xy 103.205495 -221.463965) (xy 103.182166 -221.464378) (xy 103.1562 -221.463866)
			(xy 103.104908 -221.455738) (xy 103.055518 -221.439686) (xy 103.009247 -221.416107) (xy 102.967234 -221.385581)
			(xy 102.930513 -221.348859) (xy 102.899987 -221.306844) (xy 102.87641 -221.260573) (xy 102.86036 -221.211183)
			(xy 102.852233 -221.15989) (xy 102.851712 -221.133924) (xy 102.852321 -221.105565) (xy 102.862048 -221.049687)
			(xy 102.881168 -220.996288) (xy 102.909121 -220.946936) (xy 102.926642 -220.924628) (xy 102.645972 -220.643958)
			(xy 102.632256 -220.640402) (xy 102.607597 -220.633752) (xy 102.560541 -220.613899) (xy 102.517103 -220.587041)
			(xy 102.478315 -220.553817) (xy 102.445102 -220.515019) (xy 102.418256 -220.471572) (xy 102.398417 -220.424511)
			(xy 102.391718 -220.399864) (xy 102.388162 -220.386148) (xy 102.275386 -220.273372) (xy 102.264719 -220.26336)
			(xy 102.239044 -220.249361) (xy 102.210454 -220.243213) (xy 102.181294 -220.24542) (xy 102.153954 -220.2558)
			(xy 102.130678 -220.273502) (xy 102.113372 -220.297076) (xy 102.103457 -220.324587) (xy 102.102158 -220.339158)
			(xy 102.100296 -220.363464) (xy 102.090324 -220.411181) (xy 102.073452 -220.456915) (xy 102.050046 -220.499675)
			(xy 102.020613 -220.538534) (xy 101.985792 -220.572648) (xy 101.946337 -220.601278) (xy 101.903106 -220.623802)
			(xy 101.857035 -220.639732) (xy 101.833172 -220.64472) (xy 101.810312 -220.649038) (xy 101.606604 -221.002098)
			(xy 101.614224 -221.024196) (xy 101.623015 -221.050771) (xy 101.63246 -221.105938) (xy 101.63302 -221.133924)
			(xy 101.911912 -221.133924) (xy 101.912421 -221.107957) (xy 101.920546 -221.056662) (xy 101.936594 -221.007269)
			(xy 101.960172 -220.960995) (xy 101.990698 -220.918979) (xy 102.027421 -220.882256) (xy 102.069437 -220.85173)
			(xy 102.115711 -220.828152) (xy 102.165104 -220.812104) (xy 102.216399 -220.803979) (xy 102.268333 -220.803979)
			(xy 102.319628 -220.812104) (xy 102.369021 -220.828152) (xy 102.415295 -220.85173) (xy 102.457311 -220.882256)
			(xy 102.494034 -220.918979) (xy 102.52456 -220.960995) (xy 102.548138 -221.007269) (xy 102.564186 -221.056662)
			(xy 102.572311 -221.107957) (xy 102.57282 -221.133924) (xy 102.572272 -221.16191) (xy 102.562819 -221.217078)
			(xy 102.554024 -221.243652) (xy 102.546404 -221.26575) (xy 102.750112 -221.618556) (xy 102.772972 -221.622874)
			(xy 102.7979 -221.628011) (xy 102.845885 -221.644981) (xy 102.890703 -221.669103) (xy 102.931295 -221.699808)
			(xy 102.966703 -221.736369) (xy 102.99609 -221.777925) (xy 103.018763 -221.823493) (xy 103.034185 -221.871997)
			(xy 103.041993 -221.922292) (xy 103.042466 -221.94774) (xy 103.041957 -221.973707) (xy 103.033832 -222.025002)
			(xy 103.017784 -222.074395) (xy 102.994206 -222.120669) (xy 102.96368 -222.162685) (xy 102.926957 -222.199408)
			(xy 102.884941 -222.229934) (xy 102.838667 -222.253512) (xy 102.789274 -222.26956) (xy 102.737979 -222.277685)
			(xy 102.686045 -222.277685) (xy 102.63475 -222.26956) (xy 102.585357 -222.253512) (xy 102.539083 -222.229934)
			(xy 102.497067 -222.199408) (xy 102.460344 -222.162685) (xy 102.429818 -222.120669) (xy 102.40624 -222.074395)
			(xy 102.390192 -222.025002) (xy 102.382067 -221.973707) (xy 102.381558 -221.94774) (xy 102.382118 -221.919754)
			(xy 102.391563 -221.864587) (xy 102.400354 -221.838012) (xy 102.407974 -221.815914) (xy 102.204266 -221.463108)
			(xy 102.181406 -221.45879) (xy 102.156482 -221.45363) (xy 102.108495 -221.436669) (xy 102.063674 -221.412553)
			(xy 102.023079 -221.381853) (xy 101.987668 -221.345294) (xy 101.95828 -221.303739) (xy 101.935607 -221.258171)
			(xy 101.920187 -221.209667) (xy 101.912382 -221.159372) (xy 101.911912 -221.133924) (xy 101.63302 -221.133924)
			(xy 101.632511 -221.159891) (xy 101.624386 -221.211186) (xy 101.608338 -221.260579) (xy 101.58476 -221.306853)
			(xy 101.554234 -221.348869) (xy 101.517511 -221.385592) (xy 101.475495 -221.416118) (xy 101.429221 -221.439696)
			(xy 101.379828 -221.455744) (xy 101.328533 -221.463869) (xy 101.276599 -221.463869) (xy 101.225304 -221.455744)
			(xy 101.175911 -221.439696) (xy 101.129637 -221.416118) (xy 101.087621 -221.385592) (xy 101.050898 -221.348869)
			(xy 101.020372 -221.306853) (xy 100.996794 -221.260579) (xy 100.980746 -221.211186) (xy 100.972621 -221.159891)
			(xy 100.972112 -221.133924) (xy 100.972586 -221.108478) (xy 100.980397 -221.058189) (xy 100.995822 -221.009691)
			(xy 101.018498 -220.96413) (xy 101.047888 -220.922582) (xy 101.083298 -220.886029) (xy 101.123892 -220.855335)
			(xy 101.16871 -220.831224) (xy 101.216693 -220.814267) (xy 101.241606 -220.809058) (xy 101.264466 -220.80474)
			(xy 101.468174 -220.45168) (xy 101.460554 -220.429582) (xy 101.451763 -220.403007) (xy 101.442319 -220.347839)
			(xy 101.441758 -220.319854) (xy 101.44222 -220.294853) (xy 101.449759 -220.245422) (xy 101.464656 -220.19769)
			(xy 101.486573 -220.152747) (xy 101.51501 -220.111618) (xy 101.549317 -220.07524) (xy 101.588711 -220.044446)
			(xy 101.632295 -220.019936) (xy 101.679073 -220.00227) (xy 101.727978 -219.991852) (xy 101.752908 -219.989908)
			(xy 101.76745 -219.988543) (xy 101.794896 -219.97859) (xy 101.818408 -219.961281) (xy 101.836064 -219.93803)
			(xy 101.846423 -219.910734) (xy 101.84864 -219.881623) (xy 101.842533 -219.853073) (xy 101.828601 -219.827416)
			(xy 101.818694 -219.81668) (xy 101.707442 -219.705428) (xy 101.566218 -219.705428) (xy 101.550486 -219.725429)
			(xy 101.513916 -219.76081) (xy 101.472357 -219.790171) (xy 101.426791 -219.81282) (xy 101.378293 -219.82822)
			(xy 101.328008 -219.83601) (xy 101.302566 -219.836492) (xy 101.276599 -219.83598) (xy 101.225306 -219.827852)
			(xy 101.175916 -219.811801) (xy 101.129644 -219.788222) (xy 101.08763 -219.757696) (xy 101.050907 -219.720974)
			(xy 101.02038 -219.67896) (xy 100.996801 -219.632688) (xy 100.980749 -219.583298) (xy 100.97262 -219.532005)
			(xy 100.972112 -219.506038) (xy 100.972663 -219.478824) (xy 100.981575 -219.42513) (xy 100.999164 -219.373623)
			(xy 101.024955 -219.325694) (xy 101.058251 -219.282638) (xy 101.098152 -219.24562) (xy 101.143578 -219.215639)
			(xy 101.1682 -219.204032) (xy 101.198172 -219.190824) (xy 101.198172 -219.034106) (xy 101.197707 -219.019941)
			(xy 101.189924 -218.992701) (xy 101.174954 -218.968649) (xy 101.153951 -218.949637) (xy 101.128532 -218.937128)
			(xy 101.100654 -218.932087) (xy 101.072464 -218.9349) (xy 101.046132 -218.945352) (xy 101.034596 -218.953588)
			(xy 101.012734 -218.969802) (xy 100.964813 -218.995604) (xy 100.913313 -219.01321) (xy 100.859625 -219.022142)
			(xy 100.832412 -219.022676) (xy 100.806444 -219.022168) (xy 100.755146 -219.014045) (xy 100.70575 -218.997998)
			(xy 100.659473 -218.974421) (xy 100.617454 -218.943895) (xy 100.580727 -218.907172) (xy 100.550197 -218.865156)
			(xy 100.526615 -218.818881) (xy 100.510563 -218.769487) (xy 100.502435 -218.71819) (xy 100.501958 -218.692222)
			(xy 100.50257 -218.664242) (xy 100.512019 -218.609083) (xy 100.520754 -218.582494) (xy 100.528374 -218.560396)
			(xy 100.324666 -218.20759) (xy 100.301806 -218.203272) (xy 100.276879 -218.198119) (xy 100.228884 -218.181174)
			(xy 100.184056 -218.157067) (xy 100.143456 -218.126369) (xy 100.108045 -218.089807) (xy 100.078662 -218.048246)
			(xy 100.056001 -218.00267) (xy 100.0406 -217.954157) (xy 100.032822 -217.903856) (xy 100.032312 -217.878406)
			(xy 100.032821 -217.852439) (xy 100.040946 -217.801144) (xy 100.056994 -217.751751) (xy 100.080572 -217.705477)
			(xy 100.111098 -217.663461) (xy 100.147821 -217.626738) (xy 100.189837 -217.596212) (xy 100.236111 -217.572634)
			(xy 100.285504 -217.556586) (xy 100.336799 -217.548461) (xy 100.388733 -217.548461) (xy 100.440028 -217.556586)
			(xy 100.489421 -217.572634) (xy 100.535695 -217.596212) (xy 100.577711 -217.626738) (xy 100.614434 -217.663461)
			(xy 100.64496 -217.705477) (xy 100.668538 -217.751751) (xy 100.684586 -217.801144) (xy 100.692711 -217.852439)
			(xy 100.69322 -217.878406) (xy 100.692606 -217.906386) (xy 100.683154 -217.961544) (xy 100.674424 -217.988134)
			(xy 100.666804 -218.010232) (xy 100.870512 -218.363038) (xy 100.893372 -218.367356) (xy 100.918895 -218.372665)
			(xy 100.967972 -218.390236) (xy 101.013686 -218.415289) (xy 101.034596 -218.430856) (xy 101.04611 -218.439132)
			(xy 101.072457 -218.449584) (xy 101.100662 -218.452397) (xy 101.128554 -218.447353) (xy 101.153987 -218.43484)
			(xy 101.175004 -218.415822) (xy 101.189988 -218.391761) (xy 101.197785 -218.36451) (xy 101.198172 -218.350338)
			(xy 101.198172 -218.19362) (xy 101.1682 -218.180412) (xy 101.145191 -218.169649) (xy 101.102503 -218.142119)
			(xy 101.064527 -218.108384) (xy 101.032157 -218.069238) (xy 101.006155 -218.025602) (xy 100.987132 -217.978503)
			(xy 100.975537 -217.929048) (xy 100.971641 -217.878402) (xy 100.975536 -217.827756) (xy 100.987131 -217.778302)
			(xy 101.006153 -217.731202) (xy 101.032154 -217.687566) (xy 101.064524 -217.64842) (xy 101.102499 -217.614684)
			(xy 101.145187 -217.587153) (xy 101.1682 -217.5764) (xy 101.198172 -217.563192) (xy 101.198172 -217.40622)
			(xy 101.19772 -217.392042) (xy 101.189946 -217.364774) (xy 101.174966 -217.3407) (xy 101.153937 -217.321681)
			(xy 101.128485 -217.309185) (xy 101.100576 -217.30418) (xy 101.072367 -217.307052) (xy 101.046039 -217.317578)
			(xy 101.034596 -217.325956) (xy 101.012744 -217.342108) (xy 100.964868 -217.367802) (xy 100.913437 -217.385329)
			(xy 100.859834 -217.394217) (xy 100.832666 -217.39479) (xy 100.806698 -217.394278) (xy 100.755401 -217.386149)
			(xy 100.706008 -217.370095) (xy 100.659734 -217.346513) (xy 100.617718 -217.315983) (xy 100.580995 -217.279256)
			(xy 100.550469 -217.237237) (xy 100.526892 -217.190961) (xy 100.510843 -217.141566) (xy 100.502719 -217.090268)
			(xy 100.502719 -217.038332) (xy 100.510843 -216.987034) (xy 100.526892 -216.937639) (xy 100.550469 -216.891363)
			(xy 100.580995 -216.849344) (xy 100.617718 -216.812617) (xy 100.659734 -216.782087) (xy 100.706008 -216.758505)
			(xy 100.755401 -216.742451) (xy 100.806698 -216.734322) (xy 100.832666 -216.733882) (xy 100.859836 -216.734429)
			(xy 100.913444 -216.743312) (xy 100.964877 -216.760844) (xy 101.01275 -216.786553) (xy 101.034596 -216.802716)
			(xy 101.046094 -216.810986) (xy 101.072406 -216.821439) (xy 101.100577 -216.824269) (xy 101.128441 -216.819256)
			(xy 101.15386 -216.806788) (xy 101.17488 -216.787821) (xy 101.189886 -216.763812) (xy 101.197725 -216.736607)
			(xy 101.198172 -216.722452) (xy 101.198172 -216.565734) (xy 101.1682 -216.552526) (xy 101.143121 -216.540758)
			(xy 101.096969 -216.510125) (xy 101.056573 -216.472222) (xy 101.023065 -216.428113) (xy 100.997385 -216.379031)
			(xy 100.980251 -216.326354) (xy 100.975668 -216.299034) (xy 100.969318 -216.2556) (xy 100.696014 -216.2556)
			(xy 100.689664 -216.299034) (xy 100.685334 -216.324828) (xy 100.669604 -216.374706) (xy 100.646214 -216.421484)
			(xy 100.615749 -216.463994) (xy 100.578968 -216.501176) (xy 100.53679 -216.5321) (xy 100.490268 -216.555995)
			(xy 100.440563 -216.572264) (xy 100.388916 -216.580501) (xy 100.336616 -216.580501) (xy 100.284969 -216.572264)
			(xy 100.235264 -216.555995) (xy 100.188742 -216.5321) (xy 100.146564 -216.501176) (xy 100.109783 -216.463994)
			(xy 100.079318 -216.421484) (xy 100.055928 -216.374706) (xy 100.040198 -216.324828) (xy 100.035868 -216.299034)
			(xy 100.029518 -216.2556) (xy 99.756214 -216.2556) (xy 99.749864 -216.299034) (xy 99.745534 -216.324828)
			(xy 99.729804 -216.374706) (xy 99.706414 -216.421484) (xy 99.675949 -216.463994) (xy 99.639168 -216.501176)
			(xy 99.59699 -216.5321) (xy 99.550468 -216.555995) (xy 99.500763 -216.572264) (xy 99.449116 -216.580501)
			(xy 99.396816 -216.580501) (xy 99.345169 -216.572264) (xy 99.295464 -216.555995) (xy 99.248942 -216.5321)
			(xy 99.206764 -216.501176) (xy 99.169983 -216.463994) (xy 99.139518 -216.421484) (xy 99.116128 -216.374706)
			(xy 99.100398 -216.324828) (xy 99.096068 -216.299034) (xy 99.089718 -216.2556) (xy 98.816414 -216.2556)
			(xy 98.810064 -216.299034) (xy 98.805734 -216.324828) (xy 98.790004 -216.374706) (xy 98.766614 -216.421484)
			(xy 98.736149 -216.463994) (xy 98.699368 -216.501176) (xy 98.65719 -216.5321) (xy 98.610668 -216.555995)
			(xy 98.560963 -216.572264) (xy 98.509316 -216.580501) (xy 98.457016 -216.580501) (xy 98.405369 -216.572264)
			(xy 98.355664 -216.555995) (xy 98.309142 -216.5321) (xy 98.266964 -216.501176) (xy 98.230183 -216.463994)
			(xy 98.199718 -216.421484) (xy 98.176328 -216.374706) (xy 98.160598 -216.324828) (xy 98.156268 -216.299034)
			(xy 98.149918 -216.2556) (xy 97.876614 -216.2556) (xy 97.870264 -216.299034) (xy 97.865934 -216.324828)
			(xy 97.850204 -216.374706) (xy 97.826814 -216.421484) (xy 97.796349 -216.463994) (xy 97.759568 -216.501176)
			(xy 97.71739 -216.5321) (xy 97.670868 -216.555995) (xy 97.621163 -216.572264) (xy 97.569516 -216.580501)
			(xy 97.517216 -216.580501) (xy 97.465569 -216.572264) (xy 97.415864 -216.555995) (xy 97.369342 -216.5321)
			(xy 97.327164 -216.501176) (xy 97.290383 -216.463994) (xy 97.259918 -216.421484) (xy 97.236528 -216.374706)
			(xy 97.220798 -216.324828) (xy 97.216468 -216.299034) (xy 97.210118 -216.2556) (xy 96.936814 -216.2556)
			(xy 96.930464 -216.299034) (xy 96.926134 -216.324828) (xy 96.910404 -216.374706) (xy 96.887014 -216.421484)
			(xy 96.856549 -216.463994) (xy 96.819768 -216.501176) (xy 96.77759 -216.5321) (xy 96.731068 -216.555995)
			(xy 96.681363 -216.572264) (xy 96.629716 -216.580501) (xy 96.577416 -216.580501) (xy 96.525769 -216.572264)
			(xy 96.476064 -216.555995) (xy 96.429542 -216.5321) (xy 96.387364 -216.501176) (xy 96.350583 -216.463994)
			(xy 96.320118 -216.421484) (xy 96.296728 -216.374706) (xy 96.280998 -216.324828) (xy 96.276668 -216.299034)
			(xy 96.270318 -216.2556) (xy 95.997014 -216.2556) (xy 95.990664 -216.299034) (xy 95.986334 -216.324828)
			(xy 95.970604 -216.374706) (xy 95.947214 -216.421484) (xy 95.916749 -216.463994) (xy 95.879968 -216.501176)
			(xy 95.83779 -216.5321) (xy 95.791268 -216.555995) (xy 95.741563 -216.572264) (xy 95.689916 -216.580501)
			(xy 95.637616 -216.580501) (xy 95.585969 -216.572264) (xy 95.536264 -216.555995) (xy 95.489742 -216.5321)
			(xy 95.447564 -216.501176) (xy 95.410783 -216.463994) (xy 95.380318 -216.421484) (xy 95.356928 -216.374706)
			(xy 95.341198 -216.324828) (xy 95.336868 -216.299034) (xy 95.330518 -216.2556) (xy 95.057214 -216.2556)
			(xy 95.050864 -216.299034) (xy 95.046534 -216.324828) (xy 95.030804 -216.374706) (xy 95.007414 -216.421484)
			(xy 94.976949 -216.463994) (xy 94.940168 -216.501176) (xy 94.89799 -216.5321) (xy 94.851468 -216.555995)
			(xy 94.801763 -216.572264) (xy 94.750116 -216.580501) (xy 94.697816 -216.580501) (xy 94.646169 -216.572264)
			(xy 94.596464 -216.555995) (xy 94.549942 -216.5321) (xy 94.507764 -216.501176) (xy 94.470983 -216.463994)
			(xy 94.440518 -216.421484) (xy 94.417128 -216.374706) (xy 94.401398 -216.324828) (xy 94.397068 -216.299034)
			(xy 94.390718 -216.2556) (xy 94.117414 -216.2556) (xy 94.111064 -216.299034) (xy 94.106734 -216.324828)
			(xy 94.091004 -216.374706) (xy 94.067614 -216.421484) (xy 94.037149 -216.463994) (xy 94.000368 -216.501176)
			(xy 93.95819 -216.5321) (xy 93.911668 -216.555995) (xy 93.861963 -216.572264) (xy 93.810316 -216.580501)
			(xy 93.758016 -216.580501) (xy 93.706369 -216.572264) (xy 93.656664 -216.555995) (xy 93.610142 -216.5321)
			(xy 93.567964 -216.501176) (xy 93.531183 -216.463994) (xy 93.500718 -216.421484) (xy 93.477328 -216.374706)
			(xy 93.461598 -216.324828) (xy 93.457268 -216.299034) (xy 93.450918 -216.2556) (xy 93.177614 -216.2556)
			(xy 93.171264 -216.299034) (xy 93.166934 -216.324828) (xy 93.151204 -216.374706) (xy 93.127814 -216.421484)
			(xy 93.097349 -216.463994) (xy 93.060568 -216.501176) (xy 93.01839 -216.5321) (xy 92.971868 -216.555995)
			(xy 92.922163 -216.572264) (xy 92.870516 -216.580501) (xy 92.818216 -216.580501) (xy 92.766569 -216.572264)
			(xy 92.716864 -216.555995) (xy 92.670342 -216.5321) (xy 92.628164 -216.501176) (xy 92.591383 -216.463994)
			(xy 92.560918 -216.421484) (xy 92.537528 -216.374706) (xy 92.521798 -216.324828) (xy 92.517468 -216.299034)
			(xy 92.511118 -216.2556) (xy 92.237814 -216.2556) (xy 92.231464 -216.299034) (xy 92.227134 -216.324828)
			(xy 92.211404 -216.374706) (xy 92.188014 -216.421484) (xy 92.157549 -216.463994) (xy 92.120768 -216.501176)
			(xy 92.07859 -216.5321) (xy 92.032068 -216.555995) (xy 91.982363 -216.572264) (xy 91.930716 -216.580501)
			(xy 91.878416 -216.580501) (xy 91.826769 -216.572264) (xy 91.777064 -216.555995) (xy 91.730542 -216.5321)
			(xy 91.688364 -216.501176) (xy 91.651583 -216.463994) (xy 91.621118 -216.421484) (xy 91.597728 -216.374706)
			(xy 91.581998 -216.324828) (xy 91.577668 -216.299034) (xy 91.571318 -216.2556) (xy 91.298014 -216.2556)
			(xy 91.291664 -216.299034) (xy 91.287334 -216.324828) (xy 91.271604 -216.374706) (xy 91.248214 -216.421484)
			(xy 91.217749 -216.463994) (xy 91.180968 -216.501176) (xy 91.13879 -216.5321) (xy 91.092268 -216.555995)
			(xy 91.042563 -216.572264) (xy 90.990916 -216.580501) (xy 90.938616 -216.580501) (xy 90.886969 -216.572264)
			(xy 90.837264 -216.555995) (xy 90.790742 -216.5321) (xy 90.748564 -216.501176) (xy 90.711783 -216.463994)
			(xy 90.681318 -216.421484) (xy 90.657928 -216.374706) (xy 90.642198 -216.324828) (xy 90.637868 -216.299034)
			(xy 90.631518 -216.2556) (xy 90.358214 -216.2556) (xy 90.351864 -216.299034) (xy 90.347532 -216.324825)
			(xy 90.331799 -216.374699) (xy 90.308408 -216.421472) (xy 90.277941 -216.463976) (xy 90.241159 -216.501152)
			(xy 90.198982 -216.53207) (xy 90.152461 -216.555958) (xy 90.102758 -216.572222) (xy 90.051114 -216.580453)
			(xy 90.024966 -216.580974) (xy 90.001523 -216.580562) (xy 89.955107 -216.57393) (xy 89.910094 -216.560804)
			(xy 89.888568 -216.55151) (xy 89.874259 -216.54562) (xy 89.843558 -216.541874) (xy 89.813146 -216.547504)
			(xy 89.785821 -216.561993) (xy 89.764096 -216.584006) (xy 89.756488 -216.597484) (xy 89.748292 -216.613081)
			(xy 89.730632 -216.643574) (xy 89.721182 -216.658444) (xy 89.713278 -216.671764) (xy 89.705121 -216.701627)
			(xy 89.706284 -216.732562) (xy 89.716661 -216.761728) (xy 89.735299 -216.786446) (xy 89.747598 -216.795858)
			(xy 89.768557 -216.811482) (xy 89.805725 -216.848238) (xy 89.836635 -216.890393) (xy 89.860515 -216.936893)
			(xy 89.876767 -216.986576) (xy 89.884985 -217.038199) (xy 89.88552 -217.064336) (xy 89.885008 -217.0903)
			(xy 89.876879 -217.141589) (xy 89.860827 -217.190975) (xy 89.837247 -217.237241) (xy 89.806719 -217.279249)
			(xy 89.769996 -217.315965) (xy 89.727981 -217.346483) (xy 89.68171 -217.370054) (xy 89.632321 -217.386095)
			(xy 89.581031 -217.394214) (xy 89.555066 -217.39479) (xy 89.528031 -217.394249) (xy 89.474681 -217.385447)
			(xy 89.423474 -217.368083) (xy 89.375774 -217.342619) (xy 89.332852 -217.309735) (xy 89.295851 -217.270306)
			(xy 89.265758 -217.225383) (xy 89.243374 -217.176162) (xy 89.229296 -217.123956) (xy 89.226136 -217.097102)
			(xy 89.224098 -217.081776) (xy 89.21203 -217.053326) (xy 89.191992 -217.0298) (xy 89.165825 -217.013359)
			(xy 89.135934 -217.005514) (xy 89.120472 -217.005662) (xy 89.084658 -217.006424) (xy 89.049606 -217.005662)
			(xy 89.034151 -217.005502) (xy 89.004282 -217.013388) (xy 88.978135 -217.029841) (xy 88.958101 -217.053357)
			(xy 88.94601 -217.081785) (xy 88.943942 -217.097102) (xy 88.940728 -217.123952) (xy 88.926684 -217.17617)
			(xy 88.904324 -217.225403) (xy 88.874245 -217.270338) (xy 88.83725 -217.309775) (xy 88.794326 -217.34266)
			(xy 88.74662 -217.368117) (xy 88.695405 -217.385464) (xy 88.642049 -217.39424) (xy 88.615012 -217.39479)
			(xy 88.589043 -217.394282) (xy 88.537745 -217.386159) (xy 88.488348 -217.370112) (xy 88.44207 -217.346535)
			(xy 88.400049 -217.31601) (xy 88.363321 -217.279287) (xy 88.33279 -217.237271) (xy 88.309206 -217.190996)
			(xy 88.293152 -217.141602) (xy 88.285022 -217.090305) (xy 88.284558 -217.064336) (xy 88.285055 -217.038244)
			(xy 88.293265 -216.986711) (xy 88.309469 -216.937107) (xy 88.333266 -216.890666) (xy 88.364065 -216.848541)
			(xy 88.4011 -216.811778) (xy 88.421972 -216.796112) (xy 88.434211 -216.78665) (xy 88.452787 -216.76193)
			(xy 88.463134 -216.732792) (xy 88.464308 -216.701892) (xy 88.456202 -216.672053) (xy 88.448388 -216.658698)
			(xy 88.429846 -216.628472) (xy 88.40978 -216.593928) (xy 88.401839 -216.581251) (xy 88.380023 -216.560805)
			(xy 88.353229 -216.547538) (xy 88.323744 -216.54258) (xy 88.294084 -216.546356) (xy 88.28024 -216.552018)
			(xy 88.258862 -216.561186) (xy 88.214175 -216.574094) (xy 88.168116 -216.580589) (xy 88.144858 -216.580974)
			(xy 88.118892 -216.580462) (xy 88.067601 -216.572332) (xy 88.018213 -216.55628) (xy 87.971943 -216.5327)
			(xy 87.929932 -216.502174) (xy 87.893212 -216.465452) (xy 87.862688 -216.423438) (xy 87.839111 -216.377167)
			(xy 87.823063 -216.327777) (xy 87.814937 -216.276486) (xy 87.814404 -216.25052) (xy 87.814893 -216.224458)
			(xy 87.823077 -216.17298) (xy 87.839245 -216.123426) (xy 87.862995 -216.077026) (xy 87.893738 -216.034933)
			(xy 87.930711 -215.998191) (xy 87.951564 -215.98255) (xy 87.963409 -215.973367) (xy 87.981603 -215.949568)
			(xy 87.992123 -215.921519) (xy 87.994068 -215.891626) (xy 87.987272 -215.86245) (xy 87.980266 -215.8492)
			(xy 87.9602 -215.814656) (xy 87.943436 -215.783668) (xy 87.935849 -215.770188) (xy 87.914075 -215.748238)
			(xy 87.88673 -215.73381) (xy 87.856321 -215.728228) (xy 87.825634 -215.732002) (xy 87.811356 -215.737948)
			(xy 87.789866 -215.747201) (xy 87.744931 -215.760233) (xy 87.698606 -215.766788) (xy 87.675212 -215.767158)
			(xy 87.649242 -215.766676) (xy 87.597941 -215.758552) (xy 87.548542 -215.742503) (xy 87.502262 -215.718924)
			(xy 87.460241 -215.688395) (xy 87.423513 -215.651668) (xy 87.392982 -215.609648) (xy 87.369401 -215.563369)
			(xy 87.35335 -215.513971) (xy 87.345225 -215.46267) (xy 87.345225 -215.41073) (xy 87.35335 -215.359429)
			(xy 87.369401 -215.310031) (xy 87.392982 -215.263752) (xy 87.423513 -215.221732) (xy 87.460241 -215.185005)
			(xy 87.502262 -215.154476) (xy 87.548542 -215.130897) (xy 87.597941 -215.114848) (xy 87.649242 -215.106724)
			(xy 87.675212 -215.10625) (xy 87.705184 -215.10752) (xy 87.719243 -215.108374) (xy 87.746924 -215.103226)
			(xy 87.772146 -215.090713) (xy 87.79299 -215.071785) (xy 87.807871 -215.047883) (xy 87.815655 -215.020825)
			(xy 87.815752 -214.992669) (xy 87.812372 -214.978996) (xy 87.798157 -214.926271) (xy 87.777414 -214.819048)
			(xy 87.765583 -214.71048) (xy 87.763604 -214.655908) (xy 87.763604 -214.636858) (xy 87.763858 -214.609934)
			(xy 87.764112 -214.609172) (xy 87.764112 -213.952074) (xy 87.764558 -213.914956) (xy 87.771815 -213.841076)
			(xy 87.786276 -213.768262) (xy 87.807801 -213.697215) (xy 87.836184 -213.62862) (xy 87.871152 -213.563135)
			(xy 87.912367 -213.501392) (xy 87.959434 -213.443984) (xy 87.985346 -213.417404) (xy 88.050624 -213.35238)
			(xy 88.044528 -213.325202) (xy 88.03617 -213.284827) (xy 88.027262 -213.202854) (xy 88.026748 -213.161626)
			(xy 88.026748 -212.894926) (xy 88.027248 -212.855503) (xy 88.035425 -212.777083) (xy 88.051705 -212.699937)
			(xy 88.063324 -212.662262) (xy 88.051684 -212.624592) (xy 88.035386 -212.547447) (xy 88.027224 -212.469022)
			(xy 88.026748 -212.429598) (xy 88.026748 -212.162898) (xy 88.027367 -212.119115) (xy 88.037461 -212.032134)
			(xy 88.057526 -211.946899) (xy 88.087293 -211.864549) (xy 88.10625 -211.825078) (xy 88.096598 -211.7979)
			(xy 88.092788 -211.786724) (xy 85.141816 -208.835752) (xy 85.109819 -208.802871) (xy 85.052908 -208.730904)
			(xy 85.004772 -208.652796) (xy 84.984844 -208.61147) (xy 84.431124 -207.419702) (xy 84.414909 -207.383608)
			(xy 84.388972 -207.308847) (xy 84.370687 -207.231856) (xy 84.360237 -207.153416) (xy 84.35848 -207.113886)
			(xy 84.32038 -205.924658) (xy 84.319872 -205.899512) (xy 84.320292 -205.864264) (xy 84.326655 -205.794055)
			(xy 84.332572 -205.759304) (xy 84.624164 -204.151738) (xy 84.631971 -204.111623) (xy 84.654829 -204.033158)
			(xy 84.685721 -203.957494) (xy 84.72431 -203.88545) (xy 84.77018 -203.817809) (xy 84.796122 -203.786232)
			(xy 88.365838 -199.544178) (xy 88.365838 -192.24498) (xy 88.324182 -192.23736) (xy 88.296746 -192.231906)
			(xy 88.243742 -192.214033) (xy 88.193916 -192.188612) (xy 88.148336 -192.156189) (xy 88.107978 -192.117457)
			(xy 88.073708 -192.073248) (xy 88.04626 -192.024509) (xy 88.026223 -191.972285) (xy 88.014025 -191.917695)
			(xy 88.009929 -191.861909) (xy 88.014023 -191.806122) (xy 88.026218 -191.751531) (xy 88.046253 -191.699306)
			(xy 88.073698 -191.650566) (xy 88.107966 -191.606356) (xy 88.148323 -191.567622) (xy 88.193902 -191.535197)
			(xy 88.243727 -191.509774) (xy 88.29673 -191.491898) (xy 88.324182 -191.486536) (xy 88.365838 -191.478916)
			(xy 88.365838 -191.05499) (xy 83.57616 -186.265312) (xy 83.566441 -186.256149) (xy 83.543314 -186.2428)
			(xy 83.517515 -186.235907) (xy 83.490812 -186.235943) (xy 83.465032 -186.242905) (xy 83.441941 -186.256316)
			(xy 83.423119 -186.275259) (xy 83.41614 -186.286648) (xy 83.402591 -186.309384) (xy 83.370173 -186.351218)
			(xy 83.332267 -186.388153) (xy 83.289606 -186.419476) (xy 83.266534 -186.432444) (xy 83.254724 -186.439315)
			(xy 83.234984 -186.458191) (xy 83.220953 -186.481624) (xy 83.213635 -186.507938) (xy 83.213552 -186.535251)
			(xy 83.220712 -186.561608) (xy 83.234601 -186.585126) (xy 83.254227 -186.604121) (xy 83.266026 -186.611006)
			(xy 83.291297 -186.625498) (xy 83.337513 -186.66096) (xy 83.377795 -186.703041) (xy 83.411205 -186.75076)
			(xy 83.436965 -186.803008) (xy 83.454475 -186.858567) (xy 83.463328 -186.916143) (xy 83.463892 -186.94527)
			(xy 83.463406 -186.972521) (xy 83.45565 -187.026469) (xy 83.440295 -187.078764) (xy 83.417653 -187.128341)
			(xy 83.388187 -187.174191) (xy 83.352496 -187.215382) (xy 83.311305 -187.251073) (xy 83.265455 -187.280539)
			(xy 83.215878 -187.303181) (xy 83.163583 -187.318536) (xy 83.109635 -187.326292) (xy 83.055133 -187.326292)
			(xy 83.001185 -187.318536) (xy 82.94889 -187.303181) (xy 82.899313 -187.280539) (xy 82.853463 -187.251073)
			(xy 82.812272 -187.215382) (xy 82.776581 -187.174191) (xy 82.747115 -187.128341) (xy 82.724473 -187.078764)
			(xy 82.709118 -187.026469) (xy 82.701362 -186.972521) (xy 82.700876 -186.94527) (xy 82.701415 -186.915954)
			(xy 82.710392 -186.858013) (xy 82.72813 -186.802129) (xy 82.754211 -186.749617) (xy 82.788021 -186.701714)
			(xy 82.828762 -186.65955) (xy 82.875477 -186.624117) (xy 82.901028 -186.609736) (xy 82.912829 -186.602861)
			(xy 82.932553 -186.583982) (xy 82.94657 -186.560553) (xy 82.953879 -186.534247) (xy 82.953959 -186.506945)
			(xy 82.946804 -186.480597) (xy 82.932924 -186.457086) (xy 82.913311 -186.438092) (xy 82.901536 -186.431174)
			(xy 82.876263 -186.416682) (xy 82.830044 -186.38122) (xy 82.789757 -186.33914) (xy 82.756341 -186.291421)
			(xy 82.730573 -186.239174) (xy 82.713053 -186.183615) (xy 82.704189 -186.126038) (xy 82.70367 -186.09691)
			(xy 82.704183 -186.068276) (xy 82.712743 -186.01165) (xy 82.729673 -185.956941) (xy 82.754591 -185.905378)
			(xy 82.786938 -185.858119) (xy 82.825986 -185.816227) (xy 82.870859 -185.780644) (xy 82.89544 -185.765948)
			(xy 82.906811 -185.758958) (xy 82.925716 -185.740126) (xy 82.939098 -185.717041) (xy 82.946044 -185.691277)
			(xy 82.946079 -185.664593) (xy 82.939202 -185.638811) (xy 82.925882 -185.61569) (xy 82.916776 -185.605928)
			(xy 78.96225 -181.651402) (xy 76.242672 -181.651402) (xy 76.227549 -181.651969) (xy 76.198634 -181.660844)
			(xy 76.173574 -181.677781) (xy 76.154557 -181.701301) (xy 76.143243 -181.729352) (xy 76.141326 -181.744366)
			(xy 76.138377 -181.772545) (xy 76.125213 -181.82765) (xy 76.104041 -181.880202) (xy 76.075329 -181.929043)
			(xy 76.039707 -181.9731) (xy 75.99796 -182.011402) (xy 75.951006 -182.043107) (xy 75.899879 -182.067517)
			(xy 75.845702 -182.084095) (xy 75.78967 -182.092477) (xy 75.733014 -182.092477) (xy 75.676982 -182.084095)
			(xy 75.622805 -182.067517) (xy 75.571678 -182.043107) (xy 75.524724 -182.011402) (xy 75.482977 -181.9731)
			(xy 75.447355 -181.929043) (xy 75.418643 -181.880202) (xy 75.397471 -181.82765) (xy 75.384307 -181.772545)
			(xy 75.381358 -181.744366) (xy 75.379532 -181.729326) (xy 75.368248 -181.701227) (xy 75.349219 -181.677674)
			(xy 75.324118 -181.660738) (xy 75.295153 -181.65191) (xy 75.280012 -181.651402) (xy 72.678036 -181.651402)
			(xy 72.662666 -181.651914) (xy 72.63331 -181.661029) (xy 72.608002 -181.678474) (xy 72.589037 -181.702665)
			(xy 72.578138 -181.731406) (xy 72.576294 -181.762089) (xy 72.579484 -181.777132) (xy 72.5846 -181.799452)
			(xy 72.59008 -181.844914) (xy 72.590406 -181.86781) (xy 72.58992 -181.895061) (xy 72.582164 -181.949009)
			(xy 72.566809 -182.001304) (xy 72.544167 -182.050881) (xy 72.514701 -182.096731) (xy 72.47901 -182.137922)
			(xy 72.437819 -182.173613) (xy 72.391969 -182.203079) (xy 72.342392 -182.225721) (xy 72.290097 -182.241076)
			(xy 72.236149 -182.248832) (xy 72.181647 -182.248832) (xy 72.127699 -182.241076) (xy 72.075404 -182.225721)
			(xy 72.025827 -182.203079) (xy 71.979977 -182.173613) (xy 71.938786 -182.137922) (xy 71.903095 -182.096731)
			(xy 71.873629 -182.050881) (xy 71.850987 -182.001304) (xy 71.835632 -181.949009) (xy 71.827876 -181.895061)
			(xy 71.82739 -181.86781) (xy 71.827732 -181.844915) (xy 71.833213 -181.799455) (xy 71.838312 -181.777132)
			(xy 71.841448 -181.76209) (xy 71.839553 -181.731436) (xy 71.828641 -181.702728) (xy 71.809696 -181.678555)
			(xy 71.784428 -181.661098) (xy 71.755115 -181.651932) (xy 71.73976 -181.651402) (xy 68.957952 -181.651402)
			(xy 68.943603 -181.651885) (xy 68.916034 -181.659856) (xy 68.891772 -181.675182) (xy 68.872731 -181.696654)
			(xy 68.860417 -181.722575) (xy 68.855801 -181.750899) (xy 68.857114 -181.765194) (xy 68.858414 -181.776643)
			(xy 68.859812 -181.799646) (xy 68.859908 -181.811168) (xy 68.859422 -181.838419) (xy 68.851666 -181.892367)
			(xy 68.836311 -181.944662) (xy 68.813669 -181.994239) (xy 68.784203 -182.040089) (xy 68.748512 -182.08128)
			(xy 68.707321 -182.116971) (xy 68.661471 -182.146437) (xy 68.611894 -182.169079) (xy 68.559599 -182.184434)
			(xy 68.505651 -182.19219) (xy 68.451149 -182.19219) (xy 68.397201 -182.184434) (xy 68.344906 -182.169079)
			(xy 68.295329 -182.146437) (xy 68.249479 -182.116971) (xy 68.208288 -182.08128) (xy 68.172597 -182.040089)
			(xy 68.143131 -181.994239) (xy 68.120489 -181.944662) (xy 68.105134 -181.892367) (xy 68.097378 -181.838419)
			(xy 68.096892 -181.811168) (xy 68.096978 -181.799645) (xy 68.098378 -181.776643) (xy 68.099686 -181.765194)
			(xy 68.100921 -181.750896) (xy 68.096309 -181.722584) (xy 68.084006 -181.696671) (xy 68.064984 -181.6752)
			(xy 68.040741 -181.659865) (xy 68.013191 -181.651876) (xy 67.998848 -181.651402) (xy 61.980826 -181.651402)
			(xy 61.966957 -181.651868) (xy 61.94024 -181.659329) (xy 61.916519 -181.673707) (xy 61.897545 -181.693941)
			(xy 61.884719 -181.718536) (xy 61.878988 -181.745676) (xy 61.880775 -181.773357) (xy 61.889949 -181.799535)
			(xy 61.897514 -181.811168) (xy 61.913744 -181.835319) (xy 61.93947 -181.88751) (xy 61.956959 -181.943005)
			(xy 61.965807 -182.000515) (xy 61.966348 -182.029608) (xy 61.965862 -182.056859) (xy 61.958106 -182.110807)
			(xy 61.942751 -182.163102) (xy 61.920109 -182.212679) (xy 61.890643 -182.258529) (xy 61.854952 -182.29972)
			(xy 61.813761 -182.335411) (xy 61.767911 -182.364877) (xy 61.718334 -182.387519) (xy 61.666039 -182.402874)
			(xy 61.612091 -182.41063) (xy 61.557589 -182.41063) (xy 61.503641 -182.402874) (xy 61.451346 -182.387519)
			(xy 61.401769 -182.364877) (xy 61.355919 -182.335411) (xy 61.314728 -182.29972) (xy 61.279037 -182.258529)
			(xy 61.249571 -182.212679) (xy 61.226929 -182.163102) (xy 61.211574 -182.110807) (xy 61.203818 -182.056859)
			(xy 61.203332 -182.029608) (xy 61.203906 -182.000519) (xy 61.212784 -181.943022) (xy 61.230273 -181.887534)
			(xy 61.255971 -181.835338) (xy 61.272166 -181.811168) (xy 61.279723 -181.799531) (xy 61.288898 -181.773357)
			(xy 61.290686 -181.74568) (xy 61.284956 -181.718543) (xy 61.27213 -181.693951) (xy 61.253156 -181.673721)
			(xy 61.229436 -181.659347) (xy 61.202722 -181.651892) (xy 61.188854 -181.651402) (xy 61.067188 -181.651402)
			(xy 58.498486 -179.0827) (xy 51.868324 -179.0827) (xy 51.818024 -179.110888) (xy 51.714383 -179.161451)
			(xy 51.607684 -179.205193) (xy 51.498374 -179.241928) (xy 51.386914 -179.271503) (xy 51.273772 -179.293794)
			(xy 51.159423 -179.308706) (xy 51.044349 -179.316178) (xy 50.98669 -179.316634) (xy 50.933485 -179.316269)
			(xy 50.827264 -179.309953) (xy 50.721611 -179.29729) (xy 50.66919 -179.288186) (xy 50.616766 -179.297268)
			(xy 50.511113 -179.309926) (xy 50.404894 -179.316251) (xy 50.35169 -179.316634) (xy 50.294855 -179.316192)
			(xy 50.181416 -179.308949) (xy 50.068672 -179.294473) (xy 49.957083 -179.272825) (xy 49.847104 -179.244092)
			(xy 49.739186 -179.208391) (xy 49.633769 -179.16587) (xy 49.531284 -179.1167) (xy 49.481486 -179.089304)
			(xy 49.469802 -179.0827) (xy 48.593502 -179.0827) (xy 48.588422 -179.127912) (xy 48.584838 -179.155553)
			(xy 48.570686 -179.209461) (xy 48.548841 -179.260737) (xy 48.519768 -179.308289) (xy 48.484087 -179.351105)
			(xy 48.442556 -179.388274) (xy 48.396059 -179.419006) (xy 48.345585 -179.442646) (xy 48.29221 -179.458691)
			(xy 48.237068 -179.4668) (xy 48.181332 -179.4668) (xy 48.12619 -179.458691) (xy 48.072815 -179.442646)
			(xy 48.022341 -179.419006) (xy 47.975844 -179.388274) (xy 47.934313 -179.351105) (xy 47.898632 -179.308289)
			(xy 47.869559 -179.260737) (xy 47.847714 -179.209461) (xy 47.833562 -179.155553) (xy 47.829978 -179.127912)
			(xy 47.824898 -179.0827) (xy 47.530004 -179.0827) (xy 43.447208 -174.999904) (xy 38.457632 -174.999904)
			(xy 38.443938 -175.000357) (xy 38.417538 -175.00765) (xy 38.394025 -175.021694) (xy 38.375086 -175.041479)
			(xy 38.362084 -175.065585) (xy 38.355952 -175.092278) (xy 38.357131 -175.119641) (xy 38.365537 -175.145708)
			(xy 38.380565 -175.168605) (xy 38.390576 -175.177958) (xy 38.410658 -175.196149) (xy 38.445989 -175.23723)
			(xy 38.475149 -175.282899) (xy 38.497549 -175.332236) (xy 38.512739 -175.384248) (xy 38.520413 -175.437886)
			(xy 38.520878 -175.464978) (xy 38.520416 -175.492231) (xy 38.512662 -175.546183) (xy 38.497307 -175.598482)
			(xy 38.474665 -175.648063) (xy 38.445198 -175.693916) (xy 38.409503 -175.735109) (xy 38.36831 -175.770802)
			(xy 38.322456 -175.800269) (xy 38.272874 -175.82291) (xy 38.220575 -175.838263) (xy 38.166623 -175.846017)
			(xy 38.13937 -175.846486) (xy 38.114032 -175.84607) (xy 38.063804 -175.839356) (xy 38.014906 -175.826052)
			(xy 37.9682 -175.806391) (xy 37.924508 -175.78072) (xy 37.8846 -175.74949) (xy 37.866574 -175.731678)
			(xy 37.856822 -175.722317) (xy 37.833517 -175.708641) (xy 37.807441 -175.701556) (xy 37.780419 -175.701556)
			(xy 37.754343 -175.708641) (xy 37.731038 -175.722317) (xy 37.721286 -175.731678) (xy 37.703277 -175.749507)
			(xy 37.663365 -175.780735) (xy 37.619669 -175.806404) (xy 37.57296 -175.826061) (xy 37.52406 -175.839361)
			(xy 37.473829 -175.846069) (xy 37.44849 -175.846486) (xy 37.421238 -175.846022) (xy 37.36729 -175.838264)
			(xy 37.314994 -175.822907) (xy 37.265417 -175.800263) (xy 37.219566 -175.770795) (xy 37.178377 -175.735101)
			(xy 37.142686 -175.693908) (xy 37.113221 -175.648055) (xy 37.090582 -175.598476) (xy 37.075229 -175.546179)
			(xy 37.067476 -175.49223) (xy 37.066982 -175.464978) (xy 37.067459 -175.437886) (xy 37.075132 -175.384249)
			(xy 37.09032 -175.332238) (xy 37.112718 -175.282901) (xy 37.141875 -175.237231) (xy 37.177202 -175.196149)
			(xy 37.197284 -175.177958) (xy 37.207299 -175.168591) (xy 37.22237 -175.145696) (xy 37.230808 -175.119617)
			(xy 37.232006 -175.092232) (xy 37.225878 -175.065516) (xy 37.212865 -175.041391) (xy 37.193904 -175.021597)
			(xy 37.170362 -175.007558) (xy 37.143934 -175.000286) (xy 37.130228 -174.999904) (xy 35.208972 -174.999904)
			(xy 34.630614 -175.578262) (xy 34.630614 -177.525254) (xy 36.992749 -177.525254) (xy 36.992749 -177.470746)
			(xy 37.000507 -177.416793) (xy 37.015864 -177.364493) (xy 37.038508 -177.314911) (xy 37.067977 -177.269057)
			(xy 37.103673 -177.227863) (xy 37.144868 -177.192169) (xy 37.190724 -177.162701) (xy 37.240306 -177.140059)
			(xy 37.292607 -177.124704) (xy 37.34656 -177.116948) (xy 37.373814 -177.116486) (xy 37.399393 -177.116905)
			(xy 37.450091 -177.12375) (xy 37.499421 -177.137301) (xy 37.546501 -177.157316) (xy 37.590487 -177.183437)
			(xy 37.630593 -177.215197) (xy 37.648642 -177.233326) (xy 37.658344 -177.242738) (xy 37.681549 -177.256576)
			(xy 37.707572 -177.263845) (xy 37.734589 -177.264037) (xy 37.760712 -177.257138) (xy 37.784112 -177.243631)
			(xy 37.79393 -177.234342) (xy 37.81557 -177.213378) (xy 37.864194 -177.177806) (xy 37.917806 -177.150322)
			(xy 37.975073 -177.13161) (xy 38.034571 -177.122136) (xy 38.064694 -177.121566) (xy 38.091945 -177.122081)
			(xy 38.145893 -177.129837) (xy 38.198188 -177.145191) (xy 38.247766 -177.167832) (xy 38.293616 -177.197298)
			(xy 38.334807 -177.232989) (xy 38.370499 -177.274179) (xy 38.399965 -177.320029) (xy 38.422607 -177.369606)
			(xy 38.437962 -177.421901) (xy 38.445719 -177.475849) (xy 38.445719 -177.530351) (xy 38.437962 -177.584299)
			(xy 38.422607 -177.636594) (xy 38.399965 -177.686171) (xy 38.370499 -177.732021) (xy 38.334807 -177.773211)
			(xy 38.293616 -177.808902) (xy 38.247766 -177.838368) (xy 38.198188 -177.861009) (xy 38.145893 -177.876363)
			(xy 38.091945 -177.884119) (xy 38.064694 -177.884582) (xy 38.039116 -177.884137) (xy 37.98842 -177.877295)
			(xy 37.939091 -177.863748) (xy 37.892012 -177.843737) (xy 37.848024 -177.817622) (xy 37.807916 -177.785869)
			(xy 37.789866 -177.767742) (xy 37.780156 -177.758341) (xy 37.756952 -177.744507) (xy 37.730932 -177.737239)
			(xy 37.703918 -177.737045) (xy 37.677797 -177.74394) (xy 37.654397 -177.75744) (xy 37.644578 -177.766726)
			(xy 37.622929 -177.787681) (xy 37.574308 -177.823255) (xy 37.520698 -177.850741) (xy 37.463433 -177.869455)
			(xy 37.403937 -177.878931) (xy 37.373814 -177.879502) (xy 37.34656 -177.879052) (xy 37.292607 -177.871296)
			(xy 37.240306 -177.855941) (xy 37.190724 -177.833299) (xy 37.144868 -177.803831) (xy 37.103673 -177.768137)
			(xy 37.067977 -177.726943) (xy 37.038508 -177.681089) (xy 37.015864 -177.631507) (xy 37.000507 -177.579207)
			(xy 36.992749 -177.525254) (xy 34.630614 -177.525254) (xy 34.630614 -179.563351) (xy 36.964868 -179.563351)
			(xy 36.964868 -179.508849) (xy 36.972624 -179.454902) (xy 36.987978 -179.402608) (xy 37.010618 -179.353032)
			(xy 37.040082 -179.307181) (xy 37.075772 -179.265991) (xy 37.11696 -179.230298) (xy 37.162809 -179.20083)
			(xy 37.212384 -179.178187) (xy 37.264677 -179.162829) (xy 37.318623 -179.15507) (xy 37.345874 -179.154582)
			(xy 37.374469 -179.155111) (xy 37.431019 -179.16365) (xy 37.485664 -179.180526) (xy 37.537181 -179.205361)
			(xy 37.584419 -179.237601) (xy 37.605716 -179.25669) (xy 37.617227 -179.266682) (xy 37.644676 -179.279905)
			(xy 37.674804 -179.284448) (xy 37.704932 -179.279905) (xy 37.732381 -179.266682) (xy 37.743892 -179.25669)
			(xy 37.76518 -179.237588) (xy 37.812414 -179.205336) (xy 37.863933 -179.180495) (xy 37.918581 -179.16362)
			(xy 37.975137 -179.155089) (xy 38.003734 -179.154582) (xy 38.030983 -179.155091) (xy 38.084925 -179.162851)
			(xy 38.137215 -179.178208) (xy 38.186786 -179.200851) (xy 38.232631 -179.230317) (xy 38.273816 -179.266008)
			(xy 38.309503 -179.307196) (xy 38.338965 -179.353044) (xy 38.361603 -179.402617) (xy 38.376956 -179.454908)
			(xy 38.384712 -179.508851) (xy 38.384712 -179.558556) (xy 38.726019 -179.558556) (xy 38.726019 -179.504044)
			(xy 38.733777 -179.450087) (xy 38.749135 -179.397784) (xy 38.77178 -179.348198) (xy 38.801252 -179.30234)
			(xy 38.83695 -179.261143) (xy 38.878148 -179.225446) (xy 38.924007 -179.195976) (xy 38.973593 -179.173331)
			(xy 39.025897 -179.157975) (xy 39.079854 -179.150218) (xy 39.10711 -179.149756) (xy 39.132688 -179.150187)
			(xy 39.183385 -179.157031) (xy 39.232715 -179.17058) (xy 39.279795 -179.190593) (xy 39.323781 -179.216712)
			(xy 39.363888 -179.248468) (xy 39.381938 -179.266596) (xy 39.391642 -179.276006) (xy 39.414846 -179.289848)
			(xy 39.440868 -179.29712) (xy 39.467887 -179.297313) (xy 39.49401 -179.290413) (xy 39.51741 -179.276903)
			(xy 39.527226 -179.267612) (xy 39.548862 -179.246644) (xy 39.597488 -179.211074) (xy 39.651101 -179.183591)
			(xy 39.708369 -179.16488) (xy 39.767867 -179.155406) (xy 39.79799 -179.154836) (xy 39.825246 -179.15521)
			(xy 39.879205 -179.162967) (xy 39.93151 -179.178324) (xy 39.981097 -179.200968) (xy 40.026957 -179.23044)
			(xy 40.068155 -179.266137) (xy 40.103854 -179.307335) (xy 40.133327 -179.353194) (xy 40.155973 -179.402781)
			(xy 40.171331 -179.455085) (xy 40.179089 -179.509044) (xy 40.179089 -179.563556) (xy 40.171331 -179.617515)
			(xy 40.155973 -179.669819) (xy 40.133327 -179.719406) (xy 40.103854 -179.765265) (xy 40.068155 -179.806463)
			(xy 40.026957 -179.84216) (xy 39.981097 -179.871632) (xy 39.93151 -179.894276) (xy 39.879205 -179.909633)
			(xy 39.825246 -179.91739) (xy 39.79799 -179.917852) (xy 39.772412 -179.917418) (xy 39.721715 -179.910575)
			(xy 39.672385 -179.897026) (xy 39.625306 -179.877013) (xy 39.581319 -179.850895) (xy 39.541212 -179.81914)
			(xy 39.523162 -179.801012) (xy 39.513458 -179.791602) (xy 39.490254 -179.777758) (xy 39.464232 -179.770486)
			(xy 39.437213 -179.770293) (xy 39.411089 -179.777193) (xy 39.38769 -179.790704) (xy 39.377874 -179.799996)
			(xy 39.356239 -179.820965) (xy 39.307613 -179.856535) (xy 39.253999 -179.884017) (xy 39.196731 -179.902728)
			(xy 39.137234 -179.912202) (xy 39.10711 -179.912772) (xy 39.079854 -179.912382) (xy 39.025897 -179.904625)
			(xy 38.973593 -179.889269) (xy 38.924007 -179.866624) (xy 38.878148 -179.837154) (xy 38.83695 -179.801457)
			(xy 38.801252 -179.76026) (xy 38.77178 -179.714402) (xy 38.749135 -179.664816) (xy 38.733777 -179.612513)
			(xy 38.726019 -179.558556) (xy 38.384712 -179.558556) (xy 38.384712 -179.563349) (xy 38.376956 -179.617292)
			(xy 38.361603 -179.669583) (xy 38.338965 -179.719156) (xy 38.309503 -179.765004) (xy 38.273816 -179.806192)
			(xy 38.232631 -179.841883) (xy 38.186786 -179.871349) (xy 38.137215 -179.893992) (xy 38.084925 -179.909349)
			(xy 38.030983 -179.917109) (xy 38.003734 -179.917598) (xy 37.975139 -179.917069) (xy 37.918588 -179.908531)
			(xy 37.863944 -179.891656) (xy 37.812426 -179.86682) (xy 37.765189 -179.834579) (xy 37.743892 -179.81549)
			(xy 37.732381 -179.805498) (xy 37.704932 -179.792275) (xy 37.674804 -179.787732) (xy 37.644676 -179.792275)
			(xy 37.617227 -179.805498) (xy 37.605716 -179.81549) (xy 37.584422 -179.834585) (xy 37.53719 -179.866838)
			(xy 37.485673 -179.891682) (xy 37.431025 -179.908558) (xy 37.374471 -179.91709) (xy 37.345874 -179.917598)
			(xy 37.318623 -179.91713) (xy 37.264677 -179.909371) (xy 37.212384 -179.894013) (xy 37.162809 -179.87137)
			(xy 37.11696 -179.841902) (xy 37.075772 -179.806209) (xy 37.040082 -179.765019) (xy 37.010618 -179.719168)
			(xy 36.987978 -179.669592) (xy 36.972624 -179.617298) (xy 36.964868 -179.563351) (xy 34.630614 -179.563351)
			(xy 34.630614 -181.176422) (xy 56.742582 -181.176422) (xy 56.746653 -181.1208) (xy 56.758779 -181.066363)
			(xy 56.778702 -181.014272) (xy 56.805998 -180.965637) (xy 56.840084 -180.921494) (xy 56.880233 -180.882785)
			(xy 56.925591 -180.850334) (xy 56.975191 -180.824833) (xy 57.027975 -180.806826) (xy 57.082818 -180.796696)
			(xy 57.138552 -180.794659) (xy 57.193989 -180.800759) (xy 57.247946 -180.814865) (xy 57.299275 -180.836677)
			(xy 57.346881 -180.865731) (xy 57.389749 -180.901406) (xy 57.426966 -180.942943) (xy 57.457739 -180.989456)
			(xy 57.481411 -181.039953) (xy 57.497479 -181.09336) (xy 57.505599 -181.148536) (xy 57.506108 -181.176422)
			(xy 57.505599 -181.204308) (xy 57.497479 -181.259484) (xy 57.481411 -181.312891) (xy 57.457739 -181.363388)
			(xy 57.426966 -181.409901) (xy 57.389749 -181.451438) (xy 57.346881 -181.487113) (xy 57.299275 -181.516167)
			(xy 57.247946 -181.537979) (xy 57.193989 -181.552085) (xy 57.138552 -181.558185) (xy 57.082818 -181.556148)
			(xy 57.027975 -181.546018) (xy 56.975191 -181.528011) (xy 56.925591 -181.50251) (xy 56.880233 -181.470059)
			(xy 56.840084 -181.43135) (xy 56.805998 -181.387207) (xy 56.778702 -181.338572) (xy 56.758779 -181.286481)
			(xy 56.746653 -181.232044) (xy 56.742582 -181.176422) (xy 34.630614 -181.176422) (xy 34.630614 -182.029608)
			(xy 60.308742 -182.029608) (xy 60.312813 -181.973986) (xy 60.324939 -181.919549) (xy 60.344862 -181.867458)
			(xy 60.372158 -181.818823) (xy 60.406244 -181.77468) (xy 60.446393 -181.735971) (xy 60.491751 -181.70352)
			(xy 60.541351 -181.678019) (xy 60.594135 -181.660012) (xy 60.648978 -181.649882) (xy 60.704712 -181.647845)
			(xy 60.760149 -181.653945) (xy 60.814106 -181.668051) (xy 60.865435 -181.689863) (xy 60.913041 -181.718917)
			(xy 60.955909 -181.754592) (xy 60.993126 -181.796129) (xy 61.023899 -181.842642) (xy 61.047571 -181.893139)
			(xy 61.063639 -181.946546) (xy 61.071759 -182.001722) (xy 61.072268 -182.029608) (xy 61.071759 -182.057494)
			(xy 61.063639 -182.11267) (xy 61.047571 -182.166077) (xy 61.023899 -182.216574) (xy 60.993126 -182.263087)
			(xy 60.955909 -182.304624) (xy 60.913041 -182.340299) (xy 60.865435 -182.369353) (xy 60.814106 -182.391165)
			(xy 60.760149 -182.405271) (xy 60.704712 -182.411371) (xy 60.648978 -182.409334) (xy 60.594135 -182.399204)
			(xy 60.541351 -182.381197) (xy 60.491751 -182.355696) (xy 60.446393 -182.323245) (xy 60.406244 -182.284536)
			(xy 60.372158 -182.240393) (xy 60.344862 -182.191758) (xy 60.324939 -182.139667) (xy 60.312813 -182.08523)
			(xy 60.308742 -182.029608) (xy 34.630614 -182.029608) (xy 34.630614 -182.822088) (xy 57.385202 -182.822088)
			(xy 57.389273 -182.766466) (xy 57.401399 -182.712029) (xy 57.421322 -182.659938) (xy 57.448618 -182.611303)
			(xy 57.482704 -182.56716) (xy 57.522853 -182.528451) (xy 57.568211 -182.496) (xy 57.617811 -182.470499)
			(xy 57.670595 -182.452492) (xy 57.725438 -182.442362) (xy 57.781172 -182.440325) (xy 57.836609 -182.446425)
			(xy 57.890566 -182.460531) (xy 57.941895 -182.482343) (xy 57.989501 -182.511397) (xy 58.032369 -182.547072)
			(xy 58.069586 -182.588609) (xy 58.100359 -182.635122) (xy 58.124031 -182.685619) (xy 58.140099 -182.739026)
			(xy 58.148219 -182.794202) (xy 58.148728 -182.822088) (xy 58.148219 -182.849974) (xy 58.140099 -182.90515)
			(xy 58.124031 -182.958557) (xy 58.100359 -183.009054) (xy 58.069586 -183.055567) (xy 58.032369 -183.097104)
			(xy 57.989501 -183.132779) (xy 57.941895 -183.161833) (xy 57.890566 -183.183645) (xy 57.838541 -183.197246)
			(xy 75.07808 -183.197246) (xy 75.082151 -183.141624) (xy 75.094277 -183.087187) (xy 75.1142 -183.035096)
			(xy 75.141496 -182.986461) (xy 75.175582 -182.942318) (xy 75.215731 -182.903609) (xy 75.261089 -182.871158)
			(xy 75.310689 -182.845657) (xy 75.363473 -182.82765) (xy 75.418316 -182.81752) (xy 75.47405 -182.815483)
			(xy 75.529487 -182.821583) (xy 75.583444 -182.835689) (xy 75.634773 -182.857501) (xy 75.682379 -182.886555)
			(xy 75.725247 -182.92223) (xy 75.762464 -182.963767) (xy 75.793237 -183.01028) (xy 75.816909 -183.060777)
			(xy 75.832977 -183.114184) (xy 75.841097 -183.16936) (xy 75.841606 -183.197246) (xy 75.841097 -183.225132)
			(xy 75.832977 -183.280308) (xy 75.816909 -183.333715) (xy 75.793237 -183.384212) (xy 75.762464 -183.430725)
			(xy 75.725247 -183.472262) (xy 75.682379 -183.507937) (xy 75.634773 -183.536991) (xy 75.583444 -183.558803)
			(xy 75.529487 -183.572909) (xy 75.47405 -183.579009) (xy 75.418316 -183.576972) (xy 75.363473 -183.566842)
			(xy 75.310689 -183.548835) (xy 75.261089 -183.523334) (xy 75.215731 -183.490883) (xy 75.175582 -183.452174)
			(xy 75.141496 -183.408031) (xy 75.1142 -183.359396) (xy 75.094277 -183.307305) (xy 75.082151 -183.252868)
			(xy 75.07808 -183.197246) (xy 57.838541 -183.197246) (xy 57.836609 -183.197751) (xy 57.781172 -183.203851)
			(xy 57.725438 -183.201814) (xy 57.670595 -183.191684) (xy 57.617811 -183.173677) (xy 57.568211 -183.148176)
			(xy 57.522853 -183.115725) (xy 57.482704 -183.077016) (xy 57.448618 -183.032873) (xy 57.421322 -182.984238)
			(xy 57.401399 -182.932147) (xy 57.389273 -182.87771) (xy 57.385202 -182.822088) (xy 34.630614 -182.822088)
			(xy 34.630614 -183.328847) (xy 36.977118 -183.328847) (xy 36.977118 -183.274353) (xy 36.984873 -183.220414)
			(xy 37.000225 -183.168128) (xy 37.022861 -183.118558) (xy 37.052321 -183.072714) (xy 37.088005 -183.031529)
			(xy 37.129187 -182.995841) (xy 37.175028 -182.966377) (xy 37.224596 -182.943737) (xy 37.276881 -182.92838)
			(xy 37.330819 -182.92062) (xy 37.358066 -182.920132) (xy 37.386662 -182.920653) (xy 37.443213 -182.929192)
			(xy 37.497858 -182.946069) (xy 37.549375 -182.970906) (xy 37.596612 -183.003149) (xy 37.617908 -183.02224)
			(xy 37.629419 -183.032232) (xy 37.656868 -183.045455) (xy 37.686996 -183.049998) (xy 37.717124 -183.045455)
			(xy 37.744573 -183.032232) (xy 37.756084 -183.02224) (xy 37.777382 -183.00315) (xy 37.824613 -182.970895)
			(xy 37.876129 -182.94605) (xy 37.930775 -182.929172) (xy 37.987329 -182.92064) (xy 38.015926 -182.920132)
			(xy 38.043179 -182.92054) (xy 38.097129 -182.9283) (xy 38.149427 -182.943659) (xy 38.199006 -182.966304)
			(xy 38.244858 -182.995774) (xy 38.286049 -183.031469) (xy 38.321742 -183.072663) (xy 38.351209 -183.118517)
			(xy 38.37385 -183.168098) (xy 38.389206 -183.220396) (xy 38.396962 -183.274347) (xy 38.396962 -183.328847)
			(xy 38.704318 -183.328847) (xy 38.704318 -183.274353) (xy 38.712073 -183.220414) (xy 38.727425 -183.168128)
			(xy 38.750061 -183.118558) (xy 38.779521 -183.072714) (xy 38.815205 -183.031529) (xy 38.856387 -182.995841)
			(xy 38.902228 -182.966377) (xy 38.951796 -182.943737) (xy 39.004081 -182.92838) (xy 39.058019 -182.92062)
			(xy 39.085266 -182.920132) (xy 39.113862 -182.920653) (xy 39.170413 -182.929192) (xy 39.225058 -182.946069)
			(xy 39.276575 -182.970906) (xy 39.323812 -183.003149) (xy 39.345108 -183.02224) (xy 39.356619 -183.032232)
			(xy 39.384068 -183.045455) (xy 39.414196 -183.049998) (xy 39.444324 -183.045455) (xy 39.471773 -183.032232)
			(xy 39.483284 -183.02224) (xy 39.504582 -183.00315) (xy 39.551813 -182.970895) (xy 39.603329 -182.94605)
			(xy 39.657975 -182.929172) (xy 39.714529 -182.92064) (xy 39.743126 -182.920132) (xy 39.770379 -182.92054)
			(xy 39.824329 -182.9283) (xy 39.876627 -182.943659) (xy 39.926206 -182.966304) (xy 39.972058 -182.995774)
			(xy 40.013249 -183.031469) (xy 40.048942 -183.072663) (xy 40.078409 -183.118517) (xy 40.10105 -183.168098)
			(xy 40.116406 -183.220396) (xy 40.124162 -183.274347) (xy 40.124162 -183.328853) (xy 40.116406 -183.382804)
			(xy 40.10105 -183.435102) (xy 40.078409 -183.484683) (xy 40.048942 -183.530537) (xy 40.013249 -183.571731)
			(xy 39.972058 -183.607426) (xy 39.926206 -183.636896) (xy 39.876627 -183.659541) (xy 39.824329 -183.6749)
			(xy 39.770379 -183.68266) (xy 39.743126 -183.683148) (xy 39.714531 -183.682611) (xy 39.657982 -183.674073)
			(xy 39.603338 -183.657198) (xy 39.55182 -183.632365) (xy 39.504582 -183.600128) (xy 39.483284 -183.58104)
			(xy 39.471773 -183.571048) (xy 39.444324 -183.557825) (xy 39.414196 -183.553282) (xy 39.384068 -183.557825)
			(xy 39.356619 -183.571048) (xy 39.345108 -183.58104) (xy 39.32381 -183.600131) (xy 39.27658 -183.632387)
			(xy 39.225064 -183.657231) (xy 39.170417 -183.674109) (xy 39.113863 -183.68264) (xy 39.085266 -183.683148)
			(xy 39.058019 -183.68258) (xy 39.004081 -183.67482) (xy 38.951796 -183.659463) (xy 38.902228 -183.636823)
			(xy 38.856387 -183.607359) (xy 38.815205 -183.571671) (xy 38.779521 -183.530486) (xy 38.750061 -183.484642)
			(xy 38.727425 -183.435072) (xy 38.712073 -183.382786) (xy 38.704318 -183.328847) (xy 38.396962 -183.328847)
			(xy 38.396962 -183.328853) (xy 38.389206 -183.382804) (xy 38.37385 -183.435102) (xy 38.351209 -183.484683)
			(xy 38.321742 -183.530537) (xy 38.286049 -183.571731) (xy 38.244858 -183.607426) (xy 38.199006 -183.636896)
			(xy 38.149427 -183.659541) (xy 38.097129 -183.6749) (xy 38.043179 -183.68266) (xy 38.015926 -183.683148)
			(xy 37.987331 -183.682611) (xy 37.930782 -183.674073) (xy 37.876138 -183.657198) (xy 37.82462 -183.632365)
			(xy 37.777382 -183.600128) (xy 37.756084 -183.58104) (xy 37.744573 -183.571048) (xy 37.717124 -183.557825)
			(xy 37.686996 -183.553282) (xy 37.656868 -183.557825) (xy 37.629419 -183.571048) (xy 37.617908 -183.58104)
			(xy 37.59661 -183.600131) (xy 37.54938 -183.632387) (xy 37.497864 -183.657231) (xy 37.443217 -183.674109)
			(xy 37.386663 -183.68264) (xy 37.358066 -183.683148) (xy 37.330819 -183.68258) (xy 37.276881 -183.67482)
			(xy 37.224596 -183.659463) (xy 37.175028 -183.636823) (xy 37.129187 -183.607359) (xy 37.088005 -183.571671)
			(xy 37.052321 -183.530486) (xy 37.022861 -183.484642) (xy 37.000225 -183.435072) (xy 36.984873 -183.382786)
			(xy 36.977118 -183.328847) (xy 34.630614 -183.328847) (xy 34.630614 -183.514746) (xy 35.016186 -183.900318)
			(xy 56.129174 -183.900318) (xy 56.699404 -184.470548) (xy 66.673982 -184.470548) (xy 66.678053 -184.414926)
			(xy 66.690179 -184.360489) (xy 66.710102 -184.308398) (xy 66.737398 -184.259763) (xy 66.771484 -184.21562)
			(xy 66.811633 -184.176911) (xy 66.856991 -184.14446) (xy 66.906591 -184.118959) (xy 66.959375 -184.100952)
			(xy 67.014218 -184.090822) (xy 67.069952 -184.088785) (xy 67.125389 -184.094885) (xy 67.179346 -184.108991)
			(xy 67.230675 -184.130803) (xy 67.278281 -184.159857) (xy 67.321149 -184.195532) (xy 67.358366 -184.237069)
			(xy 67.389139 -184.283582) (xy 67.412811 -184.334079) (xy 67.428879 -184.387486) (xy 67.436999 -184.442662)
			(xy 67.437508 -184.470548) (xy 67.436999 -184.498434) (xy 67.428879 -184.55361) (xy 67.412811 -184.607017)
			(xy 67.389139 -184.657514) (xy 67.358366 -184.704027) (xy 67.339979 -184.724548) (xy 68.223382 -184.724548)
			(xy 68.227453 -184.668926) (xy 68.239579 -184.614489) (xy 68.259502 -184.562398) (xy 68.286798 -184.513763)
			(xy 68.320884 -184.46962) (xy 68.361033 -184.430911) (xy 68.406391 -184.39846) (xy 68.455991 -184.372959)
			(xy 68.508775 -184.354952) (xy 68.563618 -184.344822) (xy 68.619352 -184.342785) (xy 68.674789 -184.348885)
			(xy 68.728746 -184.362991) (xy 68.780075 -184.384803) (xy 68.827681 -184.413857) (xy 68.870549 -184.449532)
			(xy 68.907766 -184.491069) (xy 68.938539 -184.537582) (xy 68.962211 -184.588079) (xy 68.978279 -184.641486)
			(xy 68.986399 -184.696662) (xy 68.986908 -184.724548) (xy 68.98686 -184.727154) (xy 69.277665 -184.727154)
			(xy 69.277665 -184.672646) (xy 69.285423 -184.618693) (xy 69.300781 -184.566394) (xy 69.323425 -184.516812)
			(xy 69.352896 -184.470959) (xy 69.388593 -184.429766) (xy 69.429789 -184.394073) (xy 69.475646 -184.364607)
			(xy 69.525229 -184.341967) (xy 69.57753 -184.326615) (xy 69.631484 -184.318863) (xy 69.658738 -184.318402)
			(xy 69.690451 -184.319061) (xy 69.752999 -184.329582) (xy 69.812953 -184.350279) (xy 69.84111 -184.364884)
			(xy 69.853841 -184.371276) (xy 69.881619 -184.377528) (xy 69.910043 -184.375855) (xy 69.936896 -184.366388)
			(xy 69.960084 -184.349865) (xy 69.9778 -184.327575) (xy 69.988661 -184.301255) (xy 69.990716 -184.28716)
			(xy 69.994415 -184.259584) (xy 70.008628 -184.205795) (xy 70.030505 -184.154641) (xy 70.05958 -184.107209)
			(xy 70.095239 -184.064504) (xy 70.136723 -184.027432) (xy 70.183153 -183.996781) (xy 70.233543 -183.9732)
			(xy 70.286825 -183.95719) (xy 70.341867 -183.949091) (xy 70.369684 -183.948578) (xy 70.397567 -183.949055)
			(xy 70.452738 -183.957185) (xy 70.506137 -183.97326) (xy 70.556628 -183.996936) (xy 70.603134 -184.027711)
			(xy 70.644665 -184.064927) (xy 70.680336 -184.107793) (xy 70.709387 -184.155395) (xy 70.7312 -184.206719)
			(xy 70.738746 -184.233566) (xy 70.742686 -184.246982) (xy 70.756884 -184.271063) (xy 70.777076 -184.290397)
			(xy 70.801751 -184.303536) (xy 70.829063 -184.309498) (xy 70.856969 -184.307837) (xy 70.870318 -184.30367)
			(xy 70.900508 -184.29394) (xy 70.963065 -184.283472) (xy 70.994778 -184.282842) (xy 71.022035 -184.283203)
			(xy 71.075996 -184.290959) (xy 71.128303 -184.306315) (xy 71.177893 -184.328959) (xy 71.223755 -184.358431)
			(xy 71.264955 -184.394129) (xy 71.300656 -184.435328) (xy 71.33013 -184.481188) (xy 71.352777 -184.530776)
			(xy 71.368136 -184.583083) (xy 71.375895 -184.637043) (xy 71.375895 -184.691557) (xy 71.368136 -184.745517)
			(xy 71.352777 -184.797824) (xy 71.33013 -184.847412) (xy 71.300656 -184.893272) (xy 71.264955 -184.934471)
			(xy 71.223755 -184.970169) (xy 71.177893 -184.999641) (xy 71.128303 -185.022285) (xy 71.086075 -185.034682)
			(xy 71.588882 -185.034682) (xy 71.592953 -184.97906) (xy 71.605079 -184.924623) (xy 71.625002 -184.872532)
			(xy 71.652298 -184.823897) (xy 71.686384 -184.779754) (xy 71.726533 -184.741045) (xy 71.771891 -184.708594)
			(xy 71.821491 -184.683093) (xy 71.874275 -184.665086) (xy 71.929118 -184.654956) (xy 71.984852 -184.652919)
			(xy 72.040289 -184.659019) (xy 72.094246 -184.673125) (xy 72.145575 -184.694937) (xy 72.193181 -184.723991)
			(xy 72.236049 -184.759666) (xy 72.273266 -184.801203) (xy 72.304039 -184.847716) (xy 72.327711 -184.898213)
			(xy 72.328955 -184.902348) (xy 72.724262 -184.902348) (xy 72.728333 -184.846726) (xy 72.740459 -184.792289)
			(xy 72.760382 -184.740198) (xy 72.787678 -184.691563) (xy 72.821764 -184.64742) (xy 72.861913 -184.608711)
			(xy 72.907271 -184.57626) (xy 72.956871 -184.550759) (xy 73.009655 -184.532752) (xy 73.064498 -184.522622)
			(xy 73.120232 -184.520585) (xy 73.175669 -184.526685) (xy 73.229626 -184.540791) (xy 73.280955 -184.562603)
			(xy 73.328561 -184.591657) (xy 73.371429 -184.627332) (xy 73.408646 -184.668869) (xy 73.439419 -184.715382)
			(xy 73.463091 -184.765879) (xy 73.479159 -184.819286) (xy 73.487279 -184.874462) (xy 73.487788 -184.902348)
			(xy 73.48776 -184.903872) (xy 76.98689 -184.903872) (xy 76.990961 -184.84825) (xy 77.003087 -184.793813)
			(xy 77.02301 -184.741722) (xy 77.050306 -184.693087) (xy 77.084392 -184.648944) (xy 77.124541 -184.610235)
			(xy 77.169899 -184.577784) (xy 77.219499 -184.552283) (xy 77.272283 -184.534276) (xy 77.327126 -184.524146)
			(xy 77.38286 -184.522109) (xy 77.438297 -184.528209) (xy 77.492254 -184.542315) (xy 77.543583 -184.564127)
			(xy 77.591189 -184.593181) (xy 77.634057 -184.628856) (xy 77.671274 -184.670393) (xy 77.702047 -184.716906)
			(xy 77.725719 -184.767403) (xy 77.741787 -184.82081) (xy 77.749907 -184.875986) (xy 77.750416 -184.903872)
			(xy 77.749907 -184.931758) (xy 77.741787 -184.986934) (xy 77.725719 -185.040341) (xy 77.702047 -185.090838)
			(xy 77.671274 -185.137351) (xy 77.634057 -185.178888) (xy 77.591189 -185.214563) (xy 77.543583 -185.243617)
			(xy 77.492254 -185.265429) (xy 77.438297 -185.279535) (xy 77.38286 -185.285635) (xy 77.327126 -185.283598)
			(xy 77.272283 -185.273468) (xy 77.219499 -185.255461) (xy 77.169899 -185.22996) (xy 77.124541 -185.197509)
			(xy 77.084392 -185.1588) (xy 77.050306 -185.114657) (xy 77.02301 -185.066022) (xy 77.003087 -185.013931)
			(xy 76.990961 -184.959494) (xy 76.98689 -184.903872) (xy 73.48776 -184.903872) (xy 73.487279 -184.930234)
			(xy 73.479159 -184.98541) (xy 73.463091 -185.038817) (xy 73.439419 -185.089314) (xy 73.408646 -185.135827)
			(xy 73.371429 -185.177364) (xy 73.328561 -185.213039) (xy 73.280955 -185.242093) (xy 73.229626 -185.263905)
			(xy 73.175669 -185.278011) (xy 73.120232 -185.284111) (xy 73.064498 -185.282074) (xy 73.009655 -185.271944)
			(xy 72.956871 -185.253937) (xy 72.907271 -185.228436) (xy 72.861913 -185.195985) (xy 72.821764 -185.157276)
			(xy 72.787678 -185.113133) (xy 72.760382 -185.064498) (xy 72.740459 -185.012407) (xy 72.728333 -184.95797)
			(xy 72.724262 -184.902348) (xy 72.328955 -184.902348) (xy 72.343779 -184.95162) (xy 72.351899 -185.006796)
			(xy 72.352408 -185.034682) (xy 72.351899 -185.062568) (xy 72.343779 -185.117744) (xy 72.327711 -185.171151)
			(xy 72.304039 -185.221648) (xy 72.273266 -185.268161) (xy 72.236049 -185.309698) (xy 72.193181 -185.345373)
			(xy 72.145575 -185.374427) (xy 72.094246 -185.396239) (xy 72.040289 -185.410345) (xy 71.984852 -185.416445)
			(xy 71.929118 -185.414408) (xy 71.874275 -185.404278) (xy 71.821491 -185.386271) (xy 71.771891 -185.36077)
			(xy 71.726533 -185.328319) (xy 71.686384 -185.28961) (xy 71.652298 -185.245467) (xy 71.625002 -185.196832)
			(xy 71.605079 -185.144741) (xy 71.592953 -185.090304) (xy 71.588882 -185.034682) (xy 71.086075 -185.034682)
			(xy 71.075996 -185.037641) (xy 71.022035 -185.045397) (xy 70.994778 -185.045858) (xy 70.966898 -185.045298)
			(xy 70.911732 -185.037178) (xy 70.858336 -185.021113) (xy 70.807847 -184.997447) (xy 70.761342 -184.966683)
			(xy 70.71981 -184.929477) (xy 70.684137 -184.886621) (xy 70.655082 -184.839028) (xy 70.633265 -184.787713)
			(xy 70.625716 -184.76087) (xy 70.621683 -184.747485) (xy 70.607504 -184.72341) (xy 70.587332 -184.704077)
			(xy 70.562676 -184.690932) (xy 70.535381 -184.684961) (xy 70.507488 -184.686608) (xy 70.494144 -184.690766)
			(xy 70.463956 -184.700504) (xy 70.401398 -184.710967) (xy 70.369684 -184.711594) (xy 70.337972 -184.710926)
			(xy 70.275424 -184.700409) (xy 70.215469 -184.679715) (xy 70.187312 -184.665112) (xy 70.174567 -184.65875)
			(xy 70.146794 -184.652495) (xy 70.118374 -184.654163) (xy 70.091525 -184.663625) (xy 70.068338 -184.680143)
			(xy 70.050623 -184.702428) (xy 70.039761 -184.728743) (xy 70.037706 -184.742836) (xy 70.03416 -184.770435)
			(xy 70.01993 -184.824232) (xy 69.998036 -184.87539) (xy 69.968943 -184.922825) (xy 69.933266 -184.96553)
			(xy 69.891765 -185.002599) (xy 69.845318 -185.033246) (xy 69.794912 -185.05682) (xy 69.741616 -185.072822)
			(xy 69.686561 -185.080911) (xy 69.658738 -185.081418) (xy 69.631484 -185.080937) (xy 69.57753 -185.073185)
			(xy 69.525229 -185.057833) (xy 69.475646 -185.035193) (xy 69.429789 -185.005727) (xy 69.388593 -184.970034)
			(xy 69.352896 -184.928841) (xy 69.323425 -184.882988) (xy 69.300781 -184.833406) (xy 69.285423 -184.781107)
			(xy 69.277665 -184.727154) (xy 68.98686 -184.727154) (xy 68.986399 -184.752434) (xy 68.978279 -184.80761)
			(xy 68.962211 -184.861017) (xy 68.938539 -184.911514) (xy 68.907766 -184.958027) (xy 68.870549 -184.999564)
			(xy 68.827681 -185.035239) (xy 68.780075 -185.064293) (xy 68.728746 -185.086105) (xy 68.674789 -185.100211)
			(xy 68.619352 -185.106311) (xy 68.563618 -185.104274) (xy 68.508775 -185.094144) (xy 68.455991 -185.076137)
			(xy 68.406391 -185.050636) (xy 68.361033 -185.018185) (xy 68.320884 -184.979476) (xy 68.286798 -184.935333)
			(xy 68.259502 -184.886698) (xy 68.239579 -184.834607) (xy 68.227453 -184.78017) (xy 68.223382 -184.724548)
			(xy 67.339979 -184.724548) (xy 67.321149 -184.745564) (xy 67.278281 -184.781239) (xy 67.230675 -184.810293)
			(xy 67.179346 -184.832105) (xy 67.125389 -184.846211) (xy 67.069952 -184.852311) (xy 67.014218 -184.850274)
			(xy 66.959375 -184.840144) (xy 66.906591 -184.822137) (xy 66.856991 -184.796636) (xy 66.811633 -184.764185)
			(xy 66.771484 -184.725476) (xy 66.737398 -184.681333) (xy 66.710102 -184.632698) (xy 66.690179 -184.580607)
			(xy 66.678053 -184.52617) (xy 66.673982 -184.470548) (xy 56.699404 -184.470548) (xy 57.893204 -185.664348)
			(xy 67.359782 -185.664348) (xy 67.363853 -185.608726) (xy 67.375979 -185.554289) (xy 67.395902 -185.502198)
			(xy 67.423198 -185.453563) (xy 67.457284 -185.40942) (xy 67.497433 -185.370711) (xy 67.542791 -185.33826)
			(xy 67.592391 -185.312759) (xy 67.645175 -185.294752) (xy 67.700018 -185.284622) (xy 67.755752 -185.282585)
			(xy 67.811189 -185.288685) (xy 67.865146 -185.302791) (xy 67.916475 -185.324603) (xy 67.964081 -185.353657)
			(xy 68.006949 -185.389332) (xy 68.044166 -185.430869) (xy 68.074939 -185.477382) (xy 68.098611 -185.527879)
			(xy 68.114679 -185.581286) (xy 68.122799 -185.636462) (xy 68.123308 -185.664348) (xy 68.122799 -185.692234)
			(xy 68.114679 -185.74741) (xy 68.098611 -185.800817) (xy 68.074939 -185.851314) (xy 68.044166 -185.897827)
			(xy 68.006949 -185.939364) (xy 67.964081 -185.975039) (xy 67.916475 -186.004093) (xy 67.865146 -186.025905)
			(xy 67.811189 -186.040011) (xy 67.755752 -186.046111) (xy 67.700018 -186.044074) (xy 67.645175 -186.033944)
			(xy 67.592391 -186.015937) (xy 67.542791 -185.990436) (xy 67.497433 -185.957985) (xy 67.457284 -185.919276)
			(xy 67.423198 -185.875133) (xy 67.395902 -185.826498) (xy 67.375979 -185.774407) (xy 67.363853 -185.71997)
			(xy 67.359782 -185.664348) (xy 57.893204 -185.664348) (xy 58.299604 -186.070748) (xy 71.844914 -186.070748)
			(xy 71.848985 -186.015126) (xy 71.861111 -185.960689) (xy 71.881034 -185.908598) (xy 71.90833 -185.859963)
			(xy 71.942416 -185.81582) (xy 71.982565 -185.777111) (xy 72.027923 -185.74466) (xy 72.077523 -185.719159)
			(xy 72.130307 -185.701152) (xy 72.18515 -185.691022) (xy 72.240884 -185.688985) (xy 72.296321 -185.695085)
			(xy 72.350278 -185.709191) (xy 72.401607 -185.731003) (xy 72.449213 -185.760057) (xy 72.492081 -185.795732)
			(xy 72.529298 -185.837269) (xy 72.560071 -185.883782) (xy 72.583743 -185.934279) (xy 72.599811 -185.987686)
			(xy 72.607931 -186.042862) (xy 72.60844 -186.070748) (xy 72.607931 -186.098634) (xy 72.599811 -186.15381)
			(xy 72.583743 -186.207217) (xy 72.560071 -186.257714) (xy 72.529298 -186.304227) (xy 72.492081 -186.345764)
			(xy 72.449213 -186.381439) (xy 72.401607 -186.410493) (xy 72.350278 -186.432305) (xy 72.296321 -186.446411)
			(xy 72.240884 -186.452511) (xy 72.18515 -186.450474) (xy 72.130307 -186.440344) (xy 72.077523 -186.422337)
			(xy 72.027923 -186.396836) (xy 71.982565 -186.364385) (xy 71.942416 -186.325676) (xy 71.90833 -186.281533)
			(xy 71.881034 -186.232898) (xy 71.861111 -186.180807) (xy 71.848985 -186.12637) (xy 71.844914 -186.070748)
			(xy 58.299604 -186.070748) (xy 58.639202 -186.410346) (xy 65.509394 -186.410346) (xy 65.984374 -186.885326)
			(xy 68.972669 -186.885326) (xy 68.972673 -186.830821) (xy 68.980434 -186.776872) (xy 68.995794 -186.724577)
			(xy 69.018439 -186.675) (xy 69.04791 -186.62915) (xy 69.083606 -186.587961) (xy 69.124801 -186.552272)
			(xy 69.170656 -186.522809) (xy 69.220237 -186.500171) (xy 69.272535 -186.48482) (xy 69.326485 -186.477069)
			(xy 69.380989 -186.477074) (xy 69.434938 -186.484836) (xy 69.487233 -186.500197) (xy 69.53681 -186.522844)
			(xy 69.582659 -186.552317) (xy 69.623846 -186.588014) (xy 69.659535 -186.62921) (xy 69.688997 -186.675065)
			(xy 69.711633 -186.724647) (xy 69.726982 -186.776945) (xy 69.734732 -186.830896) (xy 69.735192 -186.858148)
			(xy 69.734654 -186.887184) (xy 69.725848 -186.944584) (xy 69.717666 -186.972448) (xy 69.71357 -186.986898)
			(xy 69.713186 -187.01692) (xy 69.721548 -187.045756) (xy 69.737933 -187.070914) (xy 69.760925 -187.090222)
			(xy 69.788538 -187.102011) (xy 69.818385 -187.105262) (xy 69.833236 -187.103004) (xy 69.850599 -187.09993)
			(xy 69.885708 -187.096621) (xy 69.90334 -187.0964) (xy 69.921882 -187.096908) (xy 69.936661 -187.097167)
			(xy 69.96534 -187.090049) (xy 69.990791 -187.075034) (xy 70.010893 -187.053375) (xy 70.02397 -187.026877)
			(xy 70.028933 -186.997747) (xy 70.025368 -186.968413) (xy 70.019926 -186.954668) (xy 70.009877 -186.930533)
			(xy 69.995738 -186.8802) (xy 69.988603 -186.828408) (xy 69.988176 -186.802268) (xy 69.988662 -186.775017)
			(xy 69.996418 -186.721069) (xy 70.011773 -186.668774) (xy 70.034415 -186.619197) (xy 70.063881 -186.573347)
			(xy 70.099572 -186.532156) (xy 70.140763 -186.496465) (xy 70.186613 -186.466999) (xy 70.23619 -186.444357)
			(xy 70.288485 -186.429002) (xy 70.342433 -186.421246) (xy 70.396935 -186.421246) (xy 70.450883 -186.429002)
			(xy 70.503178 -186.444357) (xy 70.552755 -186.466999) (xy 70.598605 -186.496465) (xy 70.639796 -186.532156)
			(xy 70.675487 -186.573347) (xy 70.704953 -186.619197) (xy 70.727595 -186.668774) (xy 70.74295 -186.721069)
			(xy 70.748525 -186.75985) (xy 73.05878 -186.75985) (xy 73.062851 -186.704228) (xy 73.074977 -186.649791)
			(xy 73.0949 -186.5977) (xy 73.122196 -186.549065) (xy 73.156282 -186.504922) (xy 73.196431 -186.466213)
			(xy 73.241789 -186.433762) (xy 73.291389 -186.408261) (xy 73.344173 -186.390254) (xy 73.399016 -186.380124)
			(xy 73.45475 -186.378087) (xy 73.510187 -186.384187) (xy 73.564144 -186.398293) (xy 73.615473 -186.420105)
			(xy 73.663079 -186.449159) (xy 73.705947 -186.484834) (xy 73.743164 -186.526371) (xy 73.773937 -186.572884)
			(xy 73.797609 -186.623381) (xy 73.813677 -186.676788) (xy 73.821797 -186.731964) (xy 73.822306 -186.75985)
			(xy 73.821797 -186.787736) (xy 73.813677 -186.842912) (xy 73.797609 -186.896319) (xy 73.773937 -186.946816)
			(xy 73.743164 -186.993329) (xy 73.736156 -187.00115) (xy 80.78546 -187.00115) (xy 80.789531 -186.945528)
			(xy 80.801657 -186.891091) (xy 80.82158 -186.839) (xy 80.848876 -186.790365) (xy 80.882962 -186.746222)
			(xy 80.923111 -186.707513) (xy 80.968469 -186.675062) (xy 81.018069 -186.649561) (xy 81.070853 -186.631554)
			(xy 81.125696 -186.621424) (xy 81.18143 -186.619387) (xy 81.236867 -186.625487) (xy 81.290824 -186.639593)
			(xy 81.342153 -186.661405) (xy 81.389759 -186.690459) (xy 81.432627 -186.726134) (xy 81.469844 -186.767671)
			(xy 81.500617 -186.814184) (xy 81.524289 -186.864681) (xy 81.540357 -186.918088) (xy 81.548477 -186.973264)
			(xy 81.548986 -187.00115) (xy 81.548477 -187.029036) (xy 81.540357 -187.084212) (xy 81.524289 -187.137619)
			(xy 81.500617 -187.188116) (xy 81.469844 -187.234629) (xy 81.432627 -187.276166) (xy 81.389759 -187.311841)
			(xy 81.342153 -187.340895) (xy 81.290824 -187.362707) (xy 81.236867 -187.376813) (xy 81.18143 -187.382913)
			(xy 81.125696 -187.380876) (xy 81.070853 -187.370746) (xy 81.018069 -187.352739) (xy 80.968469 -187.327238)
			(xy 80.923111 -187.294787) (xy 80.882962 -187.256078) (xy 80.848876 -187.211935) (xy 80.82158 -187.1633)
			(xy 80.801657 -187.111209) (xy 80.789531 -187.056772) (xy 80.78546 -187.00115) (xy 73.736156 -187.00115)
			(xy 73.705947 -187.034866) (xy 73.663079 -187.070541) (xy 73.615473 -187.099595) (xy 73.564144 -187.121407)
			(xy 73.510187 -187.135513) (xy 73.45475 -187.141613) (xy 73.399016 -187.139576) (xy 73.344173 -187.129446)
			(xy 73.291389 -187.111439) (xy 73.241789 -187.085938) (xy 73.196431 -187.053487) (xy 73.156282 -187.014778)
			(xy 73.122196 -186.970635) (xy 73.0949 -186.922) (xy 73.074977 -186.869909) (xy 73.062851 -186.815472)
			(xy 73.05878 -186.75985) (xy 70.748525 -186.75985) (xy 70.750706 -186.775017) (xy 70.751192 -186.802268)
			(xy 70.750802 -186.827993) (xy 70.743903 -186.878978) (xy 70.730198 -186.928568) (xy 70.720458 -186.952382)
			(xy 70.715629 -186.964779) (xy 70.711855 -186.991103) (xy 70.715011 -187.017509) (xy 70.724882 -187.042203)
			(xy 70.740797 -187.063508) (xy 70.761677 -187.079977) (xy 70.786104 -187.090493) (xy 70.799198 -187.092844)
			(xy 70.824135 -187.096895) (xy 70.87273 -187.110708) (xy 70.919072 -187.130823) (xy 70.962349 -187.156888)
			(xy 70.982332 -187.172346) (xy 70.99423 -187.18117) (xy 71.021681 -187.192256) (xy 71.051158 -187.195003)
			(xy 71.080185 -187.189182) (xy 71.106324 -187.175282) (xy 71.117206 -187.165234) (xy 71.138796 -187.144688)
			(xy 71.187133 -187.109828) (xy 71.240305 -187.082911) (xy 71.297016 -187.064593) (xy 71.355886 -187.05532)
			(xy 71.385684 -187.054744) (xy 71.412934 -187.055302) (xy 71.46688 -187.063056) (xy 71.519173 -187.078409)
			(xy 71.568749 -187.101048) (xy 71.614599 -187.130512) (xy 71.655788 -187.166201) (xy 71.691479 -187.207389)
			(xy 71.720945 -187.253237) (xy 71.743585 -187.302812) (xy 71.75894 -187.355104) (xy 71.766697 -187.40905)
			(xy 71.766697 -187.442856) (xy 72.019666 -187.442856) (xy 72.023737 -187.387234) (xy 72.035863 -187.332797)
			(xy 72.055786 -187.280706) (xy 72.083082 -187.232071) (xy 72.117168 -187.187928) (xy 72.157317 -187.149219)
			(xy 72.202675 -187.116768) (xy 72.252275 -187.091267) (xy 72.305059 -187.07326) (xy 72.359902 -187.06313)
			(xy 72.415636 -187.061093) (xy 72.471073 -187.067193) (xy 72.52503 -187.081299) (xy 72.576359 -187.103111)
			(xy 72.623965 -187.132165) (xy 72.666833 -187.16784) (xy 72.70405 -187.209377) (xy 72.734823 -187.25589)
			(xy 72.758495 -187.306387) (xy 72.774563 -187.359794) (xy 72.782683 -187.41497) (xy 72.783192 -187.442856)
			(xy 72.782683 -187.470742) (xy 72.774563 -187.525918) (xy 72.758495 -187.579325) (xy 72.734823 -187.629822)
			(xy 72.70405 -187.676335) (xy 72.666833 -187.717872) (xy 72.623965 -187.753547) (xy 72.576359 -187.782601)
			(xy 72.52503 -187.804413) (xy 72.471073 -187.818519) (xy 72.415636 -187.824619) (xy 72.359902 -187.822582)
			(xy 72.305059 -187.812452) (xy 72.252275 -187.794445) (xy 72.202675 -187.768944) (xy 72.157317 -187.736493)
			(xy 72.117168 -187.697784) (xy 72.083082 -187.653641) (xy 72.055786 -187.605006) (xy 72.035863 -187.552915)
			(xy 72.023737 -187.498478) (xy 72.019666 -187.442856) (xy 71.766697 -187.442856) (xy 71.766697 -187.46355)
			(xy 71.75894 -187.517496) (xy 71.743585 -187.569788) (xy 71.720945 -187.619363) (xy 71.691479 -187.665211)
			(xy 71.655788 -187.706399) (xy 71.614599 -187.742088) (xy 71.568749 -187.771552) (xy 71.519173 -187.794191)
			(xy 71.46688 -187.809544) (xy 71.412934 -187.817298) (xy 71.385684 -187.81776) (xy 71.35994 -187.81735)
			(xy 71.308921 -187.810412) (xy 71.259299 -187.796679) (xy 71.211972 -187.7764) (xy 71.167802 -187.749942)
			(xy 71.147432 -187.734194) (xy 71.135555 -187.725342) (xy 71.108095 -187.714268) (xy 71.078614 -187.71153)
			(xy 71.049584 -187.717356) (xy 71.023442 -187.731258) (xy 71.012558 -187.741306) (xy 70.99099 -187.761876)
			(xy 70.942646 -187.796732) (xy 70.889469 -187.823643) (xy 70.832753 -187.841956) (xy 70.773879 -187.851223)
			(xy 70.74408 -187.851796) (xy 70.715555 -187.851274) (xy 70.659142 -187.842762) (xy 70.604625 -187.825948)
			(xy 70.553218 -187.801204) (xy 70.506069 -187.769083) (xy 70.464226 -187.730301) (xy 70.428624 -187.685721)
			(xy 70.41388 -187.661296) (xy 70.40679 -187.649881) (xy 70.387768 -187.630918) (xy 70.364454 -187.617578)
			(xy 70.338467 -187.610788) (xy 70.311608 -187.611017) (xy 70.28574 -187.61825) (xy 70.262658 -187.631985)
			(xy 70.243962 -187.651271) (xy 70.237096 -187.66282) (xy 70.22256 -187.687959) (xy 70.187031 -187.733889)
			(xy 70.144955 -187.773908) (xy 70.097302 -187.807092) (xy 70.045174 -187.832676) (xy 69.989772 -187.850069)
			(xy 69.932374 -187.85887) (xy 69.90334 -187.859416) (xy 69.876088 -187.858908) (xy 69.82214 -187.851156)
			(xy 69.769843 -187.835806) (xy 69.720264 -187.813168) (xy 69.674411 -187.783705) (xy 69.633218 -187.748016)
			(xy 69.597524 -187.706828) (xy 69.568055 -187.660979) (xy 69.545411 -187.611402) (xy 69.530054 -187.559107)
			(xy 69.522296 -187.505159) (xy 69.521832 -187.477908) (xy 69.522381 -187.448873) (xy 69.531179 -187.391473)
			(xy 69.539358 -187.363608) (xy 69.543364 -187.349136) (xy 69.54376 -187.319127) (xy 69.535412 -187.290301)
			(xy 69.519042 -187.265147) (xy 69.496065 -187.245841) (xy 69.468467 -187.234052) (xy 69.438633 -187.230797)
			(xy 69.423788 -187.233052) (xy 69.406424 -187.236122) (xy 69.371316 -187.239434) (xy 69.353684 -187.239656)
			(xy 69.326432 -187.239128) (xy 69.272483 -187.231368) (xy 69.220187 -187.21601) (xy 69.170609 -187.193366)
			(xy 69.124758 -187.163896) (xy 69.083569 -187.128201) (xy 69.047878 -187.087007) (xy 69.018414 -187.041154)
			(xy 68.995775 -186.991573) (xy 68.980423 -186.939276) (xy 68.972669 -186.885326) (xy 65.984374 -186.885326)
			(xy 66.58569 -187.486642) (xy 67.775104 -187.486642) (xy 67.775105 -187.432146) (xy 67.782861 -187.378203)
			(xy 67.798215 -187.325914) (xy 67.820854 -187.276342) (xy 67.850317 -187.230496) (xy 67.886004 -187.18931)
			(xy 67.92719 -187.153622) (xy 67.973035 -187.124157) (xy 68.022607 -187.101518) (xy 68.074896 -187.086163)
			(xy 68.128838 -187.078405) (xy 68.183334 -187.078403) (xy 68.237277 -187.086157) (xy 68.289567 -187.101508)
			(xy 68.33914 -187.124144) (xy 68.384988 -187.153605) (xy 68.426176 -187.18929) (xy 68.461866 -187.230474)
			(xy 68.491333 -187.276317) (xy 68.513975 -187.325888) (xy 68.529333 -187.378176) (xy 68.537093 -187.432118)
			(xy 68.537582 -187.459366) (xy 68.537474 -187.473388) (xy 68.53544 -187.501356) (xy 68.533518 -187.515246)
			(xy 68.531778 -187.530214) (xy 68.536199 -187.560008) (xy 68.549127 -187.587212) (xy 68.569435 -187.609456)
			(xy 68.595354 -187.624801) (xy 68.624624 -187.631909) (xy 68.63969 -187.631578) (xy 68.661788 -187.63107)
			(xy 68.689042 -187.631542) (xy 68.742996 -187.639298) (xy 68.795297 -187.654653) (xy 68.84488 -187.677296)
			(xy 68.890736 -187.706764) (xy 68.931932 -187.742459) (xy 68.967628 -187.783653) (xy 68.997098 -187.829509)
			(xy 69.019742 -187.879091) (xy 69.023735 -187.89269) (xy 73.29754 -187.89269) (xy 73.301611 -187.837068)
			(xy 73.313737 -187.782631) (xy 73.33366 -187.73054) (xy 73.360956 -187.681905) (xy 73.395042 -187.637762)
			(xy 73.435191 -187.599053) (xy 73.480549 -187.566602) (xy 73.530149 -187.541101) (xy 73.582933 -187.523094)
			(xy 73.637776 -187.512964) (xy 73.69351 -187.510927) (xy 73.748947 -187.517027) (xy 73.802904 -187.531133)
			(xy 73.854233 -187.552945) (xy 73.901839 -187.581999) (xy 73.944707 -187.617674) (xy 73.981924 -187.659211)
			(xy 74.012697 -187.705724) (xy 74.036369 -187.756221) (xy 74.052437 -187.809628) (xy 74.060557 -187.864804)
			(xy 74.061066 -187.89269) (xy 74.060557 -187.920576) (xy 74.052437 -187.975752) (xy 74.036369 -188.029159)
			(xy 74.012697 -188.079656) (xy 73.981924 -188.126169) (xy 73.944707 -188.167706) (xy 73.901839 -188.203381)
			(xy 73.854233 -188.232435) (xy 73.802904 -188.254247) (xy 73.748947 -188.268353) (xy 73.69351 -188.274453)
			(xy 73.637776 -188.272416) (xy 73.582933 -188.262286) (xy 73.530149 -188.244279) (xy 73.480549 -188.218778)
			(xy 73.435191 -188.186327) (xy 73.395042 -188.147618) (xy 73.360956 -188.103475) (xy 73.33366 -188.05484)
			(xy 73.313737 -188.002749) (xy 73.301611 -187.948312) (xy 73.29754 -187.89269) (xy 69.023735 -187.89269)
			(xy 69.035099 -187.931391) (xy 69.042857 -187.985345) (xy 69.042857 -188.039854) (xy 69.0351 -188.093807)
			(xy 69.019743 -188.146108) (xy 68.997099 -188.19569) (xy 68.967629 -188.241546) (xy 68.931933 -188.28274)
			(xy 68.890738 -188.318435) (xy 68.844882 -188.347904) (xy 68.795298 -188.370546) (xy 68.742997 -188.385902)
			(xy 68.689044 -188.393658) (xy 68.634535 -188.393656) (xy 68.580582 -188.385897) (xy 68.528282 -188.370539)
			(xy 68.4787 -188.347893) (xy 68.432845 -188.318422) (xy 68.391652 -188.282725) (xy 68.355958 -188.241528)
			(xy 68.326491 -188.195672) (xy 68.30385 -188.146088) (xy 68.288496 -188.093786) (xy 68.280741 -188.039832)
			(xy 68.28028 -188.012578) (xy 68.280383 -187.998556) (xy 68.28242 -187.970587) (xy 68.284344 -187.956698)
			(xy 68.28608 -187.941728) (xy 68.281669 -187.91193) (xy 68.268745 -187.884721) (xy 68.248435 -187.862474)
			(xy 68.222513 -187.847131) (xy 68.193239 -187.84003) (xy 68.178172 -187.840366) (xy 68.156074 -187.840874)
			(xy 68.128826 -187.840394) (xy 68.074884 -187.832635) (xy 68.022595 -187.817278) (xy 67.973024 -187.794637)
			(xy 67.92718 -187.765171) (xy 67.885996 -187.729482) (xy 67.85031 -187.688294) (xy 67.820848 -187.642447)
			(xy 67.798211 -187.592875) (xy 67.782858 -187.540585) (xy 67.775104 -187.486642) (xy 66.58569 -187.486642)
			(xy 68.500752 -189.401704) (xy 68.511869 -189.411977) (xy 68.538624 -189.426097) (xy 68.568338 -189.43178)
			(xy 68.598415 -189.42853) (xy 68.626229 -189.416631) (xy 68.649351 -189.397121) (xy 68.657978 -189.384686)
			(xy 68.673127 -189.362055) (xy 68.708822 -189.320925) (xy 68.750004 -189.28529) (xy 68.795835 -189.255875)
			(xy 68.845384 -189.233276) (xy 68.897643 -189.217954) (xy 68.95155 -189.210221) (xy 68.97878 -189.20968)
			(xy 69.006069 -189.210145) (xy 69.060088 -189.217925) (xy 69.112446 -189.23333) (xy 69.162072 -189.256043)
			(xy 69.207952 -189.285602) (xy 69.249148 -189.321401) (xy 69.267324 -189.34176) (xy 69.276415 -189.35165)
			(xy 69.298666 -189.366683) (xy 69.324067 -189.375394) (xy 69.350861 -189.377181) (xy 69.377194 -189.37192)
			(xy 69.401245 -189.359976) (xy 69.411596 -189.351412) (xy 69.432629 -189.333421) (xy 69.478915 -189.303073)
			(xy 69.529103 -189.279739) (xy 69.582139 -189.263909) (xy 69.636906 -189.255916) (xy 69.66458 -189.2554)
			(xy 69.691764 -189.25588) (xy 69.745581 -189.263595) (xy 69.797758 -189.278873) (xy 69.847238 -189.301404)
			(xy 69.893018 -189.33073) (xy 69.93417 -189.366259) (xy 69.952362 -189.386464) (xy 69.961833 -189.396633)
			(xy 69.98504 -189.411899) (xy 70.011503 -189.420341) (xy 70.039262 -189.421335) (xy 70.066261 -189.414807)
			(xy 70.0905 -189.40124) (xy 70.100698 -189.391798) (xy 70.12229 -189.37115) (xy 70.170701 -189.336148)
			(xy 70.223974 -189.309115) (xy 70.280807 -189.290712) (xy 70.339815 -189.281387) (xy 70.369684 -189.2808)
			(xy 70.396937 -189.281262) (xy 70.450889 -189.289017) (xy 70.503187 -189.304372) (xy 70.552768 -189.327013)
			(xy 70.598622 -189.35648) (xy 70.639816 -189.392172) (xy 70.675511 -189.433365) (xy 70.70498 -189.479218)
			(xy 70.727623 -189.528798) (xy 70.742979 -189.581096) (xy 70.750737 -189.635047) (xy 70.750737 -189.662308)
			(xy 71.003666 -189.662308) (xy 71.007737 -189.606686) (xy 71.019863 -189.552249) (xy 71.039786 -189.500158)
			(xy 71.067082 -189.451523) (xy 71.101168 -189.40738) (xy 71.141317 -189.368671) (xy 71.186675 -189.33622)
			(xy 71.236275 -189.310719) (xy 71.289059 -189.292712) (xy 71.343902 -189.282582) (xy 71.399636 -189.280545)
			(xy 71.455073 -189.286645) (xy 71.50903 -189.300751) (xy 71.560359 -189.322563) (xy 71.607965 -189.351617)
			(xy 71.650833 -189.387292) (xy 71.68805 -189.428829) (xy 71.718823 -189.475342) (xy 71.742495 -189.525839)
			(xy 71.758563 -189.579246) (xy 71.766683 -189.634422) (xy 71.767192 -189.662308) (xy 72.019666 -189.662308)
			(xy 72.023737 -189.606686) (xy 72.035863 -189.552249) (xy 72.055786 -189.500158) (xy 72.083082 -189.451523)
			(xy 72.117168 -189.40738) (xy 72.157317 -189.368671) (xy 72.202675 -189.33622) (xy 72.252275 -189.310719)
			(xy 72.305059 -189.292712) (xy 72.359902 -189.282582) (xy 72.415636 -189.280545) (xy 72.471073 -189.286645)
			(xy 72.52503 -189.300751) (xy 72.545026 -189.309248) (xy 73.450702 -189.309248) (xy 73.454773 -189.253626)
			(xy 73.466899 -189.199189) (xy 73.486822 -189.147098) (xy 73.514118 -189.098463) (xy 73.548204 -189.05432)
			(xy 73.588353 -189.015611) (xy 73.633711 -188.98316) (xy 73.683311 -188.957659) (xy 73.736095 -188.939652)
			(xy 73.790938 -188.929522) (xy 73.846672 -188.927485) (xy 73.902109 -188.933585) (xy 73.956066 -188.947691)
			(xy 74.007395 -188.969503) (xy 74.055001 -188.998557) (xy 74.097869 -189.034232) (xy 74.135086 -189.075769)
			(xy 74.165859 -189.122282) (xy 74.189531 -189.172779) (xy 74.205599 -189.226186) (xy 74.213719 -189.281362)
			(xy 74.214228 -189.309248) (xy 74.213719 -189.337134) (xy 74.205599 -189.39231) (xy 74.189531 -189.445717)
			(xy 74.165859 -189.496214) (xy 74.135086 -189.542727) (xy 74.097869 -189.584264) (xy 74.055001 -189.619939)
			(xy 74.007395 -189.648993) (xy 73.956066 -189.670805) (xy 73.902109 -189.684911) (xy 73.846672 -189.691011)
			(xy 73.790938 -189.688974) (xy 73.736095 -189.678844) (xy 73.683311 -189.660837) (xy 73.633711 -189.635336)
			(xy 73.588353 -189.602885) (xy 73.548204 -189.564176) (xy 73.514118 -189.520033) (xy 73.486822 -189.471398)
			(xy 73.466899 -189.419307) (xy 73.454773 -189.36487) (xy 73.450702 -189.309248) (xy 72.545026 -189.309248)
			(xy 72.576359 -189.322563) (xy 72.623965 -189.351617) (xy 72.666833 -189.387292) (xy 72.70405 -189.428829)
			(xy 72.734823 -189.475342) (xy 72.758495 -189.525839) (xy 72.774563 -189.579246) (xy 72.782683 -189.634422)
			(xy 72.783192 -189.662308) (xy 72.782683 -189.690194) (xy 72.776208 -189.73419) (xy 80.3816 -189.73419)
			(xy 80.385671 -189.678568) (xy 80.397797 -189.624131) (xy 80.41772 -189.57204) (xy 80.445016 -189.523405)
			(xy 80.479102 -189.479262) (xy 80.519251 -189.440553) (xy 80.564609 -189.408102) (xy 80.614209 -189.382601)
			(xy 80.666993 -189.364594) (xy 80.721836 -189.354464) (xy 80.77757 -189.352427) (xy 80.833007 -189.358527)
			(xy 80.886964 -189.372633) (xy 80.938293 -189.394445) (xy 80.985899 -189.423499) (xy 81.028767 -189.459174)
			(xy 81.065984 -189.500711) (xy 81.096757 -189.547224) (xy 81.120429 -189.597721) (xy 81.123354 -189.607444)
			(xy 85.075266 -189.607444) (xy 85.079337 -189.551822) (xy 85.091463 -189.497385) (xy 85.111386 -189.445294)
			(xy 85.138682 -189.396659) (xy 85.172768 -189.352516) (xy 85.212917 -189.313807) (xy 85.258275 -189.281356)
			(xy 85.307875 -189.255855) (xy 85.360659 -189.237848) (xy 85.415502 -189.227718) (xy 85.471236 -189.225681)
			(xy 85.526673 -189.231781) (xy 85.58063 -189.245887) (xy 85.631959 -189.267699) (xy 85.679565 -189.296753)
			(xy 85.722433 -189.332428) (xy 85.75965 -189.373965) (xy 85.790423 -189.420478) (xy 85.814095 -189.470975)
			(xy 85.830163 -189.524382) (xy 85.838283 -189.579558) (xy 85.838792 -189.607444) (xy 85.838283 -189.63533)
			(xy 85.830163 -189.690506) (xy 85.814095 -189.743913) (xy 85.790423 -189.79441) (xy 85.75965 -189.840923)
			(xy 85.722433 -189.88246) (xy 85.679565 -189.918135) (xy 85.631959 -189.947189) (xy 85.58063 -189.969001)
			(xy 85.526673 -189.983107) (xy 85.471236 -189.989207) (xy 85.415502 -189.98717) (xy 85.360659 -189.97704)
			(xy 85.307875 -189.959033) (xy 85.258275 -189.933532) (xy 85.212917 -189.901081) (xy 85.172768 -189.862372)
			(xy 85.138682 -189.818229) (xy 85.111386 -189.769594) (xy 85.091463 -189.717503) (xy 85.079337 -189.663066)
			(xy 85.075266 -189.607444) (xy 81.123354 -189.607444) (xy 81.136497 -189.651128) (xy 81.144617 -189.706304)
			(xy 81.145126 -189.73419) (xy 81.144617 -189.762076) (xy 81.136497 -189.817252) (xy 81.120429 -189.870659)
			(xy 81.096757 -189.921156) (xy 81.065984 -189.967669) (xy 81.028767 -190.009206) (xy 80.985899 -190.044881)
			(xy 80.938293 -190.073935) (xy 80.886964 -190.095747) (xy 80.833007 -190.109853) (xy 80.77757 -190.115953)
			(xy 80.721836 -190.113916) (xy 80.666993 -190.103786) (xy 80.614209 -190.085779) (xy 80.564609 -190.060278)
			(xy 80.519251 -190.027827) (xy 80.479102 -189.989118) (xy 80.445016 -189.944975) (xy 80.41772 -189.89634)
			(xy 80.397797 -189.844249) (xy 80.385671 -189.789812) (xy 80.3816 -189.73419) (xy 72.776208 -189.73419)
			(xy 72.774563 -189.74537) (xy 72.758495 -189.798777) (xy 72.734823 -189.849274) (xy 72.70405 -189.895787)
			(xy 72.666833 -189.937324) (xy 72.623965 -189.972999) (xy 72.576359 -190.002053) (xy 72.52503 -190.023865)
			(xy 72.471073 -190.037971) (xy 72.415636 -190.044071) (xy 72.359902 -190.042034) (xy 72.305059 -190.031904)
			(xy 72.252275 -190.013897) (xy 72.202675 -189.988396) (xy 72.157317 -189.955945) (xy 72.117168 -189.917236)
			(xy 72.083082 -189.873093) (xy 72.055786 -189.824458) (xy 72.035863 -189.772367) (xy 72.023737 -189.71793)
			(xy 72.019666 -189.662308) (xy 71.767192 -189.662308) (xy 71.766683 -189.690194) (xy 71.758563 -189.74537)
			(xy 71.742495 -189.798777) (xy 71.718823 -189.849274) (xy 71.68805 -189.895787) (xy 71.650833 -189.937324)
			(xy 71.607965 -189.972999) (xy 71.560359 -190.002053) (xy 71.50903 -190.023865) (xy 71.455073 -190.037971)
			(xy 71.399636 -190.044071) (xy 71.343902 -190.042034) (xy 71.289059 -190.031904) (xy 71.236275 -190.013897)
			(xy 71.186675 -189.988396) (xy 71.141317 -189.955945) (xy 71.101168 -189.917236) (xy 71.067082 -189.873093)
			(xy 71.039786 -189.824458) (xy 71.019863 -189.772367) (xy 71.007737 -189.71793) (xy 71.003666 -189.662308)
			(xy 70.750737 -189.662308) (xy 70.750737 -189.689553) (xy 70.742979 -189.743504) (xy 70.727623 -189.795802)
			(xy 70.70498 -189.845382) (xy 70.675511 -189.891235) (xy 70.639816 -189.932428) (xy 70.598622 -189.96812)
			(xy 70.552768 -189.997587) (xy 70.503187 -190.020228) (xy 70.450889 -190.035583) (xy 70.396937 -190.043338)
			(xy 70.369684 -190.043816) (xy 70.342502 -190.043333) (xy 70.288689 -190.035612) (xy 70.236517 -190.020328)
			(xy 70.187045 -189.997791) (xy 70.141273 -189.968457) (xy 70.100131 -189.932922) (xy 70.081902 -189.912752)
			(xy 70.072427 -189.902581) (xy 70.049214 -189.887312) (xy 70.022746 -189.878862) (xy 69.99498 -189.877856)
			(xy 69.967969 -189.88437) (xy 69.943713 -189.89792) (xy 69.933566 -189.907418) (xy 69.911976 -189.928068)
			(xy 69.863566 -189.963073) (xy 69.810293 -189.990107) (xy 69.753458 -190.008509) (xy 69.69445 -190.017831)
			(xy 69.66458 -190.018416) (xy 69.637293 -190.017948) (xy 69.583276 -190.010163) (xy 69.530922 -189.994754)
			(xy 69.4813 -189.972037) (xy 69.435425 -189.942476) (xy 69.394234 -189.906675) (xy 69.376036 -189.886336)
			(xy 69.366945 -189.876439) (xy 69.344691 -189.861391) (xy 69.319283 -189.852667) (xy 69.292479 -189.850868)
			(xy 69.266133 -189.856119) (xy 69.242067 -189.868058) (xy 69.231764 -189.876684) (xy 69.220746 -189.886278)
			(xy 69.197479 -189.903949) (xy 69.185282 -189.91199) (xy 69.172828 -189.920616) (xy 69.153235 -189.9437)
			(xy 69.141286 -189.971521) (xy 69.138035 -190.001624) (xy 69.143767 -190.031354) (xy 69.157979 -190.05809)
			(xy 69.168264 -190.069216) (xy 70.859396 -191.760348) (xy 72.67016 -191.760348) (xy 72.674231 -191.704726)
			(xy 72.686357 -191.650289) (xy 72.70628 -191.598198) (xy 72.733576 -191.549563) (xy 72.767662 -191.50542)
			(xy 72.807811 -191.466711) (xy 72.853169 -191.43426) (xy 72.902769 -191.408759) (xy 72.955553 -191.390752)
			(xy 73.010396 -191.380622) (xy 73.06613 -191.378585) (xy 73.121567 -191.384685) (xy 73.175524 -191.398791)
			(xy 73.226853 -191.420603) (xy 73.274459 -191.449657) (xy 73.317327 -191.485332) (xy 73.354544 -191.526869)
			(xy 73.385317 -191.573382) (xy 73.408989 -191.623879) (xy 73.425057 -191.677286) (xy 73.433177 -191.732462)
			(xy 73.433686 -191.760348) (xy 73.433177 -191.788234) (xy 73.425057 -191.84341) (xy 73.408989 -191.896817)
			(xy 73.385317 -191.947314) (xy 73.354544 -191.993827) (xy 73.330923 -192.02019) (xy 74.04684 -192.02019)
			(xy 74.050911 -191.964568) (xy 74.063037 -191.910131) (xy 74.08296 -191.85804) (xy 74.110256 -191.809405)
			(xy 74.144342 -191.765262) (xy 74.184491 -191.726553) (xy 74.229849 -191.694102) (xy 74.279449 -191.668601)
			(xy 74.332233 -191.650594) (xy 74.387076 -191.640464) (xy 74.44281 -191.638427) (xy 74.498247 -191.644527)
			(xy 74.552204 -191.658633) (xy 74.603533 -191.680445) (xy 74.651139 -191.709499) (xy 74.694007 -191.745174)
			(xy 74.731224 -191.786711) (xy 74.761997 -191.833224) (xy 74.785669 -191.883721) (xy 74.801737 -191.937128)
			(xy 74.809857 -191.992304) (xy 74.810366 -192.02019) (xy 74.809857 -192.048076) (xy 74.801737 -192.103252)
			(xy 74.785669 -192.156659) (xy 74.761997 -192.207156) (xy 74.731224 -192.253669) (xy 74.694007 -192.295206)
			(xy 74.651139 -192.330881) (xy 74.603533 -192.359935) (xy 74.552204 -192.381747) (xy 74.498247 -192.395853)
			(xy 74.44281 -192.401953) (xy 74.387076 -192.399916) (xy 74.332233 -192.389786) (xy 74.279449 -192.371779)
			(xy 74.229849 -192.346278) (xy 74.184491 -192.313827) (xy 74.144342 -192.275118) (xy 74.110256 -192.230975)
			(xy 74.08296 -192.18234) (xy 74.063037 -192.130249) (xy 74.050911 -192.075812) (xy 74.04684 -192.02019)
			(xy 73.330923 -192.02019) (xy 73.317327 -192.035364) (xy 73.274459 -192.071039) (xy 73.226853 -192.100093)
			(xy 73.175524 -192.121905) (xy 73.121567 -192.136011) (xy 73.06613 -192.142111) (xy 73.010396 -192.140074)
			(xy 72.955553 -192.129944) (xy 72.902769 -192.111937) (xy 72.853169 -192.086436) (xy 72.807811 -192.053985)
			(xy 72.767662 -192.015276) (xy 72.733576 -191.971133) (xy 72.70628 -191.922498) (xy 72.686357 -191.870407)
			(xy 72.674231 -191.81597) (xy 72.67016 -191.760348) (xy 70.859396 -191.760348) (xy 72.201278 -193.10223)
			(xy 73.03592 -193.10223) (xy 73.039991 -193.046608) (xy 73.052117 -192.992171) (xy 73.07204 -192.94008)
			(xy 73.099336 -192.891445) (xy 73.133422 -192.847302) (xy 73.173571 -192.808593) (xy 73.218929 -192.776142)
			(xy 73.268529 -192.750641) (xy 73.321313 -192.732634) (xy 73.376156 -192.722504) (xy 73.43189 -192.720467)
			(xy 73.487327 -192.726567) (xy 73.541284 -192.740673) (xy 73.592613 -192.762485) (xy 73.640219 -192.791539)
			(xy 73.683087 -192.827214) (xy 73.720304 -192.868751) (xy 73.751077 -192.915264) (xy 73.774749 -192.965761)
			(xy 73.790817 -193.019168) (xy 73.798937 -193.074344) (xy 73.799446 -193.10223) (xy 73.798937 -193.130116)
			(xy 73.790817 -193.185292) (xy 73.774749 -193.238699) (xy 73.751077 -193.289196) (xy 73.720304 -193.335709)
			(xy 73.683087 -193.377246) (xy 73.640219 -193.412921) (xy 73.592613 -193.441975) (xy 73.541284 -193.463787)
			(xy 73.487327 -193.477893) (xy 73.43189 -193.483993) (xy 73.376156 -193.481956) (xy 73.321313 -193.471826)
			(xy 73.268529 -193.453819) (xy 73.218929 -193.428318) (xy 73.173571 -193.395867) (xy 73.133422 -193.357158)
			(xy 73.099336 -193.313015) (xy 73.07204 -193.26438) (xy 73.052117 -193.212289) (xy 73.039991 -193.157852)
			(xy 73.03592 -193.10223) (xy 72.201278 -193.10223) (xy 73.885298 -194.78625) (xy 74.021095 -195.13931)
			(xy 75.67244 -195.13931) (xy 75.676511 -195.083688) (xy 75.688637 -195.029251) (xy 75.70856 -194.97716)
			(xy 75.735856 -194.928525) (xy 75.769942 -194.884382) (xy 75.810091 -194.845673) (xy 75.855449 -194.813222)
			(xy 75.905049 -194.787721) (xy 75.957833 -194.769714) (xy 76.012676 -194.759584) (xy 76.06841 -194.757547)
			(xy 76.123847 -194.763647) (xy 76.177804 -194.777753) (xy 76.229133 -194.799565) (xy 76.276739 -194.828619)
			(xy 76.319607 -194.864294) (xy 76.356824 -194.905831) (xy 76.387597 -194.952344) (xy 76.411269 -195.002841)
			(xy 76.427337 -195.056248) (xy 76.435457 -195.111424) (xy 76.435966 -195.13931) (xy 76.435457 -195.167196)
			(xy 76.427337 -195.222372) (xy 76.411269 -195.275779) (xy 76.387597 -195.326276) (xy 76.356824 -195.372789)
			(xy 76.319607 -195.414326) (xy 76.276739 -195.450001) (xy 76.229133 -195.479055) (xy 76.177804 -195.500867)
			(xy 76.123847 -195.514973) (xy 76.06841 -195.521073) (xy 76.012676 -195.519036) (xy 75.957833 -195.508906)
			(xy 75.905049 -195.490899) (xy 75.855449 -195.465398) (xy 75.810091 -195.432947) (xy 75.769942 -195.394238)
			(xy 75.735856 -195.350095) (xy 75.70856 -195.30146) (xy 75.688637 -195.249369) (xy 75.676511 -195.194932)
			(xy 75.67244 -195.13931) (xy 74.021095 -195.13931) (xy 74.373776 -196.05625) (xy 80.3816 -196.05625)
			(xy 80.385671 -196.000628) (xy 80.397797 -195.946191) (xy 80.41772 -195.8941) (xy 80.445016 -195.845465)
			(xy 80.479102 -195.801322) (xy 80.519251 -195.762613) (xy 80.564609 -195.730162) (xy 80.614209 -195.704661)
			(xy 80.666993 -195.686654) (xy 80.721836 -195.676524) (xy 80.77757 -195.674487) (xy 80.833007 -195.680587)
			(xy 80.886964 -195.694693) (xy 80.938293 -195.716505) (xy 80.985899 -195.745559) (xy 81.028767 -195.781234)
			(xy 81.065984 -195.822771) (xy 81.096757 -195.869284) (xy 81.120429 -195.919781) (xy 81.136497 -195.973188)
			(xy 81.144617 -196.028364) (xy 81.145126 -196.05625) (xy 81.144617 -196.084136) (xy 81.136497 -196.139312)
			(xy 81.120429 -196.192719) (xy 81.115699 -196.202808) (xy 85.6394 -196.202808) (xy 85.643471 -196.147186)
			(xy 85.655597 -196.092749) (xy 85.67552 -196.040658) (xy 85.702816 -195.992023) (xy 85.736902 -195.94788)
			(xy 85.777051 -195.909171) (xy 85.822409 -195.87672) (xy 85.872009 -195.851219) (xy 85.924793 -195.833212)
			(xy 85.979636 -195.823082) (xy 86.03537 -195.821045) (xy 86.090807 -195.827145) (xy 86.144764 -195.841251)
			(xy 86.196093 -195.863063) (xy 86.243699 -195.892117) (xy 86.286567 -195.927792) (xy 86.323784 -195.969329)
			(xy 86.354557 -196.015842) (xy 86.378229 -196.066339) (xy 86.394297 -196.119746) (xy 86.402417 -196.174922)
			(xy 86.402926 -196.202808) (xy 86.402417 -196.230694) (xy 86.394297 -196.28587) (xy 86.378229 -196.339277)
			(xy 86.354557 -196.389774) (xy 86.323784 -196.436287) (xy 86.286567 -196.477824) (xy 86.243699 -196.513499)
			(xy 86.196093 -196.542553) (xy 86.144764 -196.564365) (xy 86.090807 -196.578471) (xy 86.03537 -196.584571)
			(xy 85.979636 -196.582534) (xy 85.924793 -196.572404) (xy 85.872009 -196.554397) (xy 85.822409 -196.528896)
			(xy 85.777051 -196.496445) (xy 85.736902 -196.457736) (xy 85.702816 -196.413593) (xy 85.67552 -196.364958)
			(xy 85.655597 -196.312867) (xy 85.643471 -196.25843) (xy 85.6394 -196.202808) (xy 81.115699 -196.202808)
			(xy 81.096757 -196.243216) (xy 81.065984 -196.289729) (xy 81.028767 -196.331266) (xy 80.985899 -196.366941)
			(xy 80.938293 -196.395995) (xy 80.886964 -196.417807) (xy 80.833007 -196.431913) (xy 80.77757 -196.438013)
			(xy 80.721836 -196.435976) (xy 80.666993 -196.425846) (xy 80.614209 -196.407839) (xy 80.564609 -196.382338)
			(xy 80.519251 -196.349887) (xy 80.479102 -196.311178) (xy 80.445016 -196.267035) (xy 80.41772 -196.2184)
			(xy 80.397797 -196.166309) (xy 80.385671 -196.111872) (xy 80.3816 -196.05625) (xy 74.373776 -196.05625)
			(xy 74.788983 -197.13575) (xy 79.98282 -197.13575) (xy 79.986891 -197.080128) (xy 79.999017 -197.025691)
			(xy 80.01894 -196.9736) (xy 80.046236 -196.924965) (xy 80.080322 -196.880822) (xy 80.120471 -196.842113)
			(xy 80.165829 -196.809662) (xy 80.215429 -196.784161) (xy 80.268213 -196.766154) (xy 80.323056 -196.756024)
			(xy 80.37879 -196.753987) (xy 80.434227 -196.760087) (xy 80.488184 -196.774193) (xy 80.539513 -196.796005)
			(xy 80.587119 -196.825059) (xy 80.629987 -196.860734) (xy 80.667204 -196.902271) (xy 80.697977 -196.948784)
			(xy 80.721649 -196.999281) (xy 80.737717 -197.052688) (xy 80.745837 -197.107864) (xy 80.746346 -197.13575)
			(xy 80.745837 -197.163636) (xy 80.737717 -197.218812) (xy 80.721649 -197.272219) (xy 80.697977 -197.322716)
			(xy 80.667204 -197.369229) (xy 80.629987 -197.410766) (xy 80.587119 -197.446441) (xy 80.539513 -197.475495)
			(xy 80.488184 -197.497307) (xy 80.434227 -197.511413) (xy 80.37879 -197.517513) (xy 80.323056 -197.515476)
			(xy 80.268213 -197.505346) (xy 80.215429 -197.487339) (xy 80.165829 -197.461838) (xy 80.120471 -197.429387)
			(xy 80.080322 -197.390678) (xy 80.046236 -197.346535) (xy 80.01894 -197.2979) (xy 79.999017 -197.245809)
			(xy 79.986891 -197.191372) (xy 79.98282 -197.13575) (xy 74.788983 -197.13575) (xy 75.007528 -197.703948)
			(xy 86.36584 -197.703948) (xy 86.369911 -197.648326) (xy 86.382037 -197.593889) (xy 86.40196 -197.541798)
			(xy 86.429256 -197.493163) (xy 86.463342 -197.44902) (xy 86.503491 -197.410311) (xy 86.548849 -197.37786)
			(xy 86.598449 -197.352359) (xy 86.651233 -197.334352) (xy 86.706076 -197.324222) (xy 86.76181 -197.322185)
			(xy 86.817247 -197.328285) (xy 86.871204 -197.342391) (xy 86.922533 -197.364203) (xy 86.970139 -197.393257)
			(xy 87.013007 -197.428932) (xy 87.050224 -197.470469) (xy 87.080997 -197.516982) (xy 87.104669 -197.567479)
			(xy 87.120737 -197.620886) (xy 87.128857 -197.676062) (xy 87.129366 -197.703948) (xy 87.128857 -197.731834)
			(xy 87.120737 -197.78701) (xy 87.104669 -197.840417) (xy 87.080997 -197.890914) (xy 87.050224 -197.937427)
			(xy 87.013007 -197.978964) (xy 86.970139 -198.014639) (xy 86.922533 -198.043693) (xy 86.871204 -198.065505)
			(xy 86.817247 -198.079611) (xy 86.76181 -198.085711) (xy 86.706076 -198.083674) (xy 86.651233 -198.073544)
			(xy 86.598449 -198.055537) (xy 86.548849 -198.030036) (xy 86.503491 -197.997585) (xy 86.463342 -197.958876)
			(xy 86.429256 -197.914733) (xy 86.40196 -197.866098) (xy 86.382037 -197.814007) (xy 86.369911 -197.75957)
			(xy 86.36584 -197.703948) (xy 75.007528 -197.703948) (xy 79.605378 -209.65795) (xy 80.250538 -210.32089)
			(xy 85.574378 -215.64473) (xy 85.581462 -215.651196) (xy 85.599072 -215.65876) (xy 85.61823 -215.659312)
			(xy 85.636246 -215.652777) (xy 85.64372 -215.646762) (xy 85.661946 -215.631236) (xy 85.702029 -215.605054)
			(xy 85.745467 -215.584922) (xy 85.791353 -215.571261) (xy 85.83873 -215.564356) (xy 85.862668 -215.563958)
			(xy 85.888638 -215.564438) (xy 85.939939 -215.572559) (xy 85.989338 -215.588606) (xy 86.035619 -215.612183)
			(xy 86.077641 -215.64271) (xy 86.114369 -215.679435) (xy 86.144901 -215.721454) (xy 86.168482 -215.767732)
			(xy 86.184533 -215.81713) (xy 86.192659 -215.86843) (xy 86.192659 -215.92037) (xy 86.184533 -215.97167)
			(xy 86.168482 -216.021068) (xy 86.144901 -216.067346) (xy 86.114369 -216.109365) (xy 86.077641 -216.14609)
			(xy 86.035619 -216.176617) (xy 85.989338 -216.200194) (xy 85.939939 -216.216241) (xy 85.888638 -216.224362)
			(xy 85.862668 -216.224866) (xy 85.849968 -216.224612) (xy 85.836312 -216.224531) (xy 85.809734 -216.230761)
			(xy 85.785759 -216.243814) (xy 85.766102 -216.262757) (xy 85.757954 -216.276487) (xy 86.875113 -216.276487)
			(xy 86.875113 -216.224553) (xy 86.883238 -216.173258) (xy 86.899286 -216.123865) (xy 86.922864 -216.077591)
			(xy 86.95339 -216.035575) (xy 86.990113 -215.998852) (xy 87.032129 -215.968326) (xy 87.078403 -215.944748)
			(xy 87.127796 -215.9287) (xy 87.179091 -215.920575) (xy 87.231025 -215.920575) (xy 87.28232 -215.9287)
			(xy 87.331713 -215.944748) (xy 87.377987 -215.968326) (xy 87.420003 -215.998852) (xy 87.456726 -216.035575)
			(xy 87.487252 -216.077591) (xy 87.51083 -216.123865) (xy 87.526878 -216.173258) (xy 87.535003 -216.224553)
			(xy 87.535512 -216.25052) (xy 87.535003 -216.276487) (xy 87.526878 -216.327782) (xy 87.51083 -216.377175)
			(xy 87.487252 -216.423449) (xy 87.456726 -216.465465) (xy 87.420003 -216.502188) (xy 87.377987 -216.532714)
			(xy 87.331713 -216.556292) (xy 87.28232 -216.57234) (xy 87.231025 -216.580465) (xy 87.179091 -216.580465)
			(xy 87.127796 -216.57234) (xy 87.078403 -216.556292) (xy 87.032129 -216.532714) (xy 86.990113 -216.502188)
			(xy 86.95339 -216.465465) (xy 86.922864 -216.423449) (xy 86.899286 -216.377175) (xy 86.883238 -216.327782)
			(xy 86.875113 -216.276487) (xy 85.757954 -216.276487) (xy 85.752171 -216.286233) (xy 85.744963 -216.312562)
			(xy 85.744558 -216.326212) (xy 85.744558 -216.733882) (xy 85.795612 -216.733882) (xy 85.82158 -216.734366)
			(xy 85.872875 -216.742492) (xy 85.922268 -216.758544) (xy 85.968541 -216.782125) (xy 86.010556 -216.812654)
			(xy 86.047277 -216.849381) (xy 86.0778 -216.8914) (xy 86.101375 -216.937677) (xy 86.117419 -216.987072)
			(xy 86.125538 -217.038368) (xy 86.126066 -217.064336) (xy 86.125628 -217.088795) (xy 86.125403 -217.090303)
			(xy 86.405467 -217.090303) (xy 86.405467 -217.038369) (xy 86.413592 -216.987074) (xy 86.42964 -216.937681)
			(xy 86.453218 -216.891407) (xy 86.483744 -216.849391) (xy 86.520467 -216.812668) (xy 86.562483 -216.782142)
			(xy 86.608757 -216.758564) (xy 86.65815 -216.742516) (xy 86.709445 -216.734391) (xy 86.761379 -216.734391)
			(xy 86.812674 -216.742516) (xy 86.862067 -216.758564) (xy 86.908341 -216.782142) (xy 86.950357 -216.812668)
			(xy 86.98708 -216.849391) (xy 87.017606 -216.891407) (xy 87.041184 -216.937681) (xy 87.057232 -216.987074)
			(xy 87.065357 -217.038369) (xy 87.065866 -217.064336) (xy 87.065357 -217.090303) (xy 87.345267 -217.090303)
			(xy 87.345267 -217.038369) (xy 87.353392 -216.987074) (xy 87.36944 -216.937681) (xy 87.393018 -216.891407)
			(xy 87.423544 -216.849391) (xy 87.460267 -216.812668) (xy 87.502283 -216.782142) (xy 87.548557 -216.758564)
			(xy 87.59795 -216.742516) (xy 87.649245 -216.734391) (xy 87.701179 -216.734391) (xy 87.752474 -216.742516)
			(xy 87.801867 -216.758564) (xy 87.848141 -216.782142) (xy 87.890157 -216.812668) (xy 87.92688 -216.849391)
			(xy 87.957406 -216.891407) (xy 87.980984 -216.937681) (xy 87.997032 -216.987074) (xy 88.005157 -217.038369)
			(xy 88.005666 -217.064336) (xy 88.005157 -217.090303) (xy 87.997032 -217.141598) (xy 87.980984 -217.190991)
			(xy 87.957406 -217.237265) (xy 87.92688 -217.279281) (xy 87.890157 -217.316004) (xy 87.848141 -217.34653)
			(xy 87.801867 -217.370108) (xy 87.752474 -217.386156) (xy 87.701179 -217.394281) (xy 87.649245 -217.394281)
			(xy 87.59795 -217.386156) (xy 87.548557 -217.370108) (xy 87.502283 -217.34653) (xy 87.460267 -217.316004)
			(xy 87.423544 -217.279281) (xy 87.393018 -217.237265) (xy 87.36944 -217.190991) (xy 87.353392 -217.141598)
			(xy 87.345267 -217.090303) (xy 87.065357 -217.090303) (xy 87.057232 -217.141598) (xy 87.041184 -217.190991)
			(xy 87.017606 -217.237265) (xy 86.98708 -217.279281) (xy 86.950357 -217.316004) (xy 86.908341 -217.34653)
			(xy 86.862067 -217.370108) (xy 86.812674 -217.386156) (xy 86.761379 -217.394281) (xy 86.709445 -217.394281)
			(xy 86.65815 -217.386156) (xy 86.608757 -217.370108) (xy 86.562483 -217.34653) (xy 86.520467 -217.316004)
			(xy 86.483744 -217.279281) (xy 86.453218 -217.237265) (xy 86.42964 -217.190991) (xy 86.413592 -217.141598)
			(xy 86.405467 -217.090303) (xy 86.125403 -217.090303) (xy 86.11842 -217.137178) (xy 86.104152 -217.183968)
			(xy 86.083136 -217.22814) (xy 86.055833 -217.268729) (xy 86.022841 -217.304844) (xy 86.004146 -217.320622)
			(xy 85.993442 -217.329942) (xy 85.977216 -217.353213) (xy 85.968008 -217.380046) (xy 85.966527 -217.408377)
			(xy 85.972886 -217.436025) (xy 85.986596 -217.460861) (xy 85.996272 -217.471244) (xy 86.110064 -217.585036)
			(xy 86.141052 -217.572336) (xy 86.170911 -217.560996) (xy 86.233581 -217.548712) (xy 86.265512 -217.547952)
			(xy 86.291478 -217.548462) (xy 86.342772 -217.556588) (xy 86.392162 -217.572638) (xy 86.438434 -217.596216)
			(xy 86.480448 -217.626743) (xy 86.517169 -217.663466) (xy 86.547693 -217.705481) (xy 86.571269 -217.751754)
			(xy 86.587316 -217.801146) (xy 86.595439 -217.85244) (xy 86.595966 -217.878406) (xy 86.595539 -217.902664)
			(xy 86.595286 -217.904373) (xy 86.875113 -217.904373) (xy 86.875113 -217.852439) (xy 86.883238 -217.801144)
			(xy 86.899286 -217.751751) (xy 86.922864 -217.705477) (xy 86.95339 -217.663461) (xy 86.990113 -217.626738)
			(xy 87.032129 -217.596212) (xy 87.078403 -217.572634) (xy 87.127796 -217.556586) (xy 87.179091 -217.548461)
			(xy 87.231025 -217.548461) (xy 87.28232 -217.556586) (xy 87.331713 -217.572634) (xy 87.377987 -217.596212)
			(xy 87.420003 -217.626738) (xy 87.456726 -217.663461) (xy 87.487252 -217.705477) (xy 87.51083 -217.751751)
			(xy 87.526878 -217.801144) (xy 87.535003 -217.852439) (xy 87.535512 -217.878406) (xy 87.535003 -217.904373)
			(xy 87.815421 -217.904373) (xy 87.815421 -217.852439) (xy 87.823546 -217.801144) (xy 87.839594 -217.751751)
			(xy 87.863172 -217.705477) (xy 87.893698 -217.663461) (xy 87.930421 -217.626738) (xy 87.972437 -217.596212)
			(xy 88.018711 -217.572634) (xy 88.068104 -217.556586) (xy 88.119399 -217.548461) (xy 88.171333 -217.548461)
			(xy 88.222628 -217.556586) (xy 88.272021 -217.572634) (xy 88.318295 -217.596212) (xy 88.360311 -217.626738)
			(xy 88.397034 -217.663461) (xy 88.42756 -217.705477) (xy 88.451138 -217.751751) (xy 88.467186 -217.801144)
			(xy 88.475311 -217.852439) (xy 88.47582 -217.878406) (xy 88.754712 -217.878406) (xy 88.755221 -217.852439)
			(xy 88.763346 -217.801144) (xy 88.779394 -217.751751) (xy 88.802972 -217.705477) (xy 88.833498 -217.663461)
			(xy 88.870221 -217.626738) (xy 88.912237 -217.596212) (xy 88.958511 -217.572634) (xy 89.007904 -217.556586)
			(xy 89.059199 -217.548461) (xy 89.111133 -217.548461) (xy 89.162428 -217.556586) (xy 89.211821 -217.572634)
			(xy 89.258095 -217.596212) (xy 89.300111 -217.626738) (xy 89.336834 -217.663461) (xy 89.36736 -217.705477)
			(xy 89.390938 -217.751751) (xy 89.406986 -217.801144) (xy 89.415111 -217.852439) (xy 89.41562 -217.878406)
			(xy 89.694512 -217.878406) (xy 89.695033 -217.852957) (xy 89.702809 -217.802656) (xy 89.718209 -217.754143)
			(xy 89.740868 -217.708567) (xy 89.77025 -217.667006) (xy 89.805659 -217.630444) (xy 89.846258 -217.599746)
			(xy 89.891085 -217.575639) (xy 89.93908 -217.558693) (xy 89.964006 -217.55354) (xy 89.986866 -217.549222)
			(xy 90.190574 -217.196162) (xy 90.182954 -217.174064) (xy 90.174209 -217.147478) (xy 90.164766 -217.092317)
			(xy 90.164158 -217.064336) (xy 90.164667 -217.038369) (xy 90.172792 -216.987074) (xy 90.18884 -216.937681)
			(xy 90.212418 -216.891407) (xy 90.242944 -216.849391) (xy 90.279667 -216.812668) (xy 90.321683 -216.782142)
			(xy 90.367957 -216.758564) (xy 90.41735 -216.742516) (xy 90.468645 -216.734391) (xy 90.520579 -216.734391)
			(xy 90.571874 -216.742516) (xy 90.621267 -216.758564) (xy 90.667541 -216.782142) (xy 90.709557 -216.812668)
			(xy 90.74628 -216.849391) (xy 90.776806 -216.891407) (xy 90.800384 -216.937681) (xy 90.816432 -216.987074)
			(xy 90.824557 -217.038369) (xy 90.825066 -217.064336) (xy 90.824602 -217.089788) (xy 90.824522 -217.090303)
			(xy 91.104721 -217.090303) (xy 91.104721 -217.038369) (xy 91.112846 -216.987074) (xy 91.128894 -216.937681)
			(xy 91.152472 -216.891407) (xy 91.182998 -216.849391) (xy 91.219721 -216.812668) (xy 91.261737 -216.782142)
			(xy 91.308011 -216.758564) (xy 91.357404 -216.742516) (xy 91.408699 -216.734391) (xy 91.460633 -216.734391)
			(xy 91.511928 -216.742516) (xy 91.561321 -216.758564) (xy 91.607595 -216.782142) (xy 91.649611 -216.812668)
			(xy 91.686334 -216.849391) (xy 91.71686 -216.891407) (xy 91.740438 -216.937681) (xy 91.756486 -216.987074)
			(xy 91.764611 -217.038369) (xy 91.76512 -217.064336) (xy 91.764611 -217.090303) (xy 91.756486 -217.141598)
			(xy 91.740438 -217.190991) (xy 91.71686 -217.237265) (xy 91.686334 -217.279281) (xy 91.649611 -217.316004)
			(xy 91.607595 -217.34653) (xy 91.561321 -217.370108) (xy 91.511928 -217.386156) (xy 91.460633 -217.394281)
			(xy 91.408699 -217.394281) (xy 91.357404 -217.386156) (xy 91.308011 -217.370108) (xy 91.261737 -217.34653)
			(xy 91.219721 -217.316004) (xy 91.182998 -217.279281) (xy 91.152472 -217.237265) (xy 91.128894 -217.190991)
			(xy 91.112846 -217.141598) (xy 91.104721 -217.090303) (xy 90.824522 -217.090303) (xy 90.816819 -217.140092)
			(xy 90.801412 -217.188607) (xy 90.778746 -217.234184) (xy 90.749357 -217.275746) (xy 90.71394 -217.312307)
			(xy 90.673335 -217.343004) (xy 90.628501 -217.367108) (xy 90.580501 -217.384051) (xy 90.555572 -217.389202)
			(xy 90.532712 -217.39352) (xy 90.329004 -217.74658) (xy 90.336624 -217.768678) (xy 90.345357 -217.795268)
			(xy 90.354807 -217.850426) (xy 90.35542 -217.878406) (xy 90.634312 -217.878406) (xy 90.634821 -217.852439)
			(xy 90.642946 -217.801144) (xy 90.658994 -217.751751) (xy 90.682572 -217.705477) (xy 90.713098 -217.663461)
			(xy 90.749821 -217.626738) (xy 90.791837 -217.596212) (xy 90.838111 -217.572634) (xy 90.887504 -217.556586)
			(xy 90.938799 -217.548461) (xy 90.990733 -217.548461) (xy 91.042028 -217.556586) (xy 91.091421 -217.572634)
			(xy 91.137695 -217.596212) (xy 91.179711 -217.626738) (xy 91.216434 -217.663461) (xy 91.24696 -217.705477)
			(xy 91.270538 -217.751751) (xy 91.286586 -217.801144) (xy 91.294711 -217.852439) (xy 91.29522 -217.878406)
			(xy 91.574112 -217.878406) (xy 91.574633 -217.852957) (xy 91.582409 -217.802656) (xy 91.597809 -217.754143)
			(xy 91.620468 -217.708567) (xy 91.64985 -217.667006) (xy 91.685259 -217.630444) (xy 91.725858 -217.599746)
			(xy 91.770685 -217.575639) (xy 91.81868 -217.558693) (xy 91.843606 -217.55354) (xy 91.866466 -217.549222)
			(xy 92.070174 -217.196162) (xy 92.062554 -217.174064) (xy 92.053809 -217.147478) (xy 92.044366 -217.092317)
			(xy 92.043758 -217.064336) (xy 92.044267 -217.038369) (xy 92.052392 -216.987074) (xy 92.06844 -216.937681)
			(xy 92.092018 -216.891407) (xy 92.122544 -216.849391) (xy 92.159267 -216.812668) (xy 92.201283 -216.782142)
			(xy 92.247557 -216.758564) (xy 92.29695 -216.742516) (xy 92.348245 -216.734391) (xy 92.400179 -216.734391)
			(xy 92.451474 -216.742516) (xy 92.500867 -216.758564) (xy 92.547141 -216.782142) (xy 92.589157 -216.812668)
			(xy 92.62588 -216.849391) (xy 92.656406 -216.891407) (xy 92.679984 -216.937681) (xy 92.696032 -216.987074)
			(xy 92.704157 -217.038369) (xy 92.704666 -217.064336) (xy 92.704202 -217.089788) (xy 92.704122 -217.090303)
			(xy 92.984321 -217.090303) (xy 92.984321 -217.038369) (xy 92.992446 -216.987074) (xy 93.008494 -216.937681)
			(xy 93.032072 -216.891407) (xy 93.062598 -216.849391) (xy 93.099321 -216.812668) (xy 93.141337 -216.782142)
			(xy 93.187611 -216.758564) (xy 93.237004 -216.742516) (xy 93.288299 -216.734391) (xy 93.340233 -216.734391)
			(xy 93.391528 -216.742516) (xy 93.440921 -216.758564) (xy 93.487195 -216.782142) (xy 93.529211 -216.812668)
			(xy 93.565934 -216.849391) (xy 93.59646 -216.891407) (xy 93.620038 -216.937681) (xy 93.636086 -216.987074)
			(xy 93.644211 -217.038369) (xy 93.64472 -217.064336) (xy 93.644211 -217.090303) (xy 93.636086 -217.141598)
			(xy 93.620038 -217.190991) (xy 93.59646 -217.237265) (xy 93.565934 -217.279281) (xy 93.529211 -217.316004)
			(xy 93.487195 -217.34653) (xy 93.440921 -217.370108) (xy 93.391528 -217.386156) (xy 93.340233 -217.394281)
			(xy 93.288299 -217.394281) (xy 93.237004 -217.386156) (xy 93.187611 -217.370108) (xy 93.141337 -217.34653)
			(xy 93.099321 -217.316004) (xy 93.062598 -217.279281) (xy 93.032072 -217.237265) (xy 93.008494 -217.190991)
			(xy 92.992446 -217.141598) (xy 92.984321 -217.090303) (xy 92.704122 -217.090303) (xy 92.696419 -217.140092)
			(xy 92.681012 -217.188607) (xy 92.658346 -217.234184) (xy 92.628957 -217.275746) (xy 92.59354 -217.312307)
			(xy 92.552935 -217.343004) (xy 92.508101 -217.367108) (xy 92.460101 -217.384051) (xy 92.435172 -217.389202)
			(xy 92.412312 -217.39352) (xy 92.208604 -217.74658) (xy 92.216224 -217.768678) (xy 92.224957 -217.795268)
			(xy 92.234407 -217.850426) (xy 92.23502 -217.878406) (xy 92.513912 -217.878406) (xy 92.514421 -217.852439)
			(xy 92.522546 -217.801144) (xy 92.538594 -217.751751) (xy 92.562172 -217.705477) (xy 92.592698 -217.663461)
			(xy 92.629421 -217.626738) (xy 92.671437 -217.596212) (xy 92.717711 -217.572634) (xy 92.767104 -217.556586)
			(xy 92.818399 -217.548461) (xy 92.870333 -217.548461) (xy 92.921628 -217.556586) (xy 92.971021 -217.572634)
			(xy 93.017295 -217.596212) (xy 93.059311 -217.626738) (xy 93.096034 -217.663461) (xy 93.12656 -217.705477)
			(xy 93.150138 -217.751751) (xy 93.166186 -217.801144) (xy 93.174311 -217.852439) (xy 93.17482 -217.878406)
			(xy 93.453712 -217.878406) (xy 93.454233 -217.852957) (xy 93.462009 -217.802656) (xy 93.477409 -217.754143)
			(xy 93.500068 -217.708567) (xy 93.52945 -217.667006) (xy 93.564859 -217.630444) (xy 93.605458 -217.599746)
			(xy 93.650285 -217.575639) (xy 93.69828 -217.558693) (xy 93.723206 -217.55354) (xy 93.746066 -217.549222)
			(xy 93.949774 -217.196162) (xy 93.942154 -217.174064) (xy 93.933409 -217.147478) (xy 93.923966 -217.092317)
			(xy 93.923358 -217.064336) (xy 93.923867 -217.038369) (xy 93.931992 -216.987074) (xy 93.94804 -216.937681)
			(xy 93.971618 -216.891407) (xy 94.002144 -216.849391) (xy 94.038867 -216.812668) (xy 94.080883 -216.782142)
			(xy 94.127157 -216.758564) (xy 94.17655 -216.742516) (xy 94.227845 -216.734391) (xy 94.279779 -216.734391)
			(xy 94.331074 -216.742516) (xy 94.380467 -216.758564) (xy 94.426741 -216.782142) (xy 94.468757 -216.812668)
			(xy 94.50548 -216.849391) (xy 94.536006 -216.891407) (xy 94.559584 -216.937681) (xy 94.575632 -216.987074)
			(xy 94.583757 -217.038369) (xy 94.584266 -217.064336) (xy 94.583802 -217.089788) (xy 94.583722 -217.090303)
			(xy 94.863921 -217.090303) (xy 94.863921 -217.038369) (xy 94.872046 -216.987074) (xy 94.888094 -216.937681)
			(xy 94.911672 -216.891407) (xy 94.942198 -216.849391) (xy 94.978921 -216.812668) (xy 95.020937 -216.782142)
			(xy 95.067211 -216.758564) (xy 95.116604 -216.742516) (xy 95.167899 -216.734391) (xy 95.219833 -216.734391)
			(xy 95.271128 -216.742516) (xy 95.320521 -216.758564) (xy 95.366795 -216.782142) (xy 95.408811 -216.812668)
			(xy 95.445534 -216.849391) (xy 95.47606 -216.891407) (xy 95.499638 -216.937681) (xy 95.515686 -216.987074)
			(xy 95.523811 -217.038369) (xy 95.52432 -217.064336) (xy 95.523811 -217.090303) (xy 95.515686 -217.141598)
			(xy 95.499638 -217.190991) (xy 95.47606 -217.237265) (xy 95.445534 -217.279281) (xy 95.408811 -217.316004)
			(xy 95.366795 -217.34653) (xy 95.320521 -217.370108) (xy 95.271128 -217.386156) (xy 95.219833 -217.394281)
			(xy 95.167899 -217.394281) (xy 95.116604 -217.386156) (xy 95.067211 -217.370108) (xy 95.020937 -217.34653)
			(xy 94.978921 -217.316004) (xy 94.942198 -217.279281) (xy 94.911672 -217.237265) (xy 94.888094 -217.190991)
			(xy 94.872046 -217.141598) (xy 94.863921 -217.090303) (xy 94.583722 -217.090303) (xy 94.576019 -217.140092)
			(xy 94.560612 -217.188607) (xy 94.537946 -217.234184) (xy 94.508557 -217.275746) (xy 94.47314 -217.312307)
			(xy 94.432535 -217.343004) (xy 94.387701 -217.367108) (xy 94.339701 -217.384051) (xy 94.314772 -217.389202)
			(xy 94.291912 -217.39352) (xy 94.088204 -217.74658) (xy 94.095824 -217.768678) (xy 94.104557 -217.795268)
			(xy 94.114007 -217.850426) (xy 94.11462 -217.878406) (xy 94.393512 -217.878406) (xy 94.394021 -217.852439)
			(xy 94.402146 -217.801144) (xy 94.418194 -217.751751) (xy 94.441772 -217.705477) (xy 94.472298 -217.663461)
			(xy 94.509021 -217.626738) (xy 94.551037 -217.596212) (xy 94.597311 -217.572634) (xy 94.646704 -217.556586)
			(xy 94.697999 -217.548461) (xy 94.749933 -217.548461) (xy 94.801228 -217.556586) (xy 94.850621 -217.572634)
			(xy 94.896895 -217.596212) (xy 94.938911 -217.626738) (xy 94.975634 -217.663461) (xy 95.00616 -217.705477)
			(xy 95.029738 -217.751751) (xy 95.045786 -217.801144) (xy 95.053911 -217.852439) (xy 95.05442 -217.878406)
			(xy 95.333312 -217.878406) (xy 95.333833 -217.852957) (xy 95.341609 -217.802656) (xy 95.357009 -217.754143)
			(xy 95.379668 -217.708567) (xy 95.40905 -217.667006) (xy 95.444459 -217.630444) (xy 95.485058 -217.599746)
			(xy 95.529885 -217.575639) (xy 95.57788 -217.558693) (xy 95.602806 -217.55354) (xy 95.625666 -217.549222)
			(xy 95.829374 -217.196162) (xy 95.821754 -217.174064) (xy 95.813009 -217.147478) (xy 95.803566 -217.092317)
			(xy 95.802958 -217.064336) (xy 95.803467 -217.038369) (xy 95.811592 -216.987074) (xy 95.82764 -216.937681)
			(xy 95.851218 -216.891407) (xy 95.881744 -216.849391) (xy 95.918467 -216.812668) (xy 95.960483 -216.782142)
			(xy 96.006757 -216.758564) (xy 96.05615 -216.742516) (xy 96.107445 -216.734391) (xy 96.159379 -216.734391)
			(xy 96.210674 -216.742516) (xy 96.260067 -216.758564) (xy 96.306341 -216.782142) (xy 96.348357 -216.812668)
			(xy 96.38508 -216.849391) (xy 96.415606 -216.891407) (xy 96.439184 -216.937681) (xy 96.455232 -216.987074)
			(xy 96.463357 -217.038369) (xy 96.463866 -217.064336) (xy 96.463402 -217.089788) (xy 96.463322 -217.090303)
			(xy 96.743521 -217.090303) (xy 96.743521 -217.038369) (xy 96.751646 -216.987074) (xy 96.767694 -216.937681)
			(xy 96.791272 -216.891407) (xy 96.821798 -216.849391) (xy 96.858521 -216.812668) (xy 96.900537 -216.782142)
			(xy 96.946811 -216.758564) (xy 96.996204 -216.742516) (xy 97.047499 -216.734391) (xy 97.099433 -216.734391)
			(xy 97.150728 -216.742516) (xy 97.200121 -216.758564) (xy 97.246395 -216.782142) (xy 97.288411 -216.812668)
			(xy 97.325134 -216.849391) (xy 97.35566 -216.891407) (xy 97.379238 -216.937681) (xy 97.395286 -216.987074)
			(xy 97.403411 -217.038369) (xy 97.40392 -217.064336) (xy 97.403411 -217.090303) (xy 97.395286 -217.141598)
			(xy 97.379238 -217.190991) (xy 97.35566 -217.237265) (xy 97.325134 -217.279281) (xy 97.288411 -217.316004)
			(xy 97.246395 -217.34653) (xy 97.200121 -217.370108) (xy 97.150728 -217.386156) (xy 97.099433 -217.394281)
			(xy 97.047499 -217.394281) (xy 96.996204 -217.386156) (xy 96.946811 -217.370108) (xy 96.900537 -217.34653)
			(xy 96.858521 -217.316004) (xy 96.821798 -217.279281) (xy 96.791272 -217.237265) (xy 96.767694 -217.190991)
			(xy 96.751646 -217.141598) (xy 96.743521 -217.090303) (xy 96.463322 -217.090303) (xy 96.455619 -217.140092)
			(xy 96.440212 -217.188607) (xy 96.417546 -217.234184) (xy 96.388157 -217.275746) (xy 96.35274 -217.312307)
			(xy 96.312135 -217.343004) (xy 96.267301 -217.367108) (xy 96.219301 -217.384051) (xy 96.194372 -217.389202)
			(xy 96.171512 -217.39352) (xy 95.967804 -217.74658) (xy 95.975424 -217.768678) (xy 95.984157 -217.795268)
			(xy 95.993607 -217.850426) (xy 95.99422 -217.878406) (xy 96.273112 -217.878406) (xy 96.273621 -217.852439)
			(xy 96.281746 -217.801144) (xy 96.297794 -217.751751) (xy 96.321372 -217.705477) (xy 96.351898 -217.663461)
			(xy 96.388621 -217.626738) (xy 96.430637 -217.596212) (xy 96.476911 -217.572634) (xy 96.526304 -217.556586)
			(xy 96.577599 -217.548461) (xy 96.629533 -217.548461) (xy 96.680828 -217.556586) (xy 96.730221 -217.572634)
			(xy 96.776495 -217.596212) (xy 96.818511 -217.626738) (xy 96.855234 -217.663461) (xy 96.88576 -217.705477)
			(xy 96.909338 -217.751751) (xy 96.925386 -217.801144) (xy 96.933511 -217.852439) (xy 96.93402 -217.878406)
			(xy 97.212912 -217.878406) (xy 97.213433 -217.852957) (xy 97.221209 -217.802656) (xy 97.236609 -217.754143)
			(xy 97.259268 -217.708567) (xy 97.28865 -217.667006) (xy 97.324059 -217.630444) (xy 97.364658 -217.599746)
			(xy 97.409485 -217.575639) (xy 97.45748 -217.558693) (xy 97.482406 -217.55354) (xy 97.505266 -217.549222)
			(xy 97.708974 -217.196162) (xy 97.701354 -217.174064) (xy 97.692609 -217.147478) (xy 97.683166 -217.092317)
			(xy 97.682558 -217.064336) (xy 97.683067 -217.038369) (xy 97.691192 -216.987074) (xy 97.70724 -216.937681)
			(xy 97.730818 -216.891407) (xy 97.761344 -216.849391) (xy 97.798067 -216.812668) (xy 97.840083 -216.782142)
			(xy 97.886357 -216.758564) (xy 97.93575 -216.742516) (xy 97.987045 -216.734391) (xy 98.038979 -216.734391)
			(xy 98.090274 -216.742516) (xy 98.139667 -216.758564) (xy 98.185941 -216.782142) (xy 98.227957 -216.812668)
			(xy 98.26468 -216.849391) (xy 98.295206 -216.891407) (xy 98.318784 -216.937681) (xy 98.334832 -216.987074)
			(xy 98.342957 -217.038369) (xy 98.343466 -217.064336) (xy 98.343002 -217.089788) (xy 98.342922 -217.090303)
			(xy 98.623121 -217.090303) (xy 98.623121 -217.038369) (xy 98.631246 -216.987074) (xy 98.647294 -216.937681)
			(xy 98.670872 -216.891407) (xy 98.701398 -216.849391) (xy 98.738121 -216.812668) (xy 98.780137 -216.782142)
			(xy 98.826411 -216.758564) (xy 98.875804 -216.742516) (xy 98.927099 -216.734391) (xy 98.979033 -216.734391)
			(xy 99.030328 -216.742516) (xy 99.079721 -216.758564) (xy 99.125995 -216.782142) (xy 99.168011 -216.812668)
			(xy 99.204734 -216.849391) (xy 99.23526 -216.891407) (xy 99.258838 -216.937681) (xy 99.274886 -216.987074)
			(xy 99.283011 -217.038369) (xy 99.28352 -217.064336) (xy 99.283011 -217.090303) (xy 99.274886 -217.141598)
			(xy 99.258838 -217.190991) (xy 99.23526 -217.237265) (xy 99.204734 -217.279281) (xy 99.168011 -217.316004)
			(xy 99.125995 -217.34653) (xy 99.079721 -217.370108) (xy 99.030328 -217.386156) (xy 98.979033 -217.394281)
			(xy 98.927099 -217.394281) (xy 98.875804 -217.386156) (xy 98.826411 -217.370108) (xy 98.780137 -217.34653)
			(xy 98.738121 -217.316004) (xy 98.701398 -217.279281) (xy 98.670872 -217.237265) (xy 98.647294 -217.190991)
			(xy 98.631246 -217.141598) (xy 98.623121 -217.090303) (xy 98.342922 -217.090303) (xy 98.335219 -217.140092)
			(xy 98.319812 -217.188607) (xy 98.297146 -217.234184) (xy 98.267757 -217.275746) (xy 98.23234 -217.312307)
			(xy 98.191735 -217.343004) (xy 98.146901 -217.367108) (xy 98.098901 -217.384051) (xy 98.073972 -217.389202)
			(xy 98.051112 -217.39352) (xy 97.847404 -217.74658) (xy 97.855024 -217.768678) (xy 97.863757 -217.795268)
			(xy 97.873207 -217.850426) (xy 97.87382 -217.878406) (xy 98.152712 -217.878406) (xy 98.153221 -217.852439)
			(xy 98.161346 -217.801144) (xy 98.177394 -217.751751) (xy 98.200972 -217.705477) (xy 98.231498 -217.663461)
			(xy 98.268221 -217.626738) (xy 98.310237 -217.596212) (xy 98.356511 -217.572634) (xy 98.405904 -217.556586)
			(xy 98.457199 -217.548461) (xy 98.509133 -217.548461) (xy 98.560428 -217.556586) (xy 98.609821 -217.572634)
			(xy 98.656095 -217.596212) (xy 98.698111 -217.626738) (xy 98.734834 -217.663461) (xy 98.76536 -217.705477)
			(xy 98.788938 -217.751751) (xy 98.804986 -217.801144) (xy 98.813111 -217.852439) (xy 98.81362 -217.878406)
			(xy 99.092512 -217.878406) (xy 99.093033 -217.852957) (xy 99.100809 -217.802656) (xy 99.116209 -217.754143)
			(xy 99.138868 -217.708567) (xy 99.16825 -217.667006) (xy 99.203659 -217.630444) (xy 99.244258 -217.599746)
			(xy 99.289085 -217.575639) (xy 99.33708 -217.558693) (xy 99.362006 -217.55354) (xy 99.384866 -217.549222)
			(xy 99.588574 -217.196162) (xy 99.580954 -217.174064) (xy 99.572209 -217.147478) (xy 99.562766 -217.092317)
			(xy 99.562158 -217.064336) (xy 99.562667 -217.038369) (xy 99.570792 -216.987074) (xy 99.58684 -216.937681)
			(xy 99.610418 -216.891407) (xy 99.640944 -216.849391) (xy 99.677667 -216.812668) (xy 99.719683 -216.782142)
			(xy 99.765957 -216.758564) (xy 99.81535 -216.742516) (xy 99.866645 -216.734391) (xy 99.918579 -216.734391)
			(xy 99.969874 -216.742516) (xy 100.019267 -216.758564) (xy 100.065541 -216.782142) (xy 100.107557 -216.812668)
			(xy 100.14428 -216.849391) (xy 100.174806 -216.891407) (xy 100.198384 -216.937681) (xy 100.214432 -216.987074)
			(xy 100.222557 -217.038369) (xy 100.223066 -217.064336) (xy 100.222602 -217.089788) (xy 100.214819 -217.140092)
			(xy 100.199412 -217.188607) (xy 100.176746 -217.234184) (xy 100.147357 -217.275746) (xy 100.11194 -217.312307)
			(xy 100.071335 -217.343004) (xy 100.026501 -217.367108) (xy 99.978501 -217.384051) (xy 99.953572 -217.389202)
			(xy 99.930712 -217.39352) (xy 99.727004 -217.74658) (xy 99.734624 -217.768678) (xy 99.743357 -217.795268)
			(xy 99.752807 -217.850426) (xy 99.75342 -217.878406) (xy 99.752911 -217.904373) (xy 99.744786 -217.955668)
			(xy 99.728738 -218.005061) (xy 99.70516 -218.051335) (xy 99.674634 -218.093351) (xy 99.637911 -218.130074)
			(xy 99.595895 -218.1606) (xy 99.549621 -218.184178) (xy 99.500228 -218.200226) (xy 99.448933 -218.208351)
			(xy 99.396999 -218.208351) (xy 99.345704 -218.200226) (xy 99.296311 -218.184178) (xy 99.250037 -218.1606)
			(xy 99.208021 -218.130074) (xy 99.171298 -218.093351) (xy 99.140772 -218.051335) (xy 99.117194 -218.005061)
			(xy 99.101146 -217.955668) (xy 99.093021 -217.904373) (xy 99.092512 -217.878406) (xy 98.81362 -217.878406)
			(xy 98.813068 -217.906392) (xy 98.803617 -217.96156) (xy 98.794824 -217.988134) (xy 98.787204 -218.010232)
			(xy 98.990912 -218.363038) (xy 99.013772 -218.367356) (xy 99.038696 -218.37251) (xy 99.08668 -218.389479)
			(xy 99.131496 -218.413599) (xy 99.172088 -218.444302) (xy 99.207496 -218.480861) (xy 99.236884 -218.522415)
			(xy 99.259557 -218.56798) (xy 99.274982 -218.616482) (xy 99.282792 -218.666774) (xy 99.283266 -218.692222)
			(xy 99.282757 -218.718189) (xy 99.562667 -218.718189) (xy 99.562667 -218.666255) (xy 99.570792 -218.61496)
			(xy 99.58684 -218.565567) (xy 99.610418 -218.519293) (xy 99.640944 -218.477277) (xy 99.677667 -218.440554)
			(xy 99.719683 -218.410028) (xy 99.765957 -218.38645) (xy 99.81535 -218.370402) (xy 99.866645 -218.362277)
			(xy 99.918579 -218.362277) (xy 99.969874 -218.370402) (xy 100.019267 -218.38645) (xy 100.065541 -218.410028)
			(xy 100.107557 -218.440554) (xy 100.14428 -218.477277) (xy 100.174806 -218.519293) (xy 100.198384 -218.565567)
			(xy 100.214432 -218.61496) (xy 100.222557 -218.666255) (xy 100.223066 -218.692222) (xy 100.222557 -218.718189)
			(xy 100.214432 -218.769484) (xy 100.198384 -218.818877) (xy 100.174806 -218.865151) (xy 100.14428 -218.907167)
			(xy 100.107557 -218.94389) (xy 100.065541 -218.974416) (xy 100.019267 -218.997994) (xy 99.969874 -219.014042)
			(xy 99.918579 -219.022167) (xy 99.866645 -219.022167) (xy 99.81535 -219.014042) (xy 99.765957 -218.997994)
			(xy 99.719683 -218.974416) (xy 99.677667 -218.94389) (xy 99.640944 -218.907167) (xy 99.610418 -218.865151)
			(xy 99.58684 -218.818877) (xy 99.570792 -218.769484) (xy 99.562667 -218.718189) (xy 99.282757 -218.718189)
			(xy 99.274632 -218.769484) (xy 99.258584 -218.818877) (xy 99.235006 -218.865151) (xy 99.20448 -218.907167)
			(xy 99.167757 -218.94389) (xy 99.125741 -218.974416) (xy 99.079467 -218.997994) (xy 99.030074 -219.014042)
			(xy 98.978779 -219.022167) (xy 98.926845 -219.022167) (xy 98.87555 -219.014042) (xy 98.826157 -218.997994)
			(xy 98.779883 -218.974416) (xy 98.737867 -218.94389) (xy 98.701144 -218.907167) (xy 98.670618 -218.865151)
			(xy 98.64704 -218.818877) (xy 98.630992 -218.769484) (xy 98.622867 -218.718189) (xy 98.622358 -218.692222)
			(xy 98.622913 -218.664236) (xy 98.632361 -218.609068) (xy 98.641154 -218.582494) (xy 98.648774 -218.560396)
			(xy 98.445066 -218.20759) (xy 98.422206 -218.203272) (xy 98.3973 -218.198035) (xy 98.349319 -218.18108)
			(xy 98.304502 -218.156972) (xy 98.263909 -218.12628) (xy 98.228499 -218.089731) (xy 98.199108 -218.048187)
			(xy 98.176431 -218.00263) (xy 98.161003 -217.954136) (xy 98.153188 -217.90385) (xy 98.152712 -217.878406)
			(xy 97.87382 -217.878406) (xy 97.873311 -217.904373) (xy 97.865186 -217.955668) (xy 97.849138 -218.005061)
			(xy 97.82556 -218.051335) (xy 97.795034 -218.093351) (xy 97.758311 -218.130074) (xy 97.716295 -218.1606)
			(xy 97.670021 -218.184178) (xy 97.620628 -218.200226) (xy 97.569333 -218.208351) (xy 97.517399 -218.208351)
			(xy 97.466104 -218.200226) (xy 97.416711 -218.184178) (xy 97.370437 -218.1606) (xy 97.328421 -218.130074)
			(xy 97.291698 -218.093351) (xy 97.261172 -218.051335) (xy 97.237594 -218.005061) (xy 97.221546 -217.955668)
			(xy 97.213421 -217.904373) (xy 97.212912 -217.878406) (xy 96.93402 -217.878406) (xy 96.933468 -217.906392)
			(xy 96.924017 -217.96156) (xy 96.915224 -217.988134) (xy 96.907604 -218.010232) (xy 97.111312 -218.363038)
			(xy 97.134172 -218.367356) (xy 97.159096 -218.37251) (xy 97.20708 -218.389479) (xy 97.251896 -218.413599)
			(xy 97.292488 -218.444302) (xy 97.327896 -218.480861) (xy 97.357284 -218.522415) (xy 97.379957 -218.56798)
			(xy 97.395382 -218.616482) (xy 97.403192 -218.666774) (xy 97.403666 -218.692222) (xy 97.403157 -218.718189)
			(xy 97.683067 -218.718189) (xy 97.683067 -218.666255) (xy 97.691192 -218.61496) (xy 97.70724 -218.565567)
			(xy 97.730818 -218.519293) (xy 97.761344 -218.477277) (xy 97.798067 -218.440554) (xy 97.840083 -218.410028)
			(xy 97.886357 -218.38645) (xy 97.93575 -218.370402) (xy 97.987045 -218.362277) (xy 98.038979 -218.362277)
			(xy 98.090274 -218.370402) (xy 98.139667 -218.38645) (xy 98.185941 -218.410028) (xy 98.227957 -218.440554)
			(xy 98.26468 -218.477277) (xy 98.295206 -218.519293) (xy 98.318784 -218.565567) (xy 98.334832 -218.61496)
			(xy 98.342957 -218.666255) (xy 98.343466 -218.692222) (xy 98.342957 -218.718189) (xy 98.334832 -218.769484)
			(xy 98.318784 -218.818877) (xy 98.295206 -218.865151) (xy 98.26468 -218.907167) (xy 98.227957 -218.94389)
			(xy 98.185941 -218.974416) (xy 98.139667 -218.997994) (xy 98.090274 -219.014042) (xy 98.038979 -219.022167)
			(xy 97.987045 -219.022167) (xy 97.93575 -219.014042) (xy 97.886357 -218.997994) (xy 97.840083 -218.974416)
			(xy 97.798067 -218.94389) (xy 97.761344 -218.907167) (xy 97.730818 -218.865151) (xy 97.70724 -218.818877)
			(xy 97.691192 -218.769484) (xy 97.683067 -218.718189) (xy 97.403157 -218.718189) (xy 97.395032 -218.769484)
			(xy 97.378984 -218.818877) (xy 97.355406 -218.865151) (xy 97.32488 -218.907167) (xy 97.288157 -218.94389)
			(xy 97.246141 -218.974416) (xy 97.199867 -218.997994) (xy 97.150474 -219.014042) (xy 97.099179 -219.022167)
			(xy 97.047245 -219.022167) (xy 96.99595 -219.014042) (xy 96.946557 -218.997994) (xy 96.900283 -218.974416)
			(xy 96.858267 -218.94389) (xy 96.821544 -218.907167) (xy 96.791018 -218.865151) (xy 96.76744 -218.818877)
			(xy 96.751392 -218.769484) (xy 96.743267 -218.718189) (xy 96.742758 -218.692222) (xy 96.743313 -218.664236)
			(xy 96.752761 -218.609068) (xy 96.761554 -218.582494) (xy 96.769174 -218.560396) (xy 96.565466 -218.20759)
			(xy 96.542606 -218.203272) (xy 96.5177 -218.198035) (xy 96.469719 -218.18108) (xy 96.424902 -218.156972)
			(xy 96.384309 -218.12628) (xy 96.348899 -218.089731) (xy 96.319508 -218.048187) (xy 96.296831 -218.00263)
			(xy 96.281403 -217.954136) (xy 96.273588 -217.90385) (xy 96.273112 -217.878406) (xy 95.99422 -217.878406)
			(xy 95.993711 -217.904373) (xy 95.985586 -217.955668) (xy 95.969538 -218.005061) (xy 95.94596 -218.051335)
			(xy 95.915434 -218.093351) (xy 95.878711 -218.130074) (xy 95.836695 -218.1606) (xy 95.790421 -218.184178)
			(xy 95.741028 -218.200226) (xy 95.689733 -218.208351) (xy 95.637799 -218.208351) (xy 95.586504 -218.200226)
			(xy 95.537111 -218.184178) (xy 95.490837 -218.1606) (xy 95.448821 -218.130074) (xy 95.412098 -218.093351)
			(xy 95.381572 -218.051335) (xy 95.357994 -218.005061) (xy 95.341946 -217.955668) (xy 95.333821 -217.904373)
			(xy 95.333312 -217.878406) (xy 95.05442 -217.878406) (xy 95.053868 -217.906392) (xy 95.044417 -217.96156)
			(xy 95.035624 -217.988134) (xy 95.028004 -218.010232) (xy 95.231712 -218.363038) (xy 95.254572 -218.367356)
			(xy 95.279496 -218.37251) (xy 95.32748 -218.389479) (xy 95.372296 -218.413599) (xy 95.412888 -218.444302)
			(xy 95.448296 -218.480861) (xy 95.477684 -218.522415) (xy 95.500357 -218.56798) (xy 95.515782 -218.616482)
			(xy 95.523592 -218.666774) (xy 95.524066 -218.692222) (xy 95.523557 -218.718189) (xy 95.803467 -218.718189)
			(xy 95.803467 -218.666255) (xy 95.811592 -218.61496) (xy 95.82764 -218.565567) (xy 95.851218 -218.519293)
			(xy 95.881744 -218.477277) (xy 95.918467 -218.440554) (xy 95.960483 -218.410028) (xy 96.006757 -218.38645)
			(xy 96.05615 -218.370402) (xy 96.107445 -218.362277) (xy 96.159379 -218.362277) (xy 96.210674 -218.370402)
			(xy 96.260067 -218.38645) (xy 96.306341 -218.410028) (xy 96.348357 -218.440554) (xy 96.38508 -218.477277)
			(xy 96.415606 -218.519293) (xy 96.439184 -218.565567) (xy 96.455232 -218.61496) (xy 96.463357 -218.666255)
			(xy 96.463866 -218.692222) (xy 96.463357 -218.718189) (xy 96.455232 -218.769484) (xy 96.439184 -218.818877)
			(xy 96.415606 -218.865151) (xy 96.38508 -218.907167) (xy 96.348357 -218.94389) (xy 96.306341 -218.974416)
			(xy 96.260067 -218.997994) (xy 96.210674 -219.014042) (xy 96.159379 -219.022167) (xy 96.107445 -219.022167)
			(xy 96.05615 -219.014042) (xy 96.006757 -218.997994) (xy 95.960483 -218.974416) (xy 95.918467 -218.94389)
			(xy 95.881744 -218.907167) (xy 95.851218 -218.865151) (xy 95.82764 -218.818877) (xy 95.811592 -218.769484)
			(xy 95.803467 -218.718189) (xy 95.523557 -218.718189) (xy 95.515432 -218.769484) (xy 95.499384 -218.818877)
			(xy 95.475806 -218.865151) (xy 95.44528 -218.907167) (xy 95.408557 -218.94389) (xy 95.366541 -218.974416)
			(xy 95.320267 -218.997994) (xy 95.270874 -219.014042) (xy 95.219579 -219.022167) (xy 95.167645 -219.022167)
			(xy 95.11635 -219.014042) (xy 95.066957 -218.997994) (xy 95.020683 -218.974416) (xy 94.978667 -218.94389)
			(xy 94.941944 -218.907167) (xy 94.911418 -218.865151) (xy 94.88784 -218.818877) (xy 94.871792 -218.769484)
			(xy 94.863667 -218.718189) (xy 94.863158 -218.692222) (xy 94.863713 -218.664236) (xy 94.873161 -218.609068)
			(xy 94.881954 -218.582494) (xy 94.889574 -218.560396) (xy 94.685866 -218.20759) (xy 94.663006 -218.203272)
			(xy 94.6381 -218.198035) (xy 94.590119 -218.18108) (xy 94.545302 -218.156972) (xy 94.504709 -218.12628)
			(xy 94.469299 -218.089731) (xy 94.439908 -218.048187) (xy 94.417231 -218.00263) (xy 94.401803 -217.954136)
			(xy 94.393988 -217.90385) (xy 94.393512 -217.878406) (xy 94.11462 -217.878406) (xy 94.114111 -217.904373)
			(xy 94.105986 -217.955668) (xy 94.089938 -218.005061) (xy 94.06636 -218.051335) (xy 94.035834 -218.093351)
			(xy 93.999111 -218.130074) (xy 93.957095 -218.1606) (xy 93.910821 -218.184178) (xy 93.861428 -218.200226)
			(xy 93.810133 -218.208351) (xy 93.758199 -218.208351) (xy 93.706904 -218.200226) (xy 93.657511 -218.184178)
			(xy 93.611237 -218.1606) (xy 93.569221 -218.130074) (xy 93.532498 -218.093351) (xy 93.501972 -218.051335)
			(xy 93.478394 -218.005061) (xy 93.462346 -217.955668) (xy 93.454221 -217.904373) (xy 93.453712 -217.878406)
			(xy 93.17482 -217.878406) (xy 93.174268 -217.906392) (xy 93.164817 -217.96156) (xy 93.156024 -217.988134)
			(xy 93.148404 -218.010232) (xy 93.352112 -218.363038) (xy 93.374972 -218.367356) (xy 93.399896 -218.37251)
			(xy 93.44788 -218.389479) (xy 93.492696 -218.413599) (xy 93.533288 -218.444302) (xy 93.568696 -218.480861)
			(xy 93.598084 -218.522415) (xy 93.620757 -218.56798) (xy 93.636182 -218.616482) (xy 93.643992 -218.666774)
			(xy 93.644466 -218.692222) (xy 93.643957 -218.718189) (xy 93.923867 -218.718189) (xy 93.923867 -218.666255)
			(xy 93.931992 -218.61496) (xy 93.94804 -218.565567) (xy 93.971618 -218.519293) (xy 94.002144 -218.477277)
			(xy 94.038867 -218.440554) (xy 94.080883 -218.410028) (xy 94.127157 -218.38645) (xy 94.17655 -218.370402)
			(xy 94.227845 -218.362277) (xy 94.279779 -218.362277) (xy 94.331074 -218.370402) (xy 94.380467 -218.38645)
			(xy 94.426741 -218.410028) (xy 94.468757 -218.440554) (xy 94.50548 -218.477277) (xy 94.536006 -218.519293)
			(xy 94.559584 -218.565567) (xy 94.575632 -218.61496) (xy 94.583757 -218.666255) (xy 94.584266 -218.692222)
			(xy 94.583757 -218.718189) (xy 94.575632 -218.769484) (xy 94.559584 -218.818877) (xy 94.536006 -218.865151)
			(xy 94.50548 -218.907167) (xy 94.468757 -218.94389) (xy 94.426741 -218.974416) (xy 94.380467 -218.997994)
			(xy 94.331074 -219.014042) (xy 94.279779 -219.022167) (xy 94.227845 -219.022167) (xy 94.17655 -219.014042)
			(xy 94.127157 -218.997994) (xy 94.080883 -218.974416) (xy 94.038867 -218.94389) (xy 94.002144 -218.907167)
			(xy 93.971618 -218.865151) (xy 93.94804 -218.818877) (xy 93.931992 -218.769484) (xy 93.923867 -218.718189)
			(xy 93.643957 -218.718189) (xy 93.635832 -218.769484) (xy 93.619784 -218.818877) (xy 93.596206 -218.865151)
			(xy 93.56568 -218.907167) (xy 93.528957 -218.94389) (xy 93.486941 -218.974416) (xy 93.440667 -218.997994)
			(xy 93.391274 -219.014042) (xy 93.339979 -219.022167) (xy 93.288045 -219.022167) (xy 93.23675 -219.014042)
			(xy 93.187357 -218.997994) (xy 93.141083 -218.974416) (xy 93.099067 -218.94389) (xy 93.062344 -218.907167)
			(xy 93.031818 -218.865151) (xy 93.00824 -218.818877) (xy 92.992192 -218.769484) (xy 92.984067 -218.718189)
			(xy 92.983558 -218.692222) (xy 92.984113 -218.664236) (xy 92.993561 -218.609068) (xy 93.002354 -218.582494)
			(xy 93.009974 -218.560396) (xy 92.806266 -218.20759) (xy 92.783406 -218.203272) (xy 92.7585 -218.198035)
			(xy 92.710519 -218.18108) (xy 92.665702 -218.156972) (xy 92.625109 -218.12628) (xy 92.589699 -218.089731)
			(xy 92.560308 -218.048187) (xy 92.537631 -218.00263) (xy 92.522203 -217.954136) (xy 92.514388 -217.90385)
			(xy 92.513912 -217.878406) (xy 92.23502 -217.878406) (xy 92.234511 -217.904373) (xy 92.226386 -217.955668)
			(xy 92.210338 -218.005061) (xy 92.18676 -218.051335) (xy 92.156234 -218.093351) (xy 92.119511 -218.130074)
			(xy 92.077495 -218.1606) (xy 92.031221 -218.184178) (xy 91.981828 -218.200226) (xy 91.930533 -218.208351)
			(xy 91.878599 -218.208351) (xy 91.827304 -218.200226) (xy 91.777911 -218.184178) (xy 91.731637 -218.1606)
			(xy 91.689621 -218.130074) (xy 91.652898 -218.093351) (xy 91.622372 -218.051335) (xy 91.598794 -218.005061)
			(xy 91.582746 -217.955668) (xy 91.574621 -217.904373) (xy 91.574112 -217.878406) (xy 91.29522 -217.878406)
			(xy 91.294668 -217.906392) (xy 91.285217 -217.96156) (xy 91.276424 -217.988134) (xy 91.268804 -218.010232)
			(xy 91.472512 -218.363038) (xy 91.495372 -218.367356) (xy 91.520296 -218.37251) (xy 91.56828 -218.389479)
			(xy 91.613096 -218.413599) (xy 91.653688 -218.444302) (xy 91.689096 -218.480861) (xy 91.718484 -218.522415)
			(xy 91.741157 -218.56798) (xy 91.756582 -218.616482) (xy 91.764392 -218.666774) (xy 91.764866 -218.692222)
			(xy 91.764357 -218.718189) (xy 92.044267 -218.718189) (xy 92.044267 -218.666255) (xy 92.052392 -218.61496)
			(xy 92.06844 -218.565567) (xy 92.092018 -218.519293) (xy 92.122544 -218.477277) (xy 92.159267 -218.440554)
			(xy 92.201283 -218.410028) (xy 92.247557 -218.38645) (xy 92.29695 -218.370402) (xy 92.348245 -218.362277)
			(xy 92.400179 -218.362277) (xy 92.451474 -218.370402) (xy 92.500867 -218.38645) (xy 92.547141 -218.410028)
			(xy 92.589157 -218.440554) (xy 92.62588 -218.477277) (xy 92.656406 -218.519293) (xy 92.679984 -218.565567)
			(xy 92.696032 -218.61496) (xy 92.704157 -218.666255) (xy 92.704666 -218.692222) (xy 92.704157 -218.718189)
			(xy 92.696032 -218.769484) (xy 92.679984 -218.818877) (xy 92.656406 -218.865151) (xy 92.62588 -218.907167)
			(xy 92.589157 -218.94389) (xy 92.547141 -218.974416) (xy 92.500867 -218.997994) (xy 92.451474 -219.014042)
			(xy 92.400179 -219.022167) (xy 92.348245 -219.022167) (xy 92.29695 -219.014042) (xy 92.247557 -218.997994)
			(xy 92.201283 -218.974416) (xy 92.159267 -218.94389) (xy 92.122544 -218.907167) (xy 92.092018 -218.865151)
			(xy 92.06844 -218.818877) (xy 92.052392 -218.769484) (xy 92.044267 -218.718189) (xy 91.764357 -218.718189)
			(xy 91.756232 -218.769484) (xy 91.740184 -218.818877) (xy 91.716606 -218.865151) (xy 91.68608 -218.907167)
			(xy 91.649357 -218.94389) (xy 91.607341 -218.974416) (xy 91.561067 -218.997994) (xy 91.511674 -219.014042)
			(xy 91.460379 -219.022167) (xy 91.408445 -219.022167) (xy 91.35715 -219.014042) (xy 91.307757 -218.997994)
			(xy 91.261483 -218.974416) (xy 91.219467 -218.94389) (xy 91.182744 -218.907167) (xy 91.152218 -218.865151)
			(xy 91.12864 -218.818877) (xy 91.112592 -218.769484) (xy 91.104467 -218.718189) (xy 91.103958 -218.692222)
			(xy 91.104513 -218.664236) (xy 91.113961 -218.609068) (xy 91.122754 -218.582494) (xy 91.130374 -218.560396)
			(xy 90.926666 -218.20759) (xy 90.903806 -218.203272) (xy 90.8789 -218.198035) (xy 90.830919 -218.18108)
			(xy 90.786102 -218.156972) (xy 90.745509 -218.12628) (xy 90.710099 -218.089731) (xy 90.680708 -218.048187)
			(xy 90.658031 -218.00263) (xy 90.642603 -217.954136) (xy 90.634788 -217.90385) (xy 90.634312 -217.878406)
			(xy 90.35542 -217.878406) (xy 90.354911 -217.904373) (xy 90.346786 -217.955668) (xy 90.330738 -218.005061)
			(xy 90.30716 -218.051335) (xy 90.276634 -218.093351) (xy 90.239911 -218.130074) (xy 90.197895 -218.1606)
			(xy 90.151621 -218.184178) (xy 90.102228 -218.200226) (xy 90.050933 -218.208351) (xy 89.998999 -218.208351)
			(xy 89.947704 -218.200226) (xy 89.898311 -218.184178) (xy 89.852037 -218.1606) (xy 89.810021 -218.130074)
			(xy 89.773298 -218.093351) (xy 89.742772 -218.051335) (xy 89.719194 -218.005061) (xy 89.703146 -217.955668)
			(xy 89.695021 -217.904373) (xy 89.694512 -217.878406) (xy 89.41562 -217.878406) (xy 89.415068 -217.906392)
			(xy 89.405617 -217.96156) (xy 89.396824 -217.988134) (xy 89.389204 -218.010232) (xy 89.592912 -218.363038)
			(xy 89.615772 -218.367356) (xy 89.640696 -218.37251) (xy 89.68868 -218.389479) (xy 89.733496 -218.413599)
			(xy 89.774088 -218.444302) (xy 89.809496 -218.480861) (xy 89.838884 -218.522415) (xy 89.861557 -218.56798)
			(xy 89.876982 -218.616482) (xy 89.884792 -218.666774) (xy 89.885266 -218.692222) (xy 89.884757 -218.718189)
			(xy 90.164667 -218.718189) (xy 90.164667 -218.666255) (xy 90.172792 -218.61496) (xy 90.18884 -218.565567)
			(xy 90.212418 -218.519293) (xy 90.242944 -218.477277) (xy 90.279667 -218.440554) (xy 90.321683 -218.410028)
			(xy 90.367957 -218.38645) (xy 90.41735 -218.370402) (xy 90.468645 -218.362277) (xy 90.520579 -218.362277)
			(xy 90.571874 -218.370402) (xy 90.621267 -218.38645) (xy 90.667541 -218.410028) (xy 90.709557 -218.440554)
			(xy 90.74628 -218.477277) (xy 90.776806 -218.519293) (xy 90.800384 -218.565567) (xy 90.816432 -218.61496)
			(xy 90.824557 -218.666255) (xy 90.825066 -218.692222) (xy 90.824557 -218.718189) (xy 90.816432 -218.769484)
			(xy 90.800384 -218.818877) (xy 90.776806 -218.865151) (xy 90.74628 -218.907167) (xy 90.709557 -218.94389)
			(xy 90.667541 -218.974416) (xy 90.621267 -218.997994) (xy 90.571874 -219.014042) (xy 90.520579 -219.022167)
			(xy 90.468645 -219.022167) (xy 90.41735 -219.014042) (xy 90.367957 -218.997994) (xy 90.321683 -218.974416)
			(xy 90.279667 -218.94389) (xy 90.242944 -218.907167) (xy 90.212418 -218.865151) (xy 90.18884 -218.818877)
			(xy 90.172792 -218.769484) (xy 90.164667 -218.718189) (xy 89.884757 -218.718189) (xy 89.876632 -218.769484)
			(xy 89.860584 -218.818877) (xy 89.837006 -218.865151) (xy 89.80648 -218.907167) (xy 89.769757 -218.94389)
			(xy 89.727741 -218.974416) (xy 89.681467 -218.997994) (xy 89.632074 -219.014042) (xy 89.580779 -219.022167)
			(xy 89.528845 -219.022167) (xy 89.47755 -219.014042) (xy 89.428157 -218.997994) (xy 89.381883 -218.974416)
			(xy 89.339867 -218.94389) (xy 89.303144 -218.907167) (xy 89.272618 -218.865151) (xy 89.24904 -218.818877)
			(xy 89.232992 -218.769484) (xy 89.224867 -218.718189) (xy 89.224358 -218.692222) (xy 89.224913 -218.664236)
			(xy 89.234361 -218.609068) (xy 89.243154 -218.582494) (xy 89.250774 -218.560396) (xy 89.047066 -218.20759)
			(xy 89.024206 -218.203272) (xy 88.9993 -218.198035) (xy 88.951319 -218.18108) (xy 88.906502 -218.156972)
			(xy 88.865909 -218.12628) (xy 88.830499 -218.089731) (xy 88.801108 -218.048187) (xy 88.778431 -218.00263)
			(xy 88.763003 -217.954136) (xy 88.755188 -217.90385) (xy 88.754712 -217.878406) (xy 88.47582 -217.878406)
			(xy 88.475311 -217.904373) (xy 88.467186 -217.955668) (xy 88.451138 -218.005061) (xy 88.42756 -218.051335)
			(xy 88.397034 -218.093351) (xy 88.360311 -218.130074) (xy 88.318295 -218.1606) (xy 88.272021 -218.184178)
			(xy 88.222628 -218.200226) (xy 88.171333 -218.208351) (xy 88.119399 -218.208351) (xy 88.068104 -218.200226)
			(xy 88.018711 -218.184178) (xy 87.972437 -218.1606) (xy 87.930421 -218.130074) (xy 87.893698 -218.093351)
			(xy 87.863172 -218.051335) (xy 87.839594 -218.005061) (xy 87.823546 -217.955668) (xy 87.815421 -217.904373)
			(xy 87.535003 -217.904373) (xy 87.526878 -217.955668) (xy 87.51083 -218.005061) (xy 87.487252 -218.051335)
			(xy 87.456726 -218.093351) (xy 87.420003 -218.130074) (xy 87.377987 -218.1606) (xy 87.331713 -218.184178)
			(xy 87.28232 -218.200226) (xy 87.231025 -218.208351) (xy 87.179091 -218.208351) (xy 87.127796 -218.200226)
			(xy 87.078403 -218.184178) (xy 87.032129 -218.1606) (xy 86.990113 -218.130074) (xy 86.95339 -218.093351)
			(xy 86.922864 -218.051335) (xy 86.899286 -218.005061) (xy 86.883238 -217.955668) (xy 86.875113 -217.904373)
			(xy 86.595286 -217.904373) (xy 86.588447 -217.95066) (xy 86.574415 -217.997103) (xy 86.553745 -218.040996)
			(xy 86.526882 -218.081397) (xy 86.494402 -218.117437) (xy 86.457003 -218.148343) (xy 86.415488 -218.17345)
			(xy 86.393274 -218.183206) (xy 86.38029 -218.189135) (xy 86.358019 -218.20697) (xy 86.341559 -218.230275)
			(xy 86.332196 -218.257227) (xy 86.330663 -218.285718) (xy 86.33708 -218.313519) (xy 86.350944 -218.338455)
			(xy 86.360762 -218.348814) (xy 86.730137 -218.718189) (xy 87.345521 -218.718189) (xy 87.345521 -218.666255)
			(xy 87.353646 -218.61496) (xy 87.369694 -218.565567) (xy 87.393272 -218.519293) (xy 87.423798 -218.477277)
			(xy 87.460521 -218.440554) (xy 87.502537 -218.410028) (xy 87.548811 -218.38645) (xy 87.598204 -218.370402)
			(xy 87.649499 -218.362277) (xy 87.701433 -218.362277) (xy 87.752728 -218.370402) (xy 87.802121 -218.38645)
			(xy 87.848395 -218.410028) (xy 87.890411 -218.440554) (xy 87.927134 -218.477277) (xy 87.95766 -218.519293)
			(xy 87.981238 -218.565567) (xy 87.997286 -218.61496) (xy 88.005411 -218.666255) (xy 88.00592 -218.692222)
			(xy 88.005411 -218.718189) (xy 88.285321 -218.718189) (xy 88.285321 -218.666255) (xy 88.293446 -218.61496)
			(xy 88.309494 -218.565567) (xy 88.333072 -218.519293) (xy 88.363598 -218.477277) (xy 88.400321 -218.440554)
			(xy 88.442337 -218.410028) (xy 88.488611 -218.38645) (xy 88.538004 -218.370402) (xy 88.589299 -218.362277)
			(xy 88.641233 -218.362277) (xy 88.692528 -218.370402) (xy 88.741921 -218.38645) (xy 88.788195 -218.410028)
			(xy 88.830211 -218.440554) (xy 88.866934 -218.477277) (xy 88.89746 -218.519293) (xy 88.921038 -218.565567)
			(xy 88.937086 -218.61496) (xy 88.945211 -218.666255) (xy 88.94572 -218.692222) (xy 88.945211 -218.718189)
			(xy 88.937086 -218.769484) (xy 88.921038 -218.818877) (xy 88.89746 -218.865151) (xy 88.866934 -218.907167)
			(xy 88.830211 -218.94389) (xy 88.788195 -218.974416) (xy 88.741921 -218.997994) (xy 88.692528 -219.014042)
			(xy 88.641233 -219.022167) (xy 88.589299 -219.022167) (xy 88.538004 -219.014042) (xy 88.488611 -218.997994)
			(xy 88.442337 -218.974416) (xy 88.400321 -218.94389) (xy 88.363598 -218.907167) (xy 88.333072 -218.865151)
			(xy 88.309494 -218.818877) (xy 88.293446 -218.769484) (xy 88.285321 -218.718189) (xy 88.005411 -218.718189)
			(xy 87.997286 -218.769484) (xy 87.981238 -218.818877) (xy 87.95766 -218.865151) (xy 87.927134 -218.907167)
			(xy 87.890411 -218.94389) (xy 87.848395 -218.974416) (xy 87.802121 -218.997994) (xy 87.752728 -219.014042)
			(xy 87.701433 -219.022167) (xy 87.649499 -219.022167) (xy 87.598204 -219.014042) (xy 87.548811 -218.997994)
			(xy 87.502537 -218.974416) (xy 87.460521 -218.94389) (xy 87.423798 -218.907167) (xy 87.393272 -218.865151)
			(xy 87.369694 -218.818877) (xy 87.353646 -218.769484) (xy 87.345521 -218.718189) (xy 86.730137 -218.718189)
			(xy 87.450676 -219.438728) (xy 87.819738 -219.438728) (xy 87.831168 -219.403676) (xy 87.83969 -219.379159)
			(xy 87.863284 -219.33293) (xy 87.893816 -219.290959) (xy 87.930534 -219.254277) (xy 87.972535 -219.223786)
			(xy 88.018787 -219.200237) (xy 88.068152 -219.184208) (xy 88.119415 -219.176094) (xy 88.171317 -219.176094)
			(xy 88.22258 -219.184208) (xy 88.271945 -219.200237) (xy 88.318197 -219.223786) (xy 88.360198 -219.254277)
			(xy 88.396916 -219.290959) (xy 88.427448 -219.33293) (xy 88.451042 -219.379159) (xy 88.459564 -219.403676)
			(xy 88.470994 -219.438728) (xy 88.759538 -219.438728) (xy 88.770968 -219.403676) (xy 88.77949 -219.379159)
			(xy 88.803084 -219.33293) (xy 88.833616 -219.290959) (xy 88.870334 -219.254277) (xy 88.912335 -219.223786)
			(xy 88.958587 -219.200237) (xy 89.007952 -219.184208) (xy 89.059215 -219.176094) (xy 89.111117 -219.176094)
			(xy 89.16238 -219.184208) (xy 89.211745 -219.200237) (xy 89.257997 -219.223786) (xy 89.299998 -219.254277)
			(xy 89.336716 -219.290959) (xy 89.367248 -219.33293) (xy 89.390842 -219.379159) (xy 89.399364 -219.403676)
			(xy 89.410794 -219.438728) (xy 89.699338 -219.438728) (xy 89.710768 -219.403676) (xy 89.71929 -219.379159)
			(xy 89.742884 -219.33293) (xy 89.773416 -219.290959) (xy 89.810134 -219.254277) (xy 89.852135 -219.223786)
			(xy 89.898387 -219.200237) (xy 89.947752 -219.184208) (xy 89.999015 -219.176094) (xy 90.050917 -219.176094)
			(xy 90.10218 -219.184208) (xy 90.151545 -219.200237) (xy 90.197797 -219.223786) (xy 90.239798 -219.254277)
			(xy 90.276516 -219.290959) (xy 90.307048 -219.33293) (xy 90.330642 -219.379159) (xy 90.339164 -219.403676)
			(xy 90.350594 -219.438728) (xy 90.639138 -219.438728) (xy 90.650568 -219.403676) (xy 90.65909 -219.379159)
			(xy 90.682684 -219.33293) (xy 90.713216 -219.290959) (xy 90.749934 -219.254277) (xy 90.791935 -219.223786)
			(xy 90.838187 -219.200237) (xy 90.887552 -219.184208) (xy 90.938815 -219.176094) (xy 90.990717 -219.176094)
			(xy 91.04198 -219.184208) (xy 91.091345 -219.200237) (xy 91.137597 -219.223786) (xy 91.179598 -219.254277)
			(xy 91.216316 -219.290959) (xy 91.246848 -219.33293) (xy 91.270442 -219.379159) (xy 91.278964 -219.403676)
			(xy 91.290394 -219.438728) (xy 91.578938 -219.438728) (xy 91.590368 -219.403676) (xy 91.59889 -219.379159)
			(xy 91.622484 -219.33293) (xy 91.653016 -219.290959) (xy 91.689734 -219.254277) (xy 91.731735 -219.223786)
			(xy 91.777987 -219.200237) (xy 91.827352 -219.184208) (xy 91.878615 -219.176094) (xy 91.930517 -219.176094)
			(xy 91.98178 -219.184208) (xy 92.031145 -219.200237) (xy 92.077397 -219.223786) (xy 92.119398 -219.254277)
			(xy 92.156116 -219.290959) (xy 92.186648 -219.33293) (xy 92.210242 -219.379159) (xy 92.218764 -219.403676)
			(xy 92.230194 -219.438728) (xy 92.518738 -219.438728) (xy 92.530168 -219.403676) (xy 92.53869 -219.379159)
			(xy 92.562284 -219.33293) (xy 92.592816 -219.290959) (xy 92.629534 -219.254277) (xy 92.671535 -219.223786)
			(xy 92.717787 -219.200237) (xy 92.767152 -219.184208) (xy 92.818415 -219.176094) (xy 92.870317 -219.176094)
			(xy 92.92158 -219.184208) (xy 92.970945 -219.200237) (xy 93.017197 -219.223786) (xy 93.059198 -219.254277)
			(xy 93.095916 -219.290959) (xy 93.126448 -219.33293) (xy 93.150042 -219.379159) (xy 93.158564 -219.403676)
			(xy 93.169994 -219.438728) (xy 93.458538 -219.438728) (xy 93.469968 -219.403676) (xy 93.47849 -219.379159)
			(xy 93.502084 -219.33293) (xy 93.532616 -219.290959) (xy 93.569334 -219.254277) (xy 93.611335 -219.223786)
			(xy 93.657587 -219.200237) (xy 93.706952 -219.184208) (xy 93.758215 -219.176094) (xy 93.810117 -219.176094)
			(xy 93.86138 -219.184208) (xy 93.910745 -219.200237) (xy 93.956997 -219.223786) (xy 93.998998 -219.254277)
			(xy 94.035716 -219.290959) (xy 94.066248 -219.33293) (xy 94.089842 -219.379159) (xy 94.098364 -219.403676)
			(xy 94.109794 -219.438728) (xy 94.398338 -219.438728) (xy 94.409768 -219.403676) (xy 94.41829 -219.379159)
			(xy 94.441884 -219.33293) (xy 94.472416 -219.290959) (xy 94.509134 -219.254277) (xy 94.551135 -219.223786)
			(xy 94.597387 -219.200237) (xy 94.646752 -219.184208) (xy 94.698015 -219.176094) (xy 94.749917 -219.176094)
			(xy 94.80118 -219.184208) (xy 94.850545 -219.200237) (xy 94.896797 -219.223786) (xy 94.938798 -219.254277)
			(xy 94.975516 -219.290959) (xy 95.006048 -219.33293) (xy 95.029642 -219.379159) (xy 95.038164 -219.403676)
			(xy 95.049594 -219.438728) (xy 95.338138 -219.438728) (xy 95.349568 -219.403676) (xy 95.35809 -219.379159)
			(xy 95.381684 -219.33293) (xy 95.412216 -219.290959) (xy 95.448934 -219.254277) (xy 95.490935 -219.223786)
			(xy 95.537187 -219.200237) (xy 95.586552 -219.184208) (xy 95.637815 -219.176094) (xy 95.689717 -219.176094)
			(xy 95.74098 -219.184208) (xy 95.790345 -219.200237) (xy 95.836597 -219.223786) (xy 95.878598 -219.254277)
			(xy 95.915316 -219.290959) (xy 95.945848 -219.33293) (xy 95.969442 -219.379159) (xy 95.977964 -219.403676)
			(xy 95.989394 -219.438728) (xy 96.277938 -219.438728) (xy 96.289368 -219.403676) (xy 96.297887 -219.379155)
			(xy 96.321478 -219.332919) (xy 96.352007 -219.29094) (xy 96.388723 -219.25425) (xy 96.430725 -219.223752)
			(xy 96.476978 -219.200195) (xy 96.526345 -219.184159) (xy 96.577613 -219.176038) (xy 96.603566 -219.175584)
			(xy 96.629536 -219.176064) (xy 96.680837 -219.184185) (xy 96.730236 -219.200233) (xy 96.776515 -219.223811)
			(xy 96.818536 -219.25434) (xy 96.855263 -219.291067) (xy 96.885791 -219.333088) (xy 96.909369 -219.379368)
			(xy 96.925416 -219.428767) (xy 96.933536 -219.480068) (xy 96.93402 -219.506038) (xy 96.933561 -219.531103)
			(xy 96.933423 -219.532005) (xy 97.213421 -219.532005) (xy 97.213421 -219.480071) (xy 97.221546 -219.428776)
			(xy 97.237594 -219.379383) (xy 97.261172 -219.333109) (xy 97.291698 -219.291093) (xy 97.328421 -219.25437)
			(xy 97.370437 -219.223844) (xy 97.416711 -219.200266) (xy 97.466104 -219.184218) (xy 97.517399 -219.176093)
			(xy 97.569333 -219.176093) (xy 97.620628 -219.184218) (xy 97.670021 -219.200266) (xy 97.716295 -219.223844)
			(xy 97.758311 -219.25437) (xy 97.795034 -219.291093) (xy 97.82556 -219.333109) (xy 97.849138 -219.379383)
			(xy 97.865186 -219.428776) (xy 97.873311 -219.480071) (xy 97.87382 -219.506038) (xy 97.873311 -219.532005)
			(xy 98.153221 -219.532005) (xy 98.153221 -219.480071) (xy 98.161346 -219.428776) (xy 98.177394 -219.379383)
			(xy 98.200972 -219.333109) (xy 98.231498 -219.291093) (xy 98.268221 -219.25437) (xy 98.310237 -219.223844)
			(xy 98.356511 -219.200266) (xy 98.405904 -219.184218) (xy 98.457199 -219.176093) (xy 98.509133 -219.176093)
			(xy 98.560428 -219.184218) (xy 98.609821 -219.200266) (xy 98.656095 -219.223844) (xy 98.698111 -219.25437)
			(xy 98.734834 -219.291093) (xy 98.76536 -219.333109) (xy 98.788938 -219.379383) (xy 98.804986 -219.428776)
			(xy 98.813111 -219.480071) (xy 98.81362 -219.506038) (xy 98.813111 -219.532005) (xy 99.093021 -219.532005)
			(xy 99.093021 -219.480071) (xy 99.101146 -219.428776) (xy 99.117194 -219.379383) (xy 99.140772 -219.333109)
			(xy 99.171298 -219.291093) (xy 99.208021 -219.25437) (xy 99.250037 -219.223844) (xy 99.296311 -219.200266)
			(xy 99.345704 -219.184218) (xy 99.396999 -219.176093) (xy 99.448933 -219.176093) (xy 99.500228 -219.184218)
			(xy 99.549621 -219.200266) (xy 99.595895 -219.223844) (xy 99.637911 -219.25437) (xy 99.674634 -219.291093)
			(xy 99.70516 -219.333109) (xy 99.728738 -219.379383) (xy 99.744786 -219.428776) (xy 99.752911 -219.480071)
			(xy 99.75342 -219.506038) (xy 99.752911 -219.532005) (xy 100.032821 -219.532005) (xy 100.032821 -219.480071)
			(xy 100.040946 -219.428776) (xy 100.056994 -219.379383) (xy 100.080572 -219.333109) (xy 100.111098 -219.291093)
			(xy 100.147821 -219.25437) (xy 100.189837 -219.223844) (xy 100.236111 -219.200266) (xy 100.285504 -219.184218)
			(xy 100.336799 -219.176093) (xy 100.388733 -219.176093) (xy 100.440028 -219.184218) (xy 100.489421 -219.200266)
			(xy 100.535695 -219.223844) (xy 100.577711 -219.25437) (xy 100.614434 -219.291093) (xy 100.64496 -219.333109)
			(xy 100.668538 -219.379383) (xy 100.684586 -219.428776) (xy 100.692711 -219.480071) (xy 100.69322 -219.506038)
			(xy 100.692711 -219.532005) (xy 100.684586 -219.5833) (xy 100.668538 -219.632693) (xy 100.64496 -219.678967)
			(xy 100.614434 -219.720983) (xy 100.577711 -219.757706) (xy 100.535695 -219.788232) (xy 100.489421 -219.81181)
			(xy 100.440028 -219.827858) (xy 100.388733 -219.835983) (xy 100.336799 -219.835983) (xy 100.285504 -219.827858)
			(xy 100.236111 -219.81181) (xy 100.189837 -219.788232) (xy 100.147821 -219.757706) (xy 100.111098 -219.720983)
			(xy 100.080572 -219.678967) (xy 100.056994 -219.632693) (xy 100.040946 -219.5833) (xy 100.032821 -219.532005)
			(xy 99.752911 -219.532005) (xy 99.744786 -219.5833) (xy 99.728738 -219.632693) (xy 99.70516 -219.678967)
			(xy 99.674634 -219.720983) (xy 99.637911 -219.757706) (xy 99.595895 -219.788232) (xy 99.549621 -219.81181)
			(xy 99.500228 -219.827858) (xy 99.448933 -219.835983) (xy 99.396999 -219.835983) (xy 99.345704 -219.827858)
			(xy 99.296311 -219.81181) (xy 99.250037 -219.788232) (xy 99.208021 -219.757706) (xy 99.171298 -219.720983)
			(xy 99.140772 -219.678967) (xy 99.117194 -219.632693) (xy 99.101146 -219.5833) (xy 99.093021 -219.532005)
			(xy 98.813111 -219.532005) (xy 98.804986 -219.5833) (xy 98.788938 -219.632693) (xy 98.76536 -219.678967)
			(xy 98.734834 -219.720983) (xy 98.698111 -219.757706) (xy 98.656095 -219.788232) (xy 98.609821 -219.81181)
			(xy 98.560428 -219.827858) (xy 98.509133 -219.835983) (xy 98.457199 -219.835983) (xy 98.405904 -219.827858)
			(xy 98.356511 -219.81181) (xy 98.310237 -219.788232) (xy 98.268221 -219.757706) (xy 98.231498 -219.720983)
			(xy 98.200972 -219.678967) (xy 98.177394 -219.632693) (xy 98.161346 -219.5833) (xy 98.153221 -219.532005)
			(xy 97.873311 -219.532005) (xy 97.865186 -219.5833) (xy 97.849138 -219.632693) (xy 97.82556 -219.678967)
			(xy 97.795034 -219.720983) (xy 97.758311 -219.757706) (xy 97.716295 -219.788232) (xy 97.670021 -219.81181)
			(xy 97.620628 -219.827858) (xy 97.569333 -219.835983) (xy 97.517399 -219.835983) (xy 97.466104 -219.827858)
			(xy 97.416711 -219.81181) (xy 97.370437 -219.788232) (xy 97.328421 -219.757706) (xy 97.291698 -219.720983)
			(xy 97.261172 -219.678967) (xy 97.237594 -219.632693) (xy 97.221546 -219.5833) (xy 97.213421 -219.532005)
			(xy 96.933423 -219.532005) (xy 96.926 -219.580658) (xy 96.911043 -219.628503) (xy 96.889032 -219.673541)
			(xy 96.860473 -219.714739) (xy 96.826019 -219.751152) (xy 96.806512 -219.766896) (xy 96.795453 -219.776085)
			(xy 96.77854 -219.799321) (xy 96.768784 -219.826354) (xy 96.76696 -219.855036) (xy 96.773214 -219.883087)
			(xy 96.787047 -219.908279) (xy 96.79686 -219.918788) (xy 96.909128 -220.031056) (xy 96.940878 -220.017086)
			(xy 96.961872 -220.008328) (xy 97.005659 -219.995999) (xy 97.050721 -219.98978) (xy 97.073466 -219.9894)
			(xy 97.099436 -219.989907) (xy 97.150738 -219.998026) (xy 97.200138 -220.014072) (xy 97.24642 -220.037647)
			(xy 97.288444 -220.068172) (xy 97.325176 -220.104895) (xy 97.355711 -220.146912) (xy 97.379298 -220.193188)
			(xy 97.395355 -220.242584) (xy 97.403487 -220.293884) (xy 97.40392 -220.319854) (xy 97.403792 -220.333313)
			(xy 97.40163 -220.360142) (xy 97.399602 -220.373448) (xy 97.39769 -220.388032) (xy 97.40136 -220.417203)
			(xy 97.413189 -220.44412) (xy 97.432196 -220.466551) (xy 97.456805 -220.482638) (xy 97.484978 -220.491048)
			(xy 97.499678 -220.491558) (xy 97.5868 -220.491558) (xy 97.601495 -220.491028) (xy 97.62965 -220.48259)
			(xy 97.654246 -220.466497) (xy 97.673253 -220.444077) (xy 97.685102 -220.417179) (xy 97.688817 -220.388022)
			(xy 97.686876 -220.373448) (xy 97.684835 -220.360144) (xy 97.682676 -220.333313) (xy 97.682558 -220.319854)
			(xy 97.683067 -220.293887) (xy 97.691192 -220.242592) (xy 97.70724 -220.193199) (xy 97.730818 -220.146925)
			(xy 97.761344 -220.104909) (xy 97.798067 -220.068186) (xy 97.840083 -220.03766) (xy 97.886357 -220.014082)
			(xy 97.93575 -219.998034) (xy 97.987045 -219.989909) (xy 98.038979 -219.989909) (xy 98.090274 -219.998034)
			(xy 98.139667 -220.014082) (xy 98.185941 -220.03766) (xy 98.227957 -220.068186) (xy 98.26468 -220.104909)
			(xy 98.295206 -220.146925) (xy 98.318784 -220.193199) (xy 98.334832 -220.242592) (xy 98.342957 -220.293887)
			(xy 98.343466 -220.319854) (xy 98.342952 -220.345821) (xy 98.623121 -220.345821) (xy 98.623121 -220.293887)
			(xy 98.631246 -220.242592) (xy 98.647294 -220.193199) (xy 98.670872 -220.146925) (xy 98.701398 -220.104909)
			(xy 98.738121 -220.068186) (xy 98.780137 -220.03766) (xy 98.826411 -220.014082) (xy 98.875804 -219.998034)
			(xy 98.927099 -219.989909) (xy 98.979033 -219.989909) (xy 99.030328 -219.998034) (xy 99.079721 -220.014082)
			(xy 99.125995 -220.03766) (xy 99.168011 -220.068186) (xy 99.204734 -220.104909) (xy 99.23526 -220.146925)
			(xy 99.258838 -220.193199) (xy 99.274886 -220.242592) (xy 99.283011 -220.293887) (xy 99.28352 -220.319854)
			(xy 99.283011 -220.345821) (xy 99.274886 -220.397116) (xy 99.258838 -220.446509) (xy 99.23526 -220.492783)
			(xy 99.204734 -220.534799) (xy 99.168011 -220.571522) (xy 99.125995 -220.602048) (xy 99.079721 -220.625626)
			(xy 99.030328 -220.641674) (xy 98.979033 -220.649799) (xy 98.927099 -220.649799) (xy 98.875804 -220.641674)
			(xy 98.826411 -220.625626) (xy 98.780137 -220.602048) (xy 98.738121 -220.571522) (xy 98.701398 -220.534799)
			(xy 98.670872 -220.492783) (xy 98.647294 -220.446509) (xy 98.631246 -220.397116) (xy 98.623121 -220.345821)
			(xy 98.342952 -220.345821) (xy 98.342944 -220.346247) (xy 98.334539 -220.398361) (xy 98.317952 -220.448474)
			(xy 98.293605 -220.495311) (xy 98.262117 -220.537678) (xy 98.224292 -220.574498) (xy 98.203004 -220.59011)
			(xy 98.191201 -220.599035) (xy 98.172901 -220.622273) (xy 98.162012 -220.649774) (xy 98.159443 -220.679241)
			(xy 98.16541 -220.708211) (xy 98.179414 -220.734265) (xy 98.189542 -220.74505) (xy 98.30054 -220.856048)
			(xy 98.333306 -220.839284) (xy 98.356656 -220.827991) (xy 98.406 -220.812014) (xy 98.457233 -220.803939)
			(xy 98.483166 -220.80347) (xy 98.509136 -220.80395) (xy 98.560438 -220.812071) (xy 98.609838 -220.828118)
			(xy 98.656118 -220.851697) (xy 98.69814 -220.882225) (xy 98.734868 -220.918952) (xy 98.765398 -220.960973)
			(xy 98.788978 -221.007253) (xy 98.805026 -221.056652) (xy 98.813149 -221.107954) (xy 98.81362 -221.133924)
			(xy 99.092512 -221.133924) (xy 99.092958 -221.108472) (xy 99.100746 -221.058168) (xy 99.116157 -221.009654)
			(xy 99.138827 -220.964077) (xy 99.168218 -220.922517) (xy 99.203636 -220.885956) (xy 99.244243 -220.855259)
			(xy 99.289076 -220.831154) (xy 99.337077 -220.81421) (xy 99.362006 -220.809058) (xy 99.384866 -220.80474)
			(xy 99.588574 -220.45168) (xy 99.580954 -220.429582) (xy 99.572214 -220.402995) (xy 99.562768 -220.347835)
			(xy 99.562158 -220.319854) (xy 99.562667 -220.293887) (xy 99.570792 -220.242592) (xy 99.58684 -220.193199)
			(xy 99.610418 -220.146925) (xy 99.640944 -220.104909) (xy 99.677667 -220.068186) (xy 99.719683 -220.03766)
			(xy 99.765957 -220.014082) (xy 99.81535 -219.998034) (xy 99.866645 -219.989909) (xy 99.918579 -219.989909)
			(xy 99.969874 -219.998034) (xy 100.019267 -220.014082) (xy 100.065541 -220.03766) (xy 100.107557 -220.068186)
			(xy 100.14428 -220.104909) (xy 100.174806 -220.146925) (xy 100.198384 -220.193199) (xy 100.214432 -220.242592)
			(xy 100.222557 -220.293887) (xy 100.223066 -220.319854) (xy 100.222618 -220.345306) (xy 100.222538 -220.345821)
			(xy 100.502721 -220.345821) (xy 100.502721 -220.293887) (xy 100.510846 -220.242592) (xy 100.526894 -220.193199)
			(xy 100.550472 -220.146925) (xy 100.580998 -220.104909) (xy 100.617721 -220.068186) (xy 100.659737 -220.03766)
			(xy 100.706011 -220.014082) (xy 100.755404 -219.998034) (xy 100.806699 -219.989909) (xy 100.858633 -219.989909)
			(xy 100.909928 -219.998034) (xy 100.959321 -220.014082) (xy 101.005595 -220.03766) (xy 101.047611 -220.068186)
			(xy 101.084334 -220.104909) (xy 101.11486 -220.146925) (xy 101.138438 -220.193199) (xy 101.154486 -220.242592)
			(xy 101.162611 -220.293887) (xy 101.16312 -220.319854) (xy 101.162611 -220.345821) (xy 101.154486 -220.397116)
			(xy 101.138438 -220.446509) (xy 101.11486 -220.492783) (xy 101.084334 -220.534799) (xy 101.047611 -220.571522)
			(xy 101.005595 -220.602048) (xy 100.959321 -220.625626) (xy 100.909928 -220.641674) (xy 100.858633 -220.649799)
			(xy 100.806699 -220.649799) (xy 100.755404 -220.641674) (xy 100.706011 -220.625626) (xy 100.659737 -220.602048)
			(xy 100.617721 -220.571522) (xy 100.580998 -220.534799) (xy 100.550472 -220.492783) (xy 100.526894 -220.446509)
			(xy 100.510846 -220.397116) (xy 100.502721 -220.345821) (xy 100.222538 -220.345821) (xy 100.214833 -220.395611)
			(xy 100.199423 -220.444126) (xy 100.176755 -220.489704) (xy 100.147363 -220.531265) (xy 100.111945 -220.567826)
			(xy 100.071338 -220.598523) (xy 100.026503 -220.622627) (xy 99.978502 -220.639569) (xy 99.953572 -220.64472)
			(xy 99.930712 -220.649038) (xy 99.727004 -221.002098) (xy 99.734624 -221.024196) (xy 99.743361 -221.050784)
			(xy 99.752809 -221.105943) (xy 99.75342 -221.133924) (xy 100.032312 -221.133924) (xy 100.032821 -221.107957)
			(xy 100.040946 -221.056662) (xy 100.056994 -221.007269) (xy 100.080572 -220.960995) (xy 100.111098 -220.918979)
			(xy 100.147821 -220.882256) (xy 100.189837 -220.85173) (xy 100.236111 -220.828152) (xy 100.285504 -220.812104)
			(xy 100.336799 -220.803979) (xy 100.388733 -220.803979) (xy 100.440028 -220.812104) (xy 100.489421 -220.828152)
			(xy 100.535695 -220.85173) (xy 100.577711 -220.882256) (xy 100.614434 -220.918979) (xy 100.64496 -220.960995)
			(xy 100.668538 -221.007269) (xy 100.684586 -221.056662) (xy 100.692711 -221.107957) (xy 100.69322 -221.133924)
			(xy 100.692672 -221.16191) (xy 100.683219 -221.217078) (xy 100.674424 -221.243652) (xy 100.666804 -221.26575)
			(xy 100.870512 -221.618556) (xy 100.893372 -221.622874) (xy 100.9183 -221.628011) (xy 100.966285 -221.644981)
			(xy 101.011103 -221.669103) (xy 101.051695 -221.699808) (xy 101.087103 -221.736369) (xy 101.11649 -221.777925)
			(xy 101.139163 -221.823493) (xy 101.154585 -221.871997) (xy 101.162393 -221.922292) (xy 101.162866 -221.94774)
			(xy 101.162357 -221.973707) (xy 101.442267 -221.973707) (xy 101.442267 -221.921773) (xy 101.450392 -221.870478)
			(xy 101.46644 -221.821085) (xy 101.490018 -221.774811) (xy 101.520544 -221.732795) (xy 101.557267 -221.696072)
			(xy 101.599283 -221.665546) (xy 101.645557 -221.641968) (xy 101.69495 -221.62592) (xy 101.746245 -221.617795)
			(xy 101.798179 -221.617795) (xy 101.849474 -221.62592) (xy 101.898867 -221.641968) (xy 101.945141 -221.665546)
			(xy 101.987157 -221.696072) (xy 102.02388 -221.732795) (xy 102.054406 -221.774811) (xy 102.077984 -221.821085)
			(xy 102.094032 -221.870478) (xy 102.102157 -221.921773) (xy 102.102666 -221.94774) (xy 102.102157 -221.973707)
			(xy 102.094032 -222.025002) (xy 102.077984 -222.074395) (xy 102.054406 -222.120669) (xy 102.02388 -222.162685)
			(xy 101.987157 -222.199408) (xy 101.945141 -222.229934) (xy 101.898867 -222.253512) (xy 101.849474 -222.26956)
			(xy 101.798179 -222.277685) (xy 101.746245 -222.277685) (xy 101.69495 -222.26956) (xy 101.645557 -222.253512)
			(xy 101.599283 -222.229934) (xy 101.557267 -222.199408) (xy 101.520544 -222.162685) (xy 101.490018 -222.120669)
			(xy 101.46644 -222.074395) (xy 101.450392 -222.025002) (xy 101.442267 -221.973707) (xy 101.162357 -221.973707)
			(xy 101.154232 -222.025002) (xy 101.138184 -222.074395) (xy 101.114606 -222.120669) (xy 101.08408 -222.162685)
			(xy 101.047357 -222.199408) (xy 101.005341 -222.229934) (xy 100.959067 -222.253512) (xy 100.909674 -222.26956)
			(xy 100.858379 -222.277685) (xy 100.806445 -222.277685) (xy 100.75515 -222.26956) (xy 100.705757 -222.253512)
			(xy 100.659483 -222.229934) (xy 100.617467 -222.199408) (xy 100.580744 -222.162685) (xy 100.550218 -222.120669)
			(xy 100.52664 -222.074395) (xy 100.510592 -222.025002) (xy 100.502467 -221.973707) (xy 100.501958 -221.94774)
			(xy 100.502518 -221.919754) (xy 100.511963 -221.864587) (xy 100.520754 -221.838012) (xy 100.528374 -221.815914)
			(xy 100.324666 -221.463108) (xy 100.301806 -221.45879) (xy 100.276882 -221.45363) (xy 100.228895 -221.436669)
			(xy 100.184074 -221.412553) (xy 100.143479 -221.381853) (xy 100.108068 -221.345294) (xy 100.07868 -221.303739)
			(xy 100.056007 -221.258171) (xy 100.040587 -221.209667) (xy 100.032782 -221.159372) (xy 100.032312 -221.133924)
			(xy 99.75342 -221.133924) (xy 99.752911 -221.159891) (xy 99.744786 -221.211186) (xy 99.728738 -221.260579)
			(xy 99.70516 -221.306853) (xy 99.674634 -221.348869) (xy 99.637911 -221.385592) (xy 99.595895 -221.416118)
			(xy 99.549621 -221.439696) (xy 99.500228 -221.455744) (xy 99.448933 -221.463869) (xy 99.396999 -221.463869)
			(xy 99.345704 -221.455744) (xy 99.296311 -221.439696) (xy 99.250037 -221.416118) (xy 99.208021 -221.385592)
			(xy 99.171298 -221.348869) (xy 99.140772 -221.306853) (xy 99.117194 -221.260579) (xy 99.101146 -221.211186)
			(xy 99.093021 -221.159891) (xy 99.092512 -221.133924) (xy 98.81362 -221.133924) (xy 98.813005 -221.161904)
			(xy 98.80355 -221.21706) (xy 98.794824 -221.243652) (xy 98.787204 -221.26575) (xy 98.892106 -221.447614)
			(xy 99.092766 -221.648274) (xy 99.100132 -221.652084) (xy 99.1238 -221.664453) (xy 99.167139 -221.695651)
			(xy 99.204894 -221.733415) (xy 99.236083 -221.77676) (xy 99.248468 -221.80042) (xy 99.252278 -221.807786)
			(xy 99.46259 -222.018098) (xy 99.562666 -222.018098) (xy 99.562666 -221.964758) (xy 99.562158 -221.94774)
			(xy 99.562667 -221.921773) (xy 99.570792 -221.870478) (xy 99.58684 -221.821085) (xy 99.610418 -221.774811)
			(xy 99.640944 -221.732795) (xy 99.677667 -221.696072) (xy 99.719683 -221.665546) (xy 99.765957 -221.641968)
			(xy 99.81535 -221.62592) (xy 99.866645 -221.617795) (xy 99.918579 -221.617795) (xy 99.969874 -221.62592)
			(xy 100.019267 -221.641968) (xy 100.065541 -221.665546) (xy 100.107557 -221.696072) (xy 100.14428 -221.732795)
			(xy 100.174806 -221.774811) (xy 100.198384 -221.821085) (xy 100.214432 -221.870478) (xy 100.222557 -221.921773)
			(xy 100.223066 -221.94774) (xy 100.22262 -221.972531) (xy 100.215209 -222.021556) (xy 100.200559 -222.068924)
			(xy 100.178999 -222.113573) (xy 100.151013 -222.154501) (xy 100.117228 -222.190791) (xy 100.098098 -222.206566)
			(xy 100.08722 -222.215839) (xy 100.070666 -222.239126) (xy 100.061207 -222.266086) (xy 100.059582 -222.294611)
			(xy 100.06592 -222.32247) (xy 100.079723 -222.347486) (xy 100.089462 -222.35795) (xy 100.202238 -222.470726)
			(xy 100.233734 -222.457264) (xy 100.254229 -222.448992) (xy 100.296863 -222.43734) (xy 100.340667 -222.431459)
			(xy 100.362766 -222.431102) (xy 100.388736 -222.431609) (xy 100.440038 -222.439729) (xy 100.489438 -222.455774)
			(xy 100.53572 -222.479349) (xy 100.577744 -222.509874) (xy 100.614476 -222.546597) (xy 100.64501 -222.588614)
			(xy 100.668597 -222.63489) (xy 100.684653 -222.684286) (xy 100.692785 -222.735586) (xy 100.69322 -222.761556)
			(xy 100.692725 -222.787523) (xy 100.972621 -222.787523) (xy 100.972621 -222.735589) (xy 100.980746 -222.684294)
			(xy 100.996794 -222.634901) (xy 101.020372 -222.588627) (xy 101.050898 -222.546611) (xy 101.087621 -222.509888)
			(xy 101.129637 -222.479362) (xy 101.175911 -222.455784) (xy 101.225304 -222.439736) (xy 101.276599 -222.431611)
			(xy 101.328533 -222.431611) (xy 101.379828 -222.439736) (xy 101.429221 -222.455784) (xy 101.475495 -222.479362)
			(xy 101.517511 -222.509888) (xy 101.554234 -222.546611) (xy 101.58476 -222.588627) (xy 101.608338 -222.634901)
			(xy 101.624386 -222.684294) (xy 101.632511 -222.735589) (xy 101.63302 -222.761556) (xy 101.632511 -222.787523)
			(xy 101.912421 -222.787523) (xy 101.912421 -222.735589) (xy 101.920546 -222.684294) (xy 101.936594 -222.634901)
			(xy 101.960172 -222.588627) (xy 101.990698 -222.546611) (xy 102.027421 -222.509888) (xy 102.069437 -222.479362)
			(xy 102.115711 -222.455784) (xy 102.165104 -222.439736) (xy 102.216399 -222.431611) (xy 102.268333 -222.431611)
			(xy 102.319628 -222.439736) (xy 102.369021 -222.455784) (xy 102.415295 -222.479362) (xy 102.457311 -222.509888)
			(xy 102.494034 -222.546611) (xy 102.52456 -222.588627) (xy 102.548138 -222.634901) (xy 102.564186 -222.684294)
			(xy 102.572311 -222.735589) (xy 102.57282 -222.761556) (xy 102.572311 -222.787523) (xy 102.852221 -222.787523)
			(xy 102.852221 -222.735589) (xy 102.860346 -222.684294) (xy 102.876394 -222.634901) (xy 102.899972 -222.588627)
			(xy 102.930498 -222.546611) (xy 102.967221 -222.509888) (xy 103.009237 -222.479362) (xy 103.055511 -222.455784)
			(xy 103.104904 -222.439736) (xy 103.156199 -222.431611) (xy 103.208133 -222.431611) (xy 103.259428 -222.439736)
			(xy 103.308821 -222.455784) (xy 103.355095 -222.479362) (xy 103.397111 -222.509888) (xy 103.433834 -222.546611)
			(xy 103.46436 -222.588627) (xy 103.487938 -222.634901) (xy 103.503986 -222.684294) (xy 103.512111 -222.735589)
			(xy 103.51262 -222.761556) (xy 103.512111 -222.787523) (xy 103.792021 -222.787523) (xy 103.792021 -222.735589)
			(xy 103.800146 -222.684294) (xy 103.816194 -222.634901) (xy 103.839772 -222.588627) (xy 103.870298 -222.546611)
			(xy 103.907021 -222.509888) (xy 103.949037 -222.479362) (xy 103.995311 -222.455784) (xy 104.044704 -222.439736)
			(xy 104.095999 -222.431611) (xy 104.147933 -222.431611) (xy 104.199228 -222.439736) (xy 104.248621 -222.455784)
			(xy 104.294895 -222.479362) (xy 104.336911 -222.509888) (xy 104.373634 -222.546611) (xy 104.40416 -222.588627)
			(xy 104.427738 -222.634901) (xy 104.443786 -222.684294) (xy 104.451911 -222.735589) (xy 104.45242 -222.761556)
			(xy 104.451911 -222.787523) (xy 104.443786 -222.838818) (xy 104.427738 -222.888211) (xy 104.40416 -222.934485)
			(xy 104.373634 -222.976501) (xy 104.336911 -223.013224) (xy 104.294895 -223.04375) (xy 104.248621 -223.067328)
			(xy 104.199228 -223.083376) (xy 104.147933 -223.091501) (xy 104.095999 -223.091501) (xy 104.044704 -223.083376)
			(xy 103.995311 -223.067328) (xy 103.949037 -223.04375) (xy 103.907021 -223.013224) (xy 103.870298 -222.976501)
			(xy 103.839772 -222.934485) (xy 103.816194 -222.888211) (xy 103.800146 -222.838818) (xy 103.792021 -222.787523)
			(xy 103.512111 -222.787523) (xy 103.503986 -222.838818) (xy 103.487938 -222.888211) (xy 103.46436 -222.934485)
			(xy 103.433834 -222.976501) (xy 103.397111 -223.013224) (xy 103.355095 -223.04375) (xy 103.308821 -223.067328)
			(xy 103.259428 -223.083376) (xy 103.208133 -223.091501) (xy 103.156199 -223.091501) (xy 103.104904 -223.083376)
			(xy 103.055511 -223.067328) (xy 103.009237 -223.04375) (xy 102.967221 -223.013224) (xy 102.930498 -222.976501)
			(xy 102.899972 -222.934485) (xy 102.876394 -222.888211) (xy 102.860346 -222.838818) (xy 102.852221 -222.787523)
			(xy 102.572311 -222.787523) (xy 102.564186 -222.838818) (xy 102.548138 -222.888211) (xy 102.52456 -222.934485)
			(xy 102.494034 -222.976501) (xy 102.457311 -223.013224) (xy 102.415295 -223.04375) (xy 102.369021 -223.067328)
			(xy 102.319628 -223.083376) (xy 102.268333 -223.091501) (xy 102.216399 -223.091501) (xy 102.165104 -223.083376)
			(xy 102.115711 -223.067328) (xy 102.069437 -223.04375) (xy 102.027421 -223.013224) (xy 101.990698 -222.976501)
			(xy 101.960172 -222.934485) (xy 101.936594 -222.888211) (xy 101.920546 -222.838818) (xy 101.912421 -222.787523)
			(xy 101.632511 -222.787523) (xy 101.624386 -222.838818) (xy 101.608338 -222.888211) (xy 101.58476 -222.934485)
			(xy 101.554234 -222.976501) (xy 101.517511 -223.013224) (xy 101.475495 -223.04375) (xy 101.429221 -223.067328)
			(xy 101.379828 -223.083376) (xy 101.328533 -223.091501) (xy 101.276599 -223.091501) (xy 101.225304 -223.083376)
			(xy 101.175911 -223.067328) (xy 101.129637 -223.04375) (xy 101.087621 -223.013224) (xy 101.050898 -222.976501)
			(xy 101.020372 -222.934485) (xy 100.996794 -222.888211) (xy 100.980746 -222.838818) (xy 100.972621 -222.787523)
			(xy 100.692725 -222.787523) (xy 100.692712 -222.788226) (xy 100.684143 -222.840872) (xy 100.667222 -222.891457)
			(xy 100.642388 -222.938662) (xy 100.610288 -222.981261) (xy 100.591366 -223.000062) (xy 100.581895 -223.009715)
			(xy 100.567959 -223.032879) (xy 100.560586 -223.058888) (xy 100.560294 -223.08592) (xy 100.567102 -223.112083)
			(xy 100.580533 -223.135543) (xy 100.589842 -223.14535) (xy 100.711254 -223.266762) (xy 100.74021 -223.25838)
			(xy 100.762824 -223.252209) (xy 100.809228 -223.245576) (xy 100.832666 -223.245172) (xy 100.858635 -223.245652)
			(xy 100.909934 -223.253772) (xy 100.959331 -223.269818) (xy 101.00561 -223.293394) (xy 101.047631 -223.32392)
			(xy 101.084358 -223.360643) (xy 101.114888 -223.402661) (xy 101.138469 -223.448937) (xy 101.15452 -223.498333)
			(xy 101.162645 -223.549631) (xy 101.162645 -223.601569) (xy 101.15452 -223.652867) (xy 101.138469 -223.702263)
			(xy 101.114888 -223.748539) (xy 101.084358 -223.790557) (xy 101.047631 -223.82728) (xy 101.00561 -223.857806)
			(xy 100.959331 -223.881382) (xy 100.909934 -223.897428) (xy 100.858635 -223.905548) (xy 100.832666 -223.90608)
			(xy 100.815846 -223.905851) (xy 100.78238 -223.902415) (xy 100.765864 -223.899222) (xy 100.739194 -223.893634)
			(xy 100.646738 -223.98609) (xy 100.808028 -224.28708) (xy 100.815349 -224.299705) (xy 100.835859 -224.320451)
			(xy 100.861397 -224.334553) (xy 100.889879 -224.340861) (xy 100.918983 -224.338861) (xy 100.946335 -224.328716)
			(xy 100.969704 -224.311252) (xy 100.987183 -224.287896) (xy 100.992686 -224.27438) (xy 101.001557 -224.251726)
			(xy 101.024994 -224.209091) (xy 101.054428 -224.170354) (xy 101.089223 -224.136351) (xy 101.128628 -224.107816)
			(xy 101.17179 -224.085367) (xy 101.217778 -224.069489) (xy 101.241606 -224.064576) (xy 101.264466 -224.060258)
			(xy 101.468174 -223.707198) (xy 101.460554 -223.685354) (xy 101.451757 -223.65878) (xy 101.442301 -223.603612)
			(xy 101.441758 -223.575626) (xy 101.442267 -223.549659) (xy 101.450392 -223.498364) (xy 101.46644 -223.448971)
			(xy 101.490018 -223.402697) (xy 101.520544 -223.360681) (xy 101.557267 -223.323958) (xy 101.599283 -223.293432)
			(xy 101.645557 -223.269854) (xy 101.69495 -223.253806) (xy 101.746245 -223.245681) (xy 101.798179 -223.245681)
			(xy 101.849474 -223.253806) (xy 101.898867 -223.269854) (xy 101.945141 -223.293432) (xy 101.987157 -223.323958)
			(xy 102.02388 -223.360681) (xy 102.054406 -223.402697) (xy 102.077984 -223.448971) (xy 102.094032 -223.498364)
			(xy 102.102157 -223.549659) (xy 102.102666 -223.575626) (xy 102.102196 -223.601076) (xy 102.102116 -223.601593)
			(xy 102.382321 -223.601593) (xy 102.382321 -223.549659) (xy 102.390446 -223.498364) (xy 102.406494 -223.448971)
			(xy 102.430072 -223.402697) (xy 102.460598 -223.360681) (xy 102.497321 -223.323958) (xy 102.539337 -223.293432)
			(xy 102.585611 -223.269854) (xy 102.635004 -223.253806) (xy 102.686299 -223.245681) (xy 102.738233 -223.245681)
			(xy 102.789528 -223.253806) (xy 102.838921 -223.269854) (xy 102.885195 -223.293432) (xy 102.927211 -223.323958)
			(xy 102.963934 -223.360681) (xy 102.99446 -223.402697) (xy 103.018038 -223.448971) (xy 103.034086 -223.498364)
			(xy 103.042211 -223.549659) (xy 103.04272 -223.575626) (xy 103.042211 -223.601593) (xy 103.034086 -223.652888)
			(xy 103.018038 -223.702281) (xy 102.99446 -223.748555) (xy 102.963934 -223.790571) (xy 102.927211 -223.827294)
			(xy 102.885195 -223.85782) (xy 102.838921 -223.881398) (xy 102.789528 -223.897446) (xy 102.738233 -223.905571)
			(xy 102.686299 -223.905571) (xy 102.635004 -223.897446) (xy 102.585611 -223.881398) (xy 102.539337 -223.85782)
			(xy 102.497321 -223.827294) (xy 102.460598 -223.790571) (xy 102.430072 -223.748555) (xy 102.406494 -223.702281)
			(xy 102.390446 -223.652888) (xy 102.382321 -223.601593) (xy 102.102116 -223.601593) (xy 102.094392 -223.651374)
			(xy 102.078972 -223.699882) (xy 102.056302 -223.745455) (xy 102.026915 -223.787015) (xy 101.991508 -223.823581)
			(xy 101.950914 -223.85429) (xy 101.906095 -223.878415) (xy 101.858108 -223.895387) (xy 101.833172 -223.900492)
			(xy 101.810058 -223.90481) (xy 101.606604 -224.257616) (xy 101.614224 -224.279714) (xy 101.623013 -224.306289)
			(xy 101.632456 -224.361457) (xy 101.63302 -224.389442) (xy 101.911912 -224.389442) (xy 101.912421 -224.363475)
			(xy 101.920546 -224.31218) (xy 101.936594 -224.262787) (xy 101.960172 -224.216513) (xy 101.990698 -224.174497)
			(xy 102.027421 -224.137774) (xy 102.069437 -224.107248) (xy 102.115711 -224.08367) (xy 102.165104 -224.067622)
			(xy 102.216399 -224.059497) (xy 102.268333 -224.059497) (xy 102.319628 -224.067622) (xy 102.369021 -224.08367)
			(xy 102.415295 -224.107248) (xy 102.457311 -224.137774) (xy 102.494034 -224.174497) (xy 102.52456 -224.216513)
			(xy 102.548138 -224.262787) (xy 102.564186 -224.31218) (xy 102.572311 -224.363475) (xy 102.57282 -224.389442)
			(xy 102.851712 -224.389442) (xy 102.852174 -224.363991) (xy 102.85996 -224.313687) (xy 102.875368 -224.265174)
			(xy 102.898036 -224.219597) (xy 102.927425 -224.178036) (xy 102.962841 -224.141475) (xy 103.003446 -224.110778)
			(xy 103.048278 -224.086672) (xy 103.096277 -224.069728) (xy 103.121206 -224.064576) (xy 103.144066 -224.060258)
			(xy 103.347774 -223.707198) (xy 103.340154 -223.685354) (xy 103.331431 -223.658761) (xy 103.321974 -223.603606)
			(xy 103.321358 -223.575626) (xy 103.321867 -223.549659) (xy 103.329992 -223.498364) (xy 103.34604 -223.448971)
			(xy 103.369618 -223.402697) (xy 103.400144 -223.360681) (xy 103.436867 -223.323958) (xy 103.478883 -223.293432)
			(xy 103.525157 -223.269854) (xy 103.57455 -223.253806) (xy 103.625845 -223.245681) (xy 103.677779 -223.245681)
			(xy 103.729074 -223.253806) (xy 103.778467 -223.269854) (xy 103.824741 -223.293432) (xy 103.866757 -223.323958)
			(xy 103.90348 -223.360681) (xy 103.934006 -223.402697) (xy 103.957584 -223.448971) (xy 103.973632 -223.498364)
			(xy 103.981757 -223.549659) (xy 103.982266 -223.575626) (xy 103.981793 -223.601077) (xy 103.981713 -223.601593)
			(xy 104.261921 -223.601593) (xy 104.261921 -223.549659) (xy 104.270046 -223.498364) (xy 104.286094 -223.448971)
			(xy 104.309672 -223.402697) (xy 104.340198 -223.360681) (xy 104.376921 -223.323958) (xy 104.418937 -223.293432)
			(xy 104.465211 -223.269854) (xy 104.514604 -223.253806) (xy 104.565899 -223.245681) (xy 104.617833 -223.245681)
			(xy 104.669128 -223.253806) (xy 104.718521 -223.269854) (xy 104.764795 -223.293432) (xy 104.806811 -223.323958)
			(xy 104.843534 -223.360681) (xy 104.87406 -223.402697) (xy 104.897638 -223.448971) (xy 104.913686 -223.498364)
			(xy 104.921811 -223.549659) (xy 104.92232 -223.575626) (xy 104.921811 -223.601593) (xy 104.913686 -223.652888)
			(xy 104.897638 -223.702281) (xy 104.87406 -223.748555) (xy 104.843534 -223.790571) (xy 104.806811 -223.827294)
			(xy 104.764795 -223.85782) (xy 104.718521 -223.881398) (xy 104.669128 -223.897446) (xy 104.617833 -223.905571)
			(xy 104.565899 -223.905571) (xy 104.514604 -223.897446) (xy 104.465211 -223.881398) (xy 104.418937 -223.85782)
			(xy 104.376921 -223.827294) (xy 104.340198 -223.790571) (xy 104.309672 -223.748555) (xy 104.286094 -223.702281)
			(xy 104.270046 -223.652888) (xy 104.261921 -223.601593) (xy 103.981713 -223.601593) (xy 103.974011 -223.651381)
			(xy 103.958606 -223.699896) (xy 103.935941 -223.745473) (xy 103.906553 -223.787035) (xy 103.871137 -223.823597)
			(xy 103.830533 -223.854293) (xy 103.7857 -223.878398) (xy 103.737701 -223.895341) (xy 103.712772 -223.900492)
			(xy 103.689658 -223.90481) (xy 103.486204 -224.257616) (xy 103.493824 -224.279714) (xy 103.502566 -224.306301)
			(xy 103.51201 -224.361461) (xy 103.51262 -224.389442) (xy 103.791512 -224.389442) (xy 103.792021 -224.363475)
			(xy 103.800146 -224.31218) (xy 103.816194 -224.262787) (xy 103.839772 -224.216513) (xy 103.870298 -224.174497)
			(xy 103.907021 -224.137774) (xy 103.949037 -224.107248) (xy 103.995311 -224.08367) (xy 104.044704 -224.067622)
			(xy 104.095999 -224.059497) (xy 104.147933 -224.059497) (xy 104.199228 -224.067622) (xy 104.248621 -224.08367)
			(xy 104.294895 -224.107248) (xy 104.336911 -224.137774) (xy 104.373634 -224.174497) (xy 104.40416 -224.216513)
			(xy 104.427738 -224.262787) (xy 104.443786 -224.31218) (xy 104.451911 -224.363475) (xy 104.45242 -224.389442)
			(xy 104.731312 -224.389442) (xy 104.731774 -224.363991) (xy 104.73956 -224.313687) (xy 104.754968 -224.265174)
			(xy 104.777636 -224.219597) (xy 104.807025 -224.178036) (xy 104.842441 -224.141475) (xy 104.883046 -224.110778)
			(xy 104.927878 -224.086672) (xy 104.975877 -224.069728) (xy 105.000806 -224.064576) (xy 105.023666 -224.060258)
			(xy 105.227374 -223.707198) (xy 105.219754 -223.685354) (xy 105.211031 -223.658761) (xy 105.201574 -223.603606)
			(xy 105.200958 -223.575626) (xy 105.201467 -223.549659) (xy 105.209592 -223.498364) (xy 105.22564 -223.448971)
			(xy 105.249218 -223.402697) (xy 105.279744 -223.360681) (xy 105.316467 -223.323958) (xy 105.358483 -223.293432)
			(xy 105.404757 -223.269854) (xy 105.45415 -223.253806) (xy 105.505445 -223.245681) (xy 105.557379 -223.245681)
			(xy 105.608674 -223.253806) (xy 105.658067 -223.269854) (xy 105.704341 -223.293432) (xy 105.746357 -223.323958)
			(xy 105.78308 -223.360681) (xy 105.813606 -223.402697) (xy 105.837184 -223.448971) (xy 105.853232 -223.498364)
			(xy 105.861357 -223.549659) (xy 105.861866 -223.575626) (xy 105.861393 -223.601077) (xy 105.861313 -223.601593)
			(xy 106.141521 -223.601593) (xy 106.141521 -223.549659) (xy 106.149646 -223.498364) (xy 106.165694 -223.448971)
			(xy 106.189272 -223.402697) (xy 106.219798 -223.360681) (xy 106.256521 -223.323958) (xy 106.298537 -223.293432)
			(xy 106.344811 -223.269854) (xy 106.394204 -223.253806) (xy 106.445499 -223.245681) (xy 106.497433 -223.245681)
			(xy 106.548728 -223.253806) (xy 106.598121 -223.269854) (xy 106.644395 -223.293432) (xy 106.686411 -223.323958)
			(xy 106.723134 -223.360681) (xy 106.75366 -223.402697) (xy 106.777238 -223.448971) (xy 106.793286 -223.498364)
			(xy 106.801411 -223.549659) (xy 106.80192 -223.575626) (xy 106.801411 -223.601593) (xy 106.793286 -223.652888)
			(xy 106.777238 -223.702281) (xy 106.75366 -223.748555) (xy 106.723134 -223.790571) (xy 106.686411 -223.827294)
			(xy 106.644395 -223.85782) (xy 106.598121 -223.881398) (xy 106.548728 -223.897446) (xy 106.497433 -223.905571)
			(xy 106.445499 -223.905571) (xy 106.394204 -223.897446) (xy 106.344811 -223.881398) (xy 106.298537 -223.85782)
			(xy 106.256521 -223.827294) (xy 106.219798 -223.790571) (xy 106.189272 -223.748555) (xy 106.165694 -223.702281)
			(xy 106.149646 -223.652888) (xy 106.141521 -223.601593) (xy 105.861313 -223.601593) (xy 105.853611 -223.651381)
			(xy 105.838206 -223.699896) (xy 105.815541 -223.745473) (xy 105.786153 -223.787035) (xy 105.750737 -223.823597)
			(xy 105.710133 -223.854293) (xy 105.6653 -223.878398) (xy 105.617301 -223.895341) (xy 105.592372 -223.900492)
			(xy 105.569258 -223.90481) (xy 105.365804 -224.257616) (xy 105.373424 -224.279714) (xy 105.382166 -224.306301)
			(xy 105.39161 -224.361461) (xy 105.39222 -224.389442) (xy 105.671112 -224.389442) (xy 105.671621 -224.363475)
			(xy 105.679746 -224.31218) (xy 105.695794 -224.262787) (xy 105.719372 -224.216513) (xy 105.749898 -224.174497)
			(xy 105.786621 -224.137774) (xy 105.828637 -224.107248) (xy 105.874911 -224.08367) (xy 105.924304 -224.067622)
			(xy 105.975599 -224.059497) (xy 106.027533 -224.059497) (xy 106.078828 -224.067622) (xy 106.128221 -224.08367)
			(xy 106.174495 -224.107248) (xy 106.216511 -224.137774) (xy 106.253234 -224.174497) (xy 106.28376 -224.216513)
			(xy 106.307338 -224.262787) (xy 106.323386 -224.31218) (xy 106.331511 -224.363475) (xy 106.33202 -224.389442)
			(xy 106.610912 -224.389442) (xy 106.611374 -224.363991) (xy 106.61916 -224.313687) (xy 106.634568 -224.265174)
			(xy 106.657236 -224.219597) (xy 106.686625 -224.178036) (xy 106.722041 -224.141475) (xy 106.762646 -224.110778)
			(xy 106.807478 -224.086672) (xy 106.855477 -224.069728) (xy 106.880406 -224.064576) (xy 106.903266 -224.060258)
			(xy 107.106974 -223.707198) (xy 107.099354 -223.685354) (xy 107.090631 -223.658761) (xy 107.081174 -223.603606)
			(xy 107.080558 -223.575626) (xy 107.081067 -223.549659) (xy 107.089192 -223.498364) (xy 107.10524 -223.448971)
			(xy 107.128818 -223.402697) (xy 107.159344 -223.360681) (xy 107.196067 -223.323958) (xy 107.238083 -223.293432)
			(xy 107.284357 -223.269854) (xy 107.33375 -223.253806) (xy 107.385045 -223.245681) (xy 107.436979 -223.245681)
			(xy 107.488274 -223.253806) (xy 107.537667 -223.269854) (xy 107.583941 -223.293432) (xy 107.625957 -223.323958)
			(xy 107.66268 -223.360681) (xy 107.693206 -223.402697) (xy 107.716784 -223.448971) (xy 107.732832 -223.498364)
			(xy 107.740957 -223.549659) (xy 107.741466 -223.575626) (xy 107.740993 -223.601077) (xy 107.740913 -223.601593)
			(xy 108.021121 -223.601593) (xy 108.021121 -223.549659) (xy 108.029246 -223.498364) (xy 108.045294 -223.448971)
			(xy 108.068872 -223.402697) (xy 108.099398 -223.360681) (xy 108.136121 -223.323958) (xy 108.178137 -223.293432)
			(xy 108.224411 -223.269854) (xy 108.273804 -223.253806) (xy 108.325099 -223.245681) (xy 108.377033 -223.245681)
			(xy 108.428328 -223.253806) (xy 108.477721 -223.269854) (xy 108.523995 -223.293432) (xy 108.566011 -223.323958)
			(xy 108.602734 -223.360681) (xy 108.63326 -223.402697) (xy 108.656838 -223.448971) (xy 108.672886 -223.498364)
			(xy 108.681011 -223.549659) (xy 108.68152 -223.575626) (xy 108.681011 -223.601593) (xy 108.672886 -223.652888)
			(xy 108.656838 -223.702281) (xy 108.63326 -223.748555) (xy 108.602734 -223.790571) (xy 108.566011 -223.827294)
			(xy 108.523995 -223.85782) (xy 108.477721 -223.881398) (xy 108.428328 -223.897446) (xy 108.377033 -223.905571)
			(xy 108.325099 -223.905571) (xy 108.273804 -223.897446) (xy 108.224411 -223.881398) (xy 108.178137 -223.85782)
			(xy 108.136121 -223.827294) (xy 108.099398 -223.790571) (xy 108.068872 -223.748555) (xy 108.045294 -223.702281)
			(xy 108.029246 -223.652888) (xy 108.021121 -223.601593) (xy 107.740913 -223.601593) (xy 107.733211 -223.651381)
			(xy 107.717806 -223.699896) (xy 107.695141 -223.745473) (xy 107.665753 -223.787035) (xy 107.630337 -223.823597)
			(xy 107.589733 -223.854293) (xy 107.5449 -223.878398) (xy 107.496901 -223.895341) (xy 107.471972 -223.900492)
			(xy 107.448858 -223.90481) (xy 107.245404 -224.257616) (xy 107.253024 -224.279714) (xy 107.261766 -224.306301)
			(xy 107.27121 -224.361461) (xy 107.27182 -224.389442) (xy 107.550712 -224.389442) (xy 107.551221 -224.363475)
			(xy 107.559346 -224.31218) (xy 107.575394 -224.262787) (xy 107.598972 -224.216513) (xy 107.629498 -224.174497)
			(xy 107.666221 -224.137774) (xy 107.708237 -224.107248) (xy 107.754511 -224.08367) (xy 107.803904 -224.067622)
			(xy 107.855199 -224.059497) (xy 107.907133 -224.059497) (xy 107.958428 -224.067622) (xy 108.007821 -224.08367)
			(xy 108.054095 -224.107248) (xy 108.096111 -224.137774) (xy 108.132834 -224.174497) (xy 108.16336 -224.216513)
			(xy 108.186938 -224.262787) (xy 108.202986 -224.31218) (xy 108.211111 -224.363475) (xy 108.21162 -224.389442)
			(xy 108.490512 -224.389442) (xy 108.490974 -224.363991) (xy 108.49876 -224.313687) (xy 108.514168 -224.265174)
			(xy 108.536836 -224.219597) (xy 108.566225 -224.178036) (xy 108.601641 -224.141475) (xy 108.642246 -224.110778)
			(xy 108.687078 -224.086672) (xy 108.735077 -224.069728) (xy 108.760006 -224.064576) (xy 108.782866 -224.060258)
			(xy 108.986574 -223.707198) (xy 108.978954 -223.685354) (xy 108.970231 -223.658761) (xy 108.960774 -223.603606)
			(xy 108.960158 -223.575626) (xy 108.960667 -223.549659) (xy 108.968792 -223.498364) (xy 108.98484 -223.448971)
			(xy 109.008418 -223.402697) (xy 109.038944 -223.360681) (xy 109.075667 -223.323958) (xy 109.117683 -223.293432)
			(xy 109.163957 -223.269854) (xy 109.21335 -223.253806) (xy 109.264645 -223.245681) (xy 109.316579 -223.245681)
			(xy 109.367874 -223.253806) (xy 109.417267 -223.269854) (xy 109.463541 -223.293432) (xy 109.505557 -223.323958)
			(xy 109.54228 -223.360681) (xy 109.572806 -223.402697) (xy 109.596384 -223.448971) (xy 109.612432 -223.498364)
			(xy 109.620557 -223.549659) (xy 109.621066 -223.575626) (xy 109.620593 -223.601077) (xy 109.620513 -223.601593)
			(xy 109.900721 -223.601593) (xy 109.900721 -223.549659) (xy 109.908846 -223.498364) (xy 109.924894 -223.448971)
			(xy 109.948472 -223.402697) (xy 109.978998 -223.360681) (xy 110.015721 -223.323958) (xy 110.057737 -223.293432)
			(xy 110.104011 -223.269854) (xy 110.153404 -223.253806) (xy 110.204699 -223.245681) (xy 110.256633 -223.245681)
			(xy 110.307928 -223.253806) (xy 110.357321 -223.269854) (xy 110.403595 -223.293432) (xy 110.445611 -223.323958)
			(xy 110.482334 -223.360681) (xy 110.51286 -223.402697) (xy 110.536438 -223.448971) (xy 110.552486 -223.498364)
			(xy 110.560611 -223.549659) (xy 110.56112 -223.575626) (xy 110.560611 -223.601593) (xy 110.552486 -223.652888)
			(xy 110.536438 -223.702281) (xy 110.51286 -223.748555) (xy 110.482334 -223.790571) (xy 110.445611 -223.827294)
			(xy 110.403595 -223.85782) (xy 110.357321 -223.881398) (xy 110.307928 -223.897446) (xy 110.256633 -223.905571)
			(xy 110.204699 -223.905571) (xy 110.153404 -223.897446) (xy 110.104011 -223.881398) (xy 110.057737 -223.85782)
			(xy 110.015721 -223.827294) (xy 109.978998 -223.790571) (xy 109.948472 -223.748555) (xy 109.924894 -223.702281)
			(xy 109.908846 -223.652888) (xy 109.900721 -223.601593) (xy 109.620513 -223.601593) (xy 109.612811 -223.651381)
			(xy 109.597406 -223.699896) (xy 109.574741 -223.745473) (xy 109.545353 -223.787035) (xy 109.509937 -223.823597)
			(xy 109.469333 -223.854293) (xy 109.4245 -223.878398) (xy 109.376501 -223.895341) (xy 109.351572 -223.900492)
			(xy 109.328458 -223.90481) (xy 109.125004 -224.257616) (xy 109.132624 -224.279714) (xy 109.141366 -224.306301)
			(xy 109.15081 -224.361461) (xy 109.15142 -224.389442) (xy 109.430312 -224.389442) (xy 109.430821 -224.363475)
			(xy 109.438946 -224.31218) (xy 109.454994 -224.262787) (xy 109.478572 -224.216513) (xy 109.509098 -224.174497)
			(xy 109.545821 -224.137774) (xy 109.587837 -224.107248) (xy 109.634111 -224.08367) (xy 109.683504 -224.067622)
			(xy 109.734799 -224.059497) (xy 109.786733 -224.059497) (xy 109.838028 -224.067622) (xy 109.887421 -224.08367)
			(xy 109.933695 -224.107248) (xy 109.975711 -224.137774) (xy 110.012434 -224.174497) (xy 110.04296 -224.216513)
			(xy 110.066538 -224.262787) (xy 110.082586 -224.31218) (xy 110.090711 -224.363475) (xy 110.09122 -224.389442)
			(xy 110.090677 -224.417428) (xy 110.08122 -224.472596) (xy 110.072424 -224.49917) (xy 110.064804 -224.521268)
			(xy 110.268512 -224.874074) (xy 110.291372 -224.878392) (xy 110.316304 -224.883512) (xy 110.36429 -224.900483)
			(xy 110.409109 -224.924607) (xy 110.449702 -224.955314) (xy 110.485109 -224.991878) (xy 110.514496 -225.033436)
			(xy 110.537168 -225.079006) (xy 110.552589 -225.127512) (xy 110.560394 -225.177809) (xy 110.560866 -225.203258)
			(xy 110.560357 -225.229225) (xy 110.552232 -225.28052) (xy 110.536184 -225.329913) (xy 110.512606 -225.376187)
			(xy 110.48208 -225.418203) (xy 110.445357 -225.454926) (xy 110.403341 -225.485452) (xy 110.357067 -225.50903)
			(xy 110.307674 -225.525078) (xy 110.256379 -225.533203) (xy 110.204445 -225.533203) (xy 110.15315 -225.525078)
			(xy 110.103757 -225.50903) (xy 110.057483 -225.485452) (xy 110.015467 -225.454926) (xy 109.978744 -225.418203)
			(xy 109.948218 -225.376187) (xy 109.92464 -225.329913) (xy 109.908592 -225.28052) (xy 109.900467 -225.229225)
			(xy 109.899958 -225.203258) (xy 109.900497 -225.175271) (xy 109.909956 -225.120104) (xy 109.918754 -225.09353)
			(xy 109.926374 -225.071432) (xy 109.722666 -224.718626) (xy 109.699806 -224.714308) (xy 109.674886 -224.709131)
			(xy 109.6269 -224.692171) (xy 109.58208 -224.668057) (xy 109.541485 -224.637359) (xy 109.506075 -224.600802)
			(xy 109.476686 -224.55925) (xy 109.454012 -224.513684) (xy 109.43859 -224.465182) (xy 109.430784 -224.414889)
			(xy 109.430312 -224.389442) (xy 109.15142 -224.389442) (xy 109.150911 -224.415409) (xy 109.142786 -224.466704)
			(xy 109.126738 -224.516097) (xy 109.10316 -224.562371) (xy 109.072634 -224.604387) (xy 109.035911 -224.64111)
			(xy 108.993895 -224.671636) (xy 108.947621 -224.695214) (xy 108.898228 -224.711262) (xy 108.846933 -224.719387)
			(xy 108.794999 -224.719387) (xy 108.743704 -224.711262) (xy 108.694311 -224.695214) (xy 108.648037 -224.671636)
			(xy 108.606021 -224.64111) (xy 108.569298 -224.604387) (xy 108.538772 -224.562371) (xy 108.515194 -224.516097)
			(xy 108.499146 -224.466704) (xy 108.491021 -224.415409) (xy 108.490512 -224.389442) (xy 108.21162 -224.389442)
			(xy 108.211077 -224.417428) (xy 108.20162 -224.472596) (xy 108.192824 -224.49917) (xy 108.185204 -224.521268)
			(xy 108.388912 -224.874074) (xy 108.411772 -224.878392) (xy 108.436704 -224.883512) (xy 108.48469 -224.900483)
			(xy 108.529509 -224.924607) (xy 108.570102 -224.955314) (xy 108.605509 -224.991878) (xy 108.634896 -225.033436)
			(xy 108.657568 -225.079006) (xy 108.672989 -225.127512) (xy 108.680794 -225.177809) (xy 108.681266 -225.203258)
			(xy 108.680757 -225.229225) (xy 108.960667 -225.229225) (xy 108.960667 -225.177291) (xy 108.968792 -225.125996)
			(xy 108.98484 -225.076603) (xy 109.008418 -225.030329) (xy 109.038944 -224.988313) (xy 109.075667 -224.95159)
			(xy 109.117683 -224.921064) (xy 109.163957 -224.897486) (xy 109.21335 -224.881438) (xy 109.264645 -224.873313)
			(xy 109.316579 -224.873313) (xy 109.367874 -224.881438) (xy 109.417267 -224.897486) (xy 109.463541 -224.921064)
			(xy 109.505557 -224.95159) (xy 109.54228 -224.988313) (xy 109.572806 -225.030329) (xy 109.596384 -225.076603)
			(xy 109.612432 -225.125996) (xy 109.620557 -225.177291) (xy 109.621066 -225.203258) (xy 109.620557 -225.229225)
			(xy 109.612432 -225.28052) (xy 109.596384 -225.329913) (xy 109.572806 -225.376187) (xy 109.54228 -225.418203)
			(xy 109.505557 -225.454926) (xy 109.463541 -225.485452) (xy 109.417267 -225.50903) (xy 109.367874 -225.525078)
			(xy 109.316579 -225.533203) (xy 109.264645 -225.533203) (xy 109.21335 -225.525078) (xy 109.163957 -225.50903)
			(xy 109.117683 -225.485452) (xy 109.075667 -225.454926) (xy 109.038944 -225.418203) (xy 109.008418 -225.376187)
			(xy 108.98484 -225.329913) (xy 108.968792 -225.28052) (xy 108.960667 -225.229225) (xy 108.680757 -225.229225)
			(xy 108.672632 -225.28052) (xy 108.656584 -225.329913) (xy 108.633006 -225.376187) (xy 108.60248 -225.418203)
			(xy 108.565757 -225.454926) (xy 108.523741 -225.485452) (xy 108.477467 -225.50903) (xy 108.428074 -225.525078)
			(xy 108.376779 -225.533203) (xy 108.324845 -225.533203) (xy 108.27355 -225.525078) (xy 108.224157 -225.50903)
			(xy 108.177883 -225.485452) (xy 108.135867 -225.454926) (xy 108.099144 -225.418203) (xy 108.068618 -225.376187)
			(xy 108.04504 -225.329913) (xy 108.028992 -225.28052) (xy 108.020867 -225.229225) (xy 108.020358 -225.203258)
			(xy 108.020897 -225.175271) (xy 108.030356 -225.120104) (xy 108.039154 -225.09353) (xy 108.046774 -225.071432)
			(xy 107.843066 -224.718626) (xy 107.820206 -224.714308) (xy 107.795286 -224.709131) (xy 107.7473 -224.692171)
			(xy 107.70248 -224.668057) (xy 107.661885 -224.637359) (xy 107.626475 -224.600802) (xy 107.597086 -224.55925)
			(xy 107.574412 -224.513684) (xy 107.55899 -224.465182) (xy 107.551184 -224.414889) (xy 107.550712 -224.389442)
			(xy 107.27182 -224.389442) (xy 107.271311 -224.415409) (xy 107.263186 -224.466704) (xy 107.247138 -224.516097)
			(xy 107.22356 -224.562371) (xy 107.193034 -224.604387) (xy 107.156311 -224.64111) (xy 107.114295 -224.671636)
			(xy 107.068021 -224.695214) (xy 107.018628 -224.711262) (xy 106.967333 -224.719387) (xy 106.915399 -224.719387)
			(xy 106.864104 -224.711262) (xy 106.814711 -224.695214) (xy 106.768437 -224.671636) (xy 106.726421 -224.64111)
			(xy 106.689698 -224.604387) (xy 106.659172 -224.562371) (xy 106.635594 -224.516097) (xy 106.619546 -224.466704)
			(xy 106.611421 -224.415409) (xy 106.610912 -224.389442) (xy 106.33202 -224.389442) (xy 106.331477 -224.417428)
			(xy 106.32202 -224.472596) (xy 106.313224 -224.49917) (xy 106.305604 -224.521268) (xy 106.509312 -224.874074)
			(xy 106.532172 -224.878392) (xy 106.557104 -224.883512) (xy 106.60509 -224.900483) (xy 106.649909 -224.924607)
			(xy 106.690502 -224.955314) (xy 106.725909 -224.991878) (xy 106.755296 -225.033436) (xy 106.777968 -225.079006)
			(xy 106.793389 -225.127512) (xy 106.801194 -225.177809) (xy 106.801666 -225.203258) (xy 106.801157 -225.229225)
			(xy 107.081067 -225.229225) (xy 107.081067 -225.177291) (xy 107.089192 -225.125996) (xy 107.10524 -225.076603)
			(xy 107.128818 -225.030329) (xy 107.159344 -224.988313) (xy 107.196067 -224.95159) (xy 107.238083 -224.921064)
			(xy 107.284357 -224.897486) (xy 107.33375 -224.881438) (xy 107.385045 -224.873313) (xy 107.436979 -224.873313)
			(xy 107.488274 -224.881438) (xy 107.537667 -224.897486) (xy 107.583941 -224.921064) (xy 107.625957 -224.95159)
			(xy 107.66268 -224.988313) (xy 107.693206 -225.030329) (xy 107.716784 -225.076603) (xy 107.732832 -225.125996)
			(xy 107.740957 -225.177291) (xy 107.741466 -225.203258) (xy 107.740957 -225.229225) (xy 107.732832 -225.28052)
			(xy 107.716784 -225.329913) (xy 107.693206 -225.376187) (xy 107.66268 -225.418203) (xy 107.625957 -225.454926)
			(xy 107.583941 -225.485452) (xy 107.537667 -225.50903) (xy 107.488274 -225.525078) (xy 107.436979 -225.533203)
			(xy 107.385045 -225.533203) (xy 107.33375 -225.525078) (xy 107.284357 -225.50903) (xy 107.238083 -225.485452)
			(xy 107.196067 -225.454926) (xy 107.159344 -225.418203) (xy 107.128818 -225.376187) (xy 107.10524 -225.329913)
			(xy 107.089192 -225.28052) (xy 107.081067 -225.229225) (xy 106.801157 -225.229225) (xy 106.793032 -225.28052)
			(xy 106.776984 -225.329913) (xy 106.753406 -225.376187) (xy 106.72288 -225.418203) (xy 106.686157 -225.454926)
			(xy 106.644141 -225.485452) (xy 106.597867 -225.50903) (xy 106.548474 -225.525078) (xy 106.497179 -225.533203)
			(xy 106.445245 -225.533203) (xy 106.39395 -225.525078) (xy 106.344557 -225.50903) (xy 106.298283 -225.485452)
			(xy 106.256267 -225.454926) (xy 106.219544 -225.418203) (xy 106.189018 -225.376187) (xy 106.16544 -225.329913)
			(xy 106.149392 -225.28052) (xy 106.141267 -225.229225) (xy 106.140758 -225.203258) (xy 106.141297 -225.175271)
			(xy 106.150756 -225.120104) (xy 106.159554 -225.09353) (xy 106.167174 -225.071432) (xy 105.963466 -224.718626)
			(xy 105.940606 -224.714308) (xy 105.915686 -224.709131) (xy 105.8677 -224.692171) (xy 105.82288 -224.668057)
			(xy 105.782285 -224.637359) (xy 105.746875 -224.600802) (xy 105.717486 -224.55925) (xy 105.694812 -224.513684)
			(xy 105.67939 -224.465182) (xy 105.671584 -224.414889) (xy 105.671112 -224.389442) (xy 105.39222 -224.389442)
			(xy 105.391711 -224.415409) (xy 105.383586 -224.466704) (xy 105.367538 -224.516097) (xy 105.34396 -224.562371)
			(xy 105.313434 -224.604387) (xy 105.276711 -224.64111) (xy 105.234695 -224.671636) (xy 105.188421 -224.695214)
			(xy 105.139028 -224.711262) (xy 105.087733 -224.719387) (xy 105.035799 -224.719387) (xy 104.984504 -224.711262)
			(xy 104.935111 -224.695214) (xy 104.888837 -224.671636) (xy 104.846821 -224.64111) (xy 104.810098 -224.604387)
			(xy 104.779572 -224.562371) (xy 104.755994 -224.516097) (xy 104.739946 -224.466704) (xy 104.731821 -224.415409)
			(xy 104.731312 -224.389442) (xy 104.45242 -224.389442) (xy 104.451877 -224.417428) (xy 104.44242 -224.472596)
			(xy 104.433624 -224.49917) (xy 104.426004 -224.521268) (xy 104.629712 -224.874074) (xy 104.652572 -224.878392)
			(xy 104.677504 -224.883512) (xy 104.72549 -224.900483) (xy 104.770309 -224.924607) (xy 104.810902 -224.955314)
			(xy 104.846309 -224.991878) (xy 104.875696 -225.033436) (xy 104.898368 -225.079006) (xy 104.913789 -225.127512)
			(xy 104.921594 -225.177809) (xy 104.922066 -225.203258) (xy 104.921557 -225.229225) (xy 105.201467 -225.229225)
			(xy 105.201467 -225.177291) (xy 105.209592 -225.125996) (xy 105.22564 -225.076603) (xy 105.249218 -225.030329)
			(xy 105.279744 -224.988313) (xy 105.316467 -224.95159) (xy 105.358483 -224.921064) (xy 105.404757 -224.897486)
			(xy 105.45415 -224.881438) (xy 105.505445 -224.873313) (xy 105.557379 -224.873313) (xy 105.608674 -224.881438)
			(xy 105.658067 -224.897486) (xy 105.704341 -224.921064) (xy 105.746357 -224.95159) (xy 105.78308 -224.988313)
			(xy 105.813606 -225.030329) (xy 105.837184 -225.076603) (xy 105.853232 -225.125996) (xy 105.861357 -225.177291)
			(xy 105.861866 -225.203258) (xy 105.861357 -225.229225) (xy 105.853232 -225.28052) (xy 105.837184 -225.329913)
			(xy 105.813606 -225.376187) (xy 105.78308 -225.418203) (xy 105.746357 -225.454926) (xy 105.704341 -225.485452)
			(xy 105.658067 -225.50903) (xy 105.608674 -225.525078) (xy 105.557379 -225.533203) (xy 105.505445 -225.533203)
			(xy 105.45415 -225.525078) (xy 105.404757 -225.50903) (xy 105.358483 -225.485452) (xy 105.316467 -225.454926)
			(xy 105.279744 -225.418203) (xy 105.249218 -225.376187) (xy 105.22564 -225.329913) (xy 105.209592 -225.28052)
			(xy 105.201467 -225.229225) (xy 104.921557 -225.229225) (xy 104.913432 -225.28052) (xy 104.897384 -225.329913)
			(xy 104.873806 -225.376187) (xy 104.84328 -225.418203) (xy 104.806557 -225.454926) (xy 104.764541 -225.485452)
			(xy 104.718267 -225.50903) (xy 104.668874 -225.525078) (xy 104.617579 -225.533203) (xy 104.565645 -225.533203)
			(xy 104.51435 -225.525078) (xy 104.464957 -225.50903) (xy 104.418683 -225.485452) (xy 104.376667 -225.454926)
			(xy 104.339944 -225.418203) (xy 104.309418 -225.376187) (xy 104.28584 -225.329913) (xy 104.269792 -225.28052)
			(xy 104.261667 -225.229225) (xy 104.261158 -225.203258) (xy 104.261697 -225.175271) (xy 104.271156 -225.120104)
			(xy 104.279954 -225.09353) (xy 104.287574 -225.071432) (xy 104.083866 -224.718626) (xy 104.061006 -224.714308)
			(xy 104.036086 -224.709131) (xy 103.9881 -224.692171) (xy 103.94328 -224.668057) (xy 103.902685 -224.637359)
			(xy 103.867275 -224.600802) (xy 103.837886 -224.55925) (xy 103.815212 -224.513684) (xy 103.79979 -224.465182)
			(xy 103.791984 -224.414889) (xy 103.791512 -224.389442) (xy 103.51262 -224.389442) (xy 103.512111 -224.415409)
			(xy 103.503986 -224.466704) (xy 103.487938 -224.516097) (xy 103.46436 -224.562371) (xy 103.433834 -224.604387)
			(xy 103.397111 -224.64111) (xy 103.355095 -224.671636) (xy 103.308821 -224.695214) (xy 103.259428 -224.711262)
			(xy 103.208133 -224.719387) (xy 103.156199 -224.719387) (xy 103.104904 -224.711262) (xy 103.055511 -224.695214)
			(xy 103.009237 -224.671636) (xy 102.967221 -224.64111) (xy 102.930498 -224.604387) (xy 102.899972 -224.562371)
			(xy 102.876394 -224.516097) (xy 102.860346 -224.466704) (xy 102.852221 -224.415409) (xy 102.851712 -224.389442)
			(xy 102.57282 -224.389442) (xy 102.572277 -224.417428) (xy 102.56282 -224.472596) (xy 102.554024 -224.49917)
			(xy 102.546404 -224.521268) (xy 102.750112 -224.874074) (xy 102.772972 -224.878392) (xy 102.797904 -224.883512)
			(xy 102.84589 -224.900483) (xy 102.890709 -224.924607) (xy 102.931302 -224.955314) (xy 102.966709 -224.991878)
			(xy 102.996096 -225.033436) (xy 103.018768 -225.079006) (xy 103.034189 -225.127512) (xy 103.041994 -225.177809)
			(xy 103.042466 -225.203258) (xy 103.041957 -225.229225) (xy 103.321867 -225.229225) (xy 103.321867 -225.177291)
			(xy 103.329992 -225.125996) (xy 103.34604 -225.076603) (xy 103.369618 -225.030329) (xy 103.400144 -224.988313)
			(xy 103.436867 -224.95159) (xy 103.478883 -224.921064) (xy 103.525157 -224.897486) (xy 103.57455 -224.881438)
			(xy 103.625845 -224.873313) (xy 103.677779 -224.873313) (xy 103.729074 -224.881438) (xy 103.778467 -224.897486)
			(xy 103.824741 -224.921064) (xy 103.866757 -224.95159) (xy 103.90348 -224.988313) (xy 103.934006 -225.030329)
			(xy 103.957584 -225.076603) (xy 103.973632 -225.125996) (xy 103.981757 -225.177291) (xy 103.982266 -225.203258)
			(xy 103.981757 -225.229225) (xy 103.973632 -225.28052) (xy 103.957584 -225.329913) (xy 103.934006 -225.376187)
			(xy 103.90348 -225.418203) (xy 103.866757 -225.454926) (xy 103.824741 -225.485452) (xy 103.778467 -225.50903)
			(xy 103.729074 -225.525078) (xy 103.677779 -225.533203) (xy 103.625845 -225.533203) (xy 103.57455 -225.525078)
			(xy 103.525157 -225.50903) (xy 103.478883 -225.485452) (xy 103.436867 -225.454926) (xy 103.400144 -225.418203)
			(xy 103.369618 -225.376187) (xy 103.34604 -225.329913) (xy 103.329992 -225.28052) (xy 103.321867 -225.229225)
			(xy 103.041957 -225.229225) (xy 103.033832 -225.28052) (xy 103.017784 -225.329913) (xy 102.994206 -225.376187)
			(xy 102.96368 -225.418203) (xy 102.926957 -225.454926) (xy 102.884941 -225.485452) (xy 102.838667 -225.50903)
			(xy 102.789274 -225.525078) (xy 102.737979 -225.533203) (xy 102.686045 -225.533203) (xy 102.63475 -225.525078)
			(xy 102.585357 -225.50903) (xy 102.539083 -225.485452) (xy 102.497067 -225.454926) (xy 102.460344 -225.418203)
			(xy 102.429818 -225.376187) (xy 102.40624 -225.329913) (xy 102.390192 -225.28052) (xy 102.382067 -225.229225)
			(xy 102.381558 -225.203258) (xy 102.382097 -225.175271) (xy 102.391556 -225.120104) (xy 102.400354 -225.09353)
			(xy 102.407974 -225.071432) (xy 102.204266 -224.718626) (xy 102.181406 -224.714308) (xy 102.156486 -224.709131)
			(xy 102.1085 -224.692171) (xy 102.06368 -224.668057) (xy 102.023085 -224.637359) (xy 101.987675 -224.600802)
			(xy 101.958286 -224.55925) (xy 101.935612 -224.513684) (xy 101.92019 -224.465182) (xy 101.912384 -224.414889)
			(xy 101.911912 -224.389442) (xy 101.63302 -224.389442) (xy 101.632508 -224.415406) (xy 101.624378 -224.466694)
			(xy 101.608325 -224.516079) (xy 101.584745 -224.562344) (xy 101.554217 -224.604352) (xy 101.517494 -224.641066)
			(xy 101.47548 -224.671584) (xy 101.429209 -224.695154) (xy 101.37982 -224.711196) (xy 101.32853 -224.719314)
			(xy 101.302566 -224.719896) (xy 101.283465 -224.719596) (xy 101.245523 -224.715145) (xy 101.226874 -224.711006)
			(xy 101.212549 -224.708155) (xy 101.183399 -224.709835) (xy 101.155912 -224.719679) (xy 101.132323 -224.736886)
			(xy 101.114555 -224.760054) (xy 101.104054 -224.787298) (xy 101.101675 -224.816398) (xy 101.107611 -224.844986)
			(xy 101.114098 -224.858072) (xy 101.265228 -225.139758) (xy 101.271962 -225.151471) (xy 101.290494 -225.171118)
			(xy 101.313532 -225.185215) (xy 101.339462 -225.192774) (xy 101.366466 -225.193264) (xy 101.392652 -225.186652)
			(xy 101.416187 -225.173401) (xy 101.43542 -225.154439) (xy 101.449004 -225.131096) (xy 101.452934 -225.118168)
			(xy 101.460433 -225.092144) (xy 101.482726 -225.042789) (xy 101.512766 -224.99773) (xy 101.549751 -224.95817)
			(xy 101.592689 -224.925169) (xy 101.640434 -224.899609) (xy 101.691706 -224.882175) (xy 101.745134 -224.873332)
			(xy 101.772212 -224.872804) (xy 101.798182 -224.873314) (xy 101.849482 -224.881441) (xy 101.898879 -224.897493)
			(xy 101.945157 -224.921074) (xy 101.987177 -224.951605) (xy 102.023903 -224.988332) (xy 102.054432 -225.030353)
			(xy 102.078012 -225.076632) (xy 102.094062 -225.12603) (xy 102.102187 -225.17733) (xy 102.102187 -225.22927)
			(xy 102.094062 -225.28057) (xy 102.078012 -225.329968) (xy 102.054432 -225.376247) (xy 102.023903 -225.418268)
			(xy 101.987177 -225.454995) (xy 101.945157 -225.485526) (xy 101.898879 -225.509107) (xy 101.849482 -225.525159)
			(xy 101.798182 -225.533286) (xy 101.772212 -225.533712) (xy 101.745246 -225.533218) (xy 101.692021 -225.524535)
			(xy 101.666294 -225.51644) (xy 101.651748 -225.512166) (xy 101.621454 -225.511416) (xy 101.592274 -225.519584)
			(xy 101.566772 -225.535952) (xy 101.547193 -225.55908) (xy 101.535259 -225.586933) (xy 101.532019 -225.617062)
			(xy 101.537759 -225.646816) (xy 101.544374 -225.660458) (xy 101.749599 -226.043295) (xy 101.912421 -226.043295)
			(xy 101.912421 -225.991361) (xy 101.920546 -225.940066) (xy 101.936594 -225.890673) (xy 101.960172 -225.844399)
			(xy 101.990698 -225.802383) (xy 102.027421 -225.76566) (xy 102.069437 -225.735134) (xy 102.115711 -225.711556)
			(xy 102.165104 -225.695508) (xy 102.216399 -225.687383) (xy 102.268333 -225.687383) (xy 102.319628 -225.695508)
			(xy 102.369021 -225.711556) (xy 102.415295 -225.735134) (xy 102.457311 -225.76566) (xy 102.494034 -225.802383)
			(xy 102.52456 -225.844399) (xy 102.548138 -225.890673) (xy 102.564186 -225.940066) (xy 102.572311 -225.991361)
			(xy 102.57282 -226.017328) (xy 102.572311 -226.043295) (xy 102.852221 -226.043295) (xy 102.852221 -225.991361)
			(xy 102.860346 -225.940066) (xy 102.876394 -225.890673) (xy 102.899972 -225.844399) (xy 102.930498 -225.802383)
			(xy 102.967221 -225.76566) (xy 103.009237 -225.735134) (xy 103.055511 -225.711556) (xy 103.104904 -225.695508)
			(xy 103.156199 -225.687383) (xy 103.208133 -225.687383) (xy 103.259428 -225.695508) (xy 103.308821 -225.711556)
			(xy 103.355095 -225.735134) (xy 103.397111 -225.76566) (xy 103.433834 -225.802383) (xy 103.46436 -225.844399)
			(xy 103.487938 -225.890673) (xy 103.503986 -225.940066) (xy 103.512111 -225.991361) (xy 103.51262 -226.017328)
			(xy 103.512111 -226.043295) (xy 103.792021 -226.043295) (xy 103.792021 -225.991361) (xy 103.800146 -225.940066)
			(xy 103.816194 -225.890673) (xy 103.839772 -225.844399) (xy 103.870298 -225.802383) (xy 103.907021 -225.76566)
			(xy 103.949037 -225.735134) (xy 103.995311 -225.711556) (xy 104.044704 -225.695508) (xy 104.095999 -225.687383)
			(xy 104.147933 -225.687383) (xy 104.199228 -225.695508) (xy 104.248621 -225.711556) (xy 104.294895 -225.735134)
			(xy 104.336911 -225.76566) (xy 104.373634 -225.802383) (xy 104.40416 -225.844399) (xy 104.427738 -225.890673)
			(xy 104.443786 -225.940066) (xy 104.451911 -225.991361) (xy 104.45242 -226.017328) (xy 104.451911 -226.043295)
			(xy 104.731821 -226.043295) (xy 104.731821 -225.991361) (xy 104.739946 -225.940066) (xy 104.755994 -225.890673)
			(xy 104.779572 -225.844399) (xy 104.810098 -225.802383) (xy 104.846821 -225.76566) (xy 104.888837 -225.735134)
			(xy 104.935111 -225.711556) (xy 104.984504 -225.695508) (xy 105.035799 -225.687383) (xy 105.087733 -225.687383)
			(xy 105.139028 -225.695508) (xy 105.188421 -225.711556) (xy 105.234695 -225.735134) (xy 105.276711 -225.76566)
			(xy 105.313434 -225.802383) (xy 105.34396 -225.844399) (xy 105.367538 -225.890673) (xy 105.383586 -225.940066)
			(xy 105.391711 -225.991361) (xy 105.39222 -226.017328) (xy 105.391711 -226.043295) (xy 105.671621 -226.043295)
			(xy 105.671621 -225.991361) (xy 105.679746 -225.940066) (xy 105.695794 -225.890673) (xy 105.719372 -225.844399)
			(xy 105.749898 -225.802383) (xy 105.786621 -225.76566) (xy 105.828637 -225.735134) (xy 105.874911 -225.711556)
			(xy 105.924304 -225.695508) (xy 105.975599 -225.687383) (xy 106.027533 -225.687383) (xy 106.078828 -225.695508)
			(xy 106.128221 -225.711556) (xy 106.174495 -225.735134) (xy 106.216511 -225.76566) (xy 106.253234 -225.802383)
			(xy 106.28376 -225.844399) (xy 106.307338 -225.890673) (xy 106.323386 -225.940066) (xy 106.331511 -225.991361)
			(xy 106.33202 -226.017328) (xy 106.331511 -226.043295) (xy 106.611421 -226.043295) (xy 106.611421 -225.991361)
			(xy 106.619546 -225.940066) (xy 106.635594 -225.890673) (xy 106.659172 -225.844399) (xy 106.689698 -225.802383)
			(xy 106.726421 -225.76566) (xy 106.768437 -225.735134) (xy 106.814711 -225.711556) (xy 106.864104 -225.695508)
			(xy 106.915399 -225.687383) (xy 106.967333 -225.687383) (xy 107.018628 -225.695508) (xy 107.068021 -225.711556)
			(xy 107.114295 -225.735134) (xy 107.156311 -225.76566) (xy 107.193034 -225.802383) (xy 107.22356 -225.844399)
			(xy 107.247138 -225.890673) (xy 107.263186 -225.940066) (xy 107.271311 -225.991361) (xy 107.27182 -226.017328)
			(xy 107.271311 -226.043295) (xy 107.551221 -226.043295) (xy 107.551221 -225.991361) (xy 107.559346 -225.940066)
			(xy 107.575394 -225.890673) (xy 107.598972 -225.844399) (xy 107.629498 -225.802383) (xy 107.666221 -225.76566)
			(xy 107.708237 -225.735134) (xy 107.754511 -225.711556) (xy 107.803904 -225.695508) (xy 107.855199 -225.687383)
			(xy 107.907133 -225.687383) (xy 107.958428 -225.695508) (xy 108.007821 -225.711556) (xy 108.054095 -225.735134)
			(xy 108.096111 -225.76566) (xy 108.132834 -225.802383) (xy 108.16336 -225.844399) (xy 108.186938 -225.890673)
			(xy 108.202986 -225.940066) (xy 108.211111 -225.991361) (xy 108.21162 -226.017328) (xy 108.211111 -226.043295)
			(xy 108.491021 -226.043295) (xy 108.491021 -225.991361) (xy 108.499146 -225.940066) (xy 108.515194 -225.890673)
			(xy 108.538772 -225.844399) (xy 108.569298 -225.802383) (xy 108.606021 -225.76566) (xy 108.648037 -225.735134)
			(xy 108.694311 -225.711556) (xy 108.743704 -225.695508) (xy 108.794999 -225.687383) (xy 108.846933 -225.687383)
			(xy 108.898228 -225.695508) (xy 108.947621 -225.711556) (xy 108.993895 -225.735134) (xy 109.035911 -225.76566)
			(xy 109.072634 -225.802383) (xy 109.10316 -225.844399) (xy 109.126738 -225.890673) (xy 109.142786 -225.940066)
			(xy 109.150911 -225.991361) (xy 109.15142 -226.017328) (xy 109.150911 -226.043295) (xy 109.430821 -226.043295)
			(xy 109.430821 -225.991361) (xy 109.438946 -225.940066) (xy 109.454994 -225.890673) (xy 109.478572 -225.844399)
			(xy 109.509098 -225.802383) (xy 109.545821 -225.76566) (xy 109.587837 -225.735134) (xy 109.634111 -225.711556)
			(xy 109.683504 -225.695508) (xy 109.734799 -225.687383) (xy 109.786733 -225.687383) (xy 109.838028 -225.695508)
			(xy 109.887421 -225.711556) (xy 109.933695 -225.735134) (xy 109.975711 -225.76566) (xy 110.012434 -225.802383)
			(xy 110.04296 -225.844399) (xy 110.066538 -225.890673) (xy 110.082586 -225.940066) (xy 110.090711 -225.991361)
			(xy 110.09122 -226.017328) (xy 110.090711 -226.043295) (xy 110.082586 -226.09459) (xy 110.066538 -226.143983)
			(xy 110.04296 -226.190257) (xy 110.012434 -226.232273) (xy 109.975711 -226.268996) (xy 109.933695 -226.299522)
			(xy 109.887421 -226.3231) (xy 109.838028 -226.339148) (xy 109.786733 -226.347273) (xy 109.734799 -226.347273)
			(xy 109.683504 -226.339148) (xy 109.634111 -226.3231) (xy 109.587837 -226.299522) (xy 109.545821 -226.268996)
			(xy 109.509098 -226.232273) (xy 109.478572 -226.190257) (xy 109.454994 -226.143983) (xy 109.438946 -226.09459)
			(xy 109.430821 -226.043295) (xy 109.150911 -226.043295) (xy 109.142786 -226.09459) (xy 109.126738 -226.143983)
			(xy 109.10316 -226.190257) (xy 109.072634 -226.232273) (xy 109.035911 -226.268996) (xy 108.993895 -226.299522)
			(xy 108.947621 -226.3231) (xy 108.898228 -226.339148) (xy 108.846933 -226.347273) (xy 108.794999 -226.347273)
			(xy 108.743704 -226.339148) (xy 108.694311 -226.3231) (xy 108.648037 -226.299522) (xy 108.606021 -226.268996)
			(xy 108.569298 -226.232273) (xy 108.538772 -226.190257) (xy 108.515194 -226.143983) (xy 108.499146 -226.09459)
			(xy 108.491021 -226.043295) (xy 108.211111 -226.043295) (xy 108.202986 -226.09459) (xy 108.186938 -226.143983)
			(xy 108.16336 -226.190257) (xy 108.132834 -226.232273) (xy 108.096111 -226.268996) (xy 108.054095 -226.299522)
			(xy 108.007821 -226.3231) (xy 107.958428 -226.339148) (xy 107.907133 -226.347273) (xy 107.855199 -226.347273)
			(xy 107.803904 -226.339148) (xy 107.754511 -226.3231) (xy 107.708237 -226.299522) (xy 107.666221 -226.268996)
			(xy 107.629498 -226.232273) (xy 107.598972 -226.190257) (xy 107.575394 -226.143983) (xy 107.559346 -226.09459)
			(xy 107.551221 -226.043295) (xy 107.271311 -226.043295) (xy 107.263186 -226.09459) (xy 107.247138 -226.143983)
			(xy 107.22356 -226.190257) (xy 107.193034 -226.232273) (xy 107.156311 -226.268996) (xy 107.114295 -226.299522)
			(xy 107.068021 -226.3231) (xy 107.018628 -226.339148) (xy 106.967333 -226.347273) (xy 106.915399 -226.347273)
			(xy 106.864104 -226.339148) (xy 106.814711 -226.3231) (xy 106.768437 -226.299522) (xy 106.726421 -226.268996)
			(xy 106.689698 -226.232273) (xy 106.659172 -226.190257) (xy 106.635594 -226.143983) (xy 106.619546 -226.09459)
			(xy 106.611421 -226.043295) (xy 106.331511 -226.043295) (xy 106.323386 -226.09459) (xy 106.307338 -226.143983)
			(xy 106.28376 -226.190257) (xy 106.253234 -226.232273) (xy 106.216511 -226.268996) (xy 106.174495 -226.299522)
			(xy 106.128221 -226.3231) (xy 106.078828 -226.339148) (xy 106.027533 -226.347273) (xy 105.975599 -226.347273)
			(xy 105.924304 -226.339148) (xy 105.874911 -226.3231) (xy 105.828637 -226.299522) (xy 105.786621 -226.268996)
			(xy 105.749898 -226.232273) (xy 105.719372 -226.190257) (xy 105.695794 -226.143983) (xy 105.679746 -226.09459)
			(xy 105.671621 -226.043295) (xy 105.391711 -226.043295) (xy 105.383586 -226.09459) (xy 105.367538 -226.143983)
			(xy 105.34396 -226.190257) (xy 105.313434 -226.232273) (xy 105.276711 -226.268996) (xy 105.234695 -226.299522)
			(xy 105.188421 -226.3231) (xy 105.139028 -226.339148) (xy 105.087733 -226.347273) (xy 105.035799 -226.347273)
			(xy 104.984504 -226.339148) (xy 104.935111 -226.3231) (xy 104.888837 -226.299522) (xy 104.846821 -226.268996)
			(xy 104.810098 -226.232273) (xy 104.779572 -226.190257) (xy 104.755994 -226.143983) (xy 104.739946 -226.09459)
			(xy 104.731821 -226.043295) (xy 104.451911 -226.043295) (xy 104.443786 -226.09459) (xy 104.427738 -226.143983)
			(xy 104.40416 -226.190257) (xy 104.373634 -226.232273) (xy 104.336911 -226.268996) (xy 104.294895 -226.299522)
			(xy 104.248621 -226.3231) (xy 104.199228 -226.339148) (xy 104.147933 -226.347273) (xy 104.095999 -226.347273)
			(xy 104.044704 -226.339148) (xy 103.995311 -226.3231) (xy 103.949037 -226.299522) (xy 103.907021 -226.268996)
			(xy 103.870298 -226.232273) (xy 103.839772 -226.190257) (xy 103.816194 -226.143983) (xy 103.800146 -226.09459)
			(xy 103.792021 -226.043295) (xy 103.512111 -226.043295) (xy 103.503986 -226.09459) (xy 103.487938 -226.143983)
			(xy 103.46436 -226.190257) (xy 103.433834 -226.232273) (xy 103.397111 -226.268996) (xy 103.355095 -226.299522)
			(xy 103.308821 -226.3231) (xy 103.259428 -226.339148) (xy 103.208133 -226.347273) (xy 103.156199 -226.347273)
			(xy 103.104904 -226.339148) (xy 103.055511 -226.3231) (xy 103.009237 -226.299522) (xy 102.967221 -226.268996)
			(xy 102.930498 -226.232273) (xy 102.899972 -226.190257) (xy 102.876394 -226.143983) (xy 102.860346 -226.09459)
			(xy 102.852221 -226.043295) (xy 102.572311 -226.043295) (xy 102.564186 -226.09459) (xy 102.548138 -226.143983)
			(xy 102.52456 -226.190257) (xy 102.494034 -226.232273) (xy 102.457311 -226.268996) (xy 102.415295 -226.299522)
			(xy 102.369021 -226.3231) (xy 102.319628 -226.339148) (xy 102.268333 -226.347273) (xy 102.216399 -226.347273)
			(xy 102.165104 -226.339148) (xy 102.115711 -226.3231) (xy 102.069437 -226.299522) (xy 102.027421 -226.268996)
			(xy 101.990698 -226.232273) (xy 101.960172 -226.190257) (xy 101.936594 -226.143983) (xy 101.920546 -226.09459)
			(xy 101.912421 -226.043295) (xy 101.749599 -226.043295) (xy 102.185856 -226.857111) (xy 102.382067 -226.857111)
			(xy 102.382067 -226.805177) (xy 102.390192 -226.753882) (xy 102.40624 -226.704489) (xy 102.429818 -226.658215)
			(xy 102.460344 -226.616199) (xy 102.497067 -226.579476) (xy 102.539083 -226.54895) (xy 102.585357 -226.525372)
			(xy 102.63475 -226.509324) (xy 102.686045 -226.501199) (xy 102.737979 -226.501199) (xy 102.789274 -226.509324)
			(xy 102.838667 -226.525372) (xy 102.884941 -226.54895) (xy 102.926957 -226.579476) (xy 102.96368 -226.616199)
			(xy 102.994206 -226.658215) (xy 103.017784 -226.704489) (xy 103.033832 -226.753882) (xy 103.041957 -226.805177)
			(xy 103.042466 -226.831144) (xy 103.041957 -226.857111) (xy 103.322121 -226.857111) (xy 103.322121 -226.805177)
			(xy 103.330246 -226.753882) (xy 103.346294 -226.704489) (xy 103.369872 -226.658215) (xy 103.400398 -226.616199)
			(xy 103.437121 -226.579476) (xy 103.479137 -226.54895) (xy 103.525411 -226.525372) (xy 103.574804 -226.509324)
			(xy 103.626099 -226.501199) (xy 103.678033 -226.501199) (xy 103.729328 -226.509324) (xy 103.778721 -226.525372)
			(xy 103.824995 -226.54895) (xy 103.867011 -226.579476) (xy 103.903734 -226.616199) (xy 103.93426 -226.658215)
			(xy 103.957838 -226.704489) (xy 103.973886 -226.753882) (xy 103.982011 -226.805177) (xy 103.98252 -226.831144)
			(xy 103.982011 -226.857111) (xy 104.261921 -226.857111) (xy 104.261921 -226.805177) (xy 104.270046 -226.753882)
			(xy 104.286094 -226.704489) (xy 104.309672 -226.658215) (xy 104.340198 -226.616199) (xy 104.376921 -226.579476)
			(xy 104.418937 -226.54895) (xy 104.465211 -226.525372) (xy 104.514604 -226.509324) (xy 104.565899 -226.501199)
			(xy 104.617833 -226.501199) (xy 104.669128 -226.509324) (xy 104.718521 -226.525372) (xy 104.764795 -226.54895)
			(xy 104.806811 -226.579476) (xy 104.843534 -226.616199) (xy 104.87406 -226.658215) (xy 104.897638 -226.704489)
			(xy 104.913686 -226.753882) (xy 104.921811 -226.805177) (xy 104.92232 -226.831144) (xy 104.921811 -226.857111)
			(xy 105.201467 -226.857111) (xy 105.201467 -226.805177) (xy 105.209592 -226.753882) (xy 105.22564 -226.704489)
			(xy 105.249218 -226.658215) (xy 105.279744 -226.616199) (xy 105.316467 -226.579476) (xy 105.358483 -226.54895)
			(xy 105.404757 -226.525372) (xy 105.45415 -226.509324) (xy 105.505445 -226.501199) (xy 105.557379 -226.501199)
			(xy 105.608674 -226.509324) (xy 105.658067 -226.525372) (xy 105.704341 -226.54895) (xy 105.746357 -226.579476)
			(xy 105.78308 -226.616199) (xy 105.813606 -226.658215) (xy 105.837184 -226.704489) (xy 105.853232 -226.753882)
			(xy 105.861357 -226.805177) (xy 105.861866 -226.831144) (xy 105.861357 -226.857111) (xy 106.141521 -226.857111)
			(xy 106.141521 -226.805177) (xy 106.149646 -226.753882) (xy 106.165694 -226.704489) (xy 106.189272 -226.658215)
			(xy 106.219798 -226.616199) (xy 106.256521 -226.579476) (xy 106.298537 -226.54895) (xy 106.344811 -226.525372)
			(xy 106.394204 -226.509324) (xy 106.445499 -226.501199) (xy 106.497433 -226.501199) (xy 106.548728 -226.509324)
			(xy 106.598121 -226.525372) (xy 106.644395 -226.54895) (xy 106.686411 -226.579476) (xy 106.723134 -226.616199)
			(xy 106.75366 -226.658215) (xy 106.777238 -226.704489) (xy 106.793286 -226.753882) (xy 106.801411 -226.805177)
			(xy 106.80192 -226.831144) (xy 106.801411 -226.857111) (xy 107.081067 -226.857111) (xy 107.081067 -226.805177)
			(xy 107.089192 -226.753882) (xy 107.10524 -226.704489) (xy 107.128818 -226.658215) (xy 107.159344 -226.616199)
			(xy 107.196067 -226.579476) (xy 107.238083 -226.54895) (xy 107.284357 -226.525372) (xy 107.33375 -226.509324)
			(xy 107.385045 -226.501199) (xy 107.436979 -226.501199) (xy 107.488274 -226.509324) (xy 107.537667 -226.525372)
			(xy 107.583941 -226.54895) (xy 107.625957 -226.579476) (xy 107.66268 -226.616199) (xy 107.693206 -226.658215)
			(xy 107.716784 -226.704489) (xy 107.732832 -226.753882) (xy 107.740957 -226.805177) (xy 107.741466 -226.831144)
			(xy 107.740957 -226.857111) (xy 108.021121 -226.857111) (xy 108.021121 -226.805177) (xy 108.029246 -226.753882)
			(xy 108.045294 -226.704489) (xy 108.068872 -226.658215) (xy 108.099398 -226.616199) (xy 108.136121 -226.579476)
			(xy 108.178137 -226.54895) (xy 108.224411 -226.525372) (xy 108.273804 -226.509324) (xy 108.325099 -226.501199)
			(xy 108.377033 -226.501199) (xy 108.428328 -226.509324) (xy 108.477721 -226.525372) (xy 108.523995 -226.54895)
			(xy 108.566011 -226.579476) (xy 108.602734 -226.616199) (xy 108.63326 -226.658215) (xy 108.656838 -226.704489)
			(xy 108.672886 -226.753882) (xy 108.681011 -226.805177) (xy 108.68152 -226.831144) (xy 108.681011 -226.857111)
			(xy 108.960667 -226.857111) (xy 108.960667 -226.805177) (xy 108.968792 -226.753882) (xy 108.98484 -226.704489)
			(xy 109.008418 -226.658215) (xy 109.038944 -226.616199) (xy 109.075667 -226.579476) (xy 109.117683 -226.54895)
			(xy 109.163957 -226.525372) (xy 109.21335 -226.509324) (xy 109.264645 -226.501199) (xy 109.316579 -226.501199)
			(xy 109.367874 -226.509324) (xy 109.417267 -226.525372) (xy 109.463541 -226.54895) (xy 109.505557 -226.579476)
			(xy 109.54228 -226.616199) (xy 109.572806 -226.658215) (xy 109.596384 -226.704489) (xy 109.612432 -226.753882)
			(xy 109.620557 -226.805177) (xy 109.621066 -226.831144) (xy 109.620557 -226.857111) (xy 109.900721 -226.857111)
			(xy 109.900721 -226.805177) (xy 109.908846 -226.753882) (xy 109.924894 -226.704489) (xy 109.948472 -226.658215)
			(xy 109.978998 -226.616199) (xy 110.015721 -226.579476) (xy 110.057737 -226.54895) (xy 110.104011 -226.525372)
			(xy 110.153404 -226.509324) (xy 110.204699 -226.501199) (xy 110.256633 -226.501199) (xy 110.307928 -226.509324)
			(xy 110.357321 -226.525372) (xy 110.403595 -226.54895) (xy 110.445611 -226.579476) (xy 110.482334 -226.616199)
			(xy 110.51286 -226.658215) (xy 110.536438 -226.704489) (xy 110.552486 -226.753882) (xy 110.560611 -226.805177)
			(xy 110.56112 -226.831144) (xy 110.560611 -226.857111) (xy 110.552486 -226.908406) (xy 110.536438 -226.957799)
			(xy 110.51286 -227.004073) (xy 110.482334 -227.046089) (xy 110.445611 -227.082812) (xy 110.403595 -227.113338)
			(xy 110.357321 -227.136916) (xy 110.307928 -227.152964) (xy 110.256633 -227.161089) (xy 110.204699 -227.161089)
			(xy 110.153404 -227.152964) (xy 110.104011 -227.136916) (xy 110.057737 -227.113338) (xy 110.015721 -227.082812)
			(xy 109.978998 -227.046089) (xy 109.948472 -227.004073) (xy 109.924894 -226.957799) (xy 109.908846 -226.908406)
			(xy 109.900721 -226.857111) (xy 109.620557 -226.857111) (xy 109.612432 -226.908406) (xy 109.596384 -226.957799)
			(xy 109.572806 -227.004073) (xy 109.54228 -227.046089) (xy 109.505557 -227.082812) (xy 109.463541 -227.113338)
			(xy 109.417267 -227.136916) (xy 109.367874 -227.152964) (xy 109.316579 -227.161089) (xy 109.264645 -227.161089)
			(xy 109.21335 -227.152964) (xy 109.163957 -227.136916) (xy 109.117683 -227.113338) (xy 109.075667 -227.082812)
			(xy 109.038944 -227.046089) (xy 109.008418 -227.004073) (xy 108.98484 -226.957799) (xy 108.968792 -226.908406)
			(xy 108.960667 -226.857111) (xy 108.681011 -226.857111) (xy 108.672886 -226.908406) (xy 108.656838 -226.957799)
			(xy 108.63326 -227.004073) (xy 108.602734 -227.046089) (xy 108.566011 -227.082812) (xy 108.523995 -227.113338)
			(xy 108.477721 -227.136916) (xy 108.428328 -227.152964) (xy 108.377033 -227.161089) (xy 108.325099 -227.161089)
			(xy 108.273804 -227.152964) (xy 108.224411 -227.136916) (xy 108.178137 -227.113338) (xy 108.136121 -227.082812)
			(xy 108.099398 -227.046089) (xy 108.068872 -227.004073) (xy 108.045294 -226.957799) (xy 108.029246 -226.908406)
			(xy 108.021121 -226.857111) (xy 107.740957 -226.857111) (xy 107.732832 -226.908406) (xy 107.716784 -226.957799)
			(xy 107.693206 -227.004073) (xy 107.66268 -227.046089) (xy 107.625957 -227.082812) (xy 107.583941 -227.113338)
			(xy 107.537667 -227.136916) (xy 107.488274 -227.152964) (xy 107.436979 -227.161089) (xy 107.385045 -227.161089)
			(xy 107.33375 -227.152964) (xy 107.284357 -227.136916) (xy 107.238083 -227.113338) (xy 107.196067 -227.082812)
			(xy 107.159344 -227.046089) (xy 107.128818 -227.004073) (xy 107.10524 -226.957799) (xy 107.089192 -226.908406)
			(xy 107.081067 -226.857111) (xy 106.801411 -226.857111) (xy 106.793286 -226.908406) (xy 106.777238 -226.957799)
			(xy 106.75366 -227.004073) (xy 106.723134 -227.046089) (xy 106.686411 -227.082812) (xy 106.644395 -227.113338)
			(xy 106.598121 -227.136916) (xy 106.548728 -227.152964) (xy 106.497433 -227.161089) (xy 106.445499 -227.161089)
			(xy 106.394204 -227.152964) (xy 106.344811 -227.136916) (xy 106.298537 -227.113338) (xy 106.256521 -227.082812)
			(xy 106.219798 -227.046089) (xy 106.189272 -227.004073) (xy 106.165694 -226.957799) (xy 106.149646 -226.908406)
			(xy 106.141521 -226.857111) (xy 105.861357 -226.857111) (xy 105.853232 -226.908406) (xy 105.837184 -226.957799)
			(xy 105.813606 -227.004073) (xy 105.78308 -227.046089) (xy 105.746357 -227.082812) (xy 105.704341 -227.113338)
			(xy 105.658067 -227.136916) (xy 105.608674 -227.152964) (xy 105.557379 -227.161089) (xy 105.505445 -227.161089)
			(xy 105.45415 -227.152964) (xy 105.404757 -227.136916) (xy 105.358483 -227.113338) (xy 105.316467 -227.082812)
			(xy 105.279744 -227.046089) (xy 105.249218 -227.004073) (xy 105.22564 -226.957799) (xy 105.209592 -226.908406)
			(xy 105.201467 -226.857111) (xy 104.921811 -226.857111) (xy 104.913686 -226.908406) (xy 104.897638 -226.957799)
			(xy 104.87406 -227.004073) (xy 104.843534 -227.046089) (xy 104.806811 -227.082812) (xy 104.764795 -227.113338)
			(xy 104.718521 -227.136916) (xy 104.669128 -227.152964) (xy 104.617833 -227.161089) (xy 104.565899 -227.161089)
			(xy 104.514604 -227.152964) (xy 104.465211 -227.136916) (xy 104.418937 -227.113338) (xy 104.376921 -227.082812)
			(xy 104.340198 -227.046089) (xy 104.309672 -227.004073) (xy 104.286094 -226.957799) (xy 104.270046 -226.908406)
			(xy 104.261921 -226.857111) (xy 103.982011 -226.857111) (xy 103.973886 -226.908406) (xy 103.957838 -226.957799)
			(xy 103.93426 -227.004073) (xy 103.903734 -227.046089) (xy 103.867011 -227.082812) (xy 103.824995 -227.113338)
			(xy 103.778721 -227.136916) (xy 103.729328 -227.152964) (xy 103.678033 -227.161089) (xy 103.626099 -227.161089)
			(xy 103.574804 -227.152964) (xy 103.525411 -227.136916) (xy 103.479137 -227.113338) (xy 103.437121 -227.082812)
			(xy 103.400398 -227.046089) (xy 103.369872 -227.004073) (xy 103.346294 -226.957799) (xy 103.330246 -226.908406)
			(xy 103.322121 -226.857111) (xy 103.041957 -226.857111) (xy 103.033832 -226.908406) (xy 103.017784 -226.957799)
			(xy 102.994206 -227.004073) (xy 102.96368 -227.046089) (xy 102.926957 -227.082812) (xy 102.884941 -227.113338)
			(xy 102.838667 -227.136916) (xy 102.789274 -227.152964) (xy 102.737979 -227.161089) (xy 102.686045 -227.161089)
			(xy 102.63475 -227.152964) (xy 102.585357 -227.136916) (xy 102.539083 -227.113338) (xy 102.497067 -227.082812)
			(xy 102.460344 -227.046089) (xy 102.429818 -227.004073) (xy 102.40624 -226.957799) (xy 102.390192 -226.908406)
			(xy 102.382067 -226.857111) (xy 102.185856 -226.857111) (xy 102.492048 -227.428298) (xy 102.49535 -227.432362)
			(xy 102.509694 -227.450068) (xy 102.533899 -227.488677) (xy 102.552583 -227.530239) (xy 102.559358 -227.551996)
			(xy 102.560882 -227.557076) (xy 102.621954 -227.670927) (xy 102.852221 -227.670927) (xy 102.852221 -227.618993)
			(xy 102.860346 -227.567698) (xy 102.876394 -227.518305) (xy 102.899972 -227.472031) (xy 102.930498 -227.430015)
			(xy 102.967221 -227.393292) (xy 103.009237 -227.362766) (xy 103.055511 -227.339188) (xy 103.104904 -227.32314)
			(xy 103.156199 -227.315015) (xy 103.208133 -227.315015) (xy 103.259428 -227.32314) (xy 103.308821 -227.339188)
			(xy 103.355095 -227.362766) (xy 103.397111 -227.393292) (xy 103.433834 -227.430015) (xy 103.46436 -227.472031)
			(xy 103.487938 -227.518305) (xy 103.503986 -227.567698) (xy 103.512111 -227.618993) (xy 103.51262 -227.64496)
			(xy 103.512111 -227.670927) (xy 103.792021 -227.670927) (xy 103.792021 -227.618993) (xy 103.800146 -227.567698)
			(xy 103.816194 -227.518305) (xy 103.839772 -227.472031) (xy 103.870298 -227.430015) (xy 103.907021 -227.393292)
			(xy 103.949037 -227.362766) (xy 103.995311 -227.339188) (xy 104.044704 -227.32314) (xy 104.095999 -227.315015)
			(xy 104.147933 -227.315015) (xy 104.199228 -227.32314) (xy 104.248621 -227.339188) (xy 104.294895 -227.362766)
			(xy 104.336911 -227.393292) (xy 104.373634 -227.430015) (xy 104.40416 -227.472031) (xy 104.427738 -227.518305)
			(xy 104.443786 -227.567698) (xy 104.451911 -227.618993) (xy 104.45242 -227.64496) (xy 104.451911 -227.670927)
			(xy 104.731821 -227.670927) (xy 104.731821 -227.618993) (xy 104.739946 -227.567698) (xy 104.755994 -227.518305)
			(xy 104.779572 -227.472031) (xy 104.810098 -227.430015) (xy 104.846821 -227.393292) (xy 104.888837 -227.362766)
			(xy 104.935111 -227.339188) (xy 104.984504 -227.32314) (xy 105.035799 -227.315015) (xy 105.087733 -227.315015)
			(xy 105.139028 -227.32314) (xy 105.188421 -227.339188) (xy 105.234695 -227.362766) (xy 105.276711 -227.393292)
			(xy 105.313434 -227.430015) (xy 105.34396 -227.472031) (xy 105.367538 -227.518305) (xy 105.383586 -227.567698)
			(xy 105.391711 -227.618993) (xy 105.39222 -227.64496) (xy 105.391711 -227.670927) (xy 105.671621 -227.670927)
			(xy 105.671621 -227.618993) (xy 105.679746 -227.567698) (xy 105.695794 -227.518305) (xy 105.719372 -227.472031)
			(xy 105.749898 -227.430015) (xy 105.786621 -227.393292) (xy 105.828637 -227.362766) (xy 105.874911 -227.339188)
			(xy 105.924304 -227.32314) (xy 105.975599 -227.315015) (xy 106.027533 -227.315015) (xy 106.078828 -227.32314)
			(xy 106.128221 -227.339188) (xy 106.174495 -227.362766) (xy 106.216511 -227.393292) (xy 106.253234 -227.430015)
			(xy 106.28376 -227.472031) (xy 106.307338 -227.518305) (xy 106.323386 -227.567698) (xy 106.331511 -227.618993)
			(xy 106.33202 -227.64496) (xy 106.331511 -227.670927) (xy 106.611421 -227.670927) (xy 106.611421 -227.618993)
			(xy 106.619546 -227.567698) (xy 106.635594 -227.518305) (xy 106.659172 -227.472031) (xy 106.689698 -227.430015)
			(xy 106.726421 -227.393292) (xy 106.768437 -227.362766) (xy 106.814711 -227.339188) (xy 106.864104 -227.32314)
			(xy 106.915399 -227.315015) (xy 106.967333 -227.315015) (xy 107.018628 -227.32314) (xy 107.068021 -227.339188)
			(xy 107.114295 -227.362766) (xy 107.156311 -227.393292) (xy 107.193034 -227.430015) (xy 107.22356 -227.472031)
			(xy 107.247138 -227.518305) (xy 107.263186 -227.567698) (xy 107.271311 -227.618993) (xy 107.27182 -227.64496)
			(xy 107.271311 -227.670927) (xy 107.551221 -227.670927) (xy 107.551221 -227.618993) (xy 107.559346 -227.567698)
			(xy 107.575394 -227.518305) (xy 107.598972 -227.472031) (xy 107.629498 -227.430015) (xy 107.666221 -227.393292)
			(xy 107.708237 -227.362766) (xy 107.754511 -227.339188) (xy 107.803904 -227.32314) (xy 107.855199 -227.315015)
			(xy 107.907133 -227.315015) (xy 107.958428 -227.32314) (xy 108.007821 -227.339188) (xy 108.054095 -227.362766)
			(xy 108.096111 -227.393292) (xy 108.132834 -227.430015) (xy 108.16336 -227.472031) (xy 108.186938 -227.518305)
			(xy 108.202986 -227.567698) (xy 108.211111 -227.618993) (xy 108.21162 -227.64496) (xy 108.211111 -227.670927)
			(xy 108.491021 -227.670927) (xy 108.491021 -227.618993) (xy 108.499146 -227.567698) (xy 108.515194 -227.518305)
			(xy 108.538772 -227.472031) (xy 108.569298 -227.430015) (xy 108.606021 -227.393292) (xy 108.648037 -227.362766)
			(xy 108.694311 -227.339188) (xy 108.743704 -227.32314) (xy 108.794999 -227.315015) (xy 108.846933 -227.315015)
			(xy 108.898228 -227.32314) (xy 108.947621 -227.339188) (xy 108.993895 -227.362766) (xy 109.035911 -227.393292)
			(xy 109.072634 -227.430015) (xy 109.10316 -227.472031) (xy 109.126738 -227.518305) (xy 109.142786 -227.567698)
			(xy 109.150911 -227.618993) (xy 109.15142 -227.64496) (xy 109.150911 -227.670927) (xy 109.430821 -227.670927)
			(xy 109.430821 -227.618993) (xy 109.438946 -227.567698) (xy 109.454994 -227.518305) (xy 109.478572 -227.472031)
			(xy 109.509098 -227.430015) (xy 109.545821 -227.393292) (xy 109.587837 -227.362766) (xy 109.634111 -227.339188)
			(xy 109.683504 -227.32314) (xy 109.734799 -227.315015) (xy 109.786733 -227.315015) (xy 109.838028 -227.32314)
			(xy 109.887421 -227.339188) (xy 109.933695 -227.362766) (xy 109.975711 -227.393292) (xy 110.012434 -227.430015)
			(xy 110.04296 -227.472031) (xy 110.066538 -227.518305) (xy 110.082586 -227.567698) (xy 110.090711 -227.618993)
			(xy 110.09122 -227.64496) (xy 110.090711 -227.670927) (xy 110.082586 -227.722222) (xy 110.066538 -227.771615)
			(xy 110.04296 -227.817889) (xy 110.012434 -227.859905) (xy 109.975711 -227.896628) (xy 109.933695 -227.927154)
			(xy 109.887421 -227.950732) (xy 109.838028 -227.96678) (xy 109.786733 -227.974905) (xy 109.734799 -227.974905)
			(xy 109.683504 -227.96678) (xy 109.634111 -227.950732) (xy 109.587837 -227.927154) (xy 109.545821 -227.896628)
			(xy 109.509098 -227.859905) (xy 109.478572 -227.817889) (xy 109.454994 -227.771615) (xy 109.438946 -227.722222)
			(xy 109.430821 -227.670927) (xy 109.150911 -227.670927) (xy 109.142786 -227.722222) (xy 109.126738 -227.771615)
			(xy 109.10316 -227.817889) (xy 109.072634 -227.859905) (xy 109.035911 -227.896628) (xy 108.993895 -227.927154)
			(xy 108.947621 -227.950732) (xy 108.898228 -227.96678) (xy 108.846933 -227.974905) (xy 108.794999 -227.974905)
			(xy 108.743704 -227.96678) (xy 108.694311 -227.950732) (xy 108.648037 -227.927154) (xy 108.606021 -227.896628)
			(xy 108.569298 -227.859905) (xy 108.538772 -227.817889) (xy 108.515194 -227.771615) (xy 108.499146 -227.722222)
			(xy 108.491021 -227.670927) (xy 108.211111 -227.670927) (xy 108.202986 -227.722222) (xy 108.186938 -227.771615)
			(xy 108.16336 -227.817889) (xy 108.132834 -227.859905) (xy 108.096111 -227.896628) (xy 108.054095 -227.927154)
			(xy 108.007821 -227.950732) (xy 107.958428 -227.96678) (xy 107.907133 -227.974905) (xy 107.855199 -227.974905)
			(xy 107.803904 -227.96678) (xy 107.754511 -227.950732) (xy 107.708237 -227.927154) (xy 107.666221 -227.896628)
			(xy 107.629498 -227.859905) (xy 107.598972 -227.817889) (xy 107.575394 -227.771615) (xy 107.559346 -227.722222)
			(xy 107.551221 -227.670927) (xy 107.271311 -227.670927) (xy 107.263186 -227.722222) (xy 107.247138 -227.771615)
			(xy 107.22356 -227.817889) (xy 107.193034 -227.859905) (xy 107.156311 -227.896628) (xy 107.114295 -227.927154)
			(xy 107.068021 -227.950732) (xy 107.018628 -227.96678) (xy 106.967333 -227.974905) (xy 106.915399 -227.974905)
			(xy 106.864104 -227.96678) (xy 106.814711 -227.950732) (xy 106.768437 -227.927154) (xy 106.726421 -227.896628)
			(xy 106.689698 -227.859905) (xy 106.659172 -227.817889) (xy 106.635594 -227.771615) (xy 106.619546 -227.722222)
			(xy 106.611421 -227.670927) (xy 106.331511 -227.670927) (xy 106.323386 -227.722222) (xy 106.307338 -227.771615)
			(xy 106.28376 -227.817889) (xy 106.253234 -227.859905) (xy 106.216511 -227.896628) (xy 106.174495 -227.927154)
			(xy 106.128221 -227.950732) (xy 106.078828 -227.96678) (xy 106.027533 -227.974905) (xy 105.975599 -227.974905)
			(xy 105.924304 -227.96678) (xy 105.874911 -227.950732) (xy 105.828637 -227.927154) (xy 105.786621 -227.896628)
			(xy 105.749898 -227.859905) (xy 105.719372 -227.817889) (xy 105.695794 -227.771615) (xy 105.679746 -227.722222)
			(xy 105.671621 -227.670927) (xy 105.391711 -227.670927) (xy 105.383586 -227.722222) (xy 105.367538 -227.771615)
			(xy 105.34396 -227.817889) (xy 105.313434 -227.859905) (xy 105.276711 -227.896628) (xy 105.234695 -227.927154)
			(xy 105.188421 -227.950732) (xy 105.139028 -227.96678) (xy 105.087733 -227.974905) (xy 105.035799 -227.974905)
			(xy 104.984504 -227.96678) (xy 104.935111 -227.950732) (xy 104.888837 -227.927154) (xy 104.846821 -227.896628)
			(xy 104.810098 -227.859905) (xy 104.779572 -227.817889) (xy 104.755994 -227.771615) (xy 104.739946 -227.722222)
			(xy 104.731821 -227.670927) (xy 104.451911 -227.670927) (xy 104.443786 -227.722222) (xy 104.427738 -227.771615)
			(xy 104.40416 -227.817889) (xy 104.373634 -227.859905) (xy 104.336911 -227.896628) (xy 104.294895 -227.927154)
			(xy 104.248621 -227.950732) (xy 104.199228 -227.96678) (xy 104.147933 -227.974905) (xy 104.095999 -227.974905)
			(xy 104.044704 -227.96678) (xy 103.995311 -227.950732) (xy 103.949037 -227.927154) (xy 103.907021 -227.896628)
			(xy 103.870298 -227.859905) (xy 103.839772 -227.817889) (xy 103.816194 -227.771615) (xy 103.800146 -227.722222)
			(xy 103.792021 -227.670927) (xy 103.512111 -227.670927) (xy 103.503986 -227.722222) (xy 103.487938 -227.771615)
			(xy 103.46436 -227.817889) (xy 103.433834 -227.859905) (xy 103.397111 -227.896628) (xy 103.355095 -227.927154)
			(xy 103.308821 -227.950732) (xy 103.259428 -227.96678) (xy 103.208133 -227.974905) (xy 103.156199 -227.974905)
			(xy 103.104904 -227.96678) (xy 103.055511 -227.950732) (xy 103.009237 -227.927154) (xy 102.967221 -227.896628)
			(xy 102.930498 -227.859905) (xy 102.899972 -227.817889) (xy 102.876394 -227.771615) (xy 102.860346 -227.722222)
			(xy 102.852221 -227.670927) (xy 102.621954 -227.670927) (xy 102.699312 -227.81514) (xy 103.52278 -228.638608)
			(xy 103.79202 -228.638608) (xy 103.981758 -228.44887) (xy 104.258618 -228.44887) (xy 104.265476 -228.406198)
			(xy 104.270115 -228.380714) (xy 104.286274 -228.331504) (xy 104.309915 -228.285419) (xy 104.340457 -228.243588)
			(xy 104.377153 -228.207035) (xy 104.419104 -228.176656) (xy 104.465281 -228.153195) (xy 104.514554 -228.137228)
			(xy 104.565714 -228.129146) (xy 104.61751 -228.129146) (xy 104.66867 -228.137228) (xy 104.717943 -228.153195)
			(xy 104.76412 -228.176656) (xy 104.806071 -228.207035) (xy 104.842767 -228.243588) (xy 104.873309 -228.285419)
			(xy 104.89695 -228.331504) (xy 104.913109 -228.380714) (xy 104.917748 -228.406198) (xy 104.924606 -228.44887)
			(xy 105.213658 -228.44887) (xy 105.435908 -228.67112) (xy 105.649268 -228.67112) (xy 105.899458 -228.42093)
			(xy 106.140504 -228.42093) (xy 106.149902 -228.382068) (xy 106.156423 -228.35692) (xy 106.176281 -228.308915)
			(xy 106.203407 -228.264609) (xy 106.237133 -228.225095) (xy 106.276627 -228.191345) (xy 106.320916 -228.164191)
			(xy 106.368908 -228.144304) (xy 106.419422 -228.132171) (xy 106.471212 -228.128094) (xy 106.523002 -228.132171)
			(xy 106.573516 -228.144304) (xy 106.621508 -228.164191) (xy 106.665797 -228.191345) (xy 106.705291 -228.225095)
			(xy 106.739017 -228.264609) (xy 106.766143 -228.308915) (xy 106.786001 -228.35692) (xy 106.792522 -228.382068)
			(xy 106.80192 -228.42093) (xy 107.050078 -228.42093) (xy 107.114145 -228.484997) (xy 108.020867 -228.484997)
			(xy 108.020867 -228.433063) (xy 108.028992 -228.381768) (xy 108.04504 -228.332375) (xy 108.068618 -228.286101)
			(xy 108.099144 -228.244085) (xy 108.135867 -228.207362) (xy 108.177883 -228.176836) (xy 108.224157 -228.153258)
			(xy 108.27355 -228.13721) (xy 108.324845 -228.129085) (xy 108.376779 -228.129085) (xy 108.428074 -228.13721)
			(xy 108.477467 -228.153258) (xy 108.523741 -228.176836) (xy 108.565757 -228.207362) (xy 108.60248 -228.244085)
			(xy 108.633006 -228.286101) (xy 108.656584 -228.332375) (xy 108.672632 -228.381768) (xy 108.680757 -228.433063)
			(xy 108.681266 -228.45903) (xy 108.680757 -228.484997) (xy 109.900467 -228.484997) (xy 109.900467 -228.433063)
			(xy 109.908592 -228.381768) (xy 109.92464 -228.332375) (xy 109.948218 -228.286101) (xy 109.978744 -228.244085)
			(xy 110.015467 -228.207362) (xy 110.057483 -228.176836) (xy 110.103757 -228.153258) (xy 110.15315 -228.13721)
			(xy 110.204445 -228.129085) (xy 110.256379 -228.129085) (xy 110.307674 -228.13721) (xy 110.357067 -228.153258)
			(xy 110.403341 -228.176836) (xy 110.445357 -228.207362) (xy 110.48208 -228.244085) (xy 110.512606 -228.286101)
			(xy 110.536184 -228.332375) (xy 110.552232 -228.381768) (xy 110.560357 -228.433063) (xy 110.560866 -228.45903)
			(xy 110.560357 -228.484997) (xy 110.552232 -228.536292) (xy 110.536184 -228.585685) (xy 110.512606 -228.631959)
			(xy 110.48208 -228.673975) (xy 110.445357 -228.710698) (xy 110.403341 -228.741224) (xy 110.357067 -228.764802)
			(xy 110.307674 -228.78085) (xy 110.256379 -228.788975) (xy 110.204445 -228.788975) (xy 110.15315 -228.78085)
			(xy 110.103757 -228.764802) (xy 110.057483 -228.741224) (xy 110.015467 -228.710698) (xy 109.978744 -228.673975)
			(xy 109.948218 -228.631959) (xy 109.92464 -228.585685) (xy 109.908592 -228.536292) (xy 109.900467 -228.484997)
			(xy 108.680757 -228.484997) (xy 108.672632 -228.536292) (xy 108.656584 -228.585685) (xy 108.633006 -228.631959)
			(xy 108.60248 -228.673975) (xy 108.565757 -228.710698) (xy 108.523741 -228.741224) (xy 108.477467 -228.764802)
			(xy 108.428074 -228.78085) (xy 108.376779 -228.788975) (xy 108.324845 -228.788975) (xy 108.27355 -228.78085)
			(xy 108.224157 -228.764802) (xy 108.177883 -228.741224) (xy 108.135867 -228.710698) (xy 108.099144 -228.673975)
			(xy 108.068618 -228.631959) (xy 108.04504 -228.585685) (xy 108.028992 -228.536292) (xy 108.020867 -228.484997)
			(xy 107.114145 -228.484997) (xy 107.263438 -228.63429) (xy 107.288838 -228.65207) (xy 107.311698 -228.66477)
			(xy 107.342178 -228.67747) (xy 107.362498 -228.68255) (xy 107.380278 -228.68509) (xy 107.405678 -228.68763)
			(xy 107.423458 -228.68763) (xy 107.453938 -228.68255) (xy 107.482386 -228.6762) (xy 107.500674 -228.66477)
			(xy 107.525058 -228.66477) (xy 107.550458 -228.63937) (xy 107.613958 -228.63937) (xy 107.697778 -228.72319)
			(xy 107.697778 -228.816662) (xy 107.769152 -228.835966) (xy 107.78535 -228.840743) (xy 107.815633 -228.855678)
			(xy 107.842435 -228.876215) (xy 107.864734 -228.90157) (xy 107.873546 -228.915976) (xy 107.888278 -228.941376)
			(xy 107.914186 -228.943916) (xy 107.941009 -228.947176) (xy 107.993163 -228.961293) (xy 108.042328 -228.983699)
			(xy 108.087199 -229.013798) (xy 108.126581 -229.050788) (xy 108.159428 -229.093688) (xy 108.184866 -229.141355)
			(xy 108.202218 -229.192523) (xy 108.211024 -229.245831) (xy 108.21162 -229.272846) (xy 108.211107 -229.29881)
			(xy 108.211107 -229.298813) (xy 108.491021 -229.298813) (xy 108.491021 -229.246879) (xy 108.499146 -229.195584)
			(xy 108.515194 -229.146191) (xy 108.538772 -229.099917) (xy 108.569298 -229.057901) (xy 108.606021 -229.021178)
			(xy 108.648037 -228.990652) (xy 108.694311 -228.967074) (xy 108.743704 -228.951026) (xy 108.794999 -228.942901)
			(xy 108.846933 -228.942901) (xy 108.898228 -228.951026) (xy 108.947621 -228.967074) (xy 108.993895 -228.990652)
			(xy 109.035911 -229.021178) (xy 109.072634 -229.057901) (xy 109.10316 -229.099917) (xy 109.126738 -229.146191)
			(xy 109.142786 -229.195584) (xy 109.150911 -229.246879) (xy 109.15142 -229.272846) (xy 109.150911 -229.298813)
			(xy 109.430821 -229.298813) (xy 109.430821 -229.246879) (xy 109.438946 -229.195584) (xy 109.454994 -229.146191)
			(xy 109.478572 -229.099917) (xy 109.509098 -229.057901) (xy 109.545821 -229.021178) (xy 109.587837 -228.990652)
			(xy 109.634111 -228.967074) (xy 109.683504 -228.951026) (xy 109.734799 -228.942901) (xy 109.786733 -228.942901)
			(xy 109.838028 -228.951026) (xy 109.887421 -228.967074) (xy 109.933695 -228.990652) (xy 109.975711 -229.021178)
			(xy 110.012434 -229.057901) (xy 110.04296 -229.099917) (xy 110.066538 -229.146191) (xy 110.082586 -229.195584)
			(xy 110.090711 -229.246879) (xy 110.09122 -229.272846) (xy 110.090711 -229.298813) (xy 110.082586 -229.350108)
			(xy 110.066538 -229.399501) (xy 110.04296 -229.445775) (xy 110.012434 -229.487791) (xy 109.975711 -229.524514)
			(xy 109.933695 -229.55504) (xy 109.887421 -229.578618) (xy 109.838028 -229.594666) (xy 109.786733 -229.602791)
			(xy 109.734799 -229.602791) (xy 109.683504 -229.594666) (xy 109.634111 -229.578618) (xy 109.587837 -229.55504)
			(xy 109.545821 -229.524514) (xy 109.509098 -229.487791) (xy 109.478572 -229.445775) (xy 109.454994 -229.399501)
			(xy 109.438946 -229.350108) (xy 109.430821 -229.298813) (xy 109.150911 -229.298813) (xy 109.142786 -229.350108)
			(xy 109.126738 -229.399501) (xy 109.10316 -229.445775) (xy 109.072634 -229.487791) (xy 109.035911 -229.524514)
			(xy 108.993895 -229.55504) (xy 108.947621 -229.578618) (xy 108.898228 -229.594666) (xy 108.846933 -229.602791)
			(xy 108.794999 -229.602791) (xy 108.743704 -229.594666) (xy 108.694311 -229.578618) (xy 108.648037 -229.55504)
			(xy 108.606021 -229.524514) (xy 108.569298 -229.487791) (xy 108.538772 -229.445775) (xy 108.515194 -229.399501)
			(xy 108.499146 -229.350108) (xy 108.491021 -229.298813) (xy 108.211107 -229.298813) (xy 108.202977 -229.350097)
			(xy 108.186924 -229.399482) (xy 108.163343 -229.445747) (xy 108.132816 -229.487753) (xy 108.096092 -229.524468)
			(xy 108.054078 -229.554985) (xy 108.007808 -229.578555) (xy 107.958419 -229.594596) (xy 107.90713 -229.602714)
			(xy 107.881166 -229.6033) (xy 107.856127 -229.602835) (xy 107.806624 -229.595276) (xy 107.758827 -229.580334)
			(xy 107.713832 -229.558352) (xy 107.672668 -229.529834) (xy 107.636278 -229.495432) (xy 107.605494 -229.455934)
			(xy 107.581021 -229.412244) (xy 107.56342 -229.365362) (xy 107.553093 -229.316361) (xy 107.55122 -229.291388)
			(xy 107.550074 -229.278184) (xy 107.541864 -229.252994) (xy 107.527438 -229.230771) (xy 107.507771 -229.213018)
			(xy 107.484193 -229.200935) (xy 107.458296 -229.195339) (xy 107.445048 -229.19563) (xy 107.380532 -229.19563)
			(xy 107.35818 -229.194868) (xy 107.272328 -229.28072) (xy 107.270804 -229.299516) (xy 107.26982 -229.310139)
			(xy 107.266646 -229.331239) (xy 107.264454 -229.34168) (xy 107.263438 -229.347014) (xy 107.263438 -229.49027)
			(xy 106.86415 -229.889558) (xy 106.77271 -229.889558) (xy 106.77271 -229.950518) (xy 106.77652 -229.959916)
			(xy 106.784543 -229.980074) (xy 106.79584 -230.021963) (xy 106.801566 -230.064969) (xy 106.80192 -230.086662)
			(xy 106.801411 -230.112629) (xy 107.081067 -230.112629) (xy 107.081067 -230.060695) (xy 107.089192 -230.0094)
			(xy 107.10524 -229.960007) (xy 107.128818 -229.913733) (xy 107.159344 -229.871717) (xy 107.196067 -229.834994)
			(xy 107.238083 -229.804468) (xy 107.284357 -229.78089) (xy 107.33375 -229.764842) (xy 107.385045 -229.756717)
			(xy 107.436979 -229.756717) (xy 107.488274 -229.764842) (xy 107.537667 -229.78089) (xy 107.583941 -229.804468)
			(xy 107.625957 -229.834994) (xy 107.66268 -229.871717) (xy 107.693206 -229.913733) (xy 107.716784 -229.960007)
			(xy 107.732832 -230.0094) (xy 107.740957 -230.060695) (xy 107.741466 -230.086662) (xy 107.740957 -230.112629)
			(xy 108.020867 -230.112629) (xy 108.020867 -230.060695) (xy 108.028992 -230.0094) (xy 108.04504 -229.960007)
			(xy 108.068618 -229.913733) (xy 108.099144 -229.871717) (xy 108.135867 -229.834994) (xy 108.177883 -229.804468)
			(xy 108.224157 -229.78089) (xy 108.27355 -229.764842) (xy 108.324845 -229.756717) (xy 108.376779 -229.756717)
			(xy 108.428074 -229.764842) (xy 108.477467 -229.78089) (xy 108.523741 -229.804468) (xy 108.565757 -229.834994)
			(xy 108.60248 -229.871717) (xy 108.633006 -229.913733) (xy 108.656584 -229.960007) (xy 108.672632 -230.0094)
			(xy 108.680757 -230.060695) (xy 108.681266 -230.086662) (xy 108.680757 -230.112629) (xy 108.960667 -230.112629)
			(xy 108.960667 -230.060695) (xy 108.968792 -230.0094) (xy 108.98484 -229.960007) (xy 109.008418 -229.913733)
			(xy 109.038944 -229.871717) (xy 109.075667 -229.834994) (xy 109.117683 -229.804468) (xy 109.163957 -229.78089)
			(xy 109.21335 -229.764842) (xy 109.264645 -229.756717) (xy 109.316579 -229.756717) (xy 109.367874 -229.764842)
			(xy 109.417267 -229.78089) (xy 109.463541 -229.804468) (xy 109.505557 -229.834994) (xy 109.54228 -229.871717)
			(xy 109.572806 -229.913733) (xy 109.596384 -229.960007) (xy 109.612432 -230.0094) (xy 109.620557 -230.060695)
			(xy 109.621066 -230.086662) (xy 109.620557 -230.112629) (xy 109.900467 -230.112629) (xy 109.900467 -230.060695)
			(xy 109.908592 -230.0094) (xy 109.92464 -229.960007) (xy 109.948218 -229.913733) (xy 109.978744 -229.871717)
			(xy 110.015467 -229.834994) (xy 110.057483 -229.804468) (xy 110.103757 -229.78089) (xy 110.15315 -229.764842)
			(xy 110.204445 -229.756717) (xy 110.256379 -229.756717) (xy 110.307674 -229.764842) (xy 110.357067 -229.78089)
			(xy 110.403341 -229.804468) (xy 110.445357 -229.834994) (xy 110.48208 -229.871717) (xy 110.512606 -229.913733)
			(xy 110.536184 -229.960007) (xy 110.552232 -230.0094) (xy 110.560357 -230.060695) (xy 110.560866 -230.086662)
			(xy 110.560357 -230.112629) (xy 110.552232 -230.163924) (xy 110.536184 -230.213317) (xy 110.512606 -230.259591)
			(xy 110.48208 -230.301607) (xy 110.445357 -230.33833) (xy 110.403341 -230.368856) (xy 110.357067 -230.392434)
			(xy 110.307674 -230.408482) (xy 110.256379 -230.416607) (xy 110.204445 -230.416607) (xy 110.15315 -230.408482)
			(xy 110.103757 -230.392434) (xy 110.057483 -230.368856) (xy 110.015467 -230.33833) (xy 109.978744 -230.301607)
			(xy 109.948218 -230.259591) (xy 109.92464 -230.213317) (xy 109.908592 -230.163924) (xy 109.900467 -230.112629)
			(xy 109.620557 -230.112629) (xy 109.612432 -230.163924) (xy 109.596384 -230.213317) (xy 109.572806 -230.259591)
			(xy 109.54228 -230.301607) (xy 109.505557 -230.33833) (xy 109.463541 -230.368856) (xy 109.417267 -230.392434)
			(xy 109.367874 -230.408482) (xy 109.316579 -230.416607) (xy 109.264645 -230.416607) (xy 109.21335 -230.408482)
			(xy 109.163957 -230.392434) (xy 109.117683 -230.368856) (xy 109.075667 -230.33833) (xy 109.038944 -230.301607)
			(xy 109.008418 -230.259591) (xy 108.98484 -230.213317) (xy 108.968792 -230.163924) (xy 108.960667 -230.112629)
			(xy 108.680757 -230.112629) (xy 108.672632 -230.163924) (xy 108.656584 -230.213317) (xy 108.633006 -230.259591)
			(xy 108.60248 -230.301607) (xy 108.565757 -230.33833) (xy 108.523741 -230.368856) (xy 108.477467 -230.392434)
			(xy 108.428074 -230.408482) (xy 108.376779 -230.416607) (xy 108.324845 -230.416607) (xy 108.27355 -230.408482)
			(xy 108.224157 -230.392434) (xy 108.177883 -230.368856) (xy 108.135867 -230.33833) (xy 108.099144 -230.301607)
			(xy 108.068618 -230.259591) (xy 108.04504 -230.213317) (xy 108.028992 -230.163924) (xy 108.020867 -230.112629)
			(xy 107.740957 -230.112629) (xy 107.732832 -230.163924) (xy 107.716784 -230.213317) (xy 107.693206 -230.259591)
			(xy 107.66268 -230.301607) (xy 107.625957 -230.33833) (xy 107.583941 -230.368856) (xy 107.537667 -230.392434)
			(xy 107.488274 -230.408482) (xy 107.436979 -230.416607) (xy 107.385045 -230.416607) (xy 107.33375 -230.408482)
			(xy 107.284357 -230.392434) (xy 107.238083 -230.368856) (xy 107.196067 -230.33833) (xy 107.159344 -230.301607)
			(xy 107.128818 -230.259591) (xy 107.10524 -230.213317) (xy 107.089192 -230.163924) (xy 107.081067 -230.112629)
			(xy 106.801411 -230.112629) (xy 106.793286 -230.163924) (xy 106.777238 -230.213317) (xy 106.75366 -230.259591)
			(xy 106.723134 -230.301607) (xy 106.686411 -230.33833) (xy 106.644395 -230.368856) (xy 106.598121 -230.392434)
			(xy 106.548728 -230.408482) (xy 106.497433 -230.416607) (xy 106.445499 -230.416607) (xy 106.394204 -230.408482)
			(xy 106.344811 -230.392434) (xy 106.298537 -230.368856) (xy 106.256521 -230.33833) (xy 106.219798 -230.301607)
			(xy 106.189272 -230.259591) (xy 106.165694 -230.213317) (xy 106.149646 -230.163924) (xy 106.141521 -230.112629)
			(xy 106.141012 -230.086662) (xy 106.141255 -230.068219) (xy 106.145334 -230.031558) (xy 106.14914 -230.01351)
			(xy 106.151928 -229.998559) (xy 106.149583 -229.968251) (xy 106.138428 -229.939975) (xy 106.119448 -229.916231)
			(xy 106.094324 -229.899119) (xy 106.065278 -229.890155) (xy 106.05008 -229.889558) (xy 105.863898 -229.889558)
			(xy 105.82402 -229.929436) (xy 105.836974 -229.960678) (xy 105.84485 -229.980738) (xy 105.855933 -230.022383)
			(xy 105.861525 -230.065114) (xy 105.861866 -230.086662) (xy 105.861386 -230.112634) (xy 105.853266 -230.163938)
			(xy 105.837219 -230.21334) (xy 105.813642 -230.259624) (xy 105.783114 -230.30165) (xy 105.746388 -230.338382)
			(xy 105.704367 -230.368916) (xy 105.658087 -230.3925) (xy 105.608687 -230.408554) (xy 105.557384 -230.416682)
			(xy 105.531412 -230.417116) (xy 105.520713 -230.417021) (xy 105.49936 -230.415624) (xy 105.48874 -230.414322)
			(xy 105.474382 -230.412982) (xy 105.445905 -230.417446) (xy 105.41981 -230.429688) (xy 105.398175 -230.448734)
			(xy 105.382723 -230.473067) (xy 105.374686 -230.500748) (xy 105.374186 -230.51516) (xy 105.374186 -230.792528)
			(xy 105.376472 -230.800148) (xy 105.383806 -230.824581) (xy 105.391719 -230.874973) (xy 105.39222 -230.900478)
			(xy 105.391705 -230.925981) (xy 105.391632 -230.926445) (xy 105.671621 -230.926445) (xy 105.671621 -230.874511)
			(xy 105.679746 -230.823216) (xy 105.695794 -230.773823) (xy 105.719372 -230.727549) (xy 105.749898 -230.685533)
			(xy 105.786621 -230.64881) (xy 105.828637 -230.618284) (xy 105.874911 -230.594706) (xy 105.924304 -230.578658)
			(xy 105.975599 -230.570533) (xy 106.027533 -230.570533) (xy 106.078828 -230.578658) (xy 106.128221 -230.594706)
			(xy 106.174495 -230.618284) (xy 106.216511 -230.64881) (xy 106.253234 -230.685533) (xy 106.28376 -230.727549)
			(xy 106.307338 -230.773823) (xy 106.323386 -230.823216) (xy 106.331511 -230.874511) (xy 106.33202 -230.900478)
			(xy 106.331511 -230.926445) (xy 106.611421 -230.926445) (xy 106.611421 -230.874511) (xy 106.619546 -230.823216)
			(xy 106.635594 -230.773823) (xy 106.659172 -230.727549) (xy 106.689698 -230.685533) (xy 106.726421 -230.64881)
			(xy 106.768437 -230.618284) (xy 106.814711 -230.594706) (xy 106.864104 -230.578658) (xy 106.915399 -230.570533)
			(xy 106.967333 -230.570533) (xy 107.018628 -230.578658) (xy 107.068021 -230.594706) (xy 107.114295 -230.618284)
			(xy 107.156311 -230.64881) (xy 107.193034 -230.685533) (xy 107.22356 -230.727549) (xy 107.247138 -230.773823)
			(xy 107.263186 -230.823216) (xy 107.271311 -230.874511) (xy 107.27182 -230.900478) (xy 107.271311 -230.926445)
			(xy 107.550967 -230.926445) (xy 107.550967 -230.874511) (xy 107.559092 -230.823216) (xy 107.57514 -230.773823)
			(xy 107.598718 -230.727549) (xy 107.629244 -230.685533) (xy 107.665967 -230.64881) (xy 107.707983 -230.618284)
			(xy 107.754257 -230.594706) (xy 107.80365 -230.578658) (xy 107.854945 -230.570533) (xy 107.906879 -230.570533)
			(xy 107.958174 -230.578658) (xy 108.007567 -230.594706) (xy 108.053841 -230.618284) (xy 108.095857 -230.64881)
			(xy 108.13258 -230.685533) (xy 108.163106 -230.727549) (xy 108.186684 -230.773823) (xy 108.202732 -230.823216)
			(xy 108.210857 -230.874511) (xy 108.211366 -230.900478) (xy 108.210857 -230.926445) (xy 108.491021 -230.926445)
			(xy 108.491021 -230.874511) (xy 108.499146 -230.823216) (xy 108.515194 -230.773823) (xy 108.538772 -230.727549)
			(xy 108.569298 -230.685533) (xy 108.606021 -230.64881) (xy 108.648037 -230.618284) (xy 108.694311 -230.594706)
			(xy 108.743704 -230.578658) (xy 108.794999 -230.570533) (xy 108.846933 -230.570533) (xy 108.898228 -230.578658)
			(xy 108.947621 -230.594706) (xy 108.993895 -230.618284) (xy 109.035911 -230.64881) (xy 109.072634 -230.685533)
			(xy 109.10316 -230.727549) (xy 109.126738 -230.773823) (xy 109.142786 -230.823216) (xy 109.150911 -230.874511)
			(xy 109.15142 -230.900478) (xy 109.150911 -230.926445) (xy 109.430567 -230.926445) (xy 109.430567 -230.874511)
			(xy 109.438692 -230.823216) (xy 109.45474 -230.773823) (xy 109.478318 -230.727549) (xy 109.508844 -230.685533)
			(xy 109.545567 -230.64881) (xy 109.587583 -230.618284) (xy 109.633857 -230.594706) (xy 109.68325 -230.578658)
			(xy 109.734545 -230.570533) (xy 109.786479 -230.570533) (xy 109.837774 -230.578658) (xy 109.887167 -230.594706)
			(xy 109.933441 -230.618284) (xy 109.975457 -230.64881) (xy 110.01218 -230.685533) (xy 110.042706 -230.727549)
			(xy 110.066284 -230.773823) (xy 110.082332 -230.823216) (xy 110.090457 -230.874511) (xy 110.090966 -230.900478)
			(xy 110.090457 -230.926445) (xy 110.082332 -230.97774) (xy 110.066284 -231.027133) (xy 110.042706 -231.073407)
			(xy 110.01218 -231.115423) (xy 109.975457 -231.152146) (xy 109.933441 -231.182672) (xy 109.887167 -231.20625)
			(xy 109.837774 -231.222298) (xy 109.786479 -231.230423) (xy 109.734545 -231.230423) (xy 109.68325 -231.222298)
			(xy 109.633857 -231.20625) (xy 109.587583 -231.182672) (xy 109.545567 -231.152146) (xy 109.508844 -231.115423)
			(xy 109.478318 -231.073407) (xy 109.45474 -231.027133) (xy 109.438692 -230.97774) (xy 109.430567 -230.926445)
			(xy 109.150911 -230.926445) (xy 109.142786 -230.97774) (xy 109.126738 -231.027133) (xy 109.10316 -231.073407)
			(xy 109.072634 -231.115423) (xy 109.035911 -231.152146) (xy 108.993895 -231.182672) (xy 108.947621 -231.20625)
			(xy 108.898228 -231.222298) (xy 108.846933 -231.230423) (xy 108.794999 -231.230423) (xy 108.743704 -231.222298)
			(xy 108.694311 -231.20625) (xy 108.648037 -231.182672) (xy 108.606021 -231.152146) (xy 108.569298 -231.115423)
			(xy 108.538772 -231.073407) (xy 108.515194 -231.027133) (xy 108.499146 -230.97774) (xy 108.491021 -230.926445)
			(xy 108.210857 -230.926445) (xy 108.202732 -230.97774) (xy 108.186684 -231.027133) (xy 108.163106 -231.073407)
			(xy 108.13258 -231.115423) (xy 108.095857 -231.152146) (xy 108.053841 -231.182672) (xy 108.007567 -231.20625)
			(xy 107.958174 -231.222298) (xy 107.906879 -231.230423) (xy 107.854945 -231.230423) (xy 107.80365 -231.222298)
			(xy 107.754257 -231.20625) (xy 107.707983 -231.182672) (xy 107.665967 -231.152146) (xy 107.629244 -231.115423)
			(xy 107.598718 -231.073407) (xy 107.57514 -231.027133) (xy 107.559092 -230.97774) (xy 107.550967 -230.926445)
			(xy 107.271311 -230.926445) (xy 107.263186 -230.97774) (xy 107.247138 -231.027133) (xy 107.22356 -231.073407)
			(xy 107.193034 -231.115423) (xy 107.156311 -231.152146) (xy 107.114295 -231.182672) (xy 107.068021 -231.20625)
			(xy 107.018628 -231.222298) (xy 106.967333 -231.230423) (xy 106.915399 -231.230423) (xy 106.864104 -231.222298)
			(xy 106.814711 -231.20625) (xy 106.768437 -231.182672) (xy 106.726421 -231.152146) (xy 106.689698 -231.115423)
			(xy 106.659172 -231.073407) (xy 106.635594 -231.027133) (xy 106.619546 -230.97774) (xy 106.611421 -230.926445)
			(xy 106.331511 -230.926445) (xy 106.323386 -230.97774) (xy 106.307338 -231.027133) (xy 106.28376 -231.073407)
			(xy 106.253234 -231.115423) (xy 106.216511 -231.152146) (xy 106.174495 -231.182672) (xy 106.128221 -231.20625)
			(xy 106.078828 -231.222298) (xy 106.027533 -231.230423) (xy 105.975599 -231.230423) (xy 105.924304 -231.222298)
			(xy 105.874911 -231.20625) (xy 105.828637 -231.182672) (xy 105.786621 -231.152146) (xy 105.749898 -231.115423)
			(xy 105.719372 -231.073407) (xy 105.695794 -231.027133) (xy 105.679746 -230.97774) (xy 105.671621 -230.926445)
			(xy 105.391632 -230.926445) (xy 105.383792 -230.976372) (xy 105.376472 -231.000808) (xy 105.374186 -231.008428)
			(xy 105.374186 -231.09682) (xy 104.972866 -231.49814) (xy 104.972866 -231.740515) (xy 105.201467 -231.740515)
			(xy 105.201467 -231.688581) (xy 105.209592 -231.637286) (xy 105.22564 -231.587893) (xy 105.249218 -231.541619)
			(xy 105.279744 -231.499603) (xy 105.316467 -231.46288) (xy 105.358483 -231.432354) (xy 105.404757 -231.408776)
			(xy 105.45415 -231.392728) (xy 105.505445 -231.384603) (xy 105.557379 -231.384603) (xy 105.608674 -231.392728)
			(xy 105.658067 -231.408776) (xy 105.704341 -231.432354) (xy 105.746357 -231.46288) (xy 105.78308 -231.499603)
			(xy 105.813606 -231.541619) (xy 105.837184 -231.587893) (xy 105.853232 -231.637286) (xy 105.861357 -231.688581)
			(xy 105.861866 -231.714548) (xy 105.861357 -231.740515) (xy 106.141267 -231.740515) (xy 106.141267 -231.688581)
			(xy 106.149392 -231.637286) (xy 106.16544 -231.587893) (xy 106.189018 -231.541619) (xy 106.219544 -231.499603)
			(xy 106.256267 -231.46288) (xy 106.298283 -231.432354) (xy 106.344557 -231.408776) (xy 106.39395 -231.392728)
			(xy 106.445245 -231.384603) (xy 106.497179 -231.384603) (xy 106.548474 -231.392728) (xy 106.597867 -231.408776)
			(xy 106.644141 -231.432354) (xy 106.686157 -231.46288) (xy 106.72288 -231.499603) (xy 106.753406 -231.541619)
			(xy 106.776984 -231.587893) (xy 106.793032 -231.637286) (xy 106.801157 -231.688581) (xy 106.801666 -231.714548)
			(xy 106.801157 -231.740515) (xy 107.081067 -231.740515) (xy 107.081067 -231.688581) (xy 107.089192 -231.637286)
			(xy 107.10524 -231.587893) (xy 107.128818 -231.541619) (xy 107.159344 -231.499603) (xy 107.196067 -231.46288)
			(xy 107.238083 -231.432354) (xy 107.284357 -231.408776) (xy 107.33375 -231.392728) (xy 107.385045 -231.384603)
			(xy 107.436979 -231.384603) (xy 107.488274 -231.392728) (xy 107.537667 -231.408776) (xy 107.583941 -231.432354)
			(xy 107.625957 -231.46288) (xy 107.66268 -231.499603) (xy 107.693206 -231.541619) (xy 107.716784 -231.587893)
			(xy 107.732832 -231.637286) (xy 107.740957 -231.688581) (xy 107.741466 -231.714548) (xy 107.740957 -231.740515)
			(xy 108.020867 -231.740515) (xy 108.020867 -231.688581) (xy 108.028992 -231.637286) (xy 108.04504 -231.587893)
			(xy 108.068618 -231.541619) (xy 108.099144 -231.499603) (xy 108.135867 -231.46288) (xy 108.177883 -231.432354)
			(xy 108.224157 -231.408776) (xy 108.27355 -231.392728) (xy 108.324845 -231.384603) (xy 108.376779 -231.384603)
			(xy 108.428074 -231.392728) (xy 108.477467 -231.408776) (xy 108.523741 -231.432354) (xy 108.565757 -231.46288)
			(xy 108.60248 -231.499603) (xy 108.633006 -231.541619) (xy 108.656584 -231.587893) (xy 108.672632 -231.637286)
			(xy 108.680757 -231.688581) (xy 108.681266 -231.714548) (xy 108.680757 -231.740515) (xy 108.960667 -231.740515)
			(xy 108.960667 -231.688581) (xy 108.968792 -231.637286) (xy 108.98484 -231.587893) (xy 109.008418 -231.541619)
			(xy 109.038944 -231.499603) (xy 109.075667 -231.46288) (xy 109.117683 -231.432354) (xy 109.163957 -231.408776)
			(xy 109.21335 -231.392728) (xy 109.264645 -231.384603) (xy 109.316579 -231.384603) (xy 109.367874 -231.392728)
			(xy 109.417267 -231.408776) (xy 109.463541 -231.432354) (xy 109.505557 -231.46288) (xy 109.54228 -231.499603)
			(xy 109.572806 -231.541619) (xy 109.596384 -231.587893) (xy 109.612432 -231.637286) (xy 109.620557 -231.688581)
			(xy 109.621066 -231.714548) (xy 109.620557 -231.740515) (xy 109.900721 -231.740515) (xy 109.900721 -231.688581)
			(xy 109.908846 -231.637286) (xy 109.924894 -231.587893) (xy 109.948472 -231.541619) (xy 109.978998 -231.499603)
			(xy 110.015721 -231.46288) (xy 110.057737 -231.432354) (xy 110.104011 -231.408776) (xy 110.153404 -231.392728)
			(xy 110.204699 -231.384603) (xy 110.256633 -231.384603) (xy 110.307928 -231.392728) (xy 110.357321 -231.408776)
			(xy 110.403595 -231.432354) (xy 110.445611 -231.46288) (xy 110.482334 -231.499603) (xy 110.51286 -231.541619)
			(xy 110.536438 -231.587893) (xy 110.552486 -231.637286) (xy 110.560611 -231.688581) (xy 110.56112 -231.714548)
			(xy 110.560611 -231.740515) (xy 110.552486 -231.79181) (xy 110.536438 -231.841203) (xy 110.51286 -231.887477)
			(xy 110.482334 -231.929493) (xy 110.445611 -231.966216) (xy 110.403595 -231.996742) (xy 110.357321 -232.02032)
			(xy 110.307928 -232.036368) (xy 110.256633 -232.044493) (xy 110.204699 -232.044493) (xy 110.153404 -232.036368)
			(xy 110.104011 -232.02032) (xy 110.057737 -231.996742) (xy 110.015721 -231.966216) (xy 109.978998 -231.929493)
			(xy 109.948472 -231.887477) (xy 109.924894 -231.841203) (xy 109.908846 -231.79181) (xy 109.900721 -231.740515)
			(xy 109.620557 -231.740515) (xy 109.612432 -231.79181) (xy 109.596384 -231.841203) (xy 109.572806 -231.887477)
			(xy 109.54228 -231.929493) (xy 109.505557 -231.966216) (xy 109.463541 -231.996742) (xy 109.417267 -232.02032)
			(xy 109.367874 -232.036368) (xy 109.316579 -232.044493) (xy 109.264645 -232.044493) (xy 109.21335 -232.036368)
			(xy 109.163957 -232.02032) (xy 109.117683 -231.996742) (xy 109.075667 -231.966216) (xy 109.038944 -231.929493)
			(xy 109.008418 -231.887477) (xy 108.98484 -231.841203) (xy 108.968792 -231.79181) (xy 108.960667 -231.740515)
			(xy 108.680757 -231.740515) (xy 108.672632 -231.79181) (xy 108.656584 -231.841203) (xy 108.633006 -231.887477)
			(xy 108.60248 -231.929493) (xy 108.565757 -231.966216) (xy 108.523741 -231.996742) (xy 108.477467 -232.02032)
			(xy 108.428074 -232.036368) (xy 108.376779 -232.044493) (xy 108.324845 -232.044493) (xy 108.27355 -232.036368)
			(xy 108.224157 -232.02032) (xy 108.177883 -231.996742) (xy 108.135867 -231.966216) (xy 108.099144 -231.929493)
			(xy 108.068618 -231.887477) (xy 108.04504 -231.841203) (xy 108.028992 -231.79181) (xy 108.020867 -231.740515)
			(xy 107.740957 -231.740515) (xy 107.732832 -231.79181) (xy 107.716784 -231.841203) (xy 107.693206 -231.887477)
			(xy 107.66268 -231.929493) (xy 107.625957 -231.966216) (xy 107.583941 -231.996742) (xy 107.537667 -232.02032)
			(xy 107.488274 -232.036368) (xy 107.436979 -232.044493) (xy 107.385045 -232.044493) (xy 107.33375 -232.036368)
			(xy 107.284357 -232.02032) (xy 107.238083 -231.996742) (xy 107.196067 -231.966216) (xy 107.159344 -231.929493)
			(xy 107.128818 -231.887477) (xy 107.10524 -231.841203) (xy 107.089192 -231.79181) (xy 107.081067 -231.740515)
			(xy 106.801157 -231.740515) (xy 106.793032 -231.79181) (xy 106.776984 -231.841203) (xy 106.753406 -231.887477)
			(xy 106.72288 -231.929493) (xy 106.686157 -231.966216) (xy 106.644141 -231.996742) (xy 106.597867 -232.02032)
			(xy 106.548474 -232.036368) (xy 106.497179 -232.044493) (xy 106.445245 -232.044493) (xy 106.39395 -232.036368)
			(xy 106.344557 -232.02032) (xy 106.298283 -231.996742) (xy 106.256267 -231.966216) (xy 106.219544 -231.929493)
			(xy 106.189018 -231.887477) (xy 106.16544 -231.841203) (xy 106.149392 -231.79181) (xy 106.141267 -231.740515)
			(xy 105.861357 -231.740515) (xy 105.853232 -231.79181) (xy 105.837184 -231.841203) (xy 105.813606 -231.887477)
			(xy 105.78308 -231.929493) (xy 105.746357 -231.966216) (xy 105.704341 -231.996742) (xy 105.658067 -232.02032)
			(xy 105.608674 -232.036368) (xy 105.557379 -232.044493) (xy 105.505445 -232.044493) (xy 105.45415 -232.036368)
			(xy 105.404757 -232.02032) (xy 105.358483 -231.996742) (xy 105.316467 -231.966216) (xy 105.279744 -231.929493)
			(xy 105.249218 -231.887477) (xy 105.22564 -231.841203) (xy 105.209592 -231.79181) (xy 105.201467 -231.740515)
			(xy 104.972866 -231.740515) (xy 104.972866 -232.096564) (xy 104.973452 -232.112249) (xy 104.982981 -232.142138)
			(xy 105.001121 -232.167733) (xy 105.026166 -232.186625) (xy 105.055759 -232.197036) (xy 105.071418 -232.198164)
			(xy 105.096874 -232.199377) (xy 105.146982 -232.208665) (xy 105.19507 -232.225538) (xy 105.239996 -232.249595)
			(xy 105.280695 -232.280265) (xy 105.316202 -232.316821) (xy 105.345674 -232.358395) (xy 105.368413 -232.404003)
			(xy 105.383879 -232.452561) (xy 105.391704 -232.502918) (xy 105.391705 -232.55388) (xy 105.391635 -232.554331)
			(xy 105.671621 -232.554331) (xy 105.671621 -232.502397) (xy 105.679746 -232.451102) (xy 105.695794 -232.401709)
			(xy 105.719372 -232.355435) (xy 105.749898 -232.313419) (xy 105.786621 -232.276696) (xy 105.828637 -232.24617)
			(xy 105.874911 -232.222592) (xy 105.924304 -232.206544) (xy 105.975599 -232.198419) (xy 106.027533 -232.198419)
			(xy 106.078828 -232.206544) (xy 106.128221 -232.222592) (xy 106.174495 -232.24617) (xy 106.216511 -232.276696)
			(xy 106.253234 -232.313419) (xy 106.28376 -232.355435) (xy 106.307338 -232.401709) (xy 106.323386 -232.451102)
			(xy 106.331511 -232.502397) (xy 106.33202 -232.528364) (xy 106.331511 -232.554331) (xy 106.611421 -232.554331)
			(xy 106.611421 -232.502397) (xy 106.619546 -232.451102) (xy 106.635594 -232.401709) (xy 106.659172 -232.355435)
			(xy 106.689698 -232.313419) (xy 106.726421 -232.276696) (xy 106.768437 -232.24617) (xy 106.814711 -232.222592)
			(xy 106.864104 -232.206544) (xy 106.915399 -232.198419) (xy 106.967333 -232.198419) (xy 107.018628 -232.206544)
			(xy 107.068021 -232.222592) (xy 107.114295 -232.24617) (xy 107.156311 -232.276696) (xy 107.193034 -232.313419)
			(xy 107.22356 -232.355435) (xy 107.247138 -232.401709) (xy 107.263186 -232.451102) (xy 107.271311 -232.502397)
			(xy 107.27182 -232.528364) (xy 107.271311 -232.554331) (xy 107.551221 -232.554331) (xy 107.551221 -232.502397)
			(xy 107.559346 -232.451102) (xy 107.575394 -232.401709) (xy 107.598972 -232.355435) (xy 107.629498 -232.313419)
			(xy 107.666221 -232.276696) (xy 107.708237 -232.24617) (xy 107.754511 -232.222592) (xy 107.803904 -232.206544)
			(xy 107.855199 -232.198419) (xy 107.907133 -232.198419) (xy 107.958428 -232.206544) (xy 108.007821 -232.222592)
			(xy 108.054095 -232.24617) (xy 108.096111 -232.276696) (xy 108.132834 -232.313419) (xy 108.16336 -232.355435)
			(xy 108.186938 -232.401709) (xy 108.202986 -232.451102) (xy 108.211111 -232.502397) (xy 108.21162 -232.528364)
			(xy 108.211111 -232.554331) (xy 108.491021 -232.554331) (xy 108.491021 -232.502397) (xy 108.499146 -232.451102)
			(xy 108.515194 -232.401709) (xy 108.538772 -232.355435) (xy 108.569298 -232.313419) (xy 108.606021 -232.276696)
			(xy 108.648037 -232.24617) (xy 108.694311 -232.222592) (xy 108.743704 -232.206544) (xy 108.794999 -232.198419)
			(xy 108.846933 -232.198419) (xy 108.898228 -232.206544) (xy 108.947621 -232.222592) (xy 108.993895 -232.24617)
			(xy 109.035911 -232.276696) (xy 109.072634 -232.313419) (xy 109.10316 -232.355435) (xy 109.126738 -232.401709)
			(xy 109.142786 -232.451102) (xy 109.150911 -232.502397) (xy 109.15142 -232.528364) (xy 109.150911 -232.554331)
			(xy 109.430821 -232.554331) (xy 109.430821 -232.502397) (xy 109.438946 -232.451102) (xy 109.454994 -232.401709)
			(xy 109.478572 -232.355435) (xy 109.509098 -232.313419) (xy 109.545821 -232.276696) (xy 109.587837 -232.24617)
			(xy 109.634111 -232.222592) (xy 109.683504 -232.206544) (xy 109.734799 -232.198419) (xy 109.786733 -232.198419)
			(xy 109.838028 -232.206544) (xy 109.887421 -232.222592) (xy 109.933695 -232.24617) (xy 109.975711 -232.276696)
			(xy 110.012434 -232.313419) (xy 110.04296 -232.355435) (xy 110.066538 -232.401709) (xy 110.082586 -232.451102)
			(xy 110.090711 -232.502397) (xy 110.09122 -232.528364) (xy 110.090711 -232.554331) (xy 110.082586 -232.605626)
			(xy 110.066538 -232.655019) (xy 110.04296 -232.701293) (xy 110.012434 -232.743309) (xy 109.975711 -232.780032)
			(xy 109.933695 -232.810558) (xy 109.887421 -232.834136) (xy 109.838028 -232.850184) (xy 109.786733 -232.858309)
			(xy 109.734799 -232.858309) (xy 109.683504 -232.850184) (xy 109.634111 -232.834136) (xy 109.587837 -232.810558)
			(xy 109.545821 -232.780032) (xy 109.509098 -232.743309) (xy 109.478572 -232.701293) (xy 109.454994 -232.655019)
			(xy 109.438946 -232.605626) (xy 109.430821 -232.554331) (xy 109.150911 -232.554331) (xy 109.142786 -232.605626)
			(xy 109.126738 -232.655019) (xy 109.10316 -232.701293) (xy 109.072634 -232.743309) (xy 109.035911 -232.780032)
			(xy 108.993895 -232.810558) (xy 108.947621 -232.834136) (xy 108.898228 -232.850184) (xy 108.846933 -232.858309)
			(xy 108.794999 -232.858309) (xy 108.743704 -232.850184) (xy 108.694311 -232.834136) (xy 108.648037 -232.810558)
			(xy 108.606021 -232.780032) (xy 108.569298 -232.743309) (xy 108.538772 -232.701293) (xy 108.515194 -232.655019)
			(xy 108.499146 -232.605626) (xy 108.491021 -232.554331) (xy 108.211111 -232.554331) (xy 108.202986 -232.605626)
			(xy 108.186938 -232.655019) (xy 108.16336 -232.701293) (xy 108.132834 -232.743309) (xy 108.096111 -232.780032)
			(xy 108.054095 -232.810558) (xy 108.007821 -232.834136) (xy 107.958428 -232.850184) (xy 107.907133 -232.858309)
			(xy 107.855199 -232.858309) (xy 107.803904 -232.850184) (xy 107.754511 -232.834136) (xy 107.708237 -232.810558)
			(xy 107.666221 -232.780032) (xy 107.629498 -232.743309) (xy 107.598972 -232.701293) (xy 107.575394 -232.655019)
			(xy 107.559346 -232.605626) (xy 107.551221 -232.554331) (xy 107.271311 -232.554331) (xy 107.263186 -232.605626)
			(xy 107.247138 -232.655019) (xy 107.22356 -232.701293) (xy 107.193034 -232.743309) (xy 107.156311 -232.780032)
			(xy 107.114295 -232.810558) (xy 107.068021 -232.834136) (xy 107.018628 -232.850184) (xy 106.967333 -232.858309)
			(xy 106.915399 -232.858309) (xy 106.864104 -232.850184) (xy 106.814711 -232.834136) (xy 106.768437 -232.810558)
			(xy 106.726421 -232.780032) (xy 106.689698 -232.743309) (xy 106.659172 -232.701293) (xy 106.635594 -232.655019)
			(xy 106.619546 -232.605626) (xy 106.611421 -232.554331) (xy 106.331511 -232.554331) (xy 106.323386 -232.605626)
			(xy 106.307338 -232.655019) (xy 106.28376 -232.701293) (xy 106.253234 -232.743309) (xy 106.216511 -232.780032)
			(xy 106.174495 -232.810558) (xy 106.128221 -232.834136) (xy 106.078828 -232.850184) (xy 106.027533 -232.858309)
			(xy 105.975599 -232.858309) (xy 105.924304 -232.850184) (xy 105.874911 -232.834136) (xy 105.828637 -232.810558)
			(xy 105.786621 -232.780032) (xy 105.749898 -232.743309) (xy 105.719372 -232.701293) (xy 105.695794 -232.655019)
			(xy 105.679746 -232.605626) (xy 105.671621 -232.554331) (xy 105.391635 -232.554331) (xy 105.383879 -232.604237)
			(xy 105.368414 -232.652795) (xy 105.345675 -232.698403) (xy 105.316203 -232.739978) (xy 105.280697 -232.776534)
			(xy 105.239998 -232.807204) (xy 105.195072 -232.831261) (xy 105.146984 -232.848134) (xy 105.096876 -232.857423)
			(xy 105.071418 -232.858564) (xy 105.055742 -232.859605) (xy 105.026118 -232.87001) (xy 105.001049 -232.888917)
			(xy 104.982902 -232.914541) (xy 104.97339 -232.944464) (xy 104.972866 -232.960164) (xy 104.972866 -233.368147)
			(xy 105.201721 -233.368147) (xy 105.201721 -233.316213) (xy 105.209846 -233.264918) (xy 105.225894 -233.215525)
			(xy 105.249472 -233.169251) (xy 105.279998 -233.127235) (xy 105.316721 -233.090512) (xy 105.358737 -233.059986)
			(xy 105.405011 -233.036408) (xy 105.454404 -233.02036) (xy 105.505699 -233.012235) (xy 105.557633 -233.012235)
			(xy 105.608928 -233.02036) (xy 105.658321 -233.036408) (xy 105.704595 -233.059986) (xy 105.746611 -233.090512)
			(xy 105.783334 -233.127235) (xy 105.81386 -233.169251) (xy 105.837438 -233.215525) (xy 105.853486 -233.264918)
			(xy 105.861611 -233.316213) (xy 105.86212 -233.34218) (xy 105.861611 -233.368147) (xy 106.141267 -233.368147)
			(xy 106.141267 -233.316213) (xy 106.149392 -233.264918) (xy 106.16544 -233.215525) (xy 106.189018 -233.169251)
			(xy 106.219544 -233.127235) (xy 106.256267 -233.090512) (xy 106.298283 -233.059986) (xy 106.344557 -233.036408)
			(xy 106.39395 -233.02036) (xy 106.445245 -233.012235) (xy 106.497179 -233.012235) (xy 106.548474 -233.02036)
			(xy 106.597867 -233.036408) (xy 106.644141 -233.059986) (xy 106.686157 -233.090512) (xy 106.72288 -233.127235)
			(xy 106.753406 -233.169251) (xy 106.776984 -233.215525) (xy 106.793032 -233.264918) (xy 106.801157 -233.316213)
			(xy 106.801666 -233.34218) (xy 106.801157 -233.368147) (xy 107.081067 -233.368147) (xy 107.081067 -233.316213)
			(xy 107.089192 -233.264918) (xy 107.10524 -233.215525) (xy 107.128818 -233.169251) (xy 107.159344 -233.127235)
			(xy 107.196067 -233.090512) (xy 107.238083 -233.059986) (xy 107.284357 -233.036408) (xy 107.33375 -233.02036)
			(xy 107.385045 -233.012235) (xy 107.436979 -233.012235) (xy 107.488274 -233.02036) (xy 107.537667 -233.036408)
			(xy 107.583941 -233.059986) (xy 107.625957 -233.090512) (xy 107.66268 -233.127235) (xy 107.693206 -233.169251)
			(xy 107.716784 -233.215525) (xy 107.732832 -233.264918) (xy 107.740957 -233.316213) (xy 107.741466 -233.34218)
			(xy 107.740957 -233.368147) (xy 108.020867 -233.368147) (xy 108.020867 -233.316213) (xy 108.028992 -233.264918)
			(xy 108.04504 -233.215525) (xy 108.068618 -233.169251) (xy 108.099144 -233.127235) (xy 108.135867 -233.090512)
			(xy 108.177883 -233.059986) (xy 108.224157 -233.036408) (xy 108.27355 -233.02036) (xy 108.324845 -233.012235)
			(xy 108.376779 -233.012235) (xy 108.428074 -233.02036) (xy 108.477467 -233.036408) (xy 108.523741 -233.059986)
			(xy 108.565757 -233.090512) (xy 108.60248 -233.127235) (xy 108.633006 -233.169251) (xy 108.656584 -233.215525)
			(xy 108.672632 -233.264918) (xy 108.680757 -233.316213) (xy 108.681266 -233.34218) (xy 108.680757 -233.368147)
			(xy 108.960667 -233.368147) (xy 108.960667 -233.316213) (xy 108.968792 -233.264918) (xy 108.98484 -233.215525)
			(xy 109.008418 -233.169251) (xy 109.038944 -233.127235) (xy 109.075667 -233.090512) (xy 109.117683 -233.059986)
			(xy 109.163957 -233.036408) (xy 109.21335 -233.02036) (xy 109.264645 -233.012235) (xy 109.316579 -233.012235)
			(xy 109.367874 -233.02036) (xy 109.417267 -233.036408) (xy 109.463541 -233.059986) (xy 109.505557 -233.090512)
			(xy 109.54228 -233.127235) (xy 109.572806 -233.169251) (xy 109.596384 -233.215525) (xy 109.612432 -233.264918)
			(xy 109.620557 -233.316213) (xy 109.621066 -233.34218) (xy 109.620557 -233.368147) (xy 109.900721 -233.368147)
			(xy 109.900721 -233.316213) (xy 109.908846 -233.264918) (xy 109.924894 -233.215525) (xy 109.948472 -233.169251)
			(xy 109.978998 -233.127235) (xy 110.015721 -233.090512) (xy 110.057737 -233.059986) (xy 110.104011 -233.036408)
			(xy 110.153404 -233.02036) (xy 110.204699 -233.012235) (xy 110.256633 -233.012235) (xy 110.307928 -233.02036)
			(xy 110.357321 -233.036408) (xy 110.403595 -233.059986) (xy 110.445611 -233.090512) (xy 110.482334 -233.127235)
			(xy 110.51286 -233.169251) (xy 110.536438 -233.215525) (xy 110.552486 -233.264918) (xy 110.560611 -233.316213)
			(xy 110.56112 -233.34218) (xy 110.560611 -233.368147) (xy 110.552486 -233.419442) (xy 110.536438 -233.468835)
			(xy 110.51286 -233.515109) (xy 110.482334 -233.557125) (xy 110.445611 -233.593848) (xy 110.403595 -233.624374)
			(xy 110.357321 -233.647952) (xy 110.307928 -233.664) (xy 110.256633 -233.672125) (xy 110.204699 -233.672125)
			(xy 110.153404 -233.664) (xy 110.104011 -233.647952) (xy 110.057737 -233.624374) (xy 110.015721 -233.593848)
			(xy 109.978998 -233.557125) (xy 109.948472 -233.515109) (xy 109.924894 -233.468835) (xy 109.908846 -233.419442)
			(xy 109.900721 -233.368147) (xy 109.620557 -233.368147) (xy 109.612432 -233.419442) (xy 109.596384 -233.468835)
			(xy 109.572806 -233.515109) (xy 109.54228 -233.557125) (xy 109.505557 -233.593848) (xy 109.463541 -233.624374)
			(xy 109.417267 -233.647952) (xy 109.367874 -233.664) (xy 109.316579 -233.672125) (xy 109.264645 -233.672125)
			(xy 109.21335 -233.664) (xy 109.163957 -233.647952) (xy 109.117683 -233.624374) (xy 109.075667 -233.593848)
			(xy 109.038944 -233.557125) (xy 109.008418 -233.515109) (xy 108.98484 -233.468835) (xy 108.968792 -233.419442)
			(xy 108.960667 -233.368147) (xy 108.680757 -233.368147) (xy 108.672632 -233.419442) (xy 108.656584 -233.468835)
			(xy 108.633006 -233.515109) (xy 108.60248 -233.557125) (xy 108.565757 -233.593848) (xy 108.523741 -233.624374)
			(xy 108.477467 -233.647952) (xy 108.428074 -233.664) (xy 108.376779 -233.672125) (xy 108.324845 -233.672125)
			(xy 108.27355 -233.664) (xy 108.224157 -233.647952) (xy 108.177883 -233.624374) (xy 108.135867 -233.593848)
			(xy 108.099144 -233.557125) (xy 108.068618 -233.515109) (xy 108.04504 -233.468835) (xy 108.028992 -233.419442)
			(xy 108.020867 -233.368147) (xy 107.740957 -233.368147) (xy 107.732832 -233.419442) (xy 107.716784 -233.468835)
			(xy 107.693206 -233.515109) (xy 107.66268 -233.557125) (xy 107.625957 -233.593848) (xy 107.583941 -233.624374)
			(xy 107.537667 -233.647952) (xy 107.488274 -233.664) (xy 107.436979 -233.672125) (xy 107.385045 -233.672125)
			(xy 107.33375 -233.664) (xy 107.284357 -233.647952) (xy 107.238083 -233.624374) (xy 107.196067 -233.593848)
			(xy 107.159344 -233.557125) (xy 107.128818 -233.515109) (xy 107.10524 -233.468835) (xy 107.089192 -233.419442)
			(xy 107.081067 -233.368147) (xy 106.801157 -233.368147) (xy 106.793032 -233.419442) (xy 106.776984 -233.468835)
			(xy 106.753406 -233.515109) (xy 106.72288 -233.557125) (xy 106.686157 -233.593848) (xy 106.644141 -233.624374)
			(xy 106.597867 -233.647952) (xy 106.548474 -233.664) (xy 106.497179 -233.672125) (xy 106.445245 -233.672125)
			(xy 106.39395 -233.664) (xy 106.344557 -233.647952) (xy 106.298283 -233.624374) (xy 106.256267 -233.593848)
			(xy 106.219544 -233.557125) (xy 106.189018 -233.515109) (xy 106.16544 -233.468835) (xy 106.149392 -233.419442)
			(xy 106.141267 -233.368147) (xy 105.861611 -233.368147) (xy 105.853486 -233.419442) (xy 105.837438 -233.468835)
			(xy 105.81386 -233.515109) (xy 105.783334 -233.557125) (xy 105.746611 -233.593848) (xy 105.704595 -233.624374)
			(xy 105.658321 -233.647952) (xy 105.608928 -233.664) (xy 105.557633 -233.672125) (xy 105.505699 -233.672125)
			(xy 105.454404 -233.664) (xy 105.405011 -233.647952) (xy 105.358737 -233.624374) (xy 105.316721 -233.593848)
			(xy 105.279998 -233.557125) (xy 105.249472 -233.515109) (xy 105.225894 -233.468835) (xy 105.209846 -233.419442)
			(xy 105.201721 -233.368147) (xy 104.972866 -233.368147) (xy 104.972866 -234.182217) (xy 105.671621 -234.182217)
			(xy 105.671621 -234.130283) (xy 105.679746 -234.078988) (xy 105.695794 -234.029595) (xy 105.719372 -233.983321)
			(xy 105.749898 -233.941305) (xy 105.786621 -233.904582) (xy 105.828637 -233.874056) (xy 105.874911 -233.850478)
			(xy 105.924304 -233.83443) (xy 105.975599 -233.826305) (xy 106.027533 -233.826305) (xy 106.078828 -233.83443)
			(xy 106.128221 -233.850478) (xy 106.174495 -233.874056) (xy 106.216511 -233.904582) (xy 106.253234 -233.941305)
			(xy 106.28376 -233.983321) (xy 106.307338 -234.029595) (xy 106.323386 -234.078988) (xy 106.331511 -234.130283)
			(xy 106.33202 -234.15625) (xy 106.331511 -234.182217) (xy 106.611421 -234.182217) (xy 106.611421 -234.130283)
			(xy 106.619546 -234.078988) (xy 106.635594 -234.029595) (xy 106.659172 -233.983321) (xy 106.689698 -233.941305)
			(xy 106.726421 -233.904582) (xy 106.768437 -233.874056) (xy 106.814711 -233.850478) (xy 106.864104 -233.83443)
			(xy 106.915399 -233.826305) (xy 106.967333 -233.826305) (xy 107.018628 -233.83443) (xy 107.068021 -233.850478)
			(xy 107.114295 -233.874056) (xy 107.156311 -233.904582) (xy 107.193034 -233.941305) (xy 107.22356 -233.983321)
			(xy 107.247138 -234.029595) (xy 107.263186 -234.078988) (xy 107.271311 -234.130283) (xy 107.27182 -234.15625)
			(xy 107.271311 -234.182217) (xy 107.551221 -234.182217) (xy 107.551221 -234.130283) (xy 107.559346 -234.078988)
			(xy 107.575394 -234.029595) (xy 107.598972 -233.983321) (xy 107.629498 -233.941305) (xy 107.666221 -233.904582)
			(xy 107.708237 -233.874056) (xy 107.754511 -233.850478) (xy 107.803904 -233.83443) (xy 107.855199 -233.826305)
			(xy 107.907133 -233.826305) (xy 107.958428 -233.83443) (xy 108.007821 -233.850478) (xy 108.054095 -233.874056)
			(xy 108.096111 -233.904582) (xy 108.132834 -233.941305) (xy 108.16336 -233.983321) (xy 108.186938 -234.029595)
			(xy 108.202986 -234.078988) (xy 108.211111 -234.130283) (xy 108.21162 -234.15625) (xy 108.211111 -234.182217)
			(xy 108.491021 -234.182217) (xy 108.491021 -234.130283) (xy 108.499146 -234.078988) (xy 108.515194 -234.029595)
			(xy 108.538772 -233.983321) (xy 108.569298 -233.941305) (xy 108.606021 -233.904582) (xy 108.648037 -233.874056)
			(xy 108.694311 -233.850478) (xy 108.743704 -233.83443) (xy 108.794999 -233.826305) (xy 108.846933 -233.826305)
			(xy 108.898228 -233.83443) (xy 108.947621 -233.850478) (xy 108.993895 -233.874056) (xy 109.035911 -233.904582)
			(xy 109.072634 -233.941305) (xy 109.10316 -233.983321) (xy 109.126738 -234.029595) (xy 109.142786 -234.078988)
			(xy 109.150911 -234.130283) (xy 109.15142 -234.15625) (xy 109.150911 -234.182217) (xy 109.430821 -234.182217)
			(xy 109.430821 -234.130283) (xy 109.438946 -234.078988) (xy 109.454994 -234.029595) (xy 109.478572 -233.983321)
			(xy 109.509098 -233.941305) (xy 109.545821 -233.904582) (xy 109.587837 -233.874056) (xy 109.634111 -233.850478)
			(xy 109.683504 -233.83443) (xy 109.734799 -233.826305) (xy 109.786733 -233.826305) (xy 109.838028 -233.83443)
			(xy 109.887421 -233.850478) (xy 109.933695 -233.874056) (xy 109.975711 -233.904582) (xy 110.012434 -233.941305)
			(xy 110.04296 -233.983321) (xy 110.066538 -234.029595) (xy 110.082586 -234.078988) (xy 110.090711 -234.130283)
			(xy 110.09122 -234.15625) (xy 110.090711 -234.182217) (xy 110.082586 -234.233512) (xy 110.066538 -234.282905)
			(xy 110.04296 -234.329179) (xy 110.012434 -234.371195) (xy 109.975711 -234.407918) (xy 109.933695 -234.438444)
			(xy 109.887421 -234.462022) (xy 109.838028 -234.47807) (xy 109.786733 -234.486195) (xy 109.734799 -234.486195)
			(xy 109.683504 -234.47807) (xy 109.634111 -234.462022) (xy 109.587837 -234.438444) (xy 109.545821 -234.407918)
			(xy 109.509098 -234.371195) (xy 109.478572 -234.329179) (xy 109.454994 -234.282905) (xy 109.438946 -234.233512)
			(xy 109.430821 -234.182217) (xy 109.150911 -234.182217) (xy 109.142786 -234.233512) (xy 109.126738 -234.282905)
			(xy 109.10316 -234.329179) (xy 109.072634 -234.371195) (xy 109.035911 -234.407918) (xy 108.993895 -234.438444)
			(xy 108.947621 -234.462022) (xy 108.898228 -234.47807) (xy 108.846933 -234.486195) (xy 108.794999 -234.486195)
			(xy 108.743704 -234.47807) (xy 108.694311 -234.462022) (xy 108.648037 -234.438444) (xy 108.606021 -234.407918)
			(xy 108.569298 -234.371195) (xy 108.538772 -234.329179) (xy 108.515194 -234.282905) (xy 108.499146 -234.233512)
			(xy 108.491021 -234.182217) (xy 108.211111 -234.182217) (xy 108.202986 -234.233512) (xy 108.186938 -234.282905)
			(xy 108.16336 -234.329179) (xy 108.132834 -234.371195) (xy 108.096111 -234.407918) (xy 108.054095 -234.438444)
			(xy 108.007821 -234.462022) (xy 107.958428 -234.47807) (xy 107.907133 -234.486195) (xy 107.855199 -234.486195)
			(xy 107.803904 -234.47807) (xy 107.754511 -234.462022) (xy 107.708237 -234.438444) (xy 107.666221 -234.407918)
			(xy 107.629498 -234.371195) (xy 107.598972 -234.329179) (xy 107.575394 -234.282905) (xy 107.559346 -234.233512)
			(xy 107.551221 -234.182217) (xy 107.271311 -234.182217) (xy 107.263186 -234.233512) (xy 107.247138 -234.282905)
			(xy 107.22356 -234.329179) (xy 107.193034 -234.371195) (xy 107.156311 -234.407918) (xy 107.114295 -234.438444)
			(xy 107.068021 -234.462022) (xy 107.018628 -234.47807) (xy 106.967333 -234.486195) (xy 106.915399 -234.486195)
			(xy 106.864104 -234.47807) (xy 106.814711 -234.462022) (xy 106.768437 -234.438444) (xy 106.726421 -234.407918)
			(xy 106.689698 -234.371195) (xy 106.659172 -234.329179) (xy 106.635594 -234.282905) (xy 106.619546 -234.233512)
			(xy 106.611421 -234.182217) (xy 106.331511 -234.182217) (xy 106.323386 -234.233512) (xy 106.307338 -234.282905)
			(xy 106.28376 -234.329179) (xy 106.253234 -234.371195) (xy 106.216511 -234.407918) (xy 106.174495 -234.438444)
			(xy 106.128221 -234.462022) (xy 106.078828 -234.47807) (xy 106.027533 -234.486195) (xy 105.975599 -234.486195)
			(xy 105.924304 -234.47807) (xy 105.874911 -234.462022) (xy 105.828637 -234.438444) (xy 105.786621 -234.407918)
			(xy 105.749898 -234.371195) (xy 105.719372 -234.329179) (xy 105.695794 -234.282905) (xy 105.679746 -234.233512)
			(xy 105.671621 -234.182217) (xy 104.972866 -234.182217) (xy 104.972866 -234.996033) (xy 108.960921 -234.996033)
			(xy 108.960921 -234.944099) (xy 108.969046 -234.892804) (xy 108.985094 -234.843411) (xy 109.008672 -234.797137)
			(xy 109.039198 -234.755121) (xy 109.075921 -234.718398) (xy 109.117937 -234.687872) (xy 109.164211 -234.664294)
			(xy 109.213604 -234.648246) (xy 109.264899 -234.640121) (xy 109.316833 -234.640121) (xy 109.368128 -234.648246)
			(xy 109.417521 -234.664294) (xy 109.463795 -234.687872) (xy 109.505811 -234.718398) (xy 109.542534 -234.755121)
			(xy 109.57306 -234.797137) (xy 109.596638 -234.843411) (xy 109.612686 -234.892804) (xy 109.620811 -234.944099)
			(xy 109.62132 -234.970066) (xy 109.620811 -234.996033) (xy 109.612686 -235.047328) (xy 109.596638 -235.096721)
			(xy 109.57306 -235.142995) (xy 109.542534 -235.185011) (xy 109.505811 -235.221734) (xy 109.463795 -235.25226)
			(xy 109.417521 -235.275838) (xy 109.368128 -235.291886) (xy 109.316833 -235.300011) (xy 109.264899 -235.300011)
			(xy 109.213604 -235.291886) (xy 109.164211 -235.275838) (xy 109.117937 -235.25226) (xy 109.075921 -235.221734)
			(xy 109.039198 -235.185011) (xy 109.008672 -235.142995) (xy 108.985094 -235.096721) (xy 108.969046 -235.047328)
			(xy 108.960921 -234.996033) (xy 104.972866 -234.996033) (xy 104.972866 -235.457551) (xy 105.900221 -235.457551)
			(xy 105.900221 -235.405617) (xy 105.908346 -235.354322) (xy 105.924394 -235.304929) (xy 105.947972 -235.258655)
			(xy 105.978498 -235.216639) (xy 106.015221 -235.179916) (xy 106.057237 -235.14939) (xy 106.103511 -235.125812)
			(xy 106.152904 -235.109764) (xy 106.204199 -235.101639) (xy 106.256133 -235.101639) (xy 106.307428 -235.109764)
			(xy 106.356821 -235.125812) (xy 106.403095 -235.14939) (xy 106.445111 -235.179916) (xy 106.481834 -235.216639)
			(xy 106.51236 -235.258655) (xy 106.535938 -235.304929) (xy 106.551986 -235.354322) (xy 106.560111 -235.405617)
			(xy 106.56062 -235.431584) (xy 106.560111 -235.457551) (xy 106.551986 -235.508846) (xy 106.535938 -235.558239)
			(xy 106.51236 -235.604513) (xy 106.481834 -235.646529) (xy 106.445111 -235.683252) (xy 106.403095 -235.713778)
			(xy 106.356821 -235.737356) (xy 106.307428 -235.753404) (xy 106.256133 -235.761529) (xy 106.204199 -235.761529)
			(xy 106.152904 -235.753404) (xy 106.103511 -235.737356) (xy 106.057237 -235.713778) (xy 106.015221 -235.683252)
			(xy 105.978498 -235.646529) (xy 105.947972 -235.604513) (xy 105.924394 -235.558239) (xy 105.908346 -235.508846)
			(xy 105.900221 -235.457551) (xy 104.972866 -235.457551) (xy 104.972866 -236.498638) (xy 105.294938 -236.82071)
		)
		(stroke
			(width 0)
			(type solid)
		)
		(fill yes)
		(layer "In6.Cu")
		(net "PVNN_MAIN_CPU1")
	)
	(gr_poly
		(pts
			(xy 327.359772 -75.449176) (xy 327.361042 -75.429872) (xy 327.363209 -75.401523) (xy 327.374885 -75.345881)
			(xy 327.394693 -75.29259) (xy 327.422195 -75.24283) (xy 327.456781 -75.197706) (xy 327.497683 -75.158217)
			(xy 327.520554 -75.141328) (xy 327.532698 -75.132072) (xy 327.551246 -75.107835) (xy 327.561802 -75.079198)
			(xy 327.563422 -75.048721) (xy 327.555962 -75.019126) (xy 327.540088 -74.993059) (xy 327.517219 -74.972848)
			(xy 327.503536 -74.966068) (xy 327.478726 -74.954324) (xy 327.432462 -74.924787) (xy 327.390889 -74.888946)
			(xy 327.354859 -74.847537) (xy 327.325112 -74.801408) (xy 327.302255 -74.751503) (xy 327.286759 -74.698847)
			(xy 327.278939 -74.644517) (xy 327.278492 -74.617072) (xy 327.278981 -74.589725) (xy 327.286766 -74.535589)
			(xy 327.302172 -74.48311) (xy 327.324887 -74.433357) (xy 327.354448 -74.387341) (xy 327.390255 -74.345998)
			(xy 327.431579 -74.31017) (xy 327.47758 -74.280584) (xy 327.527321 -74.257843) (xy 327.579791 -74.242409)
			(xy 327.633924 -74.234596) (xy 327.66127 -74.23404) (xy 327.687813 -74.23449) (xy 327.740391 -74.241818)
			(xy 327.791452 -74.256338) (xy 327.840019 -74.277771) (xy 327.88516 -74.305707) (xy 327.92601 -74.33961)
			(xy 327.961785 -74.378829) (xy 327.991801 -74.422615) (xy 328.015482 -74.470126) (xy 328.032373 -74.520453)
			(xy 328.037698 -74.54646) (xy 328.040709 -74.559937) (xy 328.052906 -74.584701) (xy 328.071289 -74.605294)
			(xy 328.094514 -74.620213) (xy 328.120886 -74.628368) (xy 328.148479 -74.629164) (xy 328.175277 -74.622542)
			(xy 328.199324 -74.608986) (xy 328.209402 -74.599546) (xy 329.2856 -73.523348) (xy 329.2856 -69.611748)
			(xy 332.8416 -66.055748) (xy 334.935576 -66.055748) (xy 334.949993 -66.055263) (xy 334.977684 -66.047226)
			(xy 335.002017 -66.031758) (xy 335.021049 -66.010098) (xy 335.033256 -65.983976) (xy 335.037663 -65.955481)
			(xy 335.033917 -65.926892) (xy 335.02854 -65.913508) (xy 335.020352 -65.893907) (xy 335.007878 -65.853299)
			(xy 335.003648 -65.832482) (xy 335.000445 -65.818243) (xy 334.987101 -65.792299) (xy 334.966979 -65.771175)
			(xy 334.941713 -65.756588) (xy 334.913358 -65.749722) (xy 334.884218 -65.751137) (xy 334.870298 -65.75552)
			(xy 334.839881 -65.765444) (xy 334.77681 -65.776165) (xy 334.744822 -65.776856) (xy 334.717565 -65.776395)
			(xy 334.663605 -65.768639) (xy 334.611297 -65.753283) (xy 334.561708 -65.730639) (xy 334.515846 -65.701168)
			(xy 334.474646 -65.66547) (xy 334.438945 -65.624271) (xy 334.409472 -65.578411) (xy 334.386825 -65.528823)
			(xy 334.371466 -65.476517) (xy 334.363707 -65.422557) (xy 334.363707 -65.368043) (xy 334.371466 -65.314083)
			(xy 334.386825 -65.261777) (xy 334.409472 -65.212189) (xy 334.438945 -65.166329) (xy 334.474646 -65.12513)
			(xy 334.515847 -65.089432) (xy 334.561708 -65.059961) (xy 334.611297 -65.037317) (xy 334.663605 -65.021961)
			(xy 334.717565 -65.014205) (xy 334.744822 -65.01384) (xy 334.771194 -65.014281) (xy 334.823435 -65.021538)
			(xy 334.874178 -65.035926) (xy 334.922454 -65.057168) (xy 334.967342 -65.084861) (xy 335.007985 -65.118475)
			(xy 335.043609 -65.157369) (xy 335.073533 -65.200801) (xy 335.097187 -65.247943) (xy 335.114119 -65.297894)
			(xy 335.119472 -65.32372) (xy 335.122675 -65.337957) (xy 335.13602 -65.363897) (xy 335.156142 -65.385017)
			(xy 335.181406 -65.399599) (xy 335.209759 -65.40646) (xy 335.238895 -65.405041) (xy 335.252822 -65.400682)
			(xy 335.283239 -65.390759) (xy 335.346311 -65.380042) (xy 335.378298 -65.379346) (xy 335.405551 -65.379832)
			(xy 335.459501 -65.387588) (xy 335.511799 -65.402942) (xy 335.561379 -65.425583) (xy 335.607233 -65.455048)
			(xy 335.648427 -65.490739) (xy 335.684123 -65.531929) (xy 335.713594 -65.577779) (xy 335.736241 -65.627356)
			(xy 335.751602 -65.679652) (xy 335.759365 -65.733602) (xy 335.759806 -65.760854) (xy 335.759391 -65.787037)
			(xy 335.752266 -65.838915) (xy 335.738117 -65.889332) (xy 335.728056 -65.913508) (xy 335.722761 -65.926904)
			(xy 335.719082 -65.955459) (xy 335.723519 -65.983906) (xy 335.73572 -66.009985) (xy 335.754714 -66.031621)
			(xy 335.778992 -66.047097) (xy 335.806625 -66.055182) (xy 335.82102 -66.055748) (xy 336.292444 -66.055748)
			(xy 336.306449 -66.055312) (xy 336.333408 -66.047714) (xy 336.357287 -66.033073) (xy 336.376287 -66.012493)
			(xy 336.388977 -65.987523) (xy 336.394403 -65.960044) (xy 336.392154 -65.932125) (xy 336.387694 -65.918842)
			(xy 336.376586 -65.886825) (xy 336.364579 -65.820135) (xy 336.363818 -65.786254) (xy 336.364304 -65.759003)
			(xy 336.37206 -65.705055) (xy 336.387415 -65.65276) (xy 336.410057 -65.603183) (xy 336.439523 -65.557333)
			(xy 336.475214 -65.516142) (xy 336.516405 -65.480451) (xy 336.562255 -65.450985) (xy 336.611832 -65.428343)
			(xy 336.664127 -65.412988) (xy 336.718075 -65.405232) (xy 336.772577 -65.405232) (xy 336.826525 -65.412988)
			(xy 336.87882 -65.428343) (xy 336.928397 -65.450985) (xy 336.974247 -65.480451) (xy 337.015438 -65.516142)
			(xy 337.051129 -65.557333) (xy 337.080595 -65.603183) (xy 337.103237 -65.65276) (xy 337.118592 -65.705055)
			(xy 337.126348 -65.759003) (xy 337.126834 -65.786254) (xy 337.126078 -65.820135) (xy 337.11407 -65.886826)
			(xy 337.102958 -65.918842) (xy 337.098514 -65.93212) (xy 337.096291 -65.960022) (xy 337.10173 -65.987478)
			(xy 337.114422 -66.012425) (xy 337.133413 -66.032987) (xy 337.157275 -66.047618) (xy 337.184213 -66.055218)
			(xy 337.198208 -66.055748) (xy 339.2932 -66.055748) (xy 343.7382 -61.610748) (xy 343.7382 -56.417972)
			(xy 343.737674 -56.403048) (xy 343.729041 -56.374477) (xy 343.712518 -56.349619) (xy 343.689518 -56.330597)
			(xy 343.662001 -56.319034) (xy 343.632317 -56.315916) (xy 343.61755 -56.31815) (xy 343.600948 -56.32114)
			(xy 343.567362 -56.324321) (xy 343.550494 -56.3245) (xy 343.523846 -56.324002) (xy 343.471144 -56.316058)
			(xy 343.420215 -56.300347) (xy 343.372197 -56.277222) (xy 343.328161 -56.247199) (xy 343.289092 -56.210947)
			(xy 343.255862 -56.169278) (xy 343.229214 -56.123121) (xy 343.209743 -56.073508) (xy 343.197883 -56.021548)
			(xy 343.1939 -55.9684) (xy 343.197883 -55.915252) (xy 343.209743 -55.863292) (xy 343.229214 -55.813679)
			(xy 343.255862 -55.767522) (xy 343.289092 -55.725853) (xy 343.328161 -55.689601) (xy 343.372197 -55.659578)
			(xy 343.420215 -55.636453) (xy 343.471144 -55.620742) (xy 343.523846 -55.612798) (xy 343.550494 -55.612284)
			(xy 343.567361 -55.612482) (xy 343.600946 -55.615662) (xy 343.61755 -55.618634) (xy 343.632314 -55.620919)
			(xy 343.662011 -55.6178) (xy 343.68954 -55.60623) (xy 343.71255 -55.587198) (xy 343.729077 -55.562328)
			(xy 343.737711 -55.533742) (xy 343.7382 -55.518812) (xy 343.7382 -55.478172) (xy 343.737674 -55.463248)
			(xy 343.729041 -55.434677) (xy 343.712518 -55.409819) (xy 343.689518 -55.390797) (xy 343.662001 -55.379234)
			(xy 343.632317 -55.376116) (xy 343.61755 -55.37835) (xy 343.600948 -55.38134) (xy 343.567362 -55.384521)
			(xy 343.550494 -55.3847) (xy 343.523846 -55.384202) (xy 343.471144 -55.376258) (xy 343.420215 -55.360547)
			(xy 343.372197 -55.337422) (xy 343.328161 -55.307399) (xy 343.289092 -55.271147) (xy 343.255862 -55.229478)
			(xy 343.229214 -55.183321) (xy 343.209743 -55.133708) (xy 343.197883 -55.081748) (xy 343.1939 -55.0286)
			(xy 343.197883 -54.975452) (xy 343.209743 -54.923492) (xy 343.229214 -54.873879) (xy 343.255862 -54.827722)
			(xy 343.289092 -54.786053) (xy 343.328161 -54.749801) (xy 343.372197 -54.719778) (xy 343.420215 -54.696653)
			(xy 343.471144 -54.680942) (xy 343.523846 -54.672998) (xy 343.550494 -54.672484) (xy 343.567361 -54.672682)
			(xy 343.600946 -54.675862) (xy 343.61755 -54.678834) (xy 343.632314 -54.681119) (xy 343.662011 -54.678)
			(xy 343.68954 -54.66643) (xy 343.71255 -54.647398) (xy 343.729077 -54.622528) (xy 343.737711 -54.593942)
			(xy 343.7382 -54.579012) (xy 343.7382 -54.538372) (xy 343.737674 -54.523448) (xy 343.729041 -54.494877)
			(xy 343.712518 -54.470019) (xy 343.689518 -54.450997) (xy 343.662001 -54.439434) (xy 343.632317 -54.436316)
			(xy 343.61755 -54.43855) (xy 343.600948 -54.44154) (xy 343.567362 -54.444721) (xy 343.550494 -54.4449)
			(xy 343.523846 -54.444402) (xy 343.471144 -54.436458) (xy 343.420215 -54.420747) (xy 343.372197 -54.397622)
			(xy 343.328161 -54.367599) (xy 343.289092 -54.331347) (xy 343.255862 -54.289678) (xy 343.229214 -54.243521)
			(xy 343.209743 -54.193908) (xy 343.197883 -54.141948) (xy 343.1939 -54.0888) (xy 343.197883 -54.035652)
			(xy 343.209743 -53.983692) (xy 343.229214 -53.934079) (xy 343.255862 -53.887922) (xy 343.289092 -53.846253)
			(xy 343.328161 -53.810001) (xy 343.372197 -53.779978) (xy 343.420215 -53.756853) (xy 343.471144 -53.741142)
			(xy 343.523846 -53.733198) (xy 343.550494 -53.732684) (xy 343.576431 -53.733132) (xy 343.627761 -53.740625)
			(xy 343.677458 -53.755495) (xy 343.724467 -53.777429) (xy 343.76779 -53.805959) (xy 343.787476 -53.822854)
			(xy 343.82329 -53.854858) (xy 344.470482 -53.207666) (xy 344.479891 -53.197628) (xy 344.493452 -53.173702)
			(xy 344.500133 -53.147024) (xy 344.499447 -53.119531) (xy 344.491444 -53.093219) (xy 344.476706 -53.07)
			(xy 344.456303 -53.051559) (xy 344.431716 -53.039236) (xy 344.404732 -53.033926) (xy 344.39098 -53.034438)
			(xy 344.36431 -53.035454) (xy 344.337655 -53.034981) (xy 344.28494 -53.027037) (xy 344.233998 -53.011325)
			(xy 344.185967 -52.988196) (xy 344.141919 -52.958166) (xy 344.10284 -52.921906) (xy 344.069601 -52.880227)
			(xy 344.042945 -52.834059) (xy 344.023469 -52.784435) (xy 344.011606 -52.732461) (xy 344.007622 -52.6793)
			(xy 344.011606 -52.626139) (xy 344.023469 -52.574165) (xy 344.042945 -52.524541) (xy 344.069601 -52.478373)
			(xy 344.10284 -52.436694) (xy 344.141919 -52.400434) (xy 344.185967 -52.370404) (xy 344.233998 -52.347275)
			(xy 344.28494 -52.331563) (xy 344.337655 -52.323619) (xy 344.36431 -52.323238) (xy 344.392139 -52.323776)
			(xy 344.44712 -52.332435) (xy 344.500085 -52.349542) (xy 344.549744 -52.37468) (xy 344.594888 -52.407236)
			(xy 344.634418 -52.446419) (xy 344.65133 -52.468526) (xy 344.660802 -52.480434) (xy 344.685247 -52.498524)
			(xy 344.713936 -52.508615) (xy 344.744323 -52.50981) (xy 344.773715 -52.502005) (xy 344.799507 -52.485892)
			(xy 344.81941 -52.462898) (xy 344.826082 -52.449222) (xy 344.8381 -52.423429) (xy 344.869099 -52.375713)
			(xy 344.90729 -52.333533) (xy 344.951701 -52.297962) (xy 345.001204 -52.269905) (xy 345.054537 -52.250075)
			(xy 345.110345 -52.238976) (xy 345.138756 -52.237386) (xy 345.154369 -52.236267) (xy 345.183838 -52.225763)
			(xy 345.208747 -52.206835) (xy 345.226762 -52.181258) (xy 345.236194 -52.151429) (xy 345.2368 -52.135786)
			(xy 345.2368 -52.049934) (xy 345.236222 -52.034296) (xy 345.226755 -52.004486) (xy 345.208727 -51.978927)
			(xy 345.18382 -51.960008) (xy 345.154363 -51.949495) (xy 345.138756 -51.948334) (xy 345.113724 -51.946971)
			(xy 345.064386 -51.938097) (xy 345.016776 -51.9224) (xy 344.971834 -51.90019) (xy 344.930446 -51.871905)
			(xy 344.893428 -51.838101) (xy 344.877136 -51.819048) (xy 344.868167 -51.808893) (xy 344.846007 -51.79332)
			(xy 344.820533 -51.784121) (xy 344.793536 -51.781943) (xy 344.766917 -51.786941) (xy 344.742548 -51.798762)
			(xy 344.722145 -51.816575) (xy 344.707144 -51.839125) (xy 344.702384 -51.851814) (xy 344.693079 -51.878059)
			(xy 344.667487 -51.927509) (xy 344.634516 -51.972379) (xy 344.59497 -52.011576) (xy 344.549809 -52.044147)
			(xy 344.500134 -52.069299) (xy 344.447151 -52.086421) (xy 344.39215 -52.095096) (xy 344.36431 -52.095654)
			(xy 344.337655 -52.095181) (xy 344.28494 -52.087237) (xy 344.233998 -52.071525) (xy 344.185967 -52.048396)
			(xy 344.141919 -52.018366) (xy 344.10284 -51.982106) (xy 344.069601 -51.940427) (xy 344.042945 -51.894259)
			(xy 344.023469 -51.844635) (xy 344.011606 -51.792661) (xy 344.007622 -51.7395) (xy 344.011606 -51.686339)
			(xy 344.023469 -51.634365) (xy 344.042945 -51.584741) (xy 344.069601 -51.538573) (xy 344.10284 -51.496894)
			(xy 344.141919 -51.460634) (xy 344.185967 -51.430604) (xy 344.233998 -51.407475) (xy 344.28494 -51.391763)
			(xy 344.337655 -51.383819) (xy 344.36431 -51.383438) (xy 344.39046 -51.383902) (xy 344.442196 -51.391562)
			(xy 344.492252 -51.406717) (xy 344.539549 -51.429039) (xy 344.583068 -51.458047) (xy 344.621868 -51.493115)
			(xy 344.638884 -51.512978) (xy 344.647856 -51.523143) (xy 344.670025 -51.538734) (xy 344.695514 -51.547948)
			(xy 344.722528 -51.550137) (xy 344.749168 -51.545147) (xy 344.773558 -51.533328) (xy 344.793983 -51.515512)
			(xy 344.809005 -51.492953) (xy 344.813636 -51.480212) (xy 344.822623 -51.454706) (xy 344.847212 -51.406544)
			(xy 344.878804 -51.362656) (xy 344.916674 -51.324054) (xy 344.959948 -51.291626) (xy 345.00763 -51.266119)
			(xy 345.058622 -51.24812) (xy 345.111751 -51.238044) (xy 345.138756 -51.236626) (xy 345.154371 -51.235507)
			(xy 345.183845 -51.225005) (xy 345.208761 -51.206078) (xy 345.226785 -51.180502) (xy 345.236228 -51.150671)
			(xy 345.2368 -51.135026) (xy 345.2368 -51.049174) (xy 345.236227 -51.033532) (xy 345.226768 -51.003711)
			(xy 345.208741 -50.978142) (xy 345.183832 -50.959214) (xy 345.154368 -50.948696) (xy 345.138756 -50.947574)
			(xy 345.111455 -50.946082) (xy 345.057764 -50.935767) (xy 345.006279 -50.917367) (xy 344.958212 -50.891314)
			(xy 344.914692 -50.858221) (xy 344.876741 -50.818864) (xy 344.845251 -50.77417) (xy 344.820963 -50.725188)
			(xy 344.804446 -50.673069) (xy 344.796089 -50.619038) (xy 344.796089 -50.564364) (xy 344.804446 -50.510333)
			(xy 344.820962 -50.458214) (xy 344.84525 -50.409231) (xy 344.87674 -50.364537) (xy 344.914691 -50.32518)
			(xy 344.958211 -50.292087) (xy 345.006278 -50.266033) (xy 345.057762 -50.247633) (xy 345.111454 -50.237318)
			(xy 345.138756 -50.235866) (xy 345.154368 -50.234747) (xy 345.183834 -50.224243) (xy 345.20874 -50.205314)
			(xy 345.226751 -50.179737) (xy 345.236177 -50.149908) (xy 345.2368 -50.134266) (xy 345.2368 -50.048414)
			(xy 345.236219 -50.032778) (xy 345.226749 -50.002973) (xy 345.20872 -49.97742) (xy 345.183815 -49.958505)
			(xy 345.15436 -49.947995) (xy 345.138756 -49.946814) (xy 345.11146 -49.945322) (xy 345.057777 -49.935009)
			(xy 345.006302 -49.916611) (xy 344.958243 -49.890563) (xy 344.91473 -49.857475) (xy 344.876786 -49.818125)
			(xy 344.845302 -49.773437) (xy 344.821017 -49.724463) (xy 344.804504 -49.672353) (xy 344.796149 -49.618331)
			(xy 344.796149 -49.563666) (xy 344.804505 -49.509644) (xy 344.821018 -49.457534) (xy 344.845303 -49.40856)
			(xy 344.876788 -49.363873) (xy 344.914732 -49.324523) (xy 344.958245 -49.291436) (xy 345.006304 -49.265387)
			(xy 345.05778 -49.246991) (xy 345.111463 -49.236677) (xy 345.138756 -49.235106) (xy 345.15437 -49.233987)
			(xy 345.183841 -49.223484) (xy 345.208754 -49.204557) (xy 345.226774 -49.17898) (xy 345.236211 -49.14915)
			(xy 345.2368 -49.133506) (xy 345.2368 -48.394112) (xy 345.236285 -48.378745) (xy 345.227166 -48.349395)
			(xy 345.20972 -48.324093) (xy 345.185532 -48.305133) (xy 345.156794 -48.294236) (xy 345.126116 -48.292391)
			(xy 345.11107 -48.29556) (xy 345.090191 -48.300355) (xy 345.047655 -48.305455) (xy 345.026234 -48.30572)
			(xy 344.998971 -48.305202) (xy 344.945082 -48.296891) (xy 344.893091 -48.280457) (xy 344.844215 -48.256286)
			(xy 344.799598 -48.224943) (xy 344.7796 -48.206406) (xy 344.769367 -48.197208) (xy 344.74516 -48.184151)
			(xy 344.718345 -48.178039) (xy 344.690871 -48.179316) (xy 344.664738 -48.18789) (xy 344.641847 -48.203137)
			(xy 344.632534 -48.213264) (xy 344.615521 -48.232191) (xy 344.577051 -48.265507) (xy 344.534234 -48.293013)
			(xy 344.48794 -48.314151) (xy 344.439111 -48.328491) (xy 344.388739 -48.335742) (xy 344.363294 -48.3362)
			(xy 344.336646 -48.335702) (xy 344.283944 -48.327758) (xy 344.233015 -48.312047) (xy 344.184997 -48.288922)
			(xy 344.140961 -48.258899) (xy 344.101892 -48.222647) (xy 344.068662 -48.180978) (xy 344.042014 -48.134821)
			(xy 344.022543 -48.085208) (xy 344.010683 -48.033248) (xy 344.0067 -47.9801) (xy 344.010683 -47.926952)
			(xy 344.022543 -47.874992) (xy 344.042014 -47.825379) (xy 344.068662 -47.779222) (xy 344.101892 -47.737553)
			(xy 344.140961 -47.701301) (xy 344.184997 -47.671278) (xy 344.233015 -47.648153) (xy 344.283944 -47.632442)
			(xy 344.336646 -47.624498) (xy 344.363294 -47.623984) (xy 344.390556 -47.624504) (xy 344.444443 -47.632819)
			(xy 344.496431 -47.649256) (xy 344.545304 -47.67343) (xy 344.589918 -47.704775) (xy 344.609928 -47.723298)
			(xy 344.620161 -47.732492) (xy 344.644365 -47.745541) (xy 344.671177 -47.751647) (xy 344.698645 -47.750364)
			(xy 344.724771 -47.741787) (xy 344.747654 -47.72654) (xy 344.756994 -47.71644) (xy 344.774007 -47.697514)
			(xy 344.812478 -47.664201) (xy 344.855296 -47.636697) (xy 344.901589 -47.615563) (xy 344.950418 -47.601227)
			(xy 345.000789 -47.59398) (xy 345.026234 -47.593504) (xy 345.047653 -47.593807) (xy 345.090187 -47.598896)
			(xy 345.11107 -47.603664) (xy 345.126114 -47.606798) (xy 345.156772 -47.604902) (xy 345.185485 -47.593991)
			(xy 345.209665 -47.575048) (xy 345.227132 -47.549782) (xy 345.236311 -47.520469) (xy 345.2368 -47.505112)
			(xy 345.2368 -46.80839) (xy 345.23623 -46.792746) (xy 345.226773 -46.762922) (xy 345.208747 -46.737348)
			(xy 345.183837 -46.718417) (xy 345.15437 -46.707897) (xy 345.138756 -46.70679) (xy 345.111454 -46.705298)
			(xy 345.05776 -46.694983) (xy 345.006273 -46.676582) (xy 344.958204 -46.650528) (xy 344.914682 -46.617433)
			(xy 344.876729 -46.578075) (xy 344.845238 -46.533379) (xy 344.820948 -46.484394) (xy 344.804431 -46.432273)
			(xy 344.796074 -46.378239) (xy 344.796073 -46.323563) (xy 344.80443 -46.26953) (xy 344.820947 -46.217408)
			(xy 344.845236 -46.168424) (xy 344.876727 -46.123727) (xy 344.91468 -46.084369) (xy 344.958202 -46.051273)
			(xy 345.006271 -46.025219) (xy 345.057758 -46.006818) (xy 345.111452 -45.996502) (xy 345.138756 -45.995082)
			(xy 345.154369 -45.993963) (xy 345.183837 -45.983459) (xy 345.208746 -45.964531) (xy 345.22676 -45.938954)
			(xy 345.236191 -45.909125) (xy 345.2368 -45.893482) (xy 345.2368 -45.80763) (xy 345.236221 -45.791992)
			(xy 345.226754 -45.762183) (xy 345.208725 -45.736626) (xy 345.183819 -45.717707) (xy 345.154362 -45.707195)
			(xy 345.138756 -45.70603) (xy 345.113294 -45.704662) (xy 345.063123 -45.695552) (xy 345.014764 -45.679384)
			(xy 344.969202 -45.656489) (xy 344.927369 -45.627333) (xy 344.890118 -45.592513) (xy 344.858211 -45.552739)
			(xy 344.832298 -45.508824) (xy 344.812908 -45.461663) (xy 344.80627 -45.437044) (xy 344.802441 -45.423728)
			(xy 344.788712 -45.399674) (xy 344.769019 -45.3802) (xy 344.744814 -45.36674) (xy 344.71788 -45.360287)
			(xy 344.690203 -45.361317) (xy 344.663823 -45.369754) (xy 344.640685 -45.384976) (xy 344.631264 -45.395134)
			(xy 344.614286 -45.41389) (xy 344.575937 -45.446887) (xy 344.533301 -45.474118) (xy 344.487236 -45.495033)
			(xy 344.438672 -45.50921) (xy 344.388589 -45.516363) (xy 344.363294 -45.5168) (xy 344.336646 -45.516302)
			(xy 344.283944 -45.508358) (xy 344.233015 -45.492647) (xy 344.184997 -45.469522) (xy 344.140961 -45.439499)
			(xy 344.101892 -45.403247) (xy 344.068662 -45.361578) (xy 344.042014 -45.315421) (xy 344.022543 -45.265808)
			(xy 344.010683 -45.213848) (xy 344.0067 -45.1607) (xy 344.010683 -45.107552) (xy 344.022543 -45.055592)
			(xy 344.042014 -45.005979) (xy 344.068662 -44.959822) (xy 344.101892 -44.918153) (xy 344.140961 -44.881901)
			(xy 344.184997 -44.851878) (xy 344.233015 -44.828753) (xy 344.283944 -44.813042) (xy 344.336646 -44.805098)
			(xy 344.363294 -44.804584) (xy 344.389509 -44.805056) (xy 344.441372 -44.812753) (xy 344.491548 -44.827967)
			(xy 344.538951 -44.85037) (xy 344.582561 -44.879478) (xy 344.621433 -44.914662) (xy 344.65473 -44.955163)
			(xy 344.681732 -45.000107) (xy 344.701857 -45.048522) (xy 344.708734 -45.073824) (xy 344.71257 -45.087133)
			(xy 344.726306 -45.11117) (xy 344.745998 -45.130629) (xy 344.770197 -45.144078) (xy 344.797121 -45.150525)
			(xy 344.824787 -45.149497) (xy 344.851158 -45.141069) (xy 344.874292 -45.125861) (xy 344.88374 -45.115734)
			(xy 344.903309 -45.094244) (xy 344.948174 -45.057297) (xy 344.99844 -45.028121) (xy 345.052774 -45.00749)
			(xy 345.109736 -44.995949) (xy 345.138756 -44.994322) (xy 345.154371 -44.993203) (xy 345.183844 -44.9827)
			(xy 345.20876 -44.963774) (xy 345.226783 -44.938197) (xy 345.236225 -44.908367) (xy 345.2368 -44.892722)
			(xy 345.2368 -44.806616) (xy 345.236219 -44.79098) (xy 345.22675 -44.761174) (xy 345.20872 -44.73562)
			(xy 345.183815 -44.716705) (xy 345.154361 -44.706195) (xy 345.138756 -44.705016) (xy 345.112394 -44.703583)
			(xy 345.060496 -44.693901) (xy 345.010598 -44.676655) (xy 344.963797 -44.652224) (xy 344.921121 -44.621145)
			(xy 344.883506 -44.584101) (xy 344.851779 -44.541904) (xy 344.826637 -44.495482) (xy 344.817192 -44.470828)
			(xy 344.812182 -44.458292) (xy 344.796628 -44.436239) (xy 344.775839 -44.419032) (xy 344.751268 -44.407872)
			(xy 344.724632 -44.403539) (xy 344.697791 -44.406335) (xy 344.67262 -44.416067) (xy 344.650878 -44.432052)
			(xy 344.642186 -44.44238) (xy 344.6252 -44.463002) (xy 344.586097 -44.499406) (xy 344.541993 -44.529559)
			(xy 344.493879 -44.552782) (xy 344.442835 -44.568555) (xy 344.390007 -44.576522) (xy 344.363294 -44.577)
			(xy 344.336646 -44.576502) (xy 344.283944 -44.568558) (xy 344.233015 -44.552847) (xy 344.184997 -44.529722)
			(xy 344.140961 -44.499699) (xy 344.101892 -44.463447) (xy 344.068662 -44.421778) (xy 344.042014 -44.375621)
			(xy 344.022543 -44.326008) (xy 344.010683 -44.274048) (xy 344.0067 -44.2209) (xy 344.010683 -44.167752)
			(xy 344.022543 -44.115792) (xy 344.042014 -44.066179) (xy 344.068662 -44.020022) (xy 344.101892 -43.978353)
			(xy 344.140961 -43.942101) (xy 344.184997 -43.912078) (xy 344.233015 -43.888953) (xy 344.283944 -43.873242)
			(xy 344.336646 -43.865298) (xy 344.363294 -43.864784) (xy 344.390501 -43.8653) (xy 344.444282 -43.873582)
			(xy 344.496175 -43.889954) (xy 344.544972 -43.914033) (xy 344.589535 -43.94526) (xy 344.628825 -43.982907)
			(xy 344.661927 -44.026095) (xy 344.688069 -44.073818) (xy 344.697812 -44.099226) (xy 344.702818 -44.111766)
			(xy 344.718368 -44.133828) (xy 344.739157 -44.151043) (xy 344.763731 -44.162208) (xy 344.790372 -44.166542)
			(xy 344.817218 -44.163742) (xy 344.842391 -44.154005) (xy 344.864133 -44.13801) (xy 344.872818 -44.127674)
			(xy 344.889104 -44.107877) (xy 344.926408 -44.072717) (xy 344.968371 -44.043274) (xy 345.014125 -44.020158)
			(xy 345.062722 -44.003846) (xy 345.113158 -43.994678) (xy 345.138756 -43.993308) (xy 345.15437 -43.992189)
			(xy 345.183842 -43.981686) (xy 345.208755 -43.962759) (xy 345.226775 -43.937182) (xy 345.236213 -43.907352)
			(xy 345.2368 -43.891708) (xy 345.2368 -43.807888) (xy 345.236229 -43.792244) (xy 345.226772 -43.76242)
			(xy 345.208746 -43.736847) (xy 345.183836 -43.717916) (xy 345.15437 -43.707397) (xy 345.138756 -43.706288)
			(xy 345.110919 -43.704735) (xy 345.056202 -43.694051) (xy 345.003818 -43.674972) (xy 344.955047 -43.647963)
			(xy 344.911081 -43.613684) (xy 344.872993 -43.572973) (xy 344.841714 -43.526823) (xy 344.829384 -43.501818)
			(xy 344.822442 -43.488293) (xy 344.802049 -43.465769) (xy 344.77593 -43.450245) (xy 344.746399 -43.443093)
			(xy 344.716072 -43.444948) (xy 344.687633 -43.455645) (xy 344.663601 -43.474238) (xy 344.654378 -43.486324)
			(xy 344.637558 -43.509225) (xy 344.597861 -43.549875) (xy 344.552209 -43.5837) (xy 344.501763 -43.609843)
			(xy 344.447804 -43.627638) (xy 344.391703 -43.636633) (xy 344.363294 -43.6372) (xy 344.336646 -43.636702)
			(xy 344.283944 -43.628758) (xy 344.233015 -43.613047) (xy 344.184997 -43.589922) (xy 344.140961 -43.559899)
			(xy 344.101892 -43.523647) (xy 344.068662 -43.481978) (xy 344.042014 -43.435821) (xy 344.022543 -43.386208)
			(xy 344.010683 -43.334248) (xy 344.0067 -43.2811) (xy 344.010683 -43.227952) (xy 344.022543 -43.175992)
			(xy 344.042014 -43.126379) (xy 344.068662 -43.080222) (xy 344.101892 -43.038553) (xy 344.140961 -43.002301)
			(xy 344.184997 -42.972278) (xy 344.233015 -42.949153) (xy 344.283944 -42.933442) (xy 344.336646 -42.925498)
			(xy 344.363294 -42.924984) (xy 344.388494 -42.92542) (xy 344.43839 -42.932525) (xy 344.486786 -42.946594)
			(xy 344.532715 -42.967346) (xy 344.575259 -42.994366) (xy 344.613569 -43.027115) (xy 344.646879 -43.064938)
			(xy 344.674523 -43.107079) (xy 344.68562 -43.129708) (xy 344.692564 -43.14323) (xy 344.712959 -43.165746)
			(xy 344.739076 -43.181266) (xy 344.768603 -43.188415) (xy 344.798927 -43.18656) (xy 344.827362 -43.175866)
			(xy 344.851393 -43.157279) (xy 344.860626 -43.145202) (xy 344.876778 -43.123151) (xy 344.914726 -43.083814)
			(xy 344.958242 -43.050742) (xy 345.006304 -43.024713) (xy 345.057781 -43.006339) (xy 345.111462 -42.996052)
			(xy 345.138756 -42.99458) (xy 345.154368 -42.993461) (xy 345.183836 -42.982957) (xy 345.208745 -42.964029)
			(xy 345.226759 -42.938452) (xy 345.236189 -42.908623) (xy 345.2368 -42.89298) (xy 345.2368 -42.807382)
			(xy 345.236229 -42.791739) (xy 345.226771 -42.761916) (xy 345.208744 -42.736345) (xy 345.183834 -42.717415)
			(xy 345.154369 -42.706897) (xy 345.138756 -42.705782) (xy 345.113043 -42.704387) (xy 345.062392 -42.695117)
			(xy 345.013601 -42.678654) (xy 344.967687 -42.655342) (xy 344.925606 -42.625665) (xy 344.888234 -42.590242)
			(xy 344.856348 -42.549809) (xy 344.8431 -42.527728) (xy 344.835118 -42.5149) (xy 344.813099 -42.494233)
			(xy 344.785997 -42.480912) (xy 344.756185 -42.4761) (xy 344.726269 -42.480219) (xy 344.698866 -42.492908)
			(xy 344.676373 -42.513057) (xy 344.668094 -42.525696) (xy 344.654189 -42.54781) (xy 344.620919 -42.588081)
			(xy 344.582116 -42.623053) (xy 344.538616 -42.651973) (xy 344.491353 -42.67422) (xy 344.441345 -42.689315)
			(xy 344.389667 -42.696933) (xy 344.363548 -42.6974) (xy 344.336895 -42.69693) (xy 344.284184 -42.688992)
			(xy 344.233245 -42.673285) (xy 344.185216 -42.650161) (xy 344.14117 -42.620137) (xy 344.102092 -42.583883)
			(xy 344.068854 -42.542209) (xy 344.042199 -42.496046) (xy 344.022722 -42.446426) (xy 344.01086 -42.394457)
			(xy 344.006876 -42.3413) (xy 344.01086 -42.288143) (xy 344.022722 -42.236174) (xy 344.042199 -42.186554)
			(xy 344.068854 -42.140391) (xy 344.102092 -42.098717) (xy 344.14117 -42.062463) (xy 344.185216 -42.032439)
			(xy 344.233245 -42.009315) (xy 344.284184 -41.993608) (xy 344.336895 -41.98567) (xy 344.363548 -41.985184)
			(xy 344.390223 -41.985662) (xy 344.442977 -41.993623) (xy 344.493954 -42.00936) (xy 344.542015 -42.032522)
			(xy 344.586085 -42.06259) (xy 344.62518 -42.098892) (xy 344.658426 -42.140618) (xy 344.672158 -42.163492)
			(xy 344.680142 -42.176324) (xy 344.702166 -42.196998) (xy 344.729273 -42.210327) (xy 344.759093 -42.215146)
			(xy 344.789019 -42.211033) (xy 344.816433 -42.198348) (xy 344.838939 -42.178201) (xy 344.847164 -42.165524)
			(xy 344.861175 -42.143247) (xy 344.894712 -42.102692) (xy 344.913966 -42.084752) (xy 344.923935 -42.075207)
			(xy 344.93881 -42.051971) (xy 344.946926 -42.025604) (xy 344.947693 -41.998026) (xy 344.941055 -41.971248)
			(xy 344.927494 -41.947221) (xy 344.91803 -41.937178) (xy 344.626692 -41.64584) (xy 344.590878 -41.675304)
			(xy 344.571616 -41.690776) (xy 344.529628 -41.716812) (xy 344.484442 -41.736789) (xy 344.436927 -41.750325)
			(xy 344.387997 -41.757158) (xy 344.363294 -41.7576) (xy 344.335309 -41.757079) (xy 344.280029 -41.748322)
			(xy 344.226799 -41.731026) (xy 344.17693 -41.705615) (xy 344.13165 -41.672716) (xy 344.092075 -41.633139)
			(xy 344.059177 -41.587858) (xy 344.033769 -41.537988) (xy 344.016474 -41.484758) (xy 344.00772 -41.429477)
			(xy 344.007186 -41.401492) (xy 344.00761 -41.376789) (xy 344.014446 -41.327858) (xy 344.027987 -41.280343)
			(xy 344.047971 -41.235159) (xy 344.074014 -41.193174) (xy 344.089482 -41.173908) (xy 344.118946 -41.138094)
			(xy 344.034364 -41.053512) (xy 344.024192 -41.043949) (xy 343.999853 -41.030292) (xy 343.972722 -41.023746)
			(xy 343.944833 -41.024803) (xy 343.918275 -41.033382) (xy 343.895038 -41.048841) (xy 343.876864 -41.070022)
			(xy 343.870534 -41.082468) (xy 343.859444 -41.10514) (xy 343.83182 -41.147377) (xy 343.798508 -41.185291)
			(xy 343.760177 -41.218122) (xy 343.717593 -41.245211) (xy 343.671612 -41.266015) (xy 343.623153 -41.280119)
			(xy 343.573189 -41.287239) (xy 343.547954 -41.2877) (xy 343.521308 -41.287199) (xy 343.468611 -41.27925)
			(xy 343.417687 -41.263536) (xy 343.369674 -41.240409) (xy 343.325643 -41.210384) (xy 343.286579 -41.174133)
			(xy 343.253354 -41.132465) (xy 343.226709 -41.086311) (xy 343.207241 -41.036701) (xy 343.195383 -40.984744)
			(xy 343.1914 -40.9316) (xy 343.195383 -40.878456) (xy 343.207241 -40.826499) (xy 343.226709 -40.776889)
			(xy 343.253354 -40.730735) (xy 343.286579 -40.689067) (xy 343.325643 -40.652816) (xy 343.369674 -40.622791)
			(xy 343.417687 -40.599664) (xy 343.468611 -40.58395) (xy 343.521308 -40.576001) (xy 343.547954 -40.575484)
			(xy 343.570359 -40.575806) (xy 343.614816 -40.581414) (xy 343.6366 -40.58666) (xy 343.651713 -40.590001)
			(xy 343.682609 -40.58842) (xy 343.711618 -40.57767) (xy 343.736082 -40.558733) (xy 343.75376 -40.533344)
			(xy 343.763033 -40.50383) (xy 343.7636 -40.488362) (xy 343.7636 -40.435276) (xy 343.763065 -40.419798)
			(xy 343.753813 -40.390258) (xy 343.736136 -40.364846) (xy 343.711659 -40.345897) (xy 343.682629 -40.335152)
			(xy 343.651713 -40.333597) (xy 343.6366 -40.336978) (xy 343.614754 -40.342243) (xy 343.570169 -40.347851)
			(xy 343.5477 -40.348154) (xy 343.521047 -40.347656) (xy 343.468337 -40.339711) (xy 343.4174 -40.323999)
			(xy 343.369373 -40.300871) (xy 343.32533 -40.270843) (xy 343.286254 -40.234586) (xy 343.253019 -40.19291)
			(xy 343.226366 -40.146746) (xy 343.206892 -40.097125) (xy 343.19503 -40.045156) (xy 343.191047 -39.992)
			(xy 343.19503 -39.938844) (xy 343.206892 -39.886875) (xy 343.226366 -39.837254) (xy 343.253019 -39.79109)
			(xy 343.286254 -39.749414) (xy 343.32533 -39.713157) (xy 343.369373 -39.683129) (xy 343.4174 -39.660001)
			(xy 343.468337 -39.644289) (xy 343.521047 -39.636344) (xy 343.5477 -39.635938) (xy 343.570166 -39.636282)
			(xy 343.614747 -39.64189) (xy 343.6366 -39.647114) (xy 343.651716 -39.650454) (xy 343.682617 -39.648873)
			(xy 343.711631 -39.638123) (xy 343.736102 -39.619188) (xy 343.753791 -39.593801) (xy 343.763078 -39.564286)
			(xy 343.7636 -39.548816) (xy 343.7636 -34.153348) (xy 344.0684 -33.848548) (xy 344.0684 -33.26765)
			(xy 343.805764 -32.874712) (xy 340.6902 -29.759148) (xy 340.6902 -28.212034) (xy 339.815932 -26.90368)
			(xy 339.4202 -26.507948) (xy 337.5914 -26.507948) (xy 337.0326 -27.066748) (xy 337.0326 -27.879548)
			(xy 334.518 -30.394148) (xy 332.266036 -30.394148) (xy 332.244097 -30.409713) (xy 332.196717 -30.435184)
			(xy 332.146229 -30.453746) (xy 332.093635 -30.465033) (xy 332.039976 -30.46882) (xy 331.986317 -30.465033)
			(xy 331.933723 -30.453746) (xy 331.883235 -30.435184) (xy 331.835855 -30.409713) (xy 331.813916 -30.394148)
			(xy 331.361542 -30.394148) (xy 331.227684 -30.527752) (xy 331.206835 -30.54788) (xy 331.159987 -30.581987)
			(xy 331.108378 -30.608342) (xy 331.053282 -30.626297) (xy 330.996054 -30.635408) (xy 330.96708 -30.635956)
			(xy 330.10348 -30.635956) (xy 330.078474 -30.635528) (xy 330.028925 -30.628738) (xy 329.980752 -30.615299)
			(xy 329.934844 -30.595459) (xy 329.913234 -30.58287) (xy 329.879198 -30.56255) (xy 328.784966 -31.656782)
			(xy 330.570838 -31.656782) (xy 330.574909 -31.60116) (xy 330.587035 -31.546723) (xy 330.606958 -31.494632)
			(xy 330.634254 -31.445997) (xy 330.66834 -31.401854) (xy 330.708489 -31.363145) (xy 330.753847 -31.330694)
			(xy 330.803447 -31.305193) (xy 330.856231 -31.287186) (xy 330.911074 -31.277056) (xy 330.966808 -31.275019)
			(xy 331.022245 -31.281119) (xy 331.076202 -31.295225) (xy 331.127531 -31.317037) (xy 331.175137 -31.346091)
			(xy 331.218005 -31.381766) (xy 331.255222 -31.423303) (xy 331.285995 -31.469816) (xy 331.309667 -31.520313)
			(xy 331.325735 -31.57372) (xy 331.333855 -31.628896) (xy 331.334364 -31.656782) (xy 331.333855 -31.684668)
			(xy 331.325735 -31.739844) (xy 331.309667 -31.793251) (xy 331.285995 -31.843748) (xy 331.255222 -31.890261)
			(xy 331.218005 -31.931798) (xy 331.175137 -31.967473) (xy 331.127531 -31.996527) (xy 331.076202 -32.018339)
			(xy 331.022245 -32.032445) (xy 330.966808 -32.038545) (xy 330.911074 -32.036508) (xy 330.856231 -32.026378)
			(xy 330.803447 -32.008371) (xy 330.753847 -31.98287) (xy 330.708489 -31.950419) (xy 330.66834 -31.91171)
			(xy 330.634254 -31.867567) (xy 330.606958 -31.818932) (xy 330.587035 -31.766841) (xy 330.574909 -31.712404)
			(xy 330.570838 -31.656782) (xy 328.784966 -31.656782) (xy 328.393298 -32.04845) (xy 339.795102 -32.04845)
			(xy 339.799173 -31.992828) (xy 339.811299 -31.938391) (xy 339.831222 -31.8863) (xy 339.858518 -31.837665)
			(xy 339.892604 -31.793522) (xy 339.932753 -31.754813) (xy 339.978111 -31.722362) (xy 340.027711 -31.696861)
			(xy 340.080495 -31.678854) (xy 340.135338 -31.668724) (xy 340.191072 -31.666687) (xy 340.246509 -31.672787)
			(xy 340.300466 -31.686893) (xy 340.351795 -31.708705) (xy 340.399401 -31.737759) (xy 340.442269 -31.773434)
			(xy 340.479486 -31.814971) (xy 340.510259 -31.861484) (xy 340.533931 -31.911981) (xy 340.549999 -31.965388)
			(xy 340.558119 -32.020564) (xy 340.558628 -32.04845) (xy 340.558119 -32.076336) (xy 340.549999 -32.131512)
			(xy 340.533931 -32.184919) (xy 340.510259 -32.235416) (xy 340.479486 -32.281929) (xy 340.442269 -32.323466)
			(xy 340.399401 -32.359141) (xy 340.351795 -32.388195) (xy 340.300466 -32.410007) (xy 340.246509 -32.424113)
			(xy 340.191072 -32.430213) (xy 340.135338 -32.428176) (xy 340.080495 -32.418046) (xy 340.027711 -32.400039)
			(xy 339.978111 -32.374538) (xy 339.932753 -32.342087) (xy 339.892604 -32.303378) (xy 339.858518 -32.259235)
			(xy 339.831222 -32.2106) (xy 339.811299 -32.158509) (xy 339.799173 -32.104072) (xy 339.795102 -32.04845)
			(xy 328.393298 -32.04845) (xy 327.914 -32.527748) (xy 327.914 -32.606742) (xy 337.507324 -32.606742)
			(xy 337.511395 -32.55112) (xy 337.523521 -32.496683) (xy 337.543444 -32.444592) (xy 337.57074 -32.395957)
			(xy 337.604826 -32.351814) (xy 337.644975 -32.313105) (xy 337.690333 -32.280654) (xy 337.739933 -32.255153)
			(xy 337.792717 -32.237146) (xy 337.84756 -32.227016) (xy 337.903294 -32.224979) (xy 337.958731 -32.231079)
			(xy 338.012688 -32.245185) (xy 338.064017 -32.266997) (xy 338.111623 -32.296051) (xy 338.154491 -32.331726)
			(xy 338.191708 -32.373263) (xy 338.222481 -32.419776) (xy 338.246153 -32.470273) (xy 338.262221 -32.52368)
			(xy 338.270341 -32.578856) (xy 338.27085 -32.606742) (xy 338.270341 -32.634628) (xy 338.262221 -32.689804)
			(xy 338.246153 -32.743211) (xy 338.222481 -32.793708) (xy 338.191708 -32.840221) (xy 338.154491 -32.881758)
			(xy 338.111623 -32.917433) (xy 338.064017 -32.946487) (xy 338.012688 -32.968299) (xy 337.958731 -32.982405)
			(xy 337.903294 -32.988505) (xy 337.84756 -32.986468) (xy 337.792717 -32.976338) (xy 337.739933 -32.958331)
			(xy 337.690333 -32.93283) (xy 337.644975 -32.900379) (xy 337.604826 -32.86167) (xy 337.57074 -32.817527)
			(xy 337.543444 -32.768892) (xy 337.523521 -32.716801) (xy 337.511395 -32.662364) (xy 337.507324 -32.606742)
			(xy 327.914 -32.606742) (xy 327.914 -33.186624) (xy 333.667606 -33.186624) (xy 333.671677 -33.131002)
			(xy 333.683803 -33.076565) (xy 333.703726 -33.024474) (xy 333.731022 -32.975839) (xy 333.765108 -32.931696)
			(xy 333.805257 -32.892987) (xy 333.850615 -32.860536) (xy 333.900215 -32.835035) (xy 333.952999 -32.817028)
			(xy 334.007842 -32.806898) (xy 334.063576 -32.804861) (xy 334.119013 -32.810961) (xy 334.17297 -32.825067)
			(xy 334.224299 -32.846879) (xy 334.271905 -32.875933) (xy 334.314773 -32.911608) (xy 334.35199 -32.953145)
			(xy 334.382763 -32.999658) (xy 334.406435 -33.050155) (xy 334.422503 -33.103562) (xy 334.430623 -33.158738)
			(xy 334.431132 -33.186624) (xy 334.430623 -33.21451) (xy 334.422503 -33.269686) (xy 334.406435 -33.323093)
			(xy 334.382763 -33.37359) (xy 334.35199 -33.420103) (xy 334.314773 -33.46164) (xy 334.271905 -33.497315)
			(xy 334.224299 -33.526369) (xy 334.17297 -33.548181) (xy 334.119013 -33.562287) (xy 334.063576 -33.568387)
			(xy 334.007842 -33.56635) (xy 333.952999 -33.55622) (xy 333.900215 -33.538213) (xy 333.850615 -33.512712)
			(xy 333.805257 -33.480261) (xy 333.765108 -33.441552) (xy 333.731022 -33.397409) (xy 333.703726 -33.348774)
			(xy 333.683803 -33.296683) (xy 333.671677 -33.242246) (xy 333.667606 -33.186624) (xy 327.914 -33.186624)
			(xy 327.914 -34.254948) (xy 327.787254 -34.381694) (xy 333.607662 -34.381694) (xy 333.611733 -34.326072)
			(xy 333.623859 -34.271635) (xy 333.643782 -34.219544) (xy 333.671078 -34.170909) (xy 333.705164 -34.126766)
			(xy 333.745313 -34.088057) (xy 333.790671 -34.055606) (xy 333.840271 -34.030105) (xy 333.893055 -34.012098)
			(xy 333.947898 -34.001968) (xy 334.003632 -33.999931) (xy 334.059069 -34.006031) (xy 334.106665 -34.018474)
			(xy 338.07222 -34.018474) (xy 338.076291 -33.962852) (xy 338.088417 -33.908415) (xy 338.10834 -33.856324)
			(xy 338.135636 -33.807689) (xy 338.169722 -33.763546) (xy 338.209871 -33.724837) (xy 338.255229 -33.692386)
			(xy 338.304829 -33.666885) (xy 338.357613 -33.648878) (xy 338.412456 -33.638748) (xy 338.46819 -33.636711)
			(xy 338.523627 -33.642811) (xy 338.577584 -33.656917) (xy 338.628913 -33.678729) (xy 338.676519 -33.707783)
			(xy 338.719387 -33.743458) (xy 338.756604 -33.784995) (xy 338.787377 -33.831508) (xy 338.811049 -33.882005)
			(xy 338.827117 -33.935412) (xy 338.835237 -33.990588) (xy 338.835746 -34.018474) (xy 338.835237 -34.04636)
			(xy 338.827117 -34.101536) (xy 338.811049 -34.154943) (xy 338.787377 -34.20544) (xy 338.756604 -34.251953)
			(xy 338.719387 -34.29349) (xy 338.676519 -34.329165) (xy 338.628913 -34.358219) (xy 338.577584 -34.380031)
			(xy 338.523627 -34.394137) (xy 338.46819 -34.400237) (xy 338.412456 -34.3982) (xy 338.357613 -34.38807)
			(xy 338.304829 -34.370063) (xy 338.255229 -34.344562) (xy 338.209871 -34.312111) (xy 338.169722 -34.273402)
			(xy 338.135636 -34.229259) (xy 338.10834 -34.180624) (xy 338.088417 -34.128533) (xy 338.076291 -34.074096)
			(xy 338.07222 -34.018474) (xy 334.106665 -34.018474) (xy 334.113026 -34.020137) (xy 334.164355 -34.041949)
			(xy 334.211961 -34.071003) (xy 334.254829 -34.106678) (xy 334.292046 -34.148215) (xy 334.322819 -34.194728)
			(xy 334.346491 -34.245225) (xy 334.362559 -34.298632) (xy 334.370679 -34.353808) (xy 334.371188 -34.381694)
			(xy 334.370679 -34.40958) (xy 334.362559 -34.464756) (xy 334.346491 -34.518163) (xy 334.322819 -34.56866)
			(xy 334.311911 -34.585148) (xy 342.167462 -34.585148) (xy 342.171533 -34.529526) (xy 342.183659 -34.475089)
			(xy 342.203582 -34.422998) (xy 342.230878 -34.374363) (xy 342.264964 -34.33022) (xy 342.305113 -34.291511)
			(xy 342.350471 -34.25906) (xy 342.400071 -34.233559) (xy 342.452855 -34.215552) (xy 342.507698 -34.205422)
			(xy 342.563432 -34.203385) (xy 342.618869 -34.209485) (xy 342.672826 -34.223591) (xy 342.724155 -34.245403)
			(xy 342.771761 -34.274457) (xy 342.814629 -34.310132) (xy 342.851846 -34.351669) (xy 342.882619 -34.398182)
			(xy 342.906291 -34.448679) (xy 342.922359 -34.502086) (xy 342.930479 -34.557262) (xy 342.930988 -34.585148)
			(xy 342.930479 -34.613034) (xy 342.922359 -34.66821) (xy 342.906291 -34.721617) (xy 342.882619 -34.772114)
			(xy 342.851846 -34.818627) (xy 342.814629 -34.860164) (xy 342.771761 -34.895839) (xy 342.724155 -34.924893)
			(xy 342.672826 -34.946705) (xy 342.618869 -34.960811) (xy 342.563432 -34.966911) (xy 342.507698 -34.964874)
			(xy 342.452855 -34.954744) (xy 342.400071 -34.936737) (xy 342.350471 -34.911236) (xy 342.305113 -34.878785)
			(xy 342.264964 -34.840076) (xy 342.230878 -34.795933) (xy 342.203582 -34.747298) (xy 342.183659 -34.695207)
			(xy 342.171533 -34.64077) (xy 342.167462 -34.585148) (xy 334.311911 -34.585148) (xy 334.292046 -34.615173)
			(xy 334.254829 -34.65671) (xy 334.211961 -34.692385) (xy 334.164355 -34.721439) (xy 334.113026 -34.743251)
			(xy 334.059069 -34.757357) (xy 334.003632 -34.763457) (xy 333.947898 -34.76142) (xy 333.893055 -34.75129)
			(xy 333.840271 -34.733283) (xy 333.790671 -34.707782) (xy 333.745313 -34.675331) (xy 333.705164 -34.636622)
			(xy 333.671078 -34.592479) (xy 333.643782 -34.543844) (xy 333.623859 -34.491753) (xy 333.611733 -34.437316)
			(xy 333.607662 -34.381694) (xy 327.787254 -34.381694) (xy 327.181718 -34.98723) (xy 327.653394 -34.98723)
			(xy 327.657465 -34.931608) (xy 327.669591 -34.877171) (xy 327.689514 -34.82508) (xy 327.71681 -34.776445)
			(xy 327.750896 -34.732302) (xy 327.791045 -34.693593) (xy 327.836403 -34.661142) (xy 327.886003 -34.635641)
			(xy 327.938787 -34.617634) (xy 327.99363 -34.607504) (xy 328.049364 -34.605467) (xy 328.104801 -34.611567)
			(xy 328.158758 -34.625673) (xy 328.210087 -34.647485) (xy 328.257693 -34.676539) (xy 328.300561 -34.712214)
			(xy 328.337778 -34.753751) (xy 328.368551 -34.800264) (xy 328.392223 -34.850761) (xy 328.408291 -34.904168)
			(xy 328.416411 -34.959344) (xy 328.41692 -34.98723) (xy 328.416411 -35.015116) (xy 328.408291 -35.070292)
			(xy 328.392223 -35.123699) (xy 328.368551 -35.174196) (xy 328.337778 -35.220709) (xy 328.300561 -35.262246)
			(xy 328.257693 -35.297921) (xy 328.210087 -35.326975) (xy 328.158758 -35.348787) (xy 328.104801 -35.362893)
			(xy 328.049364 -35.368993) (xy 327.99363 -35.366956) (xy 327.938787 -35.356826) (xy 327.886003 -35.338819)
			(xy 327.836403 -35.313318) (xy 327.791045 -35.280867) (xy 327.750896 -35.242158) (xy 327.71681 -35.198015)
			(xy 327.689514 -35.14938) (xy 327.669591 -35.097289) (xy 327.657465 -35.042852) (xy 327.653394 -34.98723)
			(xy 327.181718 -34.98723) (xy 326.715882 -35.453066) (xy 326.706256 -35.463295) (xy 326.692524 -35.487784)
			(xy 326.685982 -35.515089) (xy 326.687125 -35.543142) (xy 326.695866 -35.569824) (xy 326.711544 -35.593116)
			(xy 326.726732 -35.605974) (xy 328.561444 -35.605974) (xy 328.565515 -35.550352) (xy 328.577641 -35.495915)
			(xy 328.597564 -35.443824) (xy 328.62486 -35.395189) (xy 328.658946 -35.351046) (xy 328.699095 -35.312337)
			(xy 328.744453 -35.279886) (xy 328.794053 -35.254385) (xy 328.846837 -35.236378) (xy 328.90168 -35.226248)
			(xy 328.957414 -35.224211) (xy 329.012851 -35.230311) (xy 329.066808 -35.244417) (xy 329.118137 -35.266229)
			(xy 329.165743 -35.295283) (xy 329.208611 -35.330958) (xy 329.245828 -35.372495) (xy 329.276601 -35.419008)
			(xy 329.300273 -35.469505) (xy 329.316341 -35.522912) (xy 329.324461 -35.578088) (xy 329.32497 -35.605974)
			(xy 329.324461 -35.63386) (xy 329.318061 -35.677348) (xy 330.324204 -35.677348) (xy 330.328275 -35.621726)
			(xy 330.340401 -35.567289) (xy 330.360324 -35.515198) (xy 330.38762 -35.466563) (xy 330.421706 -35.42242)
			(xy 330.461855 -35.383711) (xy 330.507213 -35.35126) (xy 330.556813 -35.325759) (xy 330.609597 -35.307752)
			(xy 330.66444 -35.297622) (xy 330.720174 -35.295585) (xy 330.775611 -35.301685) (xy 330.829568 -35.315791)
			(xy 330.880897 -35.337603) (xy 330.928503 -35.366657) (xy 330.971371 -35.402332) (xy 331.008588 -35.443869)
			(xy 331.039361 -35.490382) (xy 331.063033 -35.540879) (xy 331.079101 -35.594286) (xy 331.087221 -35.649462)
			(xy 331.08773 -35.677348) (xy 331.087221 -35.705234) (xy 331.079101 -35.76041) (xy 331.063033 -35.813817)
			(xy 331.039361 -35.864314) (xy 331.008588 -35.910827) (xy 330.971371 -35.952364) (xy 330.928503 -35.988039)
			(xy 330.923173 -35.991292) (xy 340.748618 -35.991292) (xy 340.752689 -35.93567) (xy 340.764815 -35.881233)
			(xy 340.784738 -35.829142) (xy 340.812034 -35.780507) (xy 340.84612 -35.736364) (xy 340.886269 -35.697655)
			(xy 340.931627 -35.665204) (xy 340.981227 -35.639703) (xy 341.034011 -35.621696) (xy 341.088854 -35.611566)
			(xy 341.144588 -35.609529) (xy 341.200025 -35.615629) (xy 341.253982 -35.629735) (xy 341.305311 -35.651547)
			(xy 341.352917 -35.680601) (xy 341.395785 -35.716276) (xy 341.433002 -35.757813) (xy 341.463775 -35.804326)
			(xy 341.487447 -35.854823) (xy 341.503515 -35.90823) (xy 341.511635 -35.963406) (xy 341.512144 -35.991292)
			(xy 341.511635 -36.019178) (xy 341.503515 -36.074354) (xy 341.487447 -36.127761) (xy 341.463775 -36.178258)
			(xy 341.433002 -36.224771) (xy 341.395785 -36.266308) (xy 341.352917 -36.301983) (xy 341.305311 -36.331037)
			(xy 341.253982 -36.352849) (xy 341.200025 -36.366955) (xy 341.144588 -36.373055) (xy 341.088854 -36.371018)
			(xy 341.034011 -36.360888) (xy 340.981227 -36.342881) (xy 340.931627 -36.31738) (xy 340.886269 -36.284929)
			(xy 340.84612 -36.24622) (xy 340.812034 -36.202077) (xy 340.784738 -36.153442) (xy 340.764815 -36.101351)
			(xy 340.752689 -36.046914) (xy 340.748618 -35.991292) (xy 330.923173 -35.991292) (xy 330.880897 -36.017093)
			(xy 330.829568 -36.038905) (xy 330.775611 -36.053011) (xy 330.720174 -36.059111) (xy 330.66444 -36.057074)
			(xy 330.609597 -36.046944) (xy 330.556813 -36.028937) (xy 330.507213 -36.003436) (xy 330.461855 -35.970985)
			(xy 330.421706 -35.932276) (xy 330.38762 -35.888133) (xy 330.360324 -35.839498) (xy 330.340401 -35.787407)
			(xy 330.328275 -35.73297) (xy 330.324204 -35.677348) (xy 329.318061 -35.677348) (xy 329.316341 -35.689036)
			(xy 329.300273 -35.742443) (xy 329.276601 -35.79294) (xy 329.245828 -35.839453) (xy 329.208611 -35.88099)
			(xy 329.165743 -35.916665) (xy 329.118137 -35.945719) (xy 329.066808 -35.967531) (xy 329.012851 -35.981637)
			(xy 328.957414 -35.987737) (xy 328.90168 -35.9857) (xy 328.846837 -35.97557) (xy 328.794053 -35.957563)
			(xy 328.744453 -35.932062) (xy 328.699095 -35.899611) (xy 328.658946 -35.860902) (xy 328.62486 -35.816759)
			(xy 328.597564 -35.768124) (xy 328.577641 -35.716033) (xy 328.565515 -35.661596) (xy 328.561444 -35.605974)
			(xy 326.726732 -35.605974) (xy 326.732973 -35.611257) (xy 326.7456 -35.617404) (xy 326.769679 -35.628865)
			(xy 326.814571 -35.657647) (xy 326.854906 -35.692531) (xy 326.88986 -35.732804) (xy 326.918721 -35.777646)
			(xy 326.940901 -35.826142) (xy 326.955945 -35.877303) (xy 326.963549 -35.930085) (xy 326.96404 -35.956748)
			(xy 326.963519 -35.984633) (xy 326.955207 -36.03978) (xy 326.938769 -36.093072) (xy 326.914571 -36.143318)
			(xy 326.883155 -36.189397) (xy 326.845222 -36.230279) (xy 326.80162 -36.265051) (xy 326.753322 -36.292936)
			(xy 326.701407 -36.313311) (xy 326.647036 -36.325721) (xy 326.591422 -36.329889) (xy 326.535808 -36.325721)
			(xy 326.481437 -36.313311) (xy 326.429522 -36.292936) (xy 326.381224 -36.265051) (xy 326.337622 -36.230279)
			(xy 326.299689 -36.189397) (xy 326.268273 -36.143318) (xy 326.244075 -36.093072) (xy 326.227637 -36.03978)
			(xy 326.219325 -35.984633) (xy 326.218804 -35.956748) (xy 326.219188 -35.932874) (xy 326.225294 -35.885518)
			(xy 326.237397 -35.839329) (xy 326.245982 -35.817048) (xy 326.250884 -35.803686) (xy 326.253877 -35.775395)
			(xy 326.24895 -35.747375) (xy 326.236486 -35.721801) (xy 326.217451 -35.700657) (xy 326.193323 -35.685584)
			(xy 326.165973 -35.677751) (xy 326.151748 -35.677348) (xy 324.947788 -35.677348) (xy 324.947788 -35.728656)
			(xy 324.947788 -35.733228) (xy 324.947302 -35.760479) (xy 324.939546 -35.814427) (xy 324.924191 -35.866722)
			(xy 324.901549 -35.916299) (xy 324.872083 -35.962149) (xy 324.836392 -36.00334) (xy 324.795201 -36.039031)
			(xy 324.749351 -36.068497) (xy 324.699774 -36.091139) (xy 324.647479 -36.106494) (xy 324.593531 -36.11425)
			(xy 324.539029 -36.11425) (xy 324.485081 -36.106494) (xy 324.432786 -36.091139) (xy 324.383209 -36.068497)
			(xy 324.337359 -36.039031) (xy 324.296168 -36.00334) (xy 324.260477 -35.962149) (xy 324.231011 -35.916299)
			(xy 324.208369 -35.866722) (xy 324.193014 -35.814427) (xy 324.185258 -35.760479) (xy 324.184772 -35.733228)
			(xy 324.184772 -35.677348) (xy 317.9318 -35.677348) (xy 317.3476 -36.261548) (xy 317.3476 -36.439348)
			(xy 318.665604 -36.439348) (xy 318.669675 -36.383726) (xy 318.681801 -36.329289) (xy 318.701724 -36.277198)
			(xy 318.72902 -36.228563) (xy 318.763106 -36.18442) (xy 318.803255 -36.145711) (xy 318.848613 -36.11326)
			(xy 318.898213 -36.087759) (xy 318.950997 -36.069752) (xy 319.00584 -36.059622) (xy 319.061574 -36.057585)
			(xy 319.117011 -36.063685) (xy 319.170968 -36.077791) (xy 319.222297 -36.099603) (xy 319.269903 -36.128657)
			(xy 319.312771 -36.164332) (xy 319.349988 -36.205869) (xy 319.380761 -36.252382) (xy 319.404433 -36.302879)
			(xy 319.420501 -36.356286) (xy 319.428621 -36.411462) (xy 319.42913 -36.439348) (xy 319.428621 -36.467234)
			(xy 319.420501 -36.52241) (xy 319.404433 -36.575817) (xy 319.380761 -36.626314) (xy 319.349988 -36.672827)
			(xy 319.319312 -36.707064) (xy 325.015604 -36.707064) (xy 325.019675 -36.651442) (xy 325.031801 -36.597005)
			(xy 325.051724 -36.544914) (xy 325.07902 -36.496279) (xy 325.113106 -36.452136) (xy 325.153255 -36.413427)
			(xy 325.198613 -36.380976) (xy 325.248213 -36.355475) (xy 325.300997 -36.337468) (xy 325.35584 -36.327338)
			(xy 325.411574 -36.325301) (xy 325.467011 -36.331401) (xy 325.520968 -36.345507) (xy 325.562482 -36.363148)
			(xy 327.860404 -36.363148) (xy 327.864475 -36.307526) (xy 327.876601 -36.253089) (xy 327.896524 -36.200998)
			(xy 327.92382 -36.152363) (xy 327.957906 -36.10822) (xy 327.998055 -36.069511) (xy 328.043413 -36.03706)
			(xy 328.093013 -36.011559) (xy 328.145797 -35.993552) (xy 328.20064 -35.983422) (xy 328.256374 -35.981385)
			(xy 328.311811 -35.987485) (xy 328.365768 -36.001591) (xy 328.417097 -36.023403) (xy 328.464703 -36.052457)
			(xy 328.507571 -36.088132) (xy 328.544788 -36.129669) (xy 328.575561 -36.176182) (xy 328.599233 -36.226679)
			(xy 328.615301 -36.280086) (xy 328.623421 -36.335262) (xy 328.62393 -36.363148) (xy 328.623421 -36.391034)
			(xy 328.615301 -36.44621) (xy 328.599233 -36.499617) (xy 328.575561 -36.550114) (xy 328.544788 -36.596627)
			(xy 328.507571 -36.638164) (xy 328.464703 -36.673839) (xy 328.417097 -36.702893) (xy 328.365768 -36.724705)
			(xy 328.311811 -36.738811) (xy 328.256374 -36.744911) (xy 328.20064 -36.742874) (xy 328.145797 -36.732744)
			(xy 328.093013 -36.714737) (xy 328.043413 -36.689236) (xy 327.998055 -36.656785) (xy 327.957906 -36.618076)
			(xy 327.92382 -36.573933) (xy 327.896524 -36.525298) (xy 327.876601 -36.473207) (xy 327.864475 -36.41877)
			(xy 327.860404 -36.363148) (xy 325.562482 -36.363148) (xy 325.572297 -36.367319) (xy 325.619903 -36.396373)
			(xy 325.662771 -36.432048) (xy 325.699988 -36.473585) (xy 325.730761 -36.520098) (xy 325.754433 -36.570595)
			(xy 325.770501 -36.624002) (xy 325.778621 -36.679178) (xy 325.77913 -36.707064) (xy 325.778621 -36.73495)
			(xy 325.770501 -36.790126) (xy 325.754433 -36.843533) (xy 325.730761 -36.89403) (xy 325.699988 -36.940543)
			(xy 325.685015 -36.957254) (xy 326.844416 -36.957254) (xy 326.848392 -36.902928) (xy 326.860235 -36.849759)
			(xy 326.879694 -36.798882) (xy 326.906354 -36.75138) (xy 326.939645 -36.708266) (xy 326.978859 -36.670459)
			(xy 327.023161 -36.638764) (xy 327.071604 -36.613858) (xy 327.123158 -36.59627) (xy 327.176724 -36.586376)
			(xy 327.231159 -36.584386) (xy 327.285304 -36.590344) (xy 327.338004 -36.604122) (xy 327.388137 -36.625426)
			(xy 327.434633 -36.653802) (xy 327.476503 -36.688646) (xy 327.512852 -36.729215) (xy 327.542908 -36.774644)
			(xy 327.566029 -36.823965) (xy 327.581722 -36.876127) (xy 327.589653 -36.930018) (xy 327.59015 -36.957254)
			(xy 327.589653 -36.98449) (xy 327.581722 -37.038381) (xy 327.581447 -37.039296) (xy 329.218554 -37.039296)
			(xy 329.22253 -36.98497) (xy 329.234373 -36.931801) (xy 329.253832 -36.880924) (xy 329.280492 -36.833422)
			(xy 329.313783 -36.790308) (xy 329.352997 -36.752501) (xy 329.397299 -36.720806) (xy 329.445742 -36.6959)
			(xy 329.497296 -36.678312) (xy 329.550862 -36.668418) (xy 329.605297 -36.666428) (xy 329.659442 -36.672386)
			(xy 329.712142 -36.686164) (xy 329.762275 -36.707468) (xy 329.808771 -36.735844) (xy 329.850641 -36.770688)
			(xy 329.88699 -36.811257) (xy 329.917046 -36.856686) (xy 329.940167 -36.906007) (xy 329.95586 -36.958169)
			(xy 329.963791 -37.01206) (xy 329.964288 -37.039296) (xy 329.963791 -37.066532) (xy 329.95586 -37.120423)
			(xy 329.949471 -37.141658) (xy 335.912216 -37.141658) (xy 335.916192 -37.087332) (xy 335.928035 -37.034163)
			(xy 335.947494 -36.983286) (xy 335.974154 -36.935784) (xy 336.007445 -36.89267) (xy 336.046659 -36.854863)
			(xy 336.090961 -36.823168) (xy 336.139404 -36.798262) (xy 336.190958 -36.780674) (xy 336.244524 -36.77078)
			(xy 336.298959 -36.76879) (xy 336.353104 -36.774748) (xy 336.405804 -36.788526) (xy 336.455937 -36.80983)
			(xy 336.502433 -36.838206) (xy 336.544303 -36.87305) (xy 336.580652 -36.913619) (xy 336.590028 -36.92779)
			(xy 342.4517 -36.92779) (xy 342.455676 -36.873464) (xy 342.467519 -36.820295) (xy 342.486978 -36.769418)
			(xy 342.513638 -36.721916) (xy 342.546929 -36.678802) (xy 342.586143 -36.640995) (xy 342.630445 -36.6093)
			(xy 342.678888 -36.584394) (xy 342.730442 -36.566806) (xy 342.784008 -36.556912) (xy 342.838443 -36.554922)
			(xy 342.892588 -36.56088) (xy 342.945288 -36.574658) (xy 342.995421 -36.595962) (xy 343.041917 -36.624338)
			(xy 343.083787 -36.659182) (xy 343.120136 -36.699751) (xy 343.150192 -36.74518) (xy 343.173313 -36.794501)
			(xy 343.189006 -36.846663) (xy 343.196937 -36.900554) (xy 343.197434 -36.92779) (xy 343.196937 -36.955026)
			(xy 343.189006 -37.008917) (xy 343.173313 -37.061079) (xy 343.150192 -37.1104) (xy 343.120136 -37.155829)
			(xy 343.083787 -37.196398) (xy 343.041917 -37.231242) (xy 342.995421 -37.259618) (xy 342.945288 -37.280922)
			(xy 342.892588 -37.2947) (xy 342.838443 -37.300658) (xy 342.784008 -37.298668) (xy 342.730442 -37.288774)
			(xy 342.678888 -37.271186) (xy 342.630445 -37.24628) (xy 342.586143 -37.214585) (xy 342.546929 -37.176778)
			(xy 342.513638 -37.133664) (xy 342.486978 -37.086162) (xy 342.467519 -37.035285) (xy 342.455676 -36.982116)
			(xy 342.4517 -36.92779) (xy 336.590028 -36.92779) (xy 336.610708 -36.959048) (xy 336.633829 -37.008369)
			(xy 336.649522 -37.060531) (xy 336.657453 -37.114422) (xy 336.65795 -37.141658) (xy 336.657453 -37.168894)
			(xy 336.649522 -37.222785) (xy 336.633829 -37.274947) (xy 336.610708 -37.324268) (xy 336.580652 -37.369697)
			(xy 336.544303 -37.410266) (xy 336.502433 -37.44511) (xy 336.455937 -37.473486) (xy 336.405804 -37.49479)
			(xy 336.353104 -37.508568) (xy 336.298959 -37.514526) (xy 336.244524 -37.512536) (xy 336.190958 -37.502642)
			(xy 336.139404 -37.485054) (xy 336.090961 -37.460148) (xy 336.046659 -37.428453) (xy 336.007445 -37.390646)
			(xy 335.974154 -37.347532) (xy 335.947494 -37.30003) (xy 335.928035 -37.249153) (xy 335.916192 -37.195984)
			(xy 335.912216 -37.141658) (xy 329.949471 -37.141658) (xy 329.940167 -37.172585) (xy 329.917046 -37.221906)
			(xy 329.88699 -37.267335) (xy 329.850641 -37.307904) (xy 329.808771 -37.342748) (xy 329.762275 -37.371124)
			(xy 329.712142 -37.392428) (xy 329.659442 -37.406206) (xy 329.605297 -37.412164) (xy 329.550862 -37.410174)
			(xy 329.497296 -37.40028) (xy 329.445742 -37.382692) (xy 329.397299 -37.357786) (xy 329.352997 -37.326091)
			(xy 329.313783 -37.288284) (xy 329.280492 -37.24517) (xy 329.253832 -37.197668) (xy 329.234373 -37.146791)
			(xy 329.22253 -37.093622) (xy 329.218554 -37.039296) (xy 327.581447 -37.039296) (xy 327.566029 -37.090543)
			(xy 327.542908 -37.139864) (xy 327.512852 -37.185293) (xy 327.476503 -37.225862) (xy 327.434633 -37.260706)
			(xy 327.388137 -37.289082) (xy 327.338004 -37.310386) (xy 327.285304 -37.324164) (xy 327.231159 -37.330122)
			(xy 327.176724 -37.328132) (xy 327.123158 -37.318238) (xy 327.071604 -37.30065) (xy 327.023161 -37.275744)
			(xy 326.978859 -37.244049) (xy 326.939645 -37.206242) (xy 326.906354 -37.163128) (xy 326.879694 -37.115626)
			(xy 326.860235 -37.064749) (xy 326.848392 -37.01158) (xy 326.844416 -36.957254) (xy 325.685015 -36.957254)
			(xy 325.662771 -36.98208) (xy 325.619903 -37.017755) (xy 325.572297 -37.046809) (xy 325.520968 -37.068621)
			(xy 325.467011 -37.082727) (xy 325.411574 -37.088827) (xy 325.35584 -37.08679) (xy 325.300997 -37.07666)
			(xy 325.248213 -37.058653) (xy 325.198613 -37.033152) (xy 325.153255 -37.000701) (xy 325.113106 -36.961992)
			(xy 325.07902 -36.917849) (xy 325.051724 -36.869214) (xy 325.031801 -36.817123) (xy 325.019675 -36.762686)
			(xy 325.015604 -36.707064) (xy 319.319312 -36.707064) (xy 319.312771 -36.714364) (xy 319.269903 -36.750039)
			(xy 319.222297 -36.779093) (xy 319.170968 -36.800905) (xy 319.117011 -36.815011) (xy 319.061574 -36.821111)
			(xy 319.00584 -36.819074) (xy 318.950997 -36.808944) (xy 318.898213 -36.790937) (xy 318.848613 -36.765436)
			(xy 318.803255 -36.732985) (xy 318.763106 -36.694276) (xy 318.72902 -36.650133) (xy 318.701724 -36.601498)
			(xy 318.681801 -36.549407) (xy 318.669675 -36.49497) (xy 318.665604 -36.439348) (xy 317.3476 -36.439348)
			(xy 317.3476 -37.963348) (xy 318.665604 -37.963348) (xy 318.669675 -37.907726) (xy 318.681801 -37.853289)
			(xy 318.701724 -37.801198) (xy 318.72902 -37.752563) (xy 318.763106 -37.70842) (xy 318.803255 -37.669711)
			(xy 318.848613 -37.63726) (xy 318.898213 -37.611759) (xy 318.950997 -37.593752) (xy 319.00584 -37.583622)
			(xy 319.061574 -37.581585) (xy 319.117011 -37.587685) (xy 319.170968 -37.601791) (xy 319.222297 -37.623603)
			(xy 319.269903 -37.652657) (xy 319.312771 -37.688332) (xy 319.349988 -37.729869) (xy 319.380761 -37.776382)
			(xy 319.404433 -37.826879) (xy 319.418974 -37.87521) (xy 325.707258 -37.87521) (xy 325.711234 -37.820884)
			(xy 325.723077 -37.767715) (xy 325.742536 -37.716838) (xy 325.769196 -37.669336) (xy 325.802487 -37.626222)
			(xy 325.841701 -37.588415) (xy 325.886003 -37.55672) (xy 325.934446 -37.531814) (xy 325.986 -37.514226)
			(xy 326.039566 -37.504332) (xy 326.094001 -37.502342) (xy 326.148146 -37.5083) (xy 326.200846 -37.522078)
			(xy 326.250979 -37.543382) (xy 326.297475 -37.571758) (xy 326.339345 -37.606602) (xy 326.375694 -37.647171)
			(xy 326.40575 -37.6926) (xy 326.428871 -37.741921) (xy 326.444564 -37.794083) (xy 326.452495 -37.847974)
			(xy 326.452992 -37.87521) (xy 326.452495 -37.902446) (xy 326.444564 -37.956337) (xy 326.428871 -38.008499)
			(xy 326.40575 -38.05782) (xy 326.375694 -38.103249) (xy 326.339345 -38.143818) (xy 326.297475 -38.178662)
			(xy 326.250979 -38.207038) (xy 326.200846 -38.228342) (xy 326.148146 -38.24212) (xy 326.094001 -38.248078)
			(xy 326.039566 -38.246088) (xy 325.986 -38.236194) (xy 325.934446 -38.218606) (xy 325.886003 -38.1937)
			(xy 325.841701 -38.162005) (xy 325.802487 -38.124198) (xy 325.769196 -38.081084) (xy 325.742536 -38.033582)
			(xy 325.723077 -37.982705) (xy 325.711234 -37.929536) (xy 325.707258 -37.87521) (xy 319.418974 -37.87521)
			(xy 319.420501 -37.880286) (xy 319.428621 -37.935462) (xy 319.42913 -37.963348) (xy 319.428621 -37.991234)
			(xy 319.420501 -38.04641) (xy 319.404433 -38.099817) (xy 319.380761 -38.150314) (xy 319.349988 -38.196827)
			(xy 319.312771 -38.238364) (xy 319.269903 -38.274039) (xy 319.222297 -38.303093) (xy 319.170968 -38.324905)
			(xy 319.117011 -38.339011) (xy 319.061574 -38.345111) (xy 319.00584 -38.343074) (xy 318.950997 -38.332944)
			(xy 318.898213 -38.314937) (xy 318.848613 -38.289436) (xy 318.803255 -38.256985) (xy 318.763106 -38.218276)
			(xy 318.72902 -38.174133) (xy 318.701724 -38.125498) (xy 318.681801 -38.073407) (xy 318.669675 -38.01897)
			(xy 318.665604 -37.963348) (xy 317.3476 -37.963348) (xy 317.3476 -39.570152) (xy 325.707258 -39.570152)
			(xy 325.711234 -39.515826) (xy 325.723077 -39.462657) (xy 325.742536 -39.41178) (xy 325.769196 -39.364278)
			(xy 325.802487 -39.321164) (xy 325.841701 -39.283357) (xy 325.886003 -39.251662) (xy 325.934446 -39.226756)
			(xy 325.986 -39.209168) (xy 326.039566 -39.199274) (xy 326.094001 -39.197284) (xy 326.148146 -39.203242)
			(xy 326.200846 -39.21702) (xy 326.250979 -39.238324) (xy 326.297475 -39.2667) (xy 326.339345 -39.301544)
			(xy 326.375694 -39.342113) (xy 326.40575 -39.387542) (xy 326.428871 -39.436863) (xy 326.43878 -39.469801)
			(xy 330.040986 -39.469801) (xy 330.040986 -39.416503) (xy 330.048929 -39.363799) (xy 330.064639 -39.312869)
			(xy 330.087765 -39.264848) (xy 330.117789 -39.220811) (xy 330.154041 -39.18174) (xy 330.195712 -39.148509)
			(xy 330.24187 -39.12186) (xy 330.291484 -39.102388) (xy 330.343446 -39.090528) (xy 330.396596 -39.086545)
			(xy 330.449746 -39.090528) (xy 330.501708 -39.102388) (xy 330.551322 -39.12186) (xy 330.59748 -39.148509)
			(xy 330.639151 -39.18174) (xy 330.675403 -39.220811) (xy 330.705427 -39.264848) (xy 330.728553 -39.312869)
			(xy 330.744263 -39.363799) (xy 330.752206 -39.416503) (xy 330.752537 -39.434198) (xy 335.042556 -39.434198)
			(xy 335.04803 -39.380312) (xy 335.061601 -39.327876) (xy 335.082956 -39.2781) (xy 335.111602 -39.232132)
			(xy 335.146879 -39.191031) (xy 335.187972 -39.155746) (xy 335.233934 -39.12709) (xy 335.283706 -39.105725)
			(xy 335.336139 -39.092143) (xy 335.390024 -39.086657) (xy 335.444119 -39.089395) (xy 335.497175 -39.100291)
			(xy 335.547969 -39.119097) (xy 335.59533 -39.145377) (xy 335.638165 -39.178525) (xy 335.675487 -39.217778)
			(xy 335.706435 -39.26223) (xy 335.730294 -39.310855) (xy 335.746516 -39.362532) (xy 335.754725 -39.41607)
			(xy 335.755234 -39.443152) (xy 335.754943 -39.463659) (xy 335.750235 -39.504401) (xy 335.745836 -39.524432)
			(xy 335.742981 -39.538986) (xy 335.744906 -39.56857) (xy 335.75523 -39.596361) (xy 335.773086 -39.620028)
			(xy 335.796977 -39.637584) (xy 335.824896 -39.647556) (xy 335.854502 -39.649107) (xy 335.869026 -39.646098)
			(xy 335.889847 -39.641343) (xy 335.932253 -39.636253) (xy 335.953608 -39.635938) (xy 335.980687 -39.636406)
			(xy 336.034219 -39.644608) (xy 336.085893 -39.660821) (xy 336.134515 -39.684672) (xy 336.178966 -39.715611)
			(xy 336.218219 -39.752923) (xy 336.251369 -39.79575) (xy 336.277652 -39.843102) (xy 336.296462 -39.893888)
			(xy 336.307365 -39.946936) (xy 336.31011 -40.001024) (xy 336.308313 -40.018695) (xy 337.226138 -40.018695)
			(xy 337.226138 -39.965397) (xy 337.234081 -39.912693) (xy 337.249791 -39.861763) (xy 337.272917 -39.813742)
			(xy 337.302941 -39.769705) (xy 337.339193 -39.730634) (xy 337.380864 -39.697403) (xy 337.427022 -39.670754)
			(xy 337.476636 -39.651282) (xy 337.528598 -39.639422) (xy 337.581748 -39.635439) (xy 337.634898 -39.639422)
			(xy 337.68686 -39.651282) (xy 337.736474 -39.670754) (xy 337.782632 -39.697403) (xy 337.824303 -39.730634)
			(xy 337.860555 -39.769705) (xy 337.890579 -39.813742) (xy 337.913705 -39.861763) (xy 337.929415 -39.912693)
			(xy 337.937358 -39.965397) (xy 337.937856 -39.992046) (xy 337.937358 -40.018695) (xy 338.854278 -40.018695)
			(xy 338.854278 -39.965397) (xy 338.862221 -39.912693) (xy 338.877931 -39.861763) (xy 338.901057 -39.813742)
			(xy 338.931081 -39.769705) (xy 338.967333 -39.730634) (xy 339.009004 -39.697403) (xy 339.055162 -39.670754)
			(xy 339.104776 -39.651282) (xy 339.156738 -39.639422) (xy 339.209888 -39.635439) (xy 339.263038 -39.639422)
			(xy 339.315 -39.651282) (xy 339.364614 -39.670754) (xy 339.410772 -39.697403) (xy 339.452443 -39.730634)
			(xy 339.488695 -39.769705) (xy 339.518719 -39.813742) (xy 339.541845 -39.861763) (xy 339.557555 -39.912693)
			(xy 339.565498 -39.965397) (xy 339.565995 -39.992) (xy 339.934139 -39.992) (xy 339.938121 -39.938861)
			(xy 339.949978 -39.886909) (xy 339.969444 -39.837305) (xy 339.996086 -39.791155) (xy 340.029309 -39.749492)
			(xy 340.068369 -39.713244) (xy 340.112395 -39.683223) (xy 340.160404 -39.660098) (xy 340.211323 -39.644387)
			(xy 340.264014 -39.636439) (xy 340.290658 -39.635938) (xy 340.318244 -39.636465) (xy 340.37275 -39.645015)
			(xy 340.425284 -39.661869) (xy 340.45017 -39.673784) (xy 340.463196 -39.679776) (xy 340.491384 -39.68496)
			(xy 340.519903 -39.682116) (xy 340.546513 -39.671469) (xy 340.569122 -39.653855) (xy 340.577932 -39.642542)
			(xy 340.594805 -39.620216) (xy 340.634371 -39.580643) (xy 340.679641 -39.547747) (xy 340.729499 -39.522337)
			(xy 340.782718 -39.50504) (xy 340.837988 -39.496281) (xy 340.865968 -39.49573) (xy 340.881674 -39.495922)
			(xy 340.912961 -39.498721) (xy 340.928452 -39.501318) (xy 340.942366 -39.503274) (xy 340.97031 -39.50049)
			(xy 340.996444 -39.49021) (xy 341.018795 -39.473207) (xy 341.035677 -39.450766) (xy 341.045817 -39.424578)
			(xy 341.047578 -39.41064) (xy 341.050405 -39.384434) (xy 341.062897 -39.333225) (xy 341.082802 -39.284418)
			(xy 341.109685 -39.239079) (xy 341.142958 -39.198198) (xy 341.181895 -39.162669) (xy 341.225644 -39.13327)
			(xy 341.27325 -39.110641) (xy 341.323671 -39.095278) (xy 341.375807 -39.087516) (xy 341.402162 -39.087044)
			(xy 341.430142 -39.087676) (xy 341.485413 -39.096424) (xy 341.538635 -39.11371) (xy 341.588498 -39.139109)
			(xy 341.633774 -39.171996) (xy 341.673348 -39.21156) (xy 341.706246 -39.256828) (xy 341.731657 -39.306685)
			(xy 341.748956 -39.359903) (xy 341.757717 -39.415172) (xy 341.75827 -39.443152) (xy 341.758002 -39.462098)
			(xy 341.753932 -39.499771) (xy 341.750142 -39.518336) (xy 341.747623 -39.532202) (xy 341.749477 -39.560313)
			(xy 341.758939 -39.586848) (xy 341.77529 -39.609789) (xy 341.797286 -39.627391) (xy 341.823253 -39.638316)
			(xy 341.851217 -39.641731) (xy 341.865204 -39.640002) (xy 341.878709 -39.638065) (xy 341.905917 -39.636034)
			(xy 341.91956 -39.635938) (xy 341.94212 -39.636302) (xy 341.986878 -39.641996) (xy 342.030559 -39.653297)
			(xy 342.05164 -39.661338) (xy 342.065478 -39.666366) (xy 342.094787 -39.66904) (xy 342.123639 -39.663233)
			(xy 342.149631 -39.649429) (xy 342.1706 -39.628777) (xy 342.178132 -39.616126) (xy 342.191701 -39.5926)
			(xy 342.224853 -39.549585) (xy 342.264149 -39.512099) (xy 342.308678 -39.481011) (xy 342.357408 -39.457039)
			(xy 342.409213 -39.44074) (xy 342.46289 -39.43249) (xy 342.490044 -39.431976) (xy 342.518027 -39.4325)
			(xy 342.573305 -39.441261) (xy 342.626531 -39.458561) (xy 342.676396 -39.483973) (xy 342.721673 -39.516872)
			(xy 342.761246 -39.556449) (xy 342.794141 -39.601728) (xy 342.81955 -39.651595) (xy 342.836845 -39.704823)
			(xy 342.845602 -39.7601) (xy 342.846152 -39.788084) (xy 342.845746 -39.812616) (xy 342.839032 -39.861219)
			(xy 342.825716 -39.908442) (xy 342.806049 -39.953392) (xy 342.793574 -39.97452) (xy 342.786085 -39.987801)
			(xy 342.77857 -40.017334) (xy 342.780092 -40.04777) (xy 342.790519 -40.076405) (xy 342.808922 -40.100695)
			(xy 342.833667 -40.118482) (xy 342.84793 -40.123872) (xy 342.87413 -40.133197) (xy 342.923498 -40.158797)
			(xy 342.968286 -40.191759) (xy 343.007407 -40.231281) (xy 343.03991 -40.276404) (xy 343.065005 -40.32603)
			(xy 343.082082 -40.378953) (xy 343.090727 -40.433887) (xy 343.091262 -40.461692) (xy 343.090764 -40.488341)
			(xy 343.082821 -40.541045) (xy 343.067111 -40.591975) (xy 343.043985 -40.639996) (xy 343.013961 -40.684033)
			(xy 342.977709 -40.723104) (xy 342.936038 -40.756335) (xy 342.88988 -40.782984) (xy 342.840266 -40.802456)
			(xy 342.788304 -40.814316) (xy 342.735154 -40.8183) (xy 342.682004 -40.814316) (xy 342.630042 -40.802456)
			(xy 342.580428 -40.782984) (xy 342.53427 -40.756335) (xy 342.492599 -40.723104) (xy 342.456347 -40.684033)
			(xy 342.426323 -40.639996) (xy 342.403197 -40.591975) (xy 342.387487 -40.541045) (xy 342.379544 -40.488341)
			(xy 342.379046 -40.461692) (xy 342.379441 -40.437159) (xy 342.386158 -40.388556) (xy 342.399478 -40.341333)
			(xy 342.419148 -40.296383) (xy 342.431624 -40.275256) (xy 342.439078 -40.261952) (xy 342.446611 -40.23242)
			(xy 342.445104 -40.20198) (xy 342.434689 -40.173337) (xy 342.416293 -40.149038) (xy 342.39155 -40.131242)
			(xy 342.377268 -40.125904) (xy 342.357964 -40.118792) (xy 342.344129 -40.113754) (xy 342.314817 -40.111079)
			(xy 342.285963 -40.116886) (xy 342.259969 -40.130694) (xy 342.239002 -40.15135) (xy 342.231472 -40.164004)
			(xy 342.217912 -40.187535) (xy 342.184757 -40.230549) (xy 342.145459 -40.268033) (xy 342.100929 -40.29912)
			(xy 342.052197 -40.323091) (xy 342.000392 -40.33939) (xy 341.946714 -40.347639) (xy 341.91956 -40.348154)
			(xy 341.891578 -40.347596) (xy 341.836304 -40.338837) (xy 341.78308 -40.321539) (xy 341.733217 -40.29613)
			(xy 341.687942 -40.263235) (xy 341.648369 -40.223663) (xy 341.615473 -40.178388) (xy 341.590063 -40.128525)
			(xy 341.572765 -40.075302) (xy 341.564004 -40.020028) (xy 341.563452 -39.992046) (xy 341.563719 -39.9731)
			(xy 341.56779 -39.935427) (xy 341.57158 -39.916862) (xy 341.57419 -39.903007) (xy 341.572336 -39.87488)
			(xy 341.562865 -39.84833) (xy 341.546499 -39.825379) (xy 341.524483 -39.807774) (xy 341.498495 -39.796856)
			(xy 341.470512 -39.793456) (xy 341.456518 -39.795196) (xy 341.443013 -39.79713) (xy 341.415804 -39.799163)
			(xy 341.402162 -39.79926) (xy 341.386456 -39.799065) (xy 341.355169 -39.796268) (xy 341.339678 -39.793672)
			(xy 341.325772 -39.791653) (xy 341.297822 -39.794453) (xy 341.271686 -39.804748) (xy 341.249336 -39.821762)
			(xy 341.232453 -39.844213) (xy 341.222313 -39.870409) (xy 341.220552 -39.88435) (xy 341.217231 -39.913883)
			(xy 341.202035 -39.971334) (xy 341.190326 -39.99865) (xy 341.185118 -40.011156) (xy 341.180899 -40.037909)
			(xy 341.183861 -40.06483) (xy 341.193795 -40.090026) (xy 341.210002 -40.111725) (xy 341.231343 -40.128401)
			(xy 341.243666 -40.134032) (xy 341.267568 -40.144596) (xy 341.312269 -40.17166) (xy 341.352535 -40.204965)
			(xy 341.387503 -40.243797) (xy 341.416421 -40.287321) (xy 341.438669 -40.334604) (xy 341.453769 -40.38463)
			(xy 341.461397 -40.436326) (xy 341.461852 -40.462454) (xy 341.461354 -40.489103) (xy 341.453411 -40.541807)
			(xy 341.437701 -40.592737) (xy 341.414575 -40.640758) (xy 341.384551 -40.684795) (xy 341.348299 -40.723866)
			(xy 341.306628 -40.757097) (xy 341.26047 -40.783746) (xy 341.210856 -40.803218) (xy 341.158894 -40.815078)
			(xy 341.105744 -40.819062) (xy 341.052594 -40.815078) (xy 341.000632 -40.803218) (xy 340.951018 -40.783746)
			(xy 340.90486 -40.757097) (xy 340.863189 -40.723866) (xy 340.826937 -40.684795) (xy 340.796913 -40.640758)
			(xy 340.773787 -40.592737) (xy 340.758077 -40.541807) (xy 340.750134 -40.489103) (xy 340.749636 -40.462454)
			(xy 340.750068 -40.437218) (xy 340.757215 -40.387255) (xy 340.77136 -40.338805) (xy 340.781386 -40.315642)
			(xy 340.786597 -40.303137) (xy 340.790813 -40.276384) (xy 340.78785 -40.249463) (xy 340.777915 -40.224267)
			(xy 340.761709 -40.202568) (xy 340.740368 -40.185892) (xy 340.728046 -40.18026) (xy 340.706456 -40.1701)
			(xy 340.693429 -40.164107) (xy 340.66524 -40.158912) (xy 340.636718 -40.161752) (xy 340.610106 -40.172402)
			(xy 340.5875 -40.190024) (xy 340.578694 -40.201342) (xy 340.561801 -40.223653) (xy 340.52224 -40.263227)
			(xy 340.476974 -40.296125) (xy 340.42712 -40.321538) (xy 340.373904 -40.338838) (xy 340.318637 -40.347601)
			(xy 340.290658 -40.348154) (xy 340.264014 -40.347561) (xy 340.211323 -40.339613) (xy 340.160404 -40.323902)
			(xy 340.112395 -40.300777) (xy 340.068369 -40.270756) (xy 340.029309 -40.234508) (xy 339.996086 -40.192845)
			(xy 339.969444 -40.146695) (xy 339.949978 -40.097091) (xy 339.938121 -40.045139) (xy 339.934139 -39.992)
			(xy 339.565995 -39.992) (xy 339.565996 -39.992046) (xy 339.565498 -40.018695) (xy 339.557555 -40.071399)
			(xy 339.541845 -40.122329) (xy 339.518719 -40.17035) (xy 339.488695 -40.214387) (xy 339.452443 -40.253458)
			(xy 339.410772 -40.286689) (xy 339.364614 -40.313338) (xy 339.315 -40.33281) (xy 339.263038 -40.34467)
			(xy 339.209888 -40.348654) (xy 339.156738 -40.34467) (xy 339.104776 -40.33281) (xy 339.055162 -40.313338)
			(xy 339.009004 -40.286689) (xy 338.967333 -40.253458) (xy 338.931081 -40.214387) (xy 338.901057 -40.17035)
			(xy 338.877931 -40.122329) (xy 338.862221 -40.071399) (xy 338.854278 -40.018695) (xy 337.937358 -40.018695)
			(xy 337.929415 -40.071399) (xy 337.913705 -40.122329) (xy 337.890579 -40.17035) (xy 337.860555 -40.214387)
			(xy 337.824303 -40.253458) (xy 337.782632 -40.286689) (xy 337.736474 -40.313338) (xy 337.68686 -40.33281)
			(xy 337.634898 -40.34467) (xy 337.581748 -40.348654) (xy 337.528598 -40.34467) (xy 337.476636 -40.33281)
			(xy 337.427022 -40.313338) (xy 337.380864 -40.286689) (xy 337.339193 -40.253458) (xy 337.302941 -40.214387)
			(xy 337.272917 -40.17035) (xy 337.249791 -40.122329) (xy 337.234081 -40.071399) (xy 337.226138 -40.018695)
			(xy 336.308313 -40.018695) (xy 336.304632 -40.054904) (xy 336.29106 -40.107333) (xy 336.269704 -40.157102)
			(xy 336.241059 -40.203064) (xy 336.205785 -40.244158) (xy 336.164694 -40.279437) (xy 336.118736 -40.308087)
			(xy 336.068969 -40.329447) (xy 336.016541 -40.343026) (xy 335.962662 -40.348509) (xy 335.908574 -40.34577)
			(xy 335.855524 -40.334873) (xy 335.804736 -40.316068) (xy 335.757381 -40.28979) (xy 335.714552 -40.256644)
			(xy 335.677235 -40.217395) (xy 335.646292 -40.172948) (xy 335.622436 -40.124328) (xy 335.606217 -40.072656)
			(xy 335.598009 -40.019125) (xy 335.5975 -39.992046) (xy 335.597792 -39.971539) (xy 335.6025 -39.930797)
			(xy 335.606898 -39.910766) (xy 335.609836 -39.896223) (xy 335.60791 -39.866623) (xy 335.597578 -39.838817)
			(xy 335.579708 -39.815142) (xy 335.555799 -39.797584) (xy 335.527861 -39.787618) (xy 335.498238 -39.78608)
			(xy 335.483708 -39.7891) (xy 335.462886 -39.793849) (xy 335.420481 -39.798943) (xy 335.399126 -39.79926)
			(xy 335.372044 -39.79883) (xy 335.318505 -39.790632) (xy 335.266824 -39.774422) (xy 335.218193 -39.750572)
			(xy 335.173735 -39.719634) (xy 335.134475 -39.68232) (xy 335.101317 -39.639492) (xy 335.075028 -39.592136)
			(xy 335.056212 -39.541346) (xy 335.045304 -39.488292) (xy 335.042556 -39.434198) (xy 330.752537 -39.434198)
			(xy 330.752704 -39.443152) (xy 330.752206 -39.469801) (xy 330.744263 -39.522505) (xy 330.728553 -39.573435)
			(xy 330.705427 -39.621456) (xy 330.675403 -39.665493) (xy 330.639151 -39.704564) (xy 330.59748 -39.737795)
			(xy 330.551322 -39.764444) (xy 330.501708 -39.783916) (xy 330.449746 -39.795776) (xy 330.396596 -39.79976)
			(xy 330.343446 -39.795776) (xy 330.291484 -39.783916) (xy 330.24187 -39.764444) (xy 330.195712 -39.737795)
			(xy 330.154041 -39.704564) (xy 330.117789 -39.665493) (xy 330.087765 -39.621456) (xy 330.064639 -39.573435)
			(xy 330.048929 -39.522505) (xy 330.040986 -39.469801) (xy 326.43878 -39.469801) (xy 326.444564 -39.489025)
			(xy 326.452495 -39.542916) (xy 326.452992 -39.570152) (xy 326.452495 -39.597388) (xy 326.444564 -39.651279)
			(xy 326.428871 -39.703441) (xy 326.40575 -39.752762) (xy 326.375694 -39.798191) (xy 326.339345 -39.83876)
			(xy 326.297475 -39.873604) (xy 326.250979 -39.90198) (xy 326.200846 -39.923284) (xy 326.148146 -39.937062)
			(xy 326.094001 -39.94302) (xy 326.039566 -39.94103) (xy 325.986 -39.931136) (xy 325.934446 -39.913548)
			(xy 325.886003 -39.888642) (xy 325.841701 -39.856947) (xy 325.802487 -39.81914) (xy 325.769196 -39.776026)
			(xy 325.742536 -39.728524) (xy 325.723077 -39.677647) (xy 325.711234 -39.624478) (xy 325.707258 -39.570152)
			(xy 317.3476 -39.570152) (xy 317.3476 -40.018695) (xy 329.085438 -40.018695) (xy 329.085438 -39.965397)
			(xy 329.093381 -39.912693) (xy 329.109091 -39.861763) (xy 329.132217 -39.813742) (xy 329.162241 -39.769705)
			(xy 329.198493 -39.730634) (xy 329.240164 -39.697403) (xy 329.286322 -39.670754) (xy 329.335936 -39.651282)
			(xy 329.387898 -39.639422) (xy 329.441048 -39.635439) (xy 329.494198 -39.639422) (xy 329.54616 -39.651282)
			(xy 329.595774 -39.670754) (xy 329.641932 -39.697403) (xy 329.683603 -39.730634) (xy 329.719855 -39.769705)
			(xy 329.749879 -39.813742) (xy 329.773005 -39.861763) (xy 329.788715 -39.912693) (xy 329.796658 -39.965397)
			(xy 329.797156 -39.992046) (xy 329.796658 -40.018695) (xy 330.712308 -40.018695) (xy 330.712308 -39.965397)
			(xy 330.720251 -39.912693) (xy 330.735961 -39.861763) (xy 330.759087 -39.813742) (xy 330.789111 -39.769705)
			(xy 330.825363 -39.730634) (xy 330.867034 -39.697403) (xy 330.913192 -39.670754) (xy 330.962806 -39.651282)
			(xy 331.014768 -39.639422) (xy 331.067918 -39.635439) (xy 331.121068 -39.639422) (xy 331.17303 -39.651282)
			(xy 331.222644 -39.670754) (xy 331.268802 -39.697403) (xy 331.310473 -39.730634) (xy 331.346725 -39.769705)
			(xy 331.376749 -39.813742) (xy 331.399875 -39.861763) (xy 331.415585 -39.912693) (xy 331.423528 -39.965397)
			(xy 331.424026 -39.992046) (xy 331.423528 -40.018695) (xy 332.341718 -40.018695) (xy 332.341718 -39.965397)
			(xy 332.349661 -39.912693) (xy 332.365371 -39.861763) (xy 332.388497 -39.813742) (xy 332.418521 -39.769705)
			(xy 332.454773 -39.730634) (xy 332.496444 -39.697403) (xy 332.542602 -39.670754) (xy 332.592216 -39.651282)
			(xy 332.644178 -39.639422) (xy 332.697328 -39.635439) (xy 332.750478 -39.639422) (xy 332.80244 -39.651282)
			(xy 332.852054 -39.670754) (xy 332.898212 -39.697403) (xy 332.939883 -39.730634) (xy 332.976135 -39.769705)
			(xy 333.006159 -39.813742) (xy 333.029285 -39.861763) (xy 333.044995 -39.912693) (xy 333.052938 -39.965397)
			(xy 333.053436 -39.992046) (xy 333.052938 -40.018695) (xy 333.969604 -40.018695) (xy 333.969604 -39.965397)
			(xy 333.977547 -39.912693) (xy 333.993257 -39.861763) (xy 334.016383 -39.813742) (xy 334.046407 -39.769705)
			(xy 334.082659 -39.730634) (xy 334.12433 -39.697403) (xy 334.170488 -39.670754) (xy 334.220102 -39.651282)
			(xy 334.272064 -39.639422) (xy 334.325214 -39.635439) (xy 334.378364 -39.639422) (xy 334.430326 -39.651282)
			(xy 334.47994 -39.670754) (xy 334.526098 -39.697403) (xy 334.567769 -39.730634) (xy 334.604021 -39.769705)
			(xy 334.634045 -39.813742) (xy 334.657171 -39.861763) (xy 334.672881 -39.912693) (xy 334.680824 -39.965397)
			(xy 334.681322 -39.992046) (xy 334.680824 -40.018695) (xy 334.672881 -40.071399) (xy 334.657171 -40.122329)
			(xy 334.634045 -40.17035) (xy 334.604021 -40.214387) (xy 334.567769 -40.253458) (xy 334.526098 -40.286689)
			(xy 334.47994 -40.313338) (xy 334.430326 -40.33281) (xy 334.378364 -40.34467) (xy 334.325214 -40.348654)
			(xy 334.272064 -40.34467) (xy 334.220102 -40.33281) (xy 334.170488 -40.313338) (xy 334.12433 -40.286689)
			(xy 334.082659 -40.253458) (xy 334.046407 -40.214387) (xy 334.016383 -40.17035) (xy 333.993257 -40.122329)
			(xy 333.977547 -40.071399) (xy 333.969604 -40.018695) (xy 333.052938 -40.018695) (xy 333.044995 -40.071399)
			(xy 333.029285 -40.122329) (xy 333.006159 -40.17035) (xy 332.976135 -40.214387) (xy 332.939883 -40.253458)
			(xy 332.898212 -40.286689) (xy 332.852054 -40.313338) (xy 332.80244 -40.33281) (xy 332.750478 -40.34467)
			(xy 332.697328 -40.348654) (xy 332.644178 -40.34467) (xy 332.592216 -40.33281) (xy 332.542602 -40.313338)
			(xy 332.496444 -40.286689) (xy 332.454773 -40.253458) (xy 332.418521 -40.214387) (xy 332.388497 -40.17035)
			(xy 332.365371 -40.122329) (xy 332.349661 -40.071399) (xy 332.341718 -40.018695) (xy 331.423528 -40.018695)
			(xy 331.415585 -40.071399) (xy 331.399875 -40.122329) (xy 331.376749 -40.17035) (xy 331.346725 -40.214387)
			(xy 331.310473 -40.253458) (xy 331.268802 -40.286689) (xy 331.222644 -40.313338) (xy 331.17303 -40.33281)
			(xy 331.121068 -40.34467) (xy 331.067918 -40.348654) (xy 331.014768 -40.34467) (xy 330.962806 -40.33281)
			(xy 330.913192 -40.313338) (xy 330.867034 -40.286689) (xy 330.825363 -40.253458) (xy 330.789111 -40.214387)
			(xy 330.759087 -40.17035) (xy 330.735961 -40.122329) (xy 330.720251 -40.071399) (xy 330.712308 -40.018695)
			(xy 329.796658 -40.018695) (xy 329.788715 -40.071399) (xy 329.773005 -40.122329) (xy 329.749879 -40.17035)
			(xy 329.719855 -40.214387) (xy 329.683603 -40.253458) (xy 329.641932 -40.286689) (xy 329.595774 -40.313338)
			(xy 329.54616 -40.33281) (xy 329.494198 -40.34467) (xy 329.441048 -40.348654) (xy 329.387898 -40.34467)
			(xy 329.335936 -40.33281) (xy 329.286322 -40.313338) (xy 329.240164 -40.286689) (xy 329.198493 -40.253458)
			(xy 329.162241 -40.214387) (xy 329.132217 -40.17035) (xy 329.109091 -40.122329) (xy 329.093381 -40.071399)
			(xy 329.085438 -40.018695) (xy 317.3476 -40.018695) (xy 317.3476 -40.198548) (xy 317.8048 -40.655748)
			(xy 322.611496 -40.655748) (xy 322.624925 -40.65534) (xy 322.650855 -40.648339) (xy 322.674063 -40.634819)
			(xy 322.692943 -40.615717) (xy 322.706191 -40.592354) (xy 322.712889 -40.566344) (xy 322.712575 -40.539488)
			(xy 322.709286 -40.526462) (xy 322.702516 -40.500961) (xy 322.695246 -40.448703) (xy 322.694808 -40.422322)
			(xy 322.695294 -40.395071) (xy 322.70305 -40.341123) (xy 322.718405 -40.288828) (xy 322.741047 -40.239251)
			(xy 322.770513 -40.193401) (xy 322.806204 -40.15221) (xy 322.847395 -40.116519) (xy 322.893245 -40.087053)
			(xy 322.942822 -40.064411) (xy 322.995117 -40.049056) (xy 323.049065 -40.0413) (xy 323.103567 -40.0413)
			(xy 323.157515 -40.049056) (xy 323.20981 -40.064411) (xy 323.259387 -40.087053) (xy 323.305237 -40.116519)
			(xy 323.346428 -40.15221) (xy 323.382119 -40.193401) (xy 323.411585 -40.239251) (xy 323.434227 -40.288828)
			(xy 323.449582 -40.341123) (xy 323.457338 -40.395071) (xy 323.457824 -40.422322) (xy 323.457377 -40.448702)
			(xy 323.45011 -40.50096) (xy 323.443346 -40.526462) (xy 323.440073 -40.539498) (xy 323.439737 -40.566364)
			(xy 323.446421 -40.592388) (xy 323.459663 -40.615767) (xy 323.478546 -40.634881) (xy 323.501761 -40.648407)
			(xy 323.527702 -40.655408) (xy 323.541136 -40.655748) (xy 328.177398 -40.655748) (xy 328.192456 -40.655207)
			(xy 328.221265 -40.646432) (xy 328.246266 -40.629643) (xy 328.265291 -40.606297) (xy 328.276687 -40.578421)
			(xy 328.279465 -40.548433) (xy 328.276966 -40.533574) (xy 328.273529 -40.515867) (xy 328.269841 -40.479982)
			(xy 328.2696 -40.461946) (xy 328.270098 -40.435297) (xy 328.278041 -40.382593) (xy 328.293751 -40.331663)
			(xy 328.316877 -40.283642) (xy 328.346901 -40.239605) (xy 328.383153 -40.200534) (xy 328.424824 -40.167303)
			(xy 328.470982 -40.140654) (xy 328.520596 -40.121182) (xy 328.572558 -40.109322) (xy 328.625708 -40.105339)
			(xy 328.678858 -40.109322) (xy 328.73082 -40.121182) (xy 328.780434 -40.140654) (xy 328.826592 -40.167303)
			(xy 328.868263 -40.200534) (xy 328.904515 -40.239605) (xy 328.934539 -40.283642) (xy 328.957665 -40.331663)
			(xy 328.973375 -40.382593) (xy 328.981318 -40.435297) (xy 328.981816 -40.461946) (xy 328.981564 -40.479982)
			(xy 328.980679 -40.488595) (xy 329.899508 -40.488595) (xy 329.899508 -40.435297) (xy 329.907451 -40.382593)
			(xy 329.923161 -40.331663) (xy 329.946287 -40.283642) (xy 329.976311 -40.239605) (xy 330.012563 -40.200534)
			(xy 330.054234 -40.167303) (xy 330.100392 -40.140654) (xy 330.150006 -40.121182) (xy 330.201968 -40.109322)
			(xy 330.255118 -40.105339) (xy 330.308268 -40.109322) (xy 330.36023 -40.121182) (xy 330.409844 -40.140654)
			(xy 330.456002 -40.167303) (xy 330.497673 -40.200534) (xy 330.533925 -40.239605) (xy 330.563949 -40.283642)
			(xy 330.587075 -40.331663) (xy 330.602785 -40.382593) (xy 330.610728 -40.435297) (xy 330.611226 -40.461946)
			(xy 330.610728 -40.488595) (xy 331.527394 -40.488595) (xy 331.527394 -40.435297) (xy 331.535337 -40.382593)
			(xy 331.551047 -40.331663) (xy 331.574173 -40.283642) (xy 331.604197 -40.239605) (xy 331.640449 -40.200534)
			(xy 331.68212 -40.167303) (xy 331.728278 -40.140654) (xy 331.777892 -40.121182) (xy 331.829854 -40.109322)
			(xy 331.883004 -40.105339) (xy 331.936154 -40.109322) (xy 331.988116 -40.121182) (xy 332.03773 -40.140654)
			(xy 332.083888 -40.167303) (xy 332.125559 -40.200534) (xy 332.161811 -40.239605) (xy 332.191835 -40.283642)
			(xy 332.214961 -40.331663) (xy 332.230671 -40.382593) (xy 332.238614 -40.435297) (xy 332.239112 -40.461946)
			(xy 332.238614 -40.488595) (xy 333.155788 -40.488595) (xy 333.155788 -40.435297) (xy 333.163731 -40.382593)
			(xy 333.179441 -40.331663) (xy 333.202567 -40.283642) (xy 333.232591 -40.239605) (xy 333.268843 -40.200534)
			(xy 333.310514 -40.167303) (xy 333.356672 -40.140654) (xy 333.406286 -40.121182) (xy 333.458248 -40.109322)
			(xy 333.511398 -40.105339) (xy 333.564548 -40.109322) (xy 333.61651 -40.121182) (xy 333.666124 -40.140654)
			(xy 333.712282 -40.167303) (xy 333.753953 -40.200534) (xy 333.790205 -40.239605) (xy 333.820229 -40.283642)
			(xy 333.843355 -40.331663) (xy 333.859065 -40.382593) (xy 333.867008 -40.435297) (xy 333.867506 -40.461946)
			(xy 333.867008 -40.488595) (xy 334.782658 -40.488595) (xy 334.782658 -40.435297) (xy 334.790601 -40.382593)
			(xy 334.806311 -40.331663) (xy 334.829437 -40.283642) (xy 334.859461 -40.239605) (xy 334.895713 -40.200534)
			(xy 334.937384 -40.167303) (xy 334.983542 -40.140654) (xy 335.033156 -40.121182) (xy 335.085118 -40.109322)
			(xy 335.138268 -40.105339) (xy 335.191418 -40.109322) (xy 335.24338 -40.121182) (xy 335.292994 -40.140654)
			(xy 335.339152 -40.167303) (xy 335.380823 -40.200534) (xy 335.417075 -40.239605) (xy 335.447099 -40.283642)
			(xy 335.470225 -40.331663) (xy 335.485935 -40.382593) (xy 335.493878 -40.435297) (xy 335.494376 -40.461946)
			(xy 335.493878 -40.488595) (xy 335.485935 -40.541299) (xy 335.470225 -40.592229) (xy 335.447099 -40.64025)
			(xy 335.417075 -40.684287) (xy 335.380823 -40.723358) (xy 335.339152 -40.756589) (xy 335.292994 -40.783238)
			(xy 335.24338 -40.80271) (xy 335.191418 -40.81457) (xy 335.138268 -40.818554) (xy 335.085118 -40.81457)
			(xy 335.033156 -40.80271) (xy 334.983542 -40.783238) (xy 334.937384 -40.756589) (xy 334.895713 -40.723358)
			(xy 334.859461 -40.684287) (xy 334.829437 -40.64025) (xy 334.806311 -40.592229) (xy 334.790601 -40.541299)
			(xy 334.782658 -40.488595) (xy 333.867008 -40.488595) (xy 333.859065 -40.541299) (xy 333.843355 -40.592229)
			(xy 333.820229 -40.64025) (xy 333.790205 -40.684287) (xy 333.753953 -40.723358) (xy 333.712282 -40.756589)
			(xy 333.666124 -40.783238) (xy 333.61651 -40.80271) (xy 333.564548 -40.81457) (xy 333.511398 -40.818554)
			(xy 333.458248 -40.81457) (xy 333.406286 -40.80271) (xy 333.356672 -40.783238) (xy 333.310514 -40.756589)
			(xy 333.268843 -40.723358) (xy 333.232591 -40.684287) (xy 333.202567 -40.64025) (xy 333.179441 -40.592229)
			(xy 333.163731 -40.541299) (xy 333.155788 -40.488595) (xy 332.238614 -40.488595) (xy 332.230671 -40.541299)
			(xy 332.214961 -40.592229) (xy 332.191835 -40.64025) (xy 332.161811 -40.684287) (xy 332.125559 -40.723358)
			(xy 332.083888 -40.756589) (xy 332.03773 -40.783238) (xy 331.988116 -40.80271) (xy 331.936154 -40.81457)
			(xy 331.883004 -40.818554) (xy 331.829854 -40.81457) (xy 331.777892 -40.80271) (xy 331.728278 -40.783238)
			(xy 331.68212 -40.756589) (xy 331.640449 -40.723358) (xy 331.604197 -40.684287) (xy 331.574173 -40.64025)
			(xy 331.551047 -40.592229) (xy 331.535337 -40.541299) (xy 331.527394 -40.488595) (xy 330.610728 -40.488595)
			(xy 330.602785 -40.541299) (xy 330.587075 -40.592229) (xy 330.563949 -40.64025) (xy 330.533925 -40.684287)
			(xy 330.497673 -40.723358) (xy 330.456002 -40.756589) (xy 330.409844 -40.783238) (xy 330.36023 -40.80271)
			(xy 330.308268 -40.81457) (xy 330.255118 -40.818554) (xy 330.201968 -40.81457) (xy 330.150006 -40.80271)
			(xy 330.100392 -40.783238) (xy 330.054234 -40.756589) (xy 330.012563 -40.723358) (xy 329.976311 -40.684287)
			(xy 329.946287 -40.64025) (xy 329.923161 -40.592229) (xy 329.907451 -40.541299) (xy 329.899508 -40.488595)
			(xy 328.980679 -40.488595) (xy 328.977878 -40.515865) (xy 328.97445 -40.533574) (xy 328.971923 -40.548436)
			(xy 328.974678 -40.578441) (xy 328.986068 -40.606336) (xy 329.005102 -40.629694) (xy 329.030122 -40.646482)
			(xy 329.058952 -40.65524) (xy 329.074018 -40.655748) (xy 329.214988 -40.655748) (xy 329.236274 -40.639052)
			(xy 329.2829 -40.611619) (xy 329.33314 -40.59156) (xy 329.385837 -40.579337) (xy 329.439778 -40.575231)
			(xy 329.493719 -40.579337) (xy 329.546416 -40.59156) (xy 329.596656 -40.611619) (xy 329.643282 -40.639052)
			(xy 329.664568 -40.655748) (xy 329.7936 -40.655748) (xy 330.096347 -40.958495) (xy 330.712308 -40.958495)
			(xy 330.712308 -40.905197) (xy 330.720251 -40.852493) (xy 330.735961 -40.801563) (xy 330.759087 -40.753542)
			(xy 330.789111 -40.709505) (xy 330.825363 -40.670434) (xy 330.867034 -40.637203) (xy 330.913192 -40.610554)
			(xy 330.962806 -40.591082) (xy 331.014768 -40.579222) (xy 331.067918 -40.575239) (xy 331.121068 -40.579222)
			(xy 331.17303 -40.591082) (xy 331.222644 -40.610554) (xy 331.268802 -40.637203) (xy 331.310473 -40.670434)
			(xy 331.346725 -40.709505) (xy 331.376749 -40.753542) (xy 331.399875 -40.801563) (xy 331.415585 -40.852493)
			(xy 331.423528 -40.905197) (xy 331.424026 -40.931846) (xy 331.423528 -40.958495) (xy 332.341718 -40.958495)
			(xy 332.341718 -40.905197) (xy 332.349661 -40.852493) (xy 332.365371 -40.801563) (xy 332.388497 -40.753542)
			(xy 332.418521 -40.709505) (xy 332.454773 -40.670434) (xy 332.496444 -40.637203) (xy 332.542602 -40.610554)
			(xy 332.592216 -40.591082) (xy 332.644178 -40.579222) (xy 332.697328 -40.575239) (xy 332.750478 -40.579222)
			(xy 332.80244 -40.591082) (xy 332.852054 -40.610554) (xy 332.898212 -40.637203) (xy 332.939883 -40.670434)
			(xy 332.976135 -40.709505) (xy 333.006159 -40.753542) (xy 333.029285 -40.801563) (xy 333.044995 -40.852493)
			(xy 333.052938 -40.905197) (xy 333.053436 -40.931846) (xy 333.052938 -40.958495) (xy 333.969858 -40.958495)
			(xy 333.969858 -40.905197) (xy 333.977801 -40.852493) (xy 333.993511 -40.801563) (xy 334.016637 -40.753542)
			(xy 334.046661 -40.709505) (xy 334.082913 -40.670434) (xy 334.124584 -40.637203) (xy 334.170742 -40.610554)
			(xy 334.220356 -40.591082) (xy 334.272318 -40.579222) (xy 334.325468 -40.575239) (xy 334.378618 -40.579222)
			(xy 334.43058 -40.591082) (xy 334.480194 -40.610554) (xy 334.526352 -40.637203) (xy 334.568023 -40.670434)
			(xy 334.604275 -40.709505) (xy 334.634299 -40.753542) (xy 334.657425 -40.801563) (xy 334.673135 -40.852493)
			(xy 334.681078 -40.905197) (xy 334.681576 -40.931846) (xy 334.681078 -40.958495) (xy 335.597998 -40.958495)
			(xy 335.597998 -40.905197) (xy 335.605941 -40.852493) (xy 335.621651 -40.801563) (xy 335.644777 -40.753542)
			(xy 335.674801 -40.709505) (xy 335.711053 -40.670434) (xy 335.752724 -40.637203) (xy 335.798882 -40.610554)
			(xy 335.848496 -40.591082) (xy 335.900458 -40.579222) (xy 335.953608 -40.575239) (xy 336.006758 -40.579222)
			(xy 336.05872 -40.591082) (xy 336.108334 -40.610554) (xy 336.154492 -40.637203) (xy 336.196163 -40.670434)
			(xy 336.232415 -40.709505) (xy 336.262439 -40.753542) (xy 336.285565 -40.801563) (xy 336.301275 -40.852493)
			(xy 336.309218 -40.905197) (xy 336.309716 -40.931846) (xy 336.309218 -40.958495) (xy 336.308759 -40.961543)
			(xy 336.681562 -40.961543) (xy 336.681562 -40.908245) (xy 336.689505 -40.855541) (xy 336.705215 -40.804611)
			(xy 336.728341 -40.75659) (xy 336.758365 -40.712553) (xy 336.794617 -40.673482) (xy 336.836288 -40.640251)
			(xy 336.882446 -40.613602) (xy 336.93206 -40.59413) (xy 336.984022 -40.58227) (xy 337.037172 -40.578287)
			(xy 337.090322 -40.58227) (xy 337.142284 -40.59413) (xy 337.191898 -40.613602) (xy 337.238056 -40.640251)
			(xy 337.279727 -40.673482) (xy 337.315979 -40.712553) (xy 337.346003 -40.75659) (xy 337.369129 -40.804611)
			(xy 337.384839 -40.855541) (xy 337.392782 -40.908245) (xy 337.39328 -40.934894) (xy 337.392839 -40.958495)
			(xy 338.854278 -40.958495) (xy 338.854278 -40.905197) (xy 338.862221 -40.852493) (xy 338.877931 -40.801563)
			(xy 338.901057 -40.753542) (xy 338.931081 -40.709505) (xy 338.967333 -40.670434) (xy 339.009004 -40.637203)
			(xy 339.055162 -40.610554) (xy 339.104776 -40.591082) (xy 339.156738 -40.579222) (xy 339.209888 -40.575239)
			(xy 339.263038 -40.579222) (xy 339.315 -40.591082) (xy 339.364614 -40.610554) (xy 339.410772 -40.637203)
			(xy 339.452443 -40.670434) (xy 339.488695 -40.709505) (xy 339.518719 -40.753542) (xy 339.541845 -40.801563)
			(xy 339.557555 -40.852493) (xy 339.565498 -40.905197) (xy 339.565996 -40.931846) (xy 339.565498 -40.958495)
			(xy 339.935048 -40.958495) (xy 339.935048 -40.905197) (xy 339.942991 -40.852493) (xy 339.958701 -40.801563)
			(xy 339.981827 -40.753542) (xy 340.011851 -40.709505) (xy 340.048103 -40.670434) (xy 340.089774 -40.637203)
			(xy 340.135932 -40.610554) (xy 340.185546 -40.591082) (xy 340.237508 -40.579222) (xy 340.290658 -40.575239)
			(xy 340.343808 -40.579222) (xy 340.39577 -40.591082) (xy 340.445384 -40.610554) (xy 340.491542 -40.637203)
			(xy 340.533213 -40.670434) (xy 340.569465 -40.709505) (xy 340.599489 -40.753542) (xy 340.622615 -40.801563)
			(xy 340.638325 -40.852493) (xy 340.646268 -40.905197) (xy 340.646766 -40.931846) (xy 340.646268 -40.958495)
			(xy 341.56395 -40.958495) (xy 341.56395 -40.905197) (xy 341.571893 -40.852493) (xy 341.587603 -40.801563)
			(xy 341.610729 -40.753542) (xy 341.640753 -40.709505) (xy 341.677005 -40.670434) (xy 341.718676 -40.637203)
			(xy 341.764834 -40.610554) (xy 341.814448 -40.591082) (xy 341.86641 -40.579222) (xy 341.91956 -40.575239)
			(xy 341.97271 -40.579222) (xy 342.024672 -40.591082) (xy 342.074286 -40.610554) (xy 342.120444 -40.637203)
			(xy 342.162115 -40.670434) (xy 342.198367 -40.709505) (xy 342.228391 -40.753542) (xy 342.251517 -40.801563)
			(xy 342.267227 -40.852493) (xy 342.27517 -40.905197) (xy 342.275668 -40.931846) (xy 342.27517 -40.958495)
			(xy 342.267227 -41.011199) (xy 342.251517 -41.062129) (xy 342.228391 -41.11015) (xy 342.198367 -41.154187)
			(xy 342.162115 -41.193258) (xy 342.120444 -41.226489) (xy 342.074286 -41.253138) (xy 342.024672 -41.27261)
			(xy 341.97271 -41.28447) (xy 341.91956 -41.288454) (xy 341.86641 -41.28447) (xy 341.814448 -41.27261)
			(xy 341.764834 -41.253138) (xy 341.718676 -41.226489) (xy 341.677005 -41.193258) (xy 341.640753 -41.154187)
			(xy 341.610729 -41.11015) (xy 341.587603 -41.062129) (xy 341.571893 -41.011199) (xy 341.56395 -40.958495)
			(xy 340.646268 -40.958495) (xy 340.638325 -41.011199) (xy 340.622615 -41.062129) (xy 340.599489 -41.11015)
			(xy 340.569465 -41.154187) (xy 340.533213 -41.193258) (xy 340.491542 -41.226489) (xy 340.445384 -41.253138)
			(xy 340.39577 -41.27261) (xy 340.343808 -41.28447) (xy 340.290658 -41.288454) (xy 340.237508 -41.28447)
			(xy 340.185546 -41.27261) (xy 340.135932 -41.253138) (xy 340.089774 -41.226489) (xy 340.048103 -41.193258)
			(xy 340.011851 -41.154187) (xy 339.981827 -41.11015) (xy 339.958701 -41.062129) (xy 339.942991 -41.011199)
			(xy 339.935048 -40.958495) (xy 339.565498 -40.958495) (xy 339.557555 -41.011199) (xy 339.541845 -41.062129)
			(xy 339.518719 -41.11015) (xy 339.488695 -41.154187) (xy 339.452443 -41.193258) (xy 339.410772 -41.226489)
			(xy 339.364614 -41.253138) (xy 339.315 -41.27261) (xy 339.263038 -41.28447) (xy 339.209888 -41.288454)
			(xy 339.156738 -41.28447) (xy 339.104776 -41.27261) (xy 339.055162 -41.253138) (xy 339.009004 -41.226489)
			(xy 338.967333 -41.193258) (xy 338.931081 -41.154187) (xy 338.901057 -41.11015) (xy 338.877931 -41.062129)
			(xy 338.862221 -41.011199) (xy 338.854278 -40.958495) (xy 337.392839 -40.958495) (xy 337.392782 -40.961543)
			(xy 337.384839 -41.014247) (xy 337.369129 -41.065177) (xy 337.346003 -41.113198) (xy 337.315979 -41.157235)
			(xy 337.279727 -41.196306) (xy 337.238056 -41.229537) (xy 337.191898 -41.256186) (xy 337.142284 -41.275658)
			(xy 337.090322 -41.287518) (xy 337.037172 -41.291502) (xy 336.984022 -41.287518) (xy 336.93206 -41.275658)
			(xy 336.882446 -41.256186) (xy 336.836288 -41.229537) (xy 336.794617 -41.196306) (xy 336.758365 -41.157235)
			(xy 336.728341 -41.113198) (xy 336.705215 -41.065177) (xy 336.689505 -41.014247) (xy 336.681562 -40.961543)
			(xy 336.308759 -40.961543) (xy 336.301275 -41.011199) (xy 336.285565 -41.062129) (xy 336.262439 -41.11015)
			(xy 336.232415 -41.154187) (xy 336.196163 -41.193258) (xy 336.154492 -41.226489) (xy 336.108334 -41.253138)
			(xy 336.05872 -41.27261) (xy 336.006758 -41.28447) (xy 335.953608 -41.288454) (xy 335.900458 -41.28447)
			(xy 335.848496 -41.27261) (xy 335.798882 -41.253138) (xy 335.752724 -41.226489) (xy 335.711053 -41.193258)
			(xy 335.674801 -41.154187) (xy 335.644777 -41.11015) (xy 335.621651 -41.062129) (xy 335.605941 -41.011199)
			(xy 335.597998 -40.958495) (xy 334.681078 -40.958495) (xy 334.673135 -41.011199) (xy 334.657425 -41.062129)
			(xy 334.634299 -41.11015) (xy 334.604275 -41.154187) (xy 334.568023 -41.193258) (xy 334.526352 -41.226489)
			(xy 334.480194 -41.253138) (xy 334.43058 -41.27261) (xy 334.378618 -41.28447) (xy 334.325468 -41.288454)
			(xy 334.272318 -41.28447) (xy 334.220356 -41.27261) (xy 334.170742 -41.253138) (xy 334.124584 -41.226489)
			(xy 334.082913 -41.193258) (xy 334.046661 -41.154187) (xy 334.016637 -41.11015) (xy 333.993511 -41.062129)
			(xy 333.977801 -41.011199) (xy 333.969858 -40.958495) (xy 333.052938 -40.958495) (xy 333.044995 -41.011199)
			(xy 333.029285 -41.062129) (xy 333.006159 -41.11015) (xy 332.976135 -41.154187) (xy 332.939883 -41.193258)
			(xy 332.898212 -41.226489) (xy 332.852054 -41.253138) (xy 332.80244 -41.27261) (xy 332.750478 -41.28447)
			(xy 332.697328 -41.288454) (xy 332.644178 -41.28447) (xy 332.592216 -41.27261) (xy 332.542602 -41.253138)
			(xy 332.496444 -41.226489) (xy 332.454773 -41.193258) (xy 332.418521 -41.154187) (xy 332.388497 -41.11015)
			(xy 332.365371 -41.062129) (xy 332.349661 -41.011199) (xy 332.341718 -40.958495) (xy 331.423528 -40.958495)
			(xy 331.415585 -41.011199) (xy 331.399875 -41.062129) (xy 331.376749 -41.11015) (xy 331.346725 -41.154187)
			(xy 331.310473 -41.193258) (xy 331.268802 -41.226489) (xy 331.222644 -41.253138) (xy 331.17303 -41.27261)
			(xy 331.121068 -41.28447) (xy 331.067918 -41.288454) (xy 331.014768 -41.28447) (xy 330.962806 -41.27261)
			(xy 330.913192 -41.253138) (xy 330.867034 -41.226489) (xy 330.825363 -41.193258) (xy 330.789111 -41.154187)
			(xy 330.759087 -41.11015) (xy 330.735961 -41.062129) (xy 330.720251 -41.011199) (xy 330.712308 -40.958495)
			(xy 330.096347 -40.958495) (xy 330.18857 -41.050718) (xy 330.213208 -41.047924) (xy 330.223396 -41.046833)
			(xy 330.243856 -41.04569) (xy 330.254102 -41.045638) (xy 330.282086 -41.046159) (xy 330.337365 -41.054915)
			(xy 330.390593 -41.072212) (xy 330.440459 -41.097623) (xy 330.485736 -41.130522) (xy 330.525309 -41.1701)
			(xy 330.558202 -41.215382) (xy 330.583607 -41.265252) (xy 330.600896 -41.318482) (xy 330.609645 -41.373762)
			(xy 330.61021 -41.401746) (xy 330.61015 -41.411992) (xy 330.609235 -41.428395) (xy 331.527394 -41.428395)
			(xy 331.527394 -41.375097) (xy 331.535337 -41.322393) (xy 331.551047 -41.271463) (xy 331.574173 -41.223442)
			(xy 331.604197 -41.179405) (xy 331.640449 -41.140334) (xy 331.68212 -41.107103) (xy 331.728278 -41.080454)
			(xy 331.777892 -41.060982) (xy 331.829854 -41.049122) (xy 331.883004 -41.045139) (xy 331.936154 -41.049122)
			(xy 331.988116 -41.060982) (xy 332.03773 -41.080454) (xy 332.083888 -41.107103) (xy 332.125559 -41.140334)
			(xy 332.161811 -41.179405) (xy 332.191835 -41.223442) (xy 332.214961 -41.271463) (xy 332.230671 -41.322393)
			(xy 332.238614 -41.375097) (xy 332.239112 -41.401746) (xy 332.238614 -41.428395) (xy 333.155788 -41.428395)
			(xy 333.155788 -41.375097) (xy 333.163731 -41.322393) (xy 333.179441 -41.271463) (xy 333.202567 -41.223442)
			(xy 333.232591 -41.179405) (xy 333.268843 -41.140334) (xy 333.310514 -41.107103) (xy 333.356672 -41.080454)
			(xy 333.406286 -41.060982) (xy 333.458248 -41.049122) (xy 333.511398 -41.045139) (xy 333.564548 -41.049122)
			(xy 333.61651 -41.060982) (xy 333.666124 -41.080454) (xy 333.712282 -41.107103) (xy 333.753953 -41.140334)
			(xy 333.790205 -41.179405) (xy 333.820229 -41.223442) (xy 333.843355 -41.271463) (xy 333.859065 -41.322393)
			(xy 333.867008 -41.375097) (xy 333.867506 -41.401746) (xy 333.867008 -41.428395) (xy 334.785198 -41.428395)
			(xy 334.785198 -41.375097) (xy 334.793141 -41.322393) (xy 334.808851 -41.271463) (xy 334.831977 -41.223442)
			(xy 334.862001 -41.179405) (xy 334.898253 -41.140334) (xy 334.939924 -41.107103) (xy 334.986082 -41.080454)
			(xy 335.035696 -41.060982) (xy 335.087658 -41.049122) (xy 335.140808 -41.045139) (xy 335.193958 -41.049122)
			(xy 335.24592 -41.060982) (xy 335.295534 -41.080454) (xy 335.341692 -41.107103) (xy 335.383363 -41.140334)
			(xy 335.419615 -41.179405) (xy 335.449639 -41.223442) (xy 335.472765 -41.271463) (xy 335.488475 -41.322393)
			(xy 335.496418 -41.375097) (xy 335.496916 -41.401746) (xy 335.496418 -41.428395) (xy 338.040462 -41.428395)
			(xy 338.040462 -41.375097) (xy 338.048405 -41.322393) (xy 338.064115 -41.271463) (xy 338.087241 -41.223442)
			(xy 338.117265 -41.179405) (xy 338.153517 -41.140334) (xy 338.195188 -41.107103) (xy 338.241346 -41.080454)
			(xy 338.29096 -41.060982) (xy 338.342922 -41.049122) (xy 338.396072 -41.045139) (xy 338.449222 -41.049122)
			(xy 338.501184 -41.060982) (xy 338.550798 -41.080454) (xy 338.596956 -41.107103) (xy 338.638627 -41.140334)
			(xy 338.674879 -41.179405) (xy 338.704903 -41.223442) (xy 338.728029 -41.271463) (xy 338.743739 -41.322393)
			(xy 338.751682 -41.375097) (xy 338.75218 -41.401746) (xy 338.751682 -41.428395) (xy 340.750388 -41.428395)
			(xy 340.750388 -41.375097) (xy 340.758331 -41.322393) (xy 340.774041 -41.271463) (xy 340.797167 -41.223442)
			(xy 340.827191 -41.179405) (xy 340.863443 -41.140334) (xy 340.905114 -41.107103) (xy 340.951272 -41.080454)
			(xy 341.000886 -41.060982) (xy 341.052848 -41.049122) (xy 341.105998 -41.045139) (xy 341.159148 -41.049122)
			(xy 341.21111 -41.060982) (xy 341.260724 -41.080454) (xy 341.306882 -41.107103) (xy 341.348553 -41.140334)
			(xy 341.384805 -41.179405) (xy 341.414829 -41.223442) (xy 341.437955 -41.271463) (xy 341.453665 -41.322393)
			(xy 341.461608 -41.375097) (xy 341.462106 -41.401746) (xy 341.461608 -41.428395) (xy 342.377766 -41.428395)
			(xy 342.377766 -41.375097) (xy 342.385709 -41.322393) (xy 342.401419 -41.271463) (xy 342.424545 -41.223442)
			(xy 342.454569 -41.179405) (xy 342.490821 -41.140334) (xy 342.532492 -41.107103) (xy 342.57865 -41.080454)
			(xy 342.628264 -41.060982) (xy 342.680226 -41.049122) (xy 342.733376 -41.045139) (xy 342.786526 -41.049122)
			(xy 342.838488 -41.060982) (xy 342.888102 -41.080454) (xy 342.93426 -41.107103) (xy 342.975931 -41.140334)
			(xy 343.012183 -41.179405) (xy 343.042207 -41.223442) (xy 343.065333 -41.271463) (xy 343.081043 -41.322393)
			(xy 343.088986 -41.375097) (xy 343.089484 -41.401746) (xy 343.088986 -41.428395) (xy 343.081043 -41.481099)
			(xy 343.065333 -41.532029) (xy 343.042207 -41.58005) (xy 343.012183 -41.624087) (xy 342.975931 -41.663158)
			(xy 342.93426 -41.696389) (xy 342.888102 -41.723038) (xy 342.838488 -41.74251) (xy 342.786526 -41.75437)
			(xy 342.733376 -41.758354) (xy 342.680226 -41.75437) (xy 342.628264 -41.74251) (xy 342.57865 -41.723038)
			(xy 342.532492 -41.696389) (xy 342.490821 -41.663158) (xy 342.454569 -41.624087) (xy 342.424545 -41.58005)
			(xy 342.401419 -41.532029) (xy 342.385709 -41.481099) (xy 342.377766 -41.428395) (xy 341.461608 -41.428395)
			(xy 341.453665 -41.481099) (xy 341.437955 -41.532029) (xy 341.414829 -41.58005) (xy 341.384805 -41.624087)
			(xy 341.348553 -41.663158) (xy 341.306882 -41.696389) (xy 341.260724 -41.723038) (xy 341.21111 -41.74251)
			(xy 341.159148 -41.75437) (xy 341.105998 -41.758354) (xy 341.052848 -41.75437) (xy 341.000886 -41.74251)
			(xy 340.951272 -41.723038) (xy 340.905114 -41.696389) (xy 340.863443 -41.663158) (xy 340.827191 -41.624087)
			(xy 340.797167 -41.58005) (xy 340.774041 -41.532029) (xy 340.758331 -41.481099) (xy 340.750388 -41.428395)
			(xy 338.751682 -41.428395) (xy 338.743739 -41.481099) (xy 338.728029 -41.532029) (xy 338.704903 -41.58005)
			(xy 338.674879 -41.624087) (xy 338.638627 -41.663158) (xy 338.596956 -41.696389) (xy 338.550798 -41.723038)
			(xy 338.501184 -41.74251) (xy 338.449222 -41.75437) (xy 338.396072 -41.758354) (xy 338.342922 -41.75437)
			(xy 338.29096 -41.74251) (xy 338.241346 -41.723038) (xy 338.195188 -41.696389) (xy 338.153517 -41.663158)
			(xy 338.117265 -41.624087) (xy 338.087241 -41.58005) (xy 338.064115 -41.532029) (xy 338.048405 -41.481099)
			(xy 338.040462 -41.428395) (xy 335.496418 -41.428395) (xy 335.488475 -41.481099) (xy 335.472765 -41.532029)
			(xy 335.449639 -41.58005) (xy 335.419615 -41.624087) (xy 335.383363 -41.663158) (xy 335.341692 -41.696389)
			(xy 335.295534 -41.723038) (xy 335.24592 -41.74251) (xy 335.193958 -41.75437) (xy 335.140808 -41.758354)
			(xy 335.087658 -41.75437) (xy 335.035696 -41.74251) (xy 334.986082 -41.723038) (xy 334.939924 -41.696389)
			(xy 334.898253 -41.663158) (xy 334.862001 -41.624087) (xy 334.831977 -41.58005) (xy 334.808851 -41.532029)
			(xy 334.793141 -41.481099) (xy 334.785198 -41.428395) (xy 333.867008 -41.428395) (xy 333.859065 -41.481099)
			(xy 333.843355 -41.532029) (xy 333.820229 -41.58005) (xy 333.790205 -41.624087) (xy 333.753953 -41.663158)
			(xy 333.712282 -41.696389) (xy 333.666124 -41.723038) (xy 333.61651 -41.74251) (xy 333.564548 -41.75437)
			(xy 333.511398 -41.758354) (xy 333.458248 -41.75437) (xy 333.406286 -41.74251) (xy 333.356672 -41.723038)
			(xy 333.310514 -41.696389) (xy 333.268843 -41.663158) (xy 333.232591 -41.624087) (xy 333.202567 -41.58005)
			(xy 333.179441 -41.532029) (xy 333.163731 -41.481099) (xy 333.155788 -41.428395) (xy 332.238614 -41.428395)
			(xy 332.230671 -41.481099) (xy 332.214961 -41.532029) (xy 332.191835 -41.58005) (xy 332.161811 -41.624087)
			(xy 332.125559 -41.663158) (xy 332.083888 -41.696389) (xy 332.03773 -41.723038) (xy 331.988116 -41.74251)
			(xy 331.936154 -41.75437) (xy 331.883004 -41.758354) (xy 331.829854 -41.75437) (xy 331.777892 -41.74251)
			(xy 331.728278 -41.723038) (xy 331.68212 -41.696389) (xy 331.640449 -41.663158) (xy 331.604197 -41.624087)
			(xy 331.574173 -41.58005) (xy 331.551047 -41.532029) (xy 331.535337 -41.481099) (xy 331.527394 -41.428395)
			(xy 330.609235 -41.428395) (xy 330.609009 -41.432452) (xy 330.607924 -41.44264) (xy 330.60513 -41.467278)
			(xy 330.786232 -41.64838) (xy 330.822046 -41.61409) (xy 330.842042 -41.595711) (xy 330.886563 -41.56461)
			(xy 330.935288 -41.540624) (xy 330.987088 -41.524309) (xy 331.040764 -41.516041) (xy 331.067918 -41.515538)
			(xy 331.095901 -41.51606) (xy 331.151178 -41.524818) (xy 331.204404 -41.542116) (xy 331.254268 -41.567528)
			(xy 331.299543 -41.600428) (xy 331.339114 -41.640006) (xy 331.372005 -41.685287) (xy 331.397408 -41.735155)
			(xy 331.414697 -41.788385) (xy 331.423445 -41.843663) (xy 331.424026 -41.871646) (xy 331.423526 -41.898295)
			(xy 332.341718 -41.898295) (xy 332.341718 -41.844997) (xy 332.349661 -41.792293) (xy 332.365371 -41.741363)
			(xy 332.388497 -41.693342) (xy 332.418521 -41.649305) (xy 332.454773 -41.610234) (xy 332.496444 -41.577003)
			(xy 332.542602 -41.550354) (xy 332.592216 -41.530882) (xy 332.644178 -41.519022) (xy 332.697328 -41.515039)
			(xy 332.750478 -41.519022) (xy 332.80244 -41.530882) (xy 332.852054 -41.550354) (xy 332.898212 -41.577003)
			(xy 332.939883 -41.610234) (xy 332.976135 -41.649305) (xy 333.006159 -41.693342) (xy 333.029285 -41.741363)
			(xy 333.044995 -41.792293) (xy 333.052938 -41.844997) (xy 333.053436 -41.871646) (xy 333.052938 -41.898295)
			(xy 333.969858 -41.898295) (xy 333.969858 -41.844997) (xy 333.977801 -41.792293) (xy 333.993511 -41.741363)
			(xy 334.016637 -41.693342) (xy 334.046661 -41.649305) (xy 334.082913 -41.610234) (xy 334.124584 -41.577003)
			(xy 334.170742 -41.550354) (xy 334.220356 -41.530882) (xy 334.272318 -41.519022) (xy 334.325468 -41.515039)
			(xy 334.378618 -41.519022) (xy 334.43058 -41.530882) (xy 334.480194 -41.550354) (xy 334.526352 -41.577003)
			(xy 334.568023 -41.610234) (xy 334.604275 -41.649305) (xy 334.634299 -41.693342) (xy 334.657425 -41.741363)
			(xy 334.673135 -41.792293) (xy 334.681078 -41.844997) (xy 334.681576 -41.871646) (xy 334.681078 -41.898295)
			(xy 335.597998 -41.898295) (xy 335.597998 -41.844997) (xy 335.605941 -41.792293) (xy 335.621651 -41.741363)
			(xy 335.644777 -41.693342) (xy 335.674801 -41.649305) (xy 335.711053 -41.610234) (xy 335.752724 -41.577003)
			(xy 335.798882 -41.550354) (xy 335.848496 -41.530882) (xy 335.900458 -41.519022) (xy 335.953608 -41.515039)
			(xy 336.006758 -41.519022) (xy 336.05872 -41.530882) (xy 336.108334 -41.550354) (xy 336.154492 -41.577003)
			(xy 336.196163 -41.610234) (xy 336.232415 -41.649305) (xy 336.262439 -41.693342) (xy 336.285565 -41.741363)
			(xy 336.301275 -41.792293) (xy 336.309218 -41.844997) (xy 336.309716 -41.871646) (xy 336.309218 -41.898295)
			(xy 337.226138 -41.898295) (xy 337.226138 -41.844997) (xy 337.234081 -41.792293) (xy 337.249791 -41.741363)
			(xy 337.272917 -41.693342) (xy 337.302941 -41.649305) (xy 337.339193 -41.610234) (xy 337.380864 -41.577003)
			(xy 337.427022 -41.550354) (xy 337.476636 -41.530882) (xy 337.528598 -41.519022) (xy 337.581748 -41.515039)
			(xy 337.634898 -41.519022) (xy 337.68686 -41.530882) (xy 337.736474 -41.550354) (xy 337.782632 -41.577003)
			(xy 337.824303 -41.610234) (xy 337.860555 -41.649305) (xy 337.890579 -41.693342) (xy 337.913705 -41.741363)
			(xy 337.929415 -41.792293) (xy 337.937358 -41.844997) (xy 337.937856 -41.871646) (xy 337.937358 -41.898295)
			(xy 338.854278 -41.898295) (xy 338.854278 -41.844997) (xy 338.862221 -41.792293) (xy 338.877931 -41.741363)
			(xy 338.901057 -41.693342) (xy 338.931081 -41.649305) (xy 338.967333 -41.610234) (xy 339.009004 -41.577003)
			(xy 339.055162 -41.550354) (xy 339.104776 -41.530882) (xy 339.156738 -41.519022) (xy 339.209888 -41.515039)
			(xy 339.263038 -41.519022) (xy 339.315 -41.530882) (xy 339.364614 -41.550354) (xy 339.410772 -41.577003)
			(xy 339.452443 -41.610234) (xy 339.488695 -41.649305) (xy 339.518719 -41.693342) (xy 339.541845 -41.741363)
			(xy 339.557555 -41.792293) (xy 339.565498 -41.844997) (xy 339.565996 -41.871646) (xy 339.565498 -41.898295)
			(xy 339.935048 -41.898295) (xy 339.935048 -41.844997) (xy 339.942991 -41.792293) (xy 339.958701 -41.741363)
			(xy 339.981827 -41.693342) (xy 340.011851 -41.649305) (xy 340.048103 -41.610234) (xy 340.089774 -41.577003)
			(xy 340.135932 -41.550354) (xy 340.185546 -41.530882) (xy 340.237508 -41.519022) (xy 340.290658 -41.515039)
			(xy 340.343808 -41.519022) (xy 340.39577 -41.530882) (xy 340.445384 -41.550354) (xy 340.491542 -41.577003)
			(xy 340.533213 -41.610234) (xy 340.569465 -41.649305) (xy 340.599489 -41.693342) (xy 340.622615 -41.741363)
			(xy 340.638325 -41.792293) (xy 340.646268 -41.844997) (xy 340.646766 -41.871646) (xy 340.646268 -41.898295)
			(xy 341.563188 -41.898295) (xy 341.563188 -41.844997) (xy 341.571131 -41.792293) (xy 341.586841 -41.741363)
			(xy 341.609967 -41.693342) (xy 341.639991 -41.649305) (xy 341.676243 -41.610234) (xy 341.717914 -41.577003)
			(xy 341.764072 -41.550354) (xy 341.813686 -41.530882) (xy 341.865648 -41.519022) (xy 341.918798 -41.515039)
			(xy 341.971948 -41.519022) (xy 342.02391 -41.530882) (xy 342.073524 -41.550354) (xy 342.119682 -41.577003)
			(xy 342.161353 -41.610234) (xy 342.197605 -41.649305) (xy 342.227629 -41.693342) (xy 342.250755 -41.741363)
			(xy 342.266465 -41.792293) (xy 342.274408 -41.844997) (xy 342.274906 -41.871646) (xy 342.274413 -41.898041)
			(xy 343.193868 -41.898041) (xy 343.193868 -41.844743) (xy 343.201811 -41.792039) (xy 343.217521 -41.741109)
			(xy 343.240647 -41.693088) (xy 343.270671 -41.649051) (xy 343.306923 -41.60998) (xy 343.348594 -41.576749)
			(xy 343.394752 -41.5501) (xy 343.444366 -41.530628) (xy 343.496328 -41.518768) (xy 343.549478 -41.514785)
			(xy 343.602628 -41.518768) (xy 343.65459 -41.530628) (xy 343.704204 -41.5501) (xy 343.750362 -41.576749)
			(xy 343.792033 -41.60998) (xy 343.828285 -41.649051) (xy 343.858309 -41.693088) (xy 343.881435 -41.741109)
			(xy 343.897145 -41.792039) (xy 343.905088 -41.844743) (xy 343.905586 -41.871392) (xy 343.905088 -41.898041)
			(xy 343.897145 -41.950745) (xy 343.881435 -42.001675) (xy 343.858309 -42.049696) (xy 343.828285 -42.093733)
			(xy 343.792033 -42.132804) (xy 343.750362 -42.166035) (xy 343.704204 -42.192684) (xy 343.65459 -42.212156)
			(xy 343.602628 -42.224016) (xy 343.549478 -42.228) (xy 343.496328 -42.224016) (xy 343.444366 -42.212156)
			(xy 343.394752 -42.192684) (xy 343.348594 -42.166035) (xy 343.306923 -42.132804) (xy 343.270671 -42.093733)
			(xy 343.240647 -42.049696) (xy 343.217521 -42.001675) (xy 343.201811 -41.950745) (xy 343.193868 -41.898041)
			(xy 342.274413 -41.898041) (xy 342.274408 -41.898295) (xy 342.266465 -41.950999) (xy 342.250755 -42.001929)
			(xy 342.227629 -42.04995) (xy 342.197605 -42.093987) (xy 342.161353 -42.133058) (xy 342.119682 -42.166289)
			(xy 342.073524 -42.192938) (xy 342.02391 -42.21241) (xy 341.971948 -42.22427) (xy 341.918798 -42.228254)
			(xy 341.865648 -42.22427) (xy 341.813686 -42.21241) (xy 341.764072 -42.192938) (xy 341.717914 -42.166289)
			(xy 341.676243 -42.133058) (xy 341.639991 -42.093987) (xy 341.609967 -42.04995) (xy 341.586841 -42.001929)
			(xy 341.571131 -41.950999) (xy 341.563188 -41.898295) (xy 340.646268 -41.898295) (xy 340.638325 -41.950999)
			(xy 340.622615 -42.001929) (xy 340.599489 -42.04995) (xy 340.569465 -42.093987) (xy 340.533213 -42.133058)
			(xy 340.491542 -42.166289) (xy 340.445384 -42.192938) (xy 340.39577 -42.21241) (xy 340.343808 -42.22427)
			(xy 340.290658 -42.228254) (xy 340.237508 -42.22427) (xy 340.185546 -42.21241) (xy 340.135932 -42.192938)
			(xy 340.089774 -42.166289) (xy 340.048103 -42.133058) (xy 340.011851 -42.093987) (xy 339.981827 -42.04995)
			(xy 339.958701 -42.001929) (xy 339.942991 -41.950999) (xy 339.935048 -41.898295) (xy 339.565498 -41.898295)
			(xy 339.557555 -41.950999) (xy 339.541845 -42.001929) (xy 339.518719 -42.04995) (xy 339.488695 -42.093987)
			(xy 339.452443 -42.133058) (xy 339.410772 -42.166289) (xy 339.364614 -42.192938) (xy 339.315 -42.21241)
			(xy 339.263038 -42.22427) (xy 339.209888 -42.228254) (xy 339.156738 -42.22427) (xy 339.104776 -42.21241)
			(xy 339.055162 -42.192938) (xy 339.009004 -42.166289) (xy 338.967333 -42.133058) (xy 338.931081 -42.093987)
			(xy 338.901057 -42.04995) (xy 338.877931 -42.001929) (xy 338.862221 -41.950999) (xy 338.854278 -41.898295)
			(xy 337.937358 -41.898295) (xy 337.929415 -41.950999) (xy 337.913705 -42.001929) (xy 337.890579 -42.04995)
			(xy 337.860555 -42.093987) (xy 337.824303 -42.133058) (xy 337.782632 -42.166289) (xy 337.736474 -42.192938)
			(xy 337.68686 -42.21241) (xy 337.634898 -42.22427) (xy 337.581748 -42.228254) (xy 337.528598 -42.22427)
			(xy 337.476636 -42.21241) (xy 337.427022 -42.192938) (xy 337.380864 -42.166289) (xy 337.339193 -42.133058)
			(xy 337.302941 -42.093987) (xy 337.272917 -42.04995) (xy 337.249791 -42.001929) (xy 337.234081 -41.950999)
			(xy 337.226138 -41.898295) (xy 336.309218 -41.898295) (xy 336.301275 -41.950999) (xy 336.285565 -42.001929)
			(xy 336.262439 -42.04995) (xy 336.232415 -42.093987) (xy 336.196163 -42.133058) (xy 336.154492 -42.166289)
			(xy 336.108334 -42.192938) (xy 336.05872 -42.21241) (xy 336.006758 -42.22427) (xy 335.953608 -42.228254)
			(xy 335.900458 -42.22427) (xy 335.848496 -42.21241) (xy 335.798882 -42.192938) (xy 335.752724 -42.166289)
			(xy 335.711053 -42.133058) (xy 335.674801 -42.093987) (xy 335.644777 -42.04995) (xy 335.621651 -42.001929)
			(xy 335.605941 -41.950999) (xy 335.597998 -41.898295) (xy 334.681078 -41.898295) (xy 334.673135 -41.950999)
			(xy 334.657425 -42.001929) (xy 334.634299 -42.04995) (xy 334.604275 -42.093987) (xy 334.568023 -42.133058)
			(xy 334.526352 -42.166289) (xy 334.480194 -42.192938) (xy 334.43058 -42.21241) (xy 334.378618 -42.22427)
			(xy 334.325468 -42.228254) (xy 334.272318 -42.22427) (xy 334.220356 -42.21241) (xy 334.170742 -42.192938)
			(xy 334.124584 -42.166289) (xy 334.082913 -42.133058) (xy 334.046661 -42.093987) (xy 334.016637 -42.04995)
			(xy 333.993511 -42.001929) (xy 333.977801 -41.950999) (xy 333.969858 -41.898295) (xy 333.052938 -41.898295)
			(xy 333.044995 -41.950999) (xy 333.029285 -42.001929) (xy 333.006159 -42.04995) (xy 332.976135 -42.093987)
			(xy 332.939883 -42.133058) (xy 332.898212 -42.166289) (xy 332.852054 -42.192938) (xy 332.80244 -42.21241)
			(xy 332.750478 -42.22427) (xy 332.697328 -42.228254) (xy 332.644178 -42.22427) (xy 332.592216 -42.21241)
			(xy 332.542602 -42.192938) (xy 332.496444 -42.166289) (xy 332.454773 -42.133058) (xy 332.418521 -42.093987)
			(xy 332.388497 -42.04995) (xy 332.365371 -42.001929) (xy 332.349661 -41.950999) (xy 332.341718 -41.898295)
			(xy 331.423526 -41.898295) (xy 331.423517 -41.898801) (xy 331.415272 -41.952483) (xy 331.398965 -42.004287)
			(xy 331.374975 -42.053012) (xy 331.343859 -42.097526) (xy 331.325474 -42.117518) (xy 331.291184 -42.153332)
			(xy 331.384148 -42.246296) (xy 331.394687 -42.256148) (xy 331.419953 -42.270046) (xy 331.448099 -42.276319)
			(xy 331.476875 -42.274467) (xy 331.503984 -42.264638) (xy 331.52726 -42.247615) (xy 331.544844 -42.224761)
			(xy 331.550518 -42.211498) (xy 331.560715 -42.18687) (xy 331.587361 -42.140707) (xy 331.620587 -42.09903)
			(xy 331.659654 -42.062769) (xy 331.703687 -42.032734) (xy 331.751705 -42.009597) (xy 331.802634 -41.993873)
			(xy 331.855338 -41.985913) (xy 331.881988 -41.985438) (xy 331.909973 -41.985958) (xy 331.965253 -41.994712)
			(xy 332.018483 -42.012008) (xy 332.068351 -42.037418) (xy 332.113631 -42.070317) (xy 332.153205 -42.109895)
			(xy 332.1861 -42.155178) (xy 332.211505 -42.205049) (xy 332.228796 -42.25828) (xy 332.237545 -42.313561)
			(xy 332.238096 -42.341546) (xy 332.237626 -42.368195) (xy 333.154772 -42.368195) (xy 333.154772 -42.314897)
			(xy 333.162715 -42.262193) (xy 333.178425 -42.211263) (xy 333.201551 -42.163242) (xy 333.231575 -42.119205)
			(xy 333.267827 -42.080134) (xy 333.309498 -42.046903) (xy 333.355656 -42.020254) (xy 333.40527 -42.000782)
			(xy 333.457232 -41.988922) (xy 333.510382 -41.984939) (xy 333.563532 -41.988922) (xy 333.615494 -42.000782)
			(xy 333.665108 -42.020254) (xy 333.711266 -42.046903) (xy 333.752937 -42.080134) (xy 333.789189 -42.119205)
			(xy 333.819213 -42.163242) (xy 333.842339 -42.211263) (xy 333.858049 -42.262193) (xy 333.865992 -42.314897)
			(xy 333.86649 -42.341546) (xy 333.865992 -42.368195) (xy 334.785198 -42.368195) (xy 334.785198 -42.314897)
			(xy 334.793141 -42.262193) (xy 334.808851 -42.211263) (xy 334.831977 -42.163242) (xy 334.862001 -42.119205)
			(xy 334.898253 -42.080134) (xy 334.939924 -42.046903) (xy 334.986082 -42.020254) (xy 335.035696 -42.000782)
			(xy 335.087658 -41.988922) (xy 335.140808 -41.984939) (xy 335.193958 -41.988922) (xy 335.24592 -42.000782)
			(xy 335.295534 -42.020254) (xy 335.341692 -42.046903) (xy 335.383363 -42.080134) (xy 335.419615 -42.119205)
			(xy 335.449639 -42.163242) (xy 335.472765 -42.211263) (xy 335.488475 -42.262193) (xy 335.496418 -42.314897)
			(xy 335.496916 -42.341546) (xy 335.496418 -42.368195) (xy 338.040462 -42.368195) (xy 338.040462 -42.314897)
			(xy 338.048405 -42.262193) (xy 338.064115 -42.211263) (xy 338.087241 -42.163242) (xy 338.117265 -42.119205)
			(xy 338.153517 -42.080134) (xy 338.195188 -42.046903) (xy 338.241346 -42.020254) (xy 338.29096 -42.000782)
			(xy 338.342922 -41.988922) (xy 338.396072 -41.984939) (xy 338.449222 -41.988922) (xy 338.501184 -42.000782)
			(xy 338.550798 -42.020254) (xy 338.596956 -42.046903) (xy 338.638627 -42.080134) (xy 338.674879 -42.119205)
			(xy 338.704903 -42.163242) (xy 338.728029 -42.211263) (xy 338.743739 -42.262193) (xy 338.751682 -42.314897)
			(xy 338.75218 -42.341546) (xy 338.751682 -42.368195) (xy 340.742768 -42.368195) (xy 340.742768 -42.314897)
			(xy 340.750711 -42.262193) (xy 340.766421 -42.211263) (xy 340.789547 -42.163242) (xy 340.819571 -42.119205)
			(xy 340.855823 -42.080134) (xy 340.897494 -42.046903) (xy 340.943652 -42.020254) (xy 340.993266 -42.000782)
			(xy 341.045228 -41.988922) (xy 341.098378 -41.984939) (xy 341.151528 -41.988922) (xy 341.20349 -42.000782)
			(xy 341.253104 -42.020254) (xy 341.299262 -42.046903) (xy 341.340933 -42.080134) (xy 341.377185 -42.119205)
			(xy 341.407209 -42.163242) (xy 341.430335 -42.211263) (xy 341.446045 -42.262193) (xy 341.453988 -42.314897)
			(xy 341.454486 -42.341546) (xy 341.453993 -42.367941) (xy 342.379544 -42.367941) (xy 342.379544 -42.314643)
			(xy 342.387487 -42.261939) (xy 342.403197 -42.211009) (xy 342.426323 -42.162988) (xy 342.456347 -42.118951)
			(xy 342.492599 -42.07988) (xy 342.53427 -42.046649) (xy 342.580428 -42.02) (xy 342.630042 -42.000528)
			(xy 342.682004 -41.988668) (xy 342.735154 -41.984685) (xy 342.788304 -41.988668) (xy 342.840266 -42.000528)
			(xy 342.88988 -42.02) (xy 342.936038 -42.046649) (xy 342.977709 -42.07988) (xy 343.013961 -42.118951)
			(xy 343.043985 -42.162988) (xy 343.067111 -42.211009) (xy 343.082821 -42.261939) (xy 343.090764 -42.314643)
			(xy 343.091262 -42.341292) (xy 343.090764 -42.367941) (xy 343.082821 -42.420645) (xy 343.067111 -42.471575)
			(xy 343.043985 -42.519596) (xy 343.013961 -42.563633) (xy 342.977709 -42.602704) (xy 342.936038 -42.635935)
			(xy 342.88988 -42.662584) (xy 342.840266 -42.682056) (xy 342.788304 -42.693916) (xy 342.735154 -42.6979)
			(xy 342.682004 -42.693916) (xy 342.630042 -42.682056) (xy 342.580428 -42.662584) (xy 342.53427 -42.635935)
			(xy 342.492599 -42.602704) (xy 342.456347 -42.563633) (xy 342.426323 -42.519596) (xy 342.403197 -42.471575)
			(xy 342.387487 -42.420645) (xy 342.379544 -42.367941) (xy 341.453993 -42.367941) (xy 341.453988 -42.368195)
			(xy 341.446045 -42.420899) (xy 341.430335 -42.471829) (xy 341.407209 -42.51985) (xy 341.377185 -42.563887)
			(xy 341.340933 -42.602958) (xy 341.299262 -42.636189) (xy 341.253104 -42.662838) (xy 341.20349 -42.68231)
			(xy 341.151528 -42.69417) (xy 341.098378 -42.698154) (xy 341.045228 -42.69417) (xy 340.993266 -42.68231)
			(xy 340.943652 -42.662838) (xy 340.897494 -42.636189) (xy 340.855823 -42.602958) (xy 340.819571 -42.563887)
			(xy 340.789547 -42.51985) (xy 340.766421 -42.471829) (xy 340.750711 -42.420899) (xy 340.742768 -42.368195)
			(xy 338.751682 -42.368195) (xy 338.743739 -42.420899) (xy 338.728029 -42.471829) (xy 338.704903 -42.51985)
			(xy 338.674879 -42.563887) (xy 338.638627 -42.602958) (xy 338.596956 -42.636189) (xy 338.550798 -42.662838)
			(xy 338.501184 -42.68231) (xy 338.449222 -42.69417) (xy 338.396072 -42.698154) (xy 338.342922 -42.69417)
			(xy 338.29096 -42.68231) (xy 338.241346 -42.662838) (xy 338.195188 -42.636189) (xy 338.153517 -42.602958)
			(xy 338.117265 -42.563887) (xy 338.087241 -42.51985) (xy 338.064115 -42.471829) (xy 338.048405 -42.420899)
			(xy 338.040462 -42.368195) (xy 335.496418 -42.368195) (xy 335.488475 -42.420899) (xy 335.472765 -42.471829)
			(xy 335.449639 -42.51985) (xy 335.419615 -42.563887) (xy 335.383363 -42.602958) (xy 335.341692 -42.636189)
			(xy 335.295534 -42.662838) (xy 335.24592 -42.68231) (xy 335.193958 -42.69417) (xy 335.140808 -42.698154)
			(xy 335.087658 -42.69417) (xy 335.035696 -42.68231) (xy 334.986082 -42.662838) (xy 334.939924 -42.636189)
			(xy 334.898253 -42.602958) (xy 334.862001 -42.563887) (xy 334.831977 -42.51985) (xy 334.808851 -42.471829)
			(xy 334.793141 -42.420899) (xy 334.785198 -42.368195) (xy 333.865992 -42.368195) (xy 333.858049 -42.420899)
			(xy 333.842339 -42.471829) (xy 333.819213 -42.51985) (xy 333.789189 -42.563887) (xy 333.752937 -42.602958)
			(xy 333.711266 -42.636189) (xy 333.665108 -42.662838) (xy 333.615494 -42.68231) (xy 333.563532 -42.69417)
			(xy 333.510382 -42.698154) (xy 333.457232 -42.69417) (xy 333.40527 -42.68231) (xy 333.355656 -42.662838)
			(xy 333.309498 -42.636189) (xy 333.267827 -42.602958) (xy 333.231575 -42.563887) (xy 333.201551 -42.51985)
			(xy 333.178425 -42.471829) (xy 333.162715 -42.420899) (xy 333.154772 -42.368195) (xy 332.237626 -42.368195)
			(xy 332.237626 -42.3682) (xy 332.229686 -42.420913) (xy 332.213974 -42.471853) (xy 332.190843 -42.519881)
			(xy 332.160809 -42.563924) (xy 332.124544 -42.602995) (xy 332.082859 -42.636223) (xy 332.036685 -42.662863)
			(xy 332.012036 -42.673016) (xy 331.998824 -42.678755) (xy 331.976044 -42.696363) (xy 331.959079 -42.719626)
			(xy 331.949278 -42.746698) (xy 331.947418 -42.77543) (xy 331.953647 -42.80354) (xy 331.96747 -42.828797)
			(xy 331.976047 -42.838095) (xy 332.341718 -42.838095) (xy 332.341718 -42.784797) (xy 332.349661 -42.732093)
			(xy 332.365371 -42.681163) (xy 332.388497 -42.633142) (xy 332.418521 -42.589105) (xy 332.454773 -42.550034)
			(xy 332.496444 -42.516803) (xy 332.542602 -42.490154) (xy 332.592216 -42.470682) (xy 332.644178 -42.458822)
			(xy 332.697328 -42.454839) (xy 332.750478 -42.458822) (xy 332.80244 -42.470682) (xy 332.852054 -42.490154)
			(xy 332.898212 -42.516803) (xy 332.939883 -42.550034) (xy 332.976135 -42.589105) (xy 333.006159 -42.633142)
			(xy 333.029285 -42.681163) (xy 333.044995 -42.732093) (xy 333.052938 -42.784797) (xy 333.053436 -42.811446)
			(xy 333.052938 -42.838095) (xy 333.969858 -42.838095) (xy 333.969858 -42.784797) (xy 333.977801 -42.732093)
			(xy 333.993511 -42.681163) (xy 334.016637 -42.633142) (xy 334.046661 -42.589105) (xy 334.082913 -42.550034)
			(xy 334.124584 -42.516803) (xy 334.170742 -42.490154) (xy 334.220356 -42.470682) (xy 334.272318 -42.458822)
			(xy 334.325468 -42.454839) (xy 334.378618 -42.458822) (xy 334.43058 -42.470682) (xy 334.480194 -42.490154)
			(xy 334.526352 -42.516803) (xy 334.568023 -42.550034) (xy 334.604275 -42.589105) (xy 334.634299 -42.633142)
			(xy 334.657425 -42.681163) (xy 334.673135 -42.732093) (xy 334.681078 -42.784797) (xy 334.681576 -42.811446)
			(xy 334.681078 -42.838095) (xy 337.226138 -42.838095) (xy 337.226138 -42.784797) (xy 337.234081 -42.732093)
			(xy 337.249791 -42.681163) (xy 337.272917 -42.633142) (xy 337.302941 -42.589105) (xy 337.339193 -42.550034)
			(xy 337.380864 -42.516803) (xy 337.427022 -42.490154) (xy 337.476636 -42.470682) (xy 337.528598 -42.458822)
			(xy 337.581748 -42.454839) (xy 337.634898 -42.458822) (xy 337.68686 -42.470682) (xy 337.736474 -42.490154)
			(xy 337.782632 -42.516803) (xy 337.824303 -42.550034) (xy 337.860555 -42.589105) (xy 337.890579 -42.633142)
			(xy 337.913705 -42.681163) (xy 337.929415 -42.732093) (xy 337.937358 -42.784797) (xy 337.937856 -42.811446)
			(xy 337.937358 -42.838095) (xy 338.854278 -42.838095) (xy 338.854278 -42.784797) (xy 338.862221 -42.732093)
			(xy 338.877931 -42.681163) (xy 338.901057 -42.633142) (xy 338.931081 -42.589105) (xy 338.967333 -42.550034)
			(xy 339.009004 -42.516803) (xy 339.055162 -42.490154) (xy 339.104776 -42.470682) (xy 339.156738 -42.458822)
			(xy 339.209888 -42.454839) (xy 339.263038 -42.458822) (xy 339.315 -42.470682) (xy 339.364614 -42.490154)
			(xy 339.410772 -42.516803) (xy 339.452443 -42.550034) (xy 339.488695 -42.589105) (xy 339.518719 -42.633142)
			(xy 339.541845 -42.681163) (xy 339.557555 -42.732093) (xy 339.565498 -42.784797) (xy 339.565996 -42.811446)
			(xy 339.565498 -42.838095) (xy 339.935048 -42.838095) (xy 339.935048 -42.784797) (xy 339.942991 -42.732093)
			(xy 339.958701 -42.681163) (xy 339.981827 -42.633142) (xy 340.011851 -42.589105) (xy 340.048103 -42.550034)
			(xy 340.089774 -42.516803) (xy 340.135932 -42.490154) (xy 340.185546 -42.470682) (xy 340.237508 -42.458822)
			(xy 340.290658 -42.454839) (xy 340.343808 -42.458822) (xy 340.39577 -42.470682) (xy 340.445384 -42.490154)
			(xy 340.491542 -42.516803) (xy 340.533213 -42.550034) (xy 340.569465 -42.589105) (xy 340.599489 -42.633142)
			(xy 340.622615 -42.681163) (xy 340.638325 -42.732093) (xy 340.646268 -42.784797) (xy 340.646766 -42.811446)
			(xy 340.646268 -42.838095) (xy 341.563188 -42.838095) (xy 341.563188 -42.784797) (xy 341.571131 -42.732093)
			(xy 341.586841 -42.681163) (xy 341.609967 -42.633142) (xy 341.639991 -42.589105) (xy 341.676243 -42.550034)
			(xy 341.717914 -42.516803) (xy 341.764072 -42.490154) (xy 341.813686 -42.470682) (xy 341.865648 -42.458822)
			(xy 341.918798 -42.454839) (xy 341.971948 -42.458822) (xy 342.02391 -42.470682) (xy 342.073524 -42.490154)
			(xy 342.119682 -42.516803) (xy 342.161353 -42.550034) (xy 342.197605 -42.589105) (xy 342.227629 -42.633142)
			(xy 342.250755 -42.681163) (xy 342.266465 -42.732093) (xy 342.274408 -42.784797) (xy 342.274906 -42.811446)
			(xy 342.274413 -42.837841) (xy 343.193868 -42.837841) (xy 343.193868 -42.784543) (xy 343.201811 -42.731839)
			(xy 343.217521 -42.680909) (xy 343.240647 -42.632888) (xy 343.270671 -42.588851) (xy 343.306923 -42.54978)
			(xy 343.348594 -42.516549) (xy 343.394752 -42.4899) (xy 343.444366 -42.470428) (xy 343.496328 -42.458568)
			(xy 343.549478 -42.454585) (xy 343.602628 -42.458568) (xy 343.65459 -42.470428) (xy 343.704204 -42.4899)
			(xy 343.750362 -42.516549) (xy 343.792033 -42.54978) (xy 343.828285 -42.588851) (xy 343.858309 -42.632888)
			(xy 343.881435 -42.680909) (xy 343.897145 -42.731839) (xy 343.905088 -42.784543) (xy 343.905586 -42.811192)
			(xy 343.905088 -42.837841) (xy 343.897145 -42.890545) (xy 343.881435 -42.941475) (xy 343.858309 -42.989496)
			(xy 343.828285 -43.033533) (xy 343.792033 -43.072604) (xy 343.750362 -43.105835) (xy 343.704204 -43.132484)
			(xy 343.65459 -43.151956) (xy 343.602628 -43.163816) (xy 343.549478 -43.1678) (xy 343.496328 -43.163816)
			(xy 343.444366 -43.151956) (xy 343.394752 -43.132484) (xy 343.348594 -43.105835) (xy 343.306923 -43.072604)
			(xy 343.270671 -43.033533) (xy 343.240647 -42.989496) (xy 343.217521 -42.941475) (xy 343.201811 -42.890545)
			(xy 343.193868 -42.837841) (xy 342.274413 -42.837841) (xy 342.274408 -42.838095) (xy 342.266465 -42.890799)
			(xy 342.250755 -42.941729) (xy 342.227629 -42.98975) (xy 342.197605 -43.033787) (xy 342.161353 -43.072858)
			(xy 342.119682 -43.106089) (xy 342.073524 -43.132738) (xy 342.02391 -43.15221) (xy 341.971948 -43.16407)
			(xy 341.918798 -43.168054) (xy 341.865648 -43.16407) (xy 341.813686 -43.15221) (xy 341.764072 -43.132738)
			(xy 341.717914 -43.106089) (xy 341.676243 -43.072858) (xy 341.639991 -43.033787) (xy 341.609967 -42.98975)
			(xy 341.586841 -42.941729) (xy 341.571131 -42.890799) (xy 341.563188 -42.838095) (xy 340.646268 -42.838095)
			(xy 340.638325 -42.890799) (xy 340.622615 -42.941729) (xy 340.599489 -42.98975) (xy 340.569465 -43.033787)
			(xy 340.533213 -43.072858) (xy 340.491542 -43.106089) (xy 340.445384 -43.132738) (xy 340.39577 -43.15221)
			(xy 340.343808 -43.16407) (xy 340.290658 -43.168054) (xy 340.237508 -43.16407) (xy 340.185546 -43.15221)
			(xy 340.135932 -43.132738) (xy 340.089774 -43.106089) (xy 340.048103 -43.072858) (xy 340.011851 -43.033787)
			(xy 339.981827 -42.98975) (xy 339.958701 -42.941729) (xy 339.942991 -42.890799) (xy 339.935048 -42.838095)
			(xy 339.565498 -42.838095) (xy 339.557555 -42.890799) (xy 339.541845 -42.941729) (xy 339.518719 -42.98975)
			(xy 339.488695 -43.033787) (xy 339.452443 -43.072858) (xy 339.410772 -43.106089) (xy 339.364614 -43.132738)
			(xy 339.315 -43.15221) (xy 339.263038 -43.16407) (xy 339.209888 -43.168054) (xy 339.156738 -43.16407)
			(xy 339.104776 -43.15221) (xy 339.055162 -43.132738) (xy 339.009004 -43.106089) (xy 338.967333 -43.072858)
			(xy 338.931081 -43.033787) (xy 338.901057 -42.98975) (xy 338.877931 -42.941729) (xy 338.862221 -42.890799)
			(xy 338.854278 -42.838095) (xy 337.937358 -42.838095) (xy 337.929415 -42.890799) (xy 337.913705 -42.941729)
			(xy 337.890579 -42.98975) (xy 337.860555 -43.033787) (xy 337.824303 -43.072858) (xy 337.782632 -43.106089)
			(xy 337.736474 -43.132738) (xy 337.68686 -43.15221) (xy 337.634898 -43.16407) (xy 337.581748 -43.168054)
			(xy 337.528598 -43.16407) (xy 337.476636 -43.15221) (xy 337.427022 -43.132738) (xy 337.380864 -43.106089)
			(xy 337.339193 -43.072858) (xy 337.302941 -43.033787) (xy 337.272917 -42.98975) (xy 337.249791 -42.941729)
			(xy 337.234081 -42.890799) (xy 337.226138 -42.838095) (xy 334.681078 -42.838095) (xy 334.673135 -42.890799)
			(xy 334.657425 -42.941729) (xy 334.634299 -42.98975) (xy 334.604275 -43.033787) (xy 334.568023 -43.072858)
			(xy 334.526352 -43.106089) (xy 334.480194 -43.132738) (xy 334.43058 -43.15221) (xy 334.378618 -43.16407)
			(xy 334.325468 -43.168054) (xy 334.272318 -43.16407) (xy 334.220356 -43.15221) (xy 334.170742 -43.132738)
			(xy 334.124584 -43.106089) (xy 334.082913 -43.072858) (xy 334.046661 -43.033787) (xy 334.016637 -42.98975)
			(xy 333.993511 -42.941729) (xy 333.977801 -42.890799) (xy 333.969858 -42.838095) (xy 333.052938 -42.838095)
			(xy 333.044995 -42.890799) (xy 333.029285 -42.941729) (xy 333.006159 -42.98975) (xy 332.976135 -43.033787)
			(xy 332.939883 -43.072858) (xy 332.898212 -43.106089) (xy 332.852054 -43.132738) (xy 332.80244 -43.15221)
			(xy 332.750478 -43.16407) (xy 332.697328 -43.168054) (xy 332.644178 -43.16407) (xy 332.592216 -43.15221)
			(xy 332.542602 -43.132738) (xy 332.496444 -43.106089) (xy 332.454773 -43.072858) (xy 332.418521 -43.033787)
			(xy 332.388497 -42.98975) (xy 332.365371 -42.941729) (xy 332.349661 -42.890799) (xy 332.341718 -42.838095)
			(xy 331.976047 -42.838095) (xy 331.977238 -42.839386) (xy 332.445847 -43.307995) (xy 333.155788 -43.307995)
			(xy 333.155788 -43.254697) (xy 333.163731 -43.201993) (xy 333.179441 -43.151063) (xy 333.202567 -43.103042)
			(xy 333.232591 -43.059005) (xy 333.268843 -43.019934) (xy 333.310514 -42.986703) (xy 333.356672 -42.960054)
			(xy 333.406286 -42.940582) (xy 333.458248 -42.928722) (xy 333.511398 -42.924739) (xy 333.564548 -42.928722)
			(xy 333.61651 -42.940582) (xy 333.666124 -42.960054) (xy 333.712282 -42.986703) (xy 333.753953 -43.019934)
			(xy 333.790205 -43.059005) (xy 333.820229 -43.103042) (xy 333.843355 -43.151063) (xy 333.859065 -43.201993)
			(xy 333.867008 -43.254697) (xy 333.867506 -43.281346) (xy 333.867008 -43.307995) (xy 334.782658 -43.307995)
			(xy 334.782658 -43.254697) (xy 334.790601 -43.201993) (xy 334.806311 -43.151063) (xy 334.829437 -43.103042)
			(xy 334.859461 -43.059005) (xy 334.895713 -43.019934) (xy 334.937384 -42.986703) (xy 334.983542 -42.960054)
			(xy 335.033156 -42.940582) (xy 335.085118 -42.928722) (xy 335.138268 -42.924739) (xy 335.191418 -42.928722)
			(xy 335.24338 -42.940582) (xy 335.292994 -42.960054) (xy 335.339152 -42.986703) (xy 335.380823 -43.019934)
			(xy 335.417075 -43.059005) (xy 335.447099 -43.103042) (xy 335.470225 -43.151063) (xy 335.485935 -43.201993)
			(xy 335.493878 -43.254697) (xy 335.494376 -43.281346) (xy 335.493878 -43.307995) (xy 338.040462 -43.307995)
			(xy 338.040462 -43.254697) (xy 338.048405 -43.201993) (xy 338.064115 -43.151063) (xy 338.087241 -43.103042)
			(xy 338.117265 -43.059005) (xy 338.153517 -43.019934) (xy 338.195188 -42.986703) (xy 338.241346 -42.960054)
			(xy 338.29096 -42.940582) (xy 338.342922 -42.928722) (xy 338.396072 -42.924739) (xy 338.449222 -42.928722)
			(xy 338.501184 -42.940582) (xy 338.550798 -42.960054) (xy 338.596956 -42.986703) (xy 338.638627 -43.019934)
			(xy 338.674879 -43.059005) (xy 338.704903 -43.103042) (xy 338.728029 -43.151063) (xy 338.743739 -43.201993)
			(xy 338.751682 -43.254697) (xy 338.75218 -43.281346) (xy 338.751682 -43.307995) (xy 340.741752 -43.307995)
			(xy 340.741752 -43.254697) (xy 340.749695 -43.201993) (xy 340.765405 -43.151063) (xy 340.788531 -43.103042)
			(xy 340.818555 -43.059005) (xy 340.854807 -43.019934) (xy 340.896478 -42.986703) (xy 340.942636 -42.960054)
			(xy 340.99225 -42.940582) (xy 341.044212 -42.928722) (xy 341.097362 -42.924739) (xy 341.150512 -42.928722)
			(xy 341.202474 -42.940582) (xy 341.252088 -42.960054) (xy 341.298246 -42.986703) (xy 341.339917 -43.019934)
			(xy 341.376169 -43.059005) (xy 341.406193 -43.103042) (xy 341.429319 -43.151063) (xy 341.445029 -43.201993)
			(xy 341.452972 -43.254697) (xy 341.45347 -43.281346) (xy 341.452977 -43.307741) (xy 342.379544 -43.307741)
			(xy 342.379544 -43.254443) (xy 342.387487 -43.201739) (xy 342.403197 -43.150809) (xy 342.426323 -43.102788)
			(xy 342.456347 -43.058751) (xy 342.492599 -43.01968) (xy 342.53427 -42.986449) (xy 342.580428 -42.9598)
			(xy 342.630042 -42.940328) (xy 342.682004 -42.928468) (xy 342.735154 -42.924485) (xy 342.788304 -42.928468)
			(xy 342.840266 -42.940328) (xy 342.88988 -42.9598) (xy 342.936038 -42.986449) (xy 342.977709 -43.01968)
			(xy 343.013961 -43.058751) (xy 343.043985 -43.102788) (xy 343.067111 -43.150809) (xy 343.082821 -43.201739)
			(xy 343.090764 -43.254443) (xy 343.091262 -43.281092) (xy 343.090764 -43.307741) (xy 343.082821 -43.360445)
			(xy 343.067111 -43.411375) (xy 343.043985 -43.459396) (xy 343.013961 -43.503433) (xy 342.977709 -43.542504)
			(xy 342.936038 -43.575735) (xy 342.88988 -43.602384) (xy 342.840266 -43.621856) (xy 342.788304 -43.633716)
			(xy 342.735154 -43.6377) (xy 342.682004 -43.633716) (xy 342.630042 -43.621856) (xy 342.580428 -43.602384)
			(xy 342.53427 -43.575735) (xy 342.492599 -43.542504) (xy 342.456347 -43.503433) (xy 342.426323 -43.459396)
			(xy 342.403197 -43.411375) (xy 342.387487 -43.360445) (xy 342.379544 -43.307741) (xy 341.452977 -43.307741)
			(xy 341.452972 -43.307995) (xy 341.445029 -43.360699) (xy 341.429319 -43.411629) (xy 341.406193 -43.45965)
			(xy 341.376169 -43.503687) (xy 341.339917 -43.542758) (xy 341.298246 -43.575989) (xy 341.252088 -43.602638)
			(xy 341.202474 -43.62211) (xy 341.150512 -43.63397) (xy 341.097362 -43.637954) (xy 341.044212 -43.63397)
			(xy 340.99225 -43.62211) (xy 340.942636 -43.602638) (xy 340.896478 -43.575989) (xy 340.854807 -43.542758)
			(xy 340.818555 -43.503687) (xy 340.788531 -43.45965) (xy 340.765405 -43.411629) (xy 340.749695 -43.360699)
			(xy 340.741752 -43.307995) (xy 338.751682 -43.307995) (xy 338.743739 -43.360699) (xy 338.728029 -43.411629)
			(xy 338.704903 -43.45965) (xy 338.674879 -43.503687) (xy 338.638627 -43.542758) (xy 338.596956 -43.575989)
			(xy 338.550798 -43.602638) (xy 338.501184 -43.62211) (xy 338.449222 -43.63397) (xy 338.396072 -43.637954)
			(xy 338.342922 -43.63397) (xy 338.29096 -43.62211) (xy 338.241346 -43.602638) (xy 338.195188 -43.575989)
			(xy 338.153517 -43.542758) (xy 338.117265 -43.503687) (xy 338.087241 -43.45965) (xy 338.064115 -43.411629)
			(xy 338.048405 -43.360699) (xy 338.040462 -43.307995) (xy 335.493878 -43.307995) (xy 335.485935 -43.360699)
			(xy 335.470225 -43.411629) (xy 335.447099 -43.45965) (xy 335.417075 -43.503687) (xy 335.380823 -43.542758)
			(xy 335.339152 -43.575989) (xy 335.292994 -43.602638) (xy 335.24338 -43.62211) (xy 335.191418 -43.63397)
			(xy 335.138268 -43.637954) (xy 335.085118 -43.63397) (xy 335.033156 -43.62211) (xy 334.983542 -43.602638)
			(xy 334.937384 -43.575989) (xy 334.895713 -43.542758) (xy 334.859461 -43.503687) (xy 334.829437 -43.45965)
			(xy 334.806311 -43.411629) (xy 334.790601 -43.360699) (xy 334.782658 -43.307995) (xy 333.867008 -43.307995)
			(xy 333.859065 -43.360699) (xy 333.843355 -43.411629) (xy 333.820229 -43.45965) (xy 333.790205 -43.503687)
			(xy 333.753953 -43.542758) (xy 333.712282 -43.575989) (xy 333.666124 -43.602638) (xy 333.61651 -43.62211)
			(xy 333.564548 -43.63397) (xy 333.511398 -43.637954) (xy 333.458248 -43.63397) (xy 333.406286 -43.62211)
			(xy 333.356672 -43.602638) (xy 333.310514 -43.575989) (xy 333.268843 -43.542758) (xy 333.232591 -43.503687)
			(xy 333.202567 -43.45965) (xy 333.179441 -43.411629) (xy 333.163731 -43.360699) (xy 333.155788 -43.307995)
			(xy 332.445847 -43.307995) (xy 332.559406 -43.421554) (xy 332.58887 -43.412156) (xy 332.615282 -43.404229)
			(xy 332.669757 -43.395675) (xy 332.697328 -43.395138) (xy 332.725311 -43.395661) (xy 332.780586 -43.40442)
			(xy 332.833811 -43.421719) (xy 332.883674 -43.447132) (xy 332.928947 -43.480032) (xy 332.968517 -43.519609)
			(xy 333.001407 -43.564889) (xy 333.026809 -43.614758) (xy 333.044097 -43.667986) (xy 333.052845 -43.723263)
			(xy 333.053436 -43.751246) (xy 333.052915 -43.777895) (xy 333.968588 -43.777895) (xy 333.968588 -43.724597)
			(xy 333.976531 -43.671893) (xy 333.992241 -43.620963) (xy 334.015367 -43.572942) (xy 334.045391 -43.528905)
			(xy 334.081643 -43.489834) (xy 334.123314 -43.456603) (xy 334.169472 -43.429954) (xy 334.219086 -43.410482)
			(xy 334.271048 -43.398622) (xy 334.324198 -43.394639) (xy 334.377348 -43.398622) (xy 334.42931 -43.410482)
			(xy 334.478924 -43.429954) (xy 334.525082 -43.456603) (xy 334.566753 -43.489834) (xy 334.603005 -43.528905)
			(xy 334.633029 -43.572942) (xy 334.656155 -43.620963) (xy 334.671865 -43.671893) (xy 334.679808 -43.724597)
			(xy 334.680306 -43.751246) (xy 334.679808 -43.777895) (xy 337.226138 -43.777895) (xy 337.226138 -43.724597)
			(xy 337.234081 -43.671893) (xy 337.249791 -43.620963) (xy 337.272917 -43.572942) (xy 337.302941 -43.528905)
			(xy 337.339193 -43.489834) (xy 337.380864 -43.456603) (xy 337.427022 -43.429954) (xy 337.476636 -43.410482)
			(xy 337.528598 -43.398622) (xy 337.581748 -43.394639) (xy 337.634898 -43.398622) (xy 337.68686 -43.410482)
			(xy 337.736474 -43.429954) (xy 337.782632 -43.456603) (xy 337.824303 -43.489834) (xy 337.860555 -43.528905)
			(xy 337.890579 -43.572942) (xy 337.913705 -43.620963) (xy 337.929415 -43.671893) (xy 337.937358 -43.724597)
			(xy 337.937856 -43.751246) (xy 337.937358 -43.777895) (xy 338.854278 -43.777895) (xy 338.854278 -43.724597)
			(xy 338.862221 -43.671893) (xy 338.877931 -43.620963) (xy 338.901057 -43.572942) (xy 338.931081 -43.528905)
			(xy 338.967333 -43.489834) (xy 339.009004 -43.456603) (xy 339.055162 -43.429954) (xy 339.104776 -43.410482)
			(xy 339.156738 -43.398622) (xy 339.209888 -43.394639) (xy 339.263038 -43.398622) (xy 339.315 -43.410482)
			(xy 339.364614 -43.429954) (xy 339.410772 -43.456603) (xy 339.452443 -43.489834) (xy 339.488695 -43.528905)
			(xy 339.518719 -43.572942) (xy 339.541845 -43.620963) (xy 339.557555 -43.671893) (xy 339.565498 -43.724597)
			(xy 339.565996 -43.751246) (xy 339.565498 -43.777895) (xy 341.563188 -43.777895) (xy 341.563188 -43.724597)
			(xy 341.571131 -43.671893) (xy 341.586841 -43.620963) (xy 341.609967 -43.572942) (xy 341.639991 -43.528905)
			(xy 341.676243 -43.489834) (xy 341.717914 -43.456603) (xy 341.764072 -43.429954) (xy 341.813686 -43.410482)
			(xy 341.865648 -43.398622) (xy 341.918798 -43.394639) (xy 341.971948 -43.398622) (xy 342.02391 -43.410482)
			(xy 342.073524 -43.429954) (xy 342.119682 -43.456603) (xy 342.161353 -43.489834) (xy 342.197605 -43.528905)
			(xy 342.227629 -43.572942) (xy 342.250755 -43.620963) (xy 342.266465 -43.671893) (xy 342.274408 -43.724597)
			(xy 342.274906 -43.751246) (xy 342.274413 -43.777641) (xy 343.193868 -43.777641) (xy 343.193868 -43.724343)
			(xy 343.201811 -43.671639) (xy 343.217521 -43.620709) (xy 343.240647 -43.572688) (xy 343.270671 -43.528651)
			(xy 343.306923 -43.48958) (xy 343.348594 -43.456349) (xy 343.394752 -43.4297) (xy 343.444366 -43.410228)
			(xy 343.496328 -43.398368) (xy 343.549478 -43.394385) (xy 343.602628 -43.398368) (xy 343.65459 -43.410228)
			(xy 343.704204 -43.4297) (xy 343.750362 -43.456349) (xy 343.792033 -43.48958) (xy 343.828285 -43.528651)
			(xy 343.858309 -43.572688) (xy 343.881435 -43.620709) (xy 343.897145 -43.671639) (xy 343.905088 -43.724343)
			(xy 343.905586 -43.750992) (xy 343.905088 -43.777641) (xy 343.897145 -43.830345) (xy 343.881435 -43.881275)
			(xy 343.858309 -43.929296) (xy 343.828285 -43.973333) (xy 343.792033 -44.012404) (xy 343.750362 -44.045635)
			(xy 343.704204 -44.072284) (xy 343.65459 -44.091756) (xy 343.602628 -44.103616) (xy 343.549478 -44.1076)
			(xy 343.496328 -44.103616) (xy 343.444366 -44.091756) (xy 343.394752 -44.072284) (xy 343.348594 -44.045635)
			(xy 343.306923 -44.012404) (xy 343.270671 -43.973333) (xy 343.240647 -43.929296) (xy 343.217521 -43.881275)
			(xy 343.201811 -43.830345) (xy 343.193868 -43.777641) (xy 342.274413 -43.777641) (xy 342.274408 -43.777895)
			(xy 342.266465 -43.830599) (xy 342.250755 -43.881529) (xy 342.227629 -43.92955) (xy 342.197605 -43.973587)
			(xy 342.161353 -44.012658) (xy 342.119682 -44.045889) (xy 342.073524 -44.072538) (xy 342.02391 -44.09201)
			(xy 341.971948 -44.10387) (xy 341.918798 -44.107854) (xy 341.865648 -44.10387) (xy 341.813686 -44.09201)
			(xy 341.764072 -44.072538) (xy 341.717914 -44.045889) (xy 341.676243 -44.012658) (xy 341.639991 -43.973587)
			(xy 341.609967 -43.92955) (xy 341.586841 -43.881529) (xy 341.571131 -43.830599) (xy 341.563188 -43.777895)
			(xy 339.565498 -43.777895) (xy 339.557555 -43.830599) (xy 339.541845 -43.881529) (xy 339.518719 -43.92955)
			(xy 339.488695 -43.973587) (xy 339.452443 -44.012658) (xy 339.410772 -44.045889) (xy 339.364614 -44.072538)
			(xy 339.315 -44.09201) (xy 339.263038 -44.10387) (xy 339.209888 -44.107854) (xy 339.156738 -44.10387)
			(xy 339.104776 -44.09201) (xy 339.055162 -44.072538) (xy 339.009004 -44.045889) (xy 338.967333 -44.012658)
			(xy 338.931081 -43.973587) (xy 338.901057 -43.92955) (xy 338.877931 -43.881529) (xy 338.862221 -43.830599)
			(xy 338.854278 -43.777895) (xy 337.937358 -43.777895) (xy 337.929415 -43.830599) (xy 337.913705 -43.881529)
			(xy 337.890579 -43.92955) (xy 337.860555 -43.973587) (xy 337.824303 -44.012658) (xy 337.782632 -44.045889)
			(xy 337.736474 -44.072538) (xy 337.68686 -44.09201) (xy 337.634898 -44.10387) (xy 337.581748 -44.107854)
			(xy 337.528598 -44.10387) (xy 337.476636 -44.09201) (xy 337.427022 -44.072538) (xy 337.380864 -44.045889)
			(xy 337.339193 -44.012658) (xy 337.302941 -43.973587) (xy 337.272917 -43.92955) (xy 337.249791 -43.881529)
			(xy 337.234081 -43.830599) (xy 337.226138 -43.777895) (xy 334.679808 -43.777895) (xy 334.671865 -43.830599)
			(xy 334.656155 -43.881529) (xy 334.633029 -43.92955) (xy 334.603005 -43.973587) (xy 334.566753 -44.012658)
			(xy 334.525082 -44.045889) (xy 334.478924 -44.072538) (xy 334.42931 -44.09201) (xy 334.377348 -44.10387)
			(xy 334.324198 -44.107854) (xy 334.271048 -44.10387) (xy 334.219086 -44.09201) (xy 334.169472 -44.072538)
			(xy 334.123314 -44.045889) (xy 334.081643 -44.012658) (xy 334.045391 -43.973587) (xy 334.015367 -43.92955)
			(xy 333.992241 -43.881529) (xy 333.976531 -43.830599) (xy 333.968588 -43.777895) (xy 333.052915 -43.777895)
			(xy 333.052897 -43.778817) (xy 333.044344 -43.833291) (xy 333.036418 -43.859704) (xy 333.02702 -43.889168)
			(xy 333.111094 -43.973242) (xy 333.120871 -43.98245) (xy 333.144141 -43.995841) (xy 333.170096 -44.002705)
			(xy 333.196944 -44.002567) (xy 333.222827 -43.995437) (xy 333.245959 -43.981808) (xy 333.25562 -43.97248)
			(xy 333.275853 -43.952524) (xy 333.321484 -43.918657) (xy 333.371916 -43.892468) (xy 333.425868 -43.874625)
			(xy 333.481969 -43.865578) (xy 333.510382 -43.865038) (xy 333.537031 -43.86551) (xy 333.589733 -43.873451)
			(xy 333.640663 -43.889158) (xy 333.688683 -43.912281) (xy 333.73272 -43.942303) (xy 333.77179 -43.978554)
			(xy 333.805021 -44.020222) (xy 333.831671 -44.066378) (xy 333.851143 -44.115991) (xy 333.863003 -44.167952)
			(xy 333.866986 -44.2211) (xy 333.863003 -44.274248) (xy 333.851143 -44.326209) (xy 333.831671 -44.375822)
			(xy 333.805021 -44.421978) (xy 333.77179 -44.463646) (xy 333.73272 -44.499897) (xy 333.688683 -44.529919)
			(xy 333.640663 -44.553042) (xy 333.589733 -44.568749) (xy 333.537031 -44.57669) (xy 333.510382 -44.577254)
			(xy 333.486141 -44.576826) (xy 333.43811 -44.570217) (xy 333.391416 -44.557164) (xy 333.346921 -44.537908)
			(xy 333.325978 -44.525692) (xy 333.314244 -44.519078) (xy 333.288362 -44.51165) (xy 333.261439 -44.511251)
			(xy 333.235348 -44.517907) (xy 333.211906 -44.531156) (xy 333.192745 -44.550074) (xy 333.179199 -44.573346)
			(xy 333.172212 -44.59935) (xy 333.1718 -44.612814) (xy 333.1718 -44.876445) (xy 334.543898 -44.876445)
			(xy 334.543898 -44.823147) (xy 334.551841 -44.770443) (xy 334.567551 -44.719513) (xy 334.590677 -44.671492)
			(xy 334.620701 -44.627455) (xy 334.656953 -44.588384) (xy 334.698624 -44.555153) (xy 334.744782 -44.528504)
			(xy 334.794396 -44.509032) (xy 334.846358 -44.497172) (xy 334.899508 -44.493189) (xy 334.952658 -44.497172)
			(xy 335.00462 -44.509032) (xy 335.054234 -44.528504) (xy 335.100392 -44.555153) (xy 335.142063 -44.588384)
			(xy 335.178315 -44.627455) (xy 335.208339 -44.671492) (xy 335.231465 -44.719513) (xy 335.247175 -44.770443)
			(xy 335.25255 -44.806108) (xy 336.215482 -44.806108) (xy 336.215984 -44.779099) (xy 336.224128 -44.725699)
			(xy 336.240247 -44.674141) (xy 336.263969 -44.625611) (xy 336.294751 -44.581222) (xy 336.331885 -44.541992)
			(xy 336.37452 -44.508823) (xy 336.397854 -44.495212) (xy 336.410714 -44.487403) (xy 336.431518 -44.465686)
			(xy 336.445101 -44.438856) (xy 336.45029 -44.409234) (xy 336.446634 -44.379383) (xy 336.441034 -44.365418)
			(xy 336.43142 -44.342592) (xy 336.417848 -44.29496) (xy 336.410986 -44.24591) (xy 336.410554 -44.221146)
			(xy 336.411052 -44.194497) (xy 336.418995 -44.141793) (xy 336.434705 -44.090863) (xy 336.457831 -44.042842)
			(xy 336.487855 -43.998805) (xy 336.524107 -43.959734) (xy 336.565778 -43.926503) (xy 336.611936 -43.899854)
			(xy 336.66155 -43.880382) (xy 336.713512 -43.868522) (xy 336.766662 -43.864539) (xy 336.819812 -43.868522)
			(xy 336.871774 -43.880382) (xy 336.921388 -43.899854) (xy 336.967546 -43.926503) (xy 337.009217 -43.959734)
			(xy 337.045469 -43.998805) (xy 337.075493 -44.042842) (xy 337.098619 -44.090863) (xy 337.114329 -44.141793)
			(xy 337.122272 -44.194497) (xy 337.12277 -44.221146) (xy 337.122256 -44.248155) (xy 337.114117 -44.301556)
			(xy 337.098002 -44.353114) (xy 337.074283 -44.401645) (xy 337.043502 -44.446035) (xy 337.006368 -44.485264)
			(xy 336.963732 -44.518432) (xy 336.940398 -44.532042) (xy 336.927561 -44.539884) (xy 336.906765 -44.561595)
			(xy 336.893181 -44.588416) (xy 336.887986 -44.618028) (xy 336.891627 -44.647872) (xy 336.897218 -44.661836)
			(xy 336.906852 -44.684654) (xy 336.920416 -44.73229) (xy 336.927269 -44.781343) (xy 336.927698 -44.806108)
			(xy 336.9272 -44.832757) (xy 336.919257 -44.885461) (xy 336.903547 -44.936391) (xy 336.880421 -44.984412)
			(xy 336.850397 -45.028449) (xy 336.814145 -45.06752) (xy 336.772474 -45.100751) (xy 336.726316 -45.1274)
			(xy 336.676702 -45.146872) (xy 336.62474 -45.158732) (xy 336.57159 -45.162716) (xy 336.51844 -45.158732)
			(xy 336.466478 -45.146872) (xy 336.416864 -45.1274) (xy 336.370706 -45.100751) (xy 336.329035 -45.06752)
			(xy 336.292783 -45.028449) (xy 336.262759 -44.984412) (xy 336.239633 -44.936391) (xy 336.223923 -44.885461)
			(xy 336.21598 -44.832757) (xy 336.215482 -44.806108) (xy 335.25255 -44.806108) (xy 335.255118 -44.823147)
			(xy 335.255616 -44.849796) (xy 335.255118 -44.876445) (xy 335.247175 -44.929149) (xy 335.231465 -44.980079)
			(xy 335.208339 -45.0281) (xy 335.178315 -45.072137) (xy 335.142063 -45.111208) (xy 335.100392 -45.144439)
			(xy 335.054234 -45.171088) (xy 335.00462 -45.19056) (xy 334.952658 -45.20242) (xy 334.899508 -45.206404)
			(xy 334.846358 -45.20242) (xy 334.794396 -45.19056) (xy 334.744782 -45.171088) (xy 334.698624 -45.144439)
			(xy 334.656953 -45.111208) (xy 334.620701 -45.072137) (xy 334.590677 -45.0281) (xy 334.567551 -44.980079)
			(xy 334.551841 -44.929149) (xy 334.543898 -44.876445) (xy 333.1718 -44.876445) (xy 333.1718 -46.648116)
			(xy 333.172212 -46.661547) (xy 333.179224 -46.687479) (xy 333.192758 -46.710683) (xy 333.211876 -46.729553)
			(xy 333.235256 -46.742783) (xy 333.261277 -46.749455) (xy 333.288137 -46.749108) (xy 333.313977 -46.741766)
			(xy 333.325724 -46.735238) (xy 333.34655 -46.723186) (xy 333.390757 -46.704186) (xy 333.437123 -46.691321)
			(xy 333.484799 -46.684827) (xy 333.508858 -46.684438) (xy 333.535508 -46.684908) (xy 333.588213 -46.692846)
			(xy 333.639146 -46.708552) (xy 333.687169 -46.731673) (xy 333.731209 -46.761695) (xy 333.770282 -46.797945)
			(xy 333.803516 -46.839615) (xy 333.830168 -46.885772) (xy 333.849642 -46.935387) (xy 333.861503 -46.98735)
			(xy 333.865486 -47.0405) (xy 333.861503 -47.09365) (xy 333.849642 -47.145613) (xy 333.830168 -47.195228)
			(xy 333.803516 -47.241385) (xy 333.770282 -47.283055) (xy 333.731209 -47.319305) (xy 333.687169 -47.349327)
			(xy 333.639146 -47.372448) (xy 333.588213 -47.388154) (xy 333.535508 -47.396092) (xy 333.508858 -47.396654)
			(xy 333.484802 -47.396237) (xy 333.437132 -47.389725) (xy 333.39077 -47.376865) (xy 333.346556 -47.357891)
			(xy 333.325724 -47.345854) (xy 333.313998 -47.339284) (xy 333.288153 -47.331933) (xy 333.261285 -47.331582)
			(xy 333.235257 -47.338258) (xy 333.211875 -47.351496) (xy 333.192758 -47.370379) (xy 333.179234 -47.393597)
			(xy 333.172239 -47.419541) (xy 333.1718 -47.432976) (xy 333.1718 -47.587662) (xy 333.172204 -47.601077)
			(xy 333.179192 -47.626981) (xy 333.192694 -47.650166) (xy 333.211776 -47.669027) (xy 333.235117 -47.682259)
			(xy 333.2611 -47.688945) (xy 333.287928 -47.688622) (xy 333.313744 -47.681314) (xy 333.32547 -47.674784)
			(xy 333.34628 -47.662787) (xy 333.390437 -47.64388) (xy 333.436735 -47.631079) (xy 333.484333 -47.624617)
			(xy 333.50835 -47.624238) (xy 333.535 -47.624708) (xy 333.587706 -47.632645) (xy 333.63864 -47.64835)
			(xy 333.686664 -47.671471) (xy 333.730705 -47.701492) (xy 333.76978 -47.737742) (xy 333.803014 -47.779412)
			(xy 333.829667 -47.82557) (xy 333.849141 -47.875185) (xy 333.861003 -47.927149) (xy 333.864986 -47.9803)
			(xy 333.861003 -48.033451) (xy 333.857181 -48.050196) (xy 334.5434 -48.050196) (xy 334.543934 -48.023136)
			(xy 334.552117 -47.969639) (xy 334.568308 -47.917998) (xy 334.592133 -47.869405) (xy 334.623044 -47.824981)
			(xy 334.660326 -47.785751) (xy 334.70312 -47.752621) (xy 334.726534 -47.739046) (xy 334.738141 -47.732043)
			(xy 334.757558 -47.713146) (xy 334.771319 -47.689807) (xy 334.778454 -47.663669) (xy 334.77846 -47.636575)
			(xy 334.771337 -47.610434) (xy 334.757586 -47.587089) (xy 334.738177 -47.568184) (xy 334.726534 -47.561246)
			(xy 334.703118 -47.547674) (xy 334.660325 -47.514541) (xy 334.623042 -47.47531) (xy 334.592129 -47.430887)
			(xy 334.568298 -47.382295) (xy 334.552099 -47.330655) (xy 334.543905 -47.277158) (xy 334.543905 -47.223038)
			(xy 334.5521 -47.169541) (xy 334.568299 -47.117901) (xy 334.592131 -47.06931) (xy 334.623045 -47.024887)
			(xy 334.660328 -46.985657) (xy 334.703121 -46.952524) (xy 334.726534 -46.938946) (xy 334.738141 -46.931943)
			(xy 334.757558 -46.913046) (xy 334.771319 -46.889707) (xy 334.778454 -46.863569) (xy 334.77846 -46.836475)
			(xy 334.771337 -46.810334) (xy 334.757586 -46.786989) (xy 334.738177 -46.768084) (xy 334.726534 -46.761146)
			(xy 334.703118 -46.747574) (xy 334.660325 -46.71444) (xy 334.623042 -46.675209) (xy 334.592129 -46.630786)
			(xy 334.568298 -46.582194) (xy 334.552099 -46.530554) (xy 334.543905 -46.477057) (xy 334.5434 -46.449996)
			(xy 334.543898 -46.423347) (xy 334.551841 -46.370643) (xy 334.567551 -46.319713) (xy 334.590677 -46.271692)
			(xy 334.620701 -46.227655) (xy 334.656953 -46.188584) (xy 334.698624 -46.155353) (xy 334.744782 -46.128704)
			(xy 334.794396 -46.109232) (xy 334.846358 -46.097372) (xy 334.899508 -46.093389) (xy 334.952658 -46.097372)
			(xy 335.00462 -46.109232) (xy 335.054234 -46.128704) (xy 335.100392 -46.155353) (xy 335.142063 -46.188584)
			(xy 335.178315 -46.227655) (xy 335.208339 -46.271692) (xy 335.231465 -46.319713) (xy 335.247175 -46.370643)
			(xy 335.255118 -46.423347) (xy 335.255616 -46.449996) (xy 335.255147 -46.477058) (xy 335.246951 -46.530558)
			(xy 335.230748 -46.5822) (xy 335.206912 -46.630793) (xy 335.175991 -46.675216) (xy 335.1387 -46.714444)
			(xy 335.095899 -46.747572) (xy 335.072482 -46.761146) (xy 335.060798 -46.768025) (xy 335.04139 -46.78695)
			(xy 335.02764 -46.810312) (xy 335.020518 -46.836468) (xy 335.020524 -46.863576) (xy 335.027658 -46.889729)
			(xy 335.041417 -46.913085) (xy 335.060834 -46.932002) (xy 335.072482 -46.938946) (xy 335.095896 -46.952526)
			(xy 335.138697 -46.985654) (xy 335.175988 -47.024881) (xy 335.206909 -47.069303) (xy 335.230746 -47.117895)
			(xy 335.24695 -47.169536) (xy 335.255147 -47.223036) (xy 335.255147 -47.250096) (xy 336.1436 -47.250096)
			(xy 336.144134 -47.223036) (xy 336.152317 -47.169539) (xy 336.168508 -47.117898) (xy 336.192333 -47.069305)
			(xy 336.223244 -47.024881) (xy 336.260526 -46.985651) (xy 336.30332 -46.952521) (xy 336.326734 -46.938946)
			(xy 336.338341 -46.931943) (xy 336.357758 -46.913046) (xy 336.371519 -46.889707) (xy 336.378654 -46.863569)
			(xy 336.37866 -46.836475) (xy 336.371537 -46.810334) (xy 336.357786 -46.786989) (xy 336.338377 -46.768084)
			(xy 336.326734 -46.761146) (xy 336.303318 -46.747574) (xy 336.260525 -46.714441) (xy 336.223242 -46.67521)
			(xy 336.192329 -46.630787) (xy 336.168498 -46.582195) (xy 336.152299 -46.530555) (xy 336.144105 -46.477058)
			(xy 336.144105 -46.422938) (xy 336.1523 -46.369441) (xy 336.168499 -46.317801) (xy 336.192331 -46.26921)
			(xy 336.223245 -46.224787) (xy 336.260528 -46.185557) (xy 336.303321 -46.152424) (xy 336.326734 -46.138846)
			(xy 336.338341 -46.131843) (xy 336.357758 -46.112946) (xy 336.371519 -46.089607) (xy 336.378654 -46.063469)
			(xy 336.37866 -46.036375) (xy 336.371537 -46.010234) (xy 336.357786 -45.986889) (xy 336.338377 -45.967984)
			(xy 336.326734 -45.961046) (xy 336.303318 -45.947474) (xy 336.260525 -45.91434) (xy 336.223242 -45.875109)
			(xy 336.192329 -45.830686) (xy 336.168498 -45.782094) (xy 336.152299 -45.730454) (xy 336.144105 -45.676957)
			(xy 336.1436 -45.649896) (xy 336.144098 -45.623247) (xy 336.152041 -45.570543) (xy 336.167751 -45.519613)
			(xy 336.190877 -45.471592) (xy 336.220901 -45.427555) (xy 336.257153 -45.388484) (xy 336.298824 -45.355253)
			(xy 336.344982 -45.328604) (xy 336.394596 -45.309132) (xy 336.446558 -45.297272) (xy 336.499708 -45.293289)
			(xy 336.552858 -45.297272) (xy 336.60482 -45.309132) (xy 336.654434 -45.328604) (xy 336.700592 -45.355253)
			(xy 336.742263 -45.388484) (xy 336.778515 -45.427555) (xy 336.808539 -45.471592) (xy 336.831665 -45.519613)
			(xy 336.847375 -45.570543) (xy 336.855318 -45.623247) (xy 336.855816 -45.649896) (xy 336.855347 -45.676958)
			(xy 336.847151 -45.730458) (xy 336.830948 -45.7821) (xy 336.807112 -45.830693) (xy 336.776191 -45.875116)
			(xy 336.7389 -45.914344) (xy 336.696099 -45.947472) (xy 336.672682 -45.961046) (xy 336.660998 -45.967925)
			(xy 336.64159 -45.98685) (xy 336.62784 -46.010212) (xy 336.620718 -46.036368) (xy 336.620724 -46.063476)
			(xy 336.627858 -46.089629) (xy 336.641617 -46.112985) (xy 336.661034 -46.131902) (xy 336.672682 -46.138846)
			(xy 336.694111 -46.151245) (xy 336.733632 -46.181065) (xy 336.768639 -46.216072) (xy 336.798458 -46.255593)
			(xy 336.810858 -46.277022) (xy 336.817799 -46.288668) (xy 336.83671 -46.308081) (xy 336.860061 -46.321836)
			(xy 336.886207 -46.328964) (xy 336.913309 -46.328964) (xy 336.939455 -46.321836) (xy 336.962806 -46.308081)
			(xy 336.981717 -46.288668) (xy 336.988658 -46.277022) (xy 337.002234 -46.253607) (xy 337.035364 -46.210809)
			(xy 337.074593 -46.173522) (xy 337.119016 -46.142605) (xy 337.167608 -46.11877) (xy 337.219248 -46.102569)
			(xy 337.272747 -46.094374) (xy 337.326869 -46.094374) (xy 337.380368 -46.102569) (xy 337.432008 -46.11877)
			(xy 337.4806 -46.142605) (xy 337.525023 -46.173522) (xy 337.564252 -46.210809) (xy 337.597382 -46.253607)
			(xy 337.610958 -46.277022) (xy 337.617899 -46.288668) (xy 337.63681 -46.308081) (xy 337.660161 -46.321836)
			(xy 337.686307 -46.328964) (xy 337.713409 -46.328964) (xy 337.739555 -46.321836) (xy 337.762906 -46.308081)
			(xy 337.781817 -46.288668) (xy 337.788758 -46.277022) (xy 337.801155 -46.255591) (xy 337.830975 -46.216071)
			(xy 337.865983 -46.181064) (xy 337.905505 -46.151246) (xy 337.926934 -46.138846) (xy 337.938541 -46.131843)
			(xy 337.957958 -46.112946) (xy 337.971719 -46.089607) (xy 337.978854 -46.063469) (xy 337.97886 -46.036375)
			(xy 337.971737 -46.010234) (xy 337.957986 -45.986889) (xy 337.938577 -45.967984) (xy 337.926934 -45.961046)
			(xy 337.903518 -45.947474) (xy 337.860725 -45.914341) (xy 337.823442 -45.87511) (xy 337.792529 -45.830687)
			(xy 337.768698 -45.782095) (xy 337.752499 -45.730455) (xy 337.744305 -45.676958) (xy 337.744305 -45.622838)
			(xy 337.7525 -45.569341) (xy 337.768699 -45.517701) (xy 337.792531 -45.46911) (xy 337.823445 -45.424687)
			(xy 337.860728 -45.385457) (xy 337.903521 -45.352324) (xy 337.926934 -45.338746) (xy 337.938541 -45.331743)
			(xy 337.957958 -45.312846) (xy 337.971719 -45.289507) (xy 337.978854 -45.263369) (xy 337.97886 -45.236275)
			(xy 337.971737 -45.210134) (xy 337.957986 -45.186789) (xy 337.938577 -45.167884) (xy 337.926934 -45.160946)
			(xy 337.903518 -45.147374) (xy 337.860725 -45.11424) (xy 337.823442 -45.075009) (xy 337.792529 -45.030586)
			(xy 337.768698 -44.981994) (xy 337.752499 -44.930354) (xy 337.744305 -44.876857) (xy 337.7438 -44.849796)
			(xy 337.744202 -44.824014) (xy 337.751626 -44.772988) (xy 337.766333 -44.723567) (xy 337.788015 -44.676784)
			(xy 337.816219 -44.633618) (xy 337.850354 -44.594971) (xy 337.889707 -44.561653) (xy 337.933455 -44.53436)
			(xy 337.980682 -44.513663) (xy 338.00542 -44.506388) (xy 338.019354 -44.501969) (xy 338.044162 -44.486539)
			(xy 338.063596 -44.464725) (xy 338.076069 -44.438307) (xy 338.080564 -44.40944) (xy 338.076714 -44.38048)
			(xy 338.071206 -44.366942) (xy 338.061319 -44.343924) (xy 338.047408 -44.295797) (xy 338.040388 -44.246194)
			(xy 338.039964 -44.221146) (xy 338.040462 -44.194497) (xy 338.048405 -44.141793) (xy 338.064115 -44.090863)
			(xy 338.087241 -44.042842) (xy 338.117265 -43.998805) (xy 338.153517 -43.959734) (xy 338.195188 -43.926503)
			(xy 338.241346 -43.899854) (xy 338.29096 -43.880382) (xy 338.342922 -43.868522) (xy 338.396072 -43.864539)
			(xy 338.449222 -43.868522) (xy 338.501184 -43.880382) (xy 338.550798 -43.899854) (xy 338.596956 -43.926503)
			(xy 338.638627 -43.959734) (xy 338.674879 -43.998805) (xy 338.704903 -44.042842) (xy 338.728029 -44.090863)
			(xy 338.743739 -44.141793) (xy 338.751682 -44.194497) (xy 338.75218 -44.221146) (xy 338.751786 -44.244942)
			(xy 338.751437 -44.247541) (xy 342.379544 -44.247541) (xy 342.379544 -44.194243) (xy 342.387487 -44.141539)
			(xy 342.403197 -44.090609) (xy 342.426323 -44.042588) (xy 342.456347 -43.998551) (xy 342.492599 -43.95948)
			(xy 342.53427 -43.926249) (xy 342.580428 -43.8996) (xy 342.630042 -43.880128) (xy 342.682004 -43.868268)
			(xy 342.735154 -43.864285) (xy 342.788304 -43.868268) (xy 342.840266 -43.880128) (xy 342.88988 -43.8996)
			(xy 342.936038 -43.926249) (xy 342.977709 -43.95948) (xy 343.013961 -43.998551) (xy 343.043985 -44.042588)
			(xy 343.067111 -44.090609) (xy 343.082821 -44.141539) (xy 343.090764 -44.194243) (xy 343.091262 -44.220892)
			(xy 343.090764 -44.247541) (xy 343.082821 -44.300245) (xy 343.067111 -44.351175) (xy 343.043985 -44.399196)
			(xy 343.013961 -44.443233) (xy 342.977709 -44.482304) (xy 342.936038 -44.515535) (xy 342.88988 -44.542184)
			(xy 342.840266 -44.561656) (xy 342.788304 -44.573516) (xy 342.735154 -44.5775) (xy 342.682004 -44.573516)
			(xy 342.630042 -44.561656) (xy 342.580428 -44.542184) (xy 342.53427 -44.515535) (xy 342.492599 -44.482304)
			(xy 342.456347 -44.443233) (xy 342.426323 -44.399196) (xy 342.403197 -44.351175) (xy 342.387487 -44.300245)
			(xy 342.379544 -44.247541) (xy 338.751437 -44.247541) (xy 338.745456 -44.292111) (xy 338.7329 -44.338017)
			(xy 338.723986 -44.360084) (xy 338.719131 -44.372878) (xy 338.71554 -44.399989) (xy 338.719284 -44.42708)
			(xy 338.730095 -44.452201) (xy 338.747194 -44.473545) (xy 338.769351 -44.489576) (xy 338.794973 -44.499141)
			(xy 338.822215 -44.501552) (xy 338.835746 -44.49953) (xy 338.85167 -44.496792) (xy 338.883851 -44.493869)
			(xy 338.900008 -44.493688) (xy 338.926657 -44.494194) (xy 338.979358 -44.502139) (xy 339.030288 -44.517849)
			(xy 339.078306 -44.540975) (xy 339.122342 -44.570999) (xy 339.161411 -44.607251) (xy 339.194641 -44.648921)
			(xy 339.22129 -44.695078) (xy 339.238041 -44.737761) (xy 339.894662 -44.737761) (xy 339.894662 -44.684463)
			(xy 339.902605 -44.631759) (xy 339.918315 -44.580829) (xy 339.941441 -44.532808) (xy 339.971465 -44.488771)
			(xy 340.007717 -44.4497) (xy 340.049388 -44.416469) (xy 340.095546 -44.38982) (xy 340.14516 -44.370348)
			(xy 340.197122 -44.358488) (xy 340.250272 -44.354505) (xy 340.303422 -44.358488) (xy 340.355384 -44.370348)
			(xy 340.404998 -44.38982) (xy 340.451156 -44.416469) (xy 340.492827 -44.4497) (xy 340.529079 -44.488771)
			(xy 340.559103 -44.532808) (xy 340.582229 -44.580829) (xy 340.597939 -44.631759) (xy 340.605882 -44.684463)
			(xy 340.60638 -44.711112) (xy 340.606257 -44.717695) (xy 341.563188 -44.717695) (xy 341.563188 -44.664397)
			(xy 341.571131 -44.611693) (xy 341.586841 -44.560763) (xy 341.609967 -44.512742) (xy 341.639991 -44.468705)
			(xy 341.676243 -44.429634) (xy 341.717914 -44.396403) (xy 341.764072 -44.369754) (xy 341.813686 -44.350282)
			(xy 341.865648 -44.338422) (xy 341.918798 -44.334439) (xy 341.971948 -44.338422) (xy 342.02391 -44.350282)
			(xy 342.073524 -44.369754) (xy 342.119682 -44.396403) (xy 342.161353 -44.429634) (xy 342.197605 -44.468705)
			(xy 342.227629 -44.512742) (xy 342.250755 -44.560763) (xy 342.266465 -44.611693) (xy 342.274408 -44.664397)
			(xy 342.274906 -44.691046) (xy 342.274413 -44.717441) (xy 343.193868 -44.717441) (xy 343.193868 -44.664143)
			(xy 343.201811 -44.611439) (xy 343.217521 -44.560509) (xy 343.240647 -44.512488) (xy 343.270671 -44.468451)
			(xy 343.306923 -44.42938) (xy 343.348594 -44.396149) (xy 343.394752 -44.3695) (xy 343.444366 -44.350028)
			(xy 343.496328 -44.338168) (xy 343.549478 -44.334185) (xy 343.602628 -44.338168) (xy 343.65459 -44.350028)
			(xy 343.704204 -44.3695) (xy 343.750362 -44.396149) (xy 343.792033 -44.42938) (xy 343.828285 -44.468451)
			(xy 343.858309 -44.512488) (xy 343.881435 -44.560509) (xy 343.897145 -44.611439) (xy 343.905088 -44.664143)
			(xy 343.905586 -44.690792) (xy 343.905088 -44.717441) (xy 343.897145 -44.770145) (xy 343.881435 -44.821075)
			(xy 343.858309 -44.869096) (xy 343.828285 -44.913133) (xy 343.792033 -44.952204) (xy 343.750362 -44.985435)
			(xy 343.704204 -45.012084) (xy 343.65459 -45.031556) (xy 343.602628 -45.043416) (xy 343.549478 -45.0474)
			(xy 343.496328 -45.043416) (xy 343.444366 -45.031556) (xy 343.394752 -45.012084) (xy 343.348594 -44.985435)
			(xy 343.306923 -44.952204) (xy 343.270671 -44.913133) (xy 343.240647 -44.869096) (xy 343.217521 -44.821075)
			(xy 343.201811 -44.770145) (xy 343.193868 -44.717441) (xy 342.274413 -44.717441) (xy 342.274408 -44.717695)
			(xy 342.266465 -44.770399) (xy 342.250755 -44.821329) (xy 342.227629 -44.86935) (xy 342.197605 -44.913387)
			(xy 342.161353 -44.952458) (xy 342.119682 -44.985689) (xy 342.073524 -45.012338) (xy 342.02391 -45.03181)
			(xy 341.971948 -45.04367) (xy 341.918798 -45.047654) (xy 341.865648 -45.04367) (xy 341.813686 -45.03181)
			(xy 341.764072 -45.012338) (xy 341.717914 -44.985689) (xy 341.676243 -44.952458) (xy 341.639991 -44.913387)
			(xy 341.609967 -44.86935) (xy 341.586841 -44.821329) (xy 341.571131 -44.770399) (xy 341.563188 -44.717695)
			(xy 340.606257 -44.717695) (xy 340.605882 -44.737761) (xy 340.597939 -44.790465) (xy 340.582229 -44.841395)
			(xy 340.559103 -44.889416) (xy 340.529079 -44.933453) (xy 340.492827 -44.972524) (xy 340.451156 -45.005755)
			(xy 340.404998 -45.032404) (xy 340.355384 -45.051876) (xy 340.303422 -45.063736) (xy 340.250272 -45.06772)
			(xy 340.197122 -45.063736) (xy 340.14516 -45.051876) (xy 340.095546 -45.032404) (xy 340.049388 -45.005755)
			(xy 340.007717 -44.972524) (xy 339.971465 -44.933453) (xy 339.941441 -44.889416) (xy 339.918315 -44.841395)
			(xy 339.902605 -44.790465) (xy 339.894662 -44.737761) (xy 339.238041 -44.737761) (xy 339.240761 -44.744691)
			(xy 339.252621 -44.796652) (xy 339.256604 -44.8498) (xy 339.252621 -44.902948) (xy 339.240761 -44.954909)
			(xy 339.22129 -45.004522) (xy 339.194641 -45.050679) (xy 339.161411 -45.092349) (xy 339.122342 -45.128601)
			(xy 339.078306 -45.158625) (xy 339.030288 -45.181751) (xy 339.011342 -45.187595) (xy 340.750388 -45.187595)
			(xy 340.750388 -45.134297) (xy 340.758331 -45.081593) (xy 340.774041 -45.030663) (xy 340.797167 -44.982642)
			(xy 340.827191 -44.938605) (xy 340.863443 -44.899534) (xy 340.905114 -44.866303) (xy 340.951272 -44.839654)
			(xy 341.000886 -44.820182) (xy 341.052848 -44.808322) (xy 341.105998 -44.804339) (xy 341.159148 -44.808322)
			(xy 341.21111 -44.820182) (xy 341.260724 -44.839654) (xy 341.306882 -44.866303) (xy 341.348553 -44.899534)
			(xy 341.384805 -44.938605) (xy 341.414829 -44.982642) (xy 341.437955 -45.030663) (xy 341.453665 -45.081593)
			(xy 341.461608 -45.134297) (xy 341.462106 -45.160946) (xy 341.461613 -45.187341) (xy 342.379544 -45.187341)
			(xy 342.379544 -45.134043) (xy 342.387487 -45.081339) (xy 342.403197 -45.030409) (xy 342.426323 -44.982388)
			(xy 342.456347 -44.938351) (xy 342.492599 -44.89928) (xy 342.53427 -44.866049) (xy 342.580428 -44.8394)
			(xy 342.630042 -44.819928) (xy 342.682004 -44.808068) (xy 342.735154 -44.804085) (xy 342.788304 -44.808068)
			(xy 342.840266 -44.819928) (xy 342.88988 -44.8394) (xy 342.936038 -44.866049) (xy 342.977709 -44.89928)
			(xy 343.013961 -44.938351) (xy 343.043985 -44.982388) (xy 343.067111 -45.030409) (xy 343.082821 -45.081339)
			(xy 343.090764 -45.134043) (xy 343.091262 -45.160692) (xy 343.090764 -45.187341) (xy 343.082821 -45.240045)
			(xy 343.067111 -45.290975) (xy 343.043985 -45.338996) (xy 343.013961 -45.383033) (xy 342.977709 -45.422104)
			(xy 342.936038 -45.455335) (xy 342.88988 -45.481984) (xy 342.840266 -45.501456) (xy 342.788304 -45.513316)
			(xy 342.735154 -45.5173) (xy 342.682004 -45.513316) (xy 342.630042 -45.501456) (xy 342.580428 -45.481984)
			(xy 342.53427 -45.455335) (xy 342.492599 -45.422104) (xy 342.456347 -45.383033) (xy 342.426323 -45.338996)
			(xy 342.403197 -45.290975) (xy 342.387487 -45.240045) (xy 342.379544 -45.187341) (xy 341.461613 -45.187341)
			(xy 341.461608 -45.187595) (xy 341.453665 -45.240299) (xy 341.437955 -45.291229) (xy 341.414829 -45.33925)
			(xy 341.384805 -45.383287) (xy 341.348553 -45.422358) (xy 341.306882 -45.455589) (xy 341.260724 -45.482238)
			(xy 341.21111 -45.50171) (xy 341.159148 -45.51357) (xy 341.105998 -45.517554) (xy 341.052848 -45.51357)
			(xy 341.000886 -45.50171) (xy 340.951272 -45.482238) (xy 340.905114 -45.455589) (xy 340.863443 -45.422358)
			(xy 340.827191 -45.383287) (xy 340.797167 -45.33925) (xy 340.774041 -45.291229) (xy 340.758331 -45.240299)
			(xy 340.750388 -45.187595) (xy 339.011342 -45.187595) (xy 338.979358 -45.197461) (xy 338.926657 -45.205406)
			(xy 338.900008 -45.205904) (xy 338.872946 -45.205438) (xy 338.819445 -45.197243) (xy 338.767803 -45.18104)
			(xy 338.71921 -45.157203) (xy 338.674787 -45.126282) (xy 338.635559 -45.08899) (xy 338.602432 -45.046187)
			(xy 338.588858 -45.02277) (xy 338.581917 -45.011124) (xy 338.563006 -44.991711) (xy 338.539655 -44.977956)
			(xy 338.513509 -44.970828) (xy 338.486407 -44.970828) (xy 338.460261 -44.977956) (xy 338.43691 -44.991711)
			(xy 338.417999 -45.011124) (xy 338.411058 -45.02277) (xy 338.398654 -45.044196) (xy 338.368836 -45.083717)
			(xy 338.33383 -45.118726) (xy 338.29431 -45.148545) (xy 338.272882 -45.160946) (xy 338.261198 -45.167825)
			(xy 338.24179 -45.18675) (xy 338.22804 -45.210112) (xy 338.220918 -45.236268) (xy 338.220924 -45.263376)
			(xy 338.228058 -45.289529) (xy 338.241817 -45.312885) (xy 338.261234 -45.331802) (xy 338.272882 -45.338746)
			(xy 338.296296 -45.352326) (xy 338.339097 -45.385454) (xy 338.376388 -45.424681) (xy 338.407309 -45.469103)
			(xy 338.431146 -45.517695) (xy 338.44735 -45.569336) (xy 338.455547 -45.622836) (xy 338.455547 -45.657495)
			(xy 339.935048 -45.657495) (xy 339.935048 -45.604197) (xy 339.942991 -45.551493) (xy 339.958701 -45.500563)
			(xy 339.981827 -45.452542) (xy 340.011851 -45.408505) (xy 340.048103 -45.369434) (xy 340.089774 -45.336203)
			(xy 340.135932 -45.309554) (xy 340.185546 -45.290082) (xy 340.237508 -45.278222) (xy 340.290658 -45.274239)
			(xy 340.343808 -45.278222) (xy 340.39577 -45.290082) (xy 340.445384 -45.309554) (xy 340.491542 -45.336203)
			(xy 340.533213 -45.369434) (xy 340.569465 -45.408505) (xy 340.599489 -45.452542) (xy 340.622615 -45.500563)
			(xy 340.638325 -45.551493) (xy 340.646268 -45.604197) (xy 340.646766 -45.630846) (xy 340.646268 -45.657495)
			(xy 341.563188 -45.657495) (xy 341.563188 -45.604197) (xy 341.571131 -45.551493) (xy 341.586841 -45.500563)
			(xy 341.609967 -45.452542) (xy 341.639991 -45.408505) (xy 341.676243 -45.369434) (xy 341.717914 -45.336203)
			(xy 341.764072 -45.309554) (xy 341.813686 -45.290082) (xy 341.865648 -45.278222) (xy 341.918798 -45.274239)
			(xy 341.971948 -45.278222) (xy 342.02391 -45.290082) (xy 342.073524 -45.309554) (xy 342.119682 -45.336203)
			(xy 342.161353 -45.369434) (xy 342.197605 -45.408505) (xy 342.227629 -45.452542) (xy 342.250755 -45.500563)
			(xy 342.266465 -45.551493) (xy 342.274408 -45.604197) (xy 342.274906 -45.630846) (xy 342.274413 -45.657241)
			(xy 343.193868 -45.657241) (xy 343.193868 -45.603943) (xy 343.201811 -45.551239) (xy 343.217521 -45.500309)
			(xy 343.240647 -45.452288) (xy 343.270671 -45.408251) (xy 343.306923 -45.36918) (xy 343.348594 -45.335949)
			(xy 343.394752 -45.3093) (xy 343.444366 -45.289828) (xy 343.496328 -45.277968) (xy 343.549478 -45.273985)
			(xy 343.602628 -45.277968) (xy 343.65459 -45.289828) (xy 343.704204 -45.3093) (xy 343.750362 -45.335949)
			(xy 343.792033 -45.36918) (xy 343.828285 -45.408251) (xy 343.858309 -45.452288) (xy 343.881435 -45.500309)
			(xy 343.897145 -45.551239) (xy 343.905088 -45.603943) (xy 343.905586 -45.630592) (xy 343.905088 -45.657241)
			(xy 343.897145 -45.709945) (xy 343.881435 -45.760875) (xy 343.858309 -45.808896) (xy 343.828285 -45.852933)
			(xy 343.792033 -45.892004) (xy 343.750362 -45.925235) (xy 343.704204 -45.951884) (xy 343.65459 -45.971356)
			(xy 343.602628 -45.983216) (xy 343.549478 -45.9872) (xy 343.496328 -45.983216) (xy 343.444366 -45.971356)
			(xy 343.394752 -45.951884) (xy 343.348594 -45.925235) (xy 343.306923 -45.892004) (xy 343.270671 -45.852933)
			(xy 343.240647 -45.808896) (xy 343.217521 -45.760875) (xy 343.201811 -45.709945) (xy 343.193868 -45.657241)
			(xy 342.274413 -45.657241) (xy 342.274408 -45.657495) (xy 342.266465 -45.710199) (xy 342.250755 -45.761129)
			(xy 342.227629 -45.80915) (xy 342.197605 -45.853187) (xy 342.161353 -45.892258) (xy 342.119682 -45.925489)
			(xy 342.073524 -45.952138) (xy 342.02391 -45.97161) (xy 341.971948 -45.98347) (xy 341.918798 -45.987454)
			(xy 341.865648 -45.98347) (xy 341.813686 -45.97161) (xy 341.764072 -45.952138) (xy 341.717914 -45.925489)
			(xy 341.676243 -45.892258) (xy 341.639991 -45.853187) (xy 341.609967 -45.80915) (xy 341.586841 -45.761129)
			(xy 341.571131 -45.710199) (xy 341.563188 -45.657495) (xy 340.646268 -45.657495) (xy 340.638325 -45.710199)
			(xy 340.622615 -45.761129) (xy 340.599489 -45.80915) (xy 340.569465 -45.853187) (xy 340.533213 -45.892258)
			(xy 340.491542 -45.925489) (xy 340.445384 -45.952138) (xy 340.39577 -45.97161) (xy 340.343808 -45.98347)
			(xy 340.290658 -45.987454) (xy 340.237508 -45.98347) (xy 340.185546 -45.97161) (xy 340.135932 -45.952138)
			(xy 340.089774 -45.925489) (xy 340.048103 -45.892258) (xy 340.011851 -45.853187) (xy 339.981827 -45.80915)
			(xy 339.958701 -45.761129) (xy 339.942991 -45.710199) (xy 339.935048 -45.657495) (xy 338.455547 -45.657495)
			(xy 338.455547 -45.67696) (xy 338.447351 -45.73046) (xy 338.431148 -45.782102) (xy 338.407311 -45.830694)
			(xy 338.376391 -45.875116) (xy 338.3391 -45.914344) (xy 338.296299 -45.947472) (xy 338.272882 -45.961046)
			(xy 338.261198 -45.967925) (xy 338.24179 -45.98685) (xy 338.22804 -46.010212) (xy 338.220918 -46.036368)
			(xy 338.220924 -46.063476) (xy 338.228058 -46.089629) (xy 338.241817 -46.112985) (xy 338.256608 -46.127395)
			(xy 340.750388 -46.127395) (xy 340.750388 -46.074097) (xy 340.758331 -46.021393) (xy 340.774041 -45.970463)
			(xy 340.797167 -45.922442) (xy 340.827191 -45.878405) (xy 340.863443 -45.839334) (xy 340.905114 -45.806103)
			(xy 340.951272 -45.779454) (xy 341.000886 -45.759982) (xy 341.052848 -45.748122) (xy 341.105998 -45.744139)
			(xy 341.159148 -45.748122) (xy 341.21111 -45.759982) (xy 341.260724 -45.779454) (xy 341.306882 -45.806103)
			(xy 341.348553 -45.839334) (xy 341.384805 -45.878405) (xy 341.414829 -45.922442) (xy 341.437955 -45.970463)
			(xy 341.453665 -46.021393) (xy 341.461608 -46.074097) (xy 341.462106 -46.100746) (xy 341.461613 -46.127141)
			(xy 342.379544 -46.127141) (xy 342.379544 -46.073843) (xy 342.387487 -46.021139) (xy 342.403197 -45.970209)
			(xy 342.426323 -45.922188) (xy 342.456347 -45.878151) (xy 342.492599 -45.83908) (xy 342.53427 -45.805849)
			(xy 342.580428 -45.7792) (xy 342.630042 -45.759728) (xy 342.682004 -45.747868) (xy 342.735154 -45.743885)
			(xy 342.788304 -45.747868) (xy 342.840266 -45.759728) (xy 342.88988 -45.7792) (xy 342.936038 -45.805849)
			(xy 342.977709 -45.83908) (xy 343.013961 -45.878151) (xy 343.043985 -45.922188) (xy 343.067111 -45.970209)
			(xy 343.082821 -46.021139) (xy 343.090764 -46.073843) (xy 343.091262 -46.100492) (xy 343.090764 -46.127141)
			(xy 344.007684 -46.127141) (xy 344.007684 -46.073843) (xy 344.015627 -46.021139) (xy 344.031337 -45.970209)
			(xy 344.054463 -45.922188) (xy 344.084487 -45.878151) (xy 344.120739 -45.83908) (xy 344.16241 -45.805849)
			(xy 344.208568 -45.7792) (xy 344.258182 -45.759728) (xy 344.310144 -45.747868) (xy 344.363294 -45.743885)
			(xy 344.416444 -45.747868) (xy 344.468406 -45.759728) (xy 344.51802 -45.7792) (xy 344.564178 -45.805849)
			(xy 344.605849 -45.83908) (xy 344.642101 -45.878151) (xy 344.672125 -45.922188) (xy 344.695251 -45.970209)
			(xy 344.710961 -46.021139) (xy 344.718904 -46.073843) (xy 344.719402 -46.100492) (xy 344.718904 -46.127141)
			(xy 344.710961 -46.179845) (xy 344.695251 -46.230775) (xy 344.672125 -46.278796) (xy 344.642101 -46.322833)
			(xy 344.605849 -46.361904) (xy 344.564178 -46.395135) (xy 344.51802 -46.421784) (xy 344.468406 -46.441256)
			(xy 344.416444 -46.453116) (xy 344.363294 -46.4571) (xy 344.310144 -46.453116) (xy 344.258182 -46.441256)
			(xy 344.208568 -46.421784) (xy 344.16241 -46.395135) (xy 344.120739 -46.361904) (xy 344.084487 -46.322833)
			(xy 344.054463 -46.278796) (xy 344.031337 -46.230775) (xy 344.015627 -46.179845) (xy 344.007684 -46.127141)
			(xy 343.090764 -46.127141) (xy 343.082821 -46.179845) (xy 343.067111 -46.230775) (xy 343.043985 -46.278796)
			(xy 343.013961 -46.322833) (xy 342.977709 -46.361904) (xy 342.936038 -46.395135) (xy 342.88988 -46.421784)
			(xy 342.840266 -46.441256) (xy 342.788304 -46.453116) (xy 342.735154 -46.4571) (xy 342.682004 -46.453116)
			(xy 342.630042 -46.441256) (xy 342.580428 -46.421784) (xy 342.53427 -46.395135) (xy 342.492599 -46.361904)
			(xy 342.456347 -46.322833) (xy 342.426323 -46.278796) (xy 342.403197 -46.230775) (xy 342.387487 -46.179845)
			(xy 342.379544 -46.127141) (xy 341.461613 -46.127141) (xy 341.461608 -46.127395) (xy 341.453665 -46.180099)
			(xy 341.437955 -46.231029) (xy 341.414829 -46.27905) (xy 341.384805 -46.323087) (xy 341.348553 -46.362158)
			(xy 341.306882 -46.395389) (xy 341.260724 -46.422038) (xy 341.21111 -46.44151) (xy 341.159148 -46.45337)
			(xy 341.105998 -46.457354) (xy 341.052848 -46.45337) (xy 341.000886 -46.44151) (xy 340.951272 -46.422038)
			(xy 340.905114 -46.395389) (xy 340.863443 -46.362158) (xy 340.827191 -46.323087) (xy 340.797167 -46.27905)
			(xy 340.774041 -46.231029) (xy 340.758331 -46.180099) (xy 340.750388 -46.127395) (xy 338.256608 -46.127395)
			(xy 338.261234 -46.131902) (xy 338.272882 -46.138846) (xy 338.296296 -46.152426) (xy 338.339097 -46.185554)
			(xy 338.376388 -46.224781) (xy 338.407309 -46.269203) (xy 338.431146 -46.317795) (xy 338.44735 -46.369436)
			(xy 338.455547 -46.422936) (xy 338.455547 -46.47706) (xy 338.447351 -46.53056) (xy 338.431148 -46.582202)
			(xy 338.423744 -46.597295) (xy 339.935048 -46.597295) (xy 339.935048 -46.543997) (xy 339.942991 -46.491293)
			(xy 339.958701 -46.440363) (xy 339.981827 -46.392342) (xy 340.011851 -46.348305) (xy 340.048103 -46.309234)
			(xy 340.089774 -46.276003) (xy 340.135932 -46.249354) (xy 340.185546 -46.229882) (xy 340.237508 -46.218022)
			(xy 340.290658 -46.214039) (xy 340.343808 -46.218022) (xy 340.39577 -46.229882) (xy 340.445384 -46.249354)
			(xy 340.491542 -46.276003) (xy 340.533213 -46.309234) (xy 340.569465 -46.348305) (xy 340.599489 -46.392342)
			(xy 340.622615 -46.440363) (xy 340.638325 -46.491293) (xy 340.646268 -46.543997) (xy 340.646766 -46.570646)
			(xy 340.646268 -46.597295) (xy 341.563188 -46.597295) (xy 341.563188 -46.543997) (xy 341.571131 -46.491293)
			(xy 341.586841 -46.440363) (xy 341.609967 -46.392342) (xy 341.639991 -46.348305) (xy 341.676243 -46.309234)
			(xy 341.717914 -46.276003) (xy 341.764072 -46.249354) (xy 341.813686 -46.229882) (xy 341.865648 -46.218022)
			(xy 341.918798 -46.214039) (xy 341.971948 -46.218022) (xy 342.02391 -46.229882) (xy 342.073524 -46.249354)
			(xy 342.119682 -46.276003) (xy 342.161353 -46.309234) (xy 342.197605 -46.348305) (xy 342.227629 -46.392342)
			(xy 342.250755 -46.440363) (xy 342.266465 -46.491293) (xy 342.274408 -46.543997) (xy 342.274906 -46.570646)
			(xy 342.274413 -46.597041) (xy 343.193868 -46.597041) (xy 343.193868 -46.543743) (xy 343.201811 -46.491039)
			(xy 343.217521 -46.440109) (xy 343.240647 -46.392088) (xy 343.270671 -46.348051) (xy 343.306923 -46.30898)
			(xy 343.348594 -46.275749) (xy 343.394752 -46.2491) (xy 343.444366 -46.229628) (xy 343.496328 -46.217768)
			(xy 343.549478 -46.213785) (xy 343.602628 -46.217768) (xy 343.65459 -46.229628) (xy 343.704204 -46.2491)
			(xy 343.750362 -46.275749) (xy 343.792033 -46.30898) (xy 343.828285 -46.348051) (xy 343.858309 -46.392088)
			(xy 343.881435 -46.440109) (xy 343.897145 -46.491039) (xy 343.905088 -46.543743) (xy 343.905586 -46.570392)
			(xy 343.905088 -46.597041) (xy 343.897145 -46.649745) (xy 343.881435 -46.700675) (xy 343.858309 -46.748696)
			(xy 343.828285 -46.792733) (xy 343.792033 -46.831804) (xy 343.750362 -46.865035) (xy 343.704204 -46.891684)
			(xy 343.65459 -46.911156) (xy 343.602628 -46.923016) (xy 343.549478 -46.927) (xy 343.496328 -46.923016)
			(xy 343.444366 -46.911156) (xy 343.394752 -46.891684) (xy 343.348594 -46.865035) (xy 343.306923 -46.831804)
			(xy 343.270671 -46.792733) (xy 343.240647 -46.748696) (xy 343.217521 -46.700675) (xy 343.201811 -46.649745)
			(xy 343.193868 -46.597041) (xy 342.274413 -46.597041) (xy 342.274408 -46.597295) (xy 342.266465 -46.649999)
			(xy 342.250755 -46.700929) (xy 342.227629 -46.74895) (xy 342.197605 -46.792987) (xy 342.161353 -46.832058)
			(xy 342.119682 -46.865289) (xy 342.073524 -46.891938) (xy 342.02391 -46.91141) (xy 341.971948 -46.92327)
			(xy 341.918798 -46.927254) (xy 341.865648 -46.92327) (xy 341.813686 -46.91141) (xy 341.764072 -46.891938)
			(xy 341.717914 -46.865289) (xy 341.676243 -46.832058) (xy 341.639991 -46.792987) (xy 341.609967 -46.74895)
			(xy 341.586841 -46.700929) (xy 341.571131 -46.649999) (xy 341.563188 -46.597295) (xy 340.646268 -46.597295)
			(xy 340.638325 -46.649999) (xy 340.622615 -46.700929) (xy 340.599489 -46.74895) (xy 340.569465 -46.792987)
			(xy 340.533213 -46.832058) (xy 340.491542 -46.865289) (xy 340.445384 -46.891938) (xy 340.39577 -46.91141)
			(xy 340.343808 -46.92327) (xy 340.290658 -46.927254) (xy 340.237508 -46.92327) (xy 340.185546 -46.91141)
			(xy 340.135932 -46.891938) (xy 340.089774 -46.865289) (xy 340.048103 -46.832058) (xy 340.011851 -46.792987)
			(xy 339.981827 -46.74895) (xy 339.958701 -46.700929) (xy 339.942991 -46.649999) (xy 339.935048 -46.597295)
			(xy 338.423744 -46.597295) (xy 338.407311 -46.630794) (xy 338.376391 -46.675216) (xy 338.3391 -46.714444)
			(xy 338.296299 -46.747572) (xy 338.272882 -46.761146) (xy 338.261198 -46.768025) (xy 338.24179 -46.78695)
			(xy 338.22804 -46.810312) (xy 338.220918 -46.836468) (xy 338.220924 -46.863576) (xy 338.228058 -46.889729)
			(xy 338.241817 -46.913085) (xy 338.261234 -46.932002) (xy 338.272882 -46.938946) (xy 338.296296 -46.952526)
			(xy 338.339097 -46.985654) (xy 338.376388 -47.024881) (xy 338.405842 -47.067195) (xy 340.750388 -47.067195)
			(xy 340.750388 -47.013897) (xy 340.758331 -46.961193) (xy 340.774041 -46.910263) (xy 340.797167 -46.862242)
			(xy 340.827191 -46.818205) (xy 340.863443 -46.779134) (xy 340.905114 -46.745903) (xy 340.951272 -46.719254)
			(xy 341.000886 -46.699782) (xy 341.052848 -46.687922) (xy 341.105998 -46.683939) (xy 341.159148 -46.687922)
			(xy 341.21111 -46.699782) (xy 341.260724 -46.719254) (xy 341.306882 -46.745903) (xy 341.348553 -46.779134)
			(xy 341.384805 -46.818205) (xy 341.414829 -46.862242) (xy 341.437955 -46.910263) (xy 341.453665 -46.961193)
			(xy 341.461608 -47.013897) (xy 341.462106 -47.040546) (xy 341.461613 -47.066941) (xy 342.379544 -47.066941)
			(xy 342.379544 -47.013643) (xy 342.387487 -46.960939) (xy 342.403197 -46.910009) (xy 342.426323 -46.861988)
			(xy 342.456347 -46.817951) (xy 342.492599 -46.77888) (xy 342.53427 -46.745649) (xy 342.580428 -46.719)
			(xy 342.630042 -46.699528) (xy 342.682004 -46.687668) (xy 342.735154 -46.683685) (xy 342.788304 -46.687668)
			(xy 342.840266 -46.699528) (xy 342.88988 -46.719) (xy 342.936038 -46.745649) (xy 342.977709 -46.77888)
			(xy 343.013961 -46.817951) (xy 343.043985 -46.861988) (xy 343.067111 -46.910009) (xy 343.082821 -46.960939)
			(xy 343.090764 -47.013643) (xy 343.091262 -47.040292) (xy 343.090764 -47.066941) (xy 344.007684 -47.066941)
			(xy 344.007684 -47.013643) (xy 344.015627 -46.960939) (xy 344.031337 -46.910009) (xy 344.054463 -46.861988)
			(xy 344.084487 -46.817951) (xy 344.120739 -46.77888) (xy 344.16241 -46.745649) (xy 344.208568 -46.719)
			(xy 344.258182 -46.699528) (xy 344.310144 -46.687668) (xy 344.363294 -46.683685) (xy 344.416444 -46.687668)
			(xy 344.468406 -46.699528) (xy 344.51802 -46.719) (xy 344.564178 -46.745649) (xy 344.605849 -46.77888)
			(xy 344.642101 -46.817951) (xy 344.672125 -46.861988) (xy 344.695251 -46.910009) (xy 344.710961 -46.960939)
			(xy 344.718904 -47.013643) (xy 344.719402 -47.040292) (xy 344.718904 -47.066941) (xy 344.710961 -47.119645)
			(xy 344.695251 -47.170575) (xy 344.672125 -47.218596) (xy 344.642101 -47.262633) (xy 344.605849 -47.301704)
			(xy 344.564178 -47.334935) (xy 344.51802 -47.361584) (xy 344.468406 -47.381056) (xy 344.416444 -47.392916)
			(xy 344.363294 -47.3969) (xy 344.310144 -47.392916) (xy 344.258182 -47.381056) (xy 344.208568 -47.361584)
			(xy 344.16241 -47.334935) (xy 344.120739 -47.301704) (xy 344.084487 -47.262633) (xy 344.054463 -47.218596)
			(xy 344.031337 -47.170575) (xy 344.015627 -47.119645) (xy 344.007684 -47.066941) (xy 343.090764 -47.066941)
			(xy 343.082821 -47.119645) (xy 343.067111 -47.170575) (xy 343.043985 -47.218596) (xy 343.013961 -47.262633)
			(xy 342.977709 -47.301704) (xy 342.936038 -47.334935) (xy 342.88988 -47.361584) (xy 342.840266 -47.381056)
			(xy 342.788304 -47.392916) (xy 342.735154 -47.3969) (xy 342.682004 -47.392916) (xy 342.630042 -47.381056)
			(xy 342.580428 -47.361584) (xy 342.53427 -47.334935) (xy 342.492599 -47.301704) (xy 342.456347 -47.262633)
			(xy 342.426323 -47.218596) (xy 342.403197 -47.170575) (xy 342.387487 -47.119645) (xy 342.379544 -47.066941)
			(xy 341.461613 -47.066941) (xy 341.461608 -47.067195) (xy 341.453665 -47.119899) (xy 341.437955 -47.170829)
			(xy 341.414829 -47.21885) (xy 341.384805 -47.262887) (xy 341.348553 -47.301958) (xy 341.306882 -47.335189)
			(xy 341.260724 -47.361838) (xy 341.21111 -47.38131) (xy 341.159148 -47.39317) (xy 341.105998 -47.397154)
			(xy 341.052848 -47.39317) (xy 341.000886 -47.38131) (xy 340.951272 -47.361838) (xy 340.905114 -47.335189)
			(xy 340.863443 -47.301958) (xy 340.827191 -47.262887) (xy 340.797167 -47.21885) (xy 340.774041 -47.170829)
			(xy 340.758331 -47.119899) (xy 340.750388 -47.067195) (xy 338.405842 -47.067195) (xy 338.407309 -47.069303)
			(xy 338.431146 -47.117895) (xy 338.44735 -47.169536) (xy 338.455547 -47.223036) (xy 338.455547 -47.27716)
			(xy 338.447351 -47.33066) (xy 338.431148 -47.382302) (xy 338.407311 -47.430894) (xy 338.376391 -47.475316)
			(xy 338.3391 -47.514544) (xy 338.309964 -47.537095) (xy 339.935048 -47.537095) (xy 339.935048 -47.483797)
			(xy 339.942991 -47.431093) (xy 339.958701 -47.380163) (xy 339.981827 -47.332142) (xy 340.011851 -47.288105)
			(xy 340.048103 -47.249034) (xy 340.089774 -47.215803) (xy 340.135932 -47.189154) (xy 340.185546 -47.169682)
			(xy 340.237508 -47.157822) (xy 340.290658 -47.153839) (xy 340.343808 -47.157822) (xy 340.39577 -47.169682)
			(xy 340.445384 -47.189154) (xy 340.491542 -47.215803) (xy 340.533213 -47.249034) (xy 340.569465 -47.288105)
			(xy 340.599489 -47.332142) (xy 340.622615 -47.380163) (xy 340.638325 -47.431093) (xy 340.646268 -47.483797)
			(xy 340.646766 -47.510446) (xy 340.646268 -47.537095) (xy 341.563188 -47.537095) (xy 341.563188 -47.483797)
			(xy 341.571131 -47.431093) (xy 341.586841 -47.380163) (xy 341.609967 -47.332142) (xy 341.639991 -47.288105)
			(xy 341.676243 -47.249034) (xy 341.717914 -47.215803) (xy 341.764072 -47.189154) (xy 341.813686 -47.169682)
			(xy 341.865648 -47.157822) (xy 341.918798 -47.153839) (xy 341.971948 -47.157822) (xy 342.02391 -47.169682)
			(xy 342.073524 -47.189154) (xy 342.119682 -47.215803) (xy 342.161353 -47.249034) (xy 342.197605 -47.288105)
			(xy 342.227629 -47.332142) (xy 342.250755 -47.380163) (xy 342.266465 -47.431093) (xy 342.274408 -47.483797)
			(xy 342.274906 -47.510446) (xy 342.274413 -47.536841) (xy 343.192344 -47.536841) (xy 343.192344 -47.483543)
			(xy 343.200287 -47.430839) (xy 343.215997 -47.379909) (xy 343.239123 -47.331888) (xy 343.269147 -47.287851)
			(xy 343.305399 -47.24878) (xy 343.34707 -47.215549) (xy 343.393228 -47.1889) (xy 343.442842 -47.169428)
			(xy 343.494804 -47.157568) (xy 343.547954 -47.153585) (xy 343.601104 -47.157568) (xy 343.653066 -47.169428)
			(xy 343.70268 -47.1889) (xy 343.748838 -47.215549) (xy 343.790509 -47.24878) (xy 343.826761 -47.287851)
			(xy 343.856785 -47.331888) (xy 343.879911 -47.379909) (xy 343.895621 -47.430839) (xy 343.903564 -47.483543)
			(xy 343.904062 -47.510192) (xy 343.903564 -47.536841) (xy 343.895621 -47.589545) (xy 343.879911 -47.640475)
			(xy 343.856785 -47.688496) (xy 343.826761 -47.732533) (xy 343.790509 -47.771604) (xy 343.748838 -47.804835)
			(xy 343.70268 -47.831484) (xy 343.653066 -47.850956) (xy 343.601104 -47.862816) (xy 343.547954 -47.8668)
			(xy 343.494804 -47.862816) (xy 343.442842 -47.850956) (xy 343.393228 -47.831484) (xy 343.34707 -47.804835)
			(xy 343.305399 -47.771604) (xy 343.269147 -47.732533) (xy 343.239123 -47.688496) (xy 343.215997 -47.640475)
			(xy 343.200287 -47.589545) (xy 343.192344 -47.536841) (xy 342.274413 -47.536841) (xy 342.274408 -47.537095)
			(xy 342.266465 -47.589799) (xy 342.250755 -47.640729) (xy 342.227629 -47.68875) (xy 342.197605 -47.732787)
			(xy 342.161353 -47.771858) (xy 342.119682 -47.805089) (xy 342.073524 -47.831738) (xy 342.02391 -47.85121)
			(xy 341.971948 -47.86307) (xy 341.918798 -47.867054) (xy 341.865648 -47.86307) (xy 341.813686 -47.85121)
			(xy 341.764072 -47.831738) (xy 341.717914 -47.805089) (xy 341.676243 -47.771858) (xy 341.639991 -47.732787)
			(xy 341.609967 -47.68875) (xy 341.586841 -47.640729) (xy 341.571131 -47.589799) (xy 341.563188 -47.537095)
			(xy 340.646268 -47.537095) (xy 340.638325 -47.589799) (xy 340.622615 -47.640729) (xy 340.599489 -47.68875)
			(xy 340.569465 -47.732787) (xy 340.533213 -47.771858) (xy 340.491542 -47.805089) (xy 340.445384 -47.831738)
			(xy 340.39577 -47.85121) (xy 340.343808 -47.86307) (xy 340.290658 -47.867054) (xy 340.237508 -47.86307)
			(xy 340.185546 -47.85121) (xy 340.135932 -47.831738) (xy 340.089774 -47.805089) (xy 340.048103 -47.771858)
			(xy 340.011851 -47.732787) (xy 339.981827 -47.68875) (xy 339.958701 -47.640729) (xy 339.942991 -47.589799)
			(xy 339.935048 -47.537095) (xy 338.309964 -47.537095) (xy 338.296299 -47.547672) (xy 338.272882 -47.561246)
			(xy 338.261198 -47.568125) (xy 338.24179 -47.58705) (xy 338.22804 -47.610412) (xy 338.220918 -47.636568)
			(xy 338.220924 -47.663676) (xy 338.228058 -47.689829) (xy 338.241817 -47.713185) (xy 338.261234 -47.732102)
			(xy 338.272882 -47.739046) (xy 338.296298 -47.752618) (xy 338.339091 -47.785752) (xy 338.376373 -47.824984)
			(xy 338.407286 -47.869407) (xy 338.431117 -47.917999) (xy 338.447316 -47.969639) (xy 338.453038 -48.006995)
			(xy 340.750388 -48.006995) (xy 340.750388 -47.953697) (xy 340.758331 -47.900993) (xy 340.774041 -47.850063)
			(xy 340.797167 -47.802042) (xy 340.827191 -47.758005) (xy 340.863443 -47.718934) (xy 340.905114 -47.685703)
			(xy 340.951272 -47.659054) (xy 341.000886 -47.639582) (xy 341.052848 -47.627722) (xy 341.105998 -47.623739)
			(xy 341.159148 -47.627722) (xy 341.21111 -47.639582) (xy 341.260724 -47.659054) (xy 341.306882 -47.685703)
			(xy 341.348553 -47.718934) (xy 341.384805 -47.758005) (xy 341.414829 -47.802042) (xy 341.437955 -47.850063)
			(xy 341.453665 -47.900993) (xy 341.461608 -47.953697) (xy 341.462106 -47.980346) (xy 341.461613 -48.006741)
			(xy 342.37802 -48.006741) (xy 342.37802 -47.953443) (xy 342.385963 -47.900739) (xy 342.401673 -47.849809)
			(xy 342.424799 -47.801788) (xy 342.454823 -47.757751) (xy 342.491075 -47.71868) (xy 342.532746 -47.685449)
			(xy 342.578904 -47.6588) (xy 342.628518 -47.639328) (xy 342.68048 -47.627468) (xy 342.73363 -47.623485)
			(xy 342.78678 -47.627468) (xy 342.838742 -47.639328) (xy 342.888356 -47.6588) (xy 342.934514 -47.685449)
			(xy 342.976185 -47.71868) (xy 343.012437 -47.757751) (xy 343.042461 -47.801788) (xy 343.065587 -47.849809)
			(xy 343.081297 -47.900739) (xy 343.08924 -47.953443) (xy 343.089738 -47.980092) (xy 343.08924 -48.006741)
			(xy 343.081297 -48.059445) (xy 343.065587 -48.110375) (xy 343.042461 -48.158396) (xy 343.012437 -48.202433)
			(xy 342.976185 -48.241504) (xy 342.934514 -48.274735) (xy 342.888356 -48.301384) (xy 342.838742 -48.320856)
			(xy 342.78678 -48.332716) (xy 342.73363 -48.3367) (xy 342.68048 -48.332716) (xy 342.628518 -48.320856)
			(xy 342.578904 -48.301384) (xy 342.532746 -48.274735) (xy 342.491075 -48.241504) (xy 342.454823 -48.202433)
			(xy 342.424799 -48.158396) (xy 342.401673 -48.110375) (xy 342.385963 -48.059445) (xy 342.37802 -48.006741)
			(xy 341.461613 -48.006741) (xy 341.461608 -48.006995) (xy 341.453665 -48.059699) (xy 341.437955 -48.110629)
			(xy 341.414829 -48.15865) (xy 341.384805 -48.202687) (xy 341.348553 -48.241758) (xy 341.306882 -48.274989)
			(xy 341.260724 -48.301638) (xy 341.21111 -48.32111) (xy 341.159148 -48.33297) (xy 341.105998 -48.336954)
			(xy 341.052848 -48.33297) (xy 341.000886 -48.32111) (xy 340.951272 -48.301638) (xy 340.905114 -48.274989)
			(xy 340.863443 -48.241758) (xy 340.827191 -48.202687) (xy 340.797167 -48.15865) (xy 340.774041 -48.110629)
			(xy 340.758331 -48.059699) (xy 340.750388 -48.006995) (xy 338.453038 -48.006995) (xy 338.455511 -48.023136)
			(xy 338.456016 -48.050196) (xy 338.455455 -48.078179) (xy 338.446701 -48.133455) (xy 338.429408 -48.186681)
			(xy 338.404001 -48.236547) (xy 338.371106 -48.281824) (xy 338.331533 -48.321398) (xy 338.286257 -48.354294)
			(xy 338.236392 -48.379703) (xy 338.183167 -48.396998) (xy 338.127891 -48.405754) (xy 338.099908 -48.406304)
			(xy 338.072846 -48.405838) (xy 338.019345 -48.397643) (xy 337.967703 -48.38144) (xy 337.91911 -48.357603)
			(xy 337.874687 -48.326682) (xy 337.835459 -48.28939) (xy 337.802332 -48.246587) (xy 337.788758 -48.22317)
			(xy 337.781817 -48.211524) (xy 337.762906 -48.192111) (xy 337.739555 -48.178356) (xy 337.713409 -48.171228)
			(xy 337.686307 -48.171228) (xy 337.660161 -48.178356) (xy 337.63681 -48.192111) (xy 337.617899 -48.211524)
			(xy 337.610958 -48.22317) (xy 337.597379 -48.246582) (xy 337.564246 -48.289375) (xy 337.525016 -48.326658)
			(xy 337.480594 -48.357571) (xy 337.432003 -48.381403) (xy 337.380364 -48.397603) (xy 337.326868 -48.405798)
			(xy 337.299808 -48.406304) (xy 337.271823 -48.40578) (xy 337.216541 -48.397025) (xy 337.163309 -48.37973)
			(xy 337.113439 -48.354321) (xy 337.068157 -48.321423) (xy 337.02858 -48.281846) (xy 336.995681 -48.236564)
			(xy 336.970271 -48.186694) (xy 336.952976 -48.133463) (xy 336.94422 -48.078181) (xy 336.9437 -48.050196)
			(xy 336.944234 -48.023136) (xy 336.952417 -47.969639) (xy 336.968608 -47.917998) (xy 336.992433 -47.869405)
			(xy 337.023344 -47.824981) (xy 337.060626 -47.785751) (xy 337.10342 -47.752621) (xy 337.126834 -47.739046)
			(xy 337.138441 -47.732043) (xy 337.157858 -47.713146) (xy 337.171619 -47.689807) (xy 337.178754 -47.663669)
			(xy 337.17876 -47.636575) (xy 337.171637 -47.610434) (xy 337.157886 -47.587089) (xy 337.138477 -47.568184)
			(xy 337.126834 -47.561246) (xy 337.105406 -47.548845) (xy 337.065885 -47.519026) (xy 337.030877 -47.484019)
			(xy 337.001058 -47.444499) (xy 336.988658 -47.42307) (xy 336.981717 -47.411424) (xy 336.962806 -47.392011)
			(xy 336.939455 -47.378256) (xy 336.913309 -47.371128) (xy 336.886207 -47.371128) (xy 336.860061 -47.378256)
			(xy 336.83671 -47.392011) (xy 336.817799 -47.411424) (xy 336.810858 -47.42307) (xy 336.797279 -47.446482)
			(xy 336.764146 -47.489275) (xy 336.724916 -47.526558) (xy 336.680494 -47.557471) (xy 336.631903 -47.581303)
			(xy 336.580264 -47.597503) (xy 336.526768 -47.605698) (xy 336.499708 -47.606204) (xy 336.471723 -47.60568)
			(xy 336.416441 -47.596925) (xy 336.363209 -47.57963) (xy 336.313339 -47.554221) (xy 336.268057 -47.521323)
			(xy 336.22848 -47.481746) (xy 336.195581 -47.436464) (xy 336.170171 -47.386594) (xy 336.152876 -47.333363)
			(xy 336.14412 -47.278081) (xy 336.1436 -47.250096) (xy 335.255147 -47.250096) (xy 335.255147 -47.27716)
			(xy 335.246951 -47.33066) (xy 335.230748 -47.382302) (xy 335.206911 -47.430894) (xy 335.175991 -47.475316)
			(xy 335.1387 -47.514544) (xy 335.095899 -47.547672) (xy 335.072482 -47.561246) (xy 335.060798 -47.568125)
			(xy 335.04139 -47.58705) (xy 335.02764 -47.610412) (xy 335.020518 -47.636568) (xy 335.020524 -47.663676)
			(xy 335.027658 -47.689829) (xy 335.041417 -47.713185) (xy 335.060834 -47.732102) (xy 335.072482 -47.739046)
			(xy 335.095898 -47.752618) (xy 335.138691 -47.785752) (xy 335.175973 -47.824984) (xy 335.206886 -47.869407)
			(xy 335.230717 -47.917999) (xy 335.246916 -47.969639) (xy 335.255111 -48.023136) (xy 335.255616 -48.050196)
			(xy 335.255118 -48.076845) (xy 335.247175 -48.129549) (xy 335.231465 -48.180479) (xy 335.208339 -48.2285)
			(xy 335.178315 -48.272537) (xy 335.142063 -48.311608) (xy 335.100392 -48.344839) (xy 335.054234 -48.371488)
			(xy 335.00462 -48.39096) (xy 334.952658 -48.40282) (xy 334.899508 -48.406804) (xy 334.846358 -48.40282)
			(xy 334.794396 -48.39096) (xy 334.744782 -48.371488) (xy 334.698624 -48.344839) (xy 334.656953 -48.311608)
			(xy 334.620701 -48.272537) (xy 334.590677 -48.2285) (xy 334.567551 -48.180479) (xy 334.551841 -48.129549)
			(xy 334.543898 -48.076845) (xy 334.5434 -48.050196) (xy 333.857181 -48.050196) (xy 333.849141 -48.085415)
			(xy 333.829667 -48.13503) (xy 333.803014 -48.181188) (xy 333.76978 -48.222858) (xy 333.730705 -48.259108)
			(xy 333.686664 -48.289129) (xy 333.63864 -48.31225) (xy 333.587706 -48.327955) (xy 333.535 -48.335892)
			(xy 333.50835 -48.336454) (xy 333.484334 -48.336057) (xy 333.436739 -48.329595) (xy 333.390443 -48.316794)
			(xy 333.346289 -48.297888) (xy 333.32547 -48.285908) (xy 333.313751 -48.279384) (xy 333.287943 -48.272108)
			(xy 333.26113 -48.271806) (xy 333.235165 -48.278501) (xy 333.211841 -48.291728) (xy 333.192768 -48.310575)
			(xy 333.179263 -48.33374) (xy 333.17226 -48.359623) (xy 333.1718 -48.37303) (xy 333.1718 -48.476895)
			(xy 339.935048 -48.476895) (xy 339.935048 -48.423597) (xy 339.942991 -48.370893) (xy 339.958701 -48.319963)
			(xy 339.981827 -48.271942) (xy 340.011851 -48.227905) (xy 340.048103 -48.188834) (xy 340.089774 -48.155603)
			(xy 340.135932 -48.128954) (xy 340.185546 -48.109482) (xy 340.237508 -48.097622) (xy 340.290658 -48.093639)
			(xy 340.343808 -48.097622) (xy 340.39577 -48.109482) (xy 340.445384 -48.128954) (xy 340.491542 -48.155603)
			(xy 340.533213 -48.188834) (xy 340.569465 -48.227905) (xy 340.599489 -48.271942) (xy 340.622615 -48.319963)
			(xy 340.638325 -48.370893) (xy 340.646268 -48.423597) (xy 340.646766 -48.450246) (xy 340.646268 -48.476895)
			(xy 341.563188 -48.476895) (xy 341.563188 -48.423597) (xy 341.571131 -48.370893) (xy 341.586841 -48.319963)
			(xy 341.609967 -48.271942) (xy 341.639991 -48.227905) (xy 341.676243 -48.188834) (xy 341.717914 -48.155603)
			(xy 341.764072 -48.128954) (xy 341.813686 -48.109482) (xy 341.865648 -48.097622) (xy 341.918798 -48.093639)
			(xy 341.971948 -48.097622) (xy 342.02391 -48.109482) (xy 342.073524 -48.128954) (xy 342.119682 -48.155603)
			(xy 342.161353 -48.188834) (xy 342.197605 -48.227905) (xy 342.227629 -48.271942) (xy 342.250755 -48.319963)
			(xy 342.266465 -48.370893) (xy 342.274408 -48.423597) (xy 342.274906 -48.450246) (xy 342.274413 -48.476641)
			(xy 343.192344 -48.476641) (xy 343.192344 -48.423343) (xy 343.200287 -48.370639) (xy 343.215997 -48.319709)
			(xy 343.239123 -48.271688) (xy 343.269147 -48.227651) (xy 343.305399 -48.18858) (xy 343.34707 -48.155349)
			(xy 343.393228 -48.1287) (xy 343.442842 -48.109228) (xy 343.494804 -48.097368) (xy 343.547954 -48.093385)
			(xy 343.601104 -48.097368) (xy 343.653066 -48.109228) (xy 343.70268 -48.1287) (xy 343.748838 -48.155349)
			(xy 343.790509 -48.18858) (xy 343.826761 -48.227651) (xy 343.856785 -48.271688) (xy 343.879911 -48.319709)
			(xy 343.895621 -48.370639) (xy 343.903564 -48.423343) (xy 343.904062 -48.449992) (xy 343.903564 -48.476641)
			(xy 343.895621 -48.529345) (xy 343.879911 -48.580275) (xy 343.856785 -48.628296) (xy 343.826761 -48.672333)
			(xy 343.790509 -48.711404) (xy 343.748838 -48.744635) (xy 343.70268 -48.771284) (xy 343.653066 -48.790756)
			(xy 343.601104 -48.802616) (xy 343.547954 -48.8066) (xy 343.494804 -48.802616) (xy 343.442842 -48.790756)
			(xy 343.393228 -48.771284) (xy 343.34707 -48.744635) (xy 343.305399 -48.711404) (xy 343.269147 -48.672333)
			(xy 343.239123 -48.628296) (xy 343.215997 -48.580275) (xy 343.200287 -48.529345) (xy 343.192344 -48.476641)
			(xy 342.274413 -48.476641) (xy 342.274408 -48.476895) (xy 342.266465 -48.529599) (xy 342.250755 -48.580529)
			(xy 342.227629 -48.62855) (xy 342.197605 -48.672587) (xy 342.161353 -48.711658) (xy 342.119682 -48.744889)
			(xy 342.073524 -48.771538) (xy 342.02391 -48.79101) (xy 341.971948 -48.80287) (xy 341.918798 -48.806854)
			(xy 341.865648 -48.80287) (xy 341.813686 -48.79101) (xy 341.764072 -48.771538) (xy 341.717914 -48.744889)
			(xy 341.676243 -48.711658) (xy 341.639991 -48.672587) (xy 341.609967 -48.62855) (xy 341.586841 -48.580529)
			(xy 341.571131 -48.529599) (xy 341.563188 -48.476895) (xy 340.646268 -48.476895) (xy 340.638325 -48.529599)
			(xy 340.622615 -48.580529) (xy 340.599489 -48.62855) (xy 340.569465 -48.672587) (xy 340.533213 -48.711658)
			(xy 340.491542 -48.744889) (xy 340.445384 -48.771538) (xy 340.39577 -48.79101) (xy 340.343808 -48.80287)
			(xy 340.290658 -48.806854) (xy 340.237508 -48.80287) (xy 340.185546 -48.79101) (xy 340.135932 -48.771538)
			(xy 340.089774 -48.744889) (xy 340.048103 -48.711658) (xy 340.011851 -48.672587) (xy 339.981827 -48.62855)
			(xy 339.958701 -48.580529) (xy 339.942991 -48.529599) (xy 339.935048 -48.476895) (xy 333.1718 -48.476895)
			(xy 333.1718 -48.946795) (xy 340.750388 -48.946795) (xy 340.750388 -48.893497) (xy 340.758331 -48.840793)
			(xy 340.774041 -48.789863) (xy 340.797167 -48.741842) (xy 340.827191 -48.697805) (xy 340.863443 -48.658734)
			(xy 340.905114 -48.625503) (xy 340.951272 -48.598854) (xy 341.000886 -48.579382) (xy 341.052848 -48.567522)
			(xy 341.105998 -48.563539) (xy 341.159148 -48.567522) (xy 341.21111 -48.579382) (xy 341.260724 -48.598854)
			(xy 341.306882 -48.625503) (xy 341.348553 -48.658734) (xy 341.384805 -48.697805) (xy 341.414829 -48.741842)
			(xy 341.437955 -48.789863) (xy 341.453665 -48.840793) (xy 341.461608 -48.893497) (xy 341.462106 -48.920146)
			(xy 341.461613 -48.946541) (xy 342.379544 -48.946541) (xy 342.379544 -48.893243) (xy 342.387487 -48.840539)
			(xy 342.403197 -48.789609) (xy 342.426323 -48.741588) (xy 342.456347 -48.697551) (xy 342.492599 -48.65848)
			(xy 342.53427 -48.625249) (xy 342.580428 -48.5986) (xy 342.630042 -48.579128) (xy 342.682004 -48.567268)
			(xy 342.735154 -48.563285) (xy 342.788304 -48.567268) (xy 342.840266 -48.579128) (xy 342.88988 -48.5986)
			(xy 342.936038 -48.625249) (xy 342.977709 -48.65848) (xy 343.013961 -48.697551) (xy 343.043985 -48.741588)
			(xy 343.067111 -48.789609) (xy 343.082821 -48.840539) (xy 343.090764 -48.893243) (xy 343.091262 -48.919892)
			(xy 343.090764 -48.946541) (xy 344.007684 -48.946541) (xy 344.007684 -48.893243) (xy 344.015627 -48.840539)
			(xy 344.031337 -48.789609) (xy 344.054463 -48.741588) (xy 344.084487 -48.697551) (xy 344.120739 -48.65848)
			(xy 344.16241 -48.625249) (xy 344.208568 -48.5986) (xy 344.258182 -48.579128) (xy 344.310144 -48.567268)
			(xy 344.363294 -48.563285) (xy 344.416444 -48.567268) (xy 344.468406 -48.579128) (xy 344.51802 -48.5986)
			(xy 344.564178 -48.625249) (xy 344.605849 -48.65848) (xy 344.642101 -48.697551) (xy 344.672125 -48.741588)
			(xy 344.695251 -48.789609) (xy 344.710961 -48.840539) (xy 344.718904 -48.893243) (xy 344.719402 -48.919892)
			(xy 344.718904 -48.946541) (xy 344.710961 -48.999245) (xy 344.695251 -49.050175) (xy 344.672125 -49.098196)
			(xy 344.642101 -49.142233) (xy 344.605849 -49.181304) (xy 344.564178 -49.214535) (xy 344.51802 -49.241184)
			(xy 344.468406 -49.260656) (xy 344.416444 -49.272516) (xy 344.363294 -49.2765) (xy 344.310144 -49.272516)
			(xy 344.258182 -49.260656) (xy 344.208568 -49.241184) (xy 344.16241 -49.214535) (xy 344.120739 -49.181304)
			(xy 344.084487 -49.142233) (xy 344.054463 -49.098196) (xy 344.031337 -49.050175) (xy 344.015627 -48.999245)
			(xy 344.007684 -48.946541) (xy 343.090764 -48.946541) (xy 343.082821 -48.999245) (xy 343.067111 -49.050175)
			(xy 343.043985 -49.098196) (xy 343.013961 -49.142233) (xy 342.977709 -49.181304) (xy 342.936038 -49.214535)
			(xy 342.88988 -49.241184) (xy 342.840266 -49.260656) (xy 342.788304 -49.272516) (xy 342.735154 -49.2765)
			(xy 342.682004 -49.272516) (xy 342.630042 -49.260656) (xy 342.580428 -49.241184) (xy 342.53427 -49.214535)
			(xy 342.492599 -49.181304) (xy 342.456347 -49.142233) (xy 342.426323 -49.098196) (xy 342.403197 -49.050175)
			(xy 342.387487 -48.999245) (xy 342.379544 -48.946541) (xy 341.461613 -48.946541) (xy 341.461608 -48.946795)
			(xy 341.453665 -48.999499) (xy 341.437955 -49.050429) (xy 341.414829 -49.09845) (xy 341.384805 -49.142487)
			(xy 341.348553 -49.181558) (xy 341.306882 -49.214789) (xy 341.260724 -49.241438) (xy 341.21111 -49.26091)
			(xy 341.159148 -49.27277) (xy 341.105998 -49.276754) (xy 341.052848 -49.27277) (xy 341.000886 -49.26091)
			(xy 340.951272 -49.241438) (xy 340.905114 -49.214789) (xy 340.863443 -49.181558) (xy 340.827191 -49.142487)
			(xy 340.797167 -49.09845) (xy 340.774041 -49.050429) (xy 340.758331 -48.999499) (xy 340.750388 -48.946795)
			(xy 333.1718 -48.946795) (xy 333.1718 -49.6504) (xy 333.742764 -49.6504) (xy 333.746747 -49.597245)
			(xy 333.758609 -49.545278) (xy 333.778083 -49.495659) (xy 333.804735 -49.449497) (xy 333.83797 -49.407823)
			(xy 333.877045 -49.371568) (xy 333.921087 -49.341541) (xy 333.969112 -49.318415) (xy 334.020048 -49.302704)
			(xy 334.072756 -49.294761) (xy 334.099408 -49.294288) (xy 334.126468 -49.294825) (xy 334.179965 -49.303008)
			(xy 334.231605 -49.319199) (xy 334.280198 -49.343024) (xy 334.324622 -49.373934) (xy 334.363852 -49.411216)
			(xy 334.396982 -49.454009) (xy 334.410558 -49.477422) (xy 334.417499 -49.489068) (xy 334.43641 -49.508481)
			(xy 334.459761 -49.522236) (xy 334.485907 -49.529364) (xy 334.513009 -49.529364) (xy 334.539155 -49.522236)
			(xy 334.562506 -49.508481) (xy 334.581417 -49.489068) (xy 334.588358 -49.477422) (xy 334.601934 -49.454007)
			(xy 334.635064 -49.411209) (xy 334.674293 -49.373922) (xy 334.718716 -49.343005) (xy 334.767308 -49.31917)
			(xy 334.818948 -49.302969) (xy 334.872447 -49.294774) (xy 334.926569 -49.294774) (xy 334.980068 -49.302969)
			(xy 335.031708 -49.31917) (xy 335.0803 -49.343005) (xy 335.124723 -49.373922) (xy 335.163952 -49.411209)
			(xy 335.197082 -49.454007) (xy 335.210658 -49.477422) (xy 335.217599 -49.489068) (xy 335.23651 -49.508481)
			(xy 335.259861 -49.522236) (xy 335.286007 -49.529364) (xy 335.313109 -49.529364) (xy 335.339255 -49.522236)
			(xy 335.362606 -49.508481) (xy 335.381517 -49.489068) (xy 335.388458 -49.477422) (xy 335.402034 -49.454007)
			(xy 335.435164 -49.411209) (xy 335.474393 -49.373922) (xy 335.518816 -49.343005) (xy 335.567408 -49.31917)
			(xy 335.619048 -49.302969) (xy 335.672547 -49.294774) (xy 335.726669 -49.294774) (xy 335.780168 -49.302969)
			(xy 335.831808 -49.31917) (xy 335.8804 -49.343005) (xy 335.924823 -49.373922) (xy 335.964052 -49.411209)
			(xy 335.997182 -49.454007) (xy 336.010758 -49.477422) (xy 336.017699 -49.489068) (xy 336.03661 -49.508481)
			(xy 336.059961 -49.522236) (xy 336.086107 -49.529364) (xy 336.113209 -49.529364) (xy 336.139355 -49.522236)
			(xy 336.162706 -49.508481) (xy 336.181617 -49.489068) (xy 336.188558 -49.477422) (xy 336.202134 -49.454007)
			(xy 336.235264 -49.411209) (xy 336.274493 -49.373922) (xy 336.318916 -49.343005) (xy 336.367508 -49.31917)
			(xy 336.419148 -49.302969) (xy 336.472647 -49.294774) (xy 336.526769 -49.294774) (xy 336.580268 -49.302969)
			(xy 336.631908 -49.31917) (xy 336.6805 -49.343005) (xy 336.724923 -49.373922) (xy 336.764152 -49.411209)
			(xy 336.797282 -49.454007) (xy 336.810858 -49.477422) (xy 336.817799 -49.489068) (xy 336.83671 -49.508481)
			(xy 336.860061 -49.522236) (xy 336.886207 -49.529364) (xy 336.913309 -49.529364) (xy 336.939455 -49.522236)
			(xy 336.962806 -49.508481) (xy 336.981717 -49.489068) (xy 336.988658 -49.477422) (xy 337.002234 -49.454007)
			(xy 337.035364 -49.411209) (xy 337.074593 -49.373922) (xy 337.119016 -49.343005) (xy 337.167608 -49.31917)
			(xy 337.219248 -49.302969) (xy 337.272747 -49.294774) (xy 337.326869 -49.294774) (xy 337.380368 -49.302969)
			(xy 337.432008 -49.31917) (xy 337.4806 -49.343005) (xy 337.525023 -49.373922) (xy 337.564252 -49.411209)
			(xy 337.597382 -49.454007) (xy 337.610958 -49.477422) (xy 337.617899 -49.489068) (xy 337.63681 -49.508481)
			(xy 337.660161 -49.522236) (xy 337.686307 -49.529364) (xy 337.713409 -49.529364) (xy 337.739555 -49.522236)
			(xy 337.762906 -49.508481) (xy 337.781817 -49.489068) (xy 337.788758 -49.477422) (xy 337.802334 -49.454007)
			(xy 337.835464 -49.411209) (xy 337.874693 -49.373922) (xy 337.919116 -49.343005) (xy 337.967708 -49.31917)
			(xy 338.019348 -49.302969) (xy 338.072847 -49.294774) (xy 338.126969 -49.294774) (xy 338.180468 -49.302969)
			(xy 338.232108 -49.31917) (xy 338.2807 -49.343005) (xy 338.325123 -49.373922) (xy 338.364352 -49.411209)
			(xy 338.397482 -49.454007) (xy 338.411058 -49.477422) (xy 338.417999 -49.489068) (xy 338.43691 -49.508481)
			(xy 338.460261 -49.522236) (xy 338.486407 -49.529364) (xy 338.513509 -49.529364) (xy 338.539655 -49.522236)
			(xy 338.563006 -49.508481) (xy 338.581917 -49.489068) (xy 338.588858 -49.477422) (xy 338.602423 -49.454001)
			(xy 338.635558 -49.411209) (xy 338.674791 -49.373927) (xy 338.719215 -49.343014) (xy 338.767808 -49.319184)
			(xy 338.819449 -49.302986) (xy 338.872947 -49.294793) (xy 338.900008 -49.294288) (xy 338.926657 -49.294794)
			(xy 338.979358 -49.302739) (xy 339.030288 -49.318449) (xy 339.078306 -49.341575) (xy 339.122342 -49.371599)
			(xy 339.161411 -49.407851) (xy 339.168464 -49.416695) (xy 341.563188 -49.416695) (xy 341.563188 -49.363397)
			(xy 341.571131 -49.310693) (xy 341.586841 -49.259763) (xy 341.609967 -49.211742) (xy 341.639991 -49.167705)
			(xy 341.676243 -49.128634) (xy 341.717914 -49.095403) (xy 341.764072 -49.068754) (xy 341.813686 -49.049282)
			(xy 341.865648 -49.037422) (xy 341.918798 -49.033439) (xy 341.971948 -49.037422) (xy 342.02391 -49.049282)
			(xy 342.073524 -49.068754) (xy 342.119682 -49.095403) (xy 342.161353 -49.128634) (xy 342.197605 -49.167705)
			(xy 342.227629 -49.211742) (xy 342.250755 -49.259763) (xy 342.266465 -49.310693) (xy 342.274408 -49.363397)
			(xy 342.274906 -49.390046) (xy 342.274413 -49.416441) (xy 343.194884 -49.416441) (xy 343.194884 -49.363143)
			(xy 343.202827 -49.310439) (xy 343.218537 -49.259509) (xy 343.241663 -49.211488) (xy 343.271687 -49.167451)
			(xy 343.307939 -49.12838) (xy 343.34961 -49.095149) (xy 343.395768 -49.0685) (xy 343.445382 -49.049028)
			(xy 343.497344 -49.037168) (xy 343.550494 -49.033185) (xy 343.603644 -49.037168) (xy 343.655606 -49.049028)
			(xy 343.70522 -49.0685) (xy 343.751378 -49.095149) (xy 343.793049 -49.12838) (xy 343.829301 -49.167451)
			(xy 343.859325 -49.211488) (xy 343.882451 -49.259509) (xy 343.898161 -49.310439) (xy 343.906104 -49.363143)
			(xy 343.906602 -49.389792) (xy 343.906104 -49.416441) (xy 343.898161 -49.469145) (xy 343.882451 -49.520075)
			(xy 343.859325 -49.568096) (xy 343.829301 -49.612133) (xy 343.793049 -49.651204) (xy 343.751378 -49.684435)
			(xy 343.70522 -49.711084) (xy 343.655606 -49.730556) (xy 343.603644 -49.742416) (xy 343.550494 -49.7464)
			(xy 343.497344 -49.742416) (xy 343.445382 -49.730556) (xy 343.395768 -49.711084) (xy 343.34961 -49.684435)
			(xy 343.307939 -49.651204) (xy 343.271687 -49.612133) (xy 343.241663 -49.568096) (xy 343.218537 -49.520075)
			(xy 343.202827 -49.469145) (xy 343.194884 -49.416441) (xy 342.274413 -49.416441) (xy 342.274408 -49.416695)
			(xy 342.266465 -49.469399) (xy 342.250755 -49.520329) (xy 342.227629 -49.56835) (xy 342.197605 -49.612387)
			(xy 342.161353 -49.651458) (xy 342.119682 -49.684689) (xy 342.073524 -49.711338) (xy 342.02391 -49.73081)
			(xy 341.971948 -49.74267) (xy 341.918798 -49.746654) (xy 341.865648 -49.74267) (xy 341.813686 -49.73081)
			(xy 341.764072 -49.711338) (xy 341.717914 -49.684689) (xy 341.676243 -49.651458) (xy 341.639991 -49.612387)
			(xy 341.609967 -49.56835) (xy 341.586841 -49.520329) (xy 341.571131 -49.469399) (xy 341.563188 -49.416695)
			(xy 339.168464 -49.416695) (xy 339.194641 -49.449521) (xy 339.22129 -49.495678) (xy 339.240761 -49.545291)
			(xy 339.252621 -49.597252) (xy 339.256604 -49.6504) (xy 339.252621 -49.703548) (xy 339.240761 -49.755509)
			(xy 339.22129 -49.805122) (xy 339.194641 -49.851279) (xy 339.161411 -49.892949) (xy 339.122342 -49.929201)
			(xy 339.078306 -49.959225) (xy 339.030288 -49.982351) (xy 338.979358 -49.998061) (xy 338.926657 -50.006006)
			(xy 338.900008 -50.006504) (xy 338.872946 -50.006038) (xy 338.819445 -49.997843) (xy 338.767803 -49.98164)
			(xy 338.71921 -49.957803) (xy 338.674787 -49.926882) (xy 338.635559 -49.88959) (xy 338.602432 -49.846787)
			(xy 338.588858 -49.82337) (xy 338.581917 -49.811724) (xy 338.563006 -49.792311) (xy 338.539655 -49.778556)
			(xy 338.513509 -49.771428) (xy 338.486407 -49.771428) (xy 338.460261 -49.778556) (xy 338.43691 -49.792311)
			(xy 338.417999 -49.811724) (xy 338.411058 -49.82337) (xy 338.397482 -49.846785) (xy 338.364352 -49.889583)
			(xy 338.325123 -49.92687) (xy 338.2807 -49.957787) (xy 338.232108 -49.981622) (xy 338.180468 -49.997823)
			(xy 338.126969 -50.006018) (xy 338.072847 -50.006018) (xy 338.019348 -49.997823) (xy 337.967708 -49.981622)
			(xy 337.919116 -49.957787) (xy 337.874693 -49.92687) (xy 337.835464 -49.889583) (xy 337.802334 -49.846785)
			(xy 337.788758 -49.82337) (xy 337.781817 -49.811724) (xy 337.762906 -49.792311) (xy 337.739555 -49.778556)
			(xy 337.713409 -49.771428) (xy 337.686307 -49.771428) (xy 337.660161 -49.778556) (xy 337.63681 -49.792311)
			(xy 337.617899 -49.811724) (xy 337.610958 -49.82337) (xy 337.598554 -49.844796) (xy 337.568736 -49.884317)
			(xy 337.53373 -49.919326) (xy 337.49421 -49.949145) (xy 337.472782 -49.961546) (xy 337.461098 -49.968425)
			(xy 337.44169 -49.98735) (xy 337.42794 -50.010712) (xy 337.420818 -50.036868) (xy 337.420824 -50.063976)
			(xy 337.427958 -50.090129) (xy 337.441717 -50.113485) (xy 337.461134 -50.132402) (xy 337.472782 -50.139346)
			(xy 337.496196 -50.152926) (xy 337.538997 -50.186054) (xy 337.576288 -50.225281) (xy 337.607209 -50.269703)
			(xy 337.631046 -50.318295) (xy 337.64725 -50.369936) (xy 337.655447 -50.423436) (xy 337.655447 -50.450496)
			(xy 339.344 -50.450496) (xy 339.344482 -50.424761) (xy 339.351872 -50.373826) (xy 339.366528 -50.324488)
			(xy 339.388142 -50.277778) (xy 339.416263 -50.234671) (xy 339.450304 -50.196068) (xy 339.489554 -50.162774)
			(xy 339.511132 -50.148744) (xy 339.522706 -50.140989) (xy 339.541389 -50.120331) (xy 339.553805 -50.095398)
			(xy 339.559033 -50.06804) (xy 339.556686 -50.040286) (xy 339.546938 -50.014194) (xy 339.539072 -50.002694)
			(xy 339.522984 -49.979699) (xy 339.497451 -49.929728) (xy 339.48007 -49.876371) (xy 339.471271 -49.820948)
			(xy 339.470746 -49.79289) (xy 339.471244 -49.766241) (xy 339.479187 -49.713537) (xy 339.494897 -49.662607)
			(xy 339.518023 -49.614586) (xy 339.548047 -49.570549) (xy 339.584299 -49.531478) (xy 339.62597 -49.498247)
			(xy 339.672128 -49.471598) (xy 339.721742 -49.452126) (xy 339.773704 -49.440266) (xy 339.826854 -49.436283)
			(xy 339.880004 -49.440266) (xy 339.931966 -49.452126) (xy 339.98158 -49.471598) (xy 340.027738 -49.498247)
			(xy 340.069409 -49.531478) (xy 340.105661 -49.570549) (xy 340.135685 -49.614586) (xy 340.158811 -49.662607)
			(xy 340.174521 -49.713537) (xy 340.182464 -49.766241) (xy 340.182962 -49.79289) (xy 340.182565 -49.818628)
			(xy 340.175161 -49.869567) (xy 340.170174 -49.886341) (xy 342.379544 -49.886341) (xy 342.379544 -49.833043)
			(xy 342.387487 -49.780339) (xy 342.403197 -49.729409) (xy 342.426323 -49.681388) (xy 342.456347 -49.637351)
			(xy 342.492599 -49.59828) (xy 342.53427 -49.565049) (xy 342.580428 -49.5384) (xy 342.630042 -49.518928)
			(xy 342.682004 -49.507068) (xy 342.735154 -49.503085) (xy 342.788304 -49.507068) (xy 342.840266 -49.518928)
			(xy 342.88988 -49.5384) (xy 342.936038 -49.565049) (xy 342.977709 -49.59828) (xy 343.013961 -49.637351)
			(xy 343.043985 -49.681388) (xy 343.067111 -49.729409) (xy 343.082821 -49.780339) (xy 343.090764 -49.833043)
			(xy 343.091262 -49.859692) (xy 343.090764 -49.886341) (xy 344.010224 -49.886341) (xy 344.010224 -49.833043)
			(xy 344.018167 -49.780339) (xy 344.033877 -49.729409) (xy 344.057003 -49.681388) (xy 344.087027 -49.637351)
			(xy 344.123279 -49.59828) (xy 344.16495 -49.565049) (xy 344.211108 -49.5384) (xy 344.260722 -49.518928)
			(xy 344.312684 -49.507068) (xy 344.365834 -49.503085) (xy 344.418984 -49.507068) (xy 344.470946 -49.518928)
			(xy 344.52056 -49.5384) (xy 344.566718 -49.565049) (xy 344.608389 -49.59828) (xy 344.644641 -49.637351)
			(xy 344.674665 -49.681388) (xy 344.697791 -49.729409) (xy 344.713501 -49.780339) (xy 344.721444 -49.833043)
			(xy 344.721942 -49.859692) (xy 344.721444 -49.886341) (xy 344.713501 -49.939045) (xy 344.697791 -49.989975)
			(xy 344.674665 -50.037996) (xy 344.644641 -50.082033) (xy 344.608389 -50.121104) (xy 344.566718 -50.154335)
			(xy 344.52056 -50.180984) (xy 344.470946 -50.200456) (xy 344.418984 -50.212316) (xy 344.365834 -50.2163)
			(xy 344.312684 -50.212316) (xy 344.260722 -50.200456) (xy 344.211108 -50.180984) (xy 344.16495 -50.154335)
			(xy 344.123279 -50.121104) (xy 344.087027 -50.082033) (xy 344.057003 -50.037996) (xy 344.033877 -49.989975)
			(xy 344.018167 -49.939045) (xy 344.010224 -49.886341) (xy 343.090764 -49.886341) (xy 343.082821 -49.939045)
			(xy 343.067111 -49.989975) (xy 343.043985 -50.037996) (xy 343.013961 -50.082033) (xy 342.977709 -50.121104)
			(xy 342.936038 -50.154335) (xy 342.88988 -50.180984) (xy 342.840266 -50.200456) (xy 342.788304 -50.212316)
			(xy 342.735154 -50.2163) (xy 342.682004 -50.212316) (xy 342.630042 -50.200456) (xy 342.580428 -50.180984)
			(xy 342.53427 -50.154335) (xy 342.492599 -50.121104) (xy 342.456347 -50.082033) (xy 342.426323 -50.037996)
			(xy 342.403197 -49.989975) (xy 342.387487 -49.939045) (xy 342.379544 -49.886341) (xy 340.170174 -49.886341)
			(xy 340.160492 -49.918908) (xy 340.138865 -49.965619) (xy 340.11073 -50.008725) (xy 340.076676 -50.047326)
			(xy 340.037414 -50.080615) (xy 340.01583 -50.094642) (xy 340.004293 -50.102441) (xy 339.985624 -50.12309)
			(xy 339.973216 -50.148009) (xy 339.96799 -50.175352) (xy 339.970331 -50.20309) (xy 339.980068 -50.22917)
			(xy 339.98789 -50.240692) (xy 340.003979 -50.263685) (xy 340.029511 -50.313658) (xy 340.043464 -50.356495)
			(xy 341.565728 -50.356495) (xy 341.565728 -50.303197) (xy 341.573671 -50.250493) (xy 341.589381 -50.199563)
			(xy 341.612507 -50.151542) (xy 341.642531 -50.107505) (xy 341.678783 -50.068434) (xy 341.720454 -50.035203)
			(xy 341.766612 -50.008554) (xy 341.816226 -49.989082) (xy 341.868188 -49.977222) (xy 341.921338 -49.973239)
			(xy 341.974488 -49.977222) (xy 342.02645 -49.989082) (xy 342.076064 -50.008554) (xy 342.122222 -50.035203)
			(xy 342.163893 -50.068434) (xy 342.200145 -50.107505) (xy 342.230169 -50.151542) (xy 342.253295 -50.199563)
			(xy 342.269005 -50.250493) (xy 342.276948 -50.303197) (xy 342.277446 -50.329846) (xy 342.276953 -50.356241)
			(xy 343.194884 -50.356241) (xy 343.194884 -50.302943) (xy 343.202827 -50.250239) (xy 343.218537 -50.199309)
			(xy 343.241663 -50.151288) (xy 343.271687 -50.107251) (xy 343.307939 -50.06818) (xy 343.34961 -50.034949)
			(xy 343.395768 -50.0083) (xy 343.445382 -49.988828) (xy 343.497344 -49.976968) (xy 343.550494 -49.972985)
			(xy 343.603644 -49.976968) (xy 343.655606 -49.988828) (xy 343.70522 -50.0083) (xy 343.751378 -50.034949)
			(xy 343.793049 -50.06818) (xy 343.829301 -50.107251) (xy 343.859325 -50.151288) (xy 343.882451 -50.199309)
			(xy 343.898161 -50.250239) (xy 343.906104 -50.302943) (xy 343.906602 -50.329592) (xy 343.906104 -50.356241)
			(xy 343.898161 -50.408945) (xy 343.882451 -50.459875) (xy 343.859325 -50.507896) (xy 343.829301 -50.551933)
			(xy 343.793049 -50.591004) (xy 343.751378 -50.624235) (xy 343.70522 -50.650884) (xy 343.655606 -50.670356)
			(xy 343.603644 -50.682216) (xy 343.550494 -50.6862) (xy 343.497344 -50.682216) (xy 343.445382 -50.670356)
			(xy 343.395768 -50.650884) (xy 343.34961 -50.624235) (xy 343.307939 -50.591004) (xy 343.271687 -50.551933)
			(xy 343.241663 -50.507896) (xy 343.218537 -50.459875) (xy 343.202827 -50.408945) (xy 343.194884 -50.356241)
			(xy 342.276953 -50.356241) (xy 342.276948 -50.356495) (xy 342.269005 -50.409199) (xy 342.253295 -50.460129)
			(xy 342.230169 -50.50815) (xy 342.200145 -50.552187) (xy 342.163893 -50.591258) (xy 342.122222 -50.624489)
			(xy 342.076064 -50.651138) (xy 342.02645 -50.67061) (xy 341.974488 -50.68247) (xy 341.921338 -50.686454)
			(xy 341.868188 -50.68247) (xy 341.816226 -50.67061) (xy 341.766612 -50.651138) (xy 341.720454 -50.624489)
			(xy 341.678783 -50.591258) (xy 341.642531 -50.552187) (xy 341.612507 -50.50815) (xy 341.589381 -50.460129)
			(xy 341.573671 -50.409199) (xy 341.565728 -50.356495) (xy 340.043464 -50.356495) (xy 340.046891 -50.367015)
			(xy 340.05569 -50.422438) (xy 340.056216 -50.450496) (xy 340.055718 -50.477145) (xy 340.047775 -50.529849)
			(xy 340.032065 -50.580779) (xy 340.008939 -50.6288) (xy 339.978915 -50.672837) (xy 339.942663 -50.711908)
			(xy 339.900992 -50.745139) (xy 339.854834 -50.771788) (xy 339.80522 -50.79126) (xy 339.753258 -50.80312)
			(xy 339.700108 -50.807104) (xy 339.646958 -50.80312) (xy 339.594996 -50.79126) (xy 339.545382 -50.771788)
			(xy 339.499224 -50.745139) (xy 339.457553 -50.711908) (xy 339.421301 -50.672837) (xy 339.391277 -50.6288)
			(xy 339.368151 -50.580779) (xy 339.352441 -50.529849) (xy 339.344498 -50.477145) (xy 339.344 -50.450496)
			(xy 337.655447 -50.450496) (xy 337.655447 -50.47756) (xy 337.647251 -50.53106) (xy 337.631048 -50.582702)
			(xy 337.607211 -50.631294) (xy 337.576291 -50.675716) (xy 337.539 -50.714944) (xy 337.496199 -50.748072)
			(xy 337.472782 -50.761646) (xy 337.461098 -50.768525) (xy 337.44169 -50.78745) (xy 337.42794 -50.810812)
			(xy 337.423766 -50.826141) (xy 342.382084 -50.826141) (xy 342.382084 -50.772843) (xy 342.390027 -50.720139)
			(xy 342.405737 -50.669209) (xy 342.428863 -50.621188) (xy 342.458887 -50.577151) (xy 342.495139 -50.53808)
			(xy 342.53681 -50.504849) (xy 342.582968 -50.4782) (xy 342.632582 -50.458728) (xy 342.684544 -50.446868)
			(xy 342.737694 -50.442885) (xy 342.790844 -50.446868) (xy 342.842806 -50.458728) (xy 342.89242 -50.4782)
			(xy 342.938578 -50.504849) (xy 342.980249 -50.53808) (xy 343.016501 -50.577151) (xy 343.046525 -50.621188)
			(xy 343.069651 -50.669209) (xy 343.085361 -50.720139) (xy 343.093304 -50.772843) (xy 343.093802 -50.799492)
			(xy 343.093304 -50.826141) (xy 343.093266 -50.826395) (xy 344.0087 -50.826395) (xy 344.0087 -50.773097)
			(xy 344.016643 -50.720393) (xy 344.032353 -50.669463) (xy 344.055479 -50.621442) (xy 344.085503 -50.577405)
			(xy 344.121755 -50.538334) (xy 344.163426 -50.505103) (xy 344.209584 -50.478454) (xy 344.259198 -50.458982)
			(xy 344.31116 -50.447122) (xy 344.36431 -50.443139) (xy 344.41746 -50.447122) (xy 344.469422 -50.458982)
			(xy 344.519036 -50.478454) (xy 344.565194 -50.505103) (xy 344.606865 -50.538334) (xy 344.643117 -50.577405)
			(xy 344.673141 -50.621442) (xy 344.696267 -50.669463) (xy 344.711977 -50.720393) (xy 344.71992 -50.773097)
			(xy 344.720418 -50.799746) (xy 344.71992 -50.826395) (xy 344.711977 -50.879099) (xy 344.696267 -50.930029)
			(xy 344.673141 -50.97805) (xy 344.643117 -51.022087) (xy 344.606865 -51.061158) (xy 344.565194 -51.094389)
			(xy 344.519036 -51.121038) (xy 344.469422 -51.14051) (xy 344.41746 -51.15237) (xy 344.36431 -51.156354)
			(xy 344.31116 -51.15237) (xy 344.259198 -51.14051) (xy 344.209584 -51.121038) (xy 344.163426 -51.094389)
			(xy 344.121755 -51.061158) (xy 344.085503 -51.022087) (xy 344.055479 -50.97805) (xy 344.032353 -50.930029)
			(xy 344.016643 -50.879099) (xy 344.0087 -50.826395) (xy 343.093266 -50.826395) (xy 343.085361 -50.878845)
			(xy 343.069651 -50.929775) (xy 343.046525 -50.977796) (xy 343.016501 -51.021833) (xy 342.980249 -51.060904)
			(xy 342.938578 -51.094135) (xy 342.89242 -51.120784) (xy 342.842806 -51.140256) (xy 342.790844 -51.152116)
			(xy 342.737694 -51.1561) (xy 342.684544 -51.152116) (xy 342.632582 -51.140256) (xy 342.582968 -51.120784)
			(xy 342.53681 -51.094135) (xy 342.495139 -51.060904) (xy 342.458887 -51.021833) (xy 342.428863 -50.977796)
			(xy 342.405737 -50.929775) (xy 342.390027 -50.878845) (xy 342.382084 -50.826141) (xy 337.423766 -50.826141)
			(xy 337.420818 -50.836968) (xy 337.420824 -50.864076) (xy 337.427958 -50.890229) (xy 337.441717 -50.913585)
			(xy 337.461134 -50.932502) (xy 337.472782 -50.939446) (xy 337.496196 -50.953026) (xy 337.538997 -50.986154)
			(xy 337.576288 -51.025381) (xy 337.607209 -51.069803) (xy 337.631046 -51.118395) (xy 337.64725 -51.170036)
			(xy 337.655447 -51.223536) (xy 337.655447 -51.2651) (xy 339.328942 -51.2651) (xy 339.332926 -51.21194)
			(xy 339.344789 -51.159968) (xy 339.364266 -51.110344) (xy 339.390922 -51.064178) (xy 339.424161 -51.0225)
			(xy 339.463241 -50.986243) (xy 339.507288 -50.956215) (xy 339.55532 -50.933088) (xy 339.606261 -50.917378)
			(xy 339.658975 -50.909437) (xy 339.68563 -50.908966) (xy 339.711635 -50.909445) (xy 339.763092 -50.917008)
			(xy 339.812903 -50.93197) (xy 339.860012 -50.954012) (xy 339.903416 -50.982667) (xy 339.92312 -50.999644)
			(xy 339.934424 -51.009028) (xy 339.96097 -51.021574) (xy 339.989992 -51.026033) (xy 340.01908 -51.022035)
			(xy 340.045822 -51.009911) (xy 340.057232 -51.00066) (xy 340.076746 -50.984292) (xy 340.119583 -50.956739)
			(xy 340.165908 -50.93557) (xy 340.214777 -50.921215) (xy 340.265191 -50.913968) (xy 340.290658 -50.913538)
			(xy 340.317315 -50.913916) (xy 340.370033 -50.921857) (xy 340.420979 -50.937566) (xy 340.469015 -50.960694)
			(xy 340.513066 -50.990723) (xy 340.55215 -51.026983) (xy 340.585392 -51.068663) (xy 340.612051 -51.114832)
			(xy 340.631529 -51.16446) (xy 340.643394 -51.216436) (xy 340.647378 -51.2696) (xy 340.645378 -51.296295)
			(xy 341.565728 -51.296295) (xy 341.565728 -51.242997) (xy 341.573671 -51.190293) (xy 341.589381 -51.139363)
			(xy 341.612507 -51.091342) (xy 341.642531 -51.047305) (xy 341.678783 -51.008234) (xy 341.720454 -50.975003)
			(xy 341.766612 -50.948354) (xy 341.816226 -50.928882) (xy 341.868188 -50.917022) (xy 341.921338 -50.913039)
			(xy 341.974488 -50.917022) (xy 342.02645 -50.928882) (xy 342.076064 -50.948354) (xy 342.122222 -50.975003)
			(xy 342.163893 -51.008234) (xy 342.200145 -51.047305) (xy 342.230169 -51.091342) (xy 342.253295 -51.139363)
			(xy 342.269005 -51.190293) (xy 342.276948 -51.242997) (xy 342.277446 -51.269646) (xy 342.276953 -51.296041)
			(xy 343.194884 -51.296041) (xy 343.194884 -51.242743) (xy 343.202827 -51.190039) (xy 343.218537 -51.139109)
			(xy 343.241663 -51.091088) (xy 343.271687 -51.047051) (xy 343.307939 -51.00798) (xy 343.34961 -50.974749)
			(xy 343.395768 -50.9481) (xy 343.445382 -50.928628) (xy 343.497344 -50.916768) (xy 343.550494 -50.912785)
			(xy 343.603644 -50.916768) (xy 343.655606 -50.928628) (xy 343.70522 -50.9481) (xy 343.751378 -50.974749)
			(xy 343.793049 -51.00798) (xy 343.829301 -51.047051) (xy 343.859325 -51.091088) (xy 343.882451 -51.139109)
			(xy 343.898161 -51.190039) (xy 343.906104 -51.242743) (xy 343.906602 -51.269392) (xy 343.906104 -51.296041)
			(xy 343.898161 -51.348745) (xy 343.882451 -51.399675) (xy 343.859325 -51.447696) (xy 343.829301 -51.491733)
			(xy 343.793049 -51.530804) (xy 343.751378 -51.564035) (xy 343.70522 -51.590684) (xy 343.655606 -51.610156)
			(xy 343.603644 -51.622016) (xy 343.550494 -51.626) (xy 343.497344 -51.622016) (xy 343.445382 -51.610156)
			(xy 343.395768 -51.590684) (xy 343.34961 -51.564035) (xy 343.307939 -51.530804) (xy 343.271687 -51.491733)
			(xy 343.241663 -51.447696) (xy 343.218537 -51.399675) (xy 343.202827 -51.348745) (xy 343.194884 -51.296041)
			(xy 342.276953 -51.296041) (xy 342.276948 -51.296295) (xy 342.269005 -51.348999) (xy 342.253295 -51.399929)
			(xy 342.230169 -51.44795) (xy 342.200145 -51.491987) (xy 342.163893 -51.531058) (xy 342.122222 -51.564289)
			(xy 342.076064 -51.590938) (xy 342.02645 -51.61041) (xy 341.974488 -51.62227) (xy 341.921338 -51.626254)
			(xy 341.868188 -51.62227) (xy 341.816226 -51.61041) (xy 341.766612 -51.590938) (xy 341.720454 -51.564289)
			(xy 341.678783 -51.531058) (xy 341.642531 -51.491987) (xy 341.612507 -51.44795) (xy 341.589381 -51.399929)
			(xy 341.573671 -51.348999) (xy 341.565728 -51.296295) (xy 340.645378 -51.296295) (xy 340.643394 -51.322764)
			(xy 340.631529 -51.37474) (xy 340.612051 -51.424368) (xy 340.585392 -51.470537) (xy 340.55215 -51.512217)
			(xy 340.513066 -51.548477) (xy 340.469015 -51.578506) (xy 340.420979 -51.601634) (xy 340.370033 -51.617343)
			(xy 340.317315 -51.625284) (xy 340.290658 -51.625754) (xy 340.264653 -51.625277) (xy 340.213196 -51.617713)
			(xy 340.163385 -51.60275) (xy 340.116277 -51.580708) (xy 340.072872 -51.552053) (xy 340.053168 -51.535076)
			(xy 340.041874 -51.525679) (xy 340.015324 -51.513132) (xy 339.986299 -51.508674) (xy 339.957208 -51.512676)
			(xy 339.930465 -51.524805) (xy 339.919056 -51.53406) (xy 339.899549 -51.550437) (xy 339.856709 -51.577987)
			(xy 339.810382 -51.599155) (xy 339.761513 -51.613508) (xy 339.711097 -51.620753) (xy 339.68563 -51.621182)
			(xy 339.658975 -51.620763) (xy 339.606261 -51.612822) (xy 339.55532 -51.597112) (xy 339.507288 -51.573985)
			(xy 339.463241 -51.543957) (xy 339.424161 -51.5077) (xy 339.390922 -51.466022) (xy 339.364266 -51.419856)
			(xy 339.344789 -51.370232) (xy 339.332926 -51.31826) (xy 339.328942 -51.2651) (xy 337.655447 -51.2651)
			(xy 337.655447 -51.27766) (xy 337.647251 -51.33116) (xy 337.631048 -51.382802) (xy 337.607211 -51.431394)
			(xy 337.576291 -51.475816) (xy 337.539 -51.515044) (xy 337.496199 -51.548172) (xy 337.472782 -51.561746)
			(xy 337.461098 -51.568625) (xy 337.44169 -51.58755) (xy 337.42794 -51.610912) (xy 337.420818 -51.637068)
			(xy 337.420824 -51.664176) (xy 337.427958 -51.690329) (xy 337.441717 -51.713685) (xy 337.461134 -51.732602)
			(xy 337.472782 -51.739546) (xy 337.496198 -51.753118) (xy 337.538991 -51.786252) (xy 337.576273 -51.825484)
			(xy 337.607186 -51.869907) (xy 337.631017 -51.918499) (xy 337.647216 -51.970139) (xy 337.655411 -52.023636)
			(xy 337.655916 -52.050696) (xy 337.655355 -52.078679) (xy 337.646601 -52.133955) (xy 337.629308 -52.187181)
			(xy 337.603901 -52.237047) (xy 337.571006 -52.282324) (xy 337.531433 -52.321898) (xy 337.486157 -52.354794)
			(xy 337.436292 -52.380203) (xy 337.383067 -52.397498) (xy 337.327791 -52.406254) (xy 337.299808 -52.406804)
			(xy 337.272746 -52.406338) (xy 337.219245 -52.398143) (xy 337.167603 -52.38194) (xy 337.11901 -52.358103)
			(xy 337.074587 -52.327182) (xy 337.035359 -52.28989) (xy 337.002232 -52.247087) (xy 336.988658 -52.22367)
			(xy 336.981717 -52.212024) (xy 336.962806 -52.192611) (xy 336.939455 -52.178856) (xy 336.913309 -52.171728)
			(xy 336.886207 -52.171728) (xy 336.860061 -52.178856) (xy 336.83671 -52.192611) (xy 336.817799 -52.212024)
			(xy 336.810858 -52.22367) (xy 336.797279 -52.247082) (xy 336.764146 -52.289875) (xy 336.724916 -52.327158)
			(xy 336.680494 -52.358071) (xy 336.631903 -52.381903) (xy 336.580264 -52.398103) (xy 336.526768 -52.406298)
			(xy 336.499708 -52.406804) (xy 336.473056 -52.406339) (xy 336.420348 -52.398396) (xy 336.369412 -52.382685)
			(xy 336.321387 -52.359559) (xy 336.277345 -52.329532) (xy 336.23827 -52.293277) (xy 336.205035 -52.251603)
			(xy 336.178383 -52.205441) (xy 336.158909 -52.155822) (xy 336.147047 -52.103855) (xy 336.143064 -52.0507)
			(xy 336.147047 -51.997545) (xy 336.158909 -51.945578) (xy 336.178383 -51.895959) (xy 336.205035 -51.849797)
			(xy 336.23827 -51.808123) (xy 336.277345 -51.771868) (xy 336.321387 -51.741841) (xy 336.369412 -51.718715)
			(xy 336.420348 -51.703004) (xy 336.473056 -51.695061) (xy 336.499708 -51.694588) (xy 336.526768 -51.695125)
			(xy 336.580265 -51.703308) (xy 336.631905 -51.719499) (xy 336.680498 -51.743324) (xy 336.724922 -51.774234)
			(xy 336.764152 -51.811516) (xy 336.797282 -51.854309) (xy 336.810858 -51.877722) (xy 336.817799 -51.889368)
			(xy 336.83671 -51.908781) (xy 336.860061 -51.922536) (xy 336.886207 -51.929664) (xy 336.913309 -51.929664)
			(xy 336.939455 -51.922536) (xy 336.962806 -51.908781) (xy 336.981717 -51.889368) (xy 336.988658 -51.877722)
			(xy 337.001055 -51.856291) (xy 337.030875 -51.816771) (xy 337.065883 -51.781764) (xy 337.105405 -51.751946)
			(xy 337.126834 -51.739546) (xy 337.138441 -51.732543) (xy 337.157858 -51.713646) (xy 337.171619 -51.690307)
			(xy 337.178754 -51.664169) (xy 337.17876 -51.637075) (xy 337.171637 -51.610934) (xy 337.157886 -51.587589)
			(xy 337.138477 -51.568684) (xy 337.126834 -51.561746) (xy 337.103418 -51.548174) (xy 337.060625 -51.515041)
			(xy 337.023342 -51.47581) (xy 336.992429 -51.431387) (xy 336.968598 -51.382795) (xy 336.952399 -51.331155)
			(xy 336.944205 -51.277658) (xy 336.944205 -51.223538) (xy 336.9524 -51.170041) (xy 336.968599 -51.118401)
			(xy 336.992431 -51.06981) (xy 337.023345 -51.025387) (xy 337.060628 -50.986157) (xy 337.103421 -50.953024)
			(xy 337.126834 -50.939446) (xy 337.138441 -50.932443) (xy 337.157858 -50.913546) (xy 337.171619 -50.890207)
			(xy 337.178754 -50.864069) (xy 337.17876 -50.836975) (xy 337.171637 -50.810834) (xy 337.157886 -50.787489)
			(xy 337.138477 -50.768584) (xy 337.126834 -50.761646) (xy 337.103418 -50.748074) (xy 337.060625 -50.714941)
			(xy 337.023342 -50.67571) (xy 336.992429 -50.631287) (xy 336.968598 -50.582695) (xy 336.952399 -50.531055)
			(xy 336.944205 -50.477558) (xy 336.944205 -50.423438) (xy 336.9524 -50.369941) (xy 336.968599 -50.318301)
			(xy 336.992431 -50.26971) (xy 337.023345 -50.225287) (xy 337.060628 -50.186057) (xy 337.103421 -50.152924)
			(xy 337.126834 -50.139346) (xy 337.138441 -50.132343) (xy 337.157858 -50.113446) (xy 337.171619 -50.090107)
			(xy 337.178754 -50.063969) (xy 337.17876 -50.036875) (xy 337.171637 -50.010734) (xy 337.157886 -49.987389)
			(xy 337.138477 -49.968484) (xy 337.126834 -49.961546) (xy 337.105406 -49.949145) (xy 337.065885 -49.919326)
			(xy 337.030877 -49.884319) (xy 337.001058 -49.844799) (xy 336.988658 -49.82337) (xy 336.981717 -49.811724)
			(xy 336.962806 -49.792311) (xy 336.939455 -49.778556) (xy 336.913309 -49.771428) (xy 336.886207 -49.771428)
			(xy 336.860061 -49.778556) (xy 336.83671 -49.792311) (xy 336.817799 -49.811724) (xy 336.810858 -49.82337)
			(xy 336.797282 -49.846785) (xy 336.764152 -49.889583) (xy 336.724923 -49.92687) (xy 336.6805 -49.957787)
			(xy 336.631908 -49.981622) (xy 336.580268 -49.997823) (xy 336.526769 -50.006018) (xy 336.472647 -50.006018)
			(xy 336.419148 -49.997823) (xy 336.367508 -49.981622) (xy 336.318916 -49.957787) (xy 336.274493 -49.92687)
			(xy 336.235264 -49.889583) (xy 336.202134 -49.846785) (xy 336.188558 -49.82337) (xy 336.181617 -49.811724)
			(xy 336.162706 -49.792311) (xy 336.139355 -49.778556) (xy 336.113209 -49.771428) (xy 336.086107 -49.771428)
			(xy 336.059961 -49.778556) (xy 336.03661 -49.792311) (xy 336.017699 -49.811724) (xy 336.010758 -49.82337)
			(xy 335.998354 -49.844796) (xy 335.968536 -49.884317) (xy 335.93353 -49.919326) (xy 335.89401 -49.949145)
			(xy 335.872582 -49.961546) (xy 335.860898 -49.968425) (xy 335.84149 -49.98735) (xy 335.82774 -50.010712)
			(xy 335.820618 -50.036868) (xy 335.820624 -50.063976) (xy 335.827758 -50.090129) (xy 335.841517 -50.113485)
			(xy 335.860934 -50.132402) (xy 335.872582 -50.139346) (xy 335.895996 -50.152926) (xy 335.938797 -50.186054)
			(xy 335.976088 -50.225281) (xy 336.007009 -50.269703) (xy 336.030846 -50.318295) (xy 336.04705 -50.369936)
			(xy 336.055247 -50.423436) (xy 336.055247 -50.47756) (xy 336.047051 -50.53106) (xy 336.030848 -50.582702)
			(xy 336.007011 -50.631294) (xy 335.976091 -50.675716) (xy 335.9388 -50.714944) (xy 335.895999 -50.748072)
			(xy 335.872582 -50.761646) (xy 335.860898 -50.768525) (xy 335.84149 -50.78745) (xy 335.82774 -50.810812)
			(xy 335.820618 -50.836968) (xy 335.820624 -50.864076) (xy 335.827758 -50.890229) (xy 335.841517 -50.913585)
			(xy 335.860934 -50.932502) (xy 335.872582 -50.939446) (xy 335.895998 -50.953018) (xy 335.938791 -50.986152)
			(xy 335.976073 -51.025384) (xy 336.006986 -51.069807) (xy 336.030817 -51.118399) (xy 336.047016 -51.170039)
			(xy 336.055211 -51.223536) (xy 336.055716 -51.250596) (xy 336.055218 -51.277245) (xy 336.047275 -51.329949)
			(xy 336.031565 -51.380879) (xy 336.008439 -51.4289) (xy 335.978415 -51.472937) (xy 335.942163 -51.512008)
			(xy 335.900492 -51.545239) (xy 335.854334 -51.571888) (xy 335.80472 -51.59136) (xy 335.752758 -51.60322)
			(xy 335.699608 -51.607204) (xy 335.646458 -51.60322) (xy 335.594496 -51.59136) (xy 335.544882 -51.571888)
			(xy 335.498724 -51.545239) (xy 335.457053 -51.512008) (xy 335.420801 -51.472937) (xy 335.390777 -51.4289)
			(xy 335.367651 -51.380879) (xy 335.351941 -51.329949) (xy 335.343998 -51.277245) (xy 335.3435 -51.250596)
			(xy 335.344034 -51.223536) (xy 335.352217 -51.170039) (xy 335.368408 -51.118398) (xy 335.392233 -51.069805)
			(xy 335.423144 -51.025381) (xy 335.460426 -50.986151) (xy 335.50322 -50.953021) (xy 335.526634 -50.939446)
			(xy 335.538241 -50.932443) (xy 335.557658 -50.913546) (xy 335.571419 -50.890207) (xy 335.578554 -50.864069)
			(xy 335.57856 -50.836975) (xy 335.571437 -50.810834) (xy 335.557686 -50.787489) (xy 335.538277 -50.768584)
			(xy 335.526634 -50.761646) (xy 335.503218 -50.748074) (xy 335.460425 -50.714941) (xy 335.423142 -50.67571)
			(xy 335.392229 -50.631287) (xy 335.368398 -50.582695) (xy 335.352199 -50.531055) (xy 335.344005 -50.477558)
			(xy 335.344005 -50.423438) (xy 335.3522 -50.369941) (xy 335.368399 -50.318301) (xy 335.392231 -50.26971)
			(xy 335.423145 -50.225287) (xy 335.460428 -50.186057) (xy 335.503221 -50.152924) (xy 335.526634 -50.139346)
			(xy 335.538241 -50.132343) (xy 335.557658 -50.113446) (xy 335.571419 -50.090107) (xy 335.578554 -50.063969)
			(xy 335.57856 -50.036875) (xy 335.571437 -50.010734) (xy 335.557686 -49.987389) (xy 335.538277 -49.968484)
			(xy 335.526634 -49.961546) (xy 335.505206 -49.949145) (xy 335.465685 -49.919326) (xy 335.430677 -49.884319)
			(xy 335.400858 -49.844799) (xy 335.388458 -49.82337) (xy 335.381517 -49.811724) (xy 335.362606 -49.792311)
			(xy 335.339255 -49.778556) (xy 335.313109 -49.771428) (xy 335.286007 -49.771428) (xy 335.259861 -49.778556)
			(xy 335.23651 -49.792311) (xy 335.217599 -49.811724) (xy 335.210658 -49.82337) (xy 335.197082 -49.846785)
			(xy 335.163952 -49.889583) (xy 335.124723 -49.92687) (xy 335.0803 -49.957787) (xy 335.031708 -49.981622)
			(xy 334.980068 -49.997823) (xy 334.926569 -50.006018) (xy 334.872447 -50.006018) (xy 334.818948 -49.997823)
			(xy 334.767308 -49.981622) (xy 334.718716 -49.957787) (xy 334.674293 -49.92687) (xy 334.635064 -49.889583)
			(xy 334.601934 -49.846785) (xy 334.588358 -49.82337) (xy 334.581417 -49.811724) (xy 334.562506 -49.792311)
			(xy 334.539155 -49.778556) (xy 334.513009 -49.771428) (xy 334.485907 -49.771428) (xy 334.459761 -49.778556)
			(xy 334.43641 -49.792311) (xy 334.417499 -49.811724) (xy 334.410558 -49.82337) (xy 334.396979 -49.846782)
			(xy 334.363846 -49.889575) (xy 334.324616 -49.926858) (xy 334.280194 -49.957771) (xy 334.231603 -49.981603)
			(xy 334.179964 -49.997803) (xy 334.126468 -50.005998) (xy 334.099408 -50.006504) (xy 334.072756 -50.006039)
			(xy 334.020048 -49.998096) (xy 333.969112 -49.982385) (xy 333.921087 -49.959259) (xy 333.877045 -49.929232)
			(xy 333.83797 -49.892977) (xy 333.804735 -49.851303) (xy 333.778083 -49.805141) (xy 333.758609 -49.755522)
			(xy 333.746747 -49.703555) (xy 333.742764 -49.6504) (xy 333.1718 -49.6504) (xy 333.1718 -50.406554)
			(xy 333.172213 -50.419968) (xy 333.17921 -50.445867) (xy 333.192707 -50.469053) (xy 333.211774 -50.487926)
			(xy 333.235096 -50.501186) (xy 333.261065 -50.507919) (xy 333.287892 -50.507659) (xy 333.313727 -50.500426)
			(xy 333.32547 -50.49393) (xy 333.346231 -50.481993) (xy 333.390274 -50.463185) (xy 333.43644 -50.450452)
			(xy 333.483897 -50.444023) (xy 333.507842 -50.443638) (xy 333.534486 -50.444139) (xy 333.587177 -50.452087)
			(xy 333.638096 -50.467798) (xy 333.686105 -50.490923) (xy 333.730131 -50.520944) (xy 333.769191 -50.557192)
			(xy 333.802414 -50.598855) (xy 333.829056 -50.645005) (xy 333.848522 -50.694609) (xy 333.860379 -50.746561)
			(xy 333.864361 -50.7997) (xy 333.860379 -50.852839) (xy 333.848522 -50.904791) (xy 333.829056 -50.954395)
			(xy 333.802414 -51.000545) (xy 333.769191 -51.042208) (xy 333.730131 -51.078456) (xy 333.686105 -51.108477)
			(xy 333.638096 -51.131602) (xy 333.587177 -51.147313) (xy 333.534486 -51.155261) (xy 333.507842 -51.155854)
			(xy 333.483896 -51.155466) (xy 333.436437 -51.149047) (xy 333.390268 -51.136319) (xy 333.346224 -51.117511)
			(xy 333.32547 -51.105562) (xy 333.313734 -51.099033) (xy 333.28789 -51.09176) (xy 333.261044 -51.091477)
			(xy 333.235053 -51.098203) (xy 333.211715 -51.111474) (xy 333.192644 -51.13037) (xy 333.17916 -51.153586)
			(xy 333.172195 -51.179514) (xy 333.1718 -51.192938) (xy 333.1718 -52.0507) (xy 333.742764 -52.0507)
			(xy 333.746747 -51.997545) (xy 333.758609 -51.945578) (xy 333.778083 -51.895959) (xy 333.804735 -51.849797)
			(xy 333.83797 -51.808123) (xy 333.877045 -51.771868) (xy 333.921087 -51.741841) (xy 333.969112 -51.718715)
			(xy 334.020048 -51.703004) (xy 334.072756 -51.695061) (xy 334.099408 -51.694588) (xy 334.126468 -51.695125)
			(xy 334.179965 -51.703308) (xy 334.231605 -51.719499) (xy 334.280198 -51.743324) (xy 334.324622 -51.774234)
			(xy 334.363852 -51.811516) (xy 334.396982 -51.854309) (xy 334.410558 -51.877722) (xy 334.417499 -51.889368)
			(xy 334.43641 -51.908781) (xy 334.459761 -51.922536) (xy 334.485907 -51.929664) (xy 334.513009 -51.929664)
			(xy 334.539155 -51.922536) (xy 334.562506 -51.908781) (xy 334.581417 -51.889368) (xy 334.588358 -51.877722)
			(xy 334.601923 -51.854301) (xy 334.635058 -51.811509) (xy 334.674291 -51.774227) (xy 334.718715 -51.743314)
			(xy 334.767308 -51.719484) (xy 334.818949 -51.703286) (xy 334.872447 -51.695093) (xy 334.899508 -51.694588)
			(xy 334.927491 -51.695134) (xy 334.982768 -51.70389) (xy 335.035995 -51.721185) (xy 335.085861 -51.746594)
			(xy 335.131138 -51.77949) (xy 335.170712 -51.819065) (xy 335.203608 -51.864342) (xy 335.229016 -51.914209)
			(xy 335.246311 -51.967436) (xy 335.255067 -52.022713) (xy 335.255616 -52.050696) (xy 335.255122 -52.078135)
			(xy 335.246701 -52.132364) (xy 335.230059 -52.184659) (xy 335.218278 -52.209446) (xy 335.212488 -52.222192)
			(xy 335.207294 -52.249686) (xy 335.209764 -52.277558) (xy 335.219713 -52.30371) (xy 335.236392 -52.326177)
			(xy 335.258546 -52.343267) (xy 335.271364 -52.348892) (xy 335.295721 -52.359231) (xy 335.341326 -52.386063)
			(xy 335.38246 -52.419345) (xy 335.41822 -52.458344) (xy 335.447819 -52.502204) (xy 335.470605 -52.549958)
			(xy 335.486078 -52.600558) (xy 335.493897 -52.65289) (xy 335.494376 -52.679346) (xy 335.493878 -52.705995)
			(xy 338.038938 -52.705995) (xy 338.038938 -52.652697) (xy 338.046881 -52.599993) (xy 338.062591 -52.549063)
			(xy 338.085717 -52.501042) (xy 338.115741 -52.457005) (xy 338.151993 -52.417934) (xy 338.193664 -52.384703)
			(xy 338.239822 -52.358054) (xy 338.289436 -52.338582) (xy 338.341398 -52.326722) (xy 338.394548 -52.322739)
			(xy 338.447698 -52.326722) (xy 338.49966 -52.338582) (xy 338.549274 -52.358054) (xy 338.595432 -52.384703)
			(xy 338.637103 -52.417934) (xy 338.673355 -52.457005) (xy 338.699532 -52.4954) (xy 339.267318 -52.4954)
			(xy 339.271301 -52.442253) (xy 339.28316 -52.390294) (xy 339.302632 -52.340683) (xy 339.32928 -52.294528)
			(xy 339.362509 -52.25286) (xy 339.401578 -52.21661) (xy 339.445614 -52.186588) (xy 339.493632 -52.163465)
			(xy 339.54456 -52.147757) (xy 339.59726 -52.139815) (xy 339.623908 -52.139342) (xy 339.652254 -52.139895)
			(xy 339.708228 -52.148895) (xy 339.762064 -52.166665) (xy 339.787484 -52.17922) (xy 339.801493 -52.185838)
			(xy 339.831986 -52.191224) (xy 339.862692 -52.187225) (xy 339.890789 -52.174209) (xy 339.913696 -52.153373)
			(xy 339.929306 -52.12663) (xy 339.93328 -52.111656) (xy 339.939738 -52.08583) (xy 339.95923 -52.036294)
			(xy 339.985883 -51.990215) (xy 340.019102 -51.948619) (xy 340.058147 -51.912435) (xy 340.102145 -51.882471)
			(xy 340.150115 -51.859394) (xy 340.200988 -51.843719) (xy 340.253628 -51.835797) (xy 340.280244 -51.835304)
			(xy 340.306892 -51.835781) (xy 340.359592 -51.84373) (xy 340.410519 -51.859445) (xy 340.458535 -51.882573)
			(xy 340.502568 -51.912599) (xy 340.541635 -51.948853) (xy 340.574862 -51.990523) (xy 340.601509 -52.03668)
			(xy 340.620978 -52.086293) (xy 340.632837 -52.138253) (xy 340.63682 -52.1914) (xy 340.63347 -52.236095)
			(xy 343.19463 -52.236095) (xy 343.19463 -52.182797) (xy 343.202573 -52.130093) (xy 343.218283 -52.079163)
			(xy 343.241409 -52.031142) (xy 343.271433 -51.987105) (xy 343.307685 -51.948034) (xy 343.349356 -51.914803)
			(xy 343.395514 -51.888154) (xy 343.445128 -51.868682) (xy 343.49709 -51.856822) (xy 343.55024 -51.852839)
			(xy 343.60339 -51.856822) (xy 343.655352 -51.868682) (xy 343.704966 -51.888154) (xy 343.751124 -51.914803)
			(xy 343.792795 -51.948034) (xy 343.829047 -51.987105) (xy 343.859071 -52.031142) (xy 343.882197 -52.079163)
			(xy 343.897907 -52.130093) (xy 343.90585 -52.182797) (xy 343.906348 -52.209446) (xy 343.90585 -52.236095)
			(xy 343.897907 -52.288799) (xy 343.882197 -52.339729) (xy 343.859071 -52.38775) (xy 343.829047 -52.431787)
			(xy 343.792795 -52.470858) (xy 343.751124 -52.504089) (xy 343.704966 -52.530738) (xy 343.655352 -52.55021)
			(xy 343.60339 -52.56207) (xy 343.55024 -52.566054) (xy 343.49709 -52.56207) (xy 343.445128 -52.55021)
			(xy 343.395514 -52.530738) (xy 343.349356 -52.504089) (xy 343.307685 -52.470858) (xy 343.271433 -52.431787)
			(xy 343.241409 -52.38775) (xy 343.218283 -52.339729) (xy 343.202573 -52.288799) (xy 343.19463 -52.236095)
			(xy 340.63347 -52.236095) (xy 340.632837 -52.244547) (xy 340.620978 -52.296507) (xy 340.601509 -52.34612)
			(xy 340.574862 -52.392277) (xy 340.541635 -52.433947) (xy 340.502568 -52.470201) (xy 340.458535 -52.500227)
			(xy 340.410519 -52.523355) (xy 340.359592 -52.53907) (xy 340.306892 -52.547019) (xy 340.280244 -52.54752)
			(xy 340.251898 -52.546952) (xy 340.195925 -52.537959) (xy 340.142089 -52.520194) (xy 340.116668 -52.507642)
			(xy 340.102675 -52.500992) (xy 340.072176 -52.49562) (xy 340.041469 -52.499628) (xy 340.013372 -52.51265)
			(xy 339.990464 -52.533489) (xy 339.974849 -52.560232) (xy 339.970872 -52.575206) (xy 339.964432 -52.601038)
			(xy 339.944942 -52.650577) (xy 339.918289 -52.696659) (xy 339.885068 -52.738257) (xy 339.846021 -52.774442)
			(xy 339.80202 -52.804406) (xy 339.754045 -52.827481) (xy 339.703169 -52.843152) (xy 339.650526 -52.851068)
			(xy 339.623908 -52.851558) (xy 339.59726 -52.850985) (xy 339.54456 -52.843043) (xy 339.493632 -52.827335)
			(xy 339.445614 -52.804212) (xy 339.401578 -52.77419) (xy 339.362509 -52.73794) (xy 339.32928 -52.696272)
			(xy 339.302632 -52.650117) (xy 339.28316 -52.600506) (xy 339.271301 -52.548547) (xy 339.267318 -52.4954)
			(xy 338.699532 -52.4954) (xy 338.703379 -52.501042) (xy 338.726505 -52.549063) (xy 338.742215 -52.599993)
			(xy 338.750158 -52.652697) (xy 338.750656 -52.679346) (xy 338.750158 -52.705995) (xy 338.742215 -52.758699)
			(xy 338.726505 -52.809629) (xy 338.703379 -52.85765) (xy 338.673355 -52.901687) (xy 338.637103 -52.940758)
			(xy 338.595432 -52.973989) (xy 338.549274 -53.000638) (xy 338.49966 -53.02011) (xy 338.447698 -53.03197)
			(xy 338.394548 -53.035954) (xy 338.341398 -53.03197) (xy 338.289436 -53.02011) (xy 338.239822 -53.000638)
			(xy 338.193664 -52.973989) (xy 338.151993 -52.940758) (xy 338.115741 -52.901687) (xy 338.085717 -52.85765)
			(xy 338.062591 -52.809629) (xy 338.046881 -52.758699) (xy 338.038938 -52.705995) (xy 335.493878 -52.705995)
			(xy 335.485935 -52.758699) (xy 335.470225 -52.809629) (xy 335.447099 -52.85765) (xy 335.417075 -52.901687)
			(xy 335.380823 -52.940758) (xy 335.339152 -52.973989) (xy 335.292994 -53.000638) (xy 335.24338 -53.02011)
			(xy 335.191418 -53.03197) (xy 335.138268 -53.035954) (xy 335.085118 -53.03197) (xy 335.033156 -53.02011)
			(xy 334.983542 -53.000638) (xy 334.937384 -52.973989) (xy 334.895713 -52.940758) (xy 334.859461 -52.901687)
			(xy 334.829437 -52.85765) (xy 334.806311 -52.809629) (xy 334.790601 -52.758699) (xy 334.782658 -52.705995)
			(xy 334.78216 -52.679346) (xy 334.782672 -52.651907) (xy 334.791086 -52.597679) (xy 334.807721 -52.545384)
			(xy 334.819498 -52.520596) (xy 334.825368 -52.507883) (xy 334.830553 -52.480374) (xy 334.82807 -52.452491)
			(xy 334.818106 -52.426331) (xy 334.80141 -52.403861) (xy 334.779238 -52.386772) (xy 334.766412 -52.38115)
			(xy 334.744074 -52.371716) (xy 334.701996 -52.347613) (xy 334.663577 -52.318026) (xy 334.629527 -52.2835)
			(xy 334.600474 -52.244675) (xy 334.588358 -52.22367) (xy 334.581417 -52.212024) (xy 334.562506 -52.192611)
			(xy 334.539155 -52.178856) (xy 334.513009 -52.171728) (xy 334.485907 -52.171728) (xy 334.459761 -52.178856)
			(xy 334.43641 -52.192611) (xy 334.417499 -52.212024) (xy 334.410558 -52.22367) (xy 334.396979 -52.247082)
			(xy 334.363846 -52.289875) (xy 334.324616 -52.327158) (xy 334.280194 -52.358071) (xy 334.231603 -52.381903)
			(xy 334.179964 -52.398103) (xy 334.126468 -52.406298) (xy 334.099408 -52.406804) (xy 334.072756 -52.406339)
			(xy 334.020048 -52.398396) (xy 333.969112 -52.382685) (xy 333.921087 -52.359559) (xy 333.877045 -52.329532)
			(xy 333.83797 -52.293277) (xy 333.804735 -52.251603) (xy 333.778083 -52.205441) (xy 333.758609 -52.155822)
			(xy 333.746747 -52.103855) (xy 333.742764 -52.0507) (xy 333.1718 -52.0507) (xy 333.1718 -53.175895)
			(xy 333.969858 -53.175895) (xy 333.969858 -53.122597) (xy 333.977801 -53.069893) (xy 333.993511 -53.018963)
			(xy 334.016637 -52.970942) (xy 334.046661 -52.926905) (xy 334.082913 -52.887834) (xy 334.124584 -52.854603)
			(xy 334.170742 -52.827954) (xy 334.220356 -52.808482) (xy 334.272318 -52.796622) (xy 334.325468 -52.792639)
			(xy 334.378618 -52.796622) (xy 334.43058 -52.808482) (xy 334.480194 -52.827954) (xy 334.526352 -52.854603)
			(xy 334.568023 -52.887834) (xy 334.604275 -52.926905) (xy 334.634299 -52.970942) (xy 334.657425 -53.018963)
			(xy 334.673135 -53.069893) (xy 334.681078 -53.122597) (xy 334.681576 -53.149246) (xy 334.681078 -53.175895)
			(xy 337.226138 -53.175895) (xy 337.226138 -53.122597) (xy 337.234081 -53.069893) (xy 337.249791 -53.018963)
			(xy 337.272917 -52.970942) (xy 337.302941 -52.926905) (xy 337.339193 -52.887834) (xy 337.380864 -52.854603)
			(xy 337.427022 -52.827954) (xy 337.476636 -52.808482) (xy 337.528598 -52.796622) (xy 337.581748 -52.792639)
			(xy 337.634898 -52.796622) (xy 337.68686 -52.808482) (xy 337.736474 -52.827954) (xy 337.782632 -52.854603)
			(xy 337.824303 -52.887834) (xy 337.860555 -52.926905) (xy 337.890579 -52.970942) (xy 337.913705 -53.018963)
			(xy 337.929415 -53.069893) (xy 337.937358 -53.122597) (xy 337.937856 -53.149246) (xy 337.937358 -53.175895)
			(xy 339.935048 -53.175895) (xy 339.935048 -53.122597) (xy 339.942991 -53.069893) (xy 339.958701 -53.018963)
			(xy 339.981827 -52.970942) (xy 340.011851 -52.926905) (xy 340.048103 -52.887834) (xy 340.089774 -52.854603)
			(xy 340.135932 -52.827954) (xy 340.185546 -52.808482) (xy 340.237508 -52.796622) (xy 340.290658 -52.792639)
			(xy 340.343808 -52.796622) (xy 340.39577 -52.808482) (xy 340.445384 -52.827954) (xy 340.491542 -52.854603)
			(xy 340.533213 -52.887834) (xy 340.569465 -52.926905) (xy 340.599489 -52.970942) (xy 340.622615 -53.018963)
			(xy 340.638325 -53.069893) (xy 340.646268 -53.122597) (xy 340.646766 -53.149246) (xy 340.646273 -53.175641)
			(xy 341.565728 -53.175641) (xy 341.565728 -53.122343) (xy 341.573671 -53.069639) (xy 341.589381 -53.018709)
			(xy 341.612507 -52.970688) (xy 341.642531 -52.926651) (xy 341.678783 -52.88758) (xy 341.720454 -52.854349)
			(xy 341.766612 -52.8277) (xy 341.816226 -52.808228) (xy 341.868188 -52.796368) (xy 341.921338 -52.792385)
			(xy 341.974488 -52.796368) (xy 342.02645 -52.808228) (xy 342.076064 -52.8277) (xy 342.122222 -52.854349)
			(xy 342.163893 -52.88758) (xy 342.200145 -52.926651) (xy 342.230169 -52.970688) (xy 342.253295 -53.018709)
			(xy 342.269005 -53.069639) (xy 342.276948 -53.122343) (xy 342.277446 -53.148992) (xy 342.276948 -53.175641)
			(xy 342.269005 -53.228345) (xy 342.253295 -53.279275) (xy 342.230169 -53.327296) (xy 342.200145 -53.371333)
			(xy 342.163893 -53.410404) (xy 342.122222 -53.443635) (xy 342.076064 -53.470284) (xy 342.02645 -53.489756)
			(xy 341.974488 -53.501616) (xy 341.921338 -53.5056) (xy 341.868188 -53.501616) (xy 341.816226 -53.489756)
			(xy 341.766612 -53.470284) (xy 341.720454 -53.443635) (xy 341.678783 -53.410404) (xy 341.642531 -53.371333)
			(xy 341.612507 -53.327296) (xy 341.589381 -53.279275) (xy 341.573671 -53.228345) (xy 341.565728 -53.175641)
			(xy 340.646273 -53.175641) (xy 340.646268 -53.175895) (xy 340.638325 -53.228599) (xy 340.622615 -53.279529)
			(xy 340.599489 -53.32755) (xy 340.569465 -53.371587) (xy 340.533213 -53.410658) (xy 340.491542 -53.443889)
			(xy 340.445384 -53.470538) (xy 340.39577 -53.49001) (xy 340.343808 -53.50187) (xy 340.290658 -53.505854)
			(xy 340.237508 -53.50187) (xy 340.185546 -53.49001) (xy 340.135932 -53.470538) (xy 340.089774 -53.443889)
			(xy 340.048103 -53.410658) (xy 340.011851 -53.371587) (xy 339.981827 -53.32755) (xy 339.958701 -53.279529)
			(xy 339.942991 -53.228599) (xy 339.935048 -53.175895) (xy 337.937358 -53.175895) (xy 337.929415 -53.228599)
			(xy 337.913705 -53.279529) (xy 337.890579 -53.32755) (xy 337.860555 -53.371587) (xy 337.824303 -53.410658)
			(xy 337.782632 -53.443889) (xy 337.736474 -53.470538) (xy 337.68686 -53.49001) (xy 337.634898 -53.50187)
			(xy 337.581748 -53.505854) (xy 337.528598 -53.50187) (xy 337.476636 -53.49001) (xy 337.427022 -53.470538)
			(xy 337.380864 -53.443889) (xy 337.339193 -53.410658) (xy 337.302941 -53.371587) (xy 337.272917 -53.32755)
			(xy 337.249791 -53.279529) (xy 337.234081 -53.228599) (xy 337.226138 -53.175895) (xy 334.681078 -53.175895)
			(xy 334.673135 -53.228599) (xy 334.657425 -53.279529) (xy 334.634299 -53.32755) (xy 334.604275 -53.371587)
			(xy 334.568023 -53.410658) (xy 334.526352 -53.443889) (xy 334.480194 -53.470538) (xy 334.43058 -53.49001)
			(xy 334.378618 -53.50187) (xy 334.325468 -53.505854) (xy 334.272318 -53.50187) (xy 334.220356 -53.49001)
			(xy 334.170742 -53.470538) (xy 334.124584 -53.443889) (xy 334.082913 -53.410658) (xy 334.046661 -53.371587)
			(xy 334.016637 -53.32755) (xy 333.993511 -53.279529) (xy 333.977801 -53.228599) (xy 333.969858 -53.175895)
			(xy 333.1718 -53.175895) (xy 333.1718 -53.645795) (xy 334.782658 -53.645795) (xy 334.782658 -53.592497)
			(xy 334.790601 -53.539793) (xy 334.806311 -53.488863) (xy 334.829437 -53.440842) (xy 334.859461 -53.396805)
			(xy 334.895713 -53.357734) (xy 334.937384 -53.324503) (xy 334.983542 -53.297854) (xy 335.033156 -53.278382)
			(xy 335.085118 -53.266522) (xy 335.138268 -53.262539) (xy 335.191418 -53.266522) (xy 335.24338 -53.278382)
			(xy 335.292994 -53.297854) (xy 335.339152 -53.324503) (xy 335.380823 -53.357734) (xy 335.417075 -53.396805)
			(xy 335.447099 -53.440842) (xy 335.470225 -53.488863) (xy 335.485935 -53.539793) (xy 335.493878 -53.592497)
			(xy 335.494376 -53.619146) (xy 335.493878 -53.645795) (xy 336.410798 -53.645795) (xy 336.410798 -53.592497)
			(xy 336.418741 -53.539793) (xy 336.434451 -53.488863) (xy 336.457577 -53.440842) (xy 336.487601 -53.396805)
			(xy 336.523853 -53.357734) (xy 336.565524 -53.324503) (xy 336.611682 -53.297854) (xy 336.661296 -53.278382)
			(xy 336.713258 -53.266522) (xy 336.766408 -53.262539) (xy 336.819558 -53.266522) (xy 336.87152 -53.278382)
			(xy 336.921134 -53.297854) (xy 336.967292 -53.324503) (xy 337.008963 -53.357734) (xy 337.045215 -53.396805)
			(xy 337.075239 -53.440842) (xy 337.098365 -53.488863) (xy 337.114075 -53.539793) (xy 337.122018 -53.592497)
			(xy 337.122516 -53.619146) (xy 337.122018 -53.645795) (xy 338.038938 -53.645795) (xy 338.038938 -53.592497)
			(xy 338.046881 -53.539793) (xy 338.062591 -53.488863) (xy 338.085717 -53.440842) (xy 338.115741 -53.396805)
			(xy 338.151993 -53.357734) (xy 338.193664 -53.324503) (xy 338.239822 -53.297854) (xy 338.289436 -53.278382)
			(xy 338.341398 -53.266522) (xy 338.394548 -53.262539) (xy 338.447698 -53.266522) (xy 338.49966 -53.278382)
			(xy 338.549274 -53.297854) (xy 338.595432 -53.324503) (xy 338.637103 -53.357734) (xy 338.673355 -53.396805)
			(xy 338.703379 -53.440842) (xy 338.726505 -53.488863) (xy 338.742215 -53.539793) (xy 338.750158 -53.592497)
			(xy 338.750656 -53.619146) (xy 338.750163 -53.645541) (xy 342.379544 -53.645541) (xy 342.379544 -53.592243)
			(xy 342.387487 -53.539539) (xy 342.403197 -53.488609) (xy 342.426323 -53.440588) (xy 342.456347 -53.396551)
			(xy 342.492599 -53.35748) (xy 342.53427 -53.324249) (xy 342.580428 -53.2976) (xy 342.630042 -53.278128)
			(xy 342.682004 -53.266268) (xy 342.735154 -53.262285) (xy 342.788304 -53.266268) (xy 342.840266 -53.278128)
			(xy 342.88988 -53.2976) (xy 342.936038 -53.324249) (xy 342.977709 -53.35748) (xy 343.013961 -53.396551)
			(xy 343.043985 -53.440588) (xy 343.067111 -53.488609) (xy 343.082821 -53.539539) (xy 343.090764 -53.592243)
			(xy 343.091262 -53.618892) (xy 343.090764 -53.645541) (xy 343.082821 -53.698245) (xy 343.067111 -53.749175)
			(xy 343.043985 -53.797196) (xy 343.013961 -53.841233) (xy 342.977709 -53.880304) (xy 342.936038 -53.913535)
			(xy 342.88988 -53.940184) (xy 342.840266 -53.959656) (xy 342.788304 -53.971516) (xy 342.735154 -53.9755)
			(xy 342.682004 -53.971516) (xy 342.630042 -53.959656) (xy 342.580428 -53.940184) (xy 342.53427 -53.913535)
			(xy 342.492599 -53.880304) (xy 342.456347 -53.841233) (xy 342.426323 -53.797196) (xy 342.403197 -53.749175)
			(xy 342.387487 -53.698245) (xy 342.379544 -53.645541) (xy 338.750163 -53.645541) (xy 338.750158 -53.645795)
			(xy 338.742215 -53.698499) (xy 338.726505 -53.749429) (xy 338.703379 -53.79745) (xy 338.673355 -53.841487)
			(xy 338.637103 -53.880558) (xy 338.595432 -53.913789) (xy 338.549274 -53.940438) (xy 338.49966 -53.95991)
			(xy 338.447698 -53.97177) (xy 338.394548 -53.975754) (xy 338.341398 -53.97177) (xy 338.289436 -53.95991)
			(xy 338.239822 -53.940438) (xy 338.193664 -53.913789) (xy 338.151993 -53.880558) (xy 338.115741 -53.841487)
			(xy 338.085717 -53.79745) (xy 338.062591 -53.749429) (xy 338.046881 -53.698499) (xy 338.038938 -53.645795)
			(xy 337.122018 -53.645795) (xy 337.114075 -53.698499) (xy 337.098365 -53.749429) (xy 337.075239 -53.79745)
			(xy 337.045215 -53.841487) (xy 337.008963 -53.880558) (xy 336.967292 -53.913789) (xy 336.921134 -53.940438)
			(xy 336.87152 -53.95991) (xy 336.819558 -53.97177) (xy 336.766408 -53.975754) (xy 336.713258 -53.97177)
			(xy 336.661296 -53.95991) (xy 336.611682 -53.940438) (xy 336.565524 -53.913789) (xy 336.523853 -53.880558)
			(xy 336.487601 -53.841487) (xy 336.457577 -53.79745) (xy 336.434451 -53.749429) (xy 336.418741 -53.698499)
			(xy 336.410798 -53.645795) (xy 335.493878 -53.645795) (xy 335.485935 -53.698499) (xy 335.470225 -53.749429)
			(xy 335.447099 -53.79745) (xy 335.417075 -53.841487) (xy 335.380823 -53.880558) (xy 335.339152 -53.913789)
			(xy 335.292994 -53.940438) (xy 335.24338 -53.95991) (xy 335.191418 -53.97177) (xy 335.138268 -53.975754)
			(xy 335.085118 -53.97177) (xy 335.033156 -53.95991) (xy 334.983542 -53.940438) (xy 334.937384 -53.913789)
			(xy 334.895713 -53.880558) (xy 334.859461 -53.841487) (xy 334.829437 -53.79745) (xy 334.806311 -53.749429)
			(xy 334.790601 -53.698499) (xy 334.782658 -53.645795) (xy 333.1718 -53.645795) (xy 333.1718 -54.115695)
			(xy 337.226138 -54.115695) (xy 337.226138 -54.062397) (xy 337.234081 -54.009693) (xy 337.249791 -53.958763)
			(xy 337.272917 -53.910742) (xy 337.302941 -53.866705) (xy 337.339193 -53.827634) (xy 337.380864 -53.794403)
			(xy 337.427022 -53.767754) (xy 337.476636 -53.748282) (xy 337.528598 -53.736422) (xy 337.581748 -53.732439)
			(xy 337.634898 -53.736422) (xy 337.68686 -53.748282) (xy 337.736474 -53.767754) (xy 337.782632 -53.794403)
			(xy 337.824303 -53.827634) (xy 337.860555 -53.866705) (xy 337.890579 -53.910742) (xy 337.913705 -53.958763)
			(xy 337.929415 -54.009693) (xy 337.937358 -54.062397) (xy 337.937856 -54.089046) (xy 337.937358 -54.115695)
			(xy 341.565728 -54.115695) (xy 341.565728 -54.062397) (xy 341.573671 -54.009693) (xy 341.589381 -53.958763)
			(xy 341.612507 -53.910742) (xy 341.642531 -53.866705) (xy 341.678783 -53.827634) (xy 341.720454 -53.794403)
			(xy 341.766612 -53.767754) (xy 341.816226 -53.748282) (xy 341.868188 -53.736422) (xy 341.921338 -53.732439)
			(xy 341.974488 -53.736422) (xy 342.02645 -53.748282) (xy 342.076064 -53.767754) (xy 342.122222 -53.794403)
			(xy 342.163893 -53.827634) (xy 342.200145 -53.866705) (xy 342.230169 -53.910742) (xy 342.253295 -53.958763)
			(xy 342.269005 -54.009693) (xy 342.276948 -54.062397) (xy 342.277446 -54.089046) (xy 342.276948 -54.115695)
			(xy 342.269005 -54.168399) (xy 342.253295 -54.219329) (xy 342.230169 -54.26735) (xy 342.200145 -54.311387)
			(xy 342.163893 -54.350458) (xy 342.122222 -54.383689) (xy 342.076064 -54.410338) (xy 342.02645 -54.42981)
			(xy 341.974488 -54.44167) (xy 341.921338 -54.445654) (xy 341.868188 -54.44167) (xy 341.816226 -54.42981)
			(xy 341.766612 -54.410338) (xy 341.720454 -54.383689) (xy 341.678783 -54.350458) (xy 341.642531 -54.311387)
			(xy 341.612507 -54.26735) (xy 341.589381 -54.219329) (xy 341.573671 -54.168399) (xy 341.565728 -54.115695)
			(xy 337.937358 -54.115695) (xy 337.929415 -54.168399) (xy 337.913705 -54.219329) (xy 337.890579 -54.26735)
			(xy 337.860555 -54.311387) (xy 337.824303 -54.350458) (xy 337.782632 -54.383689) (xy 337.736474 -54.410338)
			(xy 337.68686 -54.42981) (xy 337.634898 -54.44167) (xy 337.581748 -54.445654) (xy 337.528598 -54.44167)
			(xy 337.476636 -54.42981) (xy 337.427022 -54.410338) (xy 337.380864 -54.383689) (xy 337.339193 -54.350458)
			(xy 337.302941 -54.311387) (xy 337.272917 -54.26735) (xy 337.249791 -54.219329) (xy 337.234081 -54.168399)
			(xy 337.226138 -54.115695) (xy 333.1718 -54.115695) (xy 333.1718 -54.167278) (xy 333.172211 -54.180727)
			(xy 333.179238 -54.20669) (xy 333.192808 -54.229913) (xy 333.211979 -54.24878) (xy 333.235416 -54.261979)
			(xy 333.261488 -54.268591) (xy 333.288382 -54.268156) (xy 333.314227 -54.260704) (xy 333.325978 -54.254146)
			(xy 333.346903 -54.241979) (xy 333.391341 -54.222792) (xy 333.437969 -54.209802) (xy 333.485926 -54.203249)
			(xy 333.510128 -54.202838) (xy 333.536772 -54.203338) (xy 333.589466 -54.211284) (xy 333.640386 -54.226995)
			(xy 333.688397 -54.250118) (xy 333.732425 -54.280139) (xy 333.771487 -54.316387) (xy 333.804711 -54.358051)
			(xy 333.831354 -54.404201) (xy 333.850822 -54.453807) (xy 333.862679 -54.50576) (xy 333.866661 -54.5589)
			(xy 333.864661 -54.585595) (xy 336.410798 -54.585595) (xy 336.410798 -54.532297) (xy 336.418741 -54.479593)
			(xy 336.434451 -54.428663) (xy 336.457577 -54.380642) (xy 336.487601 -54.336605) (xy 336.523853 -54.297534)
			(xy 336.565524 -54.264303) (xy 336.611682 -54.237654) (xy 336.661296 -54.218182) (xy 336.713258 -54.206322)
			(xy 336.766408 -54.202339) (xy 336.819558 -54.206322) (xy 336.87152 -54.218182) (xy 336.921134 -54.237654)
			(xy 336.967292 -54.264303) (xy 337.008963 -54.297534) (xy 337.045215 -54.336605) (xy 337.075239 -54.380642)
			(xy 337.098365 -54.428663) (xy 337.114075 -54.479593) (xy 337.122018 -54.532297) (xy 337.122516 -54.558946)
			(xy 337.122018 -54.585595) (xy 338.038938 -54.585595) (xy 338.038938 -54.532297) (xy 338.046881 -54.479593)
			(xy 338.062591 -54.428663) (xy 338.085717 -54.380642) (xy 338.115741 -54.336605) (xy 338.151993 -54.297534)
			(xy 338.193664 -54.264303) (xy 338.239822 -54.237654) (xy 338.289436 -54.218182) (xy 338.341398 -54.206322)
			(xy 338.394548 -54.202339) (xy 338.447698 -54.206322) (xy 338.49966 -54.218182) (xy 338.549274 -54.237654)
			(xy 338.595432 -54.264303) (xy 338.637103 -54.297534) (xy 338.673355 -54.336605) (xy 338.703379 -54.380642)
			(xy 338.726505 -54.428663) (xy 338.742215 -54.479593) (xy 338.750158 -54.532297) (xy 338.750656 -54.558946)
			(xy 338.750158 -54.585595) (xy 339.122248 -54.585595) (xy 339.122248 -54.532297) (xy 339.130191 -54.479593)
			(xy 339.145901 -54.428663) (xy 339.169027 -54.380642) (xy 339.199051 -54.336605) (xy 339.235303 -54.297534)
			(xy 339.276974 -54.264303) (xy 339.323132 -54.237654) (xy 339.372746 -54.218182) (xy 339.424708 -54.206322)
			(xy 339.477858 -54.202339) (xy 339.531008 -54.206322) (xy 339.58297 -54.218182) (xy 339.632584 -54.237654)
			(xy 339.678742 -54.264303) (xy 339.720413 -54.297534) (xy 339.756665 -54.336605) (xy 339.786689 -54.380642)
			(xy 339.809815 -54.428663) (xy 339.825525 -54.479593) (xy 339.833468 -54.532297) (xy 339.833966 -54.558946)
			(xy 339.833468 -54.585595) (xy 340.750388 -54.585595) (xy 340.750388 -54.532297) (xy 340.758331 -54.479593)
			(xy 340.774041 -54.428663) (xy 340.797167 -54.380642) (xy 340.827191 -54.336605) (xy 340.863443 -54.297534)
			(xy 340.905114 -54.264303) (xy 340.951272 -54.237654) (xy 341.000886 -54.218182) (xy 341.052848 -54.206322)
			(xy 341.105998 -54.202339) (xy 341.159148 -54.206322) (xy 341.21111 -54.218182) (xy 341.260724 -54.237654)
			(xy 341.306882 -54.264303) (xy 341.348553 -54.297534) (xy 341.384805 -54.336605) (xy 341.414829 -54.380642)
			(xy 341.437955 -54.428663) (xy 341.453665 -54.479593) (xy 341.461608 -54.532297) (xy 341.462106 -54.558946)
			(xy 341.461613 -54.585341) (xy 342.379544 -54.585341) (xy 342.379544 -54.532043) (xy 342.387487 -54.479339)
			(xy 342.403197 -54.428409) (xy 342.426323 -54.380388) (xy 342.456347 -54.336351) (xy 342.492599 -54.29728)
			(xy 342.53427 -54.264049) (xy 342.580428 -54.2374) (xy 342.630042 -54.217928) (xy 342.682004 -54.206068)
			(xy 342.735154 -54.202085) (xy 342.788304 -54.206068) (xy 342.840266 -54.217928) (xy 342.88988 -54.2374)
			(xy 342.936038 -54.264049) (xy 342.977709 -54.29728) (xy 343.013961 -54.336351) (xy 343.043985 -54.380388)
			(xy 343.067111 -54.428409) (xy 343.082821 -54.479339) (xy 343.090764 -54.532043) (xy 343.091262 -54.558692)
			(xy 343.090764 -54.585341) (xy 343.082821 -54.638045) (xy 343.067111 -54.688975) (xy 343.043985 -54.736996)
			(xy 343.013961 -54.781033) (xy 342.977709 -54.820104) (xy 342.936038 -54.853335) (xy 342.88988 -54.879984)
			(xy 342.840266 -54.899456) (xy 342.788304 -54.911316) (xy 342.735154 -54.9153) (xy 342.682004 -54.911316)
			(xy 342.630042 -54.899456) (xy 342.580428 -54.879984) (xy 342.53427 -54.853335) (xy 342.492599 -54.820104)
			(xy 342.456347 -54.781033) (xy 342.426323 -54.736996) (xy 342.403197 -54.688975) (xy 342.387487 -54.638045)
			(xy 342.379544 -54.585341) (xy 341.461613 -54.585341) (xy 341.461608 -54.585595) (xy 341.453665 -54.638299)
			(xy 341.437955 -54.689229) (xy 341.414829 -54.73725) (xy 341.384805 -54.781287) (xy 341.348553 -54.820358)
			(xy 341.306882 -54.853589) (xy 341.260724 -54.880238) (xy 341.21111 -54.89971) (xy 341.159148 -54.91157)
			(xy 341.105998 -54.915554) (xy 341.052848 -54.91157) (xy 341.000886 -54.89971) (xy 340.951272 -54.880238)
			(xy 340.905114 -54.853589) (xy 340.863443 -54.820358) (xy 340.827191 -54.781287) (xy 340.797167 -54.73725)
			(xy 340.774041 -54.689229) (xy 340.758331 -54.638299) (xy 340.750388 -54.585595) (xy 339.833468 -54.585595)
			(xy 339.825525 -54.638299) (xy 339.809815 -54.689229) (xy 339.786689 -54.73725) (xy 339.756665 -54.781287)
			(xy 339.720413 -54.820358) (xy 339.678742 -54.853589) (xy 339.632584 -54.880238) (xy 339.58297 -54.89971)
			(xy 339.531008 -54.91157) (xy 339.477858 -54.915554) (xy 339.424708 -54.91157) (xy 339.372746 -54.89971)
			(xy 339.323132 -54.880238) (xy 339.276974 -54.853589) (xy 339.235303 -54.820358) (xy 339.199051 -54.781287)
			(xy 339.169027 -54.73725) (xy 339.145901 -54.689229) (xy 339.130191 -54.638299) (xy 339.122248 -54.585595)
			(xy 338.750158 -54.585595) (xy 338.742215 -54.638299) (xy 338.726505 -54.689229) (xy 338.703379 -54.73725)
			(xy 338.673355 -54.781287) (xy 338.637103 -54.820358) (xy 338.595432 -54.853589) (xy 338.549274 -54.880238)
			(xy 338.49966 -54.89971) (xy 338.447698 -54.91157) (xy 338.394548 -54.915554) (xy 338.341398 -54.91157)
			(xy 338.289436 -54.89971) (xy 338.239822 -54.880238) (xy 338.193664 -54.853589) (xy 338.151993 -54.820358)
			(xy 338.115741 -54.781287) (xy 338.085717 -54.73725) (xy 338.062591 -54.689229) (xy 338.046881 -54.638299)
			(xy 338.038938 -54.585595) (xy 337.122018 -54.585595) (xy 337.114075 -54.638299) (xy 337.098365 -54.689229)
			(xy 337.075239 -54.73725) (xy 337.045215 -54.781287) (xy 337.008963 -54.820358) (xy 336.967292 -54.853589)
			(xy 336.921134 -54.880238) (xy 336.87152 -54.89971) (xy 336.819558 -54.91157) (xy 336.766408 -54.915554)
			(xy 336.713258 -54.91157) (xy 336.661296 -54.89971) (xy 336.611682 -54.880238) (xy 336.565524 -54.853589)
			(xy 336.523853 -54.820358) (xy 336.487601 -54.781287) (xy 336.457577 -54.73725) (xy 336.434451 -54.689229)
			(xy 336.418741 -54.638299) (xy 336.410798 -54.585595) (xy 333.864661 -54.585595) (xy 333.862679 -54.61204)
			(xy 333.850822 -54.663993) (xy 333.831354 -54.713599) (xy 333.804711 -54.759749) (xy 333.771487 -54.801413)
			(xy 333.732425 -54.837661) (xy 333.688397 -54.867682) (xy 333.640386 -54.890805) (xy 333.589466 -54.906516)
			(xy 333.536772 -54.914462) (xy 333.510128 -54.915054) (xy 333.485926 -54.91465) (xy 333.437966 -54.908098)
			(xy 333.391336 -54.89511) (xy 333.346895 -54.875927) (xy 333.325978 -54.863746) (xy 333.314257 -54.85714)
			(xy 333.288405 -54.849717) (xy 333.261511 -54.849303) (xy 333.235443 -54.855927) (xy 333.212009 -54.869129)
			(xy 333.192836 -54.887992) (xy 333.179256 -54.911209) (xy 333.172209 -54.937166) (xy 333.1718 -54.950614)
			(xy 333.1718 -55.055495) (xy 335.597998 -55.055495) (xy 335.597998 -55.002197) (xy 335.605941 -54.949493)
			(xy 335.621651 -54.898563) (xy 335.644777 -54.850542) (xy 335.674801 -54.806505) (xy 335.711053 -54.767434)
			(xy 335.752724 -54.734203) (xy 335.798882 -54.707554) (xy 335.848496 -54.688082) (xy 335.900458 -54.676222)
			(xy 335.953608 -54.672239) (xy 336.006758 -54.676222) (xy 336.05872 -54.688082) (xy 336.108334 -54.707554)
			(xy 336.154492 -54.734203) (xy 336.196163 -54.767434) (xy 336.232415 -54.806505) (xy 336.262439 -54.850542)
			(xy 336.285565 -54.898563) (xy 336.301275 -54.949493) (xy 336.309218 -55.002197) (xy 336.309716 -55.028846)
			(xy 336.309218 -55.055495) (xy 337.226138 -55.055495) (xy 337.226138 -55.002197) (xy 337.234081 -54.949493)
			(xy 337.249791 -54.898563) (xy 337.272917 -54.850542) (xy 337.302941 -54.806505) (xy 337.339193 -54.767434)
			(xy 337.380864 -54.734203) (xy 337.427022 -54.707554) (xy 337.476636 -54.688082) (xy 337.528598 -54.676222)
			(xy 337.581748 -54.672239) (xy 337.634898 -54.676222) (xy 337.68686 -54.688082) (xy 337.736474 -54.707554)
			(xy 337.782632 -54.734203) (xy 337.824303 -54.767434) (xy 337.860555 -54.806505) (xy 337.890579 -54.850542)
			(xy 337.913705 -54.898563) (xy 337.929415 -54.949493) (xy 337.937358 -55.002197) (xy 337.937856 -55.028846)
			(xy 337.937358 -55.055495) (xy 339.935048 -55.055495) (xy 339.935048 -55.002197) (xy 339.942991 -54.949493)
			(xy 339.958701 -54.898563) (xy 339.981827 -54.850542) (xy 340.011851 -54.806505) (xy 340.048103 -54.767434)
			(xy 340.089774 -54.734203) (xy 340.135932 -54.707554) (xy 340.185546 -54.688082) (xy 340.237508 -54.676222)
			(xy 340.290658 -54.672239) (xy 340.343808 -54.676222) (xy 340.39577 -54.688082) (xy 340.445384 -54.707554)
			(xy 340.491542 -54.734203) (xy 340.533213 -54.767434) (xy 340.569465 -54.806505) (xy 340.599489 -54.850542)
			(xy 340.622615 -54.898563) (xy 340.638325 -54.949493) (xy 340.646268 -55.002197) (xy 340.646766 -55.028846)
			(xy 340.646268 -55.055495) (xy 341.565728 -55.055495) (xy 341.565728 -55.002197) (xy 341.573671 -54.949493)
			(xy 341.589381 -54.898563) (xy 341.612507 -54.850542) (xy 341.642531 -54.806505) (xy 341.678783 -54.767434)
			(xy 341.720454 -54.734203) (xy 341.766612 -54.707554) (xy 341.816226 -54.688082) (xy 341.868188 -54.676222)
			(xy 341.921338 -54.672239) (xy 341.974488 -54.676222) (xy 342.02645 -54.688082) (xy 342.076064 -54.707554)
			(xy 342.122222 -54.734203) (xy 342.163893 -54.767434) (xy 342.200145 -54.806505) (xy 342.230169 -54.850542)
			(xy 342.253295 -54.898563) (xy 342.269005 -54.949493) (xy 342.276948 -55.002197) (xy 342.277446 -55.028846)
			(xy 342.276948 -55.055495) (xy 342.269005 -55.108199) (xy 342.253295 -55.159129) (xy 342.230169 -55.20715)
			(xy 342.200145 -55.251187) (xy 342.163893 -55.290258) (xy 342.122222 -55.323489) (xy 342.076064 -55.350138)
			(xy 342.02645 -55.36961) (xy 341.974488 -55.38147) (xy 341.921338 -55.385454) (xy 341.868188 -55.38147)
			(xy 341.816226 -55.36961) (xy 341.766612 -55.350138) (xy 341.720454 -55.323489) (xy 341.678783 -55.290258)
			(xy 341.642531 -55.251187) (xy 341.612507 -55.20715) (xy 341.589381 -55.159129) (xy 341.573671 -55.108199)
			(xy 341.565728 -55.055495) (xy 340.646268 -55.055495) (xy 340.638325 -55.108199) (xy 340.622615 -55.159129)
			(xy 340.599489 -55.20715) (xy 340.569465 -55.251187) (xy 340.533213 -55.290258) (xy 340.491542 -55.323489)
			(xy 340.445384 -55.350138) (xy 340.39577 -55.36961) (xy 340.343808 -55.38147) (xy 340.290658 -55.385454)
			(xy 340.237508 -55.38147) (xy 340.185546 -55.36961) (xy 340.135932 -55.350138) (xy 340.089774 -55.323489)
			(xy 340.048103 -55.290258) (xy 340.011851 -55.251187) (xy 339.981827 -55.20715) (xy 339.958701 -55.159129)
			(xy 339.942991 -55.108199) (xy 339.935048 -55.055495) (xy 337.937358 -55.055495) (xy 337.929415 -55.108199)
			(xy 337.913705 -55.159129) (xy 337.890579 -55.20715) (xy 337.860555 -55.251187) (xy 337.824303 -55.290258)
			(xy 337.782632 -55.323489) (xy 337.736474 -55.350138) (xy 337.68686 -55.36961) (xy 337.634898 -55.38147)
			(xy 337.581748 -55.385454) (xy 337.528598 -55.38147) (xy 337.476636 -55.36961) (xy 337.427022 -55.350138)
			(xy 337.380864 -55.323489) (xy 337.339193 -55.290258) (xy 337.302941 -55.251187) (xy 337.272917 -55.20715)
			(xy 337.249791 -55.159129) (xy 337.234081 -55.108199) (xy 337.226138 -55.055495) (xy 336.309218 -55.055495)
			(xy 336.301275 -55.108199) (xy 336.285565 -55.159129) (xy 336.262439 -55.20715) (xy 336.232415 -55.251187)
			(xy 336.196163 -55.290258) (xy 336.154492 -55.323489) (xy 336.108334 -55.350138) (xy 336.05872 -55.36961)
			(xy 336.006758 -55.38147) (xy 335.953608 -55.385454) (xy 335.900458 -55.38147) (xy 335.848496 -55.36961)
			(xy 335.798882 -55.350138) (xy 335.752724 -55.323489) (xy 335.711053 -55.290258) (xy 335.674801 -55.251187)
			(xy 335.644777 -55.20715) (xy 335.621651 -55.159129) (xy 335.605941 -55.108199) (xy 335.597998 -55.055495)
			(xy 333.1718 -55.055495) (xy 333.1718 -55.525395) (xy 334.782658 -55.525395) (xy 334.782658 -55.472097)
			(xy 334.790601 -55.419393) (xy 334.806311 -55.368463) (xy 334.829437 -55.320442) (xy 334.859461 -55.276405)
			(xy 334.895713 -55.237334) (xy 334.937384 -55.204103) (xy 334.983542 -55.177454) (xy 335.033156 -55.157982)
			(xy 335.085118 -55.146122) (xy 335.138268 -55.142139) (xy 335.191418 -55.146122) (xy 335.24338 -55.157982)
			(xy 335.292994 -55.177454) (xy 335.339152 -55.204103) (xy 335.380823 -55.237334) (xy 335.417075 -55.276405)
			(xy 335.447099 -55.320442) (xy 335.470225 -55.368463) (xy 335.485935 -55.419393) (xy 335.493878 -55.472097)
			(xy 335.494376 -55.498746) (xy 335.493878 -55.525395) (xy 336.412068 -55.525395) (xy 336.412068 -55.472097)
			(xy 336.420011 -55.419393) (xy 336.435721 -55.368463) (xy 336.458847 -55.320442) (xy 336.488871 -55.276405)
			(xy 336.525123 -55.237334) (xy 336.566794 -55.204103) (xy 336.612952 -55.177454) (xy 336.662566 -55.157982)
			(xy 336.714528 -55.146122) (xy 336.767678 -55.142139) (xy 336.820828 -55.146122) (xy 336.87279 -55.157982)
			(xy 336.922404 -55.177454) (xy 336.968562 -55.204103) (xy 337.010233 -55.237334) (xy 337.046485 -55.276405)
			(xy 337.076509 -55.320442) (xy 337.099635 -55.368463) (xy 337.115345 -55.419393) (xy 337.123288 -55.472097)
			(xy 337.123786 -55.498746) (xy 337.123288 -55.525395) (xy 338.038938 -55.525395) (xy 338.038938 -55.472097)
			(xy 338.046881 -55.419393) (xy 338.062591 -55.368463) (xy 338.085717 -55.320442) (xy 338.115741 -55.276405)
			(xy 338.151993 -55.237334) (xy 338.193664 -55.204103) (xy 338.239822 -55.177454) (xy 338.289436 -55.157982)
			(xy 338.341398 -55.146122) (xy 338.394548 -55.142139) (xy 338.447698 -55.146122) (xy 338.49966 -55.157982)
			(xy 338.549274 -55.177454) (xy 338.595432 -55.204103) (xy 338.637103 -55.237334) (xy 338.673355 -55.276405)
			(xy 338.703379 -55.320442) (xy 338.726505 -55.368463) (xy 338.742215 -55.419393) (xy 338.750158 -55.472097)
			(xy 338.750656 -55.498746) (xy 338.750158 -55.525395) (xy 339.122248 -55.525395) (xy 339.122248 -55.472097)
			(xy 339.130191 -55.419393) (xy 339.145901 -55.368463) (xy 339.169027 -55.320442) (xy 339.199051 -55.276405)
			(xy 339.235303 -55.237334) (xy 339.276974 -55.204103) (xy 339.323132 -55.177454) (xy 339.372746 -55.157982)
			(xy 339.424708 -55.146122) (xy 339.477858 -55.142139) (xy 339.531008 -55.146122) (xy 339.58297 -55.157982)
			(xy 339.632584 -55.177454) (xy 339.678742 -55.204103) (xy 339.720413 -55.237334) (xy 339.756665 -55.276405)
			(xy 339.786689 -55.320442) (xy 339.809815 -55.368463) (xy 339.825525 -55.419393) (xy 339.833468 -55.472097)
			(xy 339.833966 -55.498746) (xy 339.833468 -55.525395) (xy 340.750388 -55.525395) (xy 340.750388 -55.472097)
			(xy 340.758331 -55.419393) (xy 340.774041 -55.368463) (xy 340.797167 -55.320442) (xy 340.827191 -55.276405)
			(xy 340.863443 -55.237334) (xy 340.905114 -55.204103) (xy 340.951272 -55.177454) (xy 341.000886 -55.157982)
			(xy 341.052848 -55.146122) (xy 341.105998 -55.142139) (xy 341.159148 -55.146122) (xy 341.21111 -55.157982)
			(xy 341.260724 -55.177454) (xy 341.306882 -55.204103) (xy 341.348553 -55.237334) (xy 341.384805 -55.276405)
			(xy 341.414829 -55.320442) (xy 341.437955 -55.368463) (xy 341.453665 -55.419393) (xy 341.461608 -55.472097)
			(xy 341.462106 -55.498746) (xy 341.461613 -55.525141) (xy 342.379544 -55.525141) (xy 342.379544 -55.471843)
			(xy 342.387487 -55.419139) (xy 342.403197 -55.368209) (xy 342.426323 -55.320188) (xy 342.456347 -55.276151)
			(xy 342.492599 -55.23708) (xy 342.53427 -55.203849) (xy 342.580428 -55.1772) (xy 342.630042 -55.157728)
			(xy 342.682004 -55.145868) (xy 342.735154 -55.141885) (xy 342.788304 -55.145868) (xy 342.840266 -55.157728)
			(xy 342.88988 -55.1772) (xy 342.936038 -55.203849) (xy 342.977709 -55.23708) (xy 343.013961 -55.276151)
			(xy 343.043985 -55.320188) (xy 343.067111 -55.368209) (xy 343.082821 -55.419139) (xy 343.090764 -55.471843)
			(xy 343.091262 -55.498492) (xy 343.090764 -55.525141) (xy 343.082821 -55.577845) (xy 343.067111 -55.628775)
			(xy 343.043985 -55.676796) (xy 343.013961 -55.720833) (xy 342.977709 -55.759904) (xy 342.936038 -55.793135)
			(xy 342.88988 -55.819784) (xy 342.840266 -55.839256) (xy 342.788304 -55.851116) (xy 342.735154 -55.8551)
			(xy 342.682004 -55.851116) (xy 342.630042 -55.839256) (xy 342.580428 -55.819784) (xy 342.53427 -55.793135)
			(xy 342.492599 -55.759904) (xy 342.456347 -55.720833) (xy 342.426323 -55.676796) (xy 342.403197 -55.628775)
			(xy 342.387487 -55.577845) (xy 342.379544 -55.525141) (xy 341.461613 -55.525141) (xy 341.461608 -55.525395)
			(xy 341.453665 -55.578099) (xy 341.437955 -55.629029) (xy 341.414829 -55.67705) (xy 341.384805 -55.721087)
			(xy 341.348553 -55.760158) (xy 341.306882 -55.793389) (xy 341.260724 -55.820038) (xy 341.21111 -55.83951)
			(xy 341.159148 -55.85137) (xy 341.105998 -55.855354) (xy 341.052848 -55.85137) (xy 341.000886 -55.83951)
			(xy 340.951272 -55.820038) (xy 340.905114 -55.793389) (xy 340.863443 -55.760158) (xy 340.827191 -55.721087)
			(xy 340.797167 -55.67705) (xy 340.774041 -55.629029) (xy 340.758331 -55.578099) (xy 340.750388 -55.525395)
			(xy 339.833468 -55.525395) (xy 339.825525 -55.578099) (xy 339.809815 -55.629029) (xy 339.786689 -55.67705)
			(xy 339.756665 -55.721087) (xy 339.720413 -55.760158) (xy 339.678742 -55.793389) (xy 339.632584 -55.820038)
			(xy 339.58297 -55.83951) (xy 339.531008 -55.85137) (xy 339.477858 -55.855354) (xy 339.424708 -55.85137)
			(xy 339.372746 -55.83951) (xy 339.323132 -55.820038) (xy 339.276974 -55.793389) (xy 339.235303 -55.760158)
			(xy 339.199051 -55.721087) (xy 339.169027 -55.67705) (xy 339.145901 -55.629029) (xy 339.130191 -55.578099)
			(xy 339.122248 -55.525395) (xy 338.750158 -55.525395) (xy 338.742215 -55.578099) (xy 338.726505 -55.629029)
			(xy 338.703379 -55.67705) (xy 338.673355 -55.721087) (xy 338.637103 -55.760158) (xy 338.595432 -55.793389)
			(xy 338.549274 -55.820038) (xy 338.49966 -55.83951) (xy 338.447698 -55.85137) (xy 338.394548 -55.855354)
			(xy 338.341398 -55.85137) (xy 338.289436 -55.83951) (xy 338.239822 -55.820038) (xy 338.193664 -55.793389)
			(xy 338.151993 -55.760158) (xy 338.115741 -55.721087) (xy 338.085717 -55.67705) (xy 338.062591 -55.629029)
			(xy 338.046881 -55.578099) (xy 338.038938 -55.525395) (xy 337.123288 -55.525395) (xy 337.115345 -55.578099)
			(xy 337.099635 -55.629029) (xy 337.076509 -55.67705) (xy 337.046485 -55.721087) (xy 337.010233 -55.760158)
			(xy 336.968562 -55.793389) (xy 336.922404 -55.820038) (xy 336.87279 -55.83951) (xy 336.820828 -55.85137)
			(xy 336.767678 -55.855354) (xy 336.714528 -55.85137) (xy 336.662566 -55.83951) (xy 336.612952 -55.820038)
			(xy 336.566794 -55.793389) (xy 336.525123 -55.760158) (xy 336.488871 -55.721087) (xy 336.458847 -55.67705)
			(xy 336.435721 -55.629029) (xy 336.420011 -55.578099) (xy 336.412068 -55.525395) (xy 335.493878 -55.525395)
			(xy 335.485935 -55.578099) (xy 335.470225 -55.629029) (xy 335.447099 -55.67705) (xy 335.417075 -55.721087)
			(xy 335.380823 -55.760158) (xy 335.339152 -55.793389) (xy 335.292994 -55.820038) (xy 335.24338 -55.83951)
			(xy 335.191418 -55.85137) (xy 335.138268 -55.855354) (xy 335.085118 -55.85137) (xy 335.033156 -55.83951)
			(xy 334.983542 -55.820038) (xy 334.937384 -55.793389) (xy 334.895713 -55.760158) (xy 334.859461 -55.721087)
			(xy 334.829437 -55.67705) (xy 334.806311 -55.629029) (xy 334.790601 -55.578099) (xy 334.782658 -55.525395)
			(xy 333.1718 -55.525395) (xy 333.1718 -55.794148) (xy 333.050388 -55.91556) (xy 333.05242 -55.938928)
			(xy 333.05369 -55.968646) (xy 333.053164 -55.995295) (xy 335.597998 -55.995295) (xy 335.597998 -55.941997)
			(xy 335.605941 -55.889293) (xy 335.621651 -55.838363) (xy 335.644777 -55.790342) (xy 335.674801 -55.746305)
			(xy 335.711053 -55.707234) (xy 335.752724 -55.674003) (xy 335.798882 -55.647354) (xy 335.848496 -55.627882)
			(xy 335.900458 -55.616022) (xy 335.953608 -55.612039) (xy 336.006758 -55.616022) (xy 336.05872 -55.627882)
			(xy 336.108334 -55.647354) (xy 336.154492 -55.674003) (xy 336.196163 -55.707234) (xy 336.232415 -55.746305)
			(xy 336.262439 -55.790342) (xy 336.285565 -55.838363) (xy 336.301275 -55.889293) (xy 336.309218 -55.941997)
			(xy 336.309716 -55.968646) (xy 336.309218 -55.995295) (xy 337.226138 -55.995295) (xy 337.226138 -55.941997)
			(xy 337.234081 -55.889293) (xy 337.249791 -55.838363) (xy 337.272917 -55.790342) (xy 337.302941 -55.746305)
			(xy 337.339193 -55.707234) (xy 337.380864 -55.674003) (xy 337.427022 -55.647354) (xy 337.476636 -55.627882)
			(xy 337.528598 -55.616022) (xy 337.581748 -55.612039) (xy 337.634898 -55.616022) (xy 337.68686 -55.627882)
			(xy 337.736474 -55.647354) (xy 337.782632 -55.674003) (xy 337.824303 -55.707234) (xy 337.860555 -55.746305)
			(xy 337.890579 -55.790342) (xy 337.913705 -55.838363) (xy 337.929415 -55.889293) (xy 337.937358 -55.941997)
			(xy 337.937856 -55.968646) (xy 337.937358 -55.995295) (xy 339.935048 -55.995295) (xy 339.935048 -55.941997)
			(xy 339.942991 -55.889293) (xy 339.958701 -55.838363) (xy 339.981827 -55.790342) (xy 340.011851 -55.746305)
			(xy 340.048103 -55.707234) (xy 340.089774 -55.674003) (xy 340.135932 -55.647354) (xy 340.185546 -55.627882)
			(xy 340.237508 -55.616022) (xy 340.290658 -55.612039) (xy 340.343808 -55.616022) (xy 340.39577 -55.627882)
			(xy 340.445384 -55.647354) (xy 340.491542 -55.674003) (xy 340.533213 -55.707234) (xy 340.569465 -55.746305)
			(xy 340.599489 -55.790342) (xy 340.622615 -55.838363) (xy 340.638325 -55.889293) (xy 340.646268 -55.941997)
			(xy 340.646766 -55.968646) (xy 340.646268 -55.995295) (xy 341.565728 -55.995295) (xy 341.565728 -55.941997)
			(xy 341.573671 -55.889293) (xy 341.589381 -55.838363) (xy 341.612507 -55.790342) (xy 341.642531 -55.746305)
			(xy 341.678783 -55.707234) (xy 341.720454 -55.674003) (xy 341.766612 -55.647354) (xy 341.816226 -55.627882)
			(xy 341.868188 -55.616022) (xy 341.921338 -55.612039) (xy 341.974488 -55.616022) (xy 342.02645 -55.627882)
			(xy 342.076064 -55.647354) (xy 342.122222 -55.674003) (xy 342.163893 -55.707234) (xy 342.200145 -55.746305)
			(xy 342.230169 -55.790342) (xy 342.253295 -55.838363) (xy 342.269005 -55.889293) (xy 342.276948 -55.941997)
			(xy 342.277446 -55.968646) (xy 342.276948 -55.995295) (xy 342.269005 -56.047999) (xy 342.253295 -56.098929)
			(xy 342.230169 -56.14695) (xy 342.200145 -56.190987) (xy 342.163893 -56.230058) (xy 342.122222 -56.263289)
			(xy 342.076064 -56.289938) (xy 342.02645 -56.30941) (xy 341.974488 -56.32127) (xy 341.921338 -56.325254)
			(xy 341.868188 -56.32127) (xy 341.816226 -56.30941) (xy 341.766612 -56.289938) (xy 341.720454 -56.263289)
			(xy 341.678783 -56.230058) (xy 341.642531 -56.190987) (xy 341.612507 -56.14695) (xy 341.589381 -56.098929)
			(xy 341.573671 -56.047999) (xy 341.565728 -55.995295) (xy 340.646268 -55.995295) (xy 340.638325 -56.047999)
			(xy 340.622615 -56.098929) (xy 340.599489 -56.14695) (xy 340.569465 -56.190987) (xy 340.533213 -56.230058)
			(xy 340.491542 -56.263289) (xy 340.445384 -56.289938) (xy 340.39577 -56.30941) (xy 340.343808 -56.32127)
			(xy 340.290658 -56.325254) (xy 340.237508 -56.32127) (xy 340.185546 -56.30941) (xy 340.135932 -56.289938)
			(xy 340.089774 -56.263289) (xy 340.048103 -56.230058) (xy 340.011851 -56.190987) (xy 339.981827 -56.14695)
			(xy 339.958701 -56.098929) (xy 339.942991 -56.047999) (xy 339.935048 -55.995295) (xy 337.937358 -55.995295)
			(xy 337.929415 -56.047999) (xy 337.913705 -56.098929) (xy 337.890579 -56.14695) (xy 337.860555 -56.190987)
			(xy 337.824303 -56.230058) (xy 337.782632 -56.263289) (xy 337.736474 -56.289938) (xy 337.68686 -56.30941)
			(xy 337.634898 -56.32127) (xy 337.581748 -56.325254) (xy 337.528598 -56.32127) (xy 337.476636 -56.30941)
			(xy 337.427022 -56.289938) (xy 337.380864 -56.263289) (xy 337.339193 -56.230058) (xy 337.302941 -56.190987)
			(xy 337.272917 -56.14695) (xy 337.249791 -56.098929) (xy 337.234081 -56.047999) (xy 337.226138 -55.995295)
			(xy 336.309218 -55.995295) (xy 336.301275 -56.047999) (xy 336.285565 -56.098929) (xy 336.262439 -56.14695)
			(xy 336.232415 -56.190987) (xy 336.196163 -56.230058) (xy 336.154492 -56.263289) (xy 336.108334 -56.289938)
			(xy 336.05872 -56.30941) (xy 336.006758 -56.32127) (xy 335.953608 -56.325254) (xy 335.900458 -56.32127)
			(xy 335.848496 -56.30941) (xy 335.798882 -56.289938) (xy 335.752724 -56.263289) (xy 335.711053 -56.230058)
			(xy 335.674801 -56.190987) (xy 335.644777 -56.14695) (xy 335.621651 -56.098929) (xy 335.605941 -56.047999)
			(xy 335.597998 -55.995295) (xy 333.053164 -55.995295) (xy 333.053138 -55.996626) (xy 333.044377 -56.051897)
			(xy 333.027078 -56.105116) (xy 333.001667 -56.154975) (xy 332.96877 -56.200245) (xy 332.929196 -56.239811)
			(xy 332.88392 -56.272701) (xy 332.834057 -56.298102) (xy 332.780834 -56.315392) (xy 332.725562 -56.324143)
			(xy 332.697582 -56.324754) (xy 332.667864 -56.323484) (xy 332.644496 -56.321452) (xy 332.585314 -56.380634)
			(xy 332.575864 -56.390713) (xy 332.562262 -56.414746) (xy 332.555606 -56.441547) (xy 332.556273 -56.465195)
			(xy 333.154772 -56.465195) (xy 333.154772 -56.411897) (xy 333.162715 -56.359193) (xy 333.178425 -56.308263)
			(xy 333.201551 -56.260242) (xy 333.231575 -56.216205) (xy 333.267827 -56.177134) (xy 333.309498 -56.143903)
			(xy 333.355656 -56.117254) (xy 333.40527 -56.097782) (xy 333.457232 -56.085922) (xy 333.510382 -56.081939)
			(xy 333.563532 -56.085922) (xy 333.615494 -56.097782) (xy 333.665108 -56.117254) (xy 333.711266 -56.143903)
			(xy 333.752937 -56.177134) (xy 333.789189 -56.216205) (xy 333.819213 -56.260242) (xy 333.842339 -56.308263)
			(xy 333.858049 -56.359193) (xy 333.865992 -56.411897) (xy 333.86649 -56.438546) (xy 333.865992 -56.465195)
			(xy 334.782658 -56.465195) (xy 334.782658 -56.411897) (xy 334.790601 -56.359193) (xy 334.806311 -56.308263)
			(xy 334.829437 -56.260242) (xy 334.859461 -56.216205) (xy 334.895713 -56.177134) (xy 334.937384 -56.143903)
			(xy 334.983542 -56.117254) (xy 335.033156 -56.097782) (xy 335.085118 -56.085922) (xy 335.138268 -56.081939)
			(xy 335.191418 -56.085922) (xy 335.24338 -56.097782) (xy 335.292994 -56.117254) (xy 335.339152 -56.143903)
			(xy 335.380823 -56.177134) (xy 335.417075 -56.216205) (xy 335.447099 -56.260242) (xy 335.470225 -56.308263)
			(xy 335.485935 -56.359193) (xy 335.493878 -56.411897) (xy 335.494376 -56.438546) (xy 335.493878 -56.465195)
			(xy 336.411814 -56.465195) (xy 336.411814 -56.411897) (xy 336.419757 -56.359193) (xy 336.435467 -56.308263)
			(xy 336.458593 -56.260242) (xy 336.488617 -56.216205) (xy 336.524869 -56.177134) (xy 336.56654 -56.143903)
			(xy 336.612698 -56.117254) (xy 336.662312 -56.097782) (xy 336.714274 -56.085922) (xy 336.767424 -56.081939)
			(xy 336.820574 -56.085922) (xy 336.872536 -56.097782) (xy 336.92215 -56.117254) (xy 336.968308 -56.143903)
			(xy 337.009979 -56.177134) (xy 337.046231 -56.216205) (xy 337.076255 -56.260242) (xy 337.099381 -56.308263)
			(xy 337.115091 -56.359193) (xy 337.123034 -56.411897) (xy 337.123532 -56.438546) (xy 337.123034 -56.465195)
			(xy 338.040208 -56.465195) (xy 338.040208 -56.411897) (xy 338.048151 -56.359193) (xy 338.063861 -56.308263)
			(xy 338.086987 -56.260242) (xy 338.117011 -56.216205) (xy 338.153263 -56.177134) (xy 338.194934 -56.143903)
			(xy 338.241092 -56.117254) (xy 338.290706 -56.097782) (xy 338.342668 -56.085922) (xy 338.395818 -56.081939)
			(xy 338.448968 -56.085922) (xy 338.50093 -56.097782) (xy 338.550544 -56.117254) (xy 338.596702 -56.143903)
			(xy 338.638373 -56.177134) (xy 338.674625 -56.216205) (xy 338.704649 -56.260242) (xy 338.727775 -56.308263)
			(xy 338.743485 -56.359193) (xy 338.751428 -56.411897) (xy 338.751926 -56.438546) (xy 338.751428 -56.465195)
			(xy 339.122248 -56.465195) (xy 339.122248 -56.411897) (xy 339.130191 -56.359193) (xy 339.145901 -56.308263)
			(xy 339.169027 -56.260242) (xy 339.199051 -56.216205) (xy 339.235303 -56.177134) (xy 339.276974 -56.143903)
			(xy 339.323132 -56.117254) (xy 339.372746 -56.097782) (xy 339.424708 -56.085922) (xy 339.477858 -56.081939)
			(xy 339.531008 -56.085922) (xy 339.58297 -56.097782) (xy 339.632584 -56.117254) (xy 339.678742 -56.143903)
			(xy 339.720413 -56.177134) (xy 339.756665 -56.216205) (xy 339.786689 -56.260242) (xy 339.809815 -56.308263)
			(xy 339.825525 -56.359193) (xy 339.833468 -56.411897) (xy 339.833966 -56.438546) (xy 339.833468 -56.465195)
			(xy 340.750388 -56.465195) (xy 340.750388 -56.411897) (xy 340.758331 -56.359193) (xy 340.774041 -56.308263)
			(xy 340.797167 -56.260242) (xy 340.827191 -56.216205) (xy 340.863443 -56.177134) (xy 340.905114 -56.143903)
			(xy 340.951272 -56.117254) (xy 341.000886 -56.097782) (xy 341.052848 -56.085922) (xy 341.105998 -56.081939)
			(xy 341.159148 -56.085922) (xy 341.21111 -56.097782) (xy 341.260724 -56.117254) (xy 341.306882 -56.143903)
			(xy 341.348553 -56.177134) (xy 341.384805 -56.216205) (xy 341.414829 -56.260242) (xy 341.437955 -56.308263)
			(xy 341.453665 -56.359193) (xy 341.461608 -56.411897) (xy 341.462106 -56.438546) (xy 341.461613 -56.464941)
			(xy 342.379544 -56.464941) (xy 342.379544 -56.411643) (xy 342.387487 -56.358939) (xy 342.403197 -56.308009)
			(xy 342.426323 -56.259988) (xy 342.456347 -56.215951) (xy 342.492599 -56.17688) (xy 342.53427 -56.143649)
			(xy 342.580428 -56.117) (xy 342.630042 -56.097528) (xy 342.682004 -56.085668) (xy 342.735154 -56.081685)
			(xy 342.788304 -56.085668) (xy 342.840266 -56.097528) (xy 342.88988 -56.117) (xy 342.936038 -56.143649)
			(xy 342.977709 -56.17688) (xy 343.013961 -56.215951) (xy 343.043985 -56.259988) (xy 343.067111 -56.308009)
			(xy 343.082821 -56.358939) (xy 343.090764 -56.411643) (xy 343.091262 -56.438292) (xy 343.090764 -56.464941)
			(xy 343.082821 -56.517645) (xy 343.067111 -56.568575) (xy 343.043985 -56.616596) (xy 343.013961 -56.660633)
			(xy 342.977709 -56.699704) (xy 342.936038 -56.732935) (xy 342.88988 -56.759584) (xy 342.840266 -56.779056)
			(xy 342.788304 -56.790916) (xy 342.735154 -56.7949) (xy 342.682004 -56.790916) (xy 342.630042 -56.779056)
			(xy 342.580428 -56.759584) (xy 342.53427 -56.732935) (xy 342.492599 -56.699704) (xy 342.456347 -56.660633)
			(xy 342.426323 -56.616596) (xy 342.403197 -56.568575) (xy 342.387487 -56.517645) (xy 342.379544 -56.464941)
			(xy 341.461613 -56.464941) (xy 341.461608 -56.465195) (xy 341.453665 -56.517899) (xy 341.437955 -56.568829)
			(xy 341.414829 -56.61685) (xy 341.384805 -56.660887) (xy 341.348553 -56.699958) (xy 341.306882 -56.733189)
			(xy 341.260724 -56.759838) (xy 341.21111 -56.77931) (xy 341.159148 -56.79117) (xy 341.105998 -56.795154)
			(xy 341.052848 -56.79117) (xy 341.000886 -56.77931) (xy 340.951272 -56.759838) (xy 340.905114 -56.733189)
			(xy 340.863443 -56.699958) (xy 340.827191 -56.660887) (xy 340.797167 -56.61685) (xy 340.774041 -56.568829)
			(xy 340.758331 -56.517899) (xy 340.750388 -56.465195) (xy 339.833468 -56.465195) (xy 339.825525 -56.517899)
			(xy 339.809815 -56.568829) (xy 339.786689 -56.61685) (xy 339.756665 -56.660887) (xy 339.720413 -56.699958)
			(xy 339.678742 -56.733189) (xy 339.632584 -56.759838) (xy 339.58297 -56.77931) (xy 339.531008 -56.79117)
			(xy 339.477858 -56.795154) (xy 339.424708 -56.79117) (xy 339.372746 -56.77931) (xy 339.323132 -56.759838)
			(xy 339.276974 -56.733189) (xy 339.235303 -56.699958) (xy 339.199051 -56.660887) (xy 339.169027 -56.61685)
			(xy 339.145901 -56.568829) (xy 339.130191 -56.517899) (xy 339.122248 -56.465195) (xy 338.751428 -56.465195)
			(xy 338.743485 -56.517899) (xy 338.727775 -56.568829) (xy 338.704649 -56.61685) (xy 338.674625 -56.660887)
			(xy 338.638373 -56.699958) (xy 338.596702 -56.733189) (xy 338.550544 -56.759838) (xy 338.50093 -56.77931)
			(xy 338.448968 -56.79117) (xy 338.395818 -56.795154) (xy 338.342668 -56.79117) (xy 338.290706 -56.77931)
			(xy 338.241092 -56.759838) (xy 338.194934 -56.733189) (xy 338.153263 -56.699958) (xy 338.117011 -56.660887)
			(xy 338.086987 -56.61685) (xy 338.063861 -56.568829) (xy 338.048151 -56.517899) (xy 338.040208 -56.465195)
			(xy 337.123034 -56.465195) (xy 337.115091 -56.517899) (xy 337.099381 -56.568829) (xy 337.076255 -56.61685)
			(xy 337.046231 -56.660887) (xy 337.009979 -56.699958) (xy 336.968308 -56.733189) (xy 336.92215 -56.759838)
			(xy 336.872536 -56.77931) (xy 336.820574 -56.79117) (xy 336.767424 -56.795154) (xy 336.714274 -56.79117)
			(xy 336.662312 -56.77931) (xy 336.612698 -56.759838) (xy 336.56654 -56.733189) (xy 336.524869 -56.699958)
			(xy 336.488617 -56.660887) (xy 336.458593 -56.61685) (xy 336.435467 -56.568829) (xy 336.419757 -56.517899)
			(xy 336.411814 -56.465195) (xy 335.493878 -56.465195) (xy 335.485935 -56.517899) (xy 335.470225 -56.568829)
			(xy 335.447099 -56.61685) (xy 335.417075 -56.660887) (xy 335.380823 -56.699958) (xy 335.339152 -56.733189)
			(xy 335.292994 -56.759838) (xy 335.24338 -56.77931) (xy 335.191418 -56.79117) (xy 335.138268 -56.795154)
			(xy 335.085118 -56.79117) (xy 335.033156 -56.77931) (xy 334.983542 -56.759838) (xy 334.937384 -56.733189)
			(xy 334.895713 -56.699958) (xy 334.859461 -56.660887) (xy 334.829437 -56.61685) (xy 334.806311 -56.568829)
			(xy 334.790601 -56.517899) (xy 334.782658 -56.465195) (xy 333.865992 -56.465195) (xy 333.858049 -56.517899)
			(xy 333.842339 -56.568829) (xy 333.819213 -56.61685) (xy 333.789189 -56.660887) (xy 333.752937 -56.699958)
			(xy 333.711266 -56.733189) (xy 333.665108 -56.759838) (xy 333.615494 -56.77931) (xy 333.563532 -56.79117)
			(xy 333.510382 -56.795154) (xy 333.457232 -56.79117) (xy 333.40527 -56.77931) (xy 333.355656 -56.759838)
			(xy 333.309498 -56.733189) (xy 333.267827 -56.699958) (xy 333.231575 -56.660887) (xy 333.201551 -56.61685)
			(xy 333.178425 -56.568829) (xy 333.162715 -56.517899) (xy 333.154772 -56.465195) (xy 332.556273 -56.465195)
			(xy 332.556385 -56.469152) (xy 332.564541 -56.495536) (xy 332.579477 -56.518764) (xy 332.600098 -56.537133)
			(xy 332.62489 -56.549297) (xy 332.652037 -56.554363) (xy 332.665832 -56.553608) (xy 332.696312 -56.552338)
			(xy 332.723388 -56.552844) (xy 332.776915 -56.561046) (xy 332.828582 -56.577258) (xy 332.877199 -56.601107)
			(xy 332.921644 -56.632043) (xy 332.960893 -56.669351) (xy 332.994039 -56.712173) (xy 333.020319 -56.75952)
			(xy 333.039127 -56.810301) (xy 333.050028 -56.863344) (xy 333.052772 -56.917426) (xy 333.050976 -56.935095)
			(xy 335.597998 -56.935095) (xy 335.597998 -56.881797) (xy 335.605941 -56.829093) (xy 335.621651 -56.778163)
			(xy 335.644777 -56.730142) (xy 335.674801 -56.686105) (xy 335.711053 -56.647034) (xy 335.752724 -56.613803)
			(xy 335.798882 -56.587154) (xy 335.848496 -56.567682) (xy 335.900458 -56.555822) (xy 335.953608 -56.551839)
			(xy 336.006758 -56.555822) (xy 336.05872 -56.567682) (xy 336.108334 -56.587154) (xy 336.154492 -56.613803)
			(xy 336.196163 -56.647034) (xy 336.232415 -56.686105) (xy 336.262439 -56.730142) (xy 336.285565 -56.778163)
			(xy 336.301275 -56.829093) (xy 336.309218 -56.881797) (xy 336.309716 -56.908446) (xy 336.309218 -56.935095)
			(xy 337.225884 -56.935095) (xy 337.225884 -56.881797) (xy 337.233827 -56.829093) (xy 337.249537 -56.778163)
			(xy 337.272663 -56.730142) (xy 337.302687 -56.686105) (xy 337.338939 -56.647034) (xy 337.38061 -56.613803)
			(xy 337.426768 -56.587154) (xy 337.476382 -56.567682) (xy 337.528344 -56.555822) (xy 337.581494 -56.551839)
			(xy 337.634644 -56.555822) (xy 337.686606 -56.567682) (xy 337.73622 -56.587154) (xy 337.782378 -56.613803)
			(xy 337.824049 -56.647034) (xy 337.860301 -56.686105) (xy 337.890325 -56.730142) (xy 337.913451 -56.778163)
			(xy 337.929161 -56.829093) (xy 337.937104 -56.881797) (xy 337.937602 -56.908446) (xy 337.937104 -56.935095)
			(xy 337.929161 -56.987799) (xy 337.913451 -57.038729) (xy 337.890325 -57.08675) (xy 337.860301 -57.130787)
			(xy 337.824049 -57.169858) (xy 337.782378 -57.203089) (xy 337.73622 -57.229738) (xy 337.686606 -57.24921)
			(xy 337.634644 -57.26107) (xy 337.581494 -57.265054) (xy 337.528344 -57.26107) (xy 337.476382 -57.24921)
			(xy 337.426768 -57.229738) (xy 337.38061 -57.203089) (xy 337.338939 -57.169858) (xy 337.302687 -57.130787)
			(xy 337.272663 -57.08675) (xy 337.249537 -57.038729) (xy 337.233827 -56.987799) (xy 337.225884 -56.935095)
			(xy 336.309218 -56.935095) (xy 336.301275 -56.987799) (xy 336.285565 -57.038729) (xy 336.262439 -57.08675)
			(xy 336.232415 -57.130787) (xy 336.196163 -57.169858) (xy 336.154492 -57.203089) (xy 336.108334 -57.229738)
			(xy 336.05872 -57.24921) (xy 336.006758 -57.26107) (xy 335.953608 -57.265054) (xy 335.900458 -57.26107)
			(xy 335.848496 -57.24921) (xy 335.798882 -57.229738) (xy 335.752724 -57.203089) (xy 335.711053 -57.169858)
			(xy 335.674801 -57.130787) (xy 335.644777 -57.08675) (xy 335.621651 -57.038729) (xy 335.605941 -56.987799)
			(xy 335.597998 -56.935095) (xy 333.050976 -56.935095) (xy 333.047295 -56.971299) (xy 333.033723 -57.023723)
			(xy 333.01237 -57.073486) (xy 332.983727 -57.119443) (xy 332.948456 -57.160532) (xy 332.90737 -57.195807)
			(xy 332.861417 -57.224454) (xy 332.811655 -57.245812) (xy 332.759233 -57.259389) (xy 332.70536 -57.264871)
			(xy 332.651277 -57.262132) (xy 332.598234 -57.251236) (xy 332.547451 -57.232433) (xy 332.500102 -57.206158)
			(xy 332.457277 -57.173016) (xy 332.419964 -57.133771) (xy 332.389024 -57.089329) (xy 332.365171 -57.040714)
			(xy 332.348954 -56.989048) (xy 332.340747 -56.935522) (xy 332.340204 -56.908446) (xy 332.341474 -56.877966)
			(xy 332.34218 -56.864183) (xy 332.337063 -56.837076) (xy 332.324876 -56.812328) (xy 332.306509 -56.791745)
			(xy 332.283303 -56.776829) (xy 332.256951 -56.76867) (xy 332.229377 -56.767862) (xy 332.202592 -56.774464)
			(xy 332.178552 -56.787995) (xy 332.1685 -56.797448) (xy 331.481959 -57.483989) (xy 338.04478 -57.483989)
			(xy 338.04478 -57.430691) (xy 338.052723 -57.377987) (xy 338.068433 -57.327057) (xy 338.091559 -57.279036)
			(xy 338.121583 -57.234999) (xy 338.157835 -57.195928) (xy 338.199506 -57.162697) (xy 338.245664 -57.136048)
			(xy 338.295278 -57.116576) (xy 338.34724 -57.104716) (xy 338.40039 -57.100733) (xy 338.45354 -57.104716)
			(xy 338.505502 -57.116576) (xy 338.555116 -57.136048) (xy 338.601274 -57.162697) (xy 338.642945 -57.195928)
			(xy 338.679197 -57.234999) (xy 338.709221 -57.279036) (xy 338.732347 -57.327057) (xy 338.748057 -57.377987)
			(xy 338.756 -57.430691) (xy 338.756498 -57.45734) (xy 338.756 -57.483989) (xy 338.748057 -57.536693)
			(xy 338.732347 -57.587623) (xy 338.709221 -57.635644) (xy 338.679197 -57.679681) (xy 338.642945 -57.718752)
			(xy 338.601274 -57.751983) (xy 338.555116 -57.778632) (xy 338.505502 -57.798104) (xy 338.45354 -57.809964)
			(xy 338.40039 -57.813948) (xy 338.34724 -57.809964) (xy 338.295278 -57.798104) (xy 338.245664 -57.778632)
			(xy 338.199506 -57.751983) (xy 338.157835 -57.718752) (xy 338.121583 -57.679681) (xy 338.091559 -57.635644)
			(xy 338.068433 -57.587623) (xy 338.052723 -57.536693) (xy 338.04478 -57.483989) (xy 331.481959 -57.483989)
			(xy 329.0824 -59.883548) (xy 329.943714 -59.883548) (xy 329.944212 -59.856899) (xy 329.952155 -59.804195)
			(xy 329.967865 -59.753265) (xy 329.990991 -59.705244) (xy 330.021015 -59.661207) (xy 330.057267 -59.622136)
			(xy 330.098938 -59.588905) (xy 330.145096 -59.562256) (xy 330.19471 -59.542784) (xy 330.246672 -59.530924)
			(xy 330.299822 -59.526941) (xy 330.352972 -59.530924) (xy 330.404934 -59.542784) (xy 330.454548 -59.562256)
			(xy 330.500706 -59.588905) (xy 330.542377 -59.622136) (xy 330.578629 -59.661207) (xy 330.608653 -59.705244)
			(xy 330.631779 -59.753265) (xy 330.647489 -59.804195) (xy 330.655432 -59.856899) (xy 330.65593 -59.883548)
			(xy 330.655362 -59.912474) (xy 330.64603 -59.969567) (xy 330.627603 -60.024404) (xy 330.600563 -60.075547)
			(xy 330.588731 -60.091807) (xy 332.15579 -60.091807) (xy 332.15579 -60.038509) (xy 332.163733 -59.985805)
			(xy 332.179443 -59.934875) (xy 332.202569 -59.886854) (xy 332.232593 -59.842817) (xy 332.268845 -59.803746)
			(xy 332.310516 -59.770515) (xy 332.356674 -59.743866) (xy 332.406288 -59.724394) (xy 332.45825 -59.712534)
			(xy 332.5114 -59.708551) (xy 332.56455 -59.712534) (xy 332.616512 -59.724394) (xy 332.666126 -59.743866)
			(xy 332.712284 -59.770515) (xy 332.753955 -59.803746) (xy 332.790207 -59.842817) (xy 332.820231 -59.886854)
			(xy 332.843357 -59.934875) (xy 332.859067 -59.985805) (xy 332.86701 -60.038509) (xy 332.867508 -60.065158)
			(xy 332.86701 -60.091807) (xy 332.859067 -60.144511) (xy 332.855815 -60.155053) (xy 335.428834 -60.155053)
			(xy 335.428834 -60.101755) (xy 335.436777 -60.049051) (xy 335.452487 -59.998121) (xy 335.475613 -59.9501)
			(xy 335.505637 -59.906063) (xy 335.541889 -59.866992) (xy 335.58356 -59.833761) (xy 335.629718 -59.807112)
			(xy 335.679332 -59.78764) (xy 335.731294 -59.77578) (xy 335.784444 -59.771797) (xy 335.837594 -59.77578)
			(xy 335.889556 -59.78764) (xy 335.93917 -59.807112) (xy 335.985328 -59.833761) (xy 336.026999 -59.866992)
			(xy 336.063251 -59.906063) (xy 336.069879 -59.915785) (xy 336.544148 -59.915785) (xy 336.544148 -59.862487)
			(xy 336.552091 -59.809783) (xy 336.567801 -59.758853) (xy 336.590927 -59.710832) (xy 336.620951 -59.666795)
			(xy 336.657203 -59.627724) (xy 336.698874 -59.594493) (xy 336.745032 -59.567844) (xy 336.794646 -59.548372)
			(xy 336.846608 -59.536512) (xy 336.899758 -59.532529) (xy 336.952908 -59.536512) (xy 337.00487 -59.548372)
			(xy 337.054484 -59.567844) (xy 337.100642 -59.594493) (xy 337.142313 -59.627724) (xy 337.178565 -59.666795)
			(xy 337.208589 -59.710832) (xy 337.231715 -59.758853) (xy 337.237742 -59.778392) (xy 338.414878 -59.778392)
			(xy 338.418854 -59.724066) (xy 338.430697 -59.670897) (xy 338.450156 -59.62002) (xy 338.476816 -59.572518)
			(xy 338.510107 -59.529404) (xy 338.549321 -59.491597) (xy 338.593623 -59.459902) (xy 338.642066 -59.434996)
			(xy 338.69362 -59.417408) (xy 338.747186 -59.407514) (xy 338.801621 -59.405524) (xy 338.855766 -59.411482)
			(xy 338.908466 -59.42526) (xy 338.958599 -59.446564) (xy 339.005095 -59.47494) (xy 339.046965 -59.509784)
			(xy 339.083314 -59.550353) (xy 339.11337 -59.595782) (xy 339.136491 -59.645103) (xy 339.152184 -59.697265)
			(xy 339.160115 -59.751156) (xy 339.160612 -59.778392) (xy 339.160115 -59.805628) (xy 339.152184 -59.859519)
			(xy 339.136491 -59.911681) (xy 339.11337 -59.961002) (xy 339.083314 -60.006431) (xy 339.046965 -60.047)
			(xy 339.005095 -60.081844) (xy 338.958599 -60.11022) (xy 338.908466 -60.131524) (xy 338.855766 -60.145302)
			(xy 338.801621 -60.15126) (xy 338.747186 -60.14927) (xy 338.69362 -60.139376) (xy 338.642066 -60.121788)
			(xy 338.593623 -60.096882) (xy 338.549321 -60.065187) (xy 338.510107 -60.02738) (xy 338.476816 -59.984266)
			(xy 338.450156 -59.936764) (xy 338.430697 -59.885887) (xy 338.418854 -59.832718) (xy 338.414878 -59.778392)
			(xy 337.237742 -59.778392) (xy 337.247425 -59.809783) (xy 337.255368 -59.862487) (xy 337.255866 -59.889136)
			(xy 337.255368 -59.915785) (xy 337.247425 -59.968489) (xy 337.231715 -60.019419) (xy 337.208589 -60.06744)
			(xy 337.178565 -60.111477) (xy 337.142313 -60.150548) (xy 337.100642 -60.183779) (xy 337.054484 -60.210428)
			(xy 337.00487 -60.2299) (xy 336.952908 -60.24176) (xy 336.899758 -60.245744) (xy 336.846608 -60.24176)
			(xy 336.794646 -60.2299) (xy 336.745032 -60.210428) (xy 336.698874 -60.183779) (xy 336.657203 -60.150548)
			(xy 336.620951 -60.111477) (xy 336.590927 -60.06744) (xy 336.567801 -60.019419) (xy 336.552091 -59.968489)
			(xy 336.544148 -59.915785) (xy 336.069879 -59.915785) (xy 336.093275 -59.9501) (xy 336.116401 -59.998121)
			(xy 336.132111 -60.049051) (xy 336.140054 -60.101755) (xy 336.140552 -60.128404) (xy 336.140054 -60.155053)
			(xy 336.132111 -60.207757) (xy 336.116401 -60.258687) (xy 336.093275 -60.306708) (xy 336.063251 -60.350745)
			(xy 336.026999 -60.389816) (xy 335.985328 -60.423047) (xy 335.93917 -60.449696) (xy 335.889556 -60.469168)
			(xy 335.837594 -60.481028) (xy 335.784444 -60.485012) (xy 335.731294 -60.481028) (xy 335.679332 -60.469168)
			(xy 335.629718 -60.449696) (xy 335.58356 -60.423047) (xy 335.541889 -60.389816) (xy 335.505637 -60.350745)
			(xy 335.475613 -60.306708) (xy 335.452487 -60.258687) (xy 335.436777 -60.207757) (xy 335.428834 -60.155053)
			(xy 332.855815 -60.155053) (xy 332.843357 -60.195441) (xy 332.820231 -60.243462) (xy 332.790207 -60.287499)
			(xy 332.753955 -60.32657) (xy 332.712284 -60.359801) (xy 332.666126 -60.38645) (xy 332.616512 -60.405922)
			(xy 332.56455 -60.417782) (xy 332.5114 -60.421766) (xy 332.45825 -60.417782) (xy 332.406288 -60.405922)
			(xy 332.356674 -60.38645) (xy 332.310516 -60.359801) (xy 332.268845 -60.32657) (xy 332.232593 -60.287499)
			(xy 332.202569 -60.243462) (xy 332.179443 -60.195441) (xy 332.163733 -60.144511) (xy 332.15579 -60.091807)
			(xy 330.588731 -60.091807) (xy 330.58354 -60.09894) (xy 330.575351 -60.110416) (xy 330.565113 -60.136675)
			(xy 330.56244 -60.164732) (xy 330.567535 -60.192452) (xy 330.580011 -60.217725) (xy 330.589128 -60.22848)
			(xy 330.606423 -60.248226) (xy 330.635583 -60.291874) (xy 330.658012 -60.339333) (xy 330.673223 -60.389572)
			(xy 330.680886 -60.441502) (xy 330.68133 -60.467748) (xy 330.680832 -60.494397) (xy 330.672889 -60.547101)
			(xy 330.657179 -60.598031) (xy 330.634053 -60.646052) (xy 330.604029 -60.690089) (xy 330.567777 -60.72916)
			(xy 330.526106 -60.762391) (xy 330.479948 -60.78904) (xy 330.430334 -60.808512) (xy 330.378372 -60.820372)
			(xy 330.325222 -60.824356) (xy 330.272072 -60.820372) (xy 330.22011 -60.808512) (xy 330.170496 -60.78904)
			(xy 330.124338 -60.762391) (xy 330.082667 -60.72916) (xy 330.046415 -60.690089) (xy 330.016391 -60.646052)
			(xy 329.993265 -60.598031) (xy 329.977555 -60.547101) (xy 329.969612 -60.494397) (xy 329.969114 -60.467748)
			(xy 329.969671 -60.438822) (xy 329.979005 -60.381728) (xy 329.997435 -60.32689) (xy 330.024479 -60.275748)
			(xy 330.041504 -60.252356) (xy 330.049703 -60.240886) (xy 330.059947 -60.214625) (xy 330.062621 -60.186565)
			(xy 330.057522 -60.158842) (xy 330.045038 -60.133569) (xy 330.035916 -60.122816) (xy 330.018626 -60.103065)
			(xy 329.989464 -60.05942) (xy 329.967033 -60.011962) (xy 329.951821 -59.961723) (xy 329.944158 -59.909794)
			(xy 329.943714 -59.883548) (xy 329.0824 -59.883548) (xy 328.9808 -59.985148) (xy 328.97572 -59.985148)
			(xy 328.96219 -59.985609) (xy 328.936099 -59.992796) (xy 328.912815 -60.006589) (xy 328.893976 -60.026019)
			(xy 328.880908 -60.049718) (xy 328.874531 -60.076018) (xy 328.875292 -60.103071) (xy 328.883138 -60.128971)
			(xy 328.897518 -60.151897) (xy 328.90714 -60.161424) (xy 328.9262 -60.179574) (xy 328.959654 -60.220207)
			(xy 328.987209 -60.265048) (xy 329.008345 -60.31325) (xy 329.022659 -60.363898) (xy 329.029882 -60.416032)
			(xy 329.03033 -60.442348) (xy 329.029847 -60.469818) (xy 329.021958 -60.524188) (xy 329.00635 -60.576864)
			(xy 328.983346 -60.626756) (xy 328.953422 -60.672831) (xy 328.917197 -60.714136) (xy 328.875421 -60.749817)
			(xy 328.828958 -60.779134) (xy 328.778769 -60.801483) (xy 328.752454 -60.809378) (xy 328.739059 -60.813626)
			(xy 328.715133 -60.828342) (xy 328.69613 -60.849028) (xy 328.683494 -60.874115) (xy 328.678183 -60.901699)
			(xy 328.6806 -60.929684) (xy 328.685144 -60.942982) (xy 328.696493 -60.97541) (xy 328.708764 -61.043)
			(xy 328.709528 -61.077348) (xy 328.709042 -61.104599) (xy 328.701286 -61.158547) (xy 328.685931 -61.210842)
			(xy 328.663289 -61.260419) (xy 328.633823 -61.306269) (xy 328.598132 -61.34746) (xy 328.556941 -61.383151)
			(xy 328.511091 -61.412617) (xy 328.461514 -61.435259) (xy 328.409219 -61.450614) (xy 328.355271 -61.45837)
			(xy 328.300769 -61.45837) (xy 328.246821 -61.450614) (xy 328.194526 -61.435259) (xy 328.144949 -61.412617)
			(xy 328.099099 -61.383151) (xy 328.057908 -61.34746) (xy 328.022217 -61.306269) (xy 327.992751 -61.260419)
			(xy 327.970109 -61.210842) (xy 327.954754 -61.158547) (xy 327.946998 -61.104599) (xy 327.946512 -61.077348)
			(xy 327.946995 -61.049879) (xy 327.954885 -60.995511) (xy 327.970494 -60.942837) (xy 327.9935 -60.892948)
			(xy 328.023425 -60.846876) (xy 328.059652 -60.805575) (xy 328.101429 -60.769899) (xy 328.147893 -60.740586)
			(xy 328.198083 -60.718243) (xy 328.224388 -60.710318) (xy 328.237778 -60.706066) (xy 328.261694 -60.691346)
			(xy 328.280687 -60.67066) (xy 328.293317 -60.645577) (xy 328.298625 -60.618) (xy 328.296209 -60.590021)
			(xy 328.291698 -60.576714) (xy 328.280348 -60.544287) (xy 328.268076 -60.476696) (xy 328.267314 -60.442348)
			(xy 328.267733 -60.416028) (xy 328.274929 -60.363882) (xy 328.289231 -60.313223) (xy 328.310367 -60.265013)
			(xy 328.337937 -60.22017) (xy 328.371414 -60.179548) (xy 328.390504 -60.161424) (xy 328.40017 -60.151934)
			(xy 328.414553 -60.128991) (xy 328.4224 -60.103074) (xy 328.42316 -60.076006) (xy 328.416779 -60.04969)
			(xy 328.403706 -60.025976) (xy 328.38486 -60.006531) (xy 328.361566 -59.992724) (xy 328.335462 -59.985524)
			(xy 328.321924 -59.985148) (xy 321.5132 -59.985148) (xy 320.7258 -60.772548) (xy 320.7258 -60.780168)
			(xy 324.311262 -60.780168) (xy 324.315333 -60.724546) (xy 324.327459 -60.670109) (xy 324.347382 -60.618018)
			(xy 324.374678 -60.569383) (xy 324.408764 -60.52524) (xy 324.448913 -60.486531) (xy 324.494271 -60.45408)
			(xy 324.543871 -60.428579) (xy 324.596655 -60.410572) (xy 324.651498 -60.400442) (xy 324.707232 -60.398405)
			(xy 324.762669 -60.404505) (xy 324.816626 -60.418611) (xy 324.867955 -60.440423) (xy 324.915561 -60.469477)
			(xy 324.958429 -60.505152) (xy 324.995646 -60.546689) (xy 325.026419 -60.593202) (xy 325.050091 -60.643699)
			(xy 325.066159 -60.697106) (xy 325.074279 -60.752282) (xy 325.074788 -60.780168) (xy 325.074279 -60.808054)
			(xy 325.066159 -60.86323) (xy 325.050091 -60.916637) (xy 325.026419 -60.967134) (xy 324.995646 -61.013647)
			(xy 324.958429 -61.055184) (xy 324.936069 -61.073792) (xy 326.93178 -61.073792) (xy 326.935851 -61.01817)
			(xy 326.947977 -60.963733) (xy 326.9679 -60.911642) (xy 326.995196 -60.863007) (xy 327.029282 -60.818864)
			(xy 327.069431 -60.780155) (xy 327.114789 -60.747704) (xy 327.164389 -60.722203) (xy 327.217173 -60.704196)
			(xy 327.272016 -60.694066) (xy 327.32775 -60.692029) (xy 327.383187 -60.698129) (xy 327.437144 -60.712235)
			(xy 327.488473 -60.734047) (xy 327.536079 -60.763101) (xy 327.578947 -60.798776) (xy 327.616164 -60.840313)
			(xy 327.646937 -60.886826) (xy 327.670609 -60.937323) (xy 327.686677 -60.99073) (xy 327.694797 -61.045906)
			(xy 327.695306 -61.073792) (xy 327.694797 -61.101678) (xy 327.686677 -61.156854) (xy 327.670609 -61.210261)
			(xy 327.646937 -61.260758) (xy 327.616164 -61.307271) (xy 327.578947 -61.348808) (xy 327.536079 -61.384483)
			(xy 327.488473 -61.413537) (xy 327.437144 -61.435349) (xy 327.383187 -61.449455) (xy 327.32775 -61.455555)
			(xy 327.272016 -61.453518) (xy 327.217173 -61.443388) (xy 327.164389 -61.425381) (xy 327.114789 -61.39988)
			(xy 327.069431 -61.367429) (xy 327.029282 -61.32872) (xy 326.995196 -61.284577) (xy 326.9679 -61.235942)
			(xy 326.947977 -61.183851) (xy 326.935851 -61.129414) (xy 326.93178 -61.073792) (xy 324.936069 -61.073792)
			(xy 324.915561 -61.090859) (xy 324.867955 -61.119913) (xy 324.816626 -61.141725) (xy 324.762669 -61.155831)
			(xy 324.707232 -61.161931) (xy 324.651498 -61.159894) (xy 324.596655 -61.149764) (xy 324.543871 -61.131757)
			(xy 324.494271 -61.106256) (xy 324.448913 -61.073805) (xy 324.408764 -61.035096) (xy 324.374678 -60.990953)
			(xy 324.347382 -60.942318) (xy 324.327459 -60.890227) (xy 324.315333 -60.83579) (xy 324.311262 -60.780168)
			(xy 320.7258 -60.780168) (xy 320.7258 -62.151768) (xy 321.363592 -62.151768) (xy 321.367663 -62.096146)
			(xy 321.379789 -62.041709) (xy 321.399712 -61.989618) (xy 321.427008 -61.940983) (xy 321.461094 -61.89684)
			(xy 321.501243 -61.858131) (xy 321.546601 -61.82568) (xy 321.596201 -61.800179) (xy 321.648985 -61.782172)
			(xy 321.703828 -61.772042) (xy 321.759562 -61.770005) (xy 321.814999 -61.776105) (xy 321.868956 -61.790211)
			(xy 321.920285 -61.812023) (xy 321.967891 -61.841077) (xy 322.010759 -61.876752) (xy 322.047976 -61.918289)
			(xy 322.078749 -61.964802) (xy 322.102421 -62.015299) (xy 322.118489 -62.068706) (xy 322.126609 -62.123882)
			(xy 322.127118 -62.151768) (xy 322.126609 -62.179654) (xy 322.118489 -62.23483) (xy 322.11146 -62.258194)
			(xy 335.89163 -62.258194) (xy 335.895701 -62.202572) (xy 335.907827 -62.148135) (xy 335.92775 -62.096044)
			(xy 335.955046 -62.047409) (xy 335.989132 -62.003266) (xy 336.029281 -61.964557) (xy 336.074639 -61.932106)
			(xy 336.124239 -61.906605) (xy 336.177023 -61.888598) (xy 336.231866 -61.878468) (xy 336.2876 -61.876431)
			(xy 336.343037 -61.882531) (xy 336.396994 -61.896637) (xy 336.448323 -61.918449) (xy 336.495929 -61.947503)
			(xy 336.538797 -61.983178) (xy 336.576014 -62.024715) (xy 336.606787 -62.071228) (xy 336.630459 -62.121725)
			(xy 336.646527 -62.175132) (xy 336.654647 -62.230308) (xy 336.655156 -62.258194) (xy 336.654647 -62.28608)
			(xy 336.646527 -62.341256) (xy 336.630459 -62.394663) (xy 336.606787 -62.44516) (xy 336.576014 -62.491673)
			(xy 336.538797 -62.53321) (xy 336.495929 -62.568885) (xy 336.448323 -62.597939) (xy 336.396994 -62.619751)
			(xy 336.343037 -62.633857) (xy 336.2876 -62.639957) (xy 336.231866 -62.63792) (xy 336.177023 -62.62779)
			(xy 336.124239 -62.609783) (xy 336.074639 -62.584282) (xy 336.029281 -62.551831) (xy 335.989132 -62.513122)
			(xy 335.955046 -62.468979) (xy 335.92775 -62.420344) (xy 335.907827 -62.368253) (xy 335.895701 -62.313816)
			(xy 335.89163 -62.258194) (xy 322.11146 -62.258194) (xy 322.102421 -62.288237) (xy 322.078749 -62.338734)
			(xy 322.047976 -62.385247) (xy 322.010759 -62.426784) (xy 321.967891 -62.462459) (xy 321.920285 -62.491513)
			(xy 321.868956 -62.513325) (xy 321.814999 -62.527431) (xy 321.759562 -62.533531) (xy 321.703828 -62.531494)
			(xy 321.648985 -62.521364) (xy 321.596201 -62.503357) (xy 321.546601 -62.477856) (xy 321.501243 -62.445405)
			(xy 321.461094 -62.406696) (xy 321.427008 -62.362553) (xy 321.399712 -62.313918) (xy 321.379789 -62.261827)
			(xy 321.367663 -62.20739) (xy 321.363592 -62.151768) (xy 320.7258 -62.151768) (xy 320.7258 -63.495428)
			(xy 320.944492 -63.495428) (xy 320.948563 -63.439806) (xy 320.960689 -63.385369) (xy 320.980612 -63.333278)
			(xy 321.007908 -63.284643) (xy 321.041994 -63.2405) (xy 321.082143 -63.201791) (xy 321.127501 -63.16934)
			(xy 321.177101 -63.143839) (xy 321.229885 -63.125832) (xy 321.284728 -63.115702) (xy 321.340462 -63.113665)
			(xy 321.395899 -63.119765) (xy 321.449856 -63.133871) (xy 321.501185 -63.155683) (xy 321.548791 -63.184737)
			(xy 321.591659 -63.220412) (xy 321.628876 -63.261949) (xy 321.659649 -63.308462) (xy 321.683321 -63.358959)
			(xy 321.699389 -63.412366) (xy 321.707509 -63.467542) (xy 321.708018 -63.495428) (xy 321.707509 -63.523314)
			(xy 321.699389 -63.57849) (xy 321.683321 -63.631897) (xy 321.659649 -63.682394) (xy 321.628876 -63.728907)
			(xy 321.591659 -63.770444) (xy 321.548791 -63.806119) (xy 321.501185 -63.835173) (xy 321.449856 -63.856985)
			(xy 321.395899 -63.871091) (xy 321.340462 -63.877191) (xy 321.284728 -63.875154) (xy 321.229885 -63.865024)
			(xy 321.177101 -63.847017) (xy 321.127501 -63.821516) (xy 321.082143 -63.789065) (xy 321.041994 -63.750356)
			(xy 321.007908 -63.706213) (xy 320.980612 -63.657578) (xy 320.960689 -63.605487) (xy 320.948563 -63.55105)
			(xy 320.944492 -63.495428) (xy 320.7258 -63.495428) (xy 320.7258 -64.302453) (xy 324.698563 -64.302453)
			(xy 324.698563 -64.247947) (xy 324.706321 -64.193996) (xy 324.721677 -64.141698) (xy 324.74432 -64.092118)
			(xy 324.773789 -64.046265) (xy 324.809483 -64.005073) (xy 324.850677 -63.96938) (xy 324.89653 -63.939913)
			(xy 324.946111 -63.917272) (xy 324.99841 -63.901918) (xy 325.052361 -63.894162) (xy 325.079614 -63.8937)
			(xy 325.108205 -63.894233) (xy 325.164746 -63.902768) (xy 325.219375 -63.91966) (xy 325.270865 -63.944528)
			(xy 325.294752 -63.960248) (xy 325.307244 -63.968192) (xy 325.335418 -63.977232) (xy 325.365002 -63.977815)
			(xy 325.39351 -63.969892) (xy 325.418551 -63.954128) (xy 325.438021 -63.931847) (xy 325.444612 -63.918592)
			(xy 325.455469 -63.895672) (xy 325.482403 -63.852697) (xy 325.514806 -63.81368) (xy 325.552103 -63.779312)
			(xy 325.572628 -63.764414) (xy 325.583496 -63.756324) (xy 325.600754 -63.735448) (xy 325.611927 -63.710772)
			(xy 325.616229 -63.684029) (xy 325.61336 -63.657095) (xy 325.60352 -63.631858) (xy 325.5874 -63.610091)
			(xy 325.56613 -63.593319) (xy 325.553832 -63.58763) (xy 325.528289 -63.576337) (xy 325.480571 -63.547317)
			(xy 325.437594 -63.51165) (xy 325.400276 -63.470098) (xy 325.369416 -63.423548) (xy 325.345673 -63.372997)
			(xy 325.329555 -63.319524) (xy 325.321404 -63.264273) (xy 325.320914 -63.236348) (xy 325.3214 -63.209097)
			(xy 325.329156 -63.155149) (xy 325.344511 -63.102854) (xy 325.367153 -63.053277) (xy 325.396619 -63.007427)
			(xy 325.43231 -62.966236) (xy 325.473501 -62.930545) (xy 325.519351 -62.901079) (xy 325.568928 -62.878437)
			(xy 325.621223 -62.863082) (xy 325.675171 -62.855326) (xy 325.729673 -62.855326) (xy 325.783621 -62.863082)
			(xy 325.835916 -62.878437) (xy 325.840976 -62.880748) (xy 327.352404 -62.880748) (xy 327.356475 -62.825126)
			(xy 327.368601 -62.770689) (xy 327.388524 -62.718598) (xy 327.41582 -62.669963) (xy 327.449906 -62.62582)
			(xy 327.490055 -62.587111) (xy 327.535413 -62.55466) (xy 327.585013 -62.529159) (xy 327.637797 -62.511152)
			(xy 327.69264 -62.501022) (xy 327.748374 -62.498985) (xy 327.803811 -62.505085) (xy 327.857768 -62.519191)
			(xy 327.909097 -62.541003) (xy 327.956703 -62.570057) (xy 327.999571 -62.605732) (xy 328.036788 -62.647269)
			(xy 328.067561 -62.693782) (xy 328.091233 -62.744279) (xy 328.107301 -62.797686) (xy 328.115421 -62.852862)
			(xy 328.11593 -62.880748) (xy 328.115421 -62.908634) (xy 328.107301 -62.96381) (xy 328.091233 -63.017217)
			(xy 328.067561 -63.067714) (xy 328.036788 -63.114227) (xy 327.999571 -63.155764) (xy 327.956703 -63.191439)
			(xy 327.909097 -63.220493) (xy 327.857768 -63.242305) (xy 327.803811 -63.256411) (xy 327.748374 -63.262511)
			(xy 327.69264 -63.260474) (xy 327.637797 -63.250344) (xy 327.585013 -63.232337) (xy 327.535413 -63.206836)
			(xy 327.490055 -63.174385) (xy 327.449906 -63.135676) (xy 327.41582 -63.091533) (xy 327.388524 -63.042898)
			(xy 327.368601 -62.990807) (xy 327.356475 -62.93637) (xy 327.352404 -62.880748) (xy 325.840976 -62.880748)
			(xy 325.885493 -62.901079) (xy 325.931343 -62.930545) (xy 325.972534 -62.966236) (xy 326.008225 -63.007427)
			(xy 326.037691 -63.053277) (xy 326.060333 -63.102854) (xy 326.075688 -63.155149) (xy 326.083444 -63.209097)
			(xy 326.08393 -63.236348) (xy 326.083479 -63.262481) (xy 326.079388 -63.292228) (xy 326.188322 -63.292228)
			(xy 326.192393 -63.236606) (xy 326.204519 -63.182169) (xy 326.224442 -63.130078) (xy 326.251738 -63.081443)
			(xy 326.285824 -63.0373) (xy 326.325973 -62.998591) (xy 326.371331 -62.96614) (xy 326.420931 -62.940639)
			(xy 326.473715 -62.922632) (xy 326.528558 -62.912502) (xy 326.584292 -62.910465) (xy 326.639729 -62.916565)
			(xy 326.693686 -62.930671) (xy 326.745015 -62.952483) (xy 326.792621 -62.981537) (xy 326.835489 -63.017212)
			(xy 326.872706 -63.058749) (xy 326.903479 -63.105262) (xy 326.927151 -63.155759) (xy 326.943219 -63.209166)
			(xy 326.951339 -63.264342) (xy 326.951848 -63.292228) (xy 326.951339 -63.320114) (xy 326.943219 -63.37529)
			(xy 326.927151 -63.428697) (xy 326.903479 -63.479194) (xy 326.872706 -63.525707) (xy 326.835489 -63.567244)
			(xy 326.792621 -63.602919) (xy 326.745015 -63.631973) (xy 326.693686 -63.653785) (xy 326.639729 -63.667891)
			(xy 326.584292 -63.673991) (xy 326.528558 -63.671954) (xy 326.473715 -63.661824) (xy 326.420931 -63.643817)
			(xy 326.371331 -63.618316) (xy 326.325973 -63.585865) (xy 326.285824 -63.547156) (xy 326.251738 -63.503013)
			(xy 326.224442 -63.454378) (xy 326.204519 -63.402287) (xy 326.192393 -63.34785) (xy 326.188322 -63.292228)
			(xy 326.079388 -63.292228) (xy 326.076358 -63.314258) (xy 326.062227 -63.364577) (xy 326.041353 -63.412492)
			(xy 326.014127 -63.457106) (xy 325.98106 -63.49758) (xy 325.942772 -63.533157) (xy 325.921624 -63.548514)
			(xy 325.910842 -63.556706) (xy 325.893594 -63.577564) (xy 325.882426 -63.602218) (xy 325.878119 -63.628939)
			(xy 325.880976 -63.655853) (xy 325.890797 -63.681074) (xy 325.906893 -63.702834) (xy 325.928135 -63.719606)
			(xy 325.94042 -63.725298) (xy 325.965956 -63.736664) (xy 326.013728 -63.76568) (xy 326.056756 -63.801354)
			(xy 326.094119 -63.842923) (xy 326.125019 -63.889498) (xy 326.148794 -63.940083) (xy 326.164936 -63.993594)
			(xy 326.173099 -64.048888) (xy 326.173592 -64.076834) (xy 326.173592 -64.940434) (xy 326.173107 -64.967703)
			(xy 326.165342 -65.021685) (xy 326.149974 -65.074013) (xy 326.127316 -65.123621) (xy 326.097829 -65.1695)
			(xy 326.062114 -65.210717) (xy 326.020897 -65.246431) (xy 325.975017 -65.275918) (xy 325.925409 -65.298575)
			(xy 325.873081 -65.313943) (xy 325.819099 -65.321708) (xy 325.79183 -65.322196) (xy 325.75978 -65.321509)
			(xy 325.69658 -65.310792) (xy 325.6661 -65.30086) (xy 325.65338 -65.296925) (xy 325.626837 -65.294976)
			(xy 325.600694 -65.299959) (xy 325.57673 -65.311536) (xy 325.556577 -65.328918) (xy 325.541607 -65.350923)
			(xy 325.536814 -65.363344) (xy 325.527796 -65.387932) (xy 325.503939 -65.434556) (xy 325.473928 -65.477478)
			(xy 325.438327 -65.51589) (xy 325.426717 -65.525396) (xy 331.2287 -65.525396) (xy 331.229226 -65.498352)
			(xy 331.236852 -65.444806) (xy 331.251967 -65.392874) (xy 331.274266 -65.343597) (xy 331.303302 -65.297965)
			(xy 331.338493 -65.256892) (xy 331.379133 -65.221202) (xy 331.424407 -65.191611) (xy 331.473407 -65.168711)
			(xy 331.525151 -65.152964) (xy 331.5786 -65.144683) (xy 331.605636 -65.143888) (xy 331.621344 -65.143096)
			(xy 331.651171 -65.133181) (xy 331.676575 -65.114672) (xy 331.695154 -65.089318) (xy 331.70515 -65.059518)
			(xy 331.705966 -65.043812) (xy 331.706847 -65.017272) (xy 331.714978 -64.964798) (xy 331.730304 -64.913958)
			(xy 331.75253 -64.865734) (xy 331.781228 -64.821056) (xy 331.815841 -64.780789) (xy 331.855703 -64.745708)
			(xy 331.900043 -64.716492) (xy 331.948006 -64.693706) (xy 331.998664 -64.677788) (xy 332.051039 -64.669047)
			(xy 332.077568 -64.667892) (xy 332.090815 -64.667154) (xy 332.116242 -64.659603) (xy 332.138867 -64.64576)
			(xy 332.157164 -64.626557) (xy 332.1699 -64.60329) (xy 332.176214 -64.577528) (xy 332.176374 -64.56426)
			(xy 332.176374 -64.557148) (xy 332.1769 -64.529897) (xy 332.18465 -64.475949) (xy 332.199999 -64.423654)
			(xy 332.222635 -64.374075) (xy 332.252096 -64.328223) (xy 332.287783 -64.28703) (xy 332.32897 -64.251335)
			(xy 332.374817 -64.221866) (xy 332.424392 -64.199222) (xy 332.476685 -64.183864) (xy 332.530631 -64.176105)
			(xy 332.557882 -64.17564) (xy 332.575916 -64.176148) (xy 332.589482 -64.176355) (xy 332.615952 -64.170436)
			(xy 332.639933 -64.157765) (xy 332.659739 -64.139234) (xy 332.673975 -64.116147) (xy 332.68164 -64.09013)
			(xy 332.682342 -64.07658) (xy 332.68329 -64.050085) (xy 332.691554 -63.997718) (xy 332.70699 -63.947)
			(xy 332.7293 -63.898908) (xy 332.758053 -63.854368) (xy 332.792697 -63.814238) (xy 332.832564 -63.779292)
			(xy 332.876885 -63.750203) (xy 332.924807 -63.72753) (xy 332.975407 -63.711712) (xy 333.02771 -63.703052)
			(xy 333.054198 -63.70193) (xy 333.068757 -63.701047) (xy 333.096492 -63.692058) (xy 333.120567 -63.675614)
			(xy 333.139027 -63.653047) (xy 333.150374 -63.62619) (xy 333.152496 -63.61176) (xy 333.155928 -63.584714)
			(xy 333.169573 -63.531931) (xy 333.190592 -63.481628) (xy 333.218557 -63.434828) (xy 333.252898 -63.392486)
			(xy 333.292916 -63.355462) (xy 333.337797 -63.324511) (xy 333.386626 -63.300264) (xy 333.438409 -63.283213)
			(xy 333.46517 -63.278004) (xy 333.479467 -63.274914) (xy 333.505589 -63.261779) (xy 333.526934 -63.241798)
			(xy 333.541762 -63.216599) (xy 333.548864 -63.188236) (xy 333.548736 -63.17361) (xy 333.548482 -63.157354)
			(xy 333.548968 -63.130103) (xy 333.556724 -63.076155) (xy 333.572079 -63.02386) (xy 333.594721 -62.974283)
			(xy 333.624187 -62.928433) (xy 333.659878 -62.887242) (xy 333.701069 -62.851551) (xy 333.746919 -62.822085)
			(xy 333.796496 -62.799443) (xy 333.848791 -62.784088) (xy 333.902739 -62.776332) (xy 333.957241 -62.776332)
			(xy 334.011189 -62.784088) (xy 334.063484 -62.799443) (xy 334.113061 -62.822085) (xy 334.158911 -62.851551)
			(xy 334.200102 -62.887242) (xy 334.235793 -62.928433) (xy 334.265259 -62.974283) (xy 334.287901 -63.02386)
			(xy 334.303256 -63.076155) (xy 334.311012 -63.130103) (xy 334.311498 -63.157354) (xy 334.311008 -63.183984)
			(xy 334.303605 -63.236726) (xy 334.288938 -63.287926) (xy 334.267291 -63.336587) (xy 334.239086 -63.381765)
			(xy 334.233232 -63.388748) (xy 336.547204 -63.388748) (xy 336.551275 -63.333126) (xy 336.563401 -63.278689)
			(xy 336.583324 -63.226598) (xy 336.61062 -63.177963) (xy 336.644706 -63.13382) (xy 336.684855 -63.095111)
			(xy 336.730213 -63.06266) (xy 336.779813 -63.037159) (xy 336.832597 -63.019152) (xy 336.88744 -63.009022)
			(xy 336.943174 -63.006985) (xy 336.998611 -63.013085) (xy 337.052568 -63.027191) (xy 337.103897 -63.049003)
			(xy 337.151503 -63.078057) (xy 337.194371 -63.113732) (xy 337.231588 -63.155269) (xy 337.262361 -63.201782)
			(xy 337.286033 -63.252279) (xy 337.302101 -63.305686) (xy 337.310221 -63.360862) (xy 337.31073 -63.388748)
			(xy 337.310221 -63.416634) (xy 337.302101 -63.47181) (xy 337.286033 -63.525217) (xy 337.262361 -63.575714)
			(xy 337.231588 -63.622227) (xy 337.194371 -63.663764) (xy 337.151503 -63.699439) (xy 337.103897 -63.728493)
			(xy 337.052568 -63.750305) (xy 336.998611 -63.764411) (xy 336.943174 -63.770511) (xy 336.88744 -63.768474)
			(xy 336.832597 -63.758344) (xy 336.779813 -63.740337) (xy 336.730213 -63.714836) (xy 336.684855 -63.682385)
			(xy 336.644706 -63.643676) (xy 336.61062 -63.599533) (xy 336.583324 -63.550898) (xy 336.563401 -63.498807)
			(xy 336.551275 -63.44437) (xy 336.547204 -63.388748) (xy 334.233232 -63.388748) (xy 334.20487 -63.422579)
			(xy 334.165309 -63.458237) (xy 334.121173 -63.488045) (xy 334.073319 -63.511424) (xy 334.022679 -63.527919)
			(xy 333.996538 -63.53302) (xy 333.982236 -63.536093) (xy 333.956111 -63.549229) (xy 333.934765 -63.569215)
			(xy 333.919938 -63.594419) (xy 333.912841 -63.622786) (xy 333.912972 -63.637414) (xy 333.913226 -63.65367)
			(xy 333.912758 -63.68049) (xy 333.905275 -63.733604) (xy 333.890424 -63.785145) (xy 333.868497 -63.834098)
			(xy 333.839928 -63.879495) (xy 333.805281 -63.920442) (xy 333.765238 -63.95613) (xy 333.720589 -63.985856)
			(xy 333.672217 -64.009033) (xy 333.621074 -64.025204) (xy 333.568169 -64.034049) (xy 333.54137 -64.035178)
			(xy 333.526808 -64.036028) (xy 333.49907 -64.045025) (xy 333.474996 -64.061478) (xy 333.456537 -64.084052)
			(xy 333.445192 -64.110915) (xy 333.443072 -64.125348) (xy 333.439465 -64.152994) (xy 333.425337 -64.206925)
			(xy 333.403511 -64.258225) (xy 333.374451 -64.305802) (xy 333.338777 -64.348645) (xy 333.297248 -64.385839)
			(xy 333.250748 -64.416593) (xy 333.200267 -64.440253) (xy 333.146881 -64.456314) (xy 333.091725 -64.464435)
			(xy 333.06385 -64.464946) (xy 333.045816 -64.464438) (xy 333.03225 -64.464274) (xy 333.005785 -64.470185)
			(xy 332.981806 -64.482847) (xy 332.962 -64.50137) (xy 332.947762 -64.524448) (xy 332.940094 -64.550459)
			(xy 332.93939 -64.564006) (xy 332.938415 -64.590473) (xy 332.930105 -64.642779) (xy 332.914644 -64.693433)
			(xy 332.89233 -64.741464) (xy 332.863589 -64.785949) (xy 332.828976 -64.826035) (xy 332.789153 -64.86095)
			(xy 332.744886 -64.890025) (xy 332.697025 -64.912702) (xy 332.646489 -64.928545) (xy 332.594248 -64.93725)
			(xy 332.567788 -64.938402) (xy 332.554546 -64.939194) (xy 332.529121 -64.946731) (xy 332.506496 -64.960562)
			(xy 332.488197 -64.979755) (xy 332.475459 -65.003014) (xy 332.469143 -65.028769) (xy 332.468982 -65.042034)
			(xy 332.468982 -65.049146) (xy 332.468513 -65.076191) (xy 332.46088 -65.129741) (xy 332.44576 -65.181675)
			(xy 332.423455 -65.230953) (xy 332.394413 -65.276586) (xy 332.359216 -65.317659) (xy 332.31857 -65.353348)
			(xy 332.273291 -65.382939) (xy 332.224286 -65.405836) (xy 332.172537 -65.421582) (xy 332.119084 -65.42986)
			(xy 332.092046 -65.430654) (xy 332.076344 -65.431487) (xy 332.046525 -65.4414) (xy 332.021126 -65.4599)
			(xy 332.002546 -65.485242) (xy 331.99254 -65.515029) (xy 331.991716 -65.53073) (xy 331.990913 -65.557732)
			(xy 331.982533 -65.611101) (xy 331.966711 -65.662754) (xy 331.943762 -65.71166) (xy 331.914146 -65.756841)
			(xy 331.878453 -65.797392) (xy 331.837398 -65.832505) (xy 331.791801 -65.861477) (xy 331.742574 -65.883728)
			(xy 331.690701 -65.898815) (xy 331.637219 -65.906435) (xy 331.610208 -65.906904) (xy 331.582955 -65.906437)
			(xy 331.529004 -65.898681) (xy 331.476706 -65.883326) (xy 331.427126 -65.860684) (xy 331.381272 -65.831217)
			(xy 331.34008 -65.795523) (xy 331.304386 -65.754331) (xy 331.274918 -65.708478) (xy 331.252275 -65.658898)
			(xy 331.23692 -65.6066) (xy 331.229163 -65.552649) (xy 331.2287 -65.525396) (xy 325.426717 -65.525396)
			(xy 325.397804 -65.549069) (xy 325.353124 -65.576393) (xy 325.305125 -65.597346) (xy 325.25471 -65.611535)
			(xy 325.202829 -65.618693) (xy 325.176642 -65.619122) (xy 325.149388 -65.618634) (xy 325.095435 -65.610882)
			(xy 325.043134 -65.59553) (xy 324.99355 -65.572891) (xy 324.947693 -65.543425) (xy 324.906497 -65.507732)
			(xy 324.8708 -65.46654) (xy 324.84133 -65.420687) (xy 324.818685 -65.371106) (xy 324.803327 -65.318806)
			(xy 324.795569 -65.264854) (xy 324.795569 -65.210346) (xy 324.803327 -65.156394) (xy 324.818685 -65.104094)
			(xy 324.84133 -65.054513) (xy 324.8708 -65.00866) (xy 324.906497 -64.967468) (xy 324.947693 -64.931775)
			(xy 324.99355 -64.902309) (xy 325.043134 -64.87967) (xy 325.095435 -64.864318) (xy 325.149388 -64.856566)
			(xy 325.176642 -64.856106) (xy 325.203022 -64.85656) (xy 325.25528 -64.863819) (xy 325.280782 -64.870584)
			(xy 325.293802 -64.873898) (xy 325.320662 -64.874207) (xy 325.346673 -64.867505) (xy 325.370038 -64.854253)
			(xy 325.38914 -64.835369) (xy 325.402659 -64.812157) (xy 325.40966 -64.786225) (xy 325.410068 -64.772794)
			(xy 325.410068 -64.700658) (xy 325.409568 -64.685663) (xy 325.400821 -64.656975) (xy 325.384123 -64.632061)
			(xy 325.360912 -64.613068) (xy 325.333186 -64.601631) (xy 325.303335 -64.598735) (xy 325.273928 -64.60463)
			(xy 325.260462 -64.61125) (xy 325.232491 -64.625567) (xy 325.17302 -64.645845) (xy 325.111031 -64.656099)
			(xy 325.079614 -64.656716) (xy 325.052361 -64.656238) (xy 324.99841 -64.648482) (xy 324.946111 -64.633128)
			(xy 324.89653 -64.610487) (xy 324.850677 -64.58102) (xy 324.809483 -64.545327) (xy 324.773789 -64.504135)
			(xy 324.74432 -64.458282) (xy 324.721677 -64.408702) (xy 324.706321 -64.356404) (xy 324.698563 -64.302453)
			(xy 320.7258 -64.302453) (xy 320.7258 -65.446148) (xy 321.3354 -66.055748) (xy 324.7898 -66.055748)
			(xy 325.004684 -66.270632) (xy 326.417176 -66.270632) (xy 326.421247 -66.21501) (xy 326.433373 -66.160573)
			(xy 326.453296 -66.108482) (xy 326.480592 -66.059847) (xy 326.514678 -66.015704) (xy 326.554827 -65.976995)
			(xy 326.600185 -65.944544) (xy 326.649785 -65.919043) (xy 326.702569 -65.901036) (xy 326.757412 -65.890906)
			(xy 326.813146 -65.888869) (xy 326.868583 -65.894969) (xy 326.92254 -65.909075) (xy 326.973869 -65.930887)
			(xy 327.021475 -65.959941) (xy 327.064343 -65.995616) (xy 327.10156 -66.037153) (xy 327.132333 -66.083666)
			(xy 327.156005 -66.134163) (xy 327.172073 -66.18757) (xy 327.180193 -66.242746) (xy 327.180702 -66.270632)
			(xy 327.180193 -66.298518) (xy 327.172073 -66.353694) (xy 327.156005 -66.407101) (xy 327.132333 -66.457598)
			(xy 327.10156 -66.504111) (xy 327.064343 -66.545648) (xy 327.021475 -66.581323) (xy 326.973869 -66.610377)
			(xy 326.92254 -66.632189) (xy 326.868583 -66.646295) (xy 326.813146 -66.652395) (xy 326.757412 -66.650358)
			(xy 326.702569 -66.640228) (xy 326.649785 -66.622221) (xy 326.600185 -66.59672) (xy 326.554827 -66.564269)
			(xy 326.514678 -66.52556) (xy 326.480592 -66.481417) (xy 326.453296 -66.432782) (xy 326.433373 -66.380691)
			(xy 326.421247 -66.326254) (xy 326.417176 -66.270632) (xy 325.004684 -66.270632) (xy 325.5518 -66.817748)
			(xy 325.6026 -66.817748) (xy 326.0344 -67.249548) (xy 326.0344 -68.14312) (xy 326.056024 -68.161338)
			(xy 326.094176 -68.203068) (xy 326.125752 -68.24997) (xy 326.15006 -68.30102) (xy 326.166568 -68.355097)
			(xy 326.174914 -68.411019) (xy 326.174915 -68.467561) (xy 326.166572 -68.523483) (xy 326.150067 -68.577562)
			(xy 326.125762 -68.628612) (xy 326.094188 -68.675517) (xy 326.056038 -68.717248) (xy 326.0344 -68.735448)
			(xy 326.0344 -70.749922) (xy 327.550526 -70.749922) (xy 327.55105 -70.721005) (xy 327.559777 -70.663834)
			(xy 327.577033 -70.608635) (xy 327.602423 -70.556673) (xy 327.635366 -70.509139) (xy 327.675107 -70.467122)
			(xy 327.697592 -70.448932) (xy 327.709375 -70.43901) (xy 327.726892 -70.413693) (xy 327.736069 -70.384307)
			(xy 327.736073 -70.35352) (xy 327.726904 -70.324131) (xy 327.709393 -70.29881) (xy 327.697592 -70.288912)
			(xy 327.675113 -70.270716) (xy 327.635378 -70.228697) (xy 327.602438 -70.181163) (xy 327.577049 -70.129203)
			(xy 327.559792 -70.074006) (xy 327.551062 -70.016838) (xy 327.550526 -69.987922) (xy 327.551012 -69.960671)
			(xy 327.558768 -69.906723) (xy 327.574123 -69.854428) (xy 327.596765 -69.804851) (xy 327.626231 -69.759001)
			(xy 327.661922 -69.71781) (xy 327.703113 -69.682119) (xy 327.748963 -69.652653) (xy 327.79854 -69.630011)
			(xy 327.850835 -69.614656) (xy 327.904783 -69.6069) (xy 327.959285 -69.6069) (xy 328.013233 -69.614656)
			(xy 328.065528 -69.630011) (xy 328.115105 -69.652653) (xy 328.160955 -69.682119) (xy 328.202146 -69.71781)
			(xy 328.237837 -69.759001) (xy 328.267303 -69.804851) (xy 328.289945 -69.854428) (xy 328.3053 -69.906723)
			(xy 328.313056 -69.960671) (xy 328.313542 -69.987922) (xy 328.312989 -70.016838) (xy 328.304271 -70.074008)
			(xy 328.287021 -70.129208) (xy 328.261636 -70.18117) (xy 328.228697 -70.228704) (xy 328.18896 -70.270722)
			(xy 328.166476 -70.288912) (xy 328.154652 -70.298787) (xy 328.137142 -70.324119) (xy 328.127972 -70.353516)
			(xy 328.127976 -70.384311) (xy 328.137153 -70.413706) (xy 328.154671 -70.439032) (xy 328.166476 -70.448932)
			(xy 328.18897 -70.467111) (xy 328.228705 -70.509133) (xy 328.261644 -70.55667) (xy 328.287031 -70.608633)
			(xy 328.304284 -70.663833) (xy 328.313009 -70.721005) (xy 328.313542 -70.749922) (xy 328.313056 -70.777173)
			(xy 328.3053 -70.831121) (xy 328.289945 -70.883416) (xy 328.267303 -70.932993) (xy 328.237837 -70.978843)
			(xy 328.202146 -71.020034) (xy 328.160955 -71.055725) (xy 328.115105 -71.085191) (xy 328.065528 -71.107833)
			(xy 328.013233 -71.123188) (xy 327.959285 -71.130944) (xy 327.904783 -71.130944) (xy 327.850835 -71.123188)
			(xy 327.79854 -71.107833) (xy 327.748963 -71.085191) (xy 327.703113 -71.055725) (xy 327.661922 -71.020034)
			(xy 327.626231 -70.978843) (xy 327.596765 -70.932993) (xy 327.574123 -70.883416) (xy 327.558768 -70.831121)
			(xy 327.551012 -70.777173) (xy 327.550526 -70.749922) (xy 326.0344 -70.749922) (xy 326.0344 -73.650348)
			(xy 325.956676 -73.728072) (xy 327.279252 -73.728072) (xy 327.283323 -73.67245) (xy 327.295449 -73.618013)
			(xy 327.315372 -73.565922) (xy 327.342668 -73.517287) (xy 327.376754 -73.473144) (xy 327.416903 -73.434435)
			(xy 327.462261 -73.401984) (xy 327.511861 -73.376483) (xy 327.564645 -73.358476) (xy 327.619488 -73.348346)
			(xy 327.675222 -73.346309) (xy 327.730659 -73.352409) (xy 327.784616 -73.366515) (xy 327.835945 -73.388327)
			(xy 327.883551 -73.417381) (xy 327.926419 -73.453056) (xy 327.963636 -73.494593) (xy 327.994409 -73.541106)
			(xy 328.018081 -73.591603) (xy 328.034149 -73.64501) (xy 328.042269 -73.700186) (xy 328.042778 -73.728072)
			(xy 328.042269 -73.755958) (xy 328.034149 -73.811134) (xy 328.018081 -73.864541) (xy 327.994409 -73.915038)
			(xy 327.963636 -73.961551) (xy 327.926419 -74.003088) (xy 327.883551 -74.038763) (xy 327.835945 -74.067817)
			(xy 327.784616 -74.089629) (xy 327.730659 -74.103735) (xy 327.675222 -74.109835) (xy 327.619488 -74.107798)
			(xy 327.564645 -74.097668) (xy 327.511861 -74.079661) (xy 327.462261 -74.05416) (xy 327.416903 -74.021709)
			(xy 327.376754 -73.983) (xy 327.342668 -73.938857) (xy 327.315372 -73.890222) (xy 327.295449 -73.838131)
			(xy 327.283323 -73.783694) (xy 327.279252 -73.728072) (xy 325.956676 -73.728072) (xy 323.0626 -76.622148)
			(xy 309.1942 -76.622148) (xy 306.8574 -74.285348) (xy 303.784 -74.285348) (xy 303.3776 -74.691748)
			(xy 303.3776 -77.873148) (xy 317.637198 -77.873148) (xy 317.637198 -77.818652) (xy 317.644953 -77.764711)
			(xy 317.660305 -77.712422) (xy 317.682942 -77.66285) (xy 317.712403 -77.617004) (xy 317.748089 -77.575817)
			(xy 317.789272 -77.540127) (xy 317.835115 -77.510662) (xy 317.884684 -77.488019) (xy 317.936972 -77.472662)
			(xy 317.990912 -77.464901) (xy 318.01816 -77.464412) (xy 318.046037 -77.464874) (xy 318.101197 -77.472989)
			(xy 318.154586 -77.489053) (xy 318.205066 -77.512721) (xy 318.25156 -77.543491) (xy 318.293077 -77.580704)
			(xy 318.311276 -77.601826) (xy 318.320566 -77.612313) (xy 318.34366 -77.62816) (xy 318.370192 -77.637131)
			(xy 318.398163 -77.638551) (xy 318.425467 -77.632312) (xy 318.450046 -77.618884) (xy 318.470048 -77.59928)
			(xy 318.477392 -77.587348) (xy 318.492068 -77.562801) (xy 318.527676 -77.518046) (xy 318.569564 -77.479106)
			(xy 318.616794 -77.446853) (xy 318.668308 -77.422009) (xy 318.722952 -77.405131) (xy 318.779504 -77.396596)
			(xy 318.8081 -77.396086) (xy 318.835351 -77.396584) (xy 318.889298 -77.40434) (xy 318.941592 -77.419695)
			(xy 318.991168 -77.442336) (xy 319.037018 -77.471802) (xy 319.078207 -77.507493) (xy 319.113898 -77.548682)
			(xy 319.143364 -77.594532) (xy 319.166005 -77.644108) (xy 319.18136 -77.696402) (xy 319.185255 -77.723492)
			(xy 321.474082 -77.723492) (xy 321.478153 -77.66787) (xy 321.490279 -77.613433) (xy 321.510202 -77.561342)
			(xy 321.537498 -77.512707) (xy 321.571584 -77.468564) (xy 321.611733 -77.429855) (xy 321.657091 -77.397404)
			(xy 321.706691 -77.371903) (xy 321.759475 -77.353896) (xy 321.814318 -77.343766) (xy 321.870052 -77.341729)
			(xy 321.925489 -77.347829) (xy 321.979446 -77.361935) (xy 322.030775 -77.383747) (xy 322.078381 -77.412801)
			(xy 322.121249 -77.448476) (xy 322.158466 -77.490013) (xy 322.189239 -77.536526) (xy 322.212911 -77.587023)
			(xy 322.228979 -77.64043) (xy 322.233503 -77.671168) (xy 322.490082 -77.671168) (xy 322.494153 -77.615546)
			(xy 322.506279 -77.561109) (xy 322.526202 -77.509018) (xy 322.553498 -77.460383) (xy 322.587584 -77.41624)
			(xy 322.627733 -77.377531) (xy 322.673091 -77.34508) (xy 322.722691 -77.319579) (xy 322.775475 -77.301572)
			(xy 322.830318 -77.291442) (xy 322.886052 -77.289405) (xy 322.941489 -77.295505) (xy 322.995446 -77.309611)
			(xy 323.046775 -77.331423) (xy 323.094381 -77.360477) (xy 323.137249 -77.396152) (xy 323.174466 -77.437689)
			(xy 323.205239 -77.484202) (xy 323.228911 -77.534699) (xy 323.244979 -77.588106) (xy 323.253099 -77.643282)
			(xy 323.253608 -77.671168) (xy 323.253099 -77.699054) (xy 323.244979 -77.75423) (xy 323.228911 -77.807637)
			(xy 323.205239 -77.858134) (xy 323.174466 -77.904647) (xy 323.137249 -77.946184) (xy 323.094381 -77.981859)
			(xy 323.046775 -78.010913) (xy 322.995446 -78.032725) (xy 322.941489 -78.046831) (xy 322.886052 -78.052931)
			(xy 322.830318 -78.050894) (xy 322.775475 -78.040764) (xy 322.722691 -78.022757) (xy 322.673091 -77.997256)
			(xy 322.627733 -77.964805) (xy 322.587584 -77.926096) (xy 322.553498 -77.881953) (xy 322.526202 -77.833318)
			(xy 322.506279 -77.781227) (xy 322.494153 -77.72679) (xy 322.490082 -77.671168) (xy 322.233503 -77.671168)
			(xy 322.237099 -77.695606) (xy 322.237608 -77.723492) (xy 322.237099 -77.751378) (xy 322.228979 -77.806554)
			(xy 322.212911 -77.859961) (xy 322.189239 -77.910458) (xy 322.158466 -77.956971) (xy 322.121249 -77.998508)
			(xy 322.078381 -78.034183) (xy 322.030775 -78.063237) (xy 321.979446 -78.085049) (xy 321.925489 -78.099155)
			(xy 321.870052 -78.105255) (xy 321.814318 -78.103218) (xy 321.759475 -78.093088) (xy 321.706691 -78.075081)
			(xy 321.657091 -78.04958) (xy 321.611733 -78.017129) (xy 321.571584 -77.97842) (xy 321.537498 -77.934277)
			(xy 321.510202 -77.885642) (xy 321.490279 -77.833551) (xy 321.478153 -77.779114) (xy 321.474082 -77.723492)
			(xy 319.185255 -77.723492) (xy 319.189116 -77.750349) (xy 319.189116 -77.804851) (xy 319.18136 -77.858798)
			(xy 319.166005 -77.911092) (xy 319.143364 -77.960668) (xy 319.113898 -78.006518) (xy 319.078207 -78.047707)
			(xy 319.037018 -78.083398) (xy 318.991168 -78.112864) (xy 318.941592 -78.135505) (xy 318.889298 -78.15086)
			(xy 318.835351 -78.158616) (xy 318.8081 -78.159102) (xy 318.780223 -78.158629) (xy 318.725063 -78.15052)
			(xy 318.671672 -78.134461) (xy 318.621191 -78.110795) (xy 318.574697 -78.080026) (xy 318.533182 -78.042811)
			(xy 318.514984 -78.021688) (xy 318.50574 -78.011155) (xy 318.482636 -77.995307) (xy 318.456093 -77.986337)
			(xy 318.428111 -77.984924) (xy 318.400799 -77.991171) (xy 318.376215 -78.00461) (xy 318.356211 -78.024228)
			(xy 318.348868 -78.036166) (xy 318.334118 -78.060667) (xy 318.298526 -78.105426) (xy 318.256652 -78.144372)
			(xy 318.209435 -78.176632) (xy 318.157932 -78.201483) (xy 318.103296 -78.21837) (xy 318.046753 -78.226914)
			(xy 318.01816 -78.227428) (xy 317.990912 -78.226899) (xy 317.936972 -78.219138) (xy 317.884684 -78.203781)
			(xy 317.835115 -78.181138) (xy 317.789272 -78.151673) (xy 317.748089 -78.115983) (xy 317.712403 -78.074796)
			(xy 317.682942 -78.02895) (xy 317.660305 -77.979378) (xy 317.644953 -77.927089) (xy 317.637198 -77.873148)
			(xy 303.3776 -77.873148) (xy 303.3776 -79.111348) (xy 303.9364 -79.670148) (xy 323.1388 -79.670148)
		)
		(stroke
			(width 0)
			(type solid)
		)
		(fill yes)
		(layer "In6.Cu")
		(net "P3V3_AUX")
	)
	(gr_poly
		(pts
			(xy 342.888824 -326.257412) (xy 371.646704 -326.257412) (xy 374.798844 -329.409552) (xy 379.678184 -329.409552)
			(xy 382.657858 -332.389226) (xy 400.162522 -332.389226) (xy 401.7518 -330.799948) (xy 401.7518 -317.109348)
			(xy 396.9512 -312.308748) (xy 396.9512 -304.059336) (xy 387.315964 -294.4241) (xy 387.315964 -291.116004)
			(xy 385.517136 -289.317176) (xy 381.77343 -289.317176) (xy 381.737616 -289.385248) (xy 381.597408 -289.65017)
			(xy 381.607568 -289.67303) (xy 381.616442 -289.693958) (xy 381.629017 -289.737643) (xy 381.635491 -289.782638)
			(xy 381.636016 -289.805364) (xy 381.636016 -289.810698) (xy 381.635247 -289.836484) (xy 381.626692 -289.887356)
			(xy 381.610335 -289.93628) (xy 381.586574 -289.982067) (xy 381.555986 -290.023606) (xy 381.519315 -290.059888)
			(xy 381.477451 -290.090029) (xy 381.431411 -290.113299) (xy 381.382315 -290.129131) (xy 381.331355 -290.137142)
			(xy 381.305562 -290.137596) (xy 381.279596 -290.137084) (xy 381.228303 -290.128955) (xy 381.178912 -290.112904)
			(xy 381.132641 -290.089325) (xy 381.090627 -290.058798) (xy 381.053904 -290.022076) (xy 381.023377 -289.980063)
			(xy 380.999798 -289.933791) (xy 380.983746 -289.884401) (xy 380.975616 -289.833108) (xy 380.975108 -289.807142)
			(xy 380.975589 -289.781598) (xy 380.983459 -289.731119) (xy 380.999004 -289.682453) (xy 381.021852 -289.636759)
			(xy 381.05146 -289.595125) (xy 381.087122 -289.558543) (xy 381.127989 -289.527884) (xy 381.173086 -289.50388)
			(xy 381.221341 -289.487101) (xy 381.24638 -289.482022) (xy 381.27051 -289.477704) (xy 381.315976 -289.391598)
			(xy 381.320389 -289.382086) (xy 381.321905 -289.361195) (xy 381.314955 -289.341435) (xy 381.300692 -289.326095)
			(xy 381.281491 -289.317725) (xy 381.271018 -289.317176) (xy 379.89383 -289.317176) (xy 379.858016 -289.385248)
			(xy 379.717808 -289.65017) (xy 379.727968 -289.67303) (xy 379.736842 -289.693958) (xy 379.749417 -289.737643)
			(xy 379.755891 -289.782638) (xy 379.756416 -289.805364) (xy 379.756416 -289.810698) (xy 379.755748 -289.833109)
			(xy 380.035817 -289.833109) (xy 380.035817 -289.781175) (xy 380.043942 -289.72988) (xy 380.05999 -289.680487)
			(xy 380.083568 -289.634213) (xy 380.114094 -289.592197) (xy 380.150817 -289.555474) (xy 380.192833 -289.524948)
			(xy 380.239107 -289.50137) (xy 380.2885 -289.485322) (xy 380.339795 -289.477197) (xy 380.391729 -289.477197)
			(xy 380.443024 -289.485322) (xy 380.492417 -289.50137) (xy 380.538691 -289.524948) (xy 380.580707 -289.555474)
			(xy 380.61743 -289.592197) (xy 380.647956 -289.634213) (xy 380.671534 -289.680487) (xy 380.687582 -289.72988)
			(xy 380.695707 -289.781175) (xy 380.696216 -289.807142) (xy 380.695707 -289.833109) (xy 380.687582 -289.884404)
			(xy 380.671534 -289.933797) (xy 380.647956 -289.980071) (xy 380.61743 -290.022087) (xy 380.580707 -290.05881)
			(xy 380.538691 -290.089336) (xy 380.492417 -290.112914) (xy 380.443024 -290.128962) (xy 380.391729 -290.137087)
			(xy 380.339795 -290.137087) (xy 380.2885 -290.128962) (xy 380.239107 -290.112914) (xy 380.192833 -290.089336)
			(xy 380.150817 -290.05881) (xy 380.114094 -290.022087) (xy 380.083568 -289.980071) (xy 380.05999 -289.933797)
			(xy 380.043942 -289.884404) (xy 380.035817 -289.833109) (xy 379.755748 -289.833109) (xy 379.755647 -289.836484)
			(xy 379.747092 -289.887356) (xy 379.730735 -289.93628) (xy 379.706974 -289.982067) (xy 379.676386 -290.023606)
			(xy 379.639715 -290.059888) (xy 379.597851 -290.090029) (xy 379.551811 -290.113299) (xy 379.502715 -290.129131)
			(xy 379.451755 -290.137142) (xy 379.425962 -290.137596) (xy 379.399996 -290.137084) (xy 379.348703 -290.128955)
			(xy 379.299312 -290.112904) (xy 379.253041 -290.089325) (xy 379.211027 -290.058798) (xy 379.174304 -290.022076)
			(xy 379.143777 -289.980063) (xy 379.120198 -289.933791) (xy 379.104146 -289.884401) (xy 379.096016 -289.833108)
			(xy 379.095508 -289.807142) (xy 379.095989 -289.781598) (xy 379.103859 -289.731119) (xy 379.119404 -289.682453)
			(xy 379.142252 -289.636759) (xy 379.17186 -289.595125) (xy 379.207522 -289.558543) (xy 379.248389 -289.527884)
			(xy 379.293486 -289.50388) (xy 379.341741 -289.487101) (xy 379.36678 -289.482022) (xy 379.39091 -289.477704)
			(xy 379.436376 -289.391598) (xy 379.440789 -289.382086) (xy 379.442305 -289.361195) (xy 379.435355 -289.341435)
			(xy 379.421092 -289.326095) (xy 379.401891 -289.317725) (xy 379.391418 -289.317176) (xy 378.01423 -289.317176)
			(xy 377.978416 -289.385248) (xy 377.838208 -289.65017) (xy 377.848368 -289.67303) (xy 377.857242 -289.693958)
			(xy 377.869817 -289.737643) (xy 377.876291 -289.782638) (xy 377.876816 -289.805364) (xy 377.876816 -289.810698)
			(xy 377.876148 -289.833109) (xy 378.156217 -289.833109) (xy 378.156217 -289.781175) (xy 378.164342 -289.72988)
			(xy 378.18039 -289.680487) (xy 378.203968 -289.634213) (xy 378.234494 -289.592197) (xy 378.271217 -289.555474)
			(xy 378.313233 -289.524948) (xy 378.359507 -289.50137) (xy 378.4089 -289.485322) (xy 378.460195 -289.477197)
			(xy 378.512129 -289.477197) (xy 378.563424 -289.485322) (xy 378.612817 -289.50137) (xy 378.659091 -289.524948)
			(xy 378.701107 -289.555474) (xy 378.73783 -289.592197) (xy 378.768356 -289.634213) (xy 378.791934 -289.680487)
			(xy 378.807982 -289.72988) (xy 378.816107 -289.781175) (xy 378.816616 -289.807142) (xy 378.816107 -289.833109)
			(xy 378.807982 -289.884404) (xy 378.791934 -289.933797) (xy 378.768356 -289.980071) (xy 378.73783 -290.022087)
			(xy 378.701107 -290.05881) (xy 378.659091 -290.089336) (xy 378.612817 -290.112914) (xy 378.563424 -290.128962)
			(xy 378.512129 -290.137087) (xy 378.460195 -290.137087) (xy 378.4089 -290.128962) (xy 378.359507 -290.112914)
			(xy 378.313233 -290.089336) (xy 378.271217 -290.05881) (xy 378.234494 -290.022087) (xy 378.203968 -289.980071)
			(xy 378.18039 -289.933797) (xy 378.164342 -289.884404) (xy 378.156217 -289.833109) (xy 377.876148 -289.833109)
			(xy 377.876047 -289.836484) (xy 377.867492 -289.887356) (xy 377.851135 -289.93628) (xy 377.827374 -289.982067)
			(xy 377.796786 -290.023606) (xy 377.760115 -290.059888) (xy 377.718251 -290.090029) (xy 377.672211 -290.113299)
			(xy 377.623115 -290.129131) (xy 377.572155 -290.137142) (xy 377.546362 -290.137596) (xy 377.520396 -290.137084)
			(xy 377.469103 -290.128955) (xy 377.419712 -290.112904) (xy 377.373441 -290.089325) (xy 377.331427 -290.058798)
			(xy 377.294704 -290.022076) (xy 377.264177 -289.980063) (xy 377.240598 -289.933791) (xy 377.224546 -289.884401)
			(xy 377.216416 -289.833108) (xy 377.215908 -289.807142) (xy 377.216389 -289.781598) (xy 377.224259 -289.731119)
			(xy 377.239804 -289.682453) (xy 377.262652 -289.636759) (xy 377.29226 -289.595125) (xy 377.327922 -289.558543)
			(xy 377.368789 -289.527884) (xy 377.413886 -289.50388) (xy 377.462141 -289.487101) (xy 377.48718 -289.482022)
			(xy 377.51131 -289.477704) (xy 377.556776 -289.391598) (xy 377.561189 -289.382086) (xy 377.562705 -289.361195)
			(xy 377.555755 -289.341435) (xy 377.541492 -289.326095) (xy 377.522291 -289.317725) (xy 377.511818 -289.317176)
			(xy 376.13463 -289.317176) (xy 376.098816 -289.385248) (xy 375.958608 -289.65017) (xy 375.968768 -289.67303)
			(xy 375.977642 -289.693958) (xy 375.990217 -289.737643) (xy 375.996691 -289.782638) (xy 375.997216 -289.805364)
			(xy 375.997216 -289.810698) (xy 375.996548 -289.833109) (xy 376.276617 -289.833109) (xy 376.276617 -289.781175)
			(xy 376.284742 -289.72988) (xy 376.30079 -289.680487) (xy 376.324368 -289.634213) (xy 376.354894 -289.592197)
			(xy 376.391617 -289.555474) (xy 376.433633 -289.524948) (xy 376.479907 -289.50137) (xy 376.5293 -289.485322)
			(xy 376.580595 -289.477197) (xy 376.632529 -289.477197) (xy 376.683824 -289.485322) (xy 376.733217 -289.50137)
			(xy 376.779491 -289.524948) (xy 376.821507 -289.555474) (xy 376.85823 -289.592197) (xy 376.888756 -289.634213)
			(xy 376.912334 -289.680487) (xy 376.928382 -289.72988) (xy 376.936507 -289.781175) (xy 376.937016 -289.807142)
			(xy 376.936507 -289.833109) (xy 376.928382 -289.884404) (xy 376.912334 -289.933797) (xy 376.888756 -289.980071)
			(xy 376.85823 -290.022087) (xy 376.821507 -290.05881) (xy 376.779491 -290.089336) (xy 376.733217 -290.112914)
			(xy 376.683824 -290.128962) (xy 376.632529 -290.137087) (xy 376.580595 -290.137087) (xy 376.5293 -290.128962)
			(xy 376.479907 -290.112914) (xy 376.433633 -290.089336) (xy 376.391617 -290.05881) (xy 376.354894 -290.022087)
			(xy 376.324368 -289.980071) (xy 376.30079 -289.933797) (xy 376.284742 -289.884404) (xy 376.276617 -289.833109)
			(xy 375.996548 -289.833109) (xy 375.996447 -289.836484) (xy 375.987892 -289.887356) (xy 375.971535 -289.93628)
			(xy 375.947774 -289.982067) (xy 375.917186 -290.023606) (xy 375.880515 -290.059888) (xy 375.838651 -290.090029)
			(xy 375.792611 -290.113299) (xy 375.743515 -290.129131) (xy 375.692555 -290.137142) (xy 375.666762 -290.137596)
			(xy 375.640796 -290.137084) (xy 375.589503 -290.128955) (xy 375.540112 -290.112904) (xy 375.493841 -290.089325)
			(xy 375.451827 -290.058798) (xy 375.415104 -290.022076) (xy 375.384577 -289.980063) (xy 375.360998 -289.933791)
			(xy 375.344946 -289.884401) (xy 375.336816 -289.833108) (xy 375.336308 -289.807142) (xy 375.336789 -289.781598)
			(xy 375.344659 -289.731119) (xy 375.360204 -289.682453) (xy 375.383052 -289.636759) (xy 375.41266 -289.595125)
			(xy 375.448322 -289.558543) (xy 375.489189 -289.527884) (xy 375.534286 -289.50388) (xy 375.582541 -289.487101)
			(xy 375.60758 -289.482022) (xy 375.63171 -289.477704) (xy 375.677176 -289.391598) (xy 375.681589 -289.382086)
			(xy 375.683105 -289.361195) (xy 375.676155 -289.341435) (xy 375.661892 -289.326095) (xy 375.642691 -289.317725)
			(xy 375.632218 -289.317176) (xy 374.25503 -289.317176) (xy 374.219216 -289.385248) (xy 374.079008 -289.65017)
			(xy 374.089168 -289.67303) (xy 374.098042 -289.693958) (xy 374.110617 -289.737643) (xy 374.117091 -289.782638)
			(xy 374.117616 -289.805364) (xy 374.117616 -289.810698) (xy 374.116948 -289.833109) (xy 374.397017 -289.833109)
			(xy 374.397017 -289.781175) (xy 374.405142 -289.72988) (xy 374.42119 -289.680487) (xy 374.444768 -289.634213)
			(xy 374.475294 -289.592197) (xy 374.512017 -289.555474) (xy 374.554033 -289.524948) (xy 374.600307 -289.50137)
			(xy 374.6497 -289.485322) (xy 374.700995 -289.477197) (xy 374.752929 -289.477197) (xy 374.804224 -289.485322)
			(xy 374.853617 -289.50137) (xy 374.899891 -289.524948) (xy 374.941907 -289.555474) (xy 374.97863 -289.592197)
			(xy 375.009156 -289.634213) (xy 375.032734 -289.680487) (xy 375.048782 -289.72988) (xy 375.056907 -289.781175)
			(xy 375.057416 -289.807142) (xy 375.056907 -289.833109) (xy 375.048782 -289.884404) (xy 375.032734 -289.933797)
			(xy 375.009156 -289.980071) (xy 374.97863 -290.022087) (xy 374.941907 -290.05881) (xy 374.899891 -290.089336)
			(xy 374.853617 -290.112914) (xy 374.804224 -290.128962) (xy 374.752929 -290.137087) (xy 374.700995 -290.137087)
			(xy 374.6497 -290.128962) (xy 374.600307 -290.112914) (xy 374.554033 -290.089336) (xy 374.512017 -290.05881)
			(xy 374.475294 -290.022087) (xy 374.444768 -289.980071) (xy 374.42119 -289.933797) (xy 374.405142 -289.884404)
			(xy 374.397017 -289.833109) (xy 374.116948 -289.833109) (xy 374.116847 -289.836484) (xy 374.108292 -289.887356)
			(xy 374.091935 -289.93628) (xy 374.068174 -289.982067) (xy 374.037586 -290.023606) (xy 374.000915 -290.059888)
			(xy 373.959051 -290.090029) (xy 373.913011 -290.113299) (xy 373.863915 -290.129131) (xy 373.812955 -290.137142)
			(xy 373.787162 -290.137596) (xy 373.761196 -290.137084) (xy 373.709903 -290.128955) (xy 373.660512 -290.112904)
			(xy 373.614241 -290.089325) (xy 373.572227 -290.058798) (xy 373.535504 -290.022076) (xy 373.504977 -289.980063)
			(xy 373.481398 -289.933791) (xy 373.465346 -289.884401) (xy 373.457216 -289.833108) (xy 373.456708 -289.807142)
			(xy 373.457189 -289.781598) (xy 373.465059 -289.731119) (xy 373.480604 -289.682453) (xy 373.503452 -289.636759)
			(xy 373.53306 -289.595125) (xy 373.568722 -289.558543) (xy 373.609589 -289.527884) (xy 373.654686 -289.50388)
			(xy 373.702941 -289.487101) (xy 373.72798 -289.482022) (xy 373.75211 -289.477704) (xy 373.797576 -289.391598)
			(xy 373.801989 -289.382086) (xy 373.803505 -289.361195) (xy 373.796555 -289.341435) (xy 373.782292 -289.326095)
			(xy 373.763091 -289.317725) (xy 373.752618 -289.317176) (xy 372.37543 -289.317176) (xy 372.339616 -289.385248)
			(xy 372.199408 -289.65017) (xy 372.209568 -289.67303) (xy 372.218442 -289.693958) (xy 372.231017 -289.737643)
			(xy 372.237491 -289.782638) (xy 372.238016 -289.805364) (xy 372.238016 -289.810698) (xy 372.237348 -289.833109)
			(xy 372.517417 -289.833109) (xy 372.517417 -289.781175) (xy 372.525542 -289.72988) (xy 372.54159 -289.680487)
			(xy 372.565168 -289.634213) (xy 372.595694 -289.592197) (xy 372.632417 -289.555474) (xy 372.674433 -289.524948)
			(xy 372.720707 -289.50137) (xy 372.7701 -289.485322) (xy 372.821395 -289.477197) (xy 372.873329 -289.477197)
			(xy 372.924624 -289.485322) (xy 372.974017 -289.50137) (xy 373.020291 -289.524948) (xy 373.062307 -289.555474)
			(xy 373.09903 -289.592197) (xy 373.129556 -289.634213) (xy 373.153134 -289.680487) (xy 373.169182 -289.72988)
			(xy 373.177307 -289.781175) (xy 373.177816 -289.807142) (xy 373.177307 -289.833109) (xy 373.169182 -289.884404)
			(xy 373.153134 -289.933797) (xy 373.129556 -289.980071) (xy 373.09903 -290.022087) (xy 373.062307 -290.05881)
			(xy 373.020291 -290.089336) (xy 372.974017 -290.112914) (xy 372.924624 -290.128962) (xy 372.873329 -290.137087)
			(xy 372.821395 -290.137087) (xy 372.7701 -290.128962) (xy 372.720707 -290.112914) (xy 372.674433 -290.089336)
			(xy 372.632417 -290.05881) (xy 372.595694 -290.022087) (xy 372.565168 -289.980071) (xy 372.54159 -289.933797)
			(xy 372.525542 -289.884404) (xy 372.517417 -289.833109) (xy 372.237348 -289.833109) (xy 372.237247 -289.836484)
			(xy 372.228692 -289.887356) (xy 372.212335 -289.93628) (xy 372.188574 -289.982067) (xy 372.157986 -290.023606)
			(xy 372.121315 -290.059888) (xy 372.079451 -290.090029) (xy 372.033411 -290.113299) (xy 371.984315 -290.129131)
			(xy 371.933355 -290.137142) (xy 371.907562 -290.137596) (xy 371.881596 -290.137084) (xy 371.830303 -290.128955)
			(xy 371.780912 -290.112904) (xy 371.734641 -290.089325) (xy 371.692627 -290.058798) (xy 371.655904 -290.022076)
			(xy 371.625377 -289.980063) (xy 371.601798 -289.933791) (xy 371.585746 -289.884401) (xy 371.577616 -289.833108)
			(xy 371.577108 -289.807142) (xy 371.577589 -289.781598) (xy 371.585459 -289.731119) (xy 371.601004 -289.682453)
			(xy 371.623852 -289.636759) (xy 371.65346 -289.595125) (xy 371.689122 -289.558543) (xy 371.729989 -289.527884)
			(xy 371.775086 -289.50388) (xy 371.823341 -289.487101) (xy 371.84838 -289.482022) (xy 371.87251 -289.477704)
			(xy 371.917976 -289.391598) (xy 371.922389 -289.382086) (xy 371.923905 -289.361195) (xy 371.916955 -289.341435)
			(xy 371.902692 -289.326095) (xy 371.883491 -289.317725) (xy 371.873018 -289.317176) (xy 370.49583 -289.317176)
			(xy 370.460016 -289.385248) (xy 370.319808 -289.65017) (xy 370.329968 -289.67303) (xy 370.338842 -289.693958)
			(xy 370.351417 -289.737643) (xy 370.357891 -289.782638) (xy 370.358416 -289.805364) (xy 370.358416 -289.810698)
			(xy 370.357748 -289.833109) (xy 370.637817 -289.833109) (xy 370.637817 -289.781175) (xy 370.645942 -289.72988)
			(xy 370.66199 -289.680487) (xy 370.685568 -289.634213) (xy 370.716094 -289.592197) (xy 370.752817 -289.555474)
			(xy 370.794833 -289.524948) (xy 370.841107 -289.50137) (xy 370.8905 -289.485322) (xy 370.941795 -289.477197)
			(xy 370.993729 -289.477197) (xy 371.045024 -289.485322) (xy 371.094417 -289.50137) (xy 371.140691 -289.524948)
			(xy 371.182707 -289.555474) (xy 371.21943 -289.592197) (xy 371.249956 -289.634213) (xy 371.273534 -289.680487)
			(xy 371.289582 -289.72988) (xy 371.297707 -289.781175) (xy 371.298216 -289.807142) (xy 371.297707 -289.833109)
			(xy 371.289582 -289.884404) (xy 371.273534 -289.933797) (xy 371.249956 -289.980071) (xy 371.21943 -290.022087)
			(xy 371.182707 -290.05881) (xy 371.140691 -290.089336) (xy 371.094417 -290.112914) (xy 371.045024 -290.128962)
			(xy 370.993729 -290.137087) (xy 370.941795 -290.137087) (xy 370.8905 -290.128962) (xy 370.841107 -290.112914)
			(xy 370.794833 -290.089336) (xy 370.752817 -290.05881) (xy 370.716094 -290.022087) (xy 370.685568 -289.980071)
			(xy 370.66199 -289.933797) (xy 370.645942 -289.884404) (xy 370.637817 -289.833109) (xy 370.357748 -289.833109)
			(xy 370.357647 -289.836484) (xy 370.349092 -289.887356) (xy 370.332735 -289.93628) (xy 370.308974 -289.982067)
			(xy 370.278386 -290.023606) (xy 370.241715 -290.059888) (xy 370.199851 -290.090029) (xy 370.153811 -290.113299)
			(xy 370.104715 -290.129131) (xy 370.053755 -290.137142) (xy 370.027962 -290.137596) (xy 370.001996 -290.137084)
			(xy 369.950703 -290.128955) (xy 369.901312 -290.112904) (xy 369.855041 -290.089325) (xy 369.813027 -290.058798)
			(xy 369.776304 -290.022076) (xy 369.745777 -289.980063) (xy 369.722198 -289.933791) (xy 369.706146 -289.884401)
			(xy 369.698016 -289.833108) (xy 369.697508 -289.807142) (xy 369.697989 -289.781598) (xy 369.705859 -289.731119)
			(xy 369.721404 -289.682453) (xy 369.744252 -289.636759) (xy 369.77386 -289.595125) (xy 369.809522 -289.558543)
			(xy 369.850389 -289.527884) (xy 369.895486 -289.50388) (xy 369.943741 -289.487101) (xy 369.96878 -289.482022)
			(xy 369.99291 -289.477704) (xy 370.038376 -289.391598) (xy 370.042789 -289.382086) (xy 370.044305 -289.361195)
			(xy 370.037355 -289.341435) (xy 370.023092 -289.326095) (xy 370.003891 -289.317725) (xy 369.993418 -289.317176)
			(xy 369.48999 -289.317176) (xy 369.112038 -288.939224) (xy 369.101833 -288.929624) (xy 369.077404 -288.915925)
			(xy 369.05017 -288.909387) (xy 369.022184 -288.910502) (xy 368.995557 -288.919187) (xy 368.972295 -288.934786)
			(xy 368.954154 -288.956124) (xy 368.947954 -288.968688) (xy 368.94516 -288.970974) (xy 368.941096 -288.989008)
			(xy 368.93542 -289.012548) (xy 368.91811 -289.057769) (xy 368.894385 -289.09998) (xy 368.864754 -289.138276)
			(xy 368.829849 -289.171837) (xy 368.790421 -289.199944) (xy 368.747312 -289.221994) (xy 368.701446 -289.237517)
			(xy 368.677698 -289.242246) (xy 368.653568 -289.246564) (xy 368.56924 -289.406076) (xy 368.440208 -289.65017)
			(xy 368.450368 -289.67303) (xy 368.459242 -289.693958) (xy 368.471817 -289.737643) (xy 368.478291 -289.782638)
			(xy 368.478816 -289.805364) (xy 368.478816 -289.810698) (xy 368.478148 -289.833109) (xy 368.758217 -289.833109)
			(xy 368.758217 -289.781175) (xy 368.766342 -289.72988) (xy 368.78239 -289.680487) (xy 368.805968 -289.634213)
			(xy 368.836494 -289.592197) (xy 368.873217 -289.555474) (xy 368.915233 -289.524948) (xy 368.961507 -289.50137)
			(xy 369.0109 -289.485322) (xy 369.062195 -289.477197) (xy 369.114129 -289.477197) (xy 369.165424 -289.485322)
			(xy 369.214817 -289.50137) (xy 369.261091 -289.524948) (xy 369.303107 -289.555474) (xy 369.33983 -289.592197)
			(xy 369.370356 -289.634213) (xy 369.393934 -289.680487) (xy 369.409982 -289.72988) (xy 369.418107 -289.781175)
			(xy 369.418616 -289.807142) (xy 369.418107 -289.833109) (xy 369.409982 -289.884404) (xy 369.393934 -289.933797)
			(xy 369.370356 -289.980071) (xy 369.33983 -290.022087) (xy 369.303107 -290.05881) (xy 369.261091 -290.089336)
			(xy 369.214817 -290.112914) (xy 369.165424 -290.128962) (xy 369.114129 -290.137087) (xy 369.062195 -290.137087)
			(xy 369.0109 -290.128962) (xy 368.961507 -290.112914) (xy 368.915233 -290.089336) (xy 368.873217 -290.05881)
			(xy 368.836494 -290.022087) (xy 368.805968 -289.980071) (xy 368.78239 -289.933797) (xy 368.766342 -289.884404)
			(xy 368.758217 -289.833109) (xy 368.478148 -289.833109) (xy 368.478047 -289.836484) (xy 368.469492 -289.887356)
			(xy 368.453135 -289.93628) (xy 368.429374 -289.982067) (xy 368.398786 -290.023606) (xy 368.362115 -290.059888)
			(xy 368.320251 -290.090029) (xy 368.274211 -290.113299) (xy 368.225115 -290.129131) (xy 368.174155 -290.137142)
			(xy 368.148362 -290.137596) (xy 368.122396 -290.137084) (xy 368.071103 -290.128955) (xy 368.021712 -290.112904)
			(xy 367.975441 -290.089325) (xy 367.933427 -290.058798) (xy 367.896704 -290.022076) (xy 367.866177 -289.980063)
			(xy 367.842598 -289.933791) (xy 367.826546 -289.884401) (xy 367.818416 -289.833108) (xy 367.817908 -289.807142)
			(xy 367.818389 -289.781598) (xy 367.826259 -289.731119) (xy 367.841804 -289.682453) (xy 367.864652 -289.636759)
			(xy 367.89426 -289.595125) (xy 367.929922 -289.558543) (xy 367.970789 -289.527884) (xy 368.015886 -289.50388)
			(xy 368.064141 -289.487101) (xy 368.08918 -289.482022) (xy 368.11331 -289.477704) (xy 368.197638 -289.318192)
			(xy 368.32667 -289.074098) (xy 368.31651 -289.051238) (xy 368.307547 -289.030071) (xy 368.294897 -288.98588)
			(xy 368.288492 -288.940363) (xy 368.288062 -288.91738) (xy 368.288062 -288.917126) (xy 368.288508 -288.892372)
			(xy 368.2959 -288.843418) (xy 368.310509 -288.796114) (xy 368.332008 -288.751516) (xy 368.359916 -288.710623)
			(xy 368.393609 -288.674348) (xy 368.432333 -288.643501) (xy 368.475225 -288.618774) (xy 368.521323 -288.600717)
			(xy 368.545364 -288.5948) (xy 368.558643 -288.591553) (xy 368.582933 -288.579032) (xy 368.603035 -288.560521)
			(xy 368.61751 -288.537343) (xy 368.625324 -288.511157) (xy 368.625917 -288.483837) (xy 368.619247 -288.457337)
			(xy 368.605791 -288.433553) (xy 368.596418 -288.423604) (xy 368.517424 -288.34461) (xy 368.506098 -288.3341)
			(xy 368.478702 -288.319842) (xy 368.448299 -288.314407) (xy 368.41766 -288.318291) (xy 368.389575 -288.331139)
			(xy 368.377724 -288.341054) (xy 368.359134 -288.358308) (xy 368.317651 -288.387488) (xy 368.2722 -288.409992)
			(xy 368.223845 -288.425292) (xy 368.173721 -288.43303) (xy 368.148362 -288.43351) (xy 368.122396 -288.433024)
			(xy 368.071104 -288.424894) (xy 368.021715 -288.40884) (xy 367.975446 -288.385258) (xy 367.933436 -288.354728)
			(xy 367.896719 -288.318002) (xy 367.866199 -288.275984) (xy 367.842628 -288.229709) (xy 367.826587 -288.180316)
			(xy 367.818469 -288.129022) (xy 367.817908 -288.103056) (xy 367.818397 -288.077699) (xy 367.826144 -288.027581)
			(xy 367.841451 -287.979232) (xy 367.863958 -287.933786) (xy 367.893138 -287.892308) (xy 367.910364 -287.873694)
			(xy 367.920328 -287.861865) (xy 367.933245 -287.833779) (xy 367.937154 -287.803114) (xy 367.931695 -287.772686)
			(xy 367.917371 -287.745291) (xy 367.906808 -287.733994) (xy 367.778284 -287.60547) (xy 367.751106 -287.611566)
			(xy 367.733248 -287.615355) (xy 367.696969 -287.619426) (xy 367.678716 -287.619694) (xy 367.652747 -287.619186)
			(xy 367.601448 -287.611064) (xy 367.55205 -287.595017) (xy 367.505771 -287.571441) (xy 367.46375 -287.540916)
			(xy 367.427021 -287.504193) (xy 367.396488 -287.462177) (xy 367.372904 -287.415902) (xy 367.356849 -287.366507)
			(xy 367.348718 -287.315209) (xy 367.348262 -287.28924) (xy 367.348543 -287.270988) (xy 367.352616 -287.23471)
			(xy 367.35639 -287.21685) (xy 367.362486 -287.189672) (xy 366.811306 -286.638492) (xy 366.811306 -286.092392)
			(xy 366.810743 -286.077187) (xy 366.801799 -286.048121) (xy 366.784705 -286.02297) (xy 366.760972 -286.003957)
			(xy 366.732697 -285.992762) (xy 366.71758 -285.991046) (xy 366.691465 -285.988854) (xy 366.640359 -285.977258)
			(xy 366.591726 -285.957738) (xy 366.546784 -285.930784) (xy 366.506662 -285.897073) (xy 366.472365 -285.85745)
			(xy 366.444755 -285.812909) (xy 366.424523 -285.764567) (xy 366.412177 -285.713637) (xy 366.408028 -285.661397)
			(xy 366.412178 -285.609157) (xy 366.424525 -285.558227) (xy 366.444757 -285.509886) (xy 366.472369 -285.465345)
			(xy 366.506666 -285.425723) (xy 366.546789 -285.392012) (xy 366.591731 -285.365059) (xy 366.640365 -285.34554)
			(xy 366.691471 -285.333945) (xy 366.71758 -285.331662) (xy 366.732693 -285.32992) (xy 366.76097 -285.318742)
			(xy 366.784703 -285.299736) (xy 366.80179 -285.274585) (xy 366.810716 -285.245519) (xy 366.811306 -285.230316)
			(xy 366.811306 -284.46476) (xy 366.81076 -284.449646) (xy 366.801907 -284.420744) (xy 366.784964 -284.395711)
			(xy 366.761422 -284.376752) (xy 366.733353 -284.365535) (xy 366.718342 -284.363668) (xy 366.692149 -284.361545)
			(xy 366.640872 -284.350053) (xy 366.592059 -284.330594) (xy 366.546939 -284.303658) (xy 366.506648 -284.269923)
			(xy 366.472201 -284.23024) (xy 366.444466 -284.185607) (xy 366.42414 -284.137148) (xy 366.411736 -284.086084)
			(xy 366.407567 -284.033701) (xy 366.411736 -283.981318) (xy 366.424139 -283.930254) (xy 366.444465 -283.881796)
			(xy 366.4722 -283.837163) (xy 366.506646 -283.797479) (xy 366.546937 -283.763744) (xy 366.592057 -283.736808)
			(xy 366.640869 -283.717348) (xy 366.692146 -283.705855) (xy 366.718342 -283.703776) (xy 366.733348 -283.701933)
			(xy 366.761384 -283.690656) (xy 366.784903 -283.671683) (xy 366.801856 -283.646668) (xy 366.810763 -283.617792)
			(xy 366.811306 -283.602684) (xy 366.811306 -282.836874) (xy 366.810762 -282.821759) (xy 366.801912 -282.792853)
			(xy 366.78497 -282.767817) (xy 366.761426 -282.748854) (xy 366.733355 -282.737635) (xy 366.718342 -282.735782)
			(xy 366.692148 -282.733659) (xy 366.640869 -282.722166) (xy 366.592054 -282.702706) (xy 366.546932 -282.675769)
			(xy 366.506639 -282.642034) (xy 366.472191 -282.602349) (xy 366.444454 -282.557714) (xy 366.424127 -282.509253)
			(xy 366.411723 -282.458187) (xy 366.407553 -282.405802) (xy 366.411722 -282.353417) (xy 366.424126 -282.302351)
			(xy 366.444452 -282.25389) (xy 366.472188 -282.209255) (xy 366.506636 -282.169569) (xy 366.546928 -282.135833)
			(xy 366.59205 -282.108895) (xy 366.640865 -282.089435) (xy 366.692143 -282.077942) (xy 366.718342 -282.07589)
			(xy 366.733349 -282.074047) (xy 366.761387 -282.062771) (xy 366.784909 -282.043798) (xy 366.801864 -282.018783)
			(xy 366.810774 -281.989906) (xy 366.811306 -281.974798) (xy 366.811306 -281.209242) (xy 366.810771 -281.19412)
			(xy 366.801933 -281.165198) (xy 366.784995 -281.140144) (xy 366.761448 -281.121167) (xy 366.733367 -281.109938)
			(xy 366.718342 -281.10815) (xy 366.69215 -281.106027) (xy 366.640876 -281.094535) (xy 366.592066 -281.075077)
			(xy 366.546949 -281.048142) (xy 366.50666 -281.014409) (xy 366.472216 -280.974728) (xy 366.444482 -280.930097)
			(xy 366.424157 -280.881641) (xy 366.411754 -280.83058) (xy 366.407585 -280.7782) (xy 366.411754 -280.72582)
			(xy 366.424157 -280.674759) (xy 366.444482 -280.626303) (xy 366.472215 -280.581673) (xy 366.50666 -280.541991)
			(xy 366.546948 -280.508258) (xy 366.592066 -280.481324) (xy 366.640876 -280.461865) (xy 366.69215 -280.450374)
			(xy 366.718342 -280.448258) (xy 366.733347 -280.446415) (xy 366.76138 -280.435138) (xy 366.784897 -280.416164)
			(xy 366.801845 -280.391148) (xy 366.810747 -280.362273) (xy 366.811306 -280.347166) (xy 366.811306 -279.581356)
			(xy 366.810759 -279.566242) (xy 366.801906 -279.537341) (xy 366.784963 -279.51231) (xy 366.761421 -279.493351)
			(xy 366.733352 -279.482134) (xy 366.718342 -279.480264) (xy 366.692149 -279.47814) (xy 366.640873 -279.466648)
			(xy 366.592061 -279.447189) (xy 366.546941 -279.420254) (xy 366.506651 -279.38652) (xy 366.472205 -279.346837)
			(xy 366.44447 -279.302204) (xy 366.424144 -279.253746) (xy 366.411741 -279.202683) (xy 366.407571 -279.150301)
			(xy 366.41174 -279.097919) (xy 366.424144 -279.046856) (xy 366.444469 -278.998398) (xy 366.472204 -278.953765)
			(xy 366.50665 -278.914082) (xy 366.54694 -278.880348) (xy 366.592059 -278.853412) (xy 366.640871 -278.833952)
			(xy 366.692147 -278.82246) (xy 366.718342 -278.820372) (xy 366.733348 -278.818529) (xy 366.761383 -278.807252)
			(xy 366.784902 -278.788279) (xy 366.801853 -278.763263) (xy 366.810759 -278.734388) (xy 366.811306 -278.71928)
			(xy 366.811306 -277.921974) (xy 366.74298 -277.853648) (xy 366.723168 -277.852632) (xy 366.698044 -277.850934)
			(xy 366.648702 -277.840885) (xy 366.601453 -277.823475) (xy 366.557389 -277.799105) (xy 366.517526 -277.768339)
			(xy 366.482786 -277.731887) (xy 366.453972 -277.690592) (xy 366.431748 -277.645407) (xy 366.416629 -277.597376)
			(xy 366.408963 -277.547609) (xy 366.408462 -277.522432) (xy 366.408932 -277.496945) (xy 366.416757 -277.446576)
			(xy 366.432227 -277.398006) (xy 366.454974 -277.35239) (xy 366.484458 -277.310809) (xy 366.51998 -277.27425)
			(xy 366.560695 -277.243582) (xy 366.605639 -277.219532) (xy 366.653743 -277.202672) (xy 366.678718 -277.197566)
			(xy 366.72012 -277.189946) (xy 366.72012 -276.227286) (xy 366.678718 -276.219666) (xy 366.653748 -276.214555)
			(xy 366.605658 -276.197676) (xy 366.560728 -276.173616) (xy 366.520025 -276.142943) (xy 366.484513 -276.106386)
			(xy 366.455033 -276.064811) (xy 366.432285 -276.019202) (xy 366.416808 -275.970643) (xy 366.408969 -275.920283)
			(xy 366.408462 -275.8948) (xy 366.408462 -275.88845) (xy 366.409389 -275.863655) (xy 366.417755 -275.814749)
			(xy 366.43333 -275.76764) (xy 366.455767 -275.723386) (xy 366.484561 -275.682979) (xy 366.519067 -275.647326)
			(xy 366.53851 -275.63191) (xy 366.54486 -275.627084) (xy 366.5474 -275.625306) (xy 366.559129 -275.616384)
			(xy 366.577295 -275.593196) (xy 366.588083 -275.565785) (xy 366.590594 -275.536435) (xy 366.584619 -275.507591)
			(xy 366.570656 -275.481653) (xy 366.560608 -275.470874) (xy 366.44961 -275.359876) (xy 366.41659 -275.376386)
			(xy 366.393857 -275.387203) (xy 366.345925 -275.402594) (xy 366.296215 -275.410545) (xy 366.271048 -275.411184)
			(xy 366.265206 -275.411184) (xy 366.239623 -275.410411) (xy 366.189149 -275.401941) (xy 366.140583 -275.385792)
			(xy 366.095087 -275.362349) (xy 366.053749 -275.332174) (xy 366.017556 -275.295986) (xy 365.987375 -275.254653)
			(xy 365.963926 -275.20916) (xy 365.94777 -275.160597) (xy 365.939294 -275.110123) (xy 365.938562 -275.08454)
			(xy 365.938562 -275.080476) (xy 365.939051 -275.055007) (xy 365.946909 -275.004678) (xy 365.962405 -274.956154)
			(xy 365.97336 -274.933156) (xy 365.98987 -274.900136) (xy 365.65332 -274.563586) (xy 365.646462 -274.56003)
			(xy 365.624301 -274.547953) (xy 365.583604 -274.51811) (xy 365.547916 -274.482427) (xy 365.518068 -274.441733)
			(xy 365.506 -274.419568) (xy 365.502444 -274.41271) (xy 365.357156 -274.267422) (xy 365.347009 -274.257875)
			(xy 365.322733 -274.244224) (xy 365.295671 -274.237642) (xy 365.267838 -274.238618) (xy 365.241304 -274.247081)
			(xy 365.218044 -274.262399) (xy 365.199791 -274.283434) (xy 365.187901 -274.30862) (xy 365.185198 -274.322286)
			(xy 365.180399 -274.347607) (xy 365.16399 -274.396459) (xy 365.140194 -274.44217) (xy 365.109588 -274.483632)
			(xy 365.072916 -274.519838) (xy 365.031066 -274.549911) (xy 364.985055 -274.57312) (xy 364.935997 -274.588903)
			(xy 364.885083 -274.596877) (xy 364.859316 -274.597368) (xy 364.833345 -274.596886) (xy 364.782044 -274.588763)
			(xy 364.732644 -274.572715) (xy 364.686363 -274.549137) (xy 364.644341 -274.518608) (xy 364.607611 -274.481882)
			(xy 364.577079 -274.439862) (xy 364.553496 -274.393584) (xy 364.537444 -274.344186) (xy 364.529316 -274.292884)
			(xy 364.528862 -274.266914) (xy 364.529361 -274.241152) (xy 364.537367 -274.190255) (xy 364.55317 -274.141215)
			(xy 364.57639 -274.09522) (xy 364.606463 -274.053384) (xy 364.642661 -274.016719) (xy 364.684109 -273.986113)
			(xy 364.729803 -273.962306) (xy 364.778636 -273.945876) (xy 364.803944 -273.941032) (xy 364.817552 -273.938196)
			(xy 364.842636 -273.926249) (xy 364.863571 -273.907981) (xy 364.878806 -273.884746) (xy 364.887213 -273.858264)
			(xy 364.888169 -273.830496) (xy 364.881604 -273.803499) (xy 364.868003 -273.779271) (xy 364.858554 -273.769074)
			(xy 364.835694 -273.746214) (xy 364.835694 -272.971514) (xy 364.800134 -272.964402) (xy 364.775071 -272.959373)
			(xy 364.726779 -272.942618) (xy 364.681643 -272.918628) (xy 364.640738 -272.887975) (xy 364.60504 -272.85139)
			(xy 364.5754 -272.809745) (xy 364.552525 -272.764033) (xy 364.536961 -272.715344) (xy 364.529079 -272.66484)
			(xy 364.528608 -272.639282) (xy 364.529089 -272.614028) (xy 364.536779 -272.564107) (xy 364.551978 -272.51594)
			(xy 364.574331 -272.470646) (xy 364.603318 -272.429283) (xy 364.638263 -272.392814) (xy 364.678352 -272.362088)
			(xy 364.72265 -272.337822) (xy 364.770125 -272.320581) (xy 364.7948 -272.315178) (xy 364.835694 -272.30705)
			(xy 364.835694 -271.792446) (xy 364.7694 -271.726152) (xy 364.717076 -271.778222) (xy 364.7186 -271.801336)
			(xy 364.719362 -271.825212) (xy 364.718853 -271.851179) (xy 364.710728 -271.902474) (xy 364.69468 -271.951867)
			(xy 364.671102 -271.998141) (xy 364.640576 -272.040157) (xy 364.603853 -272.07688) (xy 364.561837 -272.107406)
			(xy 364.515563 -272.130984) (xy 364.46617 -272.147032) (xy 364.414875 -272.155157) (xy 364.362941 -272.155157)
			(xy 364.311646 -272.147032) (xy 364.262253 -272.130984) (xy 364.215979 -272.107406) (xy 364.173963 -272.07688)
			(xy 364.13724 -272.040157) (xy 364.106714 -271.998141) (xy 364.083136 -271.951867) (xy 364.067088 -271.902474)
			(xy 364.058963 -271.851179) (xy 364.058454 -271.825212) (xy 364.058931 -271.799969) (xy 364.066609 -271.75007)
			(xy 364.081788 -271.701919) (xy 364.104115 -271.656638) (xy 364.133069 -271.61528) (xy 364.167978 -271.578807)
			(xy 364.208029 -271.548069) (xy 364.252289 -271.523781) (xy 364.299729 -271.506508) (xy 364.324392 -271.501108)
			(xy 364.337494 -271.497642) (xy 364.361355 -271.484812) (xy 364.381002 -271.466157) (xy 364.395051 -271.442993)
			(xy 364.402512 -271.416948) (xy 364.402861 -271.389858) (xy 364.396073 -271.363631) (xy 364.382625 -271.340112)
			(xy 364.373414 -271.330166) (xy 364.292388 -271.24914) (xy 364.281113 -271.238617) (xy 364.253814 -271.224299)
			(xy 364.223488 -271.218765) (xy 364.192891 -271.222518) (xy 364.164802 -271.235218) (xy 364.152942 -271.245076)
			(xy 364.134238 -271.263101) (xy 364.092218 -271.293636) (xy 364.045938 -271.31722) (xy 363.996537 -271.33327)
			(xy 363.945233 -271.341393) (xy 363.919262 -271.34185) (xy 363.893297 -271.341338) (xy 363.842007 -271.333209)
			(xy 363.792619 -271.317157) (xy 363.746351 -271.293577) (xy 363.704341 -271.26305) (xy 363.667623 -271.226327)
			(xy 363.637101 -271.184313) (xy 363.613527 -271.138042) (xy 363.597481 -271.088652) (xy 363.589359 -271.037361)
			(xy 363.588808 -271.011396) (xy 363.58926 -270.9865) (xy 363.596733 -270.937272) (xy 363.611507 -270.889722)
			(xy 363.63325 -270.844928) (xy 363.661468 -270.803904) (xy 363.695523 -270.767579) (xy 363.714792 -270.751808)
			(xy 363.717078 -270.75003) (xy 363.755178 -270.71193) (xy 363.704124 -270.660876) (xy 363.704124 -270.60144)
			(xy 363.703679 -270.587706) (xy 363.696367 -270.561229) (xy 363.682262 -270.53766) (xy 363.662384 -270.518704)
			(xy 363.638172 -270.505733) (xy 363.611378 -270.499685) (xy 363.583942 -270.500999) (xy 363.570774 -270.50492)
			(xy 363.541581 -270.51568) (xy 363.480467 -270.527304) (xy 363.449362 -270.528034) (xy 363.423398 -270.527522)
			(xy 363.372111 -270.519393) (xy 363.322726 -270.503342) (xy 363.276461 -270.479764) (xy 363.234452 -270.449239)
			(xy 363.197736 -270.412519) (xy 363.167216 -270.370507) (xy 363.143643 -270.324238) (xy 363.127598 -270.274852)
			(xy 363.119475 -270.223564) (xy 363.119475 -270.171636) (xy 363.127598 -270.120348) (xy 363.143643 -270.070962)
			(xy 363.167216 -270.024693) (xy 363.197736 -269.982681) (xy 363.234453 -269.945961) (xy 363.276461 -269.915436)
			(xy 363.322726 -269.891858) (xy 363.372111 -269.875807) (xy 363.423398 -269.867678) (xy 363.449362 -269.867126)
			(xy 363.480469 -269.867835) (xy 363.541586 -269.879462) (xy 363.570774 -269.89024) (xy 363.583956 -269.894099)
			(xy 363.61138 -269.89541) (xy 363.638161 -269.889366) (xy 363.662364 -269.876405) (xy 363.682238 -269.857462)
			(xy 363.696346 -269.833909) (xy 363.703667 -269.807448) (xy 363.704124 -269.79372) (xy 363.704124 -269.634716)
			(xy 363.684746 -269.617451) (xy 363.651086 -269.577948) (xy 363.624009 -269.533674) (xy 363.604179 -269.485714)
			(xy 363.592083 -269.435245) (xy 363.588016 -269.383507) (xy 363.59208 -269.331768) (xy 363.604175 -269.281299)
			(xy 363.624003 -269.233338) (xy 363.651079 -269.189062) (xy 363.684736 -269.149558) (xy 363.704124 -269.132304)
			(xy 363.704124 -268.973808) (xy 363.703675 -268.959745) (xy 363.696007 -268.932685) (xy 363.681249 -268.908743)
			(xy 363.660521 -268.889732) (xy 363.635395 -268.877095) (xy 363.607774 -268.87179) (xy 363.579754 -268.874218)
			(xy 363.566456 -268.878812) (xy 363.538279 -268.888772) (xy 363.479495 -268.899516) (xy 363.449616 -268.900148)
			(xy 363.423646 -268.899666) (xy 363.372346 -268.891544) (xy 363.322948 -268.875495) (xy 363.276669 -268.851917)
			(xy 363.234649 -268.821389) (xy 363.197921 -268.784663) (xy 363.167391 -268.742644) (xy 363.143811 -268.696366)
			(xy 363.12776 -268.646969) (xy 363.119635 -268.59567) (xy 363.119635 -268.54373) (xy 363.12776 -268.492431)
			(xy 363.143811 -268.443034) (xy 363.167391 -268.396756) (xy 363.197921 -268.354737) (xy 363.234649 -268.318011)
			(xy 363.276669 -268.287483) (xy 363.322948 -268.263905) (xy 363.372346 -268.247856) (xy 363.423646 -268.239734)
			(xy 363.449616 -268.23924) (xy 363.479494 -268.239884) (xy 363.538276 -268.250625) (xy 363.566456 -268.260576)
			(xy 363.57976 -268.265144) (xy 363.607772 -268.267572) (xy 363.635384 -268.262268) (xy 363.660503 -268.249634)
			(xy 363.681223 -268.230628) (xy 363.695975 -268.206691) (xy 363.703638 -268.179639) (xy 363.704124 -268.16558)
			(xy 363.704124 -268.007084) (xy 363.684748 -267.989819) (xy 363.651094 -267.950317) (xy 363.624021 -267.906044)
			(xy 363.604196 -267.858086) (xy 363.592103 -267.807621) (xy 363.588041 -267.755886) (xy 363.592108 -267.704151)
			(xy 363.604205 -267.653686) (xy 363.624034 -267.60573) (xy 363.65111 -267.56146) (xy 363.684768 -267.521961)
			(xy 363.704124 -267.504672) (xy 363.704124 -267.345668) (xy 363.70367 -267.331941) (xy 363.696347 -267.305482)
			(xy 363.682238 -267.28193) (xy 363.662364 -267.262989) (xy 363.638161 -267.250029) (xy 363.61138 -267.243985)
			(xy 363.583958 -267.245296) (xy 363.570774 -267.249148) (xy 363.541581 -267.25991) (xy 363.480467 -267.271537)
			(xy 363.449362 -267.272262) (xy 363.423396 -267.27175) (xy 363.372104 -267.263621) (xy 363.322716 -267.247568)
			(xy 363.276446 -267.223988) (xy 363.234434 -267.19346) (xy 363.197715 -267.156737) (xy 363.167192 -267.114722)
			(xy 363.143617 -267.068449) (xy 363.12757 -267.019059) (xy 363.119447 -266.967766) (xy 363.119447 -266.915834)
			(xy 363.12757 -266.864541) (xy 363.143617 -266.815151) (xy 363.167192 -266.768878) (xy 363.197715 -266.726863)
			(xy 363.234434 -266.69014) (xy 363.276446 -266.659612) (xy 363.322716 -266.636032) (xy 363.372104 -266.619979)
			(xy 363.423396 -266.61185) (xy 363.449362 -266.611354) (xy 363.480469 -266.612063) (xy 363.541586 -266.623691)
			(xy 363.570774 -266.634468) (xy 363.583953 -266.638329) (xy 363.611372 -266.639642) (xy 363.638148 -266.633598)
			(xy 363.662344 -266.620635) (xy 363.682209 -266.601689) (xy 363.696303 -266.578134) (xy 363.703608 -266.551673)
			(xy 363.704124 -266.537948) (xy 363.704124 -266.379452) (xy 363.684743 -266.362187) (xy 363.651078 -266.322683)
			(xy 363.623995 -266.278407) (xy 363.60416 -266.230444) (xy 363.592059 -266.179972) (xy 363.587989 -266.12823)
			(xy 363.59205 -266.076487) (xy 363.604142 -266.026013) (xy 363.623968 -265.978046) (xy 363.651043 -265.933765)
			(xy 363.6847 -265.894256) (xy 363.704124 -265.87704) (xy 363.704124 -265.71829) (xy 363.703673 -265.704229)
			(xy 363.696001 -265.677174) (xy 363.681243 -265.653235) (xy 363.660517 -265.634229) (xy 363.635393 -265.621594)
			(xy 363.607776 -265.61629) (xy 363.579759 -265.618717) (xy 363.566456 -265.623294) (xy 363.538279 -265.633255)
			(xy 363.479495 -265.643999) (xy 363.449616 -265.64463) (xy 363.423648 -265.644148) (xy 363.37235 -265.636026)
			(xy 363.322955 -265.619979) (xy 363.276679 -265.596402) (xy 363.234661 -265.565875) (xy 363.197935 -265.529152)
			(xy 363.167407 -265.487135) (xy 363.143827 -265.440859) (xy 363.127778 -265.391465) (xy 363.119653 -265.340168)
			(xy 363.119653 -265.288232) (xy 363.127778 -265.236935) (xy 363.143827 -265.187541) (xy 363.167407 -265.141265)
			(xy 363.197935 -265.099248) (xy 363.234661 -265.062525) (xy 363.276679 -265.031998) (xy 363.322955 -265.008421)
			(xy 363.37235 -264.992374) (xy 363.423648 -264.984252) (xy 363.449616 -264.983722) (xy 363.479494 -264.984366)
			(xy 363.538276 -264.995107) (xy 363.566456 -265.005058) (xy 363.579759 -265.009626) (xy 363.60777 -265.012055)
			(xy 363.635381 -265.006751) (xy 363.660498 -264.994116) (xy 363.681216 -264.97511) (xy 363.695964 -264.951173)
			(xy 363.703623 -264.92412) (xy 363.704124 -264.910062) (xy 363.704124 -264.751566) (xy 363.684749 -264.734301)
			(xy 363.651098 -264.6948) (xy 363.624028 -264.650527) (xy 363.604205 -264.602571) (xy 363.592115 -264.552107)
			(xy 363.588054 -264.500374) (xy 363.592123 -264.448642) (xy 363.604221 -264.39818) (xy 363.624052 -264.350226)
			(xy 363.651128 -264.305958) (xy 363.684786 -264.266462) (xy 363.704124 -264.249154) (xy 363.704124 -264.090658)
			(xy 363.703669 -264.0766) (xy 363.695992 -264.049553) (xy 363.681233 -264.025623) (xy 363.660508 -264.006623)
			(xy 363.635389 -263.993993) (xy 363.607778 -263.98869) (xy 363.579767 -263.991115) (xy 363.566456 -263.995662)
			(xy 363.538279 -264.005621) (xy 363.479495 -264.016363) (xy 363.449616 -264.016998) (xy 363.423642 -264.016516)
			(xy 363.372335 -264.008392) (xy 363.322929 -263.992342) (xy 363.276643 -263.96876) (xy 363.234616 -263.938227)
			(xy 363.197883 -263.901496) (xy 363.167349 -263.85947) (xy 363.143765 -263.813186) (xy 363.127712 -263.763781)
			(xy 363.119585 -263.712474) (xy 363.119585 -263.660526) (xy 363.127712 -263.609219) (xy 363.143765 -263.559814)
			(xy 363.167349 -263.51353) (xy 363.197883 -263.471504) (xy 363.234616 -263.434773) (xy 363.276643 -263.40424)
			(xy 363.322929 -263.380658) (xy 363.372335 -263.364608) (xy 363.423642 -263.356484) (xy 363.449616 -263.35609)
			(xy 363.479494 -263.356734) (xy 363.538277 -263.367473) (xy 363.566456 -263.377426) (xy 363.579762 -263.381992)
			(xy 363.607777 -263.384418) (xy 363.635393 -263.379114) (xy 363.660516 -263.366482) (xy 363.681243 -263.347478)
			(xy 363.696003 -263.323543) (xy 363.703678 -263.29649) (xy 363.704124 -263.28243) (xy 363.704124 -262.081264)
			(xy 364.081568 -261.70382) (xy 364.09064 -261.694161) (xy 364.103926 -261.671246) (xy 364.110847 -261.645677)
			(xy 364.110935 -261.619189) (xy 364.104182 -261.593575) (xy 364.091048 -261.570572) (xy 364.082076 -261.560818)
			(xy 364.064377 -261.542152) (xy 364.034396 -261.500357) (xy 364.011256 -261.45442) (xy 363.995515 -261.405451)
			(xy 363.987556 -261.354634) (xy 363.98708 -261.328916) (xy 363.987562 -261.302947) (xy 363.995685 -261.251648)
			(xy 364.011734 -261.202251) (xy 364.035313 -261.155974) (xy 364.065842 -261.113955) (xy 364.102569 -261.07723)
			(xy 364.144589 -261.046704) (xy 364.190868 -261.023127) (xy 364.240265 -261.007081) (xy 364.291565 -260.99896)
			(xy 364.317534 -260.998462) (xy 364.345159 -260.999021) (xy 364.399639 -261.00821) (xy 364.451834 -261.026327)
			(xy 364.500291 -261.052868) (xy 364.543663 -261.087094) (xy 364.562644 -261.107174) (xy 364.572381 -261.116463)
			(xy 364.595615 -261.130024) (xy 364.621583 -261.137047) (xy 364.648485 -261.137047) (xy 364.674453 -261.130024)
			(xy 364.697687 -261.116463) (xy 364.707424 -261.107174) (xy 364.726381 -261.087069) (xy 364.76976 -261.052845)
			(xy 364.818223 -261.026305) (xy 364.870422 -261.008187) (xy 364.924907 -260.998994) (xy 364.952534 -260.998462)
			(xy 364.979951 -260.999005) (xy 365.03403 -261.008065) (xy 365.085872 -261.025931) (xy 365.134052 -261.052111)
			(xy 365.155988 -261.068566) (xy 365.187992 -261.092696) (xy 367.927128 -258.35356) (xy 367.927128 -254.52832)
			(xy 368.070638 -254.38481) (xy 368.070638 -249.90679) (xy 366.467898 -248.30405) (xy 366.467898 -247.0912)
			(xy 366.467486 -247.07805) (xy 366.460763 -247.052624) (xy 366.447765 -247.02976) (xy 366.429355 -247.010978)
			(xy 366.406756 -246.997526) (xy 366.381469 -246.990297) (xy 366.36833 -246.9896) (xy 366.342395 -246.988734)
			(xy 366.291259 -246.979921) (xy 366.242128 -246.963227) (xy 366.196208 -246.939063) (xy 366.154627 -246.908022)
			(xy 366.136174 -246.889778) (xy 366.133634 -246.888762) (xy 366.121944 -246.880746) (xy 366.095389 -246.87087)
			(xy 366.067143 -246.868645) (xy 366.039369 -246.874243) (xy 366.01419 -246.887234) (xy 366.003586 -246.896636)
			(xy 365.984743 -246.915772) (xy 365.941995 -246.948277) (xy 365.89455 -246.973433) (xy 365.843657 -246.990576)
			(xy 365.790661 -246.999255) (xy 365.76381 -246.99976) (xy 365.73784 -246.999278) (xy 365.686538 -246.991154)
			(xy 365.63714 -246.975105) (xy 365.59086 -246.951525) (xy 365.548839 -246.920996) (xy 365.51211 -246.884269)
			(xy 365.48158 -246.842249) (xy 365.457999 -246.79597) (xy 365.441948 -246.746571) (xy 365.433823 -246.69527)
			(xy 365.433823 -246.64333) (xy 365.441948 -246.592029) (xy 365.457999 -246.54263) (xy 365.48158 -246.496351)
			(xy 365.51211 -246.454331) (xy 365.548839 -246.417604) (xy 365.59086 -246.387075) (xy 365.63714 -246.363495)
			(xy 365.686538 -246.347446) (xy 365.73784 -246.339322) (xy 365.76381 -246.338852) (xy 365.789132 -246.339336)
			(xy 365.839183 -246.347057) (xy 365.887472 -246.362319) (xy 365.93287 -246.384764) (xy 365.974316 -246.413867)
			(xy 365.992918 -246.431054) (xy 366.004456 -246.441444) (xy 366.032215 -246.455315) (xy 366.06286 -246.460198)
			(xy 366.093556 -246.45564) (xy 366.12146 -246.442063) (xy 366.133126 -246.431816) (xy 366.15109 -246.413571)
			(xy 366.191628 -246.382297) (xy 366.236503 -246.357646) (xy 366.284641 -246.340208) (xy 366.334893 -246.330401)
			(xy 366.360456 -246.328946) (xy 366.373918 -246.328438) (xy 366.389063 -246.326731) (xy 366.417416 -246.315596)
			(xy 366.441227 -246.296601) (xy 366.458383 -246.271431) (xy 366.467358 -246.242322) (xy 366.467898 -246.227092)
			(xy 366.467898 -246.10695) (xy 367.971578 -244.60327) (xy 367.971578 -241.170206) (xy 367.89614 -241.094768)
			(xy 367.89614 -239.754664) (xy 367.895613 -239.739739) (xy 367.886979 -239.711164) (xy 367.870456 -239.686302)
			(xy 367.847456 -239.667274) (xy 367.819939 -239.655702) (xy 367.790252 -239.652574) (xy 367.77549 -239.654842)
			(xy 367.760207 -239.657582) (xy 367.729294 -239.660512) (xy 367.713768 -239.660684) (xy 367.713514 -239.660684)
			(xy 367.688987 -239.660237) (xy 367.640471 -239.652984) (xy 367.593562 -239.638634) (xy 367.549291 -239.617504)
			(xy 367.508632 -239.590059) (xy 367.490248 -239.573816) (xy 367.478759 -239.564013) (xy 367.451522 -239.550999)
			(xy 367.421668 -239.546531) (xy 367.391814 -239.550999) (xy 367.364577 -239.564013) (xy 367.353088 -239.573816)
			(xy 367.334705 -239.59006) (xy 367.294042 -239.617499) (xy 367.249771 -239.638628) (xy 367.202863 -239.652983)
			(xy 367.154349 -239.66025) (xy 367.129822 -239.660684) (xy 367.129568 -239.660684) (xy 367.102493 -239.660115)
			(xy 367.049074 -239.651238) (xy 366.997815 -239.633777) (xy 366.950086 -239.608198) (xy 366.907162 -239.575183)
			(xy 366.888268 -239.555782) (xy 366.879005 -239.546494) (xy 366.856791 -239.532561) (xy 366.831761 -239.524746)
			(xy 366.805566 -239.523564) (xy 366.779934 -239.529094) (xy 366.756556 -239.540969) (xy 366.746536 -239.549432)
			(xy 366.728112 -239.565773) (xy 366.687334 -239.593382) (xy 366.642913 -239.614641) (xy 366.595832 -239.62908)
			(xy 366.547131 -239.636381) (xy 366.522508 -239.636808) (xy 366.503458 -239.6363) (xy 366.503204 -239.6363)
			(xy 366.476108 -239.63416) (xy 366.423101 -239.622153) (xy 366.372769 -239.601648) (xy 366.326463 -239.573194)
			(xy 366.305592 -239.555782) (xy 366.293908 -239.545622) (xy 366.282353 -239.536987) (xy 366.255717 -239.525949)
			(xy 366.227056 -239.522811) (xy 366.198662 -239.527822) (xy 366.172807 -239.540583) (xy 366.161828 -239.54994)
			(xy 366.143326 -239.566303) (xy 366.102375 -239.593915) (xy 366.057767 -239.615119) (xy 366.0105 -239.629443)
			(xy 365.961626 -239.636567) (xy 365.912236 -239.636332) (xy 365.887762 -239.632998) (xy 365.864855 -239.629051)
			(xy 365.820368 -239.615575) (xy 365.778206 -239.596004) (xy 365.739199 -239.570723) (xy 365.721392 -239.555782)
			(xy 365.716058 -239.550956) (xy 365.714788 -239.54994) (xy 365.703828 -239.540546) (xy 365.677968 -239.527752)
			(xy 365.649558 -239.522725) (xy 365.620878 -239.525869) (xy 365.59423 -239.53693) (xy 365.582708 -239.545622)
			(xy 365.571024 -239.555782) (xy 365.552887 -239.570992) (xy 365.513085 -239.596613) (xy 365.470039 -239.6163)
			(xy 365.424627 -239.629653) (xy 365.377775 -239.636399) (xy 365.354108 -239.636808) (xy 365.341408 -239.636554)
			(xy 365.33455 -239.6363) (xy 365.308319 -239.634235) (xy 365.256953 -239.62284) (xy 365.208041 -239.60345)
			(xy 365.16282 -239.576555) (xy 365.122431 -239.542834) (xy 365.087895 -239.50314) (xy 365.060085 -239.458476)
			(xy 365.039703 -239.409969) (xy 365.027265 -239.358846) (xy 365.023084 -239.306397) (xy 365.027266 -239.253949)
			(xy 365.039705 -239.202826) (xy 365.060088 -239.154319) (xy 365.087898 -239.109655) (xy 365.122435 -239.069962)
			(xy 365.162824 -239.036242) (xy 365.208046 -239.009348) (xy 365.256958 -238.989959) (xy 365.308324 -238.978564)
			(xy 365.33455 -238.976408) (xy 365.341408 -238.976154) (xy 365.354108 -238.9759) (xy 365.37778 -238.97628)
			(xy 365.424644 -238.982992) (xy 365.470068 -238.996334) (xy 365.513118 -239.016032) (xy 365.552911 -239.041682)
			(xy 365.571024 -239.056926) (xy 365.582708 -239.067086) (xy 365.594263 -239.075718) (xy 365.620898 -239.086751)
			(xy 365.649556 -239.089885) (xy 365.677946 -239.084871) (xy 365.703797 -239.07211) (xy 365.714788 -239.062768)
			(xy 365.733292 -239.046411) (xy 365.774246 -239.018808) (xy 365.818853 -238.997612) (xy 365.866119 -238.983294)
			(xy 365.91499 -238.976175) (xy 365.964377 -238.976412) (xy 365.988854 -238.97971) (xy 366.011761 -238.983658)
			(xy 366.056246 -238.997136) (xy 366.098406 -239.016709) (xy 366.137411 -239.041992) (xy 366.155224 -239.056926)
			(xy 366.160558 -239.061752) (xy 366.161828 -239.062768) (xy 366.172788 -239.072159) (xy 366.198647 -239.084948)
			(xy 366.227055 -239.08997) (xy 366.255731 -239.086824) (xy 366.282374 -239.075761) (xy 366.293908 -239.067086)
			(xy 366.305592 -239.056926) (xy 366.323729 -239.041716) (xy 366.363531 -239.016097) (xy 366.406577 -238.996411)
			(xy 366.45199 -238.98306) (xy 366.498841 -238.976316) (xy 366.522508 -238.9759) (xy 366.535208 -238.976154)
			(xy 366.542066 -238.976408) (xy 366.567591 -238.978397) (xy 366.61762 -238.989265) (xy 366.665373 -239.007723)
			(xy 366.709706 -239.033328) (xy 366.749556 -239.065467) (xy 366.76711 -239.084104) (xy 366.77797 -239.094069)
			(xy 366.80402 -239.107833) (xy 366.832918 -239.113569) (xy 366.86225 -239.110798) (xy 366.876076 -239.105694)
			(xy 366.891852 -239.087476) (xy 366.92778 -239.055361) (xy 366.967996 -239.028809) (xy 367.011643 -239.008383)
			(xy 367.057795 -238.994519) (xy 367.105473 -238.98751) (xy 367.129568 -238.987076) (xy 367.153683 -238.98751)
			(xy 367.201401 -238.994511) (xy 367.247597 -239.008368) (xy 367.29129 -239.028788) (xy 367.331553 -239.055338)
			(xy 367.367534 -239.087455) (xy 367.383314 -239.105694) (xy 367.395624 -239.110284) (xy 367.421668 -239.113675)
			(xy 367.447712 -239.110284) (xy 367.460022 -239.105694) (xy 367.475821 -239.087471) (xy 367.511797 -239.05535)
			(xy 367.552056 -239.028795) (xy 367.595745 -239.008368) (xy 367.641937 -238.994503) (xy 367.689654 -238.987494)
			(xy 367.713768 -238.987076) (xy 367.742901 -238.987691) (xy 367.800264 -238.997905) (xy 367.827814 -239.007396)
			(xy 367.836196 -239.010444) (xy 367.89614 -239.010444) (xy 367.89614 -238.911892) (xy 367.400078 -238.41583)
			(xy 362.199936 -238.41583) (xy 362.184327 -238.437108) (xy 362.147482 -238.474882) (xy 362.105102 -238.506323)
			(xy 362.058266 -238.53063) (xy 362.008162 -238.547186) (xy 361.956064 -238.55557) (xy 361.903296 -238.55557)
			(xy 361.851198 -238.547186) (xy 361.801094 -238.53063) (xy 361.754258 -238.506323) (xy 361.711878 -238.474882)
			(xy 361.675033 -238.437108) (xy 361.659424 -238.41583) (xy 361.260136 -238.41583) (xy 361.244527 -238.437108)
			(xy 361.207682 -238.474882) (xy 361.165302 -238.506323) (xy 361.118466 -238.53063) (xy 361.068362 -238.547186)
			(xy 361.016264 -238.55557) (xy 360.963496 -238.55557) (xy 360.911398 -238.547186) (xy 360.861294 -238.53063)
			(xy 360.814458 -238.506323) (xy 360.772078 -238.474882) (xy 360.735233 -238.437108) (xy 360.719624 -238.41583)
			(xy 360.320336 -238.41583) (xy 360.304727 -238.437108) (xy 360.267882 -238.474882) (xy 360.225502 -238.506323)
			(xy 360.178666 -238.53063) (xy 360.128562 -238.547186) (xy 360.076464 -238.55557) (xy 360.023696 -238.55557)
			(xy 359.971598 -238.547186) (xy 359.921494 -238.53063) (xy 359.874658 -238.506323) (xy 359.832278 -238.474882)
			(xy 359.795433 -238.437108) (xy 359.779824 -238.41583) (xy 359.380536 -238.41583) (xy 359.364927 -238.437108)
			(xy 359.328082 -238.474882) (xy 359.285702 -238.506323) (xy 359.238866 -238.53063) (xy 359.188762 -238.547186)
			(xy 359.136664 -238.55557) (xy 359.083896 -238.55557) (xy 359.031798 -238.547186) (xy 358.981694 -238.53063)
			(xy 358.934858 -238.506323) (xy 358.892478 -238.474882) (xy 358.855633 -238.437108) (xy 358.840024 -238.41583)
			(xy 358.440736 -238.41583) (xy 358.425127 -238.437108) (xy 358.388282 -238.474882) (xy 358.345902 -238.506323)
			(xy 358.299066 -238.53063) (xy 358.248962 -238.547186) (xy 358.196864 -238.55557) (xy 358.144096 -238.55557)
			(xy 358.091998 -238.547186) (xy 358.041894 -238.53063) (xy 357.995058 -238.506323) (xy 357.952678 -238.474882)
			(xy 357.915833 -238.437108) (xy 357.900224 -238.41583) (xy 357.500936 -238.41583) (xy 357.485327 -238.437108)
			(xy 357.448482 -238.474882) (xy 357.406102 -238.506323) (xy 357.359266 -238.53063) (xy 357.309162 -238.547186)
			(xy 357.257064 -238.55557) (xy 357.204296 -238.55557) (xy 357.152198 -238.547186) (xy 357.102094 -238.53063)
			(xy 357.055258 -238.506323) (xy 357.012878 -238.474882) (xy 356.976033 -238.437108) (xy 356.960424 -238.41583)
			(xy 352.033078 -238.41583) (xy 351.613978 -238.83493) (xy 351.613978 -239.013238) (xy 351.634782 -239.023938)
			(xy 351.673412 -239.050322) (xy 351.69094 -239.065816) (xy 351.701902 -239.075202) (xy 351.72776 -239.08798)
			(xy 351.756164 -239.092998) (xy 351.784836 -239.089851) (xy 351.811476 -239.078792) (xy 351.82302 -239.070134)
			(xy 351.834704 -239.059974) (xy 351.852843 -239.044767) (xy 351.892646 -239.019154) (xy 351.935692 -238.999472)
			(xy 351.981104 -238.986125) (xy 352.027954 -238.979384) (xy 352.05162 -238.978948) (xy 352.06432 -238.979202)
			(xy 352.071178 -238.979456) (xy 352.097411 -238.981523) (xy 352.148781 -238.992923) (xy 352.197695 -239.012317)
			(xy 352.242919 -239.039217) (xy 352.28331 -239.072942) (xy 352.317847 -239.11264) (xy 352.345658 -239.157309)
			(xy 352.366041 -239.20582) (xy 352.37848 -239.256947) (xy 352.382662 -239.3094) (xy 352.381928 -239.318605)
			(xy 352.789491 -239.318605) (xy 352.789491 -239.266671) (xy 352.797616 -239.215376) (xy 352.813664 -239.165983)
			(xy 352.837242 -239.119709) (xy 352.867768 -239.077693) (xy 352.904491 -239.04097) (xy 352.946507 -239.010444)
			(xy 352.992781 -238.986866) (xy 353.042174 -238.970818) (xy 353.093469 -238.962693) (xy 353.145403 -238.962693)
			(xy 353.196698 -238.970818) (xy 353.246091 -238.986866) (xy 353.292365 -239.010444) (xy 353.334381 -239.04097)
			(xy 353.358778 -239.065367) (xy 361.129835 -239.065367) (xy 361.129835 -239.013433) (xy 361.13796 -238.962138)
			(xy 361.154008 -238.912745) (xy 361.177586 -238.866471) (xy 361.208112 -238.824455) (xy 361.244835 -238.787732)
			(xy 361.286851 -238.757206) (xy 361.333125 -238.733628) (xy 361.382518 -238.71758) (xy 361.433813 -238.709455)
			(xy 361.485747 -238.709455) (xy 361.537042 -238.71758) (xy 361.586435 -238.733628) (xy 361.632709 -238.757206)
			(xy 361.674725 -238.787732) (xy 361.711448 -238.824455) (xy 361.741974 -238.866471) (xy 361.765552 -238.912745)
			(xy 361.7816 -238.962138) (xy 361.789725 -239.013433) (xy 361.790234 -239.0394) (xy 361.789725 -239.065367)
			(xy 361.7816 -239.116662) (xy 361.765552 -239.166055) (xy 361.741974 -239.212329) (xy 361.711448 -239.254345)
			(xy 361.674725 -239.291068) (xy 361.632709 -239.321594) (xy 361.586435 -239.345172) (xy 361.537042 -239.36122)
			(xy 361.485747 -239.369345) (xy 361.433813 -239.369345) (xy 361.382518 -239.36122) (xy 361.333125 -239.345172)
			(xy 361.286851 -239.321594) (xy 361.244835 -239.291068) (xy 361.208112 -239.254345) (xy 361.177586 -239.212329)
			(xy 361.154008 -239.166055) (xy 361.13796 -239.116662) (xy 361.129835 -239.065367) (xy 353.358778 -239.065367)
			(xy 353.371104 -239.077693) (xy 353.40163 -239.119709) (xy 353.425208 -239.165983) (xy 353.441256 -239.215376)
			(xy 353.449381 -239.266671) (xy 353.44989 -239.292638) (xy 353.449381 -239.318605) (xy 353.441256 -239.3699)
			(xy 353.425208 -239.419293) (xy 353.40163 -239.465567) (xy 353.371104 -239.507583) (xy 353.334381 -239.544306)
			(xy 353.292365 -239.574832) (xy 353.246091 -239.59841) (xy 353.196698 -239.614458) (xy 353.145403 -239.622583)
			(xy 353.093469 -239.622583) (xy 353.042174 -239.614458) (xy 352.992781 -239.59841) (xy 352.946507 -239.574832)
			(xy 352.904491 -239.544306) (xy 352.867768 -239.507583) (xy 352.837242 -239.465567) (xy 352.813664 -239.419293)
			(xy 352.797616 -239.3699) (xy 352.789491 -239.318605) (xy 352.381928 -239.318605) (xy 352.37848 -239.361853)
			(xy 352.366041 -239.41298) (xy 352.345658 -239.461491) (xy 352.317847 -239.50616) (xy 352.283309 -239.545859)
			(xy 352.242919 -239.579583) (xy 352.197695 -239.606483) (xy 352.14878 -239.625877) (xy 352.097411 -239.637277)
			(xy 352.071178 -239.639348) (xy 352.06432 -239.639602) (xy 352.05162 -239.639856) (xy 352.02795 -239.639471)
			(xy 351.981089 -239.632751) (xy 351.93567 -239.619403) (xy 351.892625 -239.599701) (xy 351.852837 -239.57405)
			(xy 351.834704 -239.55883) (xy 351.82302 -239.54867) (xy 351.811466 -239.54003) (xy 351.784829 -239.528983)
			(xy 351.756165 -239.52584) (xy 351.727767 -239.530852) (xy 351.70191 -239.543617) (xy 351.69094 -239.552988)
			(xy 351.673406 -239.568475) (xy 351.634781 -239.594865) (xy 351.613978 -239.605566) (xy 351.613978 -239.879183)
			(xy 357.840789 -239.879183) (xy 357.840789 -239.827249) (xy 357.848914 -239.775954) (xy 357.864962 -239.726561)
			(xy 357.88854 -239.680287) (xy 357.919066 -239.638271) (xy 357.955789 -239.601548) (xy 357.997805 -239.571022)
			(xy 358.044079 -239.547444) (xy 358.093472 -239.531396) (xy 358.144767 -239.523271) (xy 358.196701 -239.523271)
			(xy 358.247996 -239.531396) (xy 358.297389 -239.547444) (xy 358.343663 -239.571022) (xy 358.385679 -239.601548)
			(xy 358.422402 -239.638271) (xy 358.452928 -239.680287) (xy 358.476506 -239.726561) (xy 358.492554 -239.775954)
			(xy 358.500679 -239.827249) (xy 358.501188 -239.853216) (xy 358.500679 -239.879183) (xy 358.492554 -239.930478)
			(xy 358.476506 -239.979871) (xy 358.452928 -240.026145) (xy 358.422402 -240.068161) (xy 358.385679 -240.104884)
			(xy 358.343663 -240.13541) (xy 358.297389 -240.158988) (xy 358.247996 -240.175036) (xy 358.196701 -240.183161)
			(xy 358.144767 -240.183161) (xy 358.093472 -240.175036) (xy 358.044079 -240.158988) (xy 357.997805 -240.13541)
			(xy 357.955789 -240.104884) (xy 357.919066 -240.068161) (xy 357.88854 -240.026145) (xy 357.864962 -239.979871)
			(xy 357.848914 -239.930478) (xy 357.840789 -239.879183) (xy 351.613978 -239.879183) (xy 351.613978 -241.172492)
			(xy 356.03561 -241.172492) (xy 356.036065 -241.14794) (xy 356.0433 -241.099374) (xy 356.05764 -241.052412)
			(xy 356.078769 -241.008087) (xy 356.106222 -240.967376) (xy 356.122478 -240.948972) (xy 356.132289 -240.937489)
			(xy 356.145302 -240.91025) (xy 356.149768 -240.880394) (xy 356.145298 -240.850539) (xy 356.132282 -240.823301)
			(xy 356.122478 -240.811812) (xy 356.106199 -240.793425) (xy 356.078735 -240.752715) (xy 356.057601 -240.708388)
			(xy 356.043263 -240.66142) (xy 356.036037 -240.612846) (xy 356.03561 -240.588292) (xy 356.036119 -240.562325)
			(xy 356.044244 -240.51103) (xy 356.060292 -240.461637) (xy 356.08387 -240.415363) (xy 356.114396 -240.373347)
			(xy 356.151119 -240.336624) (xy 356.193135 -240.306098) (xy 356.239409 -240.28252) (xy 356.288802 -240.266472)
			(xy 356.340097 -240.258347) (xy 356.392031 -240.258347) (xy 356.443326 -240.266472) (xy 356.492719 -240.28252)
			(xy 356.538993 -240.306098) (xy 356.581009 -240.336624) (xy 356.617732 -240.373347) (xy 356.648258 -240.415363)
			(xy 356.671836 -240.461637) (xy 356.687884 -240.51103) (xy 356.696009 -240.562325) (xy 356.696518 -240.588292)
			(xy 356.696106 -240.612845) (xy 356.688859 -240.661413) (xy 356.67913 -240.693253) (xy 361.130089 -240.693253)
			(xy 361.130089 -240.641319) (xy 361.138214 -240.590024) (xy 361.154262 -240.540631) (xy 361.17784 -240.494357)
			(xy 361.208366 -240.452341) (xy 361.245089 -240.415618) (xy 361.287105 -240.385092) (xy 361.333379 -240.361514)
			(xy 361.382772 -240.345466) (xy 361.434067 -240.337341) (xy 361.486001 -240.337341) (xy 361.537296 -240.345466)
			(xy 361.586689 -240.361514) (xy 361.632963 -240.385092) (xy 361.674979 -240.415618) (xy 361.711702 -240.452341)
			(xy 361.742228 -240.494357) (xy 361.765806 -240.540631) (xy 361.781854 -240.590024) (xy 361.789979 -240.641319)
			(xy 361.790488 -240.667286) (xy 361.789979 -240.693253) (xy 361.781854 -240.744548) (xy 361.765806 -240.793941)
			(xy 361.742228 -240.840215) (xy 361.711702 -240.882231) (xy 361.674979 -240.918954) (xy 361.632963 -240.94948)
			(xy 361.586689 -240.973058) (xy 361.537296 -240.989106) (xy 361.486001 -240.997231) (xy 361.434067 -240.997231)
			(xy 361.382772 -240.989106) (xy 361.333379 -240.973058) (xy 361.287105 -240.94948) (xy 361.245089 -240.918954)
			(xy 361.208366 -240.882231) (xy 361.17784 -240.840215) (xy 361.154262 -240.793941) (xy 361.138214 -240.744548)
			(xy 361.130089 -240.693253) (xy 356.67913 -240.693253) (xy 356.674509 -240.708376) (xy 356.653371 -240.752699)
			(xy 356.62591 -240.793409) (xy 356.60965 -240.811812) (xy 356.599852 -240.823306) (xy 356.586834 -240.850541)
			(xy 356.582363 -240.880394) (xy 356.586831 -240.910248) (xy 356.599846 -240.937484) (xy 356.60965 -240.948972)
			(xy 356.625909 -240.967376) (xy 356.653379 -241.00808) (xy 356.674518 -241.052403) (xy 356.688861 -241.099368)
			(xy 356.69609 -241.147939) (xy 356.696518 -241.172492) (xy 356.696009 -241.198459) (xy 356.687884 -241.249754)
			(xy 356.671836 -241.299147) (xy 356.648258 -241.345421) (xy 356.617732 -241.387437) (xy 356.581009 -241.42416)
			(xy 356.538993 -241.454686) (xy 356.492719 -241.478264) (xy 356.443326 -241.494312) (xy 356.392031 -241.502437)
			(xy 356.340097 -241.502437) (xy 356.288802 -241.494312) (xy 356.239409 -241.478264) (xy 356.193135 -241.454686)
			(xy 356.151119 -241.42416) (xy 356.114396 -241.387437) (xy 356.08387 -241.345421) (xy 356.060292 -241.299147)
			(xy 356.044244 -241.249754) (xy 356.036119 -241.198459) (xy 356.03561 -241.172492) (xy 351.613978 -241.172492)
			(xy 351.613978 -241.507069) (xy 357.840789 -241.507069) (xy 357.840789 -241.455135) (xy 357.848914 -241.40384)
			(xy 357.864962 -241.354447) (xy 357.88854 -241.308173) (xy 357.919066 -241.266157) (xy 357.955789 -241.229434)
			(xy 357.997805 -241.198908) (xy 358.044079 -241.17533) (xy 358.093472 -241.159282) (xy 358.144767 -241.151157)
			(xy 358.196701 -241.151157) (xy 358.247996 -241.159282) (xy 358.297389 -241.17533) (xy 358.343663 -241.198908)
			(xy 358.385679 -241.229434) (xy 358.422402 -241.266157) (xy 358.452928 -241.308173) (xy 358.476506 -241.354447)
			(xy 358.492554 -241.40384) (xy 358.500679 -241.455135) (xy 358.501188 -241.481102) (xy 358.500679 -241.507069)
			(xy 358.492554 -241.558364) (xy 358.476506 -241.607757) (xy 358.452928 -241.654031) (xy 358.444776 -241.665252)
			(xy 363.032802 -241.665252) (xy 363.033235 -241.6407) (xy 363.040476 -241.592132) (xy 363.054821 -241.54517)
			(xy 363.075955 -241.500846) (xy 363.103412 -241.460135) (xy 363.11967 -241.441732) (xy 363.129521 -241.43028)
			(xy 363.14253 -241.40303) (xy 363.14699 -241.373164) (xy 363.142509 -241.343302) (xy 363.129481 -241.316061)
			(xy 363.11967 -241.304572) (xy 363.103419 -241.286162) (xy 363.07595 -241.245458) (xy 363.054811 -241.201137)
			(xy 363.040467 -241.154174) (xy 363.033233 -241.105605) (xy 363.032802 -241.081052) (xy 363.033311 -241.055085)
			(xy 363.041436 -241.00379) (xy 363.057484 -240.954397) (xy 363.081062 -240.908123) (xy 363.111588 -240.866107)
			(xy 363.148311 -240.829384) (xy 363.190327 -240.798858) (xy 363.236601 -240.77528) (xy 363.285994 -240.759232)
			(xy 363.337289 -240.751107) (xy 363.389223 -240.751107) (xy 363.440518 -240.759232) (xy 363.489911 -240.77528)
			(xy 363.536185 -240.798858) (xy 363.578201 -240.829384) (xy 363.614924 -240.866107) (xy 363.64545 -240.908123)
			(xy 363.669028 -240.954397) (xy 363.685076 -241.00379) (xy 363.693201 -241.055085) (xy 363.69371 -241.081052)
			(xy 363.693276 -241.105604) (xy 363.686035 -241.154172) (xy 363.67169 -241.201134) (xy 363.650557 -241.245458)
			(xy 363.6231 -241.286168) (xy 363.606842 -241.304572) (xy 363.597084 -241.316097) (xy 363.584063 -241.343321)
			(xy 363.579584 -241.373164) (xy 363.584042 -241.403011) (xy 363.597044 -241.430244) (xy 363.606842 -241.441732)
			(xy 363.623081 -241.460153) (xy 363.650554 -241.500852) (xy 363.671697 -241.545171) (xy 363.686044 -241.592132)
			(xy 363.693279 -241.6407) (xy 363.69371 -241.665252) (xy 363.693201 -241.691219) (xy 363.685076 -241.742514)
			(xy 363.669028 -241.791907) (xy 363.64545 -241.838181) (xy 363.614924 -241.880197) (xy 363.578201 -241.91692)
			(xy 363.536185 -241.947446) (xy 363.489911 -241.971024) (xy 363.440518 -241.987072) (xy 363.389223 -241.995197)
			(xy 363.337289 -241.995197) (xy 363.285994 -241.987072) (xy 363.236601 -241.971024) (xy 363.190327 -241.947446)
			(xy 363.148311 -241.91692) (xy 363.111588 -241.880197) (xy 363.081062 -241.838181) (xy 363.057484 -241.791907)
			(xy 363.041436 -241.742514) (xy 363.033311 -241.691219) (xy 363.032802 -241.665252) (xy 358.444776 -241.665252)
			(xy 358.422402 -241.696047) (xy 358.385679 -241.73277) (xy 358.343663 -241.763296) (xy 358.297389 -241.786874)
			(xy 358.247996 -241.802922) (xy 358.196701 -241.811047) (xy 358.144767 -241.811047) (xy 358.093472 -241.802922)
			(xy 358.044079 -241.786874) (xy 357.997805 -241.763296) (xy 357.955789 -241.73277) (xy 357.919066 -241.696047)
			(xy 357.88854 -241.654031) (xy 357.864962 -241.607757) (xy 357.848914 -241.558364) (xy 357.840789 -241.507069)
			(xy 351.613978 -241.507069) (xy 351.613978 -242.320885) (xy 361.130089 -242.320885) (xy 361.130089 -242.268951)
			(xy 361.138214 -242.217656) (xy 361.154262 -242.168263) (xy 361.17784 -242.121989) (xy 361.208366 -242.079973)
			(xy 361.245089 -242.04325) (xy 361.287105 -242.012724) (xy 361.333379 -241.989146) (xy 361.382772 -241.973098)
			(xy 361.434067 -241.964973) (xy 361.486001 -241.964973) (xy 361.537296 -241.973098) (xy 361.586689 -241.989146)
			(xy 361.632963 -242.012724) (xy 361.674979 -242.04325) (xy 361.711702 -242.079973) (xy 361.742228 -242.121989)
			(xy 361.765806 -242.168263) (xy 361.781854 -242.217656) (xy 361.789979 -242.268951) (xy 361.790488 -242.294918)
			(xy 361.789979 -242.320885) (xy 361.781854 -242.37218) (xy 361.765806 -242.421573) (xy 361.742228 -242.467847)
			(xy 361.711702 -242.509863) (xy 361.674979 -242.546586) (xy 361.632963 -242.577112) (xy 361.586689 -242.60069)
			(xy 361.537296 -242.616738) (xy 361.486001 -242.624863) (xy 361.434067 -242.624863) (xy 361.382772 -242.616738)
			(xy 361.333379 -242.60069) (xy 361.287105 -242.577112) (xy 361.245089 -242.546586) (xy 361.208366 -242.509863)
			(xy 361.17784 -242.467847) (xy 361.154262 -242.421573) (xy 361.138214 -242.37218) (xy 361.130089 -242.320885)
			(xy 351.613978 -242.320885) (xy 351.613978 -243.134955) (xy 357.840789 -243.134955) (xy 357.840789 -243.083021)
			(xy 357.848914 -243.031726) (xy 357.864962 -242.982333) (xy 357.88854 -242.936059) (xy 357.919066 -242.894043)
			(xy 357.955789 -242.85732) (xy 357.997805 -242.826794) (xy 358.044079 -242.803216) (xy 358.093472 -242.787168)
			(xy 358.144767 -242.779043) (xy 358.196701 -242.779043) (xy 358.247996 -242.787168) (xy 358.297389 -242.803216)
			(xy 358.343663 -242.826794) (xy 358.385679 -242.85732) (xy 358.422402 -242.894043) (xy 358.452928 -242.936059)
			(xy 358.476506 -242.982333) (xy 358.47798 -242.986869) (xy 365.433835 -242.986869) (xy 365.433835 -242.934931)
			(xy 365.44196 -242.883632) (xy 365.45801 -242.834235) (xy 365.48159 -242.787958) (xy 365.51212 -242.745939)
			(xy 365.548846 -242.709213) (xy 365.590866 -242.678685) (xy 365.637144 -242.655106) (xy 365.686541 -242.639058)
			(xy 365.737841 -242.630934) (xy 365.76381 -242.630452) (xy 365.789671 -242.630958) (xy 365.840762 -242.639005)
			(xy 365.889975 -242.654916) (xy 365.936106 -242.678303) (xy 365.978029 -242.708593) (xy 365.996728 -242.726464)
			(xy 366.006443 -242.735509) (xy 366.029452 -242.748721) (xy 366.055089 -242.755558) (xy 366.081623 -242.755558)
			(xy 366.10726 -242.748721) (xy 366.130269 -242.735509) (xy 366.139984 -242.726464) (xy 366.158664 -242.708574)
			(xy 366.200598 -242.678296) (xy 366.246735 -242.654916) (xy 366.295949 -242.639006) (xy 366.347041 -242.630952)
			(xy 366.372902 -242.630452) (xy 366.39887 -242.630949) (xy 366.450165 -242.639074) (xy 366.499559 -242.655123)
			(xy 366.545833 -242.678702) (xy 366.587849 -242.709228) (xy 366.624573 -242.745952) (xy 366.6551 -242.787969)
			(xy 366.678678 -242.834243) (xy 366.694726 -242.883637) (xy 366.702851 -242.934932) (xy 366.702851 -242.986868)
			(xy 366.694726 -243.038163) (xy 366.678678 -243.087557) (xy 366.6551 -243.133831) (xy 366.624573 -243.175848)
			(xy 366.587849 -243.212572) (xy 366.545833 -243.243098) (xy 366.499559 -243.266677) (xy 366.450165 -243.282726)
			(xy 366.39887 -243.290851) (xy 366.372902 -243.29136) (xy 366.347042 -243.290843) (xy 366.295951 -243.282798)
			(xy 366.246739 -243.26689) (xy 366.200607 -243.243506) (xy 366.158683 -243.213218) (xy 366.139984 -243.195348)
			(xy 366.130269 -243.186303) (xy 366.10726 -243.173091) (xy 366.081623 -243.166254) (xy 366.055089 -243.166254)
			(xy 366.029452 -243.173091) (xy 366.006443 -243.186303) (xy 365.996728 -243.195348) (xy 365.978028 -243.213217)
			(xy 365.936101 -243.243502) (xy 365.88997 -243.266887) (xy 365.840759 -243.282802) (xy 365.78967 -243.290859)
			(xy 365.76381 -243.29136) (xy 365.737841 -243.290866) (xy 365.686541 -243.282742) (xy 365.637144 -243.266694)
			(xy 365.590866 -243.243115) (xy 365.548846 -243.212587) (xy 365.51212 -243.175861) (xy 365.48159 -243.133842)
			(xy 365.45801 -243.087565) (xy 365.44196 -243.038168) (xy 365.433835 -242.986869) (xy 358.47798 -242.986869)
			(xy 358.492554 -243.031726) (xy 358.500679 -243.083021) (xy 358.501188 -243.108988) (xy 358.500679 -243.134955)
			(xy 358.492554 -243.18625) (xy 358.476506 -243.235643) (xy 358.452928 -243.281917) (xy 358.422402 -243.323933)
			(xy 358.385679 -243.360656) (xy 358.343663 -243.391182) (xy 358.297389 -243.41476) (xy 358.247996 -243.430808)
			(xy 358.196701 -243.438933) (xy 358.144767 -243.438933) (xy 358.093472 -243.430808) (xy 358.044079 -243.41476)
			(xy 357.997805 -243.391182) (xy 357.955789 -243.360656) (xy 357.919066 -243.323933) (xy 357.88854 -243.281917)
			(xy 357.864962 -243.235643) (xy 357.848914 -243.18625) (xy 357.840789 -243.134955) (xy 351.613978 -243.134955)
			(xy 351.613978 -243.41455) (xy 352.148199 -243.948771) (xy 361.130089 -243.948771) (xy 361.130089 -243.896837)
			(xy 361.138214 -243.845542) (xy 361.154262 -243.796149) (xy 361.17784 -243.749875) (xy 361.208366 -243.707859)
			(xy 361.245089 -243.671136) (xy 361.287105 -243.64061) (xy 361.333379 -243.617032) (xy 361.382772 -243.600984)
			(xy 361.434067 -243.592859) (xy 361.486001 -243.592859) (xy 361.537296 -243.600984) (xy 361.586689 -243.617032)
			(xy 361.632963 -243.64061) (xy 361.674979 -243.671136) (xy 361.711702 -243.707859) (xy 361.742228 -243.749875)
			(xy 361.765806 -243.796149) (xy 361.781854 -243.845542) (xy 361.789979 -243.896837) (xy 361.790488 -243.922804)
			(xy 361.789979 -243.948771) (xy 361.781854 -244.000066) (xy 361.765806 -244.049459) (xy 361.742228 -244.095733)
			(xy 361.711702 -244.137749) (xy 361.674979 -244.174472) (xy 361.632963 -244.204998) (xy 361.586689 -244.228576)
			(xy 361.537296 -244.244624) (xy 361.486001 -244.252749) (xy 361.434067 -244.252749) (xy 361.382772 -244.244624)
			(xy 361.333379 -244.228576) (xy 361.287105 -244.204998) (xy 361.245089 -244.174472) (xy 361.208366 -244.137749)
			(xy 361.17784 -244.095733) (xy 361.154262 -244.049459) (xy 361.138214 -244.000066) (xy 361.130089 -243.948771)
			(xy 352.148199 -243.948771) (xy 353.158298 -244.95887) (xy 353.158298 -245.347236) (xy 356.04323 -245.347236)
			(xy 356.043672 -245.322684) (xy 356.050914 -245.274118) (xy 356.065258 -245.227156) (xy 356.086389 -245.182832)
			(xy 356.113842 -245.142121) (xy 356.130098 -245.123716) (xy 356.139864 -245.112198) (xy 356.152879 -245.084971)
			(xy 356.157353 -245.055127) (xy 356.152895 -245.02528) (xy 356.139894 -244.998046) (xy 356.130098 -244.986556)
			(xy 356.113843 -244.968148) (xy 356.086375 -244.927445) (xy 356.065236 -244.883122) (xy 356.050892 -244.836159)
			(xy 356.04366 -244.787589) (xy 356.04323 -244.763036) (xy 356.043739 -244.737069) (xy 356.051864 -244.685774)
			(xy 356.067912 -244.636381) (xy 356.09149 -244.590107) (xy 356.122016 -244.548091) (xy 356.158739 -244.511368)
			(xy 356.200755 -244.480842) (xy 356.247029 -244.457264) (xy 356.296422 -244.441216) (xy 356.347717 -244.433091)
			(xy 356.399651 -244.433091) (xy 356.450946 -244.441216) (xy 356.500339 -244.457264) (xy 356.546613 -244.480842)
			(xy 356.588629 -244.511368) (xy 356.625352 -244.548091) (xy 356.655878 -244.590107) (xy 356.679456 -244.636381)
			(xy 356.695504 -244.685774) (xy 356.703629 -244.737069) (xy 356.704129 -244.762587) (xy 357.840789 -244.762587)
			(xy 357.840789 -244.710653) (xy 357.848914 -244.659358) (xy 357.864962 -244.609965) (xy 357.88854 -244.563691)
			(xy 357.919066 -244.521675) (xy 357.955789 -244.484952) (xy 357.997805 -244.454426) (xy 358.044079 -244.430848)
			(xy 358.093472 -244.4148) (xy 358.144767 -244.406675) (xy 358.196701 -244.406675) (xy 358.247996 -244.4148)
			(xy 358.297389 -244.430848) (xy 358.343663 -244.454426) (xy 358.385679 -244.484952) (xy 358.422402 -244.521675)
			(xy 358.452928 -244.563691) (xy 358.476506 -244.609965) (xy 358.492554 -244.659358) (xy 358.500679 -244.710653)
			(xy 358.501188 -244.73662) (xy 358.500679 -244.762587) (xy 358.492554 -244.813882) (xy 358.476506 -244.863275)
			(xy 358.452928 -244.909549) (xy 358.422402 -244.951565) (xy 358.385679 -244.988288) (xy 358.343663 -245.018814)
			(xy 358.297389 -245.042392) (xy 358.247996 -245.05844) (xy 358.196701 -245.066565) (xy 358.144767 -245.066565)
			(xy 358.093472 -245.05844) (xy 358.044079 -245.042392) (xy 357.997805 -245.018814) (xy 357.955789 -244.988288)
			(xy 357.919066 -244.951565) (xy 357.88854 -244.909549) (xy 357.864962 -244.863275) (xy 357.848914 -244.813882)
			(xy 357.840789 -244.762587) (xy 356.704129 -244.762587) (xy 356.704138 -244.763036) (xy 356.703687 -244.787588)
			(xy 356.696449 -244.836154) (xy 356.682108 -244.883116) (xy 356.660978 -244.92744) (xy 356.633526 -244.968151)
			(xy 356.61727 -244.986556) (xy 356.607428 -244.998016) (xy 356.594412 -245.025263) (xy 356.589948 -245.055127)
			(xy 356.594428 -245.084988) (xy 356.607457 -245.112228) (xy 356.61727 -245.123716) (xy 356.633553 -245.142099)
			(xy 356.661019 -245.182809) (xy 356.682153 -245.227137) (xy 356.69649 -245.274107) (xy 356.703713 -245.322681)
			(xy 356.704138 -245.347236) (xy 356.703629 -245.373203) (xy 356.695504 -245.424498) (xy 356.679456 -245.473891)
			(xy 356.655878 -245.520165) (xy 356.625352 -245.562181) (xy 356.610876 -245.576657) (xy 361.130089 -245.576657)
			(xy 361.130089 -245.524723) (xy 361.138214 -245.473428) (xy 361.154262 -245.424035) (xy 361.17784 -245.377761)
			(xy 361.208366 -245.335745) (xy 361.245089 -245.299022) (xy 361.287105 -245.268496) (xy 361.333379 -245.244918)
			(xy 361.382772 -245.22887) (xy 361.434067 -245.220745) (xy 361.486001 -245.220745) (xy 361.537296 -245.22887)
			(xy 361.586689 -245.244918) (xy 361.632963 -245.268496) (xy 361.674979 -245.299022) (xy 361.711702 -245.335745)
			(xy 361.742228 -245.377761) (xy 361.751782 -245.396512) (xy 363.025182 -245.396512) (xy 363.025596 -245.371959)
			(xy 363.032842 -245.323391) (xy 363.047192 -245.276428) (xy 363.06833 -245.232105) (xy 363.095791 -245.191395)
			(xy 363.11205 -245.172992) (xy 363.121844 -245.161495) (xy 363.134862 -245.134261) (xy 363.139334 -245.104409)
			(xy 363.134867 -245.074556) (xy 363.121854 -245.04732) (xy 363.11205 -245.035832) (xy 363.095793 -245.017427)
			(xy 363.068322 -244.976723) (xy 363.047183 -244.932401) (xy 363.03284 -244.885436) (xy 363.02561 -244.836865)
			(xy 363.025182 -244.812312) (xy 363.025691 -244.786345) (xy 363.033816 -244.73505) (xy 363.049864 -244.685657)
			(xy 363.073442 -244.639383) (xy 363.103968 -244.597367) (xy 363.140691 -244.560644) (xy 363.182707 -244.530118)
			(xy 363.228981 -244.50654) (xy 363.278374 -244.490492) (xy 363.329669 -244.482367) (xy 363.381603 -244.482367)
			(xy 363.432898 -244.490492) (xy 363.482291 -244.50654) (xy 363.528565 -244.530118) (xy 363.570581 -244.560644)
			(xy 363.607304 -244.597367) (xy 363.63783 -244.639383) (xy 363.661408 -244.685657) (xy 363.677456 -244.73505)
			(xy 363.685581 -244.786345) (xy 363.68609 -244.812312) (xy 363.685637 -244.836864) (xy 363.678402 -244.88543)
			(xy 363.664061 -244.932393) (xy 363.642932 -244.976717) (xy 363.615478 -245.017428) (xy 363.599222 -245.035832)
			(xy 363.589407 -245.047312) (xy 363.576395 -245.074552) (xy 363.571929 -245.104409) (xy 363.5764 -245.134265)
			(xy 363.589417 -245.161503) (xy 363.599222 -245.172992) (xy 363.615503 -245.191378) (xy 363.642967 -245.232088)
			(xy 363.664101 -245.276415) (xy 363.678438 -245.323384) (xy 363.685664 -245.371958) (xy 363.68609 -245.396512)
			(xy 363.685581 -245.422479) (xy 363.677456 -245.473774) (xy 363.661408 -245.523167) (xy 363.63783 -245.569441)
			(xy 363.607304 -245.611457) (xy 363.570581 -245.64818) (xy 363.528565 -245.678706) (xy 363.482291 -245.702284)
			(xy 363.432898 -245.718332) (xy 363.381603 -245.726457) (xy 363.329669 -245.726457) (xy 363.278374 -245.718332)
			(xy 363.228981 -245.702284) (xy 363.182707 -245.678706) (xy 363.140691 -245.64818) (xy 363.103968 -245.611457)
			(xy 363.073442 -245.569441) (xy 363.049864 -245.523167) (xy 363.033816 -245.473774) (xy 363.025691 -245.422479)
			(xy 363.025182 -245.396512) (xy 361.751782 -245.396512) (xy 361.765806 -245.424035) (xy 361.781854 -245.473428)
			(xy 361.789979 -245.524723) (xy 361.790488 -245.55069) (xy 361.789979 -245.576657) (xy 361.781854 -245.627952)
			(xy 361.765806 -245.677345) (xy 361.742228 -245.723619) (xy 361.711702 -245.765635) (xy 361.674979 -245.802358)
			(xy 361.632963 -245.832884) (xy 361.586689 -245.856462) (xy 361.537296 -245.87251) (xy 361.486001 -245.880635)
			(xy 361.434067 -245.880635) (xy 361.382772 -245.87251) (xy 361.333379 -245.856462) (xy 361.287105 -245.832884)
			(xy 361.245089 -245.802358) (xy 361.208366 -245.765635) (xy 361.17784 -245.723619) (xy 361.154262 -245.677345)
			(xy 361.138214 -245.627952) (xy 361.130089 -245.576657) (xy 356.610876 -245.576657) (xy 356.588629 -245.598904)
			(xy 356.546613 -245.62943) (xy 356.500339 -245.653008) (xy 356.450946 -245.669056) (xy 356.399651 -245.677181)
			(xy 356.347717 -245.677181) (xy 356.296422 -245.669056) (xy 356.247029 -245.653008) (xy 356.200755 -245.62943)
			(xy 356.158739 -245.598904) (xy 356.122016 -245.562181) (xy 356.09149 -245.520165) (xy 356.067912 -245.473891)
			(xy 356.051864 -245.424498) (xy 356.043739 -245.373203) (xy 356.04323 -245.347236) (xy 353.158298 -245.347236)
			(xy 353.158298 -246.28856) (xy 353.158727 -246.298221) (xy 353.165883 -246.316171) (xy 353.179161 -246.330209)
			(xy 353.196684 -246.338353) (xy 353.206304 -246.33936) (xy 353.235154 -246.341541) (xy 353.291486 -246.354712)
			(xy 353.344667 -246.377485) (xy 353.393074 -246.409164) (xy 353.414584 -246.428514) (xy 353.426014 -246.438928)
			(xy 353.437873 -246.448339) (xy 353.465619 -246.460408) (xy 353.495683 -246.463832) (xy 353.525433 -246.458311)
			(xy 353.552267 -246.444329) (xy 353.563428 -246.434102) (xy 353.582103 -246.416361) (xy 353.62393 -246.386304)
			(xy 353.669916 -246.363104) (xy 353.718946 -246.347322) (xy 353.76983 -246.339341) (xy 353.795584 -246.338852)
			(xy 353.821554 -246.339334) (xy 353.872854 -246.347456) (xy 353.922252 -246.363505) (xy 353.968531 -246.387083)
			(xy 353.973197 -246.390473) (xy 357.840789 -246.390473) (xy 357.840789 -246.338539) (xy 357.848914 -246.287244)
			(xy 357.864962 -246.237851) (xy 357.88854 -246.191577) (xy 357.919066 -246.149561) (xy 357.955789 -246.112838)
			(xy 357.997805 -246.082312) (xy 358.044079 -246.058734) (xy 358.093472 -246.042686) (xy 358.144767 -246.034561)
			(xy 358.196701 -246.034561) (xy 358.247996 -246.042686) (xy 358.297389 -246.058734) (xy 358.343663 -246.082312)
			(xy 358.385679 -246.112838) (xy 358.422402 -246.149561) (xy 358.452928 -246.191577) (xy 358.476506 -246.237851)
			(xy 358.492554 -246.287244) (xy 358.500679 -246.338539) (xy 358.501188 -246.364506) (xy 358.500679 -246.390473)
			(xy 358.492554 -246.441768) (xy 358.476506 -246.491161) (xy 358.452928 -246.537435) (xy 358.422402 -246.579451)
			(xy 358.385679 -246.616174) (xy 358.343663 -246.6467) (xy 358.297389 -246.670278) (xy 358.247996 -246.686326)
			(xy 358.196701 -246.694451) (xy 358.144767 -246.694451) (xy 358.093472 -246.686326) (xy 358.044079 -246.670278)
			(xy 357.997805 -246.6467) (xy 357.955789 -246.616174) (xy 357.919066 -246.579451) (xy 357.88854 -246.537435)
			(xy 357.864962 -246.491161) (xy 357.848914 -246.441768) (xy 357.840789 -246.390473) (xy 353.973197 -246.390473)
			(xy 354.010551 -246.417611) (xy 354.047279 -246.454337) (xy 354.077809 -246.496356) (xy 354.101389 -246.542634)
			(xy 354.11744 -246.592031) (xy 354.125565 -246.64333) (xy 354.125565 -246.69527) (xy 354.11744 -246.746569)
			(xy 354.101389 -246.795966) (xy 354.077809 -246.842244) (xy 354.047279 -246.884263) (xy 354.010551 -246.920989)
			(xy 353.968531 -246.951517) (xy 353.922252 -246.975095) (xy 353.872854 -246.991144) (xy 353.821554 -246.999266)
			(xy 353.795584 -246.99976) (xy 353.769831 -246.999267) (xy 353.718948 -246.991278) (xy 353.669919 -246.975496)
			(xy 353.62393 -246.952303) (xy 353.582094 -246.922259) (xy 353.563428 -246.90451) (xy 353.552267 -246.894276)
			(xy 353.525439 -246.880266) (xy 353.495683 -246.874734) (xy 353.465612 -246.878166) (xy 353.437867 -246.89026)
			(xy 353.426014 -246.899684) (xy 353.414584 -246.910098) (xy 353.393097 -246.929477) (xy 353.344686 -246.961162)
			(xy 353.291499 -246.983934) (xy 353.235158 -246.997098) (xy 353.206304 -246.999252) (xy 353.196664 -247.000191)
			(xy 353.179099 -247.008318) (xy 353.165804 -247.022381) (xy 353.158677 -247.040374) (xy 353.158298 -247.050052)
			(xy 353.158298 -247.204289) (xy 361.130089 -247.204289) (xy 361.130089 -247.152355) (xy 361.138214 -247.10106)
			(xy 361.154262 -247.051667) (xy 361.17784 -247.005393) (xy 361.208366 -246.963377) (xy 361.245089 -246.926654)
			(xy 361.287105 -246.896128) (xy 361.333379 -246.87255) (xy 361.382772 -246.856502) (xy 361.434067 -246.848377)
			(xy 361.486001 -246.848377) (xy 361.537296 -246.856502) (xy 361.586689 -246.87255) (xy 361.632963 -246.896128)
			(xy 361.674979 -246.926654) (xy 361.711702 -246.963377) (xy 361.742228 -247.005393) (xy 361.765806 -247.051667)
			(xy 361.781854 -247.10106) (xy 361.789979 -247.152355) (xy 361.790488 -247.178322) (xy 361.789979 -247.204289)
			(xy 361.781854 -247.255584) (xy 361.765806 -247.304977) (xy 361.742228 -247.351251) (xy 361.711702 -247.393267)
			(xy 361.674979 -247.42999) (xy 361.632963 -247.460516) (xy 361.586689 -247.484094) (xy 361.537296 -247.500142)
			(xy 361.486001 -247.508267) (xy 361.434067 -247.508267) (xy 361.382772 -247.500142) (xy 361.333379 -247.484094)
			(xy 361.287105 -247.460516) (xy 361.245089 -247.42999) (xy 361.208366 -247.393267) (xy 361.17784 -247.351251)
			(xy 361.154262 -247.304977) (xy 361.138214 -247.255584) (xy 361.130089 -247.204289) (xy 353.158298 -247.204289)
			(xy 353.158298 -248.018105) (xy 357.840789 -248.018105) (xy 357.840789 -247.966171) (xy 357.848914 -247.914876)
			(xy 357.864962 -247.865483) (xy 357.88854 -247.819209) (xy 357.919066 -247.777193) (xy 357.955789 -247.74047)
			(xy 357.997805 -247.709944) (xy 358.044079 -247.686366) (xy 358.093472 -247.670318) (xy 358.144767 -247.662193)
			(xy 358.196701 -247.662193) (xy 358.247996 -247.670318) (xy 358.297389 -247.686366) (xy 358.343663 -247.709944)
			(xy 358.385679 -247.74047) (xy 358.422402 -247.777193) (xy 358.452928 -247.819209) (xy 358.476506 -247.865483)
			(xy 358.492554 -247.914876) (xy 358.500679 -247.966171) (xy 358.501188 -247.992138) (xy 358.500679 -248.018105)
			(xy 358.492554 -248.0694) (xy 358.476506 -248.118793) (xy 358.452928 -248.165067) (xy 358.422402 -248.207083)
			(xy 358.385679 -248.243806) (xy 358.343663 -248.274332) (xy 358.297389 -248.29791) (xy 358.247996 -248.313958)
			(xy 358.196701 -248.322083) (xy 358.144767 -248.322083) (xy 358.093472 -248.313958) (xy 358.044079 -248.29791)
			(xy 357.997805 -248.274332) (xy 357.955789 -248.243806) (xy 357.919066 -248.207083) (xy 357.88854 -248.165067)
			(xy 357.864962 -248.118793) (xy 357.848914 -248.0694) (xy 357.840789 -248.018105) (xy 353.158298 -248.018105)
			(xy 353.158298 -248.65711) (xy 352.810318 -249.00509) (xy 356.04323 -249.00509) (xy 356.043705 -248.980539)
			(xy 356.050938 -248.931974) (xy 356.065275 -248.885013) (xy 356.086399 -248.840689) (xy 356.113845 -248.799976)
			(xy 356.130098 -248.78157) (xy 356.139909 -248.770088) (xy 356.152919 -248.742848) (xy 356.157384 -248.712993)
			(xy 356.152915 -248.683138) (xy 356.139901 -248.6559) (xy 356.130098 -248.64441) (xy 356.113822 -248.626021)
			(xy 356.086356 -248.585312) (xy 356.065221 -248.540985) (xy 356.050883 -248.494017) (xy 356.043657 -248.445444)
			(xy 356.04323 -248.42089) (xy 356.043739 -248.394923) (xy 356.051864 -248.343628) (xy 356.067912 -248.294235)
			(xy 356.09149 -248.247961) (xy 356.122016 -248.205945) (xy 356.158739 -248.169222) (xy 356.200755 -248.138696)
			(xy 356.247029 -248.115118) (xy 356.296422 -248.09907) (xy 356.347717 -248.090945) (xy 356.399651 -248.090945)
			(xy 356.450946 -248.09907) (xy 356.500339 -248.115118) (xy 356.546613 -248.138696) (xy 356.588629 -248.169222)
			(xy 356.625352 -248.205945) (xy 356.655878 -248.247961) (xy 356.679456 -248.294235) (xy 356.695504 -248.343628)
			(xy 356.703629 -248.394923) (xy 356.704138 -248.42089) (xy 356.70372 -248.445443) (xy 356.696474 -248.494011)
			(xy 356.682125 -248.540973) (xy 356.660988 -248.585296) (xy 356.633529 -248.626006) (xy 356.61727 -248.64441)
			(xy 356.607472 -248.655905) (xy 356.594452 -248.683139) (xy 356.589979 -248.712993) (xy 356.594447 -248.742847)
			(xy 356.607464 -248.770083) (xy 356.61727 -248.78157) (xy 356.633532 -248.799972) (xy 356.655264 -248.832175)
			(xy 361.130089 -248.832175) (xy 361.130089 -248.780241) (xy 361.138214 -248.728946) (xy 361.154262 -248.679553)
			(xy 361.17784 -248.633279) (xy 361.208366 -248.591263) (xy 361.245089 -248.55454) (xy 361.287105 -248.524014)
			(xy 361.333379 -248.500436) (xy 361.382772 -248.484388) (xy 361.434067 -248.476263) (xy 361.486001 -248.476263)
			(xy 361.537296 -248.484388) (xy 361.586689 -248.500436) (xy 361.632963 -248.524014) (xy 361.674979 -248.55454)
			(xy 361.711702 -248.591263) (xy 361.742228 -248.633279) (xy 361.765806 -248.679553) (xy 361.781854 -248.728946)
			(xy 361.789979 -248.780241) (xy 361.790488 -248.806208) (xy 361.789979 -248.832175) (xy 361.781854 -248.88347)
			(xy 361.765806 -248.932863) (xy 361.742228 -248.979137) (xy 361.711702 -249.021153) (xy 361.674979 -249.057876)
			(xy 361.632963 -249.088402) (xy 361.586689 -249.11198) (xy 361.537296 -249.128028) (xy 361.486001 -249.136153)
			(xy 361.434067 -249.136153) (xy 361.382772 -249.128028) (xy 361.333379 -249.11198) (xy 361.287105 -249.088402)
			(xy 361.245089 -249.057876) (xy 361.208366 -249.021153) (xy 361.17784 -248.979137) (xy 361.154262 -248.932863)
			(xy 361.138214 -248.88347) (xy 361.130089 -248.832175) (xy 356.655264 -248.832175) (xy 356.661001 -248.840676)
			(xy 356.682139 -248.885) (xy 356.696481 -248.931965) (xy 356.70371 -248.980537) (xy 356.704138 -249.00509)
			(xy 356.703629 -249.031057) (xy 356.695504 -249.082352) (xy 356.679456 -249.131745) (xy 356.655878 -249.178019)
			(xy 356.625352 -249.220035) (xy 356.618555 -249.226832) (xy 362.992162 -249.226832) (xy 362.992593 -249.20228)
			(xy 362.999836 -249.153712) (xy 363.014182 -249.106751) (xy 363.035316 -249.062427) (xy 363.062773 -249.021716)
			(xy 363.07903 -249.003312) (xy 363.088806 -248.9918) (xy 363.101829 -248.964572) (xy 363.106306 -248.934724)
			(xy 363.101843 -248.904873) (xy 363.088833 -248.877639) (xy 363.07903 -248.866152) (xy 363.062779 -248.847742)
			(xy 363.035308 -248.807039) (xy 363.014168 -248.762718) (xy 362.999824 -248.715754) (xy 362.992592 -248.667185)
			(xy 362.992162 -248.642632) (xy 362.992671 -248.616665) (xy 363.000796 -248.56537) (xy 363.016844 -248.515977)
			(xy 363.040422 -248.469703) (xy 363.070948 -248.427687) (xy 363.107671 -248.390964) (xy 363.149687 -248.360438)
			(xy 363.195961 -248.33686) (xy 363.245354 -248.320812) (xy 363.296649 -248.312687) (xy 363.348583 -248.312687)
			(xy 363.399878 -248.320812) (xy 363.449271 -248.33686) (xy 363.495545 -248.360438) (xy 363.537561 -248.390964)
			(xy 363.574284 -248.427687) (xy 363.60481 -248.469703) (xy 363.628388 -248.515977) (xy 363.644436 -248.56537)
			(xy 363.652561 -248.616665) (xy 363.65307 -248.642632) (xy 363.652609 -248.667183) (xy 363.645372 -248.715749)
			(xy 363.631032 -248.76271) (xy 363.609905 -248.807034) (xy 363.582456 -248.847747) (xy 363.566202 -248.866152)
			(xy 363.556369 -248.877617) (xy 363.543362 -248.904863) (xy 363.5389 -248.934724) (xy 363.543375 -248.964582)
			(xy 363.556395 -248.991822) (xy 363.566202 -249.003312) (xy 363.582489 -249.021692) (xy 363.609953 -249.062404)
			(xy 363.631086 -249.106733) (xy 363.645422 -249.153702) (xy 363.652645 -249.202277) (xy 363.65307 -249.226832)
			(xy 363.652561 -249.252799) (xy 363.644436 -249.304094) (xy 363.628388 -249.353487) (xy 363.60481 -249.399761)
			(xy 363.574284 -249.441777) (xy 363.537561 -249.4785) (xy 363.495545 -249.509026) (xy 363.449271 -249.532604)
			(xy 363.399878 -249.548652) (xy 363.348583 -249.556777) (xy 363.296649 -249.556777) (xy 363.245354 -249.548652)
			(xy 363.195961 -249.532604) (xy 363.149687 -249.509026) (xy 363.107671 -249.4785) (xy 363.070948 -249.441777)
			(xy 363.040422 -249.399761) (xy 363.016844 -249.353487) (xy 363.000796 -249.304094) (xy 362.992671 -249.252799)
			(xy 362.992162 -249.226832) (xy 356.618555 -249.226832) (xy 356.588629 -249.256758) (xy 356.546613 -249.287284)
			(xy 356.500339 -249.310862) (xy 356.450946 -249.32691) (xy 356.399651 -249.335035) (xy 356.347717 -249.335035)
			(xy 356.296422 -249.32691) (xy 356.247029 -249.310862) (xy 356.200755 -249.287284) (xy 356.158739 -249.256758)
			(xy 356.122016 -249.220035) (xy 356.09149 -249.178019) (xy 356.067912 -249.131745) (xy 356.051864 -249.082352)
			(xy 356.043739 -249.031057) (xy 356.04323 -249.00509) (xy 352.810318 -249.00509) (xy 352.169417 -249.645991)
			(xy 357.840789 -249.645991) (xy 357.840789 -249.594057) (xy 357.848914 -249.542762) (xy 357.864962 -249.493369)
			(xy 357.88854 -249.447095) (xy 357.919066 -249.405079) (xy 357.955789 -249.368356) (xy 357.997805 -249.33783)
			(xy 358.044079 -249.314252) (xy 358.093472 -249.298204) (xy 358.144767 -249.290079) (xy 358.196701 -249.290079)
			(xy 358.247996 -249.298204) (xy 358.297389 -249.314252) (xy 358.343663 -249.33783) (xy 358.385679 -249.368356)
			(xy 358.422402 -249.405079) (xy 358.452928 -249.447095) (xy 358.476506 -249.493369) (xy 358.492554 -249.542762)
			(xy 358.500679 -249.594057) (xy 358.501188 -249.620024) (xy 358.500679 -249.645991) (xy 358.492554 -249.697286)
			(xy 358.476506 -249.746679) (xy 358.452928 -249.792953) (xy 358.422402 -249.834969) (xy 358.385679 -249.871692)
			(xy 358.343663 -249.902218) (xy 358.297389 -249.925796) (xy 358.247996 -249.941844) (xy 358.196701 -249.949969)
			(xy 358.144767 -249.949969) (xy 358.093472 -249.941844) (xy 358.044079 -249.925796) (xy 357.997805 -249.902218)
			(xy 357.955789 -249.871692) (xy 357.919066 -249.834969) (xy 357.88854 -249.792953) (xy 357.864962 -249.746679)
			(xy 357.848914 -249.697286) (xy 357.840789 -249.645991) (xy 352.169417 -249.645991) (xy 351.794318 -250.02109)
			(xy 351.794318 -250.363072) (xy 353.066795 -250.363072) (xy 353.066795 -250.311128) (xy 353.074921 -250.259823)
			(xy 353.090973 -250.210421) (xy 353.114555 -250.164138) (xy 353.145087 -250.122115) (xy 353.181818 -250.085385)
			(xy 353.223842 -250.054853) (xy 353.270125 -250.031271) (xy 353.319527 -250.01522) (xy 353.370832 -250.007095)
			(xy 353.396804 -250.006612) (xy 353.422558 -250.007091) (xy 353.473444 -250.015072) (xy 353.522474 -250.030855)
			(xy 353.56846 -250.054059) (xy 353.610287 -250.084119) (xy 353.62896 -250.101862) (xy 353.63865 -250.110855)
			(xy 353.661582 -250.123987) (xy 353.687121 -250.130782) (xy 353.713547 -250.130782) (xy 353.739086 -250.123987)
			(xy 353.762018 -250.110855) (xy 353.771708 -250.101862) (xy 353.790394 -250.084135) (xy 353.832224 -250.054086)
			(xy 353.878207 -250.030887) (xy 353.927232 -250.0151) (xy 353.978112 -250.007107) (xy 354.003864 -250.006612)
			(xy 354.029832 -250.00716) (xy 354.081131 -250.01528) (xy 354.130527 -250.031325) (xy 354.176805 -250.0549)
			(xy 354.218825 -250.085425) (xy 354.255552 -250.122148) (xy 354.286081 -250.164164) (xy 354.309661 -250.21044)
			(xy 354.325712 -250.259834) (xy 354.333837 -250.311132) (xy 354.333837 -250.363068) (xy 354.333836 -250.363072)
			(xy 365.433795 -250.363072) (xy 365.433795 -250.311128) (xy 365.441921 -250.259822) (xy 365.457973 -250.21042)
			(xy 365.481556 -250.164137) (xy 365.512089 -250.122113) (xy 365.54882 -250.085383) (xy 365.590845 -250.054851)
			(xy 365.637129 -250.031269) (xy 365.686532 -250.015219) (xy 365.737838 -250.007094) (xy 365.76381 -250.006612)
			(xy 365.789672 -250.007101) (xy 365.840764 -250.015149) (xy 365.889978 -250.031063) (xy 365.936109 -250.054454)
			(xy 365.978031 -250.08475) (xy 365.996728 -250.102624) (xy 366.006443 -250.111669) (xy 366.029452 -250.124881)
			(xy 366.055089 -250.131718) (xy 366.081623 -250.131718) (xy 366.10726 -250.124881) (xy 366.130269 -250.111669)
			(xy 366.139984 -250.102624) (xy 366.158674 -250.084744) (xy 366.200604 -250.054462) (xy 366.246738 -250.03108)
			(xy 366.295951 -250.015167) (xy 366.347041 -250.007112) (xy 366.372902 -250.006612) (xy 366.398866 -250.007189)
			(xy 366.450156 -250.015313) (xy 366.499543 -250.03136) (xy 366.545812 -250.054936) (xy 366.587823 -250.085459)
			(xy 366.624542 -250.122178) (xy 366.655065 -250.16419) (xy 366.678641 -250.210459) (xy 366.694687 -250.259846)
			(xy 366.702811 -250.311136) (xy 366.702811 -250.363064) (xy 366.694687 -250.414354) (xy 366.678641 -250.463741)
			(xy 366.655065 -250.51001) (xy 366.624542 -250.552022) (xy 366.587823 -250.588741) (xy 366.545812 -250.619264)
			(xy 366.499543 -250.64284) (xy 366.450156 -250.658887) (xy 366.398866 -250.667011) (xy 366.372902 -250.66752)
			(xy 366.347041 -250.667014) (xy 366.29595 -250.658969) (xy 366.246737 -250.643058) (xy 366.200605 -250.619671)
			(xy 366.158682 -250.58938) (xy 366.139984 -250.571508) (xy 366.130269 -250.562463) (xy 366.10726 -250.549251)
			(xy 366.081623 -250.542414) (xy 366.055089 -250.542414) (xy 366.029452 -250.549251) (xy 366.006443 -250.562463)
			(xy 365.996728 -250.571508) (xy 365.978038 -250.589387) (xy 365.936107 -250.619668) (xy 365.889973 -250.64305)
			(xy 365.840761 -250.658963) (xy 365.789671 -250.667019) (xy 365.76381 -250.66752) (xy 365.737838 -250.667106)
			(xy 365.686532 -250.658981) (xy 365.637129 -250.642931) (xy 365.590845 -250.619349) (xy 365.54882 -250.588817)
			(xy 365.512089 -250.552087) (xy 365.481556 -250.510063) (xy 365.457973 -250.46378) (xy 365.441921 -250.414378)
			(xy 365.433795 -250.363072) (xy 354.333836 -250.363072) (xy 354.325712 -250.414366) (xy 354.309661 -250.46376)
			(xy 354.286081 -250.510036) (xy 354.255552 -250.552052) (xy 354.218825 -250.588775) (xy 354.176805 -250.6193)
			(xy 354.130527 -250.642875) (xy 354.081131 -250.65892) (xy 354.029832 -250.66704) (xy 354.003864 -250.66752)
			(xy 353.97811 -250.667052) (xy 353.927223 -250.659067) (xy 353.878193 -250.64328) (xy 353.832208 -250.620075)
			(xy 353.790381 -250.590014) (xy 353.771708 -250.57227) (xy 353.762018 -250.563277) (xy 353.739086 -250.550145)
			(xy 353.713547 -250.54335) (xy 353.687121 -250.54335) (xy 353.661582 -250.550145) (xy 353.63865 -250.563277)
			(xy 353.62896 -250.57227) (xy 353.610293 -250.590018) (xy 353.568458 -250.620063) (xy 353.522469 -250.643258)
			(xy 353.47344 -250.65904) (xy 353.422557 -250.667028) (xy 353.396804 -250.66752) (xy 353.370832 -250.667105)
			(xy 353.319527 -250.65898) (xy 353.270125 -250.642929) (xy 353.223842 -250.619347) (xy 353.181818 -250.588815)
			(xy 353.145087 -250.552085) (xy 353.114555 -250.510062) (xy 353.090973 -250.463779) (xy 353.074921 -250.414377)
			(xy 353.066795 -250.363072) (xy 351.794318 -250.363072) (xy 351.794318 -252.659134) (xy 356.04323 -252.659134)
			(xy 356.043671 -252.634582) (xy 356.050913 -252.586016) (xy 356.065257 -252.539054) (xy 356.086388 -252.49473)
			(xy 356.113842 -252.454019) (xy 356.130098 -252.435614) (xy 356.139866 -252.424098) (xy 356.152881 -252.39687)
			(xy 356.157355 -252.367025) (xy 356.152896 -252.337178) (xy 356.139895 -252.309944) (xy 356.130098 -252.298454)
			(xy 356.113843 -252.280047) (xy 356.086374 -252.239343) (xy 356.065235 -252.195021) (xy 356.050891 -252.148057)
			(xy 356.04366 -252.099487) (xy 356.04323 -252.074934) (xy 356.043739 -252.048967) (xy 356.051864 -251.997672)
			(xy 356.067912 -251.948279) (xy 356.09149 -251.902005) (xy 356.122016 -251.859989) (xy 356.158739 -251.823266)
			(xy 356.200755 -251.79274) (xy 356.247029 -251.769162) (xy 356.296422 -251.753114) (xy 356.347717 -251.744989)
			(xy 356.399651 -251.744989) (xy 356.450946 -251.753114) (xy 356.500339 -251.769162) (xy 356.546613 -251.79274)
			(xy 356.588629 -251.823266) (xy 356.625352 -251.859989) (xy 356.655878 -251.902005) (xy 356.679456 -251.948279)
			(xy 356.695504 -251.997672) (xy 356.703629 -252.048967) (xy 356.704138 -252.074934) (xy 356.703686 -252.099486)
			(xy 356.696448 -252.148052) (xy 356.682107 -252.195014) (xy 356.660978 -252.239338) (xy 356.633525 -252.280049)
			(xy 356.61727 -252.298454) (xy 356.60743 -252.309915) (xy 356.594414 -252.337162) (xy 356.589949 -252.367025)
			(xy 356.594428 -252.396887) (xy 356.607458 -252.424126) (xy 356.61727 -252.435614) (xy 356.633552 -252.453998)
			(xy 356.661018 -252.494708) (xy 356.682153 -252.539036) (xy 356.69649 -252.586005) (xy 356.703713 -252.634579)
			(xy 356.704138 -252.659134) (xy 356.703629 -252.685101) (xy 356.695504 -252.736396) (xy 356.679456 -252.785789)
			(xy 356.669315 -252.805692) (xy 363.042962 -252.805692) (xy 363.04343 -252.781141) (xy 363.050664 -252.732575)
			(xy 363.065001 -252.685614) (xy 363.086127 -252.641289) (xy 363.113576 -252.600577) (xy 363.12983 -252.582172)
			(xy 363.139645 -252.570691) (xy 363.152664 -252.543452) (xy 363.157133 -252.513594) (xy 363.15266 -252.483737)
			(xy 363.139638 -252.456499) (xy 363.12983 -252.445012) (xy 363.11356 -252.426618) (xy 363.086092 -252.385911)
			(xy 363.064955 -252.341585) (xy 363.050616 -252.294618) (xy 363.043389 -252.246046) (xy 363.042962 -252.221492)
			(xy 363.043471 -252.195525) (xy 363.051596 -252.14423) (xy 363.067644 -252.094837) (xy 363.091222 -252.048563)
			(xy 363.121748 -252.006547) (xy 363.158471 -251.969824) (xy 363.200487 -251.939298) (xy 363.246761 -251.91572)
			(xy 363.296154 -251.899672) (xy 363.347449 -251.891547) (xy 363.399383 -251.891547) (xy 363.450678 -251.899672)
			(xy 363.500071 -251.91572) (xy 363.546345 -251.939298) (xy 363.588361 -251.969824) (xy 363.625084 -252.006547)
			(xy 363.65561 -252.048563) (xy 363.679188 -252.094837) (xy 363.695236 -252.14423) (xy 363.703361 -252.195525)
			(xy 363.70387 -252.221492) (xy 363.703445 -252.246044) (xy 363.696199 -252.294612) (xy 363.681851 -252.341573)
			(xy 363.660716 -252.385897) (xy 363.633259 -252.426608) (xy 363.617002 -252.445012) (xy 363.607208 -252.456508)
			(xy 363.594197 -252.483743) (xy 363.589728 -252.513594) (xy 363.594193 -252.543446) (xy 363.607202 -252.570682)
			(xy 363.617002 -252.582172) (xy 363.63327 -252.600568) (xy 363.660737 -252.641275) (xy 363.681873 -252.6856)
			(xy 363.696214 -252.732566) (xy 363.703442 -252.781138) (xy 363.70387 -252.805692) (xy 363.703361 -252.831659)
			(xy 363.695236 -252.882954) (xy 363.679188 -252.932347) (xy 363.65561 -252.978621) (xy 363.625084 -253.020637)
			(xy 363.588361 -253.05736) (xy 363.546345 -253.087886) (xy 363.500071 -253.111464) (xy 363.450678 -253.127512)
			(xy 363.399383 -253.135637) (xy 363.347449 -253.135637) (xy 363.296154 -253.127512) (xy 363.246761 -253.111464)
			(xy 363.200487 -253.087886) (xy 363.158471 -253.05736) (xy 363.121748 -253.020637) (xy 363.091222 -252.978621)
			(xy 363.067644 -252.932347) (xy 363.051596 -252.882954) (xy 363.043471 -252.831659) (xy 363.042962 -252.805692)
			(xy 356.669315 -252.805692) (xy 356.655878 -252.832063) (xy 356.625352 -252.874079) (xy 356.588629 -252.910802)
			(xy 356.546613 -252.941328) (xy 356.500339 -252.964906) (xy 356.450946 -252.980954) (xy 356.399651 -252.989079)
			(xy 356.347717 -252.989079) (xy 356.296422 -252.980954) (xy 356.247029 -252.964906) (xy 356.200755 -252.941328)
			(xy 356.158739 -252.910802) (xy 356.122016 -252.874079) (xy 356.09149 -252.832063) (xy 356.067912 -252.785789)
			(xy 356.051864 -252.736396) (xy 356.043739 -252.685101) (xy 356.04323 -252.659134) (xy 351.794318 -252.659134)
			(xy 351.794318 -254.040971) (xy 353.066815 -254.040971) (xy 353.066815 -253.989029) (xy 353.07494 -253.937728)
			(xy 353.090991 -253.888329) (xy 353.114572 -253.842049) (xy 353.145103 -253.800028) (xy 353.181831 -253.7633)
			(xy 353.223852 -253.73277) (xy 353.270132 -253.70919) (xy 353.319532 -253.693139) (xy 353.370833 -253.685015)
			(xy 353.396804 -253.684532) (xy 353.422558 -253.685005) (xy 353.473445 -253.692987) (xy 353.522475 -253.708771)
			(xy 353.568461 -253.731976) (xy 353.610287 -253.762038) (xy 353.62896 -253.779782) (xy 353.63865 -253.788775)
			(xy 353.661582 -253.801907) (xy 353.687121 -253.808702) (xy 353.713547 -253.808702) (xy 353.739086 -253.801907)
			(xy 353.762018 -253.788775) (xy 353.771708 -253.779782) (xy 353.790381 -253.762041) (xy 353.832216 -253.731997)
			(xy 353.878203 -253.708802) (xy 353.92723 -253.693018) (xy 353.978111 -253.685027) (xy 354.003864 -253.684532)
			(xy 354.029834 -253.68504) (xy 354.081135 -253.69316) (xy 354.130535 -253.709206) (xy 354.176815 -253.732783)
			(xy 354.218838 -253.76331) (xy 354.255567 -253.800035) (xy 354.286098 -253.842054) (xy 354.30968 -253.888332)
			(xy 354.325731 -253.93773) (xy 354.326994 -253.945703) (xy 361.239817 -253.945703) (xy 361.239817 -253.893769)
			(xy 361.247942 -253.842474) (xy 361.26399 -253.793081) (xy 361.287568 -253.746807) (xy 361.318094 -253.704791)
			(xy 361.354817 -253.668068) (xy 361.396833 -253.637542) (xy 361.443107 -253.613964) (xy 361.4925 -253.597916)
			(xy 361.543795 -253.589791) (xy 361.595729 -253.589791) (xy 361.647024 -253.597916) (xy 361.696417 -253.613964)
			(xy 361.742691 -253.637542) (xy 361.784707 -253.668068) (xy 361.82143 -253.704791) (xy 361.851956 -253.746807)
			(xy 361.875534 -253.793081) (xy 361.891582 -253.842474) (xy 361.899707 -253.893769) (xy 361.900216 -253.919736)
			(xy 361.899707 -253.945703) (xy 361.891582 -253.996998) (xy 361.877295 -254.040971) (xy 365.433815 -254.040971)
			(xy 365.433815 -253.989029) (xy 365.441941 -253.937727) (xy 365.457992 -253.888327) (xy 365.481573 -253.842047)
			(xy 365.512104 -253.800026) (xy 365.548833 -253.763298) (xy 365.590856 -253.732768) (xy 365.637137 -253.709188)
			(xy 365.686537 -253.693138) (xy 365.737839 -253.685014) (xy 365.76381 -253.684532) (xy 365.78967 -253.685043)
			(xy 365.840761 -253.69309) (xy 365.889974 -253.709) (xy 365.936105 -253.732385) (xy 365.978029 -253.762674)
			(xy 365.996728 -253.780544) (xy 366.006443 -253.789589) (xy 366.029452 -253.802801) (xy 366.055089 -253.809638)
			(xy 366.081623 -253.809638) (xy 366.10726 -253.802801) (xy 366.130269 -253.789589) (xy 366.139984 -253.780544)
			(xy 366.158678 -253.762668) (xy 366.200606 -253.732384) (xy 366.246739 -253.709001) (xy 366.295951 -253.693087)
			(xy 366.347041 -253.685032) (xy 366.372902 -253.684532) (xy 366.398868 -253.685069) (xy 366.450161 -253.693194)
			(xy 366.499551 -253.709242) (xy 366.545823 -253.732819) (xy 366.587836 -253.763344) (xy 366.624558 -253.800065)
			(xy 366.655082 -253.842079) (xy 366.678659 -253.888351) (xy 366.694707 -253.937741) (xy 366.702831 -253.989034)
			(xy 366.702831 -254.040966) (xy 366.694707 -254.092259) (xy 366.678659 -254.141649) (xy 366.655082 -254.187921)
			(xy 366.624558 -254.229935) (xy 366.587836 -254.266656) (xy 366.545823 -254.297181) (xy 366.499551 -254.320758)
			(xy 366.450161 -254.336806) (xy 366.398868 -254.344931) (xy 366.372902 -254.34544) (xy 366.347042 -254.344929)
			(xy 366.295951 -254.336883) (xy 366.246738 -254.320974) (xy 366.200606 -254.297588) (xy 366.158683 -254.267299)
			(xy 366.139984 -254.249428) (xy 366.130269 -254.240383) (xy 366.10726 -254.227171) (xy 366.081623 -254.220334)
			(xy 366.055089 -254.220334) (xy 366.029452 -254.227171) (xy 366.006443 -254.240383) (xy 365.996728 -254.249428)
			(xy 365.978041 -254.267311) (xy 365.936109 -254.297591) (xy 365.889974 -254.320972) (xy 365.840761 -254.336884)
			(xy 365.789671 -254.344939) (xy 365.76381 -254.34544) (xy 365.737839 -254.344986) (xy 365.686537 -254.336862)
			(xy 365.637137 -254.320812) (xy 365.590856 -254.297232) (xy 365.548833 -254.266702) (xy 365.512104 -254.229974)
			(xy 365.481573 -254.187953) (xy 365.457992 -254.141673) (xy 365.441941 -254.092273) (xy 365.433815 -254.040971)
			(xy 361.877295 -254.040971) (xy 361.875534 -254.046391) (xy 361.851956 -254.092665) (xy 361.82143 -254.134681)
			(xy 361.784707 -254.171404) (xy 361.742691 -254.20193) (xy 361.696417 -254.225508) (xy 361.647024 -254.241556)
			(xy 361.595729 -254.249681) (xy 361.543795 -254.249681) (xy 361.4925 -254.241556) (xy 361.443107 -254.225508)
			(xy 361.396833 -254.20193) (xy 361.354817 -254.171404) (xy 361.318094 -254.134681) (xy 361.287568 -254.092665)
			(xy 361.26399 -254.046391) (xy 361.247942 -253.996998) (xy 361.239817 -253.945703) (xy 354.326994 -253.945703)
			(xy 354.333857 -253.98903) (xy 354.333857 -254.04097) (xy 354.325731 -254.09227) (xy 354.30968 -254.141668)
			(xy 354.286098 -254.187946) (xy 354.255567 -254.229965) (xy 354.218838 -254.26669) (xy 354.176815 -254.297217)
			(xy 354.130535 -254.320794) (xy 354.081135 -254.33684) (xy 354.029834 -254.34496) (xy 354.003864 -254.34544)
			(xy 353.97811 -254.344966) (xy 353.927224 -254.336982) (xy 353.878194 -254.321197) (xy 353.832209 -254.297993)
			(xy 353.790382 -254.267933) (xy 353.771708 -254.25019) (xy 353.762018 -254.241197) (xy 353.739086 -254.228065)
			(xy 353.713547 -254.22127) (xy 353.687121 -254.22127) (xy 353.661582 -254.228065) (xy 353.63865 -254.241197)
			(xy 353.62896 -254.25019) (xy 353.610296 -254.267941) (xy 353.56846 -254.297985) (xy 353.52247 -254.321179)
			(xy 353.473441 -254.33696) (xy 353.422557 -254.344948) (xy 353.396804 -254.34544) (xy 353.370833 -254.344985)
			(xy 353.319532 -254.336861) (xy 353.270132 -254.32081) (xy 353.223852 -254.29723) (xy 353.181831 -254.2667)
			(xy 353.145103 -254.229972) (xy 353.114572 -254.187951) (xy 353.090991 -254.141671) (xy 353.07494 -254.092272)
			(xy 353.066815 -254.040971) (xy 351.794318 -254.040971) (xy 351.794318 -254.759519) (xy 357.950517 -254.759519)
			(xy 357.950517 -254.707585) (xy 357.958642 -254.65629) (xy 357.97469 -254.606897) (xy 357.998268 -254.560623)
			(xy 358.028794 -254.518607) (xy 358.065517 -254.481884) (xy 358.107533 -254.451358) (xy 358.153807 -254.42778)
			(xy 358.2032 -254.411732) (xy 358.254495 -254.403607) (xy 358.306429 -254.403607) (xy 358.357724 -254.411732)
			(xy 358.407117 -254.42778) (xy 358.453391 -254.451358) (xy 358.495407 -254.481884) (xy 358.53213 -254.518607)
			(xy 358.562656 -254.560623) (xy 358.586234 -254.606897) (xy 358.602282 -254.65629) (xy 358.610407 -254.707585)
			(xy 358.610916 -254.733552) (xy 358.610407 -254.759519) (xy 358.602282 -254.810814) (xy 358.586234 -254.860207)
			(xy 358.562656 -254.906481) (xy 358.53213 -254.948497) (xy 358.495407 -254.98522) (xy 358.453391 -255.015746)
			(xy 358.407117 -255.039324) (xy 358.357724 -255.055372) (xy 358.306429 -255.063497) (xy 358.254495 -255.063497)
			(xy 358.2032 -255.055372) (xy 358.153807 -255.039324) (xy 358.107533 -255.015746) (xy 358.065517 -254.98522)
			(xy 358.028794 -254.948497) (xy 357.998268 -254.906481) (xy 357.97469 -254.860207) (xy 357.958642 -254.810814)
			(xy 357.950517 -254.759519) (xy 351.794318 -254.759519) (xy 351.794318 -256.330196) (xy 356.04323 -256.330196)
			(xy 356.043648 -256.305643) (xy 356.050895 -256.257076) (xy 356.065245 -256.210114) (xy 356.086382 -256.165791)
			(xy 356.11384 -256.12508) (xy 356.130098 -256.106676) (xy 356.139903 -256.095189) (xy 356.152914 -256.067951)
			(xy 356.15738 -256.038097) (xy 356.152912 -256.008244) (xy 356.1399 -255.981006) (xy 356.130098 -255.969516)
			(xy 356.113825 -255.951124) (xy 356.086359 -255.910416) (xy 356.065223 -255.86609) (xy 356.050884 -255.819123)
			(xy 356.043657 -255.77055) (xy 356.04323 -255.745996) (xy 356.043739 -255.720029) (xy 356.051864 -255.668734)
			(xy 356.067912 -255.619341) (xy 356.09149 -255.573067) (xy 356.122016 -255.531051) (xy 356.158739 -255.494328)
			(xy 356.200755 -255.463802) (xy 356.247029 -255.440224) (xy 356.296422 -255.424176) (xy 356.347717 -255.416051)
			(xy 356.399651 -255.416051) (xy 356.450946 -255.424176) (xy 356.500339 -255.440224) (xy 356.546613 -255.463802)
			(xy 356.588629 -255.494328) (xy 356.625352 -255.531051) (xy 356.655878 -255.573067) (xy 356.656144 -255.573589)
			(xy 361.239817 -255.573589) (xy 361.239817 -255.521655) (xy 361.247942 -255.47036) (xy 361.26399 -255.420967)
			(xy 361.287568 -255.374693) (xy 361.318094 -255.332677) (xy 361.354817 -255.295954) (xy 361.396833 -255.265428)
			(xy 361.443107 -255.24185) (xy 361.4925 -255.225802) (xy 361.543795 -255.217677) (xy 361.595729 -255.217677)
			(xy 361.647024 -255.225802) (xy 361.696417 -255.24185) (xy 361.742691 -255.265428) (xy 361.784707 -255.295954)
			(xy 361.82143 -255.332677) (xy 361.851956 -255.374693) (xy 361.875534 -255.420967) (xy 361.891582 -255.47036)
			(xy 361.899707 -255.521655) (xy 361.900216 -255.547622) (xy 361.899707 -255.573589) (xy 361.891582 -255.624884)
			(xy 361.875534 -255.674277) (xy 361.851956 -255.720551) (xy 361.82143 -255.762567) (xy 361.784707 -255.79929)
			(xy 361.742691 -255.829816) (xy 361.696417 -255.853394) (xy 361.647024 -255.869442) (xy 361.595729 -255.877567)
			(xy 361.543795 -255.877567) (xy 361.4925 -255.869442) (xy 361.443107 -255.853394) (xy 361.396833 -255.829816)
			(xy 361.354817 -255.79929) (xy 361.318094 -255.762567) (xy 361.287568 -255.720551) (xy 361.26399 -255.674277)
			(xy 361.247942 -255.624884) (xy 361.239817 -255.573589) (xy 356.656144 -255.573589) (xy 356.679456 -255.619341)
			(xy 356.695504 -255.668734) (xy 356.703629 -255.720029) (xy 356.704138 -255.745996) (xy 356.703723 -255.770549)
			(xy 356.696476 -255.819117) (xy 356.682126 -255.866079) (xy 356.660989 -255.910403) (xy 356.633529 -255.951113)
			(xy 356.61727 -255.969516) (xy 356.607467 -255.981006) (xy 356.594446 -256.008242) (xy 356.589975 -256.038097)
			(xy 356.594445 -256.067952) (xy 356.607463 -256.095189) (xy 356.61727 -256.106676) (xy 356.633534 -256.125075)
			(xy 356.661003 -256.165781) (xy 356.682141 -256.210105) (xy 356.696482 -256.257071) (xy 356.70371 -256.305642)
			(xy 356.704138 -256.330196) (xy 356.703629 -256.356163) (xy 356.69868 -256.387405) (xy 357.950517 -256.387405)
			(xy 357.950517 -256.335471) (xy 357.958642 -256.284176) (xy 357.97469 -256.234783) (xy 357.998268 -256.188509)
			(xy 358.028794 -256.146493) (xy 358.065517 -256.10977) (xy 358.107533 -256.079244) (xy 358.153807 -256.055666)
			(xy 358.2032 -256.039618) (xy 358.254495 -256.031493) (xy 358.306429 -256.031493) (xy 358.357724 -256.039618)
			(xy 358.407117 -256.055666) (xy 358.453391 -256.079244) (xy 358.495407 -256.10977) (xy 358.53213 -256.146493)
			(xy 358.562656 -256.188509) (xy 358.586234 -256.234783) (xy 358.602282 -256.284176) (xy 358.610407 -256.335471)
			(xy 358.610916 -256.361438) (xy 358.610407 -256.387405) (xy 358.610054 -256.389632) (xy 363.037882 -256.389632)
			(xy 363.038308 -256.365079) (xy 363.045552 -256.316512) (xy 363.059899 -256.26955) (xy 363.081034 -256.225226)
			(xy 363.108492 -256.184515) (xy 363.12475 -256.166112) (xy 363.134524 -256.154599) (xy 363.147545 -256.127371)
			(xy 363.152021 -256.097524) (xy 363.147559 -256.067674) (xy 363.134551 -256.04044) (xy 363.12475 -256.028952)
			(xy 363.108502 -256.010539) (xy 363.08103 -255.969837) (xy 363.059889 -255.925517) (xy 363.045544 -255.878554)
			(xy 363.038312 -255.829985) (xy 363.037882 -255.805432) (xy 363.038391 -255.779465) (xy 363.046516 -255.72817)
			(xy 363.062564 -255.678777) (xy 363.086142 -255.632503) (xy 363.116668 -255.590487) (xy 363.153391 -255.553764)
			(xy 363.195407 -255.523238) (xy 363.241681 -255.49966) (xy 363.291074 -255.483612) (xy 363.342369 -255.475487)
			(xy 363.394303 -255.475487) (xy 363.445598 -255.483612) (xy 363.494991 -255.49966) (xy 363.541265 -255.523238)
			(xy 363.583281 -255.553764) (xy 363.620004 -255.590487) (xy 363.65053 -255.632503) (xy 363.674108 -255.678777)
			(xy 363.690156 -255.72817) (xy 363.698281 -255.779465) (xy 363.69879 -255.805432) (xy 363.698349 -255.829984)
			(xy 363.691111 -255.878551) (xy 363.676767 -255.925514) (xy 363.655635 -255.969838) (xy 363.628179 -256.010548)
			(xy 363.611922 -256.028952) (xy 363.602088 -256.040417) (xy 363.589078 -256.067663) (xy 363.584615 -256.097524)
			(xy 363.589092 -256.127383) (xy 363.602114 -256.154623) (xy 363.611922 -256.166112) (xy 363.628212 -256.18449)
			(xy 363.655675 -256.225202) (xy 363.676807 -256.269532) (xy 363.691142 -256.316502) (xy 363.698365 -256.365077)
			(xy 363.69879 -256.389632) (xy 363.698281 -256.415599) (xy 363.690156 -256.466894) (xy 363.674108 -256.516287)
			(xy 363.65053 -256.562561) (xy 363.620004 -256.604577) (xy 363.583281 -256.6413) (xy 363.541265 -256.671826)
			(xy 363.494991 -256.695404) (xy 363.445598 -256.711452) (xy 363.394303 -256.719577) (xy 363.342369 -256.719577)
			(xy 363.291074 -256.711452) (xy 363.241681 -256.695404) (xy 363.195407 -256.671826) (xy 363.153391 -256.6413)
			(xy 363.116668 -256.604577) (xy 363.086142 -256.562561) (xy 363.062564 -256.516287) (xy 363.046516 -256.466894)
			(xy 363.038391 -256.415599) (xy 363.037882 -256.389632) (xy 358.610054 -256.389632) (xy 358.602282 -256.4387)
			(xy 358.586234 -256.488093) (xy 358.562656 -256.534367) (xy 358.53213 -256.576383) (xy 358.495407 -256.613106)
			(xy 358.453391 -256.643632) (xy 358.407117 -256.66721) (xy 358.357724 -256.683258) (xy 358.306429 -256.691383)
			(xy 358.254495 -256.691383) (xy 358.2032 -256.683258) (xy 358.153807 -256.66721) (xy 358.107533 -256.643632)
			(xy 358.065517 -256.613106) (xy 358.028794 -256.576383) (xy 357.998268 -256.534367) (xy 357.97469 -256.488093)
			(xy 357.958642 -256.4387) (xy 357.950517 -256.387405) (xy 356.69868 -256.387405) (xy 356.695504 -256.407458)
			(xy 356.679456 -256.456851) (xy 356.655878 -256.503125) (xy 356.625352 -256.545141) (xy 356.588629 -256.581864)
			(xy 356.546613 -256.61239) (xy 356.500339 -256.635968) (xy 356.450946 -256.652016) (xy 356.399651 -256.660141)
			(xy 356.347717 -256.660141) (xy 356.296422 -256.652016) (xy 356.247029 -256.635968) (xy 356.200755 -256.61239)
			(xy 356.158739 -256.581864) (xy 356.122016 -256.545141) (xy 356.09149 -256.503125) (xy 356.067912 -256.456851)
			(xy 356.051864 -256.407458) (xy 356.043739 -256.356163) (xy 356.04323 -256.330196) (xy 351.794318 -256.330196)
			(xy 351.794318 -257.201221) (xy 361.239817 -257.201221) (xy 361.239817 -257.149287) (xy 361.247942 -257.097992)
			(xy 361.26399 -257.048599) (xy 361.287568 -257.002325) (xy 361.318094 -256.960309) (xy 361.354817 -256.923586)
			(xy 361.396833 -256.89306) (xy 361.443107 -256.869482) (xy 361.4925 -256.853434) (xy 361.543795 -256.845309)
			(xy 361.595729 -256.845309) (xy 361.647024 -256.853434) (xy 361.696417 -256.869482) (xy 361.742691 -256.89306)
			(xy 361.784707 -256.923586) (xy 361.82143 -256.960309) (xy 361.851956 -257.002325) (xy 361.875534 -257.048599)
			(xy 361.891582 -257.097992) (xy 361.899707 -257.149287) (xy 361.900216 -257.175254) (xy 361.899707 -257.201221)
			(xy 361.891582 -257.252516) (xy 361.875534 -257.301909) (xy 361.851956 -257.348183) (xy 361.82143 -257.390199)
			(xy 361.784707 -257.426922) (xy 361.742691 -257.457448) (xy 361.696417 -257.481026) (xy 361.647024 -257.497074)
			(xy 361.595729 -257.505199) (xy 361.543795 -257.505199) (xy 361.4925 -257.497074) (xy 361.443107 -257.481026)
			(xy 361.396833 -257.457448) (xy 361.354817 -257.426922) (xy 361.318094 -257.390199) (xy 361.287568 -257.348183)
			(xy 361.26399 -257.301909) (xy 361.247942 -257.252516) (xy 361.239817 -257.201221) (xy 351.794318 -257.201221)
			(xy 351.794318 -257.261868) (xy 351.794752 -257.275422) (xy 351.801899 -257.301571) (xy 351.815672 -257.324919)
			(xy 351.8351 -257.343824) (xy 351.858816 -257.356953) (xy 351.885151 -257.363382) (xy 351.898712 -257.363468)
			(xy 351.904046 -257.36296) (xy 351.910904 -257.362706) (xy 351.923604 -257.362452) (xy 351.947276 -257.362831)
			(xy 351.994142 -257.369542) (xy 352.039567 -257.382882) (xy 352.082619 -257.402577) (xy 352.122415 -257.428224)
			(xy 352.14052 -257.443478) (xy 352.152204 -257.453638) (xy 352.163204 -257.461896) (xy 352.188461 -257.472761)
			(xy 352.215704 -257.476472) (xy 352.242947 -257.472761) (xy 352.268204 -257.461896) (xy 352.279204 -257.453638)
			(xy 352.290888 -257.443478) (xy 352.309026 -257.42827) (xy 352.348829 -257.402654) (xy 352.391875 -257.382971)
			(xy 352.437287 -257.369621) (xy 352.484137 -257.362878) (xy 352.507804 -257.362452) (xy 352.520504 -257.362706)
			(xy 352.527362 -257.36296) (xy 352.553596 -257.365026) (xy 352.604967 -257.376424) (xy 352.653883 -257.395817)
			(xy 352.699108 -257.422715) (xy 352.7395 -257.456439) (xy 352.774039 -257.496138) (xy 352.801852 -257.540807)
			(xy 352.822235 -257.589318) (xy 352.834675 -257.640447) (xy 352.838857 -257.6929) (xy 352.836787 -257.718869)
			(xy 353.066835 -257.718869) (xy 353.066835 -257.666931) (xy 353.07496 -257.615632) (xy 353.09101 -257.566236)
			(xy 353.114589 -257.519959) (xy 353.145118 -257.477941) (xy 353.181844 -257.441215) (xy 353.223863 -257.410687)
			(xy 353.27014 -257.387108) (xy 353.319536 -257.371059) (xy 353.370835 -257.362935) (xy 353.396804 -257.362452)
			(xy 353.422557 -257.362948) (xy 353.473442 -257.370928) (xy 353.522471 -257.386708) (xy 353.568457 -257.409907)
			(xy 353.610285 -257.439962) (xy 353.62896 -257.457702) (xy 353.63865 -257.466695) (xy 353.661582 -257.479827)
			(xy 353.687121 -257.486622) (xy 353.713547 -257.486622) (xy 353.739086 -257.479827) (xy 353.762018 -257.466695)
			(xy 353.771708 -257.457702) (xy 353.790385 -257.439965) (xy 353.832218 -257.409919) (xy 353.878204 -257.386723)
			(xy 353.92723 -257.370938) (xy 353.978112 -257.362947) (xy 354.003864 -257.362452) (xy 354.029836 -257.36292)
			(xy 354.08114 -257.371041) (xy 354.130542 -257.387088) (xy 354.176826 -257.410666) (xy 354.218851 -257.441195)
			(xy 354.255582 -257.477922) (xy 354.286115 -257.519944) (xy 354.309698 -257.566224) (xy 354.325751 -257.615625)
			(xy 354.333877 -257.666928) (xy 354.333877 -257.718872) (xy 354.325751 -257.770175) (xy 354.309698 -257.819576)
			(xy 354.286115 -257.865856) (xy 354.255582 -257.907878) (xy 354.218851 -257.944605) (xy 354.176826 -257.975134)
			(xy 354.130542 -257.998712) (xy 354.08114 -258.014759) (xy 354.079384 -258.015037) (xy 357.950517 -258.015037)
			(xy 357.950517 -257.963103) (xy 357.958642 -257.911808) (xy 357.97469 -257.862415) (xy 357.998268 -257.816141)
			(xy 358.028794 -257.774125) (xy 358.065517 -257.737402) (xy 358.107533 -257.706876) (xy 358.153807 -257.683298)
			(xy 358.2032 -257.66725) (xy 358.254495 -257.659125) (xy 358.306429 -257.659125) (xy 358.357724 -257.66725)
			(xy 358.407117 -257.683298) (xy 358.453391 -257.706876) (xy 358.469898 -257.718869) (xy 365.433835 -257.718869)
			(xy 365.433835 -257.666931) (xy 365.44196 -257.615632) (xy 365.45801 -257.566235) (xy 365.48159 -257.519958)
			(xy 365.51212 -257.477939) (xy 365.548846 -257.441213) (xy 365.590866 -257.410685) (xy 365.637144 -257.387106)
			(xy 365.686541 -257.371058) (xy 365.737841 -257.362934) (xy 365.76381 -257.362452) (xy 365.789671 -257.362958)
			(xy 365.840762 -257.371005) (xy 365.889975 -257.386916) (xy 365.936106 -257.410303) (xy 365.978029 -257.440593)
			(xy 365.996728 -257.458464) (xy 366.006443 -257.467509) (xy 366.029452 -257.480721) (xy 366.055089 -257.487558)
			(xy 366.081623 -257.487558) (xy 366.10726 -257.480721) (xy 366.130269 -257.467509) (xy 366.139984 -257.458464)
			(xy 366.158664 -257.440574) (xy 366.200598 -257.410296) (xy 366.246735 -257.386916) (xy 366.295949 -257.371006)
			(xy 366.347041 -257.362952) (xy 366.372902 -257.362452) (xy 366.39887 -257.362949) (xy 366.450165 -257.371074)
			(xy 366.499559 -257.387123) (xy 366.545833 -257.410702) (xy 366.587849 -257.441228) (xy 366.624573 -257.477952)
			(xy 366.6551 -257.519969) (xy 366.678678 -257.566243) (xy 366.694726 -257.615637) (xy 366.702851 -257.666932)
			(xy 366.702851 -257.718868) (xy 366.694726 -257.770163) (xy 366.678678 -257.819557) (xy 366.6551 -257.865831)
			(xy 366.624573 -257.907848) (xy 366.587849 -257.944572) (xy 366.545833 -257.975098) (xy 366.499559 -257.998677)
			(xy 366.450165 -258.014726) (xy 366.39887 -258.022851) (xy 366.372902 -258.02336) (xy 366.347042 -258.022843)
			(xy 366.295951 -258.014798) (xy 366.246739 -257.99889) (xy 366.200607 -257.975506) (xy 366.158683 -257.945218)
			(xy 366.139984 -257.927348) (xy 366.130269 -257.918303) (xy 366.10726 -257.905091) (xy 366.081623 -257.898254)
			(xy 366.055089 -257.898254) (xy 366.029452 -257.905091) (xy 366.006443 -257.918303) (xy 365.996728 -257.927348)
			(xy 365.978028 -257.945217) (xy 365.936101 -257.975502) (xy 365.88997 -257.998887) (xy 365.840759 -258.014802)
			(xy 365.78967 -258.022859) (xy 365.76381 -258.02336) (xy 365.737841 -258.022866) (xy 365.686541 -258.014742)
			(xy 365.637144 -257.998694) (xy 365.590866 -257.975115) (xy 365.548846 -257.944587) (xy 365.51212 -257.907861)
			(xy 365.48159 -257.865842) (xy 365.45801 -257.819565) (xy 365.44196 -257.770168) (xy 365.433835 -257.718869)
			(xy 358.469898 -257.718869) (xy 358.495407 -257.737402) (xy 358.53213 -257.774125) (xy 358.562656 -257.816141)
			(xy 358.586234 -257.862415) (xy 358.602282 -257.911808) (xy 358.610407 -257.963103) (xy 358.610916 -257.98907)
			(xy 358.610407 -258.015037) (xy 358.602282 -258.066332) (xy 358.586234 -258.115725) (xy 358.562656 -258.161999)
			(xy 358.53213 -258.204015) (xy 358.495407 -258.240738) (xy 358.453391 -258.271264) (xy 358.407117 -258.294842)
			(xy 358.357724 -258.31089) (xy 358.306429 -258.319015) (xy 358.254495 -258.319015) (xy 358.2032 -258.31089)
			(xy 358.153807 -258.294842) (xy 358.107533 -258.271264) (xy 358.065517 -258.240738) (xy 358.028794 -258.204015)
			(xy 357.998268 -258.161999) (xy 357.97469 -258.115725) (xy 357.958642 -258.066332) (xy 357.950517 -258.015037)
			(xy 354.079384 -258.015037) (xy 354.029836 -258.02288) (xy 354.003864 -258.02336) (xy 353.978109 -258.022909)
			(xy 353.927221 -258.014922) (xy 353.87819 -257.999133) (xy 353.832205 -257.975923) (xy 353.79038 -257.945856)
			(xy 353.771708 -257.92811) (xy 353.762018 -257.919117) (xy 353.739086 -257.905985) (xy 353.713547 -257.89919)
			(xy 353.687121 -257.89919) (xy 353.661582 -257.905985) (xy 353.63865 -257.919117) (xy 353.62896 -257.92811)
			(xy 353.610299 -257.945865) (xy 353.568461 -257.975908) (xy 353.522471 -257.9991) (xy 353.473441 -258.014881)
			(xy 353.422557 -258.022868) (xy 353.396804 -258.02336) (xy 353.370835 -258.022865) (xy 353.319536 -258.014741)
			(xy 353.27014 -257.998692) (xy 353.223863 -257.975113) (xy 353.181844 -257.944585) (xy 353.145118 -257.907859)
			(xy 353.114589 -257.865841) (xy 353.09101 -257.819564) (xy 353.07496 -257.770168) (xy 353.066835 -257.718869)
			(xy 352.836787 -257.718869) (xy 352.834675 -257.745354) (xy 352.822235 -257.796482) (xy 352.801851 -257.844994)
			(xy 352.774039 -257.889663) (xy 352.7395 -257.929361) (xy 352.699107 -257.963085) (xy 352.653882 -257.989984)
			(xy 352.604966 -258.009377) (xy 352.553595 -258.020774) (xy 352.527362 -258.022852) (xy 352.520504 -258.023106)
			(xy 352.507804 -258.02336) (xy 352.484134 -258.022974) (xy 352.437275 -258.016252) (xy 352.391857 -258.002903)
			(xy 352.348813 -257.983199) (xy 352.309027 -257.957547) (xy 352.290888 -257.942334) (xy 352.279204 -257.932174)
			(xy 352.268204 -257.923916) (xy 352.242947 -257.913051) (xy 352.215704 -257.90934) (xy 352.188461 -257.913051)
			(xy 352.163204 -257.923916) (xy 352.152204 -257.932174) (xy 352.14052 -257.942334) (xy 352.122384 -257.957546)
			(xy 352.082583 -257.983169) (xy 352.039537 -258.002859) (xy 351.994124 -258.016214) (xy 351.947272 -258.02296)
			(xy 351.923604 -258.02336) (xy 351.910904 -258.023106) (xy 351.904046 -258.022852) (xy 351.898712 -258.022344)
			(xy 351.885145 -258.022396) (xy 351.858794 -258.028811) (xy 351.835063 -258.041939) (xy 351.815627 -258.060853)
			(xy 351.801857 -258.084217) (xy 351.794726 -258.110384) (xy 351.794318 -258.123944) (xy 351.794318 -259.578348)
			(xy 356.04323 -259.578348) (xy 356.043679 -259.553796) (xy 356.050919 -259.50523) (xy 356.065261 -259.458269)
			(xy 356.086391 -259.413945) (xy 356.113843 -259.373233) (xy 356.130098 -259.354828) (xy 356.139853 -259.343301)
			(xy 356.152869 -259.316077) (xy 356.157345 -259.286236) (xy 356.15289 -259.256391) (xy 356.139893 -259.229158)
			(xy 356.130098 -259.217668) (xy 356.113849 -259.199256) (xy 356.08638 -259.158553) (xy 356.065239 -259.114232)
			(xy 356.050894 -259.06727) (xy 356.043661 -259.018701) (xy 356.04323 -258.994148) (xy 356.043739 -258.968181)
			(xy 356.051864 -258.916886) (xy 356.067912 -258.867493) (xy 356.09149 -258.821219) (xy 356.122016 -258.779203)
			(xy 356.158739 -258.74248) (xy 356.200755 -258.711954) (xy 356.247029 -258.688376) (xy 356.296422 -258.672328)
			(xy 356.347717 -258.664203) (xy 356.399651 -258.664203) (xy 356.450946 -258.672328) (xy 356.500339 -258.688376)
			(xy 356.546613 -258.711954) (xy 356.588629 -258.74248) (xy 356.625352 -258.779203) (xy 356.655878 -258.821219)
			(xy 356.659897 -258.829107) (xy 361.239817 -258.829107) (xy 361.239817 -258.777173) (xy 361.247942 -258.725878)
			(xy 361.26399 -258.676485) (xy 361.287568 -258.630211) (xy 361.318094 -258.588195) (xy 361.354817 -258.551472)
			(xy 361.396833 -258.520946) (xy 361.443107 -258.497368) (xy 361.4925 -258.48132) (xy 361.543795 -258.473195)
			(xy 361.595729 -258.473195) (xy 361.647024 -258.48132) (xy 361.696417 -258.497368) (xy 361.742691 -258.520946)
			(xy 361.784707 -258.551472) (xy 361.82143 -258.588195) (xy 361.851956 -258.630211) (xy 361.875534 -258.676485)
			(xy 361.891582 -258.725878) (xy 361.899707 -258.777173) (xy 361.900216 -258.80314) (xy 361.899707 -258.829107)
			(xy 361.891582 -258.880402) (xy 361.875534 -258.929795) (xy 361.851956 -258.976069) (xy 361.82143 -259.018085)
			(xy 361.784707 -259.054808) (xy 361.742691 -259.085334) (xy 361.696417 -259.108912) (xy 361.647024 -259.12496)
			(xy 361.595729 -259.133085) (xy 361.543795 -259.133085) (xy 361.4925 -259.12496) (xy 361.443107 -259.108912)
			(xy 361.396833 -259.085334) (xy 361.354817 -259.054808) (xy 361.318094 -259.018085) (xy 361.287568 -258.976069)
			(xy 361.26399 -258.929795) (xy 361.247942 -258.880402) (xy 361.239817 -258.829107) (xy 356.659897 -258.829107)
			(xy 356.679456 -258.867493) (xy 356.695504 -258.916886) (xy 356.703629 -258.968181) (xy 356.704138 -258.994148)
			(xy 356.703695 -259.0187) (xy 356.696455 -259.067267) (xy 356.682111 -259.114228) (xy 356.66098 -259.158552)
			(xy 356.633526 -259.199264) (xy 356.61727 -259.217668) (xy 356.607416 -259.229119) (xy 356.594402 -259.256369)
			(xy 356.58994 -259.286236) (xy 356.594422 -259.316099) (xy 356.607456 -259.34334) (xy 356.61727 -259.354828)
			(xy 356.633512 -259.373246) (xy 356.660983 -259.413947) (xy 356.682126 -259.458266) (xy 356.696472 -259.505228)
			(xy 356.703707 -259.553796) (xy 356.704138 -259.578348) (xy 356.703629 -259.604315) (xy 356.697514 -259.642923)
			(xy 357.950517 -259.642923) (xy 357.950517 -259.590989) (xy 357.958642 -259.539694) (xy 357.97469 -259.490301)
			(xy 357.998268 -259.444027) (xy 358.028794 -259.402011) (xy 358.065517 -259.365288) (xy 358.107533 -259.334762)
			(xy 358.153807 -259.311184) (xy 358.2032 -259.295136) (xy 358.254495 -259.287011) (xy 358.306429 -259.287011)
			(xy 358.357724 -259.295136) (xy 358.407117 -259.311184) (xy 358.453391 -259.334762) (xy 358.495407 -259.365288)
			(xy 358.53213 -259.402011) (xy 358.562656 -259.444027) (xy 358.586234 -259.490301) (xy 358.602282 -259.539694)
			(xy 358.610407 -259.590989) (xy 358.610916 -259.616956) (xy 358.610563 -259.63499) (xy 363.035596 -259.63499)
			(xy 363.036054 -259.610439) (xy 363.043289 -259.561872) (xy 363.057628 -259.51491) (xy 363.078756 -259.470586)
			(xy 363.106208 -259.429874) (xy 363.122464 -259.41147) (xy 363.132278 -259.399989) (xy 363.145292 -259.372749)
			(xy 363.149759 -259.342893) (xy 363.145288 -259.313037) (xy 363.13227 -259.285799) (xy 363.122464 -259.27431)
			(xy 363.106198 -259.255912) (xy 363.078729 -259.215206) (xy 363.057591 -259.170882) (xy 363.04325 -259.123916)
			(xy 363.036023 -259.075344) (xy 363.035596 -259.05079) (xy 363.036105 -259.024823) (xy 363.04423 -258.973528)
			(xy 363.060278 -258.924135) (xy 363.083856 -258.877861) (xy 363.114382 -258.835845) (xy 363.151105 -258.799122)
			(xy 363.193121 -258.768596) (xy 363.239395 -258.745018) (xy 363.288788 -258.72897) (xy 363.340083 -258.720845)
			(xy 363.392017 -258.720845) (xy 363.443312 -258.72897) (xy 363.492705 -258.745018) (xy 363.538979 -258.768596)
			(xy 363.580995 -258.799122) (xy 363.617718 -258.835845) (xy 363.648244 -258.877861) (xy 363.671822 -258.924135)
			(xy 363.68787 -258.973528) (xy 363.695995 -259.024823) (xy 363.696504 -259.05079) (xy 363.696095 -259.075343)
			(xy 363.688848 -259.123912) (xy 363.674497 -259.170874) (xy 363.653358 -259.215198) (xy 363.625896 -259.255907)
			(xy 363.609636 -259.27431) (xy 363.599841 -259.285806) (xy 363.586825 -259.313041) (xy 363.582354 -259.342893)
			(xy 363.586821 -259.372745) (xy 363.599833 -259.399981) (xy 363.609636 -259.41147) (xy 363.625892 -259.429876)
			(xy 363.653363 -259.470579) (xy 363.674503 -259.514902) (xy 363.688846 -259.561866) (xy 363.696076 -259.610437)
			(xy 363.696504 -259.63499) (xy 363.695995 -259.660957) (xy 363.68787 -259.712252) (xy 363.671822 -259.761645)
			(xy 363.648244 -259.807919) (xy 363.617718 -259.849935) (xy 363.580995 -259.886658) (xy 363.538979 -259.917184)
			(xy 363.492705 -259.940762) (xy 363.443312 -259.95681) (xy 363.392017 -259.964935) (xy 363.340083 -259.964935)
			(xy 363.288788 -259.95681) (xy 363.239395 -259.940762) (xy 363.193121 -259.917184) (xy 363.151105 -259.886658)
			(xy 363.114382 -259.849935) (xy 363.083856 -259.807919) (xy 363.060278 -259.761645) (xy 363.04423 -259.712252)
			(xy 363.036105 -259.660957) (xy 363.035596 -259.63499) (xy 358.610563 -259.63499) (xy 358.610407 -259.642923)
			(xy 358.602282 -259.694218) (xy 358.586234 -259.743611) (xy 358.562656 -259.789885) (xy 358.53213 -259.831901)
			(xy 358.495407 -259.868624) (xy 358.453391 -259.89915) (xy 358.407117 -259.922728) (xy 358.357724 -259.938776)
			(xy 358.306429 -259.946901) (xy 358.254495 -259.946901) (xy 358.2032 -259.938776) (xy 358.153807 -259.922728)
			(xy 358.107533 -259.89915) (xy 358.065517 -259.868624) (xy 358.028794 -259.831901) (xy 357.998268 -259.789885)
			(xy 357.97469 -259.743611) (xy 357.958642 -259.694218) (xy 357.950517 -259.642923) (xy 356.697514 -259.642923)
			(xy 356.695504 -259.65561) (xy 356.679456 -259.705003) (xy 356.655878 -259.751277) (xy 356.625352 -259.793293)
			(xy 356.588629 -259.830016) (xy 356.546613 -259.860542) (xy 356.500339 -259.88412) (xy 356.450946 -259.900168)
			(xy 356.399651 -259.908293) (xy 356.347717 -259.908293) (xy 356.296422 -259.900168) (xy 356.247029 -259.88412)
			(xy 356.200755 -259.860542) (xy 356.158739 -259.830016) (xy 356.122016 -259.793293) (xy 356.09149 -259.751277)
			(xy 356.067912 -259.705003) (xy 356.051864 -259.65561) (xy 356.043739 -259.604315) (xy 356.04323 -259.578348)
			(xy 351.794318 -259.578348) (xy 351.794318 -260.456739) (xy 361.239817 -260.456739) (xy 361.239817 -260.404805)
			(xy 361.247942 -260.35351) (xy 361.26399 -260.304117) (xy 361.287568 -260.257843) (xy 361.318094 -260.215827)
			(xy 361.354817 -260.179104) (xy 361.396833 -260.148578) (xy 361.443107 -260.125) (xy 361.4925 -260.108952)
			(xy 361.543795 -260.100827) (xy 361.595729 -260.100827) (xy 361.647024 -260.108952) (xy 361.696417 -260.125)
			(xy 361.742691 -260.148578) (xy 361.784707 -260.179104) (xy 361.82143 -260.215827) (xy 361.851956 -260.257843)
			(xy 361.875534 -260.304117) (xy 361.891582 -260.35351) (xy 361.899707 -260.404805) (xy 361.900216 -260.430772)
			(xy 361.899707 -260.456739) (xy 361.891582 -260.508034) (xy 361.875534 -260.557427) (xy 361.851956 -260.603701)
			(xy 361.82143 -260.645717) (xy 361.784707 -260.68244) (xy 361.742691 -260.712966) (xy 361.696417 -260.736544)
			(xy 361.647024 -260.752592) (xy 361.595729 -260.760717) (xy 361.543795 -260.760717) (xy 361.4925 -260.752592)
			(xy 361.443107 -260.736544) (xy 361.396833 -260.712966) (xy 361.354817 -260.68244) (xy 361.318094 -260.645717)
			(xy 361.287568 -260.603701) (xy 361.26399 -260.557427) (xy 361.247942 -260.508034) (xy 361.239817 -260.456739)
			(xy 351.794318 -260.456739) (xy 351.794318 -261.062216) (xy 351.501666 -261.354868) (xy 352.247945 -261.354868)
			(xy 352.247945 -261.302932) (xy 352.25607 -261.251634) (xy 352.272119 -261.202239) (xy 352.295698 -261.155963)
			(xy 352.326227 -261.113946) (xy 352.362952 -261.077221) (xy 352.40497 -261.046694) (xy 352.451247 -261.023116)
			(xy 352.500642 -261.007068) (xy 352.55194 -260.998944) (xy 352.577908 -260.998462) (xy 352.605207 -260.99899)
			(xy 352.659061 -261.007973) (xy 352.710703 -261.025694) (xy 352.758726 -261.05167) (xy 352.801822 -261.085192)
			(xy 352.820732 -261.104888) (xy 352.830565 -261.114868) (xy 352.854449 -261.129494) (xy 352.881405 -261.137093)
			(xy 352.909411 -261.137093) (xy 352.936367 -261.129494) (xy 352.960251 -261.114868) (xy 352.970084 -261.104888)
			(xy 352.987229 -261.086943) (xy 353.025945 -261.055891) (xy 353.068872 -261.030983) (xy 353.115043 -261.01278)
			(xy 353.163418 -261.001691) (xy 353.212908 -260.997967) (xy 353.262398 -261.001691) (xy 353.310773 -261.01278)
			(xy 353.356944 -261.030983) (xy 353.399871 -261.055891) (xy 353.438587 -261.086943) (xy 353.455732 -261.104888)
			(xy 353.465565 -261.114868) (xy 353.489449 -261.129494) (xy 353.516405 -261.137093) (xy 353.544411 -261.137093)
			(xy 353.571367 -261.129494) (xy 353.595251 -261.114868) (xy 353.605084 -261.104888) (xy 353.622229 -261.086943)
			(xy 353.660945 -261.055891) (xy 353.703872 -261.030983) (xy 353.750043 -261.01278) (xy 353.798418 -261.001691)
			(xy 353.847908 -260.997967) (xy 353.897398 -261.001691) (xy 353.945773 -261.01278) (xy 353.991944 -261.030983)
			(xy 354.034871 -261.055891) (xy 354.073587 -261.086943) (xy 354.090732 -261.104888) (xy 354.100565 -261.114868)
			(xy 354.124449 -261.129494) (xy 354.151405 -261.137093) (xy 354.179411 -261.137093) (xy 354.206367 -261.129494)
			(xy 354.230251 -261.114868) (xy 354.240084 -261.104888) (xy 354.257229 -261.086943) (xy 354.295945 -261.055891)
			(xy 354.338872 -261.030983) (xy 354.385043 -261.01278) (xy 354.433418 -261.001691) (xy 354.482908 -260.997967)
			(xy 354.532398 -261.001691) (xy 354.580773 -261.01278) (xy 354.626944 -261.030983) (xy 354.669871 -261.055891)
			(xy 354.708587 -261.086943) (xy 354.725732 -261.104888) (xy 354.735565 -261.114868) (xy 354.759449 -261.129494)
			(xy 354.786405 -261.137093) (xy 354.814411 -261.137093) (xy 354.841367 -261.129494) (xy 354.865251 -261.114868)
			(xy 354.875084 -261.104888) (xy 354.893992 -261.085191) (xy 354.937092 -261.051681) (xy 354.985117 -261.025715)
			(xy 355.036759 -261.008002) (xy 355.09061 -260.999024) (xy 355.117908 -260.998462) (xy 355.143876 -260.99894)
			(xy 355.195173 -261.007066) (xy 355.244566 -261.023116) (xy 355.290842 -261.046695) (xy 355.332858 -261.077223)
			(xy 355.369582 -261.113948) (xy 355.400109 -261.155965) (xy 355.423687 -261.202241) (xy 355.439736 -261.251635)
			(xy 355.442773 -261.270809) (xy 357.950517 -261.270809) (xy 357.950517 -261.218875) (xy 357.958642 -261.16758)
			(xy 357.97469 -261.118187) (xy 357.998268 -261.071913) (xy 358.028794 -261.029897) (xy 358.065517 -260.993174)
			(xy 358.107533 -260.962648) (xy 358.153807 -260.93907) (xy 358.2032 -260.923022) (xy 358.254495 -260.914897)
			(xy 358.306429 -260.914897) (xy 358.357724 -260.923022) (xy 358.407117 -260.93907) (xy 358.453391 -260.962648)
			(xy 358.495407 -260.993174) (xy 358.53213 -261.029897) (xy 358.562656 -261.071913) (xy 358.586234 -261.118187)
			(xy 358.602282 -261.16758) (xy 358.610407 -261.218875) (xy 358.610916 -261.244842) (xy 358.610407 -261.270809)
			(xy 358.602282 -261.322104) (xy 358.586234 -261.371497) (xy 358.562656 -261.417771) (xy 358.53213 -261.459787)
			(xy 358.495407 -261.49651) (xy 358.453391 -261.527036) (xy 358.407117 -261.550614) (xy 358.357724 -261.566662)
			(xy 358.306429 -261.574787) (xy 358.254495 -261.574787) (xy 358.2032 -261.566662) (xy 358.153807 -261.550614)
			(xy 358.107533 -261.527036) (xy 358.065517 -261.49651) (xy 358.028794 -261.459787) (xy 357.998268 -261.417771)
			(xy 357.97469 -261.371497) (xy 357.958642 -261.322104) (xy 357.950517 -261.270809) (xy 355.442773 -261.270809)
			(xy 355.447861 -261.302932) (xy 355.447861 -261.354868) (xy 355.439736 -261.406165) (xy 355.423687 -261.455559)
			(xy 355.400109 -261.501835) (xy 355.369582 -261.543852) (xy 355.332858 -261.580577) (xy 355.290842 -261.611105)
			(xy 355.244566 -261.634684) (xy 355.195173 -261.650734) (xy 355.143876 -261.65886) (xy 355.117908 -261.65937)
			(xy 355.09061 -261.658821) (xy 355.036758 -261.649842) (xy 354.985116 -261.632125) (xy 354.937093 -261.606154)
			(xy 354.893996 -261.572638) (xy 354.875084 -261.552944) (xy 354.865251 -261.542964) (xy 354.841367 -261.528338)
			(xy 354.814411 -261.520739) (xy 354.786405 -261.520739) (xy 354.759449 -261.528338) (xy 354.735565 -261.542964)
			(xy 354.725732 -261.552944) (xy 354.708587 -261.570889) (xy 354.669871 -261.601941) (xy 354.626944 -261.626849)
			(xy 354.580773 -261.645052) (xy 354.532398 -261.656141) (xy 354.482908 -261.659865) (xy 354.433418 -261.656141)
			(xy 354.385043 -261.645052) (xy 354.338872 -261.626849) (xy 354.295945 -261.601941) (xy 354.257229 -261.570889)
			(xy 354.240084 -261.552944) (xy 354.230251 -261.542964) (xy 354.206367 -261.528338) (xy 354.179411 -261.520739)
			(xy 354.151405 -261.520739) (xy 354.124449 -261.528338) (xy 354.100565 -261.542964) (xy 354.090732 -261.552944)
			(xy 354.073587 -261.570889) (xy 354.034871 -261.601941) (xy 353.991944 -261.626849) (xy 353.945773 -261.645052)
			(xy 353.897398 -261.656141) (xy 353.847908 -261.659865) (xy 353.798418 -261.656141) (xy 353.750043 -261.645052)
			(xy 353.703872 -261.626849) (xy 353.660945 -261.601941) (xy 353.622229 -261.570889) (xy 353.605084 -261.552944)
			(xy 353.595251 -261.542964) (xy 353.571367 -261.528338) (xy 353.544411 -261.520739) (xy 353.516405 -261.520739)
			(xy 353.489449 -261.528338) (xy 353.465565 -261.542964) (xy 353.455732 -261.552944) (xy 353.438587 -261.570889)
			(xy 353.399871 -261.601941) (xy 353.356944 -261.626849) (xy 353.310773 -261.645052) (xy 353.262398 -261.656141)
			(xy 353.212908 -261.659865) (xy 353.163418 -261.656141) (xy 353.115043 -261.645052) (xy 353.068872 -261.626849)
			(xy 353.025945 -261.601941) (xy 352.987229 -261.570889) (xy 352.970084 -261.552944) (xy 352.960251 -261.542964)
			(xy 352.936367 -261.528338) (xy 352.909411 -261.520739) (xy 352.881405 -261.520739) (xy 352.854449 -261.528338)
			(xy 352.830565 -261.542964) (xy 352.820732 -261.552944) (xy 352.801823 -261.572639) (xy 352.758722 -261.606149)
			(xy 352.710697 -261.632114) (xy 352.659056 -261.649827) (xy 352.605205 -261.658807) (xy 352.577908 -261.65937)
			(xy 352.55194 -261.658856) (xy 352.500642 -261.650732) (xy 352.451247 -261.634684) (xy 352.40497 -261.611106)
			(xy 352.362952 -261.580579) (xy 352.326227 -261.543854) (xy 352.295698 -261.501837) (xy 352.272119 -261.455561)
			(xy 352.25607 -261.406166) (xy 352.247945 -261.354868) (xy 351.501666 -261.354868) (xy 350.922844 -261.93369)
			(xy 350.922844 -262.70458) (xy 351.32391 -262.70458) (xy 351.324358 -262.680028) (xy 351.331595 -262.631461)
			(xy 351.345936 -262.584499) (xy 351.367067 -262.540175) (xy 351.394521 -262.499464) (xy 351.410778 -262.48106)
			(xy 351.420601 -262.469586) (xy 351.433612 -262.442343) (xy 351.438076 -262.412485) (xy 351.433603 -262.382628)
			(xy 351.420584 -262.355389) (xy 351.410778 -262.3439) (xy 351.394494 -262.325518) (xy 351.36703 -262.284807)
			(xy 351.345897 -262.240478) (xy 351.33156 -262.193509) (xy 351.324336 -262.144935) (xy 351.32391 -262.12038)
			(xy 351.324419 -262.094413) (xy 351.332544 -262.043118) (xy 351.348592 -261.993725) (xy 351.37217 -261.947451)
			(xy 351.402696 -261.905435) (xy 351.439419 -261.868712) (xy 351.481435 -261.838186) (xy 351.527709 -261.814608)
			(xy 351.577102 -261.79856) (xy 351.628397 -261.790435) (xy 351.680331 -261.790435) (xy 351.731626 -261.79856)
			(xy 351.781019 -261.814608) (xy 351.827293 -261.838186) (xy 351.869309 -261.868712) (xy 351.906032 -261.905435)
			(xy 351.936558 -261.947451) (xy 351.960136 -261.993725) (xy 351.976184 -262.043118) (xy 351.982759 -262.084625)
			(xy 361.239817 -262.084625) (xy 361.239817 -262.032691) (xy 361.247942 -261.981396) (xy 361.26399 -261.932003)
			(xy 361.287568 -261.885729) (xy 361.318094 -261.843713) (xy 361.354817 -261.80699) (xy 361.396833 -261.776464)
			(xy 361.443107 -261.752886) (xy 361.4925 -261.736838) (xy 361.543795 -261.728713) (xy 361.595729 -261.728713)
			(xy 361.647024 -261.736838) (xy 361.696417 -261.752886) (xy 361.742691 -261.776464) (xy 361.784707 -261.80699)
			(xy 361.82143 -261.843713) (xy 361.851956 -261.885729) (xy 361.875534 -261.932003) (xy 361.891582 -261.981396)
			(xy 361.899707 -262.032691) (xy 361.900216 -262.058658) (xy 361.899707 -262.084625) (xy 361.891582 -262.13592)
			(xy 361.875534 -262.185313) (xy 361.851956 -262.231587) (xy 361.82143 -262.273603) (xy 361.784707 -262.310326)
			(xy 361.742691 -262.340852) (xy 361.696417 -262.36443) (xy 361.647024 -262.380478) (xy 361.595729 -262.388603)
			(xy 361.543795 -262.388603) (xy 361.4925 -262.380478) (xy 361.443107 -262.36443) (xy 361.396833 -262.340852)
			(xy 361.354817 -262.310326) (xy 361.318094 -262.273603) (xy 361.287568 -262.231587) (xy 361.26399 -262.185313)
			(xy 361.247942 -262.13592) (xy 361.239817 -262.084625) (xy 351.982759 -262.084625) (xy 351.984309 -262.094413)
			(xy 351.984818 -262.12038) (xy 351.984399 -262.144933) (xy 351.977154 -262.193501) (xy 351.962805 -262.240463)
			(xy 351.941669 -262.284787) (xy 351.914209 -262.325497) (xy 351.89795 -262.3439) (xy 351.888164 -262.355403)
			(xy 351.875145 -262.382635) (xy 351.870671 -262.412485) (xy 351.875136 -262.442337) (xy 351.888147 -262.469572)
			(xy 351.89795 -262.48106) (xy 351.914204 -262.499468) (xy 351.941674 -262.540171) (xy 351.962815 -262.584493)
			(xy 351.977158 -262.631457) (xy 351.984389 -262.680027) (xy 351.984818 -262.70458) (xy 351.984309 -262.730547)
			(xy 351.976184 -262.781842) (xy 351.960136 -262.831235) (xy 351.936558 -262.877509) (xy 351.92135 -262.898441)
			(xy 357.950517 -262.898441) (xy 357.950517 -262.846507) (xy 357.958642 -262.795212) (xy 357.97469 -262.745819)
			(xy 357.998268 -262.699545) (xy 358.028794 -262.657529) (xy 358.065517 -262.620806) (xy 358.107533 -262.59028)
			(xy 358.153807 -262.566702) (xy 358.2032 -262.550654) (xy 358.254495 -262.542529) (xy 358.306429 -262.542529)
			(xy 358.357724 -262.550654) (xy 358.407117 -262.566702) (xy 358.453391 -262.59028) (xy 358.495407 -262.620806)
			(xy 358.53213 -262.657529) (xy 358.562656 -262.699545) (xy 358.586234 -262.745819) (xy 358.602282 -262.795212)
			(xy 358.610407 -262.846507) (xy 358.610916 -262.872474) (xy 358.610407 -262.898441) (xy 358.602282 -262.949736)
			(xy 358.586234 -262.999129) (xy 358.562656 -263.045403) (xy 358.53213 -263.087419) (xy 358.495407 -263.124142)
			(xy 358.453391 -263.154668) (xy 358.407117 -263.178246) (xy 358.357724 -263.194294) (xy 358.306429 -263.202419)
			(xy 358.254495 -263.202419) (xy 358.2032 -263.194294) (xy 358.153807 -263.178246) (xy 358.107533 -263.154668)
			(xy 358.065517 -263.124142) (xy 358.028794 -263.087419) (xy 357.998268 -263.045403) (xy 357.97469 -262.999129)
			(xy 357.958642 -262.949736) (xy 357.950517 -262.898441) (xy 351.92135 -262.898441) (xy 351.906032 -262.919525)
			(xy 351.869309 -262.956248) (xy 351.827293 -262.986774) (xy 351.781019 -263.010352) (xy 351.731626 -263.0264)
			(xy 351.680331 -263.034525) (xy 351.628397 -263.034525) (xy 351.577102 -263.0264) (xy 351.527709 -263.010352)
			(xy 351.481435 -262.986774) (xy 351.439419 -262.956248) (xy 351.402696 -262.919525) (xy 351.37217 -262.877509)
			(xy 351.348592 -262.831235) (xy 351.332544 -262.781842) (xy 351.324419 -262.730547) (xy 351.32391 -262.70458)
			(xy 350.922844 -262.70458) (xy 350.922844 -263.712511) (xy 361.239817 -263.712511) (xy 361.239817 -263.660577)
			(xy 361.247942 -263.609282) (xy 361.26399 -263.559889) (xy 361.287568 -263.513615) (xy 361.318094 -263.471599)
			(xy 361.354817 -263.434876) (xy 361.396833 -263.40435) (xy 361.443107 -263.380772) (xy 361.4925 -263.364724)
			(xy 361.543795 -263.356599) (xy 361.595729 -263.356599) (xy 361.647024 -263.364724) (xy 361.696417 -263.380772)
			(xy 361.742691 -263.40435) (xy 361.784707 -263.434876) (xy 361.82143 -263.471599) (xy 361.851956 -263.513615)
			(xy 361.875534 -263.559889) (xy 361.891582 -263.609282) (xy 361.899707 -263.660577) (xy 361.900216 -263.686544)
			(xy 361.899707 -263.712511) (xy 361.891582 -263.763806) (xy 361.875534 -263.813199) (xy 361.851956 -263.859473)
			(xy 361.82143 -263.901489) (xy 361.784707 -263.938212) (xy 361.742691 -263.968738) (xy 361.696417 -263.992316)
			(xy 361.647024 -264.008364) (xy 361.595729 -264.016489) (xy 361.543795 -264.016489) (xy 361.4925 -264.008364)
			(xy 361.443107 -263.992316) (xy 361.396833 -263.968738) (xy 361.354817 -263.938212) (xy 361.318094 -263.901489)
			(xy 361.287568 -263.859473) (xy 361.26399 -263.813199) (xy 361.247942 -263.763806) (xy 361.239817 -263.712511)
			(xy 350.922844 -263.712511) (xy 350.922844 -264.211562) (xy 350.944541 -264.224193) (xy 350.98419 -264.254987)
			(xy 351.018728 -264.291421) (xy 351.047363 -264.332656) (xy 351.069437 -264.377746) (xy 351.084442 -264.425654)
			(xy 351.092033 -264.475279) (xy 351.092035 -264.525482) (xy 351.091906 -264.526327) (xy 351.371917 -264.526327)
			(xy 351.371917 -264.474393) (xy 351.380042 -264.423098) (xy 351.39609 -264.373705) (xy 351.419668 -264.327431)
			(xy 351.450194 -264.285415) (xy 351.486917 -264.248692) (xy 351.528933 -264.218166) (xy 351.575207 -264.194588)
			(xy 351.6246 -264.17854) (xy 351.675895 -264.170415) (xy 351.727829 -264.170415) (xy 351.779124 -264.17854)
			(xy 351.828517 -264.194588) (xy 351.874791 -264.218166) (xy 351.916807 -264.248692) (xy 351.95353 -264.285415)
			(xy 351.984056 -264.327431) (xy 352.007634 -264.373705) (xy 352.023682 -264.423098) (xy 352.031807 -264.474393)
			(xy 352.032316 -264.50036) (xy 352.031807 -264.526327) (xy 352.311717 -264.526327) (xy 352.311717 -264.474393)
			(xy 352.319842 -264.423098) (xy 352.33589 -264.373705) (xy 352.359468 -264.327431) (xy 352.389994 -264.285415)
			(xy 352.426717 -264.248692) (xy 352.468733 -264.218166) (xy 352.515007 -264.194588) (xy 352.5644 -264.17854)
			(xy 352.615695 -264.170415) (xy 352.667629 -264.170415) (xy 352.718924 -264.17854) (xy 352.768317 -264.194588)
			(xy 352.814591 -264.218166) (xy 352.856607 -264.248692) (xy 352.89333 -264.285415) (xy 352.923856 -264.327431)
			(xy 352.947434 -264.373705) (xy 352.963482 -264.423098) (xy 352.971607 -264.474393) (xy 352.972116 -264.50036)
			(xy 352.971607 -264.526327) (xy 353.251517 -264.526327) (xy 353.251517 -264.474393) (xy 353.259642 -264.423098)
			(xy 353.27569 -264.373705) (xy 353.299268 -264.327431) (xy 353.329794 -264.285415) (xy 353.366517 -264.248692)
			(xy 353.408533 -264.218166) (xy 353.454807 -264.194588) (xy 353.5042 -264.17854) (xy 353.555495 -264.170415)
			(xy 353.607429 -264.170415) (xy 353.658724 -264.17854) (xy 353.708117 -264.194588) (xy 353.754391 -264.218166)
			(xy 353.796407 -264.248692) (xy 353.83313 -264.285415) (xy 353.863656 -264.327431) (xy 353.887234 -264.373705)
			(xy 353.903282 -264.423098) (xy 353.911407 -264.474393) (xy 353.911916 -264.50036) (xy 353.911407 -264.526327)
			(xy 354.191317 -264.526327) (xy 354.191317 -264.474393) (xy 354.199442 -264.423098) (xy 354.21549 -264.373705)
			(xy 354.239068 -264.327431) (xy 354.269594 -264.285415) (xy 354.306317 -264.248692) (xy 354.348333 -264.218166)
			(xy 354.394607 -264.194588) (xy 354.444 -264.17854) (xy 354.495295 -264.170415) (xy 354.547229 -264.170415)
			(xy 354.598524 -264.17854) (xy 354.647917 -264.194588) (xy 354.694191 -264.218166) (xy 354.736207 -264.248692)
			(xy 354.77293 -264.285415) (xy 354.803456 -264.327431) (xy 354.827034 -264.373705) (xy 354.843082 -264.423098)
			(xy 354.851207 -264.474393) (xy 354.851716 -264.50036) (xy 354.851207 -264.526327) (xy 355.131371 -264.526327)
			(xy 355.131371 -264.474393) (xy 355.139496 -264.423098) (xy 355.155544 -264.373705) (xy 355.179122 -264.327431)
			(xy 355.209648 -264.285415) (xy 355.246371 -264.248692) (xy 355.288387 -264.218166) (xy 355.334661 -264.194588)
			(xy 355.384054 -264.17854) (xy 355.435349 -264.170415) (xy 355.487283 -264.170415) (xy 355.538578 -264.17854)
			(xy 355.587971 -264.194588) (xy 355.634245 -264.218166) (xy 355.676261 -264.248692) (xy 355.712984 -264.285415)
			(xy 355.74351 -264.327431) (xy 355.767088 -264.373705) (xy 355.783136 -264.423098) (xy 355.791261 -264.474393)
			(xy 355.79177 -264.50036) (xy 355.791261 -264.526327) (xy 356.071171 -264.526327) (xy 356.071171 -264.474393)
			(xy 356.079296 -264.423098) (xy 356.095344 -264.373705) (xy 356.118922 -264.327431) (xy 356.149448 -264.285415)
			(xy 356.186171 -264.248692) (xy 356.228187 -264.218166) (xy 356.274461 -264.194588) (xy 356.323854 -264.17854)
			(xy 356.375149 -264.170415) (xy 356.427083 -264.170415) (xy 356.478378 -264.17854) (xy 356.527771 -264.194588)
			(xy 356.574045 -264.218166) (xy 356.616061 -264.248692) (xy 356.652784 -264.285415) (xy 356.68331 -264.327431)
			(xy 356.706888 -264.373705) (xy 356.722936 -264.423098) (xy 356.731061 -264.474393) (xy 356.73157 -264.50036)
			(xy 356.731061 -264.526327) (xy 362.649517 -264.526327) (xy 362.649517 -264.474393) (xy 362.657642 -264.423098)
			(xy 362.67369 -264.373705) (xy 362.697268 -264.327431) (xy 362.727794 -264.285415) (xy 362.764517 -264.248692)
			(xy 362.806533 -264.218166) (xy 362.852807 -264.194588) (xy 362.9022 -264.17854) (xy 362.953495 -264.170415)
			(xy 363.005429 -264.170415) (xy 363.056724 -264.17854) (xy 363.106117 -264.194588) (xy 363.152391 -264.218166)
			(xy 363.194407 -264.248692) (xy 363.23113 -264.285415) (xy 363.261656 -264.327431) (xy 363.285234 -264.373705)
			(xy 363.301282 -264.423098) (xy 363.309407 -264.474393) (xy 363.309916 -264.50036) (xy 363.309407 -264.526327)
			(xy 363.301282 -264.577622) (xy 363.285234 -264.627015) (xy 363.261656 -264.673289) (xy 363.23113 -264.715305)
			(xy 363.194407 -264.752028) (xy 363.152391 -264.782554) (xy 363.106117 -264.806132) (xy 363.056724 -264.82218)
			(xy 363.005429 -264.830305) (xy 362.953495 -264.830305) (xy 362.9022 -264.82218) (xy 362.852807 -264.806132)
			(xy 362.806533 -264.782554) (xy 362.764517 -264.752028) (xy 362.727794 -264.715305) (xy 362.697268 -264.673289)
			(xy 362.67369 -264.627015) (xy 362.657642 -264.577622) (xy 362.649517 -264.526327) (xy 356.731061 -264.526327)
			(xy 356.722936 -264.577622) (xy 356.706888 -264.627015) (xy 356.68331 -264.673289) (xy 356.652784 -264.715305)
			(xy 356.616061 -264.752028) (xy 356.574045 -264.782554) (xy 356.527771 -264.806132) (xy 356.478378 -264.82218)
			(xy 356.427083 -264.830305) (xy 356.375149 -264.830305) (xy 356.323854 -264.82218) (xy 356.274461 -264.806132)
			(xy 356.228187 -264.782554) (xy 356.186171 -264.752028) (xy 356.149448 -264.715305) (xy 356.118922 -264.673289)
			(xy 356.095344 -264.627015) (xy 356.079296 -264.577622) (xy 356.071171 -264.526327) (xy 355.791261 -264.526327)
			(xy 355.783136 -264.577622) (xy 355.767088 -264.627015) (xy 355.74351 -264.673289) (xy 355.712984 -264.715305)
			(xy 355.676261 -264.752028) (xy 355.634245 -264.782554) (xy 355.587971 -264.806132) (xy 355.538578 -264.82218)
			(xy 355.487283 -264.830305) (xy 355.435349 -264.830305) (xy 355.384054 -264.82218) (xy 355.334661 -264.806132)
			(xy 355.288387 -264.782554) (xy 355.246371 -264.752028) (xy 355.209648 -264.715305) (xy 355.179122 -264.673289)
			(xy 355.155544 -264.627015) (xy 355.139496 -264.577622) (xy 355.131371 -264.526327) (xy 354.851207 -264.526327)
			(xy 354.843082 -264.577622) (xy 354.827034 -264.627015) (xy 354.803456 -264.673289) (xy 354.77293 -264.715305)
			(xy 354.736207 -264.752028) (xy 354.694191 -264.782554) (xy 354.647917 -264.806132) (xy 354.598524 -264.82218)
			(xy 354.547229 -264.830305) (xy 354.495295 -264.830305) (xy 354.444 -264.82218) (xy 354.394607 -264.806132)
			(xy 354.348333 -264.782554) (xy 354.306317 -264.752028) (xy 354.269594 -264.715305) (xy 354.239068 -264.673289)
			(xy 354.21549 -264.627015) (xy 354.199442 -264.577622) (xy 354.191317 -264.526327) (xy 353.911407 -264.526327)
			(xy 353.903282 -264.577622) (xy 353.887234 -264.627015) (xy 353.863656 -264.673289) (xy 353.83313 -264.715305)
			(xy 353.796407 -264.752028) (xy 353.754391 -264.782554) (xy 353.708117 -264.806132) (xy 353.658724 -264.82218)
			(xy 353.607429 -264.830305) (xy 353.555495 -264.830305) (xy 353.5042 -264.82218) (xy 353.454807 -264.806132)
			(xy 353.408533 -264.782554) (xy 353.366517 -264.752028) (xy 353.329794 -264.715305) (xy 353.299268 -264.673289)
			(xy 353.27569 -264.627015) (xy 353.259642 -264.577622) (xy 353.251517 -264.526327) (xy 352.971607 -264.526327)
			(xy 352.963482 -264.577622) (xy 352.947434 -264.627015) (xy 352.923856 -264.673289) (xy 352.89333 -264.715305)
			(xy 352.856607 -264.752028) (xy 352.814591 -264.782554) (xy 352.768317 -264.806132) (xy 352.718924 -264.82218)
			(xy 352.667629 -264.830305) (xy 352.615695 -264.830305) (xy 352.5644 -264.82218) (xy 352.515007 -264.806132)
			(xy 352.468733 -264.782554) (xy 352.426717 -264.752028) (xy 352.389994 -264.715305) (xy 352.359468 -264.673289)
			(xy 352.33589 -264.627015) (xy 352.319842 -264.577622) (xy 352.311717 -264.526327) (xy 352.031807 -264.526327)
			(xy 352.023682 -264.577622) (xy 352.007634 -264.627015) (xy 351.984056 -264.673289) (xy 351.95353 -264.715305)
			(xy 351.916807 -264.752028) (xy 351.874791 -264.782554) (xy 351.828517 -264.806132) (xy 351.779124 -264.82218)
			(xy 351.727829 -264.830305) (xy 351.675895 -264.830305) (xy 351.6246 -264.82218) (xy 351.575207 -264.806132)
			(xy 351.528933 -264.782554) (xy 351.486917 -264.752028) (xy 351.450194 -264.715305) (xy 351.419668 -264.673289)
			(xy 351.39609 -264.627015) (xy 351.380042 -264.577622) (xy 351.371917 -264.526327) (xy 351.091906 -264.526327)
			(xy 351.08445 -264.575108) (xy 351.069451 -264.623018) (xy 351.047383 -264.66811) (xy 351.018753 -264.709349)
			(xy 350.984219 -264.745787) (xy 350.944573 -264.776586) (xy 350.922844 -264.789158) (xy 350.922844 -264.935462)
			(xy 350.923386 -264.950258) (xy 350.931945 -264.978588) (xy 350.948266 -265.003275) (xy 350.970981 -265.022245)
			(xy 350.99818 -265.033907) (xy 351.027582 -265.03728) (xy 351.056716 -265.032082) (xy 351.070164 -265.025886)
			(xy 351.078546 -265.021568) (xy 351.102117 -265.009766) (xy 351.152084 -264.992984) (xy 351.204085 -264.984366)
			(xy 351.230438 -264.983722) (xy 351.236534 -264.983722) (xy 351.26228 -264.984552) (xy 351.313057 -264.99321)
			(xy 351.361876 -265.00964) (xy 351.407555 -265.033446) (xy 351.448988 -265.064049) (xy 351.485172 -265.10071)
			(xy 351.515229 -265.142541) (xy 351.538434 -265.188528) (xy 351.554223 -265.237559) (xy 351.562214 -265.288445)
			(xy 351.562214 -265.339955) (xy 351.562184 -265.340143) (xy 351.842071 -265.340143) (xy 351.842071 -265.288209)
			(xy 351.850196 -265.236914) (xy 351.866244 -265.187521) (xy 351.889822 -265.141247) (xy 351.920348 -265.099231)
			(xy 351.957071 -265.062508) (xy 351.999087 -265.031982) (xy 352.045361 -265.008404) (xy 352.094754 -264.992356)
			(xy 352.146049 -264.984231) (xy 352.197983 -264.984231) (xy 352.249278 -264.992356) (xy 352.298671 -265.008404)
			(xy 352.344945 -265.031982) (xy 352.386961 -265.062508) (xy 352.423684 -265.099231) (xy 352.45421 -265.141247)
			(xy 352.477788 -265.187521) (xy 352.493836 -265.236914) (xy 352.501961 -265.288209) (xy 352.50247 -265.314176)
			(xy 352.501961 -265.340143) (xy 352.781871 -265.340143) (xy 352.781871 -265.288209) (xy 352.789996 -265.236914)
			(xy 352.806044 -265.187521) (xy 352.829622 -265.141247) (xy 352.860148 -265.099231) (xy 352.896871 -265.062508)
			(xy 352.938887 -265.031982) (xy 352.985161 -265.008404) (xy 353.034554 -264.992356) (xy 353.085849 -264.984231)
			(xy 353.137783 -264.984231) (xy 353.189078 -264.992356) (xy 353.238471 -265.008404) (xy 353.284745 -265.031982)
			(xy 353.326761 -265.062508) (xy 353.363484 -265.099231) (xy 353.39401 -265.141247) (xy 353.417588 -265.187521)
			(xy 353.433636 -265.236914) (xy 353.441761 -265.288209) (xy 353.44227 -265.314176) (xy 353.441761 -265.340143)
			(xy 353.721671 -265.340143) (xy 353.721671 -265.288209) (xy 353.729796 -265.236914) (xy 353.745844 -265.187521)
			(xy 353.769422 -265.141247) (xy 353.799948 -265.099231) (xy 353.836671 -265.062508) (xy 353.878687 -265.031982)
			(xy 353.924961 -265.008404) (xy 353.974354 -264.992356) (xy 354.025649 -264.984231) (xy 354.077583 -264.984231)
			(xy 354.128878 -264.992356) (xy 354.178271 -265.008404) (xy 354.224545 -265.031982) (xy 354.266561 -265.062508)
			(xy 354.303284 -265.099231) (xy 354.33381 -265.141247) (xy 354.357388 -265.187521) (xy 354.373436 -265.236914)
			(xy 354.381561 -265.288209) (xy 354.38207 -265.314176) (xy 354.381561 -265.340143) (xy 354.661471 -265.340143)
			(xy 354.661471 -265.288209) (xy 354.669596 -265.236914) (xy 354.685644 -265.187521) (xy 354.709222 -265.141247)
			(xy 354.739748 -265.099231) (xy 354.776471 -265.062508) (xy 354.818487 -265.031982) (xy 354.864761 -265.008404)
			(xy 354.914154 -264.992356) (xy 354.965449 -264.984231) (xy 355.017383 -264.984231) (xy 355.068678 -264.992356)
			(xy 355.118071 -265.008404) (xy 355.164345 -265.031982) (xy 355.206361 -265.062508) (xy 355.243084 -265.099231)
			(xy 355.27361 -265.141247) (xy 355.297188 -265.187521) (xy 355.313236 -265.236914) (xy 355.321361 -265.288209)
			(xy 355.32187 -265.314176) (xy 355.321361 -265.340143) (xy 355.601271 -265.340143) (xy 355.601271 -265.288209)
			(xy 355.609396 -265.236914) (xy 355.625444 -265.187521) (xy 355.649022 -265.141247) (xy 355.679548 -265.099231)
			(xy 355.716271 -265.062508) (xy 355.758287 -265.031982) (xy 355.804561 -265.008404) (xy 355.853954 -264.992356)
			(xy 355.905249 -264.984231) (xy 355.957183 -264.984231) (xy 356.008478 -264.992356) (xy 356.057871 -265.008404)
			(xy 356.104145 -265.031982) (xy 356.146161 -265.062508) (xy 356.182884 -265.099231) (xy 356.21341 -265.141247)
			(xy 356.236988 -265.187521) (xy 356.253036 -265.236914) (xy 356.261161 -265.288209) (xy 356.26167 -265.314176)
			(xy 356.261161 -265.340143) (xy 356.541071 -265.340143) (xy 356.541071 -265.288209) (xy 356.549196 -265.236914)
			(xy 356.565244 -265.187521) (xy 356.588822 -265.141247) (xy 356.619348 -265.099231) (xy 356.656071 -265.062508)
			(xy 356.698087 -265.031982) (xy 356.744361 -265.008404) (xy 356.793754 -264.992356) (xy 356.845049 -264.984231)
			(xy 356.896983 -264.984231) (xy 356.948278 -264.992356) (xy 356.997671 -265.008404) (xy 357.043945 -265.031982)
			(xy 357.085961 -265.062508) (xy 357.122684 -265.099231) (xy 357.15321 -265.141247) (xy 357.176788 -265.187521)
			(xy 357.192836 -265.236914) (xy 357.200961 -265.288209) (xy 357.20147 -265.314176) (xy 357.200961 -265.340143)
			(xy 362.179617 -265.340143) (xy 362.179617 -265.288209) (xy 362.187742 -265.236914) (xy 362.20379 -265.187521)
			(xy 362.227368 -265.141247) (xy 362.257894 -265.099231) (xy 362.294617 -265.062508) (xy 362.336633 -265.031982)
			(xy 362.382907 -265.008404) (xy 362.4323 -264.992356) (xy 362.483595 -264.984231) (xy 362.535529 -264.984231)
			(xy 362.586824 -264.992356) (xy 362.636217 -265.008404) (xy 362.682491 -265.031982) (xy 362.724507 -265.062508)
			(xy 362.76123 -265.099231) (xy 362.791756 -265.141247) (xy 362.815334 -265.187521) (xy 362.831382 -265.236914)
			(xy 362.839507 -265.288209) (xy 362.840016 -265.314176) (xy 362.839507 -265.340143) (xy 362.831382 -265.391438)
			(xy 362.815334 -265.440831) (xy 362.791756 -265.487105) (xy 362.76123 -265.529121) (xy 362.724507 -265.565844)
			(xy 362.682491 -265.59637) (xy 362.636217 -265.619948) (xy 362.586824 -265.635996) (xy 362.535529 -265.644121)
			(xy 362.483595 -265.644121) (xy 362.4323 -265.635996) (xy 362.382907 -265.619948) (xy 362.336633 -265.59637)
			(xy 362.294617 -265.565844) (xy 362.257894 -265.529121) (xy 362.227368 -265.487105) (xy 362.20379 -265.440831)
			(xy 362.187742 -265.391438) (xy 362.179617 -265.340143) (xy 357.200961 -265.340143) (xy 357.192836 -265.391438)
			(xy 357.176788 -265.440831) (xy 357.15321 -265.487105) (xy 357.122684 -265.529121) (xy 357.085961 -265.565844)
			(xy 357.043945 -265.59637) (xy 356.997671 -265.619948) (xy 356.948278 -265.635996) (xy 356.896983 -265.644121)
			(xy 356.845049 -265.644121) (xy 356.793754 -265.635996) (xy 356.744361 -265.619948) (xy 356.698087 -265.59637)
			(xy 356.656071 -265.565844) (xy 356.619348 -265.529121) (xy 356.588822 -265.487105) (xy 356.565244 -265.440831)
			(xy 356.549196 -265.391438) (xy 356.541071 -265.340143) (xy 356.261161 -265.340143) (xy 356.253036 -265.391438)
			(xy 356.236988 -265.440831) (xy 356.21341 -265.487105) (xy 356.182884 -265.529121) (xy 356.146161 -265.565844)
			(xy 356.104145 -265.59637) (xy 356.057871 -265.619948) (xy 356.008478 -265.635996) (xy 355.957183 -265.644121)
			(xy 355.905249 -265.644121) (xy 355.853954 -265.635996) (xy 355.804561 -265.619948) (xy 355.758287 -265.59637)
			(xy 355.716271 -265.565844) (xy 355.679548 -265.529121) (xy 355.649022 -265.487105) (xy 355.625444 -265.440831)
			(xy 355.609396 -265.391438) (xy 355.601271 -265.340143) (xy 355.321361 -265.340143) (xy 355.313236 -265.391438)
			(xy 355.297188 -265.440831) (xy 355.27361 -265.487105) (xy 355.243084 -265.529121) (xy 355.206361 -265.565844)
			(xy 355.164345 -265.59637) (xy 355.118071 -265.619948) (xy 355.068678 -265.635996) (xy 355.017383 -265.644121)
			(xy 354.965449 -265.644121) (xy 354.914154 -265.635996) (xy 354.864761 -265.619948) (xy 354.818487 -265.59637)
			(xy 354.776471 -265.565844) (xy 354.739748 -265.529121) (xy 354.709222 -265.487105) (xy 354.685644 -265.440831)
			(xy 354.669596 -265.391438) (xy 354.661471 -265.340143) (xy 354.381561 -265.340143) (xy 354.373436 -265.391438)
			(xy 354.357388 -265.440831) (xy 354.33381 -265.487105) (xy 354.303284 -265.529121) (xy 354.266561 -265.565844)
			(xy 354.224545 -265.59637) (xy 354.178271 -265.619948) (xy 354.128878 -265.635996) (xy 354.077583 -265.644121)
			(xy 354.025649 -265.644121) (xy 353.974354 -265.635996) (xy 353.924961 -265.619948) (xy 353.878687 -265.59637)
			(xy 353.836671 -265.565844) (xy 353.799948 -265.529121) (xy 353.769422 -265.487105) (xy 353.745844 -265.440831)
			(xy 353.729796 -265.391438) (xy 353.721671 -265.340143) (xy 353.441761 -265.340143) (xy 353.433636 -265.391438)
			(xy 353.417588 -265.440831) (xy 353.39401 -265.487105) (xy 353.363484 -265.529121) (xy 353.326761 -265.565844)
			(xy 353.284745 -265.59637) (xy 353.238471 -265.619948) (xy 353.189078 -265.635996) (xy 353.137783 -265.644121)
			(xy 353.085849 -265.644121) (xy 353.034554 -265.635996) (xy 352.985161 -265.619948) (xy 352.938887 -265.59637)
			(xy 352.896871 -265.565844) (xy 352.860148 -265.529121) (xy 352.829622 -265.487105) (xy 352.806044 -265.440831)
			(xy 352.789996 -265.391438) (xy 352.781871 -265.340143) (xy 352.501961 -265.340143) (xy 352.493836 -265.391438)
			(xy 352.477788 -265.440831) (xy 352.45421 -265.487105) (xy 352.423684 -265.529121) (xy 352.386961 -265.565844)
			(xy 352.344945 -265.59637) (xy 352.298671 -265.619948) (xy 352.249278 -265.635996) (xy 352.197983 -265.644121)
			(xy 352.146049 -265.644121) (xy 352.094754 -265.635996) (xy 352.045361 -265.619948) (xy 351.999087 -265.59637)
			(xy 351.957071 -265.565844) (xy 351.920348 -265.529121) (xy 351.889822 -265.487105) (xy 351.866244 -265.440831)
			(xy 351.850196 -265.391438) (xy 351.842071 -265.340143) (xy 351.562184 -265.340143) (xy 351.554223 -265.390841)
			(xy 351.538434 -265.439871) (xy 351.51523 -265.485859) (xy 351.485172 -265.527689) (xy 351.448989 -265.56435)
			(xy 351.407556 -265.594954) (xy 351.361877 -265.618759) (xy 351.313058 -265.63519) (xy 351.262281 -265.643848)
			(xy 351.236534 -265.64463) (xy 351.231962 -265.64463) (xy 351.205355 -265.644074) (xy 351.152834 -265.635515)
			(xy 351.102356 -265.618671) (xy 351.078546 -265.606784) (xy 351.073212 -265.60399) (xy 351.059751 -265.597233)
			(xy 351.030281 -265.591092) (xy 351.0003 -265.593806) (xy 350.972412 -265.605138) (xy 350.949035 -265.624105)
			(xy 350.932201 -265.649061) (xy 350.923369 -265.677839) (xy 350.922844 -265.69289) (xy 350.922844 -265.839448)
			(xy 350.944534 -265.852079) (xy 350.98417 -265.882871) (xy 351.018697 -265.919301) (xy 351.04732 -265.96053)
			(xy 351.069383 -266.005612) (xy 351.084378 -266.053511) (xy 351.091961 -266.103127) (xy 351.091957 -266.153318)
			(xy 351.09182 -266.154213) (xy 351.371917 -266.154213) (xy 351.371917 -266.102279) (xy 351.380042 -266.050984)
			(xy 351.39609 -266.001591) (xy 351.419668 -265.955317) (xy 351.450194 -265.913301) (xy 351.486917 -265.876578)
			(xy 351.528933 -265.846052) (xy 351.575207 -265.822474) (xy 351.6246 -265.806426) (xy 351.675895 -265.798301)
			(xy 351.727829 -265.798301) (xy 351.779124 -265.806426) (xy 351.828517 -265.822474) (xy 351.874791 -265.846052)
			(xy 351.916807 -265.876578) (xy 351.95353 -265.913301) (xy 351.984056 -265.955317) (xy 352.007634 -266.001591)
			(xy 352.023682 -266.050984) (xy 352.031807 -266.102279) (xy 352.032316 -266.128246) (xy 352.031807 -266.154213)
			(xy 352.311717 -266.154213) (xy 352.311717 -266.102279) (xy 352.319842 -266.050984) (xy 352.33589 -266.001591)
			(xy 352.359468 -265.955317) (xy 352.389994 -265.913301) (xy 352.426717 -265.876578) (xy 352.468733 -265.846052)
			(xy 352.515007 -265.822474) (xy 352.5644 -265.806426) (xy 352.615695 -265.798301) (xy 352.667629 -265.798301)
			(xy 352.718924 -265.806426) (xy 352.768317 -265.822474) (xy 352.814591 -265.846052) (xy 352.856607 -265.876578)
			(xy 352.89333 -265.913301) (xy 352.923856 -265.955317) (xy 352.947434 -266.001591) (xy 352.963482 -266.050984)
			(xy 352.971607 -266.102279) (xy 352.972116 -266.128246) (xy 352.971607 -266.154213) (xy 353.251517 -266.154213)
			(xy 353.251517 -266.102279) (xy 353.259642 -266.050984) (xy 353.27569 -266.001591) (xy 353.299268 -265.955317)
			(xy 353.329794 -265.913301) (xy 353.366517 -265.876578) (xy 353.408533 -265.846052) (xy 353.454807 -265.822474)
			(xy 353.5042 -265.806426) (xy 353.555495 -265.798301) (xy 353.607429 -265.798301) (xy 353.658724 -265.806426)
			(xy 353.708117 -265.822474) (xy 353.754391 -265.846052) (xy 353.796407 -265.876578) (xy 353.83313 -265.913301)
			(xy 353.863656 -265.955317) (xy 353.887234 -266.001591) (xy 353.903282 -266.050984) (xy 353.911407 -266.102279)
			(xy 353.911916 -266.128246) (xy 353.911407 -266.154213) (xy 354.191317 -266.154213) (xy 354.191317 -266.102279)
			(xy 354.199442 -266.050984) (xy 354.21549 -266.001591) (xy 354.239068 -265.955317) (xy 354.269594 -265.913301)
			(xy 354.306317 -265.876578) (xy 354.348333 -265.846052) (xy 354.394607 -265.822474) (xy 354.444 -265.806426)
			(xy 354.495295 -265.798301) (xy 354.547229 -265.798301) (xy 354.598524 -265.806426) (xy 354.647917 -265.822474)
			(xy 354.694191 -265.846052) (xy 354.736207 -265.876578) (xy 354.77293 -265.913301) (xy 354.803456 -265.955317)
			(xy 354.827034 -266.001591) (xy 354.843082 -266.050984) (xy 354.851207 -266.102279) (xy 354.851716 -266.128246)
			(xy 354.851207 -266.154213) (xy 355.131117 -266.154213) (xy 355.131117 -266.102279) (xy 355.139242 -266.050984)
			(xy 355.15529 -266.001591) (xy 355.178868 -265.955317) (xy 355.209394 -265.913301) (xy 355.246117 -265.876578)
			(xy 355.288133 -265.846052) (xy 355.334407 -265.822474) (xy 355.3838 -265.806426) (xy 355.435095 -265.798301)
			(xy 355.487029 -265.798301) (xy 355.538324 -265.806426) (xy 355.587717 -265.822474) (xy 355.633991 -265.846052)
			(xy 355.676007 -265.876578) (xy 355.71273 -265.913301) (xy 355.743256 -265.955317) (xy 355.766834 -266.001591)
			(xy 355.782882 -266.050984) (xy 355.791007 -266.102279) (xy 355.791516 -266.128246) (xy 355.791007 -266.154213)
			(xy 356.070917 -266.154213) (xy 356.070917 -266.102279) (xy 356.079042 -266.050984) (xy 356.09509 -266.001591)
			(xy 356.118668 -265.955317) (xy 356.149194 -265.913301) (xy 356.185917 -265.876578) (xy 356.227933 -265.846052)
			(xy 356.274207 -265.822474) (xy 356.3236 -265.806426) (xy 356.374895 -265.798301) (xy 356.426829 -265.798301)
			(xy 356.478124 -265.806426) (xy 356.527517 -265.822474) (xy 356.573791 -265.846052) (xy 356.615807 -265.876578)
			(xy 356.65253 -265.913301) (xy 356.683056 -265.955317) (xy 356.706634 -266.001591) (xy 356.722682 -266.050984)
			(xy 356.730807 -266.102279) (xy 356.731316 -266.128246) (xy 356.730807 -266.154213) (xy 357.010971 -266.154213)
			(xy 357.010971 -266.102279) (xy 357.019096 -266.050984) (xy 357.035144 -266.001591) (xy 357.058722 -265.955317)
			(xy 357.089248 -265.913301) (xy 357.125971 -265.876578) (xy 357.167987 -265.846052) (xy 357.214261 -265.822474)
			(xy 357.263654 -265.806426) (xy 357.314949 -265.798301) (xy 357.366883 -265.798301) (xy 357.418178 -265.806426)
			(xy 357.467571 -265.822474) (xy 357.513845 -265.846052) (xy 357.555861 -265.876578) (xy 357.592584 -265.913301)
			(xy 357.62311 -265.955317) (xy 357.646688 -266.001591) (xy 357.662736 -266.050984) (xy 357.670861 -266.102279)
			(xy 357.67137 -266.128246) (xy 357.670861 -266.154213) (xy 361.709717 -266.154213) (xy 361.709717 -266.102279)
			(xy 361.717842 -266.050984) (xy 361.73389 -266.001591) (xy 361.757468 -265.955317) (xy 361.787994 -265.913301)
			(xy 361.824717 -265.876578) (xy 361.866733 -265.846052) (xy 361.913007 -265.822474) (xy 361.9624 -265.806426)
			(xy 362.013695 -265.798301) (xy 362.065629 -265.798301) (xy 362.116924 -265.806426) (xy 362.166317 -265.822474)
			(xy 362.212591 -265.846052) (xy 362.254607 -265.876578) (xy 362.29133 -265.913301) (xy 362.321856 -265.955317)
			(xy 362.345434 -266.001591) (xy 362.361482 -266.050984) (xy 362.369607 -266.102279) (xy 362.370116 -266.128246)
			(xy 362.369607 -266.154213) (xy 362.649517 -266.154213) (xy 362.649517 -266.102279) (xy 362.657642 -266.050984)
			(xy 362.67369 -266.001591) (xy 362.697268 -265.955317) (xy 362.727794 -265.913301) (xy 362.764517 -265.876578)
			(xy 362.806533 -265.846052) (xy 362.852807 -265.822474) (xy 362.9022 -265.806426) (xy 362.953495 -265.798301)
			(xy 363.005429 -265.798301) (xy 363.056724 -265.806426) (xy 363.106117 -265.822474) (xy 363.152391 -265.846052)
			(xy 363.194407 -265.876578) (xy 363.23113 -265.913301) (xy 363.261656 -265.955317) (xy 363.285234 -266.001591)
			(xy 363.301282 -266.050984) (xy 363.309407 -266.102279) (xy 363.309916 -266.128246) (xy 363.309407 -266.154213)
			(xy 363.301282 -266.205508) (xy 363.285234 -266.254901) (xy 363.261656 -266.301175) (xy 363.23113 -266.343191)
			(xy 363.194407 -266.379914) (xy 363.152391 -266.41044) (xy 363.106117 -266.434018) (xy 363.056724 -266.450066)
			(xy 363.005429 -266.458191) (xy 362.953495 -266.458191) (xy 362.9022 -266.450066) (xy 362.852807 -266.434018)
			(xy 362.806533 -266.41044) (xy 362.764517 -266.379914) (xy 362.727794 -266.343191) (xy 362.697268 -266.301175)
			(xy 362.67369 -266.254901) (xy 362.657642 -266.205508) (xy 362.649517 -266.154213) (xy 362.369607 -266.154213)
			(xy 362.361482 -266.205508) (xy 362.345434 -266.254901) (xy 362.321856 -266.301175) (xy 362.29133 -266.343191)
			(xy 362.254607 -266.379914) (xy 362.212591 -266.41044) (xy 362.166317 -266.434018) (xy 362.116924 -266.450066)
			(xy 362.065629 -266.458191) (xy 362.013695 -266.458191) (xy 361.9624 -266.450066) (xy 361.913007 -266.434018)
			(xy 361.866733 -266.41044) (xy 361.824717 -266.379914) (xy 361.787994 -266.343191) (xy 361.757468 -266.301175)
			(xy 361.73389 -266.254901) (xy 361.717842 -266.205508) (xy 361.709717 -266.154213) (xy 357.670861 -266.154213)
			(xy 357.662736 -266.205508) (xy 357.646688 -266.254901) (xy 357.62311 -266.301175) (xy 357.592584 -266.343191)
			(xy 357.555861 -266.379914) (xy 357.513845 -266.41044) (xy 357.467571 -266.434018) (xy 357.418178 -266.450066)
			(xy 357.366883 -266.458191) (xy 357.314949 -266.458191) (xy 357.263654 -266.450066) (xy 357.214261 -266.434018)
			(xy 357.167987 -266.41044) (xy 357.125971 -266.379914) (xy 357.089248 -266.343191) (xy 357.058722 -266.301175)
			(xy 357.035144 -266.254901) (xy 357.019096 -266.205508) (xy 357.010971 -266.154213) (xy 356.730807 -266.154213)
			(xy 356.722682 -266.205508) (xy 356.706634 -266.254901) (xy 356.683056 -266.301175) (xy 356.65253 -266.343191)
			(xy 356.615807 -266.379914) (xy 356.573791 -266.41044) (xy 356.527517 -266.434018) (xy 356.478124 -266.450066)
			(xy 356.426829 -266.458191) (xy 356.374895 -266.458191) (xy 356.3236 -266.450066) (xy 356.274207 -266.434018)
			(xy 356.227933 -266.41044) (xy 356.185917 -266.379914) (xy 356.149194 -266.343191) (xy 356.118668 -266.301175)
			(xy 356.09509 -266.254901) (xy 356.079042 -266.205508) (xy 356.070917 -266.154213) (xy 355.791007 -266.154213)
			(xy 355.782882 -266.205508) (xy 355.766834 -266.254901) (xy 355.743256 -266.301175) (xy 355.71273 -266.343191)
			(xy 355.676007 -266.379914) (xy 355.633991 -266.41044) (xy 355.587717 -266.434018) (xy 355.538324 -266.450066)
			(xy 355.487029 -266.458191) (xy 355.435095 -266.458191) (xy 355.3838 -266.450066) (xy 355.334407 -266.434018)
			(xy 355.288133 -266.41044) (xy 355.246117 -266.379914) (xy 355.209394 -266.343191) (xy 355.178868 -266.301175)
			(xy 355.15529 -266.254901) (xy 355.139242 -266.205508) (xy 355.131117 -266.154213) (xy 354.851207 -266.154213)
			(xy 354.843082 -266.205508) (xy 354.827034 -266.254901) (xy 354.803456 -266.301175) (xy 354.77293 -266.343191)
			(xy 354.736207 -266.379914) (xy 354.694191 -266.41044) (xy 354.647917 -266.434018) (xy 354.598524 -266.450066)
			(xy 354.547229 -266.458191) (xy 354.495295 -266.458191) (xy 354.444 -266.450066) (xy 354.394607 -266.434018)
			(xy 354.348333 -266.41044) (xy 354.306317 -266.379914) (xy 354.269594 -266.343191) (xy 354.239068 -266.301175)
			(xy 354.21549 -266.254901) (xy 354.199442 -266.205508) (xy 354.191317 -266.154213) (xy 353.911407 -266.154213)
			(xy 353.903282 -266.205508) (xy 353.887234 -266.254901) (xy 353.863656 -266.301175) (xy 353.83313 -266.343191)
			(xy 353.796407 -266.379914) (xy 353.754391 -266.41044) (xy 353.708117 -266.434018) (xy 353.658724 -266.450066)
			(xy 353.607429 -266.458191) (xy 353.555495 -266.458191) (xy 353.5042 -266.450066) (xy 353.454807 -266.434018)
			(xy 353.408533 -266.41044) (xy 353.366517 -266.379914) (xy 353.329794 -266.343191) (xy 353.299268 -266.301175)
			(xy 353.27569 -266.254901) (xy 353.259642 -266.205508) (xy 353.251517 -266.154213) (xy 352.971607 -266.154213)
			(xy 352.963482 -266.205508) (xy 352.947434 -266.254901) (xy 352.923856 -266.301175) (xy 352.89333 -266.343191)
			(xy 352.856607 -266.379914) (xy 352.814591 -266.41044) (xy 352.768317 -266.434018) (xy 352.718924 -266.450066)
			(xy 352.667629 -266.458191) (xy 352.615695 -266.458191) (xy 352.5644 -266.450066) (xy 352.515007 -266.434018)
			(xy 352.468733 -266.41044) (xy 352.426717 -266.379914) (xy 352.389994 -266.343191) (xy 352.359468 -266.301175)
			(xy 352.33589 -266.254901) (xy 352.319842 -266.205508) (xy 352.311717 -266.154213) (xy 352.031807 -266.154213)
			(xy 352.023682 -266.205508) (xy 352.007634 -266.254901) (xy 351.984056 -266.301175) (xy 351.95353 -266.343191)
			(xy 351.916807 -266.379914) (xy 351.874791 -266.41044) (xy 351.828517 -266.434018) (xy 351.779124 -266.450066)
			(xy 351.727829 -266.458191) (xy 351.675895 -266.458191) (xy 351.6246 -266.450066) (xy 351.575207 -266.434018)
			(xy 351.528933 -266.41044) (xy 351.486917 -266.379914) (xy 351.450194 -266.343191) (xy 351.419668 -266.301175)
			(xy 351.39609 -266.254901) (xy 351.380042 -266.205508) (xy 351.371917 -266.154213) (xy 351.09182 -266.154213)
			(xy 351.084368 -266.202932) (xy 351.069366 -266.250829) (xy 351.047297 -266.295909) (xy 351.018668 -266.337134)
			(xy 350.984137 -266.373559) (xy 350.944497 -266.404346) (xy 350.922844 -266.417044) (xy 350.922844 -266.563094)
			(xy 350.923377 -266.577897) (xy 350.931925 -266.606245) (xy 350.948244 -266.63095) (xy 350.970965 -266.649935)
			(xy 350.998176 -266.661605) (xy 351.027591 -266.66498) (xy 351.056739 -266.659775) (xy 351.070164 -266.653518)
			(xy 351.078546 -266.6492) (xy 351.102117 -266.637397) (xy 351.152084 -266.620613) (xy 351.204085 -266.611994)
			(xy 351.230438 -266.611354) (xy 351.236534 -266.611354) (xy 351.262278 -266.612184) (xy 351.31305 -266.620841)
			(xy 351.361864 -266.63727) (xy 351.407539 -266.661073) (xy 351.448968 -266.691674) (xy 351.485148 -266.728331)
			(xy 351.515202 -266.770158) (xy 351.538404 -266.816141) (xy 351.554192 -266.865166) (xy 351.562182 -266.916048)
			(xy 351.562182 -266.967553) (xy 351.562147 -266.967775) (xy 351.842071 -266.967775) (xy 351.842071 -266.915841)
			(xy 351.850196 -266.864546) (xy 351.866244 -266.815153) (xy 351.889822 -266.768879) (xy 351.920348 -266.726863)
			(xy 351.957071 -266.69014) (xy 351.999087 -266.659614) (xy 352.045361 -266.636036) (xy 352.094754 -266.619988)
			(xy 352.146049 -266.611863) (xy 352.197983 -266.611863) (xy 352.249278 -266.619988) (xy 352.298671 -266.636036)
			(xy 352.344945 -266.659614) (xy 352.386961 -266.69014) (xy 352.423684 -266.726863) (xy 352.45421 -266.768879)
			(xy 352.477788 -266.815153) (xy 352.493836 -266.864546) (xy 352.501961 -266.915841) (xy 352.50247 -266.941808)
			(xy 352.501961 -266.967775) (xy 352.781871 -266.967775) (xy 352.781871 -266.915841) (xy 352.789996 -266.864546)
			(xy 352.806044 -266.815153) (xy 352.829622 -266.768879) (xy 352.860148 -266.726863) (xy 352.896871 -266.69014)
			(xy 352.938887 -266.659614) (xy 352.985161 -266.636036) (xy 353.034554 -266.619988) (xy 353.085849 -266.611863)
			(xy 353.137783 -266.611863) (xy 353.189078 -266.619988) (xy 353.238471 -266.636036) (xy 353.284745 -266.659614)
			(xy 353.326761 -266.69014) (xy 353.363484 -266.726863) (xy 353.39401 -266.768879) (xy 353.417588 -266.815153)
			(xy 353.433636 -266.864546) (xy 353.441761 -266.915841) (xy 353.44227 -266.941808) (xy 353.441761 -266.967775)
			(xy 353.721671 -266.967775) (xy 353.721671 -266.915841) (xy 353.729796 -266.864546) (xy 353.745844 -266.815153)
			(xy 353.769422 -266.768879) (xy 353.799948 -266.726863) (xy 353.836671 -266.69014) (xy 353.878687 -266.659614)
			(xy 353.924961 -266.636036) (xy 353.974354 -266.619988) (xy 354.025649 -266.611863) (xy 354.077583 -266.611863)
			(xy 354.128878 -266.619988) (xy 354.178271 -266.636036) (xy 354.224545 -266.659614) (xy 354.266561 -266.69014)
			(xy 354.303284 -266.726863) (xy 354.33381 -266.768879) (xy 354.357388 -266.815153) (xy 354.373436 -266.864546)
			(xy 354.381561 -266.915841) (xy 354.38207 -266.941808) (xy 354.381561 -266.967775) (xy 354.661471 -266.967775)
			(xy 354.661471 -266.915841) (xy 354.669596 -266.864546) (xy 354.685644 -266.815153) (xy 354.709222 -266.768879)
			(xy 354.739748 -266.726863) (xy 354.776471 -266.69014) (xy 354.818487 -266.659614) (xy 354.864761 -266.636036)
			(xy 354.914154 -266.619988) (xy 354.965449 -266.611863) (xy 355.017383 -266.611863) (xy 355.068678 -266.619988)
			(xy 355.118071 -266.636036) (xy 355.164345 -266.659614) (xy 355.206361 -266.69014) (xy 355.243084 -266.726863)
			(xy 355.27361 -266.768879) (xy 355.297188 -266.815153) (xy 355.313236 -266.864546) (xy 355.321361 -266.915841)
			(xy 355.32187 -266.941808) (xy 355.321361 -266.967775) (xy 355.601271 -266.967775) (xy 355.601271 -266.915841)
			(xy 355.609396 -266.864546) (xy 355.625444 -266.815153) (xy 355.649022 -266.768879) (xy 355.679548 -266.726863)
			(xy 355.716271 -266.69014) (xy 355.758287 -266.659614) (xy 355.804561 -266.636036) (xy 355.853954 -266.619988)
			(xy 355.905249 -266.611863) (xy 355.957183 -266.611863) (xy 356.008478 -266.619988) (xy 356.057871 -266.636036)
			(xy 356.104145 -266.659614) (xy 356.146161 -266.69014) (xy 356.182884 -266.726863) (xy 356.21341 -266.768879)
			(xy 356.236988 -266.815153) (xy 356.253036 -266.864546) (xy 356.261161 -266.915841) (xy 356.26167 -266.941808)
			(xy 356.261161 -266.967775) (xy 356.541071 -266.967775) (xy 356.541071 -266.915841) (xy 356.549196 -266.864546)
			(xy 356.565244 -266.815153) (xy 356.588822 -266.768879) (xy 356.619348 -266.726863) (xy 356.656071 -266.69014)
			(xy 356.698087 -266.659614) (xy 356.744361 -266.636036) (xy 356.793754 -266.619988) (xy 356.845049 -266.611863)
			(xy 356.896983 -266.611863) (xy 356.948278 -266.619988) (xy 356.997671 -266.636036) (xy 357.043945 -266.659614)
			(xy 357.085961 -266.69014) (xy 357.122684 -266.726863) (xy 357.15321 -266.768879) (xy 357.176788 -266.815153)
			(xy 357.192836 -266.864546) (xy 357.200961 -266.915841) (xy 357.20147 -266.941808) (xy 357.200961 -266.967775)
			(xy 357.480617 -266.967775) (xy 357.480617 -266.915841) (xy 357.488742 -266.864546) (xy 357.50479 -266.815153)
			(xy 357.528368 -266.768879) (xy 357.558894 -266.726863) (xy 357.595617 -266.69014) (xy 357.637633 -266.659614)
			(xy 357.683907 -266.636036) (xy 357.7333 -266.619988) (xy 357.784595 -266.611863) (xy 357.836529 -266.611863)
			(xy 357.887824 -266.619988) (xy 357.937217 -266.636036) (xy 357.983491 -266.659614) (xy 358.025507 -266.69014)
			(xy 358.06223 -266.726863) (xy 358.092756 -266.768879) (xy 358.116334 -266.815153) (xy 358.132382 -266.864546)
			(xy 358.140507 -266.915841) (xy 358.141016 -266.941808) (xy 358.140507 -266.967775) (xy 361.239817 -266.967775)
			(xy 361.239817 -266.915841) (xy 361.247942 -266.864546) (xy 361.26399 -266.815153) (xy 361.287568 -266.768879)
			(xy 361.318094 -266.726863) (xy 361.354817 -266.69014) (xy 361.396833 -266.659614) (xy 361.443107 -266.636036)
			(xy 361.4925 -266.619988) (xy 361.543795 -266.611863) (xy 361.595729 -266.611863) (xy 361.647024 -266.619988)
			(xy 361.696417 -266.636036) (xy 361.742691 -266.659614) (xy 361.784707 -266.69014) (xy 361.82143 -266.726863)
			(xy 361.851956 -266.768879) (xy 361.875534 -266.815153) (xy 361.891582 -266.864546) (xy 361.899707 -266.915841)
			(xy 361.900216 -266.941808) (xy 361.899707 -266.967775) (xy 362.179617 -266.967775) (xy 362.179617 -266.915841)
			(xy 362.187742 -266.864546) (xy 362.20379 -266.815153) (xy 362.227368 -266.768879) (xy 362.257894 -266.726863)
			(xy 362.294617 -266.69014) (xy 362.336633 -266.659614) (xy 362.382907 -266.636036) (xy 362.4323 -266.619988)
			(xy 362.483595 -266.611863) (xy 362.535529 -266.611863) (xy 362.586824 -266.619988) (xy 362.636217 -266.636036)
			(xy 362.682491 -266.659614) (xy 362.724507 -266.69014) (xy 362.76123 -266.726863) (xy 362.791756 -266.768879)
			(xy 362.815334 -266.815153) (xy 362.831382 -266.864546) (xy 362.839507 -266.915841) (xy 362.840016 -266.941808)
			(xy 362.839507 -266.967775) (xy 362.831382 -267.01907) (xy 362.815334 -267.068463) (xy 362.791756 -267.114737)
			(xy 362.76123 -267.156753) (xy 362.724507 -267.193476) (xy 362.682491 -267.224002) (xy 362.636217 -267.24758)
			(xy 362.586824 -267.263628) (xy 362.535529 -267.271753) (xy 362.483595 -267.271753) (xy 362.4323 -267.263628)
			(xy 362.382907 -267.24758) (xy 362.336633 -267.224002) (xy 362.294617 -267.193476) (xy 362.257894 -267.156753)
			(xy 362.227368 -267.114737) (xy 362.20379 -267.068463) (xy 362.187742 -267.01907) (xy 362.179617 -266.967775)
			(xy 361.899707 -266.967775) (xy 361.891582 -267.01907) (xy 361.875534 -267.068463) (xy 361.851956 -267.114737)
			(xy 361.82143 -267.156753) (xy 361.784707 -267.193476) (xy 361.742691 -267.224002) (xy 361.696417 -267.24758)
			(xy 361.647024 -267.263628) (xy 361.595729 -267.271753) (xy 361.543795 -267.271753) (xy 361.4925 -267.263628)
			(xy 361.443107 -267.24758) (xy 361.396833 -267.224002) (xy 361.354817 -267.193476) (xy 361.318094 -267.156753)
			(xy 361.287568 -267.114737) (xy 361.26399 -267.068463) (xy 361.247942 -267.01907) (xy 361.239817 -266.967775)
			(xy 358.140507 -266.967775) (xy 358.132382 -267.01907) (xy 358.116334 -267.068463) (xy 358.092756 -267.114737)
			(xy 358.06223 -267.156753) (xy 358.025507 -267.193476) (xy 357.983491 -267.224002) (xy 357.937217 -267.24758)
			(xy 357.887824 -267.263628) (xy 357.836529 -267.271753) (xy 357.784595 -267.271753) (xy 357.7333 -267.263628)
			(xy 357.683907 -267.24758) (xy 357.637633 -267.224002) (xy 357.595617 -267.193476) (xy 357.558894 -267.156753)
			(xy 357.528368 -267.114737) (xy 357.50479 -267.068463) (xy 357.488742 -267.01907) (xy 357.480617 -266.967775)
			(xy 357.200961 -266.967775) (xy 357.192836 -267.01907) (xy 357.176788 -267.068463) (xy 357.15321 -267.114737)
			(xy 357.122684 -267.156753) (xy 357.085961 -267.193476) (xy 357.043945 -267.224002) (xy 356.997671 -267.24758)
			(xy 356.948278 -267.263628) (xy 356.896983 -267.271753) (xy 356.845049 -267.271753) (xy 356.793754 -267.263628)
			(xy 356.744361 -267.24758) (xy 356.698087 -267.224002) (xy 356.656071 -267.193476) (xy 356.619348 -267.156753)
			(xy 356.588822 -267.114737) (xy 356.565244 -267.068463) (xy 356.549196 -267.01907) (xy 356.541071 -266.967775)
			(xy 356.261161 -266.967775) (xy 356.253036 -267.01907) (xy 356.236988 -267.068463) (xy 356.21341 -267.114737)
			(xy 356.182884 -267.156753) (xy 356.146161 -267.193476) (xy 356.104145 -267.224002) (xy 356.057871 -267.24758)
			(xy 356.008478 -267.263628) (xy 355.957183 -267.271753) (xy 355.905249 -267.271753) (xy 355.853954 -267.263628)
			(xy 355.804561 -267.24758) (xy 355.758287 -267.224002) (xy 355.716271 -267.193476) (xy 355.679548 -267.156753)
			(xy 355.649022 -267.114737) (xy 355.625444 -267.068463) (xy 355.609396 -267.01907) (xy 355.601271 -266.967775)
			(xy 355.321361 -266.967775) (xy 355.313236 -267.01907) (xy 355.297188 -267.068463) (xy 355.27361 -267.114737)
			(xy 355.243084 -267.156753) (xy 355.206361 -267.193476) (xy 355.164345 -267.224002) (xy 355.118071 -267.24758)
			(xy 355.068678 -267.263628) (xy 355.017383 -267.271753) (xy 354.965449 -267.271753) (xy 354.914154 -267.263628)
			(xy 354.864761 -267.24758) (xy 354.818487 -267.224002) (xy 354.776471 -267.193476) (xy 354.739748 -267.156753)
			(xy 354.709222 -267.114737) (xy 354.685644 -267.068463) (xy 354.669596 -267.01907) (xy 354.661471 -266.967775)
			(xy 354.381561 -266.967775) (xy 354.373436 -267.01907) (xy 354.357388 -267.068463) (xy 354.33381 -267.114737)
			(xy 354.303284 -267.156753) (xy 354.266561 -267.193476) (xy 354.224545 -267.224002) (xy 354.178271 -267.24758)
			(xy 354.128878 -267.263628) (xy 354.077583 -267.271753) (xy 354.025649 -267.271753) (xy 353.974354 -267.263628)
			(xy 353.924961 -267.24758) (xy 353.878687 -267.224002) (xy 353.836671 -267.193476) (xy 353.799948 -267.156753)
			(xy 353.769422 -267.114737) (xy 353.745844 -267.068463) (xy 353.729796 -267.01907) (xy 353.721671 -266.967775)
			(xy 353.441761 -266.967775) (xy 353.433636 -267.01907) (xy 353.417588 -267.068463) (xy 353.39401 -267.114737)
			(xy 353.363484 -267.156753) (xy 353.326761 -267.193476) (xy 353.284745 -267.224002) (xy 353.238471 -267.24758)
			(xy 353.189078 -267.263628) (xy 353.137783 -267.271753) (xy 353.085849 -267.271753) (xy 353.034554 -267.263628)
			(xy 352.985161 -267.24758) (xy 352.938887 -267.224002) (xy 352.896871 -267.193476) (xy 352.860148 -267.156753)
			(xy 352.829622 -267.114737) (xy 352.806044 -267.068463) (xy 352.789996 -267.01907) (xy 352.781871 -266.967775)
			(xy 352.501961 -266.967775) (xy 352.493836 -267.01907) (xy 352.477788 -267.068463) (xy 352.45421 -267.114737)
			(xy 352.423684 -267.156753) (xy 352.386961 -267.193476) (xy 352.344945 -267.224002) (xy 352.298671 -267.24758)
			(xy 352.249278 -267.263628) (xy 352.197983 -267.271753) (xy 352.146049 -267.271753) (xy 352.094754 -267.263628)
			(xy 352.045361 -267.24758) (xy 351.999087 -267.224002) (xy 351.957071 -267.193476) (xy 351.920348 -267.156753)
			(xy 351.889822 -267.114737) (xy 351.866244 -267.068463) (xy 351.850196 -267.01907) (xy 351.842071 -266.967775)
			(xy 351.562147 -266.967775) (xy 351.554192 -267.018434) (xy 351.538404 -267.067459) (xy 351.515202 -267.113442)
			(xy 351.485147 -267.155269) (xy 351.448968 -267.191926) (xy 351.407539 -267.222527) (xy 351.361864 -267.24633)
			(xy 351.31305 -267.262759) (xy 351.262278 -267.271416) (xy 351.236534 -267.272262) (xy 351.231962 -267.272262)
			(xy 351.205355 -267.271706) (xy 351.152834 -267.263148) (xy 351.102355 -267.246306) (xy 351.078546 -267.234416)
			(xy 351.073212 -267.231622) (xy 351.059748 -267.224868) (xy 351.030273 -267.218732) (xy 351.00029 -267.221447)
			(xy 350.972397 -267.232777) (xy 350.949013 -267.251741) (xy 350.932167 -267.276693) (xy 350.923319 -267.30547)
			(xy 350.922844 -267.320522) (xy 350.922844 -267.46708) (xy 350.94454 -267.479711) (xy 350.984186 -267.510505)
			(xy 351.018722 -267.546937) (xy 351.047354 -267.588171) (xy 351.069426 -267.63326) (xy 351.084428 -267.681166)
			(xy 351.092018 -267.730789) (xy 351.092019 -267.780989) (xy 351.091888 -267.781845) (xy 351.371917 -267.781845)
			(xy 351.371917 -267.729911) (xy 351.380042 -267.678616) (xy 351.39609 -267.629223) (xy 351.419668 -267.582949)
			(xy 351.450194 -267.540933) (xy 351.486917 -267.50421) (xy 351.528933 -267.473684) (xy 351.575207 -267.450106)
			(xy 351.6246 -267.434058) (xy 351.675895 -267.425933) (xy 351.727829 -267.425933) (xy 351.779124 -267.434058)
			(xy 351.828517 -267.450106) (xy 351.874791 -267.473684) (xy 351.916807 -267.50421) (xy 351.95353 -267.540933)
			(xy 351.984056 -267.582949) (xy 352.007634 -267.629223) (xy 352.023682 -267.678616) (xy 352.031807 -267.729911)
			(xy 352.032316 -267.755878) (xy 352.031807 -267.781845) (xy 352.311717 -267.781845) (xy 352.311717 -267.729911)
			(xy 352.319842 -267.678616) (xy 352.33589 -267.629223) (xy 352.359468 -267.582949) (xy 352.389994 -267.540933)
			(xy 352.426717 -267.50421) (xy 352.468733 -267.473684) (xy 352.515007 -267.450106) (xy 352.5644 -267.434058)
			(xy 352.615695 -267.425933) (xy 352.667629 -267.425933) (xy 352.718924 -267.434058) (xy 352.768317 -267.450106)
			(xy 352.814591 -267.473684) (xy 352.856607 -267.50421) (xy 352.89333 -267.540933) (xy 352.923856 -267.582949)
			(xy 352.947434 -267.629223) (xy 352.963482 -267.678616) (xy 352.971607 -267.729911) (xy 352.972116 -267.755878)
			(xy 352.971607 -267.781845) (xy 353.251517 -267.781845) (xy 353.251517 -267.729911) (xy 353.259642 -267.678616)
			(xy 353.27569 -267.629223) (xy 353.299268 -267.582949) (xy 353.329794 -267.540933) (xy 353.366517 -267.50421)
			(xy 353.408533 -267.473684) (xy 353.454807 -267.450106) (xy 353.5042 -267.434058) (xy 353.555495 -267.425933)
			(xy 353.607429 -267.425933) (xy 353.658724 -267.434058) (xy 353.708117 -267.450106) (xy 353.754391 -267.473684)
			(xy 353.796407 -267.50421) (xy 353.83313 -267.540933) (xy 353.863656 -267.582949) (xy 353.887234 -267.629223)
			(xy 353.903282 -267.678616) (xy 353.911407 -267.729911) (xy 353.911916 -267.755878) (xy 353.911407 -267.781845)
			(xy 354.191317 -267.781845) (xy 354.191317 -267.729911) (xy 354.199442 -267.678616) (xy 354.21549 -267.629223)
			(xy 354.239068 -267.582949) (xy 354.269594 -267.540933) (xy 354.306317 -267.50421) (xy 354.348333 -267.473684)
			(xy 354.394607 -267.450106) (xy 354.444 -267.434058) (xy 354.495295 -267.425933) (xy 354.547229 -267.425933)
			(xy 354.598524 -267.434058) (xy 354.647917 -267.450106) (xy 354.694191 -267.473684) (xy 354.736207 -267.50421)
			(xy 354.77293 -267.540933) (xy 354.803456 -267.582949) (xy 354.827034 -267.629223) (xy 354.843082 -267.678616)
			(xy 354.851207 -267.729911) (xy 354.851716 -267.755878) (xy 354.851207 -267.781845) (xy 355.131117 -267.781845)
			(xy 355.131117 -267.729911) (xy 355.139242 -267.678616) (xy 355.15529 -267.629223) (xy 355.178868 -267.582949)
			(xy 355.209394 -267.540933) (xy 355.246117 -267.50421) (xy 355.288133 -267.473684) (xy 355.334407 -267.450106)
			(xy 355.3838 -267.434058) (xy 355.435095 -267.425933) (xy 355.487029 -267.425933) (xy 355.538324 -267.434058)
			(xy 355.587717 -267.450106) (xy 355.633991 -267.473684) (xy 355.676007 -267.50421) (xy 355.71273 -267.540933)
			(xy 355.743256 -267.582949) (xy 355.766834 -267.629223) (xy 355.782882 -267.678616) (xy 355.791007 -267.729911)
			(xy 355.791516 -267.755878) (xy 355.791007 -267.781845) (xy 356.070917 -267.781845) (xy 356.070917 -267.729911)
			(xy 356.079042 -267.678616) (xy 356.09509 -267.629223) (xy 356.118668 -267.582949) (xy 356.149194 -267.540933)
			(xy 356.185917 -267.50421) (xy 356.227933 -267.473684) (xy 356.274207 -267.450106) (xy 356.3236 -267.434058)
			(xy 356.374895 -267.425933) (xy 356.426829 -267.425933) (xy 356.478124 -267.434058) (xy 356.527517 -267.450106)
			(xy 356.573791 -267.473684) (xy 356.615807 -267.50421) (xy 356.65253 -267.540933) (xy 356.683056 -267.582949)
			(xy 356.706634 -267.629223) (xy 356.722682 -267.678616) (xy 356.730807 -267.729911) (xy 356.731316 -267.755878)
			(xy 356.730807 -267.781845) (xy 357.010717 -267.781845) (xy 357.010717 -267.729911) (xy 357.018842 -267.678616)
			(xy 357.03489 -267.629223) (xy 357.058468 -267.582949) (xy 357.088994 -267.540933) (xy 357.125717 -267.50421)
			(xy 357.167733 -267.473684) (xy 357.214007 -267.450106) (xy 357.2634 -267.434058) (xy 357.314695 -267.425933)
			(xy 357.366629 -267.425933) (xy 357.417924 -267.434058) (xy 357.467317 -267.450106) (xy 357.513591 -267.473684)
			(xy 357.555607 -267.50421) (xy 357.59233 -267.540933) (xy 357.622856 -267.582949) (xy 357.646434 -267.629223)
			(xy 357.662482 -267.678616) (xy 357.670607 -267.729911) (xy 357.671116 -267.755878) (xy 357.670607 -267.781845)
			(xy 357.950517 -267.781845) (xy 357.950517 -267.729911) (xy 357.958642 -267.678616) (xy 357.97469 -267.629223)
			(xy 357.998268 -267.582949) (xy 358.028794 -267.540933) (xy 358.065517 -267.50421) (xy 358.107533 -267.473684)
			(xy 358.153807 -267.450106) (xy 358.2032 -267.434058) (xy 358.254495 -267.425933) (xy 358.306429 -267.425933)
			(xy 358.357724 -267.434058) (xy 358.407117 -267.450106) (xy 358.453391 -267.473684) (xy 358.495407 -267.50421)
			(xy 358.53213 -267.540933) (xy 358.562656 -267.582949) (xy 358.586234 -267.629223) (xy 358.602282 -267.678616)
			(xy 358.610407 -267.729911) (xy 358.610916 -267.755878) (xy 358.610407 -267.781845) (xy 361.709717 -267.781845)
			(xy 361.709717 -267.729911) (xy 361.717842 -267.678616) (xy 361.73389 -267.629223) (xy 361.757468 -267.582949)
			(xy 361.787994 -267.540933) (xy 361.824717 -267.50421) (xy 361.866733 -267.473684) (xy 361.913007 -267.450106)
			(xy 361.9624 -267.434058) (xy 362.013695 -267.425933) (xy 362.065629 -267.425933) (xy 362.116924 -267.434058)
			(xy 362.166317 -267.450106) (xy 362.212591 -267.473684) (xy 362.254607 -267.50421) (xy 362.29133 -267.540933)
			(xy 362.321856 -267.582949) (xy 362.345434 -267.629223) (xy 362.361482 -267.678616) (xy 362.369607 -267.729911)
			(xy 362.370116 -267.755878) (xy 362.369607 -267.781845) (xy 362.649517 -267.781845) (xy 362.649517 -267.729911)
			(xy 362.657642 -267.678616) (xy 362.67369 -267.629223) (xy 362.697268 -267.582949) (xy 362.727794 -267.540933)
			(xy 362.764517 -267.50421) (xy 362.806533 -267.473684) (xy 362.852807 -267.450106) (xy 362.9022 -267.434058)
			(xy 362.953495 -267.425933) (xy 363.005429 -267.425933) (xy 363.056724 -267.434058) (xy 363.106117 -267.450106)
			(xy 363.152391 -267.473684) (xy 363.194407 -267.50421) (xy 363.23113 -267.540933) (xy 363.261656 -267.582949)
			(xy 363.285234 -267.629223) (xy 363.301282 -267.678616) (xy 363.309407 -267.729911) (xy 363.309916 -267.755878)
			(xy 363.309407 -267.781845) (xy 363.301282 -267.83314) (xy 363.285234 -267.882533) (xy 363.261656 -267.928807)
			(xy 363.23113 -267.970823) (xy 363.194407 -268.007546) (xy 363.152391 -268.038072) (xy 363.106117 -268.06165)
			(xy 363.056724 -268.077698) (xy 363.005429 -268.085823) (xy 362.953495 -268.085823) (xy 362.9022 -268.077698)
			(xy 362.852807 -268.06165) (xy 362.806533 -268.038072) (xy 362.764517 -268.007546) (xy 362.727794 -267.970823)
			(xy 362.697268 -267.928807) (xy 362.67369 -267.882533) (xy 362.657642 -267.83314) (xy 362.649517 -267.781845)
			(xy 362.369607 -267.781845) (xy 362.361482 -267.83314) (xy 362.345434 -267.882533) (xy 362.321856 -267.928807)
			(xy 362.29133 -267.970823) (xy 362.254607 -268.007546) (xy 362.212591 -268.038072) (xy 362.166317 -268.06165)
			(xy 362.116924 -268.077698) (xy 362.065629 -268.085823) (xy 362.013695 -268.085823) (xy 361.9624 -268.077698)
			(xy 361.913007 -268.06165) (xy 361.866733 -268.038072) (xy 361.824717 -268.007546) (xy 361.787994 -267.970823)
			(xy 361.757468 -267.928807) (xy 361.73389 -267.882533) (xy 361.717842 -267.83314) (xy 361.709717 -267.781845)
			(xy 358.610407 -267.781845) (xy 358.602282 -267.83314) (xy 358.586234 -267.882533) (xy 358.562656 -267.928807)
			(xy 358.53213 -267.970823) (xy 358.495407 -268.007546) (xy 358.453391 -268.038072) (xy 358.407117 -268.06165)
			(xy 358.357724 -268.077698) (xy 358.306429 -268.085823) (xy 358.254495 -268.085823) (xy 358.2032 -268.077698)
			(xy 358.153807 -268.06165) (xy 358.107533 -268.038072) (xy 358.065517 -268.007546) (xy 358.028794 -267.970823)
			(xy 357.998268 -267.928807) (xy 357.97469 -267.882533) (xy 357.958642 -267.83314) (xy 357.950517 -267.781845)
			(xy 357.670607 -267.781845) (xy 357.662482 -267.83314) (xy 357.646434 -267.882533) (xy 357.622856 -267.928807)
			(xy 357.59233 -267.970823) (xy 357.555607 -268.007546) (xy 357.513591 -268.038072) (xy 357.467317 -268.06165)
			(xy 357.417924 -268.077698) (xy 357.366629 -268.085823) (xy 357.314695 -268.085823) (xy 357.2634 -268.077698)
			(xy 357.214007 -268.06165) (xy 357.167733 -268.038072) (xy 357.125717 -268.007546) (xy 357.088994 -267.970823)
			(xy 357.058468 -267.928807) (xy 357.03489 -267.882533) (xy 357.018842 -267.83314) (xy 357.010717 -267.781845)
			(xy 356.730807 -267.781845) (xy 356.722682 -267.83314) (xy 356.706634 -267.882533) (xy 356.683056 -267.928807)
			(xy 356.65253 -267.970823) (xy 356.615807 -268.007546) (xy 356.573791 -268.038072) (xy 356.527517 -268.06165)
			(xy 356.478124 -268.077698) (xy 356.426829 -268.085823) (xy 356.374895 -268.085823) (xy 356.3236 -268.077698)
			(xy 356.274207 -268.06165) (xy 356.227933 -268.038072) (xy 356.185917 -268.007546) (xy 356.149194 -267.970823)
			(xy 356.118668 -267.928807) (xy 356.09509 -267.882533) (xy 356.079042 -267.83314) (xy 356.070917 -267.781845)
			(xy 355.791007 -267.781845) (xy 355.782882 -267.83314) (xy 355.766834 -267.882533) (xy 355.743256 -267.928807)
			(xy 355.71273 -267.970823) (xy 355.676007 -268.007546) (xy 355.633991 -268.038072) (xy 355.587717 -268.06165)
			(xy 355.538324 -268.077698) (xy 355.487029 -268.085823) (xy 355.435095 -268.085823) (xy 355.3838 -268.077698)
			(xy 355.334407 -268.06165) (xy 355.288133 -268.038072) (xy 355.246117 -268.007546) (xy 355.209394 -267.970823)
			(xy 355.178868 -267.928807) (xy 355.15529 -267.882533) (xy 355.139242 -267.83314) (xy 355.131117 -267.781845)
			(xy 354.851207 -267.781845) (xy 354.843082 -267.83314) (xy 354.827034 -267.882533) (xy 354.803456 -267.928807)
			(xy 354.77293 -267.970823) (xy 354.736207 -268.007546) (xy 354.694191 -268.038072) (xy 354.647917 -268.06165)
			(xy 354.598524 -268.077698) (xy 354.547229 -268.085823) (xy 354.495295 -268.085823) (xy 354.444 -268.077698)
			(xy 354.394607 -268.06165) (xy 354.348333 -268.038072) (xy 354.306317 -268.007546) (xy 354.269594 -267.970823)
			(xy 354.239068 -267.928807) (xy 354.21549 -267.882533) (xy 354.199442 -267.83314) (xy 354.191317 -267.781845)
			(xy 353.911407 -267.781845) (xy 353.903282 -267.83314) (xy 353.887234 -267.882533) (xy 353.863656 -267.928807)
			(xy 353.83313 -267.970823) (xy 353.796407 -268.007546) (xy 353.754391 -268.038072) (xy 353.708117 -268.06165)
			(xy 353.658724 -268.077698) (xy 353.607429 -268.085823) (xy 353.555495 -268.085823) (xy 353.5042 -268.077698)
			(xy 353.454807 -268.06165) (xy 353.408533 -268.038072) (xy 353.366517 -268.007546) (xy 353.329794 -267.970823)
			(xy 353.299268 -267.928807) (xy 353.27569 -267.882533) (xy 353.259642 -267.83314) (xy 353.251517 -267.781845)
			(xy 352.971607 -267.781845) (xy 352.963482 -267.83314) (xy 352.947434 -267.882533) (xy 352.923856 -267.928807)
			(xy 352.89333 -267.970823) (xy 352.856607 -268.007546) (xy 352.814591 -268.038072) (xy 352.768317 -268.06165)
			(xy 352.718924 -268.077698) (xy 352.667629 -268.085823) (xy 352.615695 -268.085823) (xy 352.5644 -268.077698)
			(xy 352.515007 -268.06165) (xy 352.468733 -268.038072) (xy 352.426717 -268.007546) (xy 352.389994 -267.970823)
			(xy 352.359468 -267.928807) (xy 352.33589 -267.882533) (xy 352.319842 -267.83314) (xy 352.311717 -267.781845)
			(xy 352.031807 -267.781845) (xy 352.023682 -267.83314) (xy 352.007634 -267.882533) (xy 351.984056 -267.928807)
			(xy 351.95353 -267.970823) (xy 351.916807 -268.007546) (xy 351.874791 -268.038072) (xy 351.828517 -268.06165)
			(xy 351.779124 -268.077698) (xy 351.727829 -268.085823) (xy 351.675895 -268.085823) (xy 351.6246 -268.077698)
			(xy 351.575207 -268.06165) (xy 351.528933 -268.038072) (xy 351.486917 -268.007546) (xy 351.450194 -267.970823)
			(xy 351.419668 -267.928807) (xy 351.39609 -267.882533) (xy 351.380042 -267.83314) (xy 351.371917 -267.781845)
			(xy 351.091888 -267.781845) (xy 351.084433 -267.830613) (xy 351.069434 -267.87852) (xy 351.047365 -267.92361)
			(xy 351.018735 -267.964846) (xy 350.984202 -268.001281) (xy 350.944557 -268.032077) (xy 350.922844 -268.044676)
			(xy 350.922844 -268.19098) (xy 350.923376 -268.205785) (xy 350.931921 -268.234136) (xy 350.94824 -268.258845)
			(xy 350.970961 -268.277833) (xy 350.998175 -268.289505) (xy 351.027593 -268.29288) (xy 351.056743 -268.287673)
			(xy 351.070164 -268.281404) (xy 351.078546 -268.277086) (xy 351.102117 -268.265284) (xy 351.152084 -268.2485)
			(xy 351.204085 -268.239882) (xy 351.230438 -268.23924) (xy 351.236534 -268.23924) (xy 351.262279 -268.24007)
			(xy 351.313053 -268.248727) (xy 351.36187 -268.265157) (xy 351.407546 -268.288961) (xy 351.448977 -268.319563)
			(xy 351.485158 -268.356222) (xy 351.515214 -268.39805) (xy 351.538417 -268.444035) (xy 351.554205 -268.493063)
			(xy 351.562196 -268.543946) (xy 351.562196 -268.595453) (xy 351.562163 -268.595661) (xy 351.842071 -268.595661)
			(xy 351.842071 -268.543727) (xy 351.850196 -268.492432) (xy 351.866244 -268.443039) (xy 351.889822 -268.396765)
			(xy 351.920348 -268.354749) (xy 351.957071 -268.318026) (xy 351.999087 -268.2875) (xy 352.045361 -268.263922)
			(xy 352.094754 -268.247874) (xy 352.146049 -268.239749) (xy 352.197983 -268.239749) (xy 352.249278 -268.247874)
			(xy 352.298671 -268.263922) (xy 352.344945 -268.2875) (xy 352.386961 -268.318026) (xy 352.423684 -268.354749)
			(xy 352.45421 -268.396765) (xy 352.477788 -268.443039) (xy 352.493836 -268.492432) (xy 352.501961 -268.543727)
			(xy 352.50247 -268.569694) (xy 352.501961 -268.595661) (xy 352.781871 -268.595661) (xy 352.781871 -268.543727)
			(xy 352.789996 -268.492432) (xy 352.806044 -268.443039) (xy 352.829622 -268.396765) (xy 352.860148 -268.354749)
			(xy 352.896871 -268.318026) (xy 352.938887 -268.2875) (xy 352.985161 -268.263922) (xy 353.034554 -268.247874)
			(xy 353.085849 -268.239749) (xy 353.137783 -268.239749) (xy 353.189078 -268.247874) (xy 353.238471 -268.263922)
			(xy 353.284745 -268.2875) (xy 353.326761 -268.318026) (xy 353.363484 -268.354749) (xy 353.39401 -268.396765)
			(xy 353.417588 -268.443039) (xy 353.433636 -268.492432) (xy 353.441761 -268.543727) (xy 353.44227 -268.569694)
			(xy 353.441761 -268.595661) (xy 353.721671 -268.595661) (xy 353.721671 -268.543727) (xy 353.729796 -268.492432)
			(xy 353.745844 -268.443039) (xy 353.769422 -268.396765) (xy 353.799948 -268.354749) (xy 353.836671 -268.318026)
			(xy 353.878687 -268.2875) (xy 353.924961 -268.263922) (xy 353.974354 -268.247874) (xy 354.025649 -268.239749)
			(xy 354.077583 -268.239749) (xy 354.128878 -268.247874) (xy 354.178271 -268.263922) (xy 354.224545 -268.2875)
			(xy 354.266561 -268.318026) (xy 354.303284 -268.354749) (xy 354.33381 -268.396765) (xy 354.357388 -268.443039)
			(xy 354.373436 -268.492432) (xy 354.381561 -268.543727) (xy 354.38207 -268.569694) (xy 354.381561 -268.595661)
			(xy 354.661471 -268.595661) (xy 354.661471 -268.543727) (xy 354.669596 -268.492432) (xy 354.685644 -268.443039)
			(xy 354.709222 -268.396765) (xy 354.739748 -268.354749) (xy 354.776471 -268.318026) (xy 354.818487 -268.2875)
			(xy 354.864761 -268.263922) (xy 354.914154 -268.247874) (xy 354.965449 -268.239749) (xy 355.017383 -268.239749)
			(xy 355.068678 -268.247874) (xy 355.118071 -268.263922) (xy 355.164345 -268.2875) (xy 355.206361 -268.318026)
			(xy 355.243084 -268.354749) (xy 355.27361 -268.396765) (xy 355.297188 -268.443039) (xy 355.313236 -268.492432)
			(xy 355.321361 -268.543727) (xy 355.32187 -268.569694) (xy 355.321361 -268.595661) (xy 355.601271 -268.595661)
			(xy 355.601271 -268.543727) (xy 355.609396 -268.492432) (xy 355.625444 -268.443039) (xy 355.649022 -268.396765)
			(xy 355.679548 -268.354749) (xy 355.716271 -268.318026) (xy 355.758287 -268.2875) (xy 355.804561 -268.263922)
			(xy 355.853954 -268.247874) (xy 355.905249 -268.239749) (xy 355.957183 -268.239749) (xy 356.008478 -268.247874)
			(xy 356.057871 -268.263922) (xy 356.104145 -268.2875) (xy 356.146161 -268.318026) (xy 356.182884 -268.354749)
			(xy 356.21341 -268.396765) (xy 356.236988 -268.443039) (xy 356.253036 -268.492432) (xy 356.261161 -268.543727)
			(xy 356.26167 -268.569694) (xy 356.261161 -268.595661) (xy 356.540817 -268.595661) (xy 356.540817 -268.543727)
			(xy 356.548942 -268.492432) (xy 356.56499 -268.443039) (xy 356.588568 -268.396765) (xy 356.619094 -268.354749)
			(xy 356.655817 -268.318026) (xy 356.697833 -268.2875) (xy 356.744107 -268.263922) (xy 356.7935 -268.247874)
			(xy 356.844795 -268.239749) (xy 356.896729 -268.239749) (xy 356.948024 -268.247874) (xy 356.997417 -268.263922)
			(xy 357.043691 -268.2875) (xy 357.085707 -268.318026) (xy 357.12243 -268.354749) (xy 357.152956 -268.396765)
			(xy 357.176534 -268.443039) (xy 357.192582 -268.492432) (xy 357.200707 -268.543727) (xy 357.201216 -268.569694)
			(xy 357.200707 -268.595661) (xy 357.480617 -268.595661) (xy 357.480617 -268.543727) (xy 357.488742 -268.492432)
			(xy 357.50479 -268.443039) (xy 357.528368 -268.396765) (xy 357.558894 -268.354749) (xy 357.595617 -268.318026)
			(xy 357.637633 -268.2875) (xy 357.683907 -268.263922) (xy 357.7333 -268.247874) (xy 357.784595 -268.239749)
			(xy 357.836529 -268.239749) (xy 357.887824 -268.247874) (xy 357.937217 -268.263922) (xy 357.983491 -268.2875)
			(xy 358.025507 -268.318026) (xy 358.06223 -268.354749) (xy 358.092756 -268.396765) (xy 358.116334 -268.443039)
			(xy 358.132382 -268.492432) (xy 358.140507 -268.543727) (xy 358.141016 -268.569694) (xy 358.140507 -268.595661)
			(xy 361.239817 -268.595661) (xy 361.239817 -268.543727) (xy 361.247942 -268.492432) (xy 361.26399 -268.443039)
			(xy 361.287568 -268.396765) (xy 361.318094 -268.354749) (xy 361.354817 -268.318026) (xy 361.396833 -268.2875)
			(xy 361.443107 -268.263922) (xy 361.4925 -268.247874) (xy 361.543795 -268.239749) (xy 361.595729 -268.239749)
			(xy 361.647024 -268.247874) (xy 361.696417 -268.263922) (xy 361.742691 -268.2875) (xy 361.784707 -268.318026)
			(xy 361.82143 -268.354749) (xy 361.851956 -268.396765) (xy 361.875534 -268.443039) (xy 361.891582 -268.492432)
			(xy 361.899707 -268.543727) (xy 361.900216 -268.569694) (xy 361.899707 -268.595661) (xy 362.179871 -268.595661)
			(xy 362.179871 -268.543727) (xy 362.187996 -268.492432) (xy 362.204044 -268.443039) (xy 362.227622 -268.396765)
			(xy 362.258148 -268.354749) (xy 362.294871 -268.318026) (xy 362.336887 -268.2875) (xy 362.383161 -268.263922)
			(xy 362.432554 -268.247874) (xy 362.483849 -268.239749) (xy 362.535783 -268.239749) (xy 362.587078 -268.247874)
			(xy 362.636471 -268.263922) (xy 362.682745 -268.2875) (xy 362.724761 -268.318026) (xy 362.761484 -268.354749)
			(xy 362.79201 -268.396765) (xy 362.815588 -268.443039) (xy 362.831636 -268.492432) (xy 362.839761 -268.543727)
			(xy 362.84027 -268.569694) (xy 362.839761 -268.595661) (xy 362.831636 -268.646956) (xy 362.815588 -268.696349)
			(xy 362.79201 -268.742623) (xy 362.761484 -268.784639) (xy 362.724761 -268.821362) (xy 362.682745 -268.851888)
			(xy 362.636471 -268.875466) (xy 362.587078 -268.891514) (xy 362.535783 -268.899639) (xy 362.483849 -268.899639)
			(xy 362.432554 -268.891514) (xy 362.383161 -268.875466) (xy 362.336887 -268.851888) (xy 362.294871 -268.821362)
			(xy 362.258148 -268.784639) (xy 362.227622 -268.742623) (xy 362.204044 -268.696349) (xy 362.187996 -268.646956)
			(xy 362.179871 -268.595661) (xy 361.899707 -268.595661) (xy 361.891582 -268.646956) (xy 361.875534 -268.696349)
			(xy 361.851956 -268.742623) (xy 361.82143 -268.784639) (xy 361.784707 -268.821362) (xy 361.742691 -268.851888)
			(xy 361.696417 -268.875466) (xy 361.647024 -268.891514) (xy 361.595729 -268.899639) (xy 361.543795 -268.899639)
			(xy 361.4925 -268.891514) (xy 361.443107 -268.875466) (xy 361.396833 -268.851888) (xy 361.354817 -268.821362)
			(xy 361.318094 -268.784639) (xy 361.287568 -268.742623) (xy 361.26399 -268.696349) (xy 361.247942 -268.646956)
			(xy 361.239817 -268.595661) (xy 358.140507 -268.595661) (xy 358.132382 -268.646956) (xy 358.116334 -268.696349)
			(xy 358.092756 -268.742623) (xy 358.06223 -268.784639) (xy 358.025507 -268.821362) (xy 357.983491 -268.851888)
			(xy 357.937217 -268.875466) (xy 357.887824 -268.891514) (xy 357.836529 -268.899639) (xy 357.784595 -268.899639)
			(xy 357.7333 -268.891514) (xy 357.683907 -268.875466) (xy 357.637633 -268.851888) (xy 357.595617 -268.821362)
			(xy 357.558894 -268.784639) (xy 357.528368 -268.742623) (xy 357.50479 -268.696349) (xy 357.488742 -268.646956)
			(xy 357.480617 -268.595661) (xy 357.200707 -268.595661) (xy 357.192582 -268.646956) (xy 357.176534 -268.696349)
			(xy 357.152956 -268.742623) (xy 357.12243 -268.784639) (xy 357.085707 -268.821362) (xy 357.043691 -268.851888)
			(xy 356.997417 -268.875466) (xy 356.948024 -268.891514) (xy 356.896729 -268.899639) (xy 356.844795 -268.899639)
			(xy 356.7935 -268.891514) (xy 356.744107 -268.875466) (xy 356.697833 -268.851888) (xy 356.655817 -268.821362)
			(xy 356.619094 -268.784639) (xy 356.588568 -268.742623) (xy 356.56499 -268.696349) (xy 356.548942 -268.646956)
			(xy 356.540817 -268.595661) (xy 356.261161 -268.595661) (xy 356.253036 -268.646956) (xy 356.236988 -268.696349)
			(xy 356.21341 -268.742623) (xy 356.182884 -268.784639) (xy 356.146161 -268.821362) (xy 356.104145 -268.851888)
			(xy 356.057871 -268.875466) (xy 356.008478 -268.891514) (xy 355.957183 -268.899639) (xy 355.905249 -268.899639)
			(xy 355.853954 -268.891514) (xy 355.804561 -268.875466) (xy 355.758287 -268.851888) (xy 355.716271 -268.821362)
			(xy 355.679548 -268.784639) (xy 355.649022 -268.742623) (xy 355.625444 -268.696349) (xy 355.609396 -268.646956)
			(xy 355.601271 -268.595661) (xy 355.321361 -268.595661) (xy 355.313236 -268.646956) (xy 355.297188 -268.696349)
			(xy 355.27361 -268.742623) (xy 355.243084 -268.784639) (xy 355.206361 -268.821362) (xy 355.164345 -268.851888)
			(xy 355.118071 -268.875466) (xy 355.068678 -268.891514) (xy 355.017383 -268.899639) (xy 354.965449 -268.899639)
			(xy 354.914154 -268.891514) (xy 354.864761 -268.875466) (xy 354.818487 -268.851888) (xy 354.776471 -268.821362)
			(xy 354.739748 -268.784639) (xy 354.709222 -268.742623) (xy 354.685644 -268.696349) (xy 354.669596 -268.646956)
			(xy 354.661471 -268.595661) (xy 354.381561 -268.595661) (xy 354.373436 -268.646956) (xy 354.357388 -268.696349)
			(xy 354.33381 -268.742623) (xy 354.303284 -268.784639) (xy 354.266561 -268.821362) (xy 354.224545 -268.851888)
			(xy 354.178271 -268.875466) (xy 354.128878 -268.891514) (xy 354.077583 -268.899639) (xy 354.025649 -268.899639)
			(xy 353.974354 -268.891514) (xy 353.924961 -268.875466) (xy 353.878687 -268.851888) (xy 353.836671 -268.821362)
			(xy 353.799948 -268.784639) (xy 353.769422 -268.742623) (xy 353.745844 -268.696349) (xy 353.729796 -268.646956)
			(xy 353.721671 -268.595661) (xy 353.441761 -268.595661) (xy 353.433636 -268.646956) (xy 353.417588 -268.696349)
			(xy 353.39401 -268.742623) (xy 353.363484 -268.784639) (xy 353.326761 -268.821362) (xy 353.284745 -268.851888)
			(xy 353.238471 -268.875466) (xy 353.189078 -268.891514) (xy 353.137783 -268.899639) (xy 353.085849 -268.899639)
			(xy 353.034554 -268.891514) (xy 352.985161 -268.875466) (xy 352.938887 -268.851888) (xy 352.896871 -268.821362)
			(xy 352.860148 -268.784639) (xy 352.829622 -268.742623) (xy 352.806044 -268.696349) (xy 352.789996 -268.646956)
			(xy 352.781871 -268.595661) (xy 352.501961 -268.595661) (xy 352.493836 -268.646956) (xy 352.477788 -268.696349)
			(xy 352.45421 -268.742623) (xy 352.423684 -268.784639) (xy 352.386961 -268.821362) (xy 352.344945 -268.851888)
			(xy 352.298671 -268.875466) (xy 352.249278 -268.891514) (xy 352.197983 -268.899639) (xy 352.146049 -268.899639)
			(xy 352.094754 -268.891514) (xy 352.045361 -268.875466) (xy 351.999087 -268.851888) (xy 351.957071 -268.821362)
			(xy 351.920348 -268.784639) (xy 351.889822 -268.742623) (xy 351.866244 -268.696349) (xy 351.850196 -268.646956)
			(xy 351.842071 -268.595661) (xy 351.562163 -268.595661) (xy 351.554205 -268.646337) (xy 351.538417 -268.695365)
			(xy 351.515214 -268.741349) (xy 351.485158 -268.783178) (xy 351.448977 -268.819837) (xy 351.407546 -268.850439)
			(xy 351.36187 -268.874243) (xy 351.313053 -268.890673) (xy 351.262279 -268.89933) (xy 351.236534 -268.900148)
			(xy 351.231962 -268.900148) (xy 351.205355 -268.899592) (xy 351.152834 -268.891033) (xy 351.102355 -268.874191)
			(xy 351.078546 -268.862302) (xy 351.073212 -268.859508) (xy 351.059752 -268.852751) (xy 351.030283 -268.846609)
			(xy 351.000303 -268.849322) (xy 350.972416 -268.860654) (xy 350.949041 -268.879622) (xy 350.93221 -268.904579)
			(xy 350.923383 -268.933358) (xy 350.922844 -268.948408) (xy 350.922844 -269.094712) (xy 350.944537 -269.107343)
			(xy 350.984178 -269.138136) (xy 351.01871 -269.174567) (xy 351.047338 -269.215799) (xy 351.069405 -269.260884)
			(xy 351.084404 -269.308787) (xy 351.091991 -269.358407) (xy 351.09199 -269.408603) (xy 351.091856 -269.409477)
			(xy 351.371917 -269.409477) (xy 351.371917 -269.357543) (xy 351.380042 -269.306248) (xy 351.39609 -269.256855)
			(xy 351.419668 -269.210581) (xy 351.450194 -269.168565) (xy 351.486917 -269.131842) (xy 351.528933 -269.101316)
			(xy 351.575207 -269.077738) (xy 351.6246 -269.06169) (xy 351.675895 -269.053565) (xy 351.727829 -269.053565)
			(xy 351.779124 -269.06169) (xy 351.828517 -269.077738) (xy 351.874791 -269.101316) (xy 351.916807 -269.131842)
			(xy 351.95353 -269.168565) (xy 351.984056 -269.210581) (xy 352.007634 -269.256855) (xy 352.023682 -269.306248)
			(xy 352.031807 -269.357543) (xy 352.032316 -269.38351) (xy 352.031807 -269.409477) (xy 352.311717 -269.409477)
			(xy 352.311717 -269.357543) (xy 352.319842 -269.306248) (xy 352.33589 -269.256855) (xy 352.359468 -269.210581)
			(xy 352.389994 -269.168565) (xy 352.426717 -269.131842) (xy 352.468733 -269.101316) (xy 352.515007 -269.077738)
			(xy 352.5644 -269.06169) (xy 352.615695 -269.053565) (xy 352.667629 -269.053565) (xy 352.718924 -269.06169)
			(xy 352.768317 -269.077738) (xy 352.814591 -269.101316) (xy 352.856607 -269.131842) (xy 352.89333 -269.168565)
			(xy 352.923856 -269.210581) (xy 352.947434 -269.256855) (xy 352.963482 -269.306248) (xy 352.971607 -269.357543)
			(xy 352.972116 -269.38351) (xy 352.971607 -269.409477) (xy 353.251517 -269.409477) (xy 353.251517 -269.357543)
			(xy 353.259642 -269.306248) (xy 353.27569 -269.256855) (xy 353.299268 -269.210581) (xy 353.329794 -269.168565)
			(xy 353.366517 -269.131842) (xy 353.408533 -269.101316) (xy 353.454807 -269.077738) (xy 353.5042 -269.06169)
			(xy 353.555495 -269.053565) (xy 353.607429 -269.053565) (xy 353.658724 -269.06169) (xy 353.708117 -269.077738)
			(xy 353.754391 -269.101316) (xy 353.796407 -269.131842) (xy 353.83313 -269.168565) (xy 353.863656 -269.210581)
			(xy 353.887234 -269.256855) (xy 353.903282 -269.306248) (xy 353.911407 -269.357543) (xy 353.911916 -269.38351)
			(xy 353.911407 -269.409477) (xy 354.191317 -269.409477) (xy 354.191317 -269.357543) (xy 354.199442 -269.306248)
			(xy 354.21549 -269.256855) (xy 354.239068 -269.210581) (xy 354.269594 -269.168565) (xy 354.306317 -269.131842)
			(xy 354.348333 -269.101316) (xy 354.394607 -269.077738) (xy 354.444 -269.06169) (xy 354.495295 -269.053565)
			(xy 354.547229 -269.053565) (xy 354.598524 -269.06169) (xy 354.647917 -269.077738) (xy 354.694191 -269.101316)
			(xy 354.736207 -269.131842) (xy 354.77293 -269.168565) (xy 354.803456 -269.210581) (xy 354.827034 -269.256855)
			(xy 354.843082 -269.306248) (xy 354.851207 -269.357543) (xy 354.851716 -269.38351) (xy 354.851207 -269.409477)
			(xy 355.131117 -269.409477) (xy 355.131117 -269.357543) (xy 355.139242 -269.306248) (xy 355.15529 -269.256855)
			(xy 355.178868 -269.210581) (xy 355.209394 -269.168565) (xy 355.246117 -269.131842) (xy 355.288133 -269.101316)
			(xy 355.334407 -269.077738) (xy 355.3838 -269.06169) (xy 355.435095 -269.053565) (xy 355.487029 -269.053565)
			(xy 355.538324 -269.06169) (xy 355.587717 -269.077738) (xy 355.633991 -269.101316) (xy 355.676007 -269.131842)
			(xy 355.71273 -269.168565) (xy 355.743256 -269.210581) (xy 355.766834 -269.256855) (xy 355.782882 -269.306248)
			(xy 355.791007 -269.357543) (xy 355.791516 -269.38351) (xy 355.791007 -269.409477) (xy 356.070917 -269.409477)
			(xy 356.070917 -269.357543) (xy 356.079042 -269.306248) (xy 356.09509 -269.256855) (xy 356.118668 -269.210581)
			(xy 356.149194 -269.168565) (xy 356.185917 -269.131842) (xy 356.227933 -269.101316) (xy 356.274207 -269.077738)
			(xy 356.3236 -269.06169) (xy 356.374895 -269.053565) (xy 356.426829 -269.053565) (xy 356.478124 -269.06169)
			(xy 356.527517 -269.077738) (xy 356.573791 -269.101316) (xy 356.615807 -269.131842) (xy 356.65253 -269.168565)
			(xy 356.683056 -269.210581) (xy 356.706634 -269.256855) (xy 356.722682 -269.306248) (xy 356.730807 -269.357543)
			(xy 356.731316 -269.38351) (xy 356.730807 -269.409477) (xy 357.010717 -269.409477) (xy 357.010717 -269.357543)
			(xy 357.018842 -269.306248) (xy 357.03489 -269.256855) (xy 357.058468 -269.210581) (xy 357.088994 -269.168565)
			(xy 357.125717 -269.131842) (xy 357.167733 -269.101316) (xy 357.214007 -269.077738) (xy 357.2634 -269.06169)
			(xy 357.314695 -269.053565) (xy 357.366629 -269.053565) (xy 357.417924 -269.06169) (xy 357.467317 -269.077738)
			(xy 357.513591 -269.101316) (xy 357.555607 -269.131842) (xy 357.59233 -269.168565) (xy 357.622856 -269.210581)
			(xy 357.646434 -269.256855) (xy 357.662482 -269.306248) (xy 357.670607 -269.357543) (xy 357.671116 -269.38351)
			(xy 357.670607 -269.409477) (xy 357.950517 -269.409477) (xy 357.950517 -269.357543) (xy 357.958642 -269.306248)
			(xy 357.97469 -269.256855) (xy 357.998268 -269.210581) (xy 358.028794 -269.168565) (xy 358.065517 -269.131842)
			(xy 358.107533 -269.101316) (xy 358.153807 -269.077738) (xy 358.2032 -269.06169) (xy 358.254495 -269.053565)
			(xy 358.306429 -269.053565) (xy 358.357724 -269.06169) (xy 358.407117 -269.077738) (xy 358.453391 -269.101316)
			(xy 358.495407 -269.131842) (xy 358.53213 -269.168565) (xy 358.562656 -269.210581) (xy 358.586234 -269.256855)
			(xy 358.602282 -269.306248) (xy 358.610407 -269.357543) (xy 358.610916 -269.38351) (xy 358.610407 -269.409477)
			(xy 361.710225 -269.409477) (xy 361.710225 -269.357543) (xy 361.71835 -269.306248) (xy 361.734398 -269.256855)
			(xy 361.757976 -269.210581) (xy 361.788502 -269.168565) (xy 361.825225 -269.131842) (xy 361.867241 -269.101316)
			(xy 361.913515 -269.077738) (xy 361.962908 -269.06169) (xy 362.014203 -269.053565) (xy 362.066137 -269.053565)
			(xy 362.117432 -269.06169) (xy 362.166825 -269.077738) (xy 362.213099 -269.101316) (xy 362.255115 -269.131842)
			(xy 362.291838 -269.168565) (xy 362.322364 -269.210581) (xy 362.345942 -269.256855) (xy 362.36199 -269.306248)
			(xy 362.370115 -269.357543) (xy 362.370624 -269.38351) (xy 362.370115 -269.409477) (xy 362.649517 -269.409477)
			(xy 362.649517 -269.357543) (xy 362.657642 -269.306248) (xy 362.67369 -269.256855) (xy 362.697268 -269.210581)
			(xy 362.727794 -269.168565) (xy 362.764517 -269.131842) (xy 362.806533 -269.101316) (xy 362.852807 -269.077738)
			(xy 362.9022 -269.06169) (xy 362.953495 -269.053565) (xy 363.005429 -269.053565) (xy 363.056724 -269.06169)
			(xy 363.106117 -269.077738) (xy 363.152391 -269.101316) (xy 363.194407 -269.131842) (xy 363.23113 -269.168565)
			(xy 363.261656 -269.210581) (xy 363.285234 -269.256855) (xy 363.301282 -269.306248) (xy 363.309407 -269.357543)
			(xy 363.309916 -269.38351) (xy 363.309407 -269.409477) (xy 363.301282 -269.460772) (xy 363.285234 -269.510165)
			(xy 363.261656 -269.556439) (xy 363.23113 -269.598455) (xy 363.194407 -269.635178) (xy 363.152391 -269.665704)
			(xy 363.106117 -269.689282) (xy 363.056724 -269.70533) (xy 363.005429 -269.713455) (xy 362.953495 -269.713455)
			(xy 362.9022 -269.70533) (xy 362.852807 -269.689282) (xy 362.806533 -269.665704) (xy 362.764517 -269.635178)
			(xy 362.727794 -269.598455) (xy 362.697268 -269.556439) (xy 362.67369 -269.510165) (xy 362.657642 -269.460772)
			(xy 362.649517 -269.409477) (xy 362.370115 -269.409477) (xy 362.36199 -269.460772) (xy 362.345942 -269.510165)
			(xy 362.322364 -269.556439) (xy 362.291838 -269.598455) (xy 362.255115 -269.635178) (xy 362.213099 -269.665704)
			(xy 362.166825 -269.689282) (xy 362.117432 -269.70533) (xy 362.066137 -269.713455) (xy 362.014203 -269.713455)
			(xy 361.962908 -269.70533) (xy 361.913515 -269.689282) (xy 361.867241 -269.665704) (xy 361.825225 -269.635178)
			(xy 361.788502 -269.598455) (xy 361.757976 -269.556439) (xy 361.734398 -269.510165) (xy 361.71835 -269.460772)
			(xy 361.710225 -269.409477) (xy 358.610407 -269.409477) (xy 358.602282 -269.460772) (xy 358.586234 -269.510165)
			(xy 358.562656 -269.556439) (xy 358.53213 -269.598455) (xy 358.495407 -269.635178) (xy 358.453391 -269.665704)
			(xy 358.407117 -269.689282) (xy 358.357724 -269.70533) (xy 358.306429 -269.713455) (xy 358.254495 -269.713455)
			(xy 358.2032 -269.70533) (xy 358.153807 -269.689282) (xy 358.107533 -269.665704) (xy 358.065517 -269.635178)
			(xy 358.028794 -269.598455) (xy 357.998268 -269.556439) (xy 357.97469 -269.510165) (xy 357.958642 -269.460772)
			(xy 357.950517 -269.409477) (xy 357.670607 -269.409477) (xy 357.662482 -269.460772) (xy 357.646434 -269.510165)
			(xy 357.622856 -269.556439) (xy 357.59233 -269.598455) (xy 357.555607 -269.635178) (xy 357.513591 -269.665704)
			(xy 357.467317 -269.689282) (xy 357.417924 -269.70533) (xy 357.366629 -269.713455) (xy 357.314695 -269.713455)
			(xy 357.2634 -269.70533) (xy 357.214007 -269.689282) (xy 357.167733 -269.665704) (xy 357.125717 -269.635178)
			(xy 357.088994 -269.598455) (xy 357.058468 -269.556439) (xy 357.03489 -269.510165) (xy 357.018842 -269.460772)
			(xy 357.010717 -269.409477) (xy 356.730807 -269.409477) (xy 356.722682 -269.460772) (xy 356.706634 -269.510165)
			(xy 356.683056 -269.556439) (xy 356.65253 -269.598455) (xy 356.615807 -269.635178) (xy 356.573791 -269.665704)
			(xy 356.527517 -269.689282) (xy 356.478124 -269.70533) (xy 356.426829 -269.713455) (xy 356.374895 -269.713455)
			(xy 356.3236 -269.70533) (xy 356.274207 -269.689282) (xy 356.227933 -269.665704) (xy 356.185917 -269.635178)
			(xy 356.149194 -269.598455) (xy 356.118668 -269.556439) (xy 356.09509 -269.510165) (xy 356.079042 -269.460772)
			(xy 356.070917 -269.409477) (xy 355.791007 -269.409477) (xy 355.782882 -269.460772) (xy 355.766834 -269.510165)
			(xy 355.743256 -269.556439) (xy 355.71273 -269.598455) (xy 355.676007 -269.635178) (xy 355.633991 -269.665704)
			(xy 355.587717 -269.689282) (xy 355.538324 -269.70533) (xy 355.487029 -269.713455) (xy 355.435095 -269.713455)
			(xy 355.3838 -269.70533) (xy 355.334407 -269.689282) (xy 355.288133 -269.665704) (xy 355.246117 -269.635178)
			(xy 355.209394 -269.598455) (xy 355.178868 -269.556439) (xy 355.15529 -269.510165) (xy 355.139242 -269.460772)
			(xy 355.131117 -269.409477) (xy 354.851207 -269.409477) (xy 354.843082 -269.460772) (xy 354.827034 -269.510165)
			(xy 354.803456 -269.556439) (xy 354.77293 -269.598455) (xy 354.736207 -269.635178) (xy 354.694191 -269.665704)
			(xy 354.647917 -269.689282) (xy 354.598524 -269.70533) (xy 354.547229 -269.713455) (xy 354.495295 -269.713455)
			(xy 354.444 -269.70533) (xy 354.394607 -269.689282) (xy 354.348333 -269.665704) (xy 354.306317 -269.635178)
			(xy 354.269594 -269.598455) (xy 354.239068 -269.556439) (xy 354.21549 -269.510165) (xy 354.199442 -269.460772)
			(xy 354.191317 -269.409477) (xy 353.911407 -269.409477) (xy 353.903282 -269.460772) (xy 353.887234 -269.510165)
			(xy 353.863656 -269.556439) (xy 353.83313 -269.598455) (xy 353.796407 -269.635178) (xy 353.754391 -269.665704)
			(xy 353.708117 -269.689282) (xy 353.658724 -269.70533) (xy 353.607429 -269.713455) (xy 353.555495 -269.713455)
			(xy 353.5042 -269.70533) (xy 353.454807 -269.689282) (xy 353.408533 -269.665704) (xy 353.366517 -269.635178)
			(xy 353.329794 -269.598455) (xy 353.299268 -269.556439) (xy 353.27569 -269.510165) (xy 353.259642 -269.460772)
			(xy 353.251517 -269.409477) (xy 352.971607 -269.409477) (xy 352.963482 -269.460772) (xy 352.947434 -269.510165)
			(xy 352.923856 -269.556439) (xy 352.89333 -269.598455) (xy 352.856607 -269.635178) (xy 352.814591 -269.665704)
			(xy 352.768317 -269.689282) (xy 352.718924 -269.70533) (xy 352.667629 -269.713455) (xy 352.615695 -269.713455)
			(xy 352.5644 -269.70533) (xy 352.515007 -269.689282) (xy 352.468733 -269.665704) (xy 352.426717 -269.635178)
			(xy 352.389994 -269.598455) (xy 352.359468 -269.556439) (xy 352.33589 -269.510165) (xy 352.319842 -269.460772)
			(xy 352.311717 -269.409477) (xy 352.031807 -269.409477) (xy 352.023682 -269.460772) (xy 352.007634 -269.510165)
			(xy 351.984056 -269.556439) (xy 351.95353 -269.598455) (xy 351.916807 -269.635178) (xy 351.874791 -269.665704)
			(xy 351.828517 -269.689282) (xy 351.779124 -269.70533) (xy 351.727829 -269.713455) (xy 351.675895 -269.713455)
			(xy 351.6246 -269.70533) (xy 351.575207 -269.689282) (xy 351.528933 -269.665704) (xy 351.486917 -269.635178)
			(xy 351.450194 -269.598455) (xy 351.419668 -269.556439) (xy 351.39609 -269.510165) (xy 351.380042 -269.460772)
			(xy 351.371917 -269.409477) (xy 351.091856 -269.409477) (xy 351.084402 -269.458222) (xy 351.069402 -269.506125)
			(xy 351.047333 -269.551209) (xy 351.018704 -269.59244) (xy 350.984171 -269.628871) (xy 350.944529 -269.659663)
			(xy 350.922844 -269.672308) (xy 350.922844 -269.818866) (xy 350.923387 -269.833661) (xy 350.931946 -269.86199)
			(xy 350.948267 -269.886676) (xy 350.970981 -269.905646) (xy 350.998181 -269.917307) (xy 351.027581 -269.92068)
			(xy 351.056715 -269.915483) (xy 351.070164 -269.90929) (xy 351.078546 -269.904972) (xy 351.102117 -269.89317)
			(xy 351.152084 -269.876388) (xy 351.204085 -269.86777) (xy 351.230438 -269.867126) (xy 351.236534 -269.867126)
			(xy 351.26228 -269.867956) (xy 351.313056 -269.876614) (xy 351.361875 -269.893044) (xy 351.407553 -269.916849)
			(xy 351.448986 -269.947452) (xy 351.485169 -269.984113) (xy 351.515226 -270.025943) (xy 351.53843 -270.07193)
			(xy 351.554219 -270.12096) (xy 351.56221 -270.171845) (xy 351.56221 -270.223354) (xy 351.56218 -270.223547)
			(xy 351.842071 -270.223547) (xy 351.842071 -270.171613) (xy 351.850196 -270.120318) (xy 351.866244 -270.070925)
			(xy 351.889822 -270.024651) (xy 351.920348 -269.982635) (xy 351.957071 -269.945912) (xy 351.999087 -269.915386)
			(xy 352.045361 -269.891808) (xy 352.094754 -269.87576) (xy 352.146049 -269.867635) (xy 352.197983 -269.867635)
			(xy 352.249278 -269.87576) (xy 352.298671 -269.891808) (xy 352.344945 -269.915386) (xy 352.386961 -269.945912)
			(xy 352.423684 -269.982635) (xy 352.45421 -270.024651) (xy 352.477788 -270.070925) (xy 352.493836 -270.120318)
			(xy 352.501961 -270.171613) (xy 352.50247 -270.19758) (xy 352.501961 -270.223547) (xy 352.781871 -270.223547)
			(xy 352.781871 -270.171613) (xy 352.789996 -270.120318) (xy 352.806044 -270.070925) (xy 352.829622 -270.024651)
			(xy 352.860148 -269.982635) (xy 352.896871 -269.945912) (xy 352.938887 -269.915386) (xy 352.985161 -269.891808)
			(xy 353.034554 -269.87576) (xy 353.085849 -269.867635) (xy 353.137783 -269.867635) (xy 353.189078 -269.87576)
			(xy 353.238471 -269.891808) (xy 353.284745 -269.915386) (xy 353.326761 -269.945912) (xy 353.363484 -269.982635)
			(xy 353.39401 -270.024651) (xy 353.417588 -270.070925) (xy 353.433636 -270.120318) (xy 353.441761 -270.171613)
			(xy 353.44227 -270.19758) (xy 353.441761 -270.223547) (xy 353.721671 -270.223547) (xy 353.721671 -270.171613)
			(xy 353.729796 -270.120318) (xy 353.745844 -270.070925) (xy 353.769422 -270.024651) (xy 353.799948 -269.982635)
			(xy 353.836671 -269.945912) (xy 353.878687 -269.915386) (xy 353.924961 -269.891808) (xy 353.974354 -269.87576)
			(xy 354.025649 -269.867635) (xy 354.077583 -269.867635) (xy 354.128878 -269.87576) (xy 354.178271 -269.891808)
			(xy 354.224545 -269.915386) (xy 354.266561 -269.945912) (xy 354.303284 -269.982635) (xy 354.33381 -270.024651)
			(xy 354.357388 -270.070925) (xy 354.373436 -270.120318) (xy 354.381561 -270.171613) (xy 354.38207 -270.19758)
			(xy 354.381561 -270.223547) (xy 354.661471 -270.223547) (xy 354.661471 -270.171613) (xy 354.669596 -270.120318)
			(xy 354.685644 -270.070925) (xy 354.709222 -270.024651) (xy 354.739748 -269.982635) (xy 354.776471 -269.945912)
			(xy 354.818487 -269.915386) (xy 354.864761 -269.891808) (xy 354.914154 -269.87576) (xy 354.965449 -269.867635)
			(xy 355.017383 -269.867635) (xy 355.068678 -269.87576) (xy 355.118071 -269.891808) (xy 355.164345 -269.915386)
			(xy 355.206361 -269.945912) (xy 355.243084 -269.982635) (xy 355.27361 -270.024651) (xy 355.297188 -270.070925)
			(xy 355.313236 -270.120318) (xy 355.321361 -270.171613) (xy 355.32187 -270.19758) (xy 355.321361 -270.223547)
			(xy 355.601271 -270.223547) (xy 355.601271 -270.171613) (xy 355.609396 -270.120318) (xy 355.625444 -270.070925)
			(xy 355.649022 -270.024651) (xy 355.679548 -269.982635) (xy 355.716271 -269.945912) (xy 355.758287 -269.915386)
			(xy 355.804561 -269.891808) (xy 355.853954 -269.87576) (xy 355.905249 -269.867635) (xy 355.957183 -269.867635)
			(xy 356.008478 -269.87576) (xy 356.057871 -269.891808) (xy 356.104145 -269.915386) (xy 356.146161 -269.945912)
			(xy 356.182884 -269.982635) (xy 356.21341 -270.024651) (xy 356.236988 -270.070925) (xy 356.253036 -270.120318)
			(xy 356.261161 -270.171613) (xy 356.26167 -270.19758) (xy 356.261161 -270.223547) (xy 356.540817 -270.223547)
			(xy 356.540817 -270.171613) (xy 356.548942 -270.120318) (xy 356.56499 -270.070925) (xy 356.588568 -270.024651)
			(xy 356.619094 -269.982635) (xy 356.655817 -269.945912) (xy 356.697833 -269.915386) (xy 356.744107 -269.891808)
			(xy 356.7935 -269.87576) (xy 356.844795 -269.867635) (xy 356.896729 -269.867635) (xy 356.948024 -269.87576)
			(xy 356.997417 -269.891808) (xy 357.043691 -269.915386) (xy 357.085707 -269.945912) (xy 357.12243 -269.982635)
			(xy 357.152956 -270.024651) (xy 357.176534 -270.070925) (xy 357.192582 -270.120318) (xy 357.200707 -270.171613)
			(xy 357.201216 -270.19758) (xy 357.200707 -270.223547) (xy 357.480617 -270.223547) (xy 357.480617 -270.171613)
			(xy 357.488742 -270.120318) (xy 357.50479 -270.070925) (xy 357.528368 -270.024651) (xy 357.558894 -269.982635)
			(xy 357.595617 -269.945912) (xy 357.637633 -269.915386) (xy 357.683907 -269.891808) (xy 357.7333 -269.87576)
			(xy 357.784595 -269.867635) (xy 357.836529 -269.867635) (xy 357.887824 -269.87576) (xy 357.937217 -269.891808)
			(xy 357.983491 -269.915386) (xy 358.025507 -269.945912) (xy 358.06223 -269.982635) (xy 358.092756 -270.024651)
			(xy 358.116334 -270.070925) (xy 358.132382 -270.120318) (xy 358.140507 -270.171613) (xy 358.141016 -270.19758)
			(xy 358.140507 -270.223547) (xy 361.239817 -270.223547) (xy 361.239817 -270.171613) (xy 361.247942 -270.120318)
			(xy 361.26399 -270.070925) (xy 361.287568 -270.024651) (xy 361.318094 -269.982635) (xy 361.354817 -269.945912)
			(xy 361.396833 -269.915386) (xy 361.443107 -269.891808) (xy 361.4925 -269.87576) (xy 361.543795 -269.867635)
			(xy 361.595729 -269.867635) (xy 361.647024 -269.87576) (xy 361.696417 -269.891808) (xy 361.742691 -269.915386)
			(xy 361.784707 -269.945912) (xy 361.82143 -269.982635) (xy 361.851956 -270.024651) (xy 361.875534 -270.070925)
			(xy 361.891582 -270.120318) (xy 361.899707 -270.171613) (xy 361.900216 -270.19758) (xy 361.899707 -270.223547)
			(xy 362.179617 -270.223547) (xy 362.179617 -270.171613) (xy 362.187742 -270.120318) (xy 362.20379 -270.070925)
			(xy 362.227368 -270.024651) (xy 362.257894 -269.982635) (xy 362.294617 -269.945912) (xy 362.336633 -269.915386)
			(xy 362.382907 -269.891808) (xy 362.4323 -269.87576) (xy 362.483595 -269.867635) (xy 362.535529 -269.867635)
			(xy 362.586824 -269.87576) (xy 362.636217 -269.891808) (xy 362.682491 -269.915386) (xy 362.724507 -269.945912)
			(xy 362.76123 -269.982635) (xy 362.791756 -270.024651) (xy 362.815334 -270.070925) (xy 362.831382 -270.120318)
			(xy 362.839507 -270.171613) (xy 362.840016 -270.19758) (xy 362.839507 -270.223547) (xy 362.831382 -270.274842)
			(xy 362.815334 -270.324235) (xy 362.791756 -270.370509) (xy 362.76123 -270.412525) (xy 362.724507 -270.449248)
			(xy 362.682491 -270.479774) (xy 362.636217 -270.503352) (xy 362.586824 -270.5194) (xy 362.535529 -270.527525)
			(xy 362.483595 -270.527525) (xy 362.4323 -270.5194) (xy 362.382907 -270.503352) (xy 362.336633 -270.479774)
			(xy 362.294617 -270.449248) (xy 362.257894 -270.412525) (xy 362.227368 -270.370509) (xy 362.20379 -270.324235)
			(xy 362.187742 -270.274842) (xy 362.179617 -270.223547) (xy 361.899707 -270.223547) (xy 361.891582 -270.274842)
			(xy 361.875534 -270.324235) (xy 361.851956 -270.370509) (xy 361.82143 -270.412525) (xy 361.784707 -270.449248)
			(xy 361.742691 -270.479774) (xy 361.696417 -270.503352) (xy 361.647024 -270.5194) (xy 361.595729 -270.527525)
			(xy 361.543795 -270.527525) (xy 361.4925 -270.5194) (xy 361.443107 -270.503352) (xy 361.396833 -270.479774)
			(xy 361.354817 -270.449248) (xy 361.318094 -270.412525) (xy 361.287568 -270.370509) (xy 361.26399 -270.324235)
			(xy 361.247942 -270.274842) (xy 361.239817 -270.223547) (xy 358.140507 -270.223547) (xy 358.132382 -270.274842)
			(xy 358.116334 -270.324235) (xy 358.092756 -270.370509) (xy 358.06223 -270.412525) (xy 358.025507 -270.449248)
			(xy 357.983491 -270.479774) (xy 357.937217 -270.503352) (xy 357.887824 -270.5194) (xy 357.836529 -270.527525)
			(xy 357.784595 -270.527525) (xy 357.7333 -270.5194) (xy 357.683907 -270.503352) (xy 357.637633 -270.479774)
			(xy 357.595617 -270.449248) (xy 357.558894 -270.412525) (xy 357.528368 -270.370509) (xy 357.50479 -270.324235)
			(xy 357.488742 -270.274842) (xy 357.480617 -270.223547) (xy 357.200707 -270.223547) (xy 357.192582 -270.274842)
			(xy 357.176534 -270.324235) (xy 357.152956 -270.370509) (xy 357.12243 -270.412525) (xy 357.085707 -270.449248)
			(xy 357.043691 -270.479774) (xy 356.997417 -270.503352) (xy 356.948024 -270.5194) (xy 356.896729 -270.527525)
			(xy 356.844795 -270.527525) (xy 356.7935 -270.5194) (xy 356.744107 -270.503352) (xy 356.697833 -270.479774)
			(xy 356.655817 -270.449248) (xy 356.619094 -270.412525) (xy 356.588568 -270.370509) (xy 356.56499 -270.324235)
			(xy 356.548942 -270.274842) (xy 356.540817 -270.223547) (xy 356.261161 -270.223547) (xy 356.253036 -270.274842)
			(xy 356.236988 -270.324235) (xy 356.21341 -270.370509) (xy 356.182884 -270.412525) (xy 356.146161 -270.449248)
			(xy 356.104145 -270.479774) (xy 356.057871 -270.503352) (xy 356.008478 -270.5194) (xy 355.957183 -270.527525)
			(xy 355.905249 -270.527525) (xy 355.853954 -270.5194) (xy 355.804561 -270.503352) (xy 355.758287 -270.479774)
			(xy 355.716271 -270.449248) (xy 355.679548 -270.412525) (xy 355.649022 -270.370509) (xy 355.625444 -270.324235)
			(xy 355.609396 -270.274842) (xy 355.601271 -270.223547) (xy 355.321361 -270.223547) (xy 355.313236 -270.274842)
			(xy 355.297188 -270.324235) (xy 355.27361 -270.370509) (xy 355.243084 -270.412525) (xy 355.206361 -270.449248)
			(xy 355.164345 -270.479774) (xy 355.118071 -270.503352) (xy 355.068678 -270.5194) (xy 355.017383 -270.527525)
			(xy 354.965449 -270.527525) (xy 354.914154 -270.5194) (xy 354.864761 -270.503352) (xy 354.818487 -270.479774)
			(xy 354.776471 -270.449248) (xy 354.739748 -270.412525) (xy 354.709222 -270.370509) (xy 354.685644 -270.324235)
			(xy 354.669596 -270.274842) (xy 354.661471 -270.223547) (xy 354.381561 -270.223547) (xy 354.373436 -270.274842)
			(xy 354.357388 -270.324235) (xy 354.33381 -270.370509) (xy 354.303284 -270.412525) (xy 354.266561 -270.449248)
			(xy 354.224545 -270.479774) (xy 354.178271 -270.503352) (xy 354.128878 -270.5194) (xy 354.077583 -270.527525)
			(xy 354.025649 -270.527525) (xy 353.974354 -270.5194) (xy 353.924961 -270.503352) (xy 353.878687 -270.479774)
			(xy 353.836671 -270.449248) (xy 353.799948 -270.412525) (xy 353.769422 -270.370509) (xy 353.745844 -270.324235)
			(xy 353.729796 -270.274842) (xy 353.721671 -270.223547) (xy 353.441761 -270.223547) (xy 353.433636 -270.274842)
			(xy 353.417588 -270.324235) (xy 353.39401 -270.370509) (xy 353.363484 -270.412525) (xy 353.326761 -270.449248)
			(xy 353.284745 -270.479774) (xy 353.238471 -270.503352) (xy 353.189078 -270.5194) (xy 353.137783 -270.527525)
			(xy 353.085849 -270.527525) (xy 353.034554 -270.5194) (xy 352.985161 -270.503352) (xy 352.938887 -270.479774)
			(xy 352.896871 -270.449248) (xy 352.860148 -270.412525) (xy 352.829622 -270.370509) (xy 352.806044 -270.324235)
			(xy 352.789996 -270.274842) (xy 352.781871 -270.223547) (xy 352.501961 -270.223547) (xy 352.493836 -270.274842)
			(xy 352.477788 -270.324235) (xy 352.45421 -270.370509) (xy 352.423684 -270.412525) (xy 352.386961 -270.449248)
			(xy 352.344945 -270.479774) (xy 352.298671 -270.503352) (xy 352.249278 -270.5194) (xy 352.197983 -270.527525)
			(xy 352.146049 -270.527525) (xy 352.094754 -270.5194) (xy 352.045361 -270.503352) (xy 351.999087 -270.479774)
			(xy 351.957071 -270.449248) (xy 351.920348 -270.412525) (xy 351.889822 -270.370509) (xy 351.866244 -270.324235)
			(xy 351.850196 -270.274842) (xy 351.842071 -270.223547) (xy 351.56218 -270.223547) (xy 351.554219 -270.27424)
			(xy 351.53843 -270.32327) (xy 351.515226 -270.369257) (xy 351.485169 -270.411087) (xy 351.448986 -270.447747)
			(xy 351.407554 -270.478351) (xy 351.361875 -270.502156) (xy 351.313057 -270.518586) (xy 351.26228 -270.527244)
			(xy 351.236534 -270.528034) (xy 351.231962 -270.528034) (xy 351.205355 -270.527478) (xy 351.152834 -270.518919)
			(xy 351.102356 -270.502076) (xy 351.078546 -270.490188) (xy 351.073212 -270.487394) (xy 351.059752 -270.480637)
			(xy 351.030282 -270.474496) (xy 351.000301 -270.477209) (xy 350.972412 -270.488541) (xy 350.949037 -270.507509)
			(xy 350.932203 -270.532465) (xy 350.923372 -270.561244) (xy 350.922844 -270.576294) (xy 350.922844 -270.722598)
			(xy 350.944538 -270.735229) (xy 350.984182 -270.766022) (xy 351.018715 -270.802454) (xy 351.047345 -270.843687)
			(xy 351.069414 -270.888774) (xy 351.084415 -270.936678) (xy 351.092002 -270.986299) (xy 351.092003 -271.036497)
			(xy 351.091871 -271.037363) (xy 351.371917 -271.037363) (xy 351.371917 -270.985429) (xy 351.380042 -270.934134)
			(xy 351.39609 -270.884741) (xy 351.419668 -270.838467) (xy 351.450194 -270.796451) (xy 351.486917 -270.759728)
			(xy 351.528933 -270.729202) (xy 351.575207 -270.705624) (xy 351.6246 -270.689576) (xy 351.675895 -270.681451)
			(xy 351.727829 -270.681451) (xy 351.779124 -270.689576) (xy 351.828517 -270.705624) (xy 351.874791 -270.729202)
			(xy 351.916807 -270.759728) (xy 351.95353 -270.796451) (xy 351.984056 -270.838467) (xy 352.007634 -270.884741)
			(xy 352.023682 -270.934134) (xy 352.031807 -270.985429) (xy 352.032316 -271.011396) (xy 352.031807 -271.037363)
			(xy 352.311717 -271.037363) (xy 352.311717 -270.985429) (xy 352.319842 -270.934134) (xy 352.33589 -270.884741)
			(xy 352.359468 -270.838467) (xy 352.389994 -270.796451) (xy 352.426717 -270.759728) (xy 352.468733 -270.729202)
			(xy 352.515007 -270.705624) (xy 352.5644 -270.689576) (xy 352.615695 -270.681451) (xy 352.667629 -270.681451)
			(xy 352.718924 -270.689576) (xy 352.768317 -270.705624) (xy 352.814591 -270.729202) (xy 352.856607 -270.759728)
			(xy 352.89333 -270.796451) (xy 352.923856 -270.838467) (xy 352.947434 -270.884741) (xy 352.963482 -270.934134)
			(xy 352.971607 -270.985429) (xy 352.972116 -271.011396) (xy 352.971607 -271.037363) (xy 353.251517 -271.037363)
			(xy 353.251517 -270.985429) (xy 353.259642 -270.934134) (xy 353.27569 -270.884741) (xy 353.299268 -270.838467)
			(xy 353.329794 -270.796451) (xy 353.366517 -270.759728) (xy 353.408533 -270.729202) (xy 353.454807 -270.705624)
			(xy 353.5042 -270.689576) (xy 353.555495 -270.681451) (xy 353.607429 -270.681451) (xy 353.658724 -270.689576)
			(xy 353.708117 -270.705624) (xy 353.754391 -270.729202) (xy 353.796407 -270.759728) (xy 353.83313 -270.796451)
			(xy 353.863656 -270.838467) (xy 353.887234 -270.884741) (xy 353.903282 -270.934134) (xy 353.911407 -270.985429)
			(xy 353.911916 -271.011396) (xy 353.911407 -271.037363) (xy 354.191317 -271.037363) (xy 354.191317 -270.985429)
			(xy 354.199442 -270.934134) (xy 354.21549 -270.884741) (xy 354.239068 -270.838467) (xy 354.269594 -270.796451)
			(xy 354.306317 -270.759728) (xy 354.348333 -270.729202) (xy 354.394607 -270.705624) (xy 354.444 -270.689576)
			(xy 354.495295 -270.681451) (xy 354.547229 -270.681451) (xy 354.598524 -270.689576) (xy 354.647917 -270.705624)
			(xy 354.694191 -270.729202) (xy 354.736207 -270.759728) (xy 354.77293 -270.796451) (xy 354.803456 -270.838467)
			(xy 354.827034 -270.884741) (xy 354.843082 -270.934134) (xy 354.851207 -270.985429) (xy 354.851716 -271.011396)
			(xy 354.851207 -271.037363) (xy 355.131117 -271.037363) (xy 355.131117 -270.985429) (xy 355.139242 -270.934134)
			(xy 355.15529 -270.884741) (xy 355.178868 -270.838467) (xy 355.209394 -270.796451) (xy 355.246117 -270.759728)
			(xy 355.288133 -270.729202) (xy 355.334407 -270.705624) (xy 355.3838 -270.689576) (xy 355.435095 -270.681451)
			(xy 355.487029 -270.681451) (xy 355.538324 -270.689576) (xy 355.587717 -270.705624) (xy 355.633991 -270.729202)
			(xy 355.676007 -270.759728) (xy 355.71273 -270.796451) (xy 355.743256 -270.838467) (xy 355.766834 -270.884741)
			(xy 355.782882 -270.934134) (xy 355.791007 -270.985429) (xy 355.791516 -271.011396) (xy 355.791007 -271.037363)
			(xy 356.070917 -271.037363) (xy 356.070917 -270.985429) (xy 356.079042 -270.934134) (xy 356.09509 -270.884741)
			(xy 356.118668 -270.838467) (xy 356.149194 -270.796451) (xy 356.185917 -270.759728) (xy 356.227933 -270.729202)
			(xy 356.274207 -270.705624) (xy 356.3236 -270.689576) (xy 356.374895 -270.681451) (xy 356.426829 -270.681451)
			(xy 356.478124 -270.689576) (xy 356.527517 -270.705624) (xy 356.573791 -270.729202) (xy 356.615807 -270.759728)
			(xy 356.65253 -270.796451) (xy 356.683056 -270.838467) (xy 356.706634 -270.884741) (xy 356.722682 -270.934134)
			(xy 356.730807 -270.985429) (xy 356.731316 -271.011396) (xy 356.730807 -271.037363) (xy 357.010717 -271.037363)
			(xy 357.010717 -270.985429) (xy 357.018842 -270.934134) (xy 357.03489 -270.884741) (xy 357.058468 -270.838467)
			(xy 357.088994 -270.796451) (xy 357.125717 -270.759728) (xy 357.167733 -270.729202) (xy 357.214007 -270.705624)
			(xy 357.2634 -270.689576) (xy 357.314695 -270.681451) (xy 357.366629 -270.681451) (xy 357.417924 -270.689576)
			(xy 357.467317 -270.705624) (xy 357.513591 -270.729202) (xy 357.555607 -270.759728) (xy 357.59233 -270.796451)
			(xy 357.622856 -270.838467) (xy 357.646434 -270.884741) (xy 357.662482 -270.934134) (xy 357.670607 -270.985429)
			(xy 357.671116 -271.011396) (xy 357.670607 -271.037363) (xy 357.950517 -271.037363) (xy 357.950517 -270.985429)
			(xy 357.958642 -270.934134) (xy 357.97469 -270.884741) (xy 357.998268 -270.838467) (xy 358.028794 -270.796451)
			(xy 358.065517 -270.759728) (xy 358.107533 -270.729202) (xy 358.153807 -270.705624) (xy 358.2032 -270.689576)
			(xy 358.254495 -270.681451) (xy 358.306429 -270.681451) (xy 358.357724 -270.689576) (xy 358.407117 -270.705624)
			(xy 358.453391 -270.729202) (xy 358.495407 -270.759728) (xy 358.53213 -270.796451) (xy 358.562656 -270.838467)
			(xy 358.586234 -270.884741) (xy 358.602282 -270.934134) (xy 358.610407 -270.985429) (xy 358.610916 -271.011396)
			(xy 358.610407 -271.037363) (xy 361.709717 -271.037363) (xy 361.709717 -270.985429) (xy 361.717842 -270.934134)
			(xy 361.73389 -270.884741) (xy 361.757468 -270.838467) (xy 361.787994 -270.796451) (xy 361.824717 -270.759728)
			(xy 361.866733 -270.729202) (xy 361.913007 -270.705624) (xy 361.9624 -270.689576) (xy 362.013695 -270.681451)
			(xy 362.065629 -270.681451) (xy 362.116924 -270.689576) (xy 362.166317 -270.705624) (xy 362.212591 -270.729202)
			(xy 362.254607 -270.759728) (xy 362.29133 -270.796451) (xy 362.321856 -270.838467) (xy 362.345434 -270.884741)
			(xy 362.361482 -270.934134) (xy 362.369607 -270.985429) (xy 362.370116 -271.011396) (xy 362.369607 -271.037363)
			(xy 362.649517 -271.037363) (xy 362.649517 -270.985429) (xy 362.657642 -270.934134) (xy 362.67369 -270.884741)
			(xy 362.697268 -270.838467) (xy 362.727794 -270.796451) (xy 362.764517 -270.759728) (xy 362.806533 -270.729202)
			(xy 362.852807 -270.705624) (xy 362.9022 -270.689576) (xy 362.953495 -270.681451) (xy 363.005429 -270.681451)
			(xy 363.056724 -270.689576) (xy 363.106117 -270.705624) (xy 363.152391 -270.729202) (xy 363.194407 -270.759728)
			(xy 363.23113 -270.796451) (xy 363.261656 -270.838467) (xy 363.285234 -270.884741) (xy 363.301282 -270.934134)
			(xy 363.309407 -270.985429) (xy 363.309916 -271.011396) (xy 363.309407 -271.037363) (xy 363.301282 -271.088658)
			(xy 363.285234 -271.138051) (xy 363.261656 -271.184325) (xy 363.23113 -271.226341) (xy 363.194407 -271.263064)
			(xy 363.152391 -271.29359) (xy 363.106117 -271.317168) (xy 363.056724 -271.333216) (xy 363.005429 -271.341341)
			(xy 362.953495 -271.341341) (xy 362.9022 -271.333216) (xy 362.852807 -271.317168) (xy 362.806533 -271.29359)
			(xy 362.764517 -271.263064) (xy 362.727794 -271.226341) (xy 362.697268 -271.184325) (xy 362.67369 -271.138051)
			(xy 362.657642 -271.088658) (xy 362.649517 -271.037363) (xy 362.369607 -271.037363) (xy 362.361482 -271.088658)
			(xy 362.345434 -271.138051) (xy 362.321856 -271.184325) (xy 362.29133 -271.226341) (xy 362.254607 -271.263064)
			(xy 362.212591 -271.29359) (xy 362.166317 -271.317168) (xy 362.116924 -271.333216) (xy 362.065629 -271.341341)
			(xy 362.013695 -271.341341) (xy 361.9624 -271.333216) (xy 361.913007 -271.317168) (xy 361.866733 -271.29359)
			(xy 361.824717 -271.263064) (xy 361.787994 -271.226341) (xy 361.757468 -271.184325) (xy 361.73389 -271.138051)
			(xy 361.717842 -271.088658) (xy 361.709717 -271.037363) (xy 358.610407 -271.037363) (xy 358.602282 -271.088658)
			(xy 358.586234 -271.138051) (xy 358.562656 -271.184325) (xy 358.53213 -271.226341) (xy 358.495407 -271.263064)
			(xy 358.453391 -271.29359) (xy 358.407117 -271.317168) (xy 358.357724 -271.333216) (xy 358.306429 -271.341341)
			(xy 358.254495 -271.341341) (xy 358.2032 -271.333216) (xy 358.153807 -271.317168) (xy 358.107533 -271.29359)
			(xy 358.065517 -271.263064) (xy 358.028794 -271.226341) (xy 357.998268 -271.184325) (xy 357.97469 -271.138051)
			(xy 357.958642 -271.088658) (xy 357.950517 -271.037363) (xy 357.670607 -271.037363) (xy 357.662482 -271.088658)
			(xy 357.646434 -271.138051) (xy 357.622856 -271.184325) (xy 357.59233 -271.226341) (xy 357.555607 -271.263064)
			(xy 357.513591 -271.29359) (xy 357.467317 -271.317168) (xy 357.417924 -271.333216) (xy 357.366629 -271.341341)
			(xy 357.314695 -271.341341) (xy 357.2634 -271.333216) (xy 357.214007 -271.317168) (xy 357.167733 -271.29359)
			(xy 357.125717 -271.263064) (xy 357.088994 -271.226341) (xy 357.058468 -271.184325) (xy 357.03489 -271.138051)
			(xy 357.018842 -271.088658) (xy 357.010717 -271.037363) (xy 356.730807 -271.037363) (xy 356.722682 -271.088658)
			(xy 356.706634 -271.138051) (xy 356.683056 -271.184325) (xy 356.65253 -271.226341) (xy 356.615807 -271.263064)
			(xy 356.573791 -271.29359) (xy 356.527517 -271.317168) (xy 356.478124 -271.333216) (xy 356.426829 -271.341341)
			(xy 356.374895 -271.341341) (xy 356.3236 -271.333216) (xy 356.274207 -271.317168) (xy 356.227933 -271.29359)
			(xy 356.185917 -271.263064) (xy 356.149194 -271.226341) (xy 356.118668 -271.184325) (xy 356.09509 -271.138051)
			(xy 356.079042 -271.088658) (xy 356.070917 -271.037363) (xy 355.791007 -271.037363) (xy 355.782882 -271.088658)
			(xy 355.766834 -271.138051) (xy 355.743256 -271.184325) (xy 355.71273 -271.226341) (xy 355.676007 -271.263064)
			(xy 355.633991 -271.29359) (xy 355.587717 -271.317168) (xy 355.538324 -271.333216) (xy 355.487029 -271.341341)
			(xy 355.435095 -271.341341) (xy 355.3838 -271.333216) (xy 355.334407 -271.317168) (xy 355.288133 -271.29359)
			(xy 355.246117 -271.263064) (xy 355.209394 -271.226341) (xy 355.178868 -271.184325) (xy 355.15529 -271.138051)
			(xy 355.139242 -271.088658) (xy 355.131117 -271.037363) (xy 354.851207 -271.037363) (xy 354.843082 -271.088658)
			(xy 354.827034 -271.138051) (xy 354.803456 -271.184325) (xy 354.77293 -271.226341) (xy 354.736207 -271.263064)
			(xy 354.694191 -271.29359) (xy 354.647917 -271.317168) (xy 354.598524 -271.333216) (xy 354.547229 -271.341341)
			(xy 354.495295 -271.341341) (xy 354.444 -271.333216) (xy 354.394607 -271.317168) (xy 354.348333 -271.29359)
			(xy 354.306317 -271.263064) (xy 354.269594 -271.226341) (xy 354.239068 -271.184325) (xy 354.21549 -271.138051)
			(xy 354.199442 -271.088658) (xy 354.191317 -271.037363) (xy 353.911407 -271.037363) (xy 353.903282 -271.088658)
			(xy 353.887234 -271.138051) (xy 353.863656 -271.184325) (xy 353.83313 -271.226341) (xy 353.796407 -271.263064)
			(xy 353.754391 -271.29359) (xy 353.708117 -271.317168) (xy 353.658724 -271.333216) (xy 353.607429 -271.341341)
			(xy 353.555495 -271.341341) (xy 353.5042 -271.333216) (xy 353.454807 -271.317168) (xy 353.408533 -271.29359)
			(xy 353.366517 -271.263064) (xy 353.329794 -271.226341) (xy 353.299268 -271.184325) (xy 353.27569 -271.138051)
			(xy 353.259642 -271.088658) (xy 353.251517 -271.037363) (xy 352.971607 -271.037363) (xy 352.963482 -271.088658)
			(xy 352.947434 -271.138051) (xy 352.923856 -271.184325) (xy 352.89333 -271.226341) (xy 352.856607 -271.263064)
			(xy 352.814591 -271.29359) (xy 352.768317 -271.317168) (xy 352.718924 -271.333216) (xy 352.667629 -271.341341)
			(xy 352.615695 -271.341341) (xy 352.5644 -271.333216) (xy 352.515007 -271.317168) (xy 352.468733 -271.29359)
			(xy 352.426717 -271.263064) (xy 352.389994 -271.226341) (xy 352.359468 -271.184325) (xy 352.33589 -271.138051)
			(xy 352.319842 -271.088658) (xy 352.311717 -271.037363) (xy 352.031807 -271.037363) (xy 352.023682 -271.088658)
			(xy 352.007634 -271.138051) (xy 351.984056 -271.184325) (xy 351.95353 -271.226341) (xy 351.916807 -271.263064)
			(xy 351.874791 -271.29359) (xy 351.828517 -271.317168) (xy 351.779124 -271.333216) (xy 351.727829 -271.341341)
			(xy 351.675895 -271.341341) (xy 351.6246 -271.333216) (xy 351.575207 -271.317168) (xy 351.528933 -271.29359)
			(xy 351.486917 -271.263064) (xy 351.450194 -271.226341) (xy 351.419668 -271.184325) (xy 351.39609 -271.138051)
			(xy 351.380042 -271.088658) (xy 351.371917 -271.037363) (xy 351.091871 -271.037363) (xy 351.084416 -271.086118)
			(xy 351.069416 -271.134023) (xy 351.047347 -271.17911) (xy 351.018718 -271.220343) (xy 350.984184 -271.256775)
			(xy 350.944541 -271.287569) (xy 350.922844 -271.300194) (xy 350.922844 -271.446498) (xy 350.923378 -271.461301)
			(xy 350.931926 -271.489648) (xy 350.948246 -271.514351) (xy 350.970966 -271.533336) (xy 350.998176 -271.545006)
			(xy 351.027591 -271.54838) (xy 351.056737 -271.543175) (xy 351.070164 -271.536922) (xy 351.078546 -271.532604)
			(xy 351.102117 -271.520801) (xy 351.152084 -271.504017) (xy 351.204085 -271.495398) (xy 351.230438 -271.494758)
			(xy 351.236534 -271.494758) (xy 351.262277 -271.495588) (xy 351.313049 -271.504245) (xy 351.361863 -271.520674)
			(xy 351.407537 -271.544476) (xy 351.448965 -271.575077) (xy 351.485145 -271.611734) (xy 351.515199 -271.65356)
			(xy 351.538401 -271.699542) (xy 351.554188 -271.748567) (xy 351.562178 -271.799448) (xy 351.562178 -271.850952)
			(xy 351.562142 -271.851179) (xy 351.842071 -271.851179) (xy 351.842071 -271.799245) (xy 351.850196 -271.74795)
			(xy 351.866244 -271.698557) (xy 351.889822 -271.652283) (xy 351.920348 -271.610267) (xy 351.957071 -271.573544)
			(xy 351.999087 -271.543018) (xy 352.045361 -271.51944) (xy 352.094754 -271.503392) (xy 352.146049 -271.495267)
			(xy 352.197983 -271.495267) (xy 352.249278 -271.503392) (xy 352.298671 -271.51944) (xy 352.344945 -271.543018)
			(xy 352.386961 -271.573544) (xy 352.423684 -271.610267) (xy 352.45421 -271.652283) (xy 352.477788 -271.698557)
			(xy 352.493836 -271.74795) (xy 352.501961 -271.799245) (xy 352.50247 -271.825212) (xy 352.501961 -271.851179)
			(xy 352.781871 -271.851179) (xy 352.781871 -271.799245) (xy 352.789996 -271.74795) (xy 352.806044 -271.698557)
			(xy 352.829622 -271.652283) (xy 352.860148 -271.610267) (xy 352.896871 -271.573544) (xy 352.938887 -271.543018)
			(xy 352.985161 -271.51944) (xy 353.034554 -271.503392) (xy 353.085849 -271.495267) (xy 353.137783 -271.495267)
			(xy 353.189078 -271.503392) (xy 353.238471 -271.51944) (xy 353.284745 -271.543018) (xy 353.326761 -271.573544)
			(xy 353.363484 -271.610267) (xy 353.39401 -271.652283) (xy 353.417588 -271.698557) (xy 353.433636 -271.74795)
			(xy 353.441761 -271.799245) (xy 353.44227 -271.825212) (xy 353.441761 -271.851179) (xy 353.721671 -271.851179)
			(xy 353.721671 -271.799245) (xy 353.729796 -271.74795) (xy 353.745844 -271.698557) (xy 353.769422 -271.652283)
			(xy 353.799948 -271.610267) (xy 353.836671 -271.573544) (xy 353.878687 -271.543018) (xy 353.924961 -271.51944)
			(xy 353.974354 -271.503392) (xy 354.025649 -271.495267) (xy 354.077583 -271.495267) (xy 354.128878 -271.503392)
			(xy 354.178271 -271.51944) (xy 354.224545 -271.543018) (xy 354.266561 -271.573544) (xy 354.303284 -271.610267)
			(xy 354.33381 -271.652283) (xy 354.357388 -271.698557) (xy 354.373436 -271.74795) (xy 354.381561 -271.799245)
			(xy 354.38207 -271.825212) (xy 354.381561 -271.851179) (xy 354.661471 -271.851179) (xy 354.661471 -271.799245)
			(xy 354.669596 -271.74795) (xy 354.685644 -271.698557) (xy 354.709222 -271.652283) (xy 354.739748 -271.610267)
			(xy 354.776471 -271.573544) (xy 354.818487 -271.543018) (xy 354.864761 -271.51944) (xy 354.914154 -271.503392)
			(xy 354.965449 -271.495267) (xy 355.017383 -271.495267) (xy 355.068678 -271.503392) (xy 355.118071 -271.51944)
			(xy 355.164345 -271.543018) (xy 355.206361 -271.573544) (xy 355.243084 -271.610267) (xy 355.27361 -271.652283)
			(xy 355.297188 -271.698557) (xy 355.313236 -271.74795) (xy 355.321361 -271.799245) (xy 355.32187 -271.825212)
			(xy 355.321361 -271.851179) (xy 355.601271 -271.851179) (xy 355.601271 -271.799245) (xy 355.609396 -271.74795)
			(xy 355.625444 -271.698557) (xy 355.649022 -271.652283) (xy 355.679548 -271.610267) (xy 355.716271 -271.573544)
			(xy 355.758287 -271.543018) (xy 355.804561 -271.51944) (xy 355.853954 -271.503392) (xy 355.905249 -271.495267)
			(xy 355.957183 -271.495267) (xy 356.008478 -271.503392) (xy 356.057871 -271.51944) (xy 356.104145 -271.543018)
			(xy 356.146161 -271.573544) (xy 356.182884 -271.610267) (xy 356.21341 -271.652283) (xy 356.236988 -271.698557)
			(xy 356.253036 -271.74795) (xy 356.261161 -271.799245) (xy 356.26167 -271.825212) (xy 356.261161 -271.851179)
			(xy 356.541071 -271.851179) (xy 356.541071 -271.799245) (xy 356.549196 -271.74795) (xy 356.565244 -271.698557)
			(xy 356.588822 -271.652283) (xy 356.619348 -271.610267) (xy 356.656071 -271.573544) (xy 356.698087 -271.543018)
			(xy 356.744361 -271.51944) (xy 356.793754 -271.503392) (xy 356.845049 -271.495267) (xy 356.896983 -271.495267)
			(xy 356.948278 -271.503392) (xy 356.997671 -271.51944) (xy 357.043945 -271.543018) (xy 357.085961 -271.573544)
			(xy 357.122684 -271.610267) (xy 357.15321 -271.652283) (xy 357.176788 -271.698557) (xy 357.192836 -271.74795)
			(xy 357.200961 -271.799245) (xy 357.20147 -271.825212) (xy 357.200961 -271.851179) (xy 357.480363 -271.851179)
			(xy 357.480363 -271.799245) (xy 357.488488 -271.74795) (xy 357.504536 -271.698557) (xy 357.528114 -271.652283)
			(xy 357.55864 -271.610267) (xy 357.595363 -271.573544) (xy 357.637379 -271.543018) (xy 357.683653 -271.51944)
			(xy 357.733046 -271.503392) (xy 357.784341 -271.495267) (xy 357.836275 -271.495267) (xy 357.88757 -271.503392)
			(xy 357.936963 -271.51944) (xy 357.983237 -271.543018) (xy 358.025253 -271.573544) (xy 358.061976 -271.610267)
			(xy 358.092502 -271.652283) (xy 358.11608 -271.698557) (xy 358.132128 -271.74795) (xy 358.140253 -271.799245)
			(xy 358.140762 -271.825212) (xy 358.140253 -271.851179) (xy 361.239817 -271.851179) (xy 361.239817 -271.799245)
			(xy 361.247942 -271.74795) (xy 361.26399 -271.698557) (xy 361.287568 -271.652283) (xy 361.318094 -271.610267)
			(xy 361.354817 -271.573544) (xy 361.396833 -271.543018) (xy 361.443107 -271.51944) (xy 361.4925 -271.503392)
			(xy 361.543795 -271.495267) (xy 361.595729 -271.495267) (xy 361.647024 -271.503392) (xy 361.696417 -271.51944)
			(xy 361.742691 -271.543018) (xy 361.784707 -271.573544) (xy 361.82143 -271.610267) (xy 361.851956 -271.652283)
			(xy 361.875534 -271.698557) (xy 361.891582 -271.74795) (xy 361.899707 -271.799245) (xy 361.900216 -271.825212)
			(xy 361.899707 -271.851179) (xy 362.179871 -271.851179) (xy 362.179871 -271.799245) (xy 362.187996 -271.74795)
			(xy 362.204044 -271.698557) (xy 362.227622 -271.652283) (xy 362.258148 -271.610267) (xy 362.294871 -271.573544)
			(xy 362.336887 -271.543018) (xy 362.383161 -271.51944) (xy 362.432554 -271.503392) (xy 362.483849 -271.495267)
			(xy 362.535783 -271.495267) (xy 362.587078 -271.503392) (xy 362.636471 -271.51944) (xy 362.682745 -271.543018)
			(xy 362.724761 -271.573544) (xy 362.761484 -271.610267) (xy 362.79201 -271.652283) (xy 362.815588 -271.698557)
			(xy 362.831636 -271.74795) (xy 362.839761 -271.799245) (xy 362.84027 -271.825212) (xy 362.839761 -271.851179)
			(xy 363.119671 -271.851179) (xy 363.119671 -271.799245) (xy 363.127796 -271.74795) (xy 363.143844 -271.698557)
			(xy 363.167422 -271.652283) (xy 363.197948 -271.610267) (xy 363.234671 -271.573544) (xy 363.276687 -271.543018)
			(xy 363.322961 -271.51944) (xy 363.372354 -271.503392) (xy 363.423649 -271.495267) (xy 363.475583 -271.495267)
			(xy 363.526878 -271.503392) (xy 363.576271 -271.51944) (xy 363.622545 -271.543018) (xy 363.664561 -271.573544)
			(xy 363.701284 -271.610267) (xy 363.73181 -271.652283) (xy 363.755388 -271.698557) (xy 363.771436 -271.74795)
			(xy 363.779561 -271.799245) (xy 363.78007 -271.825212) (xy 363.779561 -271.851179) (xy 363.771436 -271.902474)
			(xy 363.755388 -271.951867) (xy 363.73181 -271.998141) (xy 363.701284 -272.040157) (xy 363.664561 -272.07688)
			(xy 363.622545 -272.107406) (xy 363.576271 -272.130984) (xy 363.526878 -272.147032) (xy 363.475583 -272.155157)
			(xy 363.423649 -272.155157) (xy 363.372354 -272.147032) (xy 363.322961 -272.130984) (xy 363.276687 -272.107406)
			(xy 363.234671 -272.07688) (xy 363.197948 -272.040157) (xy 363.167422 -271.998141) (xy 363.143844 -271.951867)
			(xy 363.127796 -271.902474) (xy 363.119671 -271.851179) (xy 362.839761 -271.851179) (xy 362.831636 -271.902474)
			(xy 362.815588 -271.951867) (xy 362.79201 -271.998141) (xy 362.761484 -272.040157) (xy 362.724761 -272.07688)
			(xy 362.682745 -272.107406) (xy 362.636471 -272.130984) (xy 362.587078 -272.147032) (xy 362.535783 -272.155157)
			(xy 362.483849 -272.155157) (xy 362.432554 -272.147032) (xy 362.383161 -272.130984) (xy 362.336887 -272.107406)
			(xy 362.294871 -272.07688) (xy 362.258148 -272.040157) (xy 362.227622 -271.998141) (xy 362.204044 -271.951867)
			(xy 362.187996 -271.902474) (xy 362.179871 -271.851179) (xy 361.899707 -271.851179) (xy 361.891582 -271.902474)
			(xy 361.875534 -271.951867) (xy 361.851956 -271.998141) (xy 361.82143 -272.040157) (xy 361.784707 -272.07688)
			(xy 361.742691 -272.107406) (xy 361.696417 -272.130984) (xy 361.647024 -272.147032) (xy 361.595729 -272.155157)
			(xy 361.543795 -272.155157) (xy 361.4925 -272.147032) (xy 361.443107 -272.130984) (xy 361.396833 -272.107406)
			(xy 361.354817 -272.07688) (xy 361.318094 -272.040157) (xy 361.287568 -271.998141) (xy 361.26399 -271.951867)
			(xy 361.247942 -271.902474) (xy 361.239817 -271.851179) (xy 358.140253 -271.851179) (xy 358.132128 -271.902474)
			(xy 358.11608 -271.951867) (xy 358.092502 -271.998141) (xy 358.061976 -272.040157) (xy 358.025253 -272.07688)
			(xy 357.983237 -272.107406) (xy 357.936963 -272.130984) (xy 357.88757 -272.147032) (xy 357.836275 -272.155157)
			(xy 357.784341 -272.155157) (xy 357.733046 -272.147032) (xy 357.683653 -272.130984) (xy 357.637379 -272.107406)
			(xy 357.595363 -272.07688) (xy 357.55864 -272.040157) (xy 357.528114 -271.998141) (xy 357.504536 -271.951867)
			(xy 357.488488 -271.902474) (xy 357.480363 -271.851179) (xy 357.200961 -271.851179) (xy 357.192836 -271.902474)
			(xy 357.176788 -271.951867) (xy 357.15321 -271.998141) (xy 357.122684 -272.040157) (xy 357.085961 -272.07688)
			(xy 357.043945 -272.107406) (xy 356.997671 -272.130984) (xy 356.948278 -272.147032) (xy 356.896983 -272.155157)
			(xy 356.845049 -272.155157) (xy 356.793754 -272.147032) (xy 356.744361 -272.130984) (xy 356.698087 -272.107406)
			(xy 356.656071 -272.07688) (xy 356.619348 -272.040157) (xy 356.588822 -271.998141) (xy 356.565244 -271.951867)
			(xy 356.549196 -271.902474) (xy 356.541071 -271.851179) (xy 356.261161 -271.851179) (xy 356.253036 -271.902474)
			(xy 356.236988 -271.951867) (xy 356.21341 -271.998141) (xy 356.182884 -272.040157) (xy 356.146161 -272.07688)
			(xy 356.104145 -272.107406) (xy 356.057871 -272.130984) (xy 356.008478 -272.147032) (xy 355.957183 -272.155157)
			(xy 355.905249 -272.155157) (xy 355.853954 -272.147032) (xy 355.804561 -272.130984) (xy 355.758287 -272.107406)
			(xy 355.716271 -272.07688) (xy 355.679548 -272.040157) (xy 355.649022 -271.998141) (xy 355.625444 -271.951867)
			(xy 355.609396 -271.902474) (xy 355.601271 -271.851179) (xy 355.321361 -271.851179) (xy 355.313236 -271.902474)
			(xy 355.297188 -271.951867) (xy 355.27361 -271.998141) (xy 355.243084 -272.040157) (xy 355.206361 -272.07688)
			(xy 355.164345 -272.107406) (xy 355.118071 -272.130984) (xy 355.068678 -272.147032) (xy 355.017383 -272.155157)
			(xy 354.965449 -272.155157) (xy 354.914154 -272.147032) (xy 354.864761 -272.130984) (xy 354.818487 -272.107406)
			(xy 354.776471 -272.07688) (xy 354.739748 -272.040157) (xy 354.709222 -271.998141) (xy 354.685644 -271.951867)
			(xy 354.669596 -271.902474) (xy 354.661471 -271.851179) (xy 354.381561 -271.851179) (xy 354.373436 -271.902474)
			(xy 354.357388 -271.951867) (xy 354.33381 -271.998141) (xy 354.303284 -272.040157) (xy 354.266561 -272.07688)
			(xy 354.224545 -272.107406) (xy 354.178271 -272.130984) (xy 354.128878 -272.147032) (xy 354.077583 -272.155157)
			(xy 354.025649 -272.155157) (xy 353.974354 -272.147032) (xy 353.924961 -272.130984) (xy 353.878687 -272.107406)
			(xy 353.836671 -272.07688) (xy 353.799948 -272.040157) (xy 353.769422 -271.998141) (xy 353.745844 -271.951867)
			(xy 353.729796 -271.902474) (xy 353.721671 -271.851179) (xy 353.441761 -271.851179) (xy 353.433636 -271.902474)
			(xy 353.417588 -271.951867) (xy 353.39401 -271.998141) (xy 353.363484 -272.040157) (xy 353.326761 -272.07688)
			(xy 353.284745 -272.107406) (xy 353.238471 -272.130984) (xy 353.189078 -272.147032) (xy 353.137783 -272.155157)
			(xy 353.085849 -272.155157) (xy 353.034554 -272.147032) (xy 352.985161 -272.130984) (xy 352.938887 -272.107406)
			(xy 352.896871 -272.07688) (xy 352.860148 -272.040157) (xy 352.829622 -271.998141) (xy 352.806044 -271.951867)
			(xy 352.789996 -271.902474) (xy 352.781871 -271.851179) (xy 352.501961 -271.851179) (xy 352.493836 -271.902474)
			(xy 352.477788 -271.951867) (xy 352.45421 -271.998141) (xy 352.423684 -272.040157) (xy 352.386961 -272.07688)
			(xy 352.344945 -272.107406) (xy 352.298671 -272.130984) (xy 352.249278 -272.147032) (xy 352.197983 -272.155157)
			(xy 352.146049 -272.155157) (xy 352.094754 -272.147032) (xy 352.045361 -272.130984) (xy 351.999087 -272.107406)
			(xy 351.957071 -272.07688) (xy 351.920348 -272.040157) (xy 351.889822 -271.998141) (xy 351.866244 -271.951867)
			(xy 351.850196 -271.902474) (xy 351.842071 -271.851179) (xy 351.562142 -271.851179) (xy 351.554188 -271.901833)
			(xy 351.538401 -271.950858) (xy 351.515199 -271.99684) (xy 351.485144 -272.038666) (xy 351.448965 -272.075323)
			(xy 351.407537 -272.105924) (xy 351.361862 -272.129726) (xy 351.313049 -272.146155) (xy 351.262277 -272.154812)
			(xy 351.236534 -272.155666) (xy 351.231962 -272.155666) (xy 351.205355 -272.15511) (xy 351.152833 -272.146552)
			(xy 351.102354 -272.12971) (xy 351.078546 -272.11782) (xy 351.073212 -272.115026) (xy 351.059748 -272.108272)
			(xy 351.030274 -272.102136) (xy 351.00029 -272.10485) (xy 350.972397 -272.116181) (xy 350.949014 -272.135145)
			(xy 350.932169 -272.160097) (xy 350.923322 -272.188874) (xy 350.922844 -272.203926) (xy 350.922844 -272.350484)
			(xy 350.944539 -272.363115) (xy 350.984185 -272.393909) (xy 351.01872 -272.430341) (xy 351.047352 -272.471575)
			(xy 351.069423 -272.516663) (xy 351.084425 -272.564568) (xy 351.092014 -272.614191) (xy 351.092015 -272.664391)
			(xy 351.091884 -272.665249) (xy 351.371917 -272.665249) (xy 351.371917 -272.613315) (xy 351.380042 -272.56202)
			(xy 351.39609 -272.512627) (xy 351.419668 -272.466353) (xy 351.450194 -272.424337) (xy 351.486917 -272.387614)
			(xy 351.528933 -272.357088) (xy 351.575207 -272.33351) (xy 351.6246 -272.317462) (xy 351.675895 -272.309337)
			(xy 351.727829 -272.309337) (xy 351.779124 -272.317462) (xy 351.828517 -272.33351) (xy 351.874791 -272.357088)
			(xy 351.916807 -272.387614) (xy 351.95353 -272.424337) (xy 351.984056 -272.466353) (xy 352.007634 -272.512627)
			(xy 352.023682 -272.56202) (xy 352.031807 -272.613315) (xy 352.032316 -272.639282) (xy 352.031807 -272.665249)
			(xy 352.311717 -272.665249) (xy 352.311717 -272.613315) (xy 352.319842 -272.56202) (xy 352.33589 -272.512627)
			(xy 352.359468 -272.466353) (xy 352.389994 -272.424337) (xy 352.426717 -272.387614) (xy 352.468733 -272.357088)
			(xy 352.515007 -272.33351) (xy 352.5644 -272.317462) (xy 352.615695 -272.309337) (xy 352.667629 -272.309337)
			(xy 352.718924 -272.317462) (xy 352.768317 -272.33351) (xy 352.814591 -272.357088) (xy 352.856607 -272.387614)
			(xy 352.89333 -272.424337) (xy 352.923856 -272.466353) (xy 352.947434 -272.512627) (xy 352.963482 -272.56202)
			(xy 352.971607 -272.613315) (xy 352.972116 -272.639282) (xy 352.971607 -272.665249) (xy 353.251517 -272.665249)
			(xy 353.251517 -272.613315) (xy 353.259642 -272.56202) (xy 353.27569 -272.512627) (xy 353.299268 -272.466353)
			(xy 353.329794 -272.424337) (xy 353.366517 -272.387614) (xy 353.408533 -272.357088) (xy 353.454807 -272.33351)
			(xy 353.5042 -272.317462) (xy 353.555495 -272.309337) (xy 353.607429 -272.309337) (xy 353.658724 -272.317462)
			(xy 353.708117 -272.33351) (xy 353.754391 -272.357088) (xy 353.796407 -272.387614) (xy 353.83313 -272.424337)
			(xy 353.863656 -272.466353) (xy 353.887234 -272.512627) (xy 353.903282 -272.56202) (xy 353.911407 -272.613315)
			(xy 353.911916 -272.639282) (xy 353.911407 -272.665249) (xy 354.191317 -272.665249) (xy 354.191317 -272.613315)
			(xy 354.199442 -272.56202) (xy 354.21549 -272.512627) (xy 354.239068 -272.466353) (xy 354.269594 -272.424337)
			(xy 354.306317 -272.387614) (xy 354.348333 -272.357088) (xy 354.394607 -272.33351) (xy 354.444 -272.317462)
			(xy 354.495295 -272.309337) (xy 354.547229 -272.309337) (xy 354.598524 -272.317462) (xy 354.647917 -272.33351)
			(xy 354.694191 -272.357088) (xy 354.736207 -272.387614) (xy 354.77293 -272.424337) (xy 354.803456 -272.466353)
			(xy 354.827034 -272.512627) (xy 354.843082 -272.56202) (xy 354.851207 -272.613315) (xy 354.851716 -272.639282)
			(xy 354.851207 -272.665249) (xy 355.131117 -272.665249) (xy 355.131117 -272.613315) (xy 355.139242 -272.56202)
			(xy 355.15529 -272.512627) (xy 355.178868 -272.466353) (xy 355.209394 -272.424337) (xy 355.246117 -272.387614)
			(xy 355.288133 -272.357088) (xy 355.334407 -272.33351) (xy 355.3838 -272.317462) (xy 355.435095 -272.309337)
			(xy 355.487029 -272.309337) (xy 355.538324 -272.317462) (xy 355.587717 -272.33351) (xy 355.633991 -272.357088)
			(xy 355.676007 -272.387614) (xy 355.71273 -272.424337) (xy 355.743256 -272.466353) (xy 355.766834 -272.512627)
			(xy 355.782882 -272.56202) (xy 355.791007 -272.613315) (xy 355.791516 -272.639282) (xy 355.791007 -272.665249)
			(xy 355.782882 -272.716544) (xy 355.766834 -272.765937) (xy 355.743256 -272.812211) (xy 355.71273 -272.854227)
			(xy 355.676007 -272.89095) (xy 355.633991 -272.921476) (xy 355.587717 -272.945054) (xy 355.538324 -272.961102)
			(xy 355.487029 -272.969227) (xy 355.435095 -272.969227) (xy 355.3838 -272.961102) (xy 355.334407 -272.945054)
			(xy 355.288133 -272.921476) (xy 355.246117 -272.89095) (xy 355.209394 -272.854227) (xy 355.178868 -272.812211)
			(xy 355.15529 -272.765937) (xy 355.139242 -272.716544) (xy 355.131117 -272.665249) (xy 354.851207 -272.665249)
			(xy 354.843082 -272.716544) (xy 354.827034 -272.765937) (xy 354.803456 -272.812211) (xy 354.77293 -272.854227)
			(xy 354.736207 -272.89095) (xy 354.694191 -272.921476) (xy 354.647917 -272.945054) (xy 354.598524 -272.961102)
			(xy 354.547229 -272.969227) (xy 354.495295 -272.969227) (xy 354.444 -272.961102) (xy 354.394607 -272.945054)
			(xy 354.348333 -272.921476) (xy 354.306317 -272.89095) (xy 354.269594 -272.854227) (xy 354.239068 -272.812211)
			(xy 354.21549 -272.765937) (xy 354.199442 -272.716544) (xy 354.191317 -272.665249) (xy 353.911407 -272.665249)
			(xy 353.903282 -272.716544) (xy 353.887234 -272.765937) (xy 353.863656 -272.812211) (xy 353.83313 -272.854227)
			(xy 353.796407 -272.89095) (xy 353.754391 -272.921476) (xy 353.708117 -272.945054) (xy 353.658724 -272.961102)
			(xy 353.607429 -272.969227) (xy 353.555495 -272.969227) (xy 353.5042 -272.961102) (xy 353.454807 -272.945054)
			(xy 353.408533 -272.921476) (xy 353.366517 -272.89095) (xy 353.329794 -272.854227) (xy 353.299268 -272.812211)
			(xy 353.27569 -272.765937) (xy 353.259642 -272.716544) (xy 353.251517 -272.665249) (xy 352.971607 -272.665249)
			(xy 352.963482 -272.716544) (xy 352.947434 -272.765937) (xy 352.923856 -272.812211) (xy 352.89333 -272.854227)
			(xy 352.856607 -272.89095) (xy 352.814591 -272.921476) (xy 352.768317 -272.945054) (xy 352.718924 -272.961102)
			(xy 352.667629 -272.969227) (xy 352.615695 -272.969227) (xy 352.5644 -272.961102) (xy 352.515007 -272.945054)
			(xy 352.468733 -272.921476) (xy 352.426717 -272.89095) (xy 352.389994 -272.854227) (xy 352.359468 -272.812211)
			(xy 352.33589 -272.765937) (xy 352.319842 -272.716544) (xy 352.311717 -272.665249) (xy 352.031807 -272.665249)
			(xy 352.023682 -272.716544) (xy 352.007634 -272.765937) (xy 351.984056 -272.812211) (xy 351.95353 -272.854227)
			(xy 351.916807 -272.89095) (xy 351.874791 -272.921476) (xy 351.828517 -272.945054) (xy 351.779124 -272.961102)
			(xy 351.727829 -272.969227) (xy 351.675895 -272.969227) (xy 351.6246 -272.961102) (xy 351.575207 -272.945054)
			(xy 351.528933 -272.921476) (xy 351.486917 -272.89095) (xy 351.450194 -272.854227) (xy 351.419668 -272.812211)
			(xy 351.39609 -272.765937) (xy 351.380042 -272.716544) (xy 351.371917 -272.665249) (xy 351.091884 -272.665249)
			(xy 351.084429 -272.714014) (xy 351.06943 -272.761921) (xy 351.047361 -272.80701) (xy 351.018731 -272.848245)
			(xy 350.984198 -272.884679) (xy 350.944554 -272.915475) (xy 350.922844 -272.92808) (xy 350.922844 -273.07413)
			(xy 350.923379 -273.089104) (xy 350.932074 -273.117762) (xy 350.948709 -273.142666) (xy 350.971853 -273.161674)
			(xy 350.999515 -273.173151) (xy 351.029317 -273.176111) (xy 351.058696 -273.170299) (xy 351.072196 -273.163792)
			(xy 351.09682 -273.150861) (xy 351.149324 -273.132525) (xy 351.204155 -273.12323) (xy 351.231962 -273.122644)
			(xy 351.257431 -273.123113) (xy 351.307766 -273.130928) (xy 351.356303 -273.146379) (xy 351.401893 -273.169099)
			(xy 351.443454 -273.19855) (xy 351.48 -273.234033) (xy 351.510664 -273.274707) (xy 351.53472 -273.319607)
			(xy 351.551596 -273.367667) (xy 351.560893 -273.417749) (xy 351.562162 -273.443192) (xy 351.562416 -273.449034)
			(xy 351.562416 -273.453098) (xy 351.561892 -273.47995) (xy 351.55321 -273.532947) (xy 351.536074 -273.583843)
			(xy 351.510935 -273.6313) (xy 351.495106 -273.652996) (xy 351.49155 -273.657822) (xy 351.49028 -273.659346)
			(xy 351.481781 -273.670797) (xy 351.470892 -273.69714) (xy 351.467708 -273.725466) (xy 351.472476 -273.753569)
			(xy 351.484826 -273.77926) (xy 351.503794 -273.800537) (xy 351.527904 -273.815743) (xy 351.555277 -273.823694)
			(xy 351.569528 -273.824192) (xy 351.83445 -273.824192) (xy 351.848701 -273.82368) (xy 351.876075 -273.815734)
			(xy 351.900187 -273.800531) (xy 351.919156 -273.779255) (xy 351.931507 -273.753566) (xy 351.936275 -273.725463)
			(xy 351.933089 -273.697137) (xy 351.922198 -273.670796) (xy 351.913698 -273.659346) (xy 351.912428 -273.657822)
			(xy 351.908872 -273.652996) (xy 351.893046 -273.631297) (xy 351.867902 -273.583843) (xy 351.850762 -273.532947)
			(xy 351.842078 -273.47995) (xy 351.841562 -273.453098) (xy 351.841562 -273.449034) (xy 351.841816 -273.443192)
			(xy 351.84305 -273.417753) (xy 351.852371 -273.367685) (xy 351.869267 -273.319641) (xy 351.893335 -273.274758)
			(xy 351.924007 -273.234101) (xy 351.960555 -273.198633) (xy 352.002113 -273.169195) (xy 352.047697 -273.146483)
			(xy 352.096226 -273.131036) (xy 352.146552 -273.12322) (xy 352.19748 -273.12322) (xy 352.247806 -273.131036)
			(xy 352.296335 -273.146483) (xy 352.341919 -273.169195) (xy 352.383477 -273.198633) (xy 352.420025 -273.234101)
			(xy 352.450697 -273.274758) (xy 352.474765 -273.319641) (xy 352.491661 -273.367685) (xy 352.500982 -273.417753)
			(xy 352.502216 -273.443192) (xy 352.50247 -273.449034) (xy 352.50247 -273.453098) (xy 352.501946 -273.47995)
			(xy 352.493265 -273.532948) (xy 352.476132 -273.583846) (xy 352.450996 -273.631305) (xy 352.43516 -273.652996)
			(xy 352.431604 -273.657822) (xy 352.430334 -273.659346) (xy 352.421832 -273.670794) (xy 352.410938 -273.697134)
			(xy 352.407751 -273.725459) (xy 352.412519 -273.753561) (xy 352.42487 -273.779249) (xy 352.443842 -273.800522)
			(xy 352.467956 -273.81572) (xy 352.495331 -273.823659) (xy 352.509582 -273.824192) (xy 353.71405 -273.824192)
			(xy 353.728301 -273.82368) (xy 353.755675 -273.815734) (xy 353.779787 -273.800531) (xy 353.798756 -273.779255)
			(xy 353.811107 -273.753566) (xy 353.815875 -273.725463) (xy 353.812689 -273.697137) (xy 353.801798 -273.670796)
			(xy 353.793298 -273.659346) (xy 353.776389 -273.637207) (xy 353.749456 -273.588447) (xy 353.731068 -273.535867)
			(xy 353.721742 -273.48095) (xy 353.721162 -273.453098) (xy 353.721671 -273.427131) (xy 353.729796 -273.375836)
			(xy 353.745844 -273.326443) (xy 353.769422 -273.280169) (xy 353.799948 -273.238153) (xy 353.836671 -273.20143)
			(xy 353.878687 -273.170904) (xy 353.924961 -273.147326) (xy 353.974354 -273.131278) (xy 354.025649 -273.123153)
			(xy 354.077583 -273.123153) (xy 354.128878 -273.131278) (xy 354.178271 -273.147326) (xy 354.224545 -273.170904)
			(xy 354.266561 -273.20143) (xy 354.303284 -273.238153) (xy 354.33381 -273.280169) (xy 354.357388 -273.326443)
			(xy 354.373436 -273.375836) (xy 354.381561 -273.427131) (xy 354.38207 -273.453098) (xy 354.381516 -273.480953)
			(xy 354.372212 -273.535879) (xy 354.353816 -273.588462) (xy 354.326851 -273.63721) (xy 354.309934 -273.659346)
			(xy 354.301432 -273.670794) (xy 354.290538 -273.697134) (xy 354.287351 -273.725459) (xy 354.292119 -273.753561)
			(xy 354.30447 -273.779249) (xy 354.323442 -273.800522) (xy 354.347556 -273.81572) (xy 354.374931 -273.823659)
			(xy 354.389182 -273.824192) (xy 354.65385 -273.824192) (xy 354.668101 -273.82368) (xy 354.695475 -273.815734)
			(xy 354.719587 -273.800531) (xy 354.738556 -273.779255) (xy 354.750907 -273.753566) (xy 354.755675 -273.725463)
			(xy 354.752489 -273.697137) (xy 354.741598 -273.670796) (xy 354.733098 -273.659346) (xy 354.731828 -273.657822)
			(xy 354.728272 -273.652996) (xy 354.712446 -273.631297) (xy 354.687302 -273.583843) (xy 354.670162 -273.532947)
			(xy 354.661478 -273.47995) (xy 354.660962 -273.453098) (xy 354.660962 -273.449034) (xy 354.661216 -273.443192)
			(xy 354.66245 -273.417753) (xy 354.671771 -273.367685) (xy 354.688667 -273.319641) (xy 354.712735 -273.274758)
			(xy 354.743407 -273.234101) (xy 354.779955 -273.198633) (xy 354.821513 -273.169195) (xy 354.867097 -273.146483)
			(xy 354.915626 -273.131036) (xy 354.965952 -273.12322) (xy 355.01688 -273.12322) (xy 355.067206 -273.131036)
			(xy 355.115735 -273.146483) (xy 355.161319 -273.169195) (xy 355.202877 -273.198633) (xy 355.239425 -273.234101)
			(xy 355.270097 -273.274758) (xy 355.294165 -273.319641) (xy 355.311061 -273.367685) (xy 355.320382 -273.417753)
			(xy 355.321616 -273.443192) (xy 355.32187 -273.449034) (xy 355.32187 -273.453098) (xy 355.321346 -273.47995)
			(xy 355.312665 -273.532948) (xy 355.295532 -273.583846) (xy 355.270396 -273.631305) (xy 355.25456 -273.652996)
			(xy 355.251004 -273.657822) (xy 355.249734 -273.659346) (xy 355.241232 -273.670794) (xy 355.230338 -273.697134)
			(xy 355.227151 -273.725459) (xy 355.231919 -273.753561) (xy 355.24427 -273.779249) (xy 355.263242 -273.800522)
			(xy 355.287356 -273.81572) (xy 355.314731 -273.823659) (xy 355.328982 -273.824192) (xy 355.59365 -273.824192)
			(xy 355.607901 -273.82368) (xy 355.635275 -273.815734) (xy 355.659387 -273.800531) (xy 355.678356 -273.779255)
			(xy 355.690707 -273.753566) (xy 355.695475 -273.725463) (xy 355.692289 -273.697137) (xy 355.681398 -273.670796)
			(xy 355.672898 -273.659346) (xy 355.671628 -273.657822) (xy 355.668072 -273.652996) (xy 355.652246 -273.631297)
			(xy 355.627102 -273.583843) (xy 355.609962 -273.532947) (xy 355.601278 -273.47995) (xy 355.600762 -273.453098)
			(xy 355.600762 -273.449034) (xy 355.601016 -273.443192) (xy 355.602257 -273.417753) (xy 355.611589 -273.367686)
			(xy 355.62849 -273.319643) (xy 355.652561 -273.274761) (xy 355.683231 -273.234102) (xy 355.719775 -273.198629)
			(xy 355.761327 -273.169181) (xy 355.806905 -273.146454) (xy 355.855429 -273.130988) (xy 355.905752 -273.123149)
			(xy 355.931216 -273.122644) (xy 355.931216 -273.12239) (xy 355.955549 -273.122842) (xy 356.003685 -273.130005)
			(xy 356.050256 -273.144131) (xy 356.07244 -273.15414) (xy 356.086401 -273.158999) (xy 356.115859 -273.161304)
			(xy 356.144741 -273.155064) (xy 356.170619 -273.140803) (xy 356.19132 -273.119718) (xy 356.198678 -273.106896)
			(xy 356.200456 -273.10334) (xy 356.208329 -273.088411) (xy 356.225225 -273.059189) (xy 356.234238 -273.04492)
			(xy 356.242126 -273.031636) (xy 356.250282 -273.001853) (xy 356.249156 -272.970993) (xy 356.238853 -272.941883)
			(xy 356.220315 -272.917187) (xy 356.208076 -272.90776) (xy 356.187155 -272.892108) (xy 356.15006 -272.855316)
			(xy 356.119209 -272.813151) (xy 356.095371 -272.76666) (xy 356.079137 -272.717) (xy 356.070911 -272.665405)
			(xy 356.070408 -272.639282) (xy 356.070919 -272.613315) (xy 356.079045 -272.56202) (xy 356.095095 -272.512627)
			(xy 356.118673 -272.466353) (xy 356.149199 -272.424336) (xy 356.185921 -272.387612) (xy 356.227936 -272.357083)
			(xy 356.274208 -272.333502) (xy 356.3236 -272.31745) (xy 356.374895 -272.30932) (xy 356.400862 -272.308828)
			(xy 356.427896 -272.309372) (xy 356.481241 -272.318177) (xy 356.532443 -272.335544) (xy 356.580138 -272.36101)
			(xy 356.623054 -272.393895) (xy 356.66005 -272.433324) (xy 356.690137 -272.478246) (xy 356.712516 -272.527464)
			(xy 356.72659 -272.579668) (xy 356.729792 -272.606516) (xy 356.731854 -272.621479) (xy 356.743531 -272.649318)
			(xy 356.762833 -272.672531) (xy 356.788075 -272.689091) (xy 356.817053 -272.697554) (xy 356.832154 -272.697956)
			(xy 356.847394 -272.697448) (xy 356.870762 -272.69694) (xy 356.89413 -272.697448) (xy 356.90937 -272.697956)
			(xy 356.924469 -272.697591) (xy 356.953443 -272.689117) (xy 356.978674 -272.672544) (xy 356.997958 -272.64932)
			(xy 357.009612 -272.621473) (xy 357.011732 -272.606516) (xy 357.014944 -272.579664) (xy 357.028986 -272.527442)
			(xy 357.051344 -272.478204) (xy 357.081422 -272.433265) (xy 357.118417 -272.393823) (xy 357.161341 -272.360932)
			(xy 357.209048 -272.335471) (xy 357.260265 -272.318119) (xy 357.313624 -272.309338) (xy 357.340662 -272.308828)
			(xy 357.366634 -272.309308) (xy 357.417939 -272.317428) (xy 357.467341 -272.333474) (xy 357.513626 -272.357052)
			(xy 357.555651 -272.38758) (xy 357.592384 -272.424306) (xy 357.622919 -272.466327) (xy 357.646504 -272.512607)
			(xy 357.662559 -272.562007) (xy 357.670688 -272.61331) (xy 357.671116 -272.639282) (xy 357.670659 -272.664866)
			(xy 357.6706 -272.665249) (xy 357.950517 -272.665249) (xy 357.950517 -272.613315) (xy 357.958642 -272.56202)
			(xy 357.97469 -272.512627) (xy 357.998268 -272.466353) (xy 358.028794 -272.424337) (xy 358.065517 -272.387614)
			(xy 358.107533 -272.357088) (xy 358.153807 -272.33351) (xy 358.2032 -272.317462) (xy 358.254495 -272.309337)
			(xy 358.306429 -272.309337) (xy 358.357724 -272.317462) (xy 358.407117 -272.33351) (xy 358.453391 -272.357088)
			(xy 358.495407 -272.387614) (xy 358.53213 -272.424337) (xy 358.562656 -272.466353) (xy 358.586234 -272.512627)
			(xy 358.602282 -272.56202) (xy 358.610407 -272.613315) (xy 358.610916 -272.639282) (xy 358.610407 -272.665249)
			(xy 361.709717 -272.665249) (xy 361.709717 -272.613315) (xy 361.717842 -272.56202) (xy 361.73389 -272.512627)
			(xy 361.757468 -272.466353) (xy 361.787994 -272.424337) (xy 361.824717 -272.387614) (xy 361.866733 -272.357088)
			(xy 361.913007 -272.33351) (xy 361.9624 -272.317462) (xy 362.013695 -272.309337) (xy 362.065629 -272.309337)
			(xy 362.116924 -272.317462) (xy 362.166317 -272.33351) (xy 362.212591 -272.357088) (xy 362.254607 -272.387614)
			(xy 362.29133 -272.424337) (xy 362.321856 -272.466353) (xy 362.345434 -272.512627) (xy 362.361482 -272.56202)
			(xy 362.369607 -272.613315) (xy 362.370116 -272.639282) (xy 362.369607 -272.665249) (xy 362.649517 -272.665249)
			(xy 362.649517 -272.613315) (xy 362.657642 -272.56202) (xy 362.67369 -272.512627) (xy 362.697268 -272.466353)
			(xy 362.727794 -272.424337) (xy 362.764517 -272.387614) (xy 362.806533 -272.357088) (xy 362.852807 -272.33351)
			(xy 362.9022 -272.317462) (xy 362.953495 -272.309337) (xy 363.005429 -272.309337) (xy 363.056724 -272.317462)
			(xy 363.106117 -272.33351) (xy 363.152391 -272.357088) (xy 363.194407 -272.387614) (xy 363.23113 -272.424337)
			(xy 363.261656 -272.466353) (xy 363.285234 -272.512627) (xy 363.301282 -272.56202) (xy 363.309407 -272.613315)
			(xy 363.309916 -272.639282) (xy 363.309407 -272.665249) (xy 363.589317 -272.665249) (xy 363.589317 -272.613315)
			(xy 363.597442 -272.56202) (xy 363.61349 -272.512627) (xy 363.637068 -272.466353) (xy 363.667594 -272.424337)
			(xy 363.704317 -272.387614) (xy 363.746333 -272.357088) (xy 363.792607 -272.33351) (xy 363.842 -272.317462)
			(xy 363.893295 -272.309337) (xy 363.945229 -272.309337) (xy 363.996524 -272.317462) (xy 364.045917 -272.33351)
			(xy 364.092191 -272.357088) (xy 364.134207 -272.387614) (xy 364.17093 -272.424337) (xy 364.201456 -272.466353)
			(xy 364.225034 -272.512627) (xy 364.241082 -272.56202) (xy 364.249207 -272.613315) (xy 364.249716 -272.639282)
			(xy 364.249207 -272.665249) (xy 364.241082 -272.716544) (xy 364.225034 -272.765937) (xy 364.201456 -272.812211)
			(xy 364.17093 -272.854227) (xy 364.134207 -272.89095) (xy 364.092191 -272.921476) (xy 364.045917 -272.945054)
			(xy 363.996524 -272.961102) (xy 363.945229 -272.969227) (xy 363.893295 -272.969227) (xy 363.842 -272.961102)
			(xy 363.792607 -272.945054) (xy 363.746333 -272.921476) (xy 363.704317 -272.89095) (xy 363.667594 -272.854227)
			(xy 363.637068 -272.812211) (xy 363.61349 -272.765937) (xy 363.597442 -272.716544) (xy 363.589317 -272.665249)
			(xy 363.309407 -272.665249) (xy 363.301282 -272.716544) (xy 363.285234 -272.765937) (xy 363.261656 -272.812211)
			(xy 363.23113 -272.854227) (xy 363.194407 -272.89095) (xy 363.152391 -272.921476) (xy 363.106117 -272.945054)
			(xy 363.056724 -272.961102) (xy 363.005429 -272.969227) (xy 362.953495 -272.969227) (xy 362.9022 -272.961102)
			(xy 362.852807 -272.945054) (xy 362.806533 -272.921476) (xy 362.764517 -272.89095) (xy 362.727794 -272.854227)
			(xy 362.697268 -272.812211) (xy 362.67369 -272.765937) (xy 362.657642 -272.716544) (xy 362.649517 -272.665249)
			(xy 362.369607 -272.665249) (xy 362.361482 -272.716544) (xy 362.345434 -272.765937) (xy 362.321856 -272.812211)
			(xy 362.29133 -272.854227) (xy 362.254607 -272.89095) (xy 362.212591 -272.921476) (xy 362.166317 -272.945054)
			(xy 362.116924 -272.961102) (xy 362.065629 -272.969227) (xy 362.013695 -272.969227) (xy 361.9624 -272.961102)
			(xy 361.913007 -272.945054) (xy 361.866733 -272.921476) (xy 361.824717 -272.89095) (xy 361.787994 -272.854227)
			(xy 361.757468 -272.812211) (xy 361.73389 -272.765937) (xy 361.717842 -272.716544) (xy 361.709717 -272.665249)
			(xy 358.610407 -272.665249) (xy 358.602282 -272.716544) (xy 358.586234 -272.765937) (xy 358.562656 -272.812211)
			(xy 358.53213 -272.854227) (xy 358.495407 -272.89095) (xy 358.453391 -272.921476) (xy 358.407117 -272.945054)
			(xy 358.357724 -272.961102) (xy 358.306429 -272.969227) (xy 358.254495 -272.969227) (xy 358.2032 -272.961102)
			(xy 358.153807 -272.945054) (xy 358.107533 -272.921476) (xy 358.065517 -272.89095) (xy 358.028794 -272.854227)
			(xy 357.998268 -272.812211) (xy 357.97469 -272.765937) (xy 357.958642 -272.716544) (xy 357.950517 -272.665249)
			(xy 357.6706 -272.665249) (xy 357.662808 -272.715428) (xy 357.647245 -272.764171) (xy 357.624343 -272.809928)
			(xy 357.609902 -272.831052) (xy 357.602381 -272.8428) (xy 357.59344 -272.869211) (xy 357.591986 -272.897056)
			(xy 357.598129 -272.924255) (xy 357.611409 -272.948773) (xy 357.630833 -272.968778) (xy 357.65495 -272.982774)
			(xy 357.668322 -272.986754) (xy 357.718776 -273.0002) (xy 357.817572 -273.03402) (xy 357.86568 -273.054318)
			(xy 357.9005 -273.06973) (xy 357.968487 -273.104043) (xy 358.00157 -273.122898) (xy 358.046615 -273.149515)
			(xy 358.132794 -273.208864) (xy 358.214009 -273.274842) (xy 358.289752 -273.347037) (xy 358.359547 -273.424997)
			(xy 358.400737 -273.479065) (xy 361.239817 -273.479065) (xy 361.239817 -273.427131) (xy 361.247942 -273.375836)
			(xy 361.26399 -273.326443) (xy 361.287568 -273.280169) (xy 361.318094 -273.238153) (xy 361.354817 -273.20143)
			(xy 361.396833 -273.170904) (xy 361.443107 -273.147326) (xy 361.4925 -273.131278) (xy 361.543795 -273.123153)
			(xy 361.595729 -273.123153) (xy 361.647024 -273.131278) (xy 361.696417 -273.147326) (xy 361.742691 -273.170904)
			(xy 361.784707 -273.20143) (xy 361.82143 -273.238153) (xy 361.851956 -273.280169) (xy 361.875534 -273.326443)
			(xy 361.891582 -273.375836) (xy 361.899707 -273.427131) (xy 361.900216 -273.453098) (xy 361.899707 -273.479065)
			(xy 362.179617 -273.479065) (xy 362.179617 -273.427131) (xy 362.187742 -273.375836) (xy 362.20379 -273.326443)
			(xy 362.227368 -273.280169) (xy 362.257894 -273.238153) (xy 362.294617 -273.20143) (xy 362.336633 -273.170904)
			(xy 362.382907 -273.147326) (xy 362.4323 -273.131278) (xy 362.483595 -273.123153) (xy 362.535529 -273.123153)
			(xy 362.586824 -273.131278) (xy 362.636217 -273.147326) (xy 362.682491 -273.170904) (xy 362.724507 -273.20143)
			(xy 362.76123 -273.238153) (xy 362.791756 -273.280169) (xy 362.815334 -273.326443) (xy 362.831382 -273.375836)
			(xy 362.839507 -273.427131) (xy 362.840016 -273.453098) (xy 362.839507 -273.479065) (xy 363.119417 -273.479065)
			(xy 363.119417 -273.427131) (xy 363.127542 -273.375836) (xy 363.14359 -273.326443) (xy 363.167168 -273.280169)
			(xy 363.197694 -273.238153) (xy 363.234417 -273.20143) (xy 363.276433 -273.170904) (xy 363.322707 -273.147326)
			(xy 363.3721 -273.131278) (xy 363.423395 -273.123153) (xy 363.475329 -273.123153) (xy 363.526624 -273.131278)
			(xy 363.576017 -273.147326) (xy 363.622291 -273.170904) (xy 363.664307 -273.20143) (xy 363.70103 -273.238153)
			(xy 363.731556 -273.280169) (xy 363.755134 -273.326443) (xy 363.771182 -273.375836) (xy 363.779307 -273.427131)
			(xy 363.779816 -273.453098) (xy 363.779307 -273.479065) (xy 364.059471 -273.479065) (xy 364.059471 -273.427131)
			(xy 364.067596 -273.375836) (xy 364.083644 -273.326443) (xy 364.107222 -273.280169) (xy 364.137748 -273.238153)
			(xy 364.174471 -273.20143) (xy 364.216487 -273.170904) (xy 364.262761 -273.147326) (xy 364.312154 -273.131278)
			(xy 364.363449 -273.123153) (xy 364.415383 -273.123153) (xy 364.466678 -273.131278) (xy 364.516071 -273.147326)
			(xy 364.562345 -273.170904) (xy 364.604361 -273.20143) (xy 364.641084 -273.238153) (xy 364.67161 -273.280169)
			(xy 364.695188 -273.326443) (xy 364.711236 -273.375836) (xy 364.719361 -273.427131) (xy 364.71987 -273.453098)
			(xy 364.719361 -273.479065) (xy 364.711236 -273.53036) (xy 364.695188 -273.579753) (xy 364.67161 -273.626027)
			(xy 364.641084 -273.668043) (xy 364.604361 -273.704766) (xy 364.562345 -273.735292) (xy 364.516071 -273.75887)
			(xy 364.466678 -273.774918) (xy 364.415383 -273.783043) (xy 364.363449 -273.783043) (xy 364.312154 -273.774918)
			(xy 364.262761 -273.75887) (xy 364.216487 -273.735292) (xy 364.174471 -273.704766) (xy 364.137748 -273.668043)
			(xy 364.107222 -273.626027) (xy 364.083644 -273.579753) (xy 364.067596 -273.53036) (xy 364.059471 -273.479065)
			(xy 363.779307 -273.479065) (xy 363.771182 -273.53036) (xy 363.755134 -273.579753) (xy 363.731556 -273.626027)
			(xy 363.70103 -273.668043) (xy 363.664307 -273.704766) (xy 363.622291 -273.735292) (xy 363.576017 -273.75887)
			(xy 363.526624 -273.774918) (xy 363.475329 -273.783043) (xy 363.423395 -273.783043) (xy 363.3721 -273.774918)
			(xy 363.322707 -273.75887) (xy 363.276433 -273.735292) (xy 363.234417 -273.704766) (xy 363.197694 -273.668043)
			(xy 363.167168 -273.626027) (xy 363.14359 -273.579753) (xy 363.127542 -273.53036) (xy 363.119417 -273.479065)
			(xy 362.839507 -273.479065) (xy 362.831382 -273.53036) (xy 362.815334 -273.579753) (xy 362.791756 -273.626027)
			(xy 362.76123 -273.668043) (xy 362.724507 -273.704766) (xy 362.682491 -273.735292) (xy 362.636217 -273.75887)
			(xy 362.586824 -273.774918) (xy 362.535529 -273.783043) (xy 362.483595 -273.783043) (xy 362.4323 -273.774918)
			(xy 362.382907 -273.75887) (xy 362.336633 -273.735292) (xy 362.294617 -273.704766) (xy 362.257894 -273.668043)
			(xy 362.227368 -273.626027) (xy 362.20379 -273.579753) (xy 362.187742 -273.53036) (xy 362.179617 -273.479065)
			(xy 361.899707 -273.479065) (xy 361.891582 -273.53036) (xy 361.875534 -273.579753) (xy 361.851956 -273.626027)
			(xy 361.82143 -273.668043) (xy 361.784707 -273.704766) (xy 361.742691 -273.735292) (xy 361.696417 -273.75887)
			(xy 361.647024 -273.774918) (xy 361.595729 -273.783043) (xy 361.543795 -273.783043) (xy 361.4925 -273.774918)
			(xy 361.443107 -273.75887) (xy 361.396833 -273.735292) (xy 361.354817 -273.704766) (xy 361.318094 -273.668043)
			(xy 361.287568 -273.626027) (xy 361.26399 -273.579753) (xy 361.247942 -273.53036) (xy 361.239817 -273.479065)
			(xy 358.400737 -273.479065) (xy 358.422957 -273.508232) (xy 358.479586 -273.596222) (xy 358.529078 -273.688416)
			(xy 358.571124 -273.784234) (xy 358.605459 -273.883078) (xy 358.631869 -273.984328) (xy 358.650189 -274.08735)
			(xy 358.660302 -274.191498) (xy 358.661716 -274.2438) (xy 358.661716 -274.27682) (xy 358.661716 -274.290028)
			(xy 358.661638 -274.292881) (xy 361.709717 -274.292881) (xy 361.709717 -274.240947) (xy 361.717842 -274.189652)
			(xy 361.73389 -274.140259) (xy 361.757468 -274.093985) (xy 361.787994 -274.051969) (xy 361.824717 -274.015246)
			(xy 361.866733 -273.98472) (xy 361.913007 -273.961142) (xy 361.9624 -273.945094) (xy 362.013695 -273.936969)
			(xy 362.065629 -273.936969) (xy 362.116924 -273.945094) (xy 362.166317 -273.961142) (xy 362.212591 -273.98472)
			(xy 362.254607 -274.015246) (xy 362.29133 -274.051969) (xy 362.321856 -274.093985) (xy 362.345434 -274.140259)
			(xy 362.361482 -274.189652) (xy 362.369607 -274.240947) (xy 362.370116 -274.266914) (xy 362.369607 -274.292881)
			(xy 362.649517 -274.292881) (xy 362.649517 -274.240947) (xy 362.657642 -274.189652) (xy 362.67369 -274.140259)
			(xy 362.697268 -274.093985) (xy 362.727794 -274.051969) (xy 362.764517 -274.015246) (xy 362.806533 -273.98472)
			(xy 362.852807 -273.961142) (xy 362.9022 -273.945094) (xy 362.953495 -273.936969) (xy 363.005429 -273.936969)
			(xy 363.056724 -273.945094) (xy 363.106117 -273.961142) (xy 363.152391 -273.98472) (xy 363.194407 -274.015246)
			(xy 363.23113 -274.051969) (xy 363.261656 -274.093985) (xy 363.285234 -274.140259) (xy 363.301282 -274.189652)
			(xy 363.309407 -274.240947) (xy 363.309916 -274.266914) (xy 363.309407 -274.292881) (xy 363.589571 -274.292881)
			(xy 363.589571 -274.240947) (xy 363.597696 -274.189652) (xy 363.613744 -274.140259) (xy 363.637322 -274.093985)
			(xy 363.667848 -274.051969) (xy 363.704571 -274.015246) (xy 363.746587 -273.98472) (xy 363.792861 -273.961142)
			(xy 363.842254 -273.945094) (xy 363.893549 -273.936969) (xy 363.945483 -273.936969) (xy 363.996778 -273.945094)
			(xy 364.046171 -273.961142) (xy 364.092445 -273.98472) (xy 364.134461 -274.015246) (xy 364.171184 -274.051969)
			(xy 364.20171 -274.093985) (xy 364.225288 -274.140259) (xy 364.241336 -274.189652) (xy 364.249461 -274.240947)
			(xy 364.24997 -274.266914) (xy 364.249461 -274.292881) (xy 364.241336 -274.344176) (xy 364.225288 -274.393569)
			(xy 364.20171 -274.439843) (xy 364.171184 -274.481859) (xy 364.134461 -274.518582) (xy 364.092445 -274.549108)
			(xy 364.046171 -274.572686) (xy 363.996778 -274.588734) (xy 363.945483 -274.596859) (xy 363.893549 -274.596859)
			(xy 363.842254 -274.588734) (xy 363.792861 -274.572686) (xy 363.746587 -274.549108) (xy 363.704571 -274.518582)
			(xy 363.667848 -274.481859) (xy 363.637322 -274.439843) (xy 363.613744 -274.393569) (xy 363.597696 -274.344176)
			(xy 363.589571 -274.292881) (xy 363.309407 -274.292881) (xy 363.301282 -274.344176) (xy 363.285234 -274.393569)
			(xy 363.261656 -274.439843) (xy 363.23113 -274.481859) (xy 363.194407 -274.518582) (xy 363.152391 -274.549108)
			(xy 363.106117 -274.572686) (xy 363.056724 -274.588734) (xy 363.005429 -274.596859) (xy 362.953495 -274.596859)
			(xy 362.9022 -274.588734) (xy 362.852807 -274.572686) (xy 362.806533 -274.549108) (xy 362.764517 -274.518582)
			(xy 362.727794 -274.481859) (xy 362.697268 -274.439843) (xy 362.67369 -274.393569) (xy 362.657642 -274.344176)
			(xy 362.649517 -274.292881) (xy 362.369607 -274.292881) (xy 362.361482 -274.344176) (xy 362.345434 -274.393569)
			(xy 362.321856 -274.439843) (xy 362.29133 -274.481859) (xy 362.254607 -274.518582) (xy 362.212591 -274.549108)
			(xy 362.166317 -274.572686) (xy 362.116924 -274.588734) (xy 362.065629 -274.596859) (xy 362.013695 -274.596859)
			(xy 361.9624 -274.588734) (xy 361.913007 -274.572686) (xy 361.866733 -274.549108) (xy 361.824717 -274.518582)
			(xy 361.787994 -274.481859) (xy 361.757468 -274.439843) (xy 361.73389 -274.393569) (xy 361.717842 -274.344176)
			(xy 361.709717 -274.292881) (xy 358.661638 -274.292881) (xy 358.660255 -274.343371) (xy 358.649787 -274.449576)
			(xy 358.630785 -274.554591) (xy 358.603375 -274.657732) (xy 358.567734 -274.758325) (xy 358.524096 -274.855715)
			(xy 358.472744 -274.949268) (xy 358.414013 -275.038374) (xy 358.381554 -275.08073) (xy 358.401462 -275.106697)
			(xy 361.239817 -275.106697) (xy 361.239817 -275.054763) (xy 361.247942 -275.003468) (xy 361.26399 -274.954075)
			(xy 361.287568 -274.907801) (xy 361.318094 -274.865785) (xy 361.354817 -274.829062) (xy 361.396833 -274.798536)
			(xy 361.443107 -274.774958) (xy 361.4925 -274.75891) (xy 361.543795 -274.750785) (xy 361.595729 -274.750785)
			(xy 361.647024 -274.75891) (xy 361.696417 -274.774958) (xy 361.742691 -274.798536) (xy 361.784707 -274.829062)
			(xy 361.82143 -274.865785) (xy 361.851956 -274.907801) (xy 361.875534 -274.954075) (xy 361.891582 -275.003468)
			(xy 361.899707 -275.054763) (xy 361.900216 -275.08073) (xy 361.899707 -275.106697) (xy 362.179363 -275.106697)
			(xy 362.179363 -275.054763) (xy 362.187488 -275.003468) (xy 362.203536 -274.954075) (xy 362.227114 -274.907801)
			(xy 362.25764 -274.865785) (xy 362.294363 -274.829062) (xy 362.336379 -274.798536) (xy 362.382653 -274.774958)
			(xy 362.432046 -274.75891) (xy 362.483341 -274.750785) (xy 362.535275 -274.750785) (xy 362.58657 -274.75891)
			(xy 362.635963 -274.774958) (xy 362.682237 -274.798536) (xy 362.724253 -274.829062) (xy 362.760976 -274.865785)
			(xy 362.791502 -274.907801) (xy 362.81508 -274.954075) (xy 362.831128 -275.003468) (xy 362.839253 -275.054763)
			(xy 362.839762 -275.08073) (xy 362.839253 -275.106697) (xy 363.119163 -275.106697) (xy 363.119163 -275.054763)
			(xy 363.127288 -275.003468) (xy 363.143336 -274.954075) (xy 363.166914 -274.907801) (xy 363.19744 -274.865785)
			(xy 363.234163 -274.829062) (xy 363.276179 -274.798536) (xy 363.322453 -274.774958) (xy 363.371846 -274.75891)
			(xy 363.423141 -274.750785) (xy 363.475075 -274.750785) (xy 363.52637 -274.75891) (xy 363.575763 -274.774958)
			(xy 363.622037 -274.798536) (xy 363.664053 -274.829062) (xy 363.700776 -274.865785) (xy 363.731302 -274.907801)
			(xy 363.75488 -274.954075) (xy 363.770928 -275.003468) (xy 363.779053 -275.054763) (xy 363.779562 -275.08073)
			(xy 363.779053 -275.106697) (xy 364.059217 -275.106697) (xy 364.059217 -275.054763) (xy 364.067342 -275.003468)
			(xy 364.08339 -274.954075) (xy 364.106968 -274.907801) (xy 364.137494 -274.865785) (xy 364.174217 -274.829062)
			(xy 364.216233 -274.798536) (xy 364.262507 -274.774958) (xy 364.3119 -274.75891) (xy 364.363195 -274.750785)
			(xy 364.415129 -274.750785) (xy 364.466424 -274.75891) (xy 364.515817 -274.774958) (xy 364.562091 -274.798536)
			(xy 364.604107 -274.829062) (xy 364.64083 -274.865785) (xy 364.671356 -274.907801) (xy 364.694934 -274.954075)
			(xy 364.710982 -275.003468) (xy 364.719107 -275.054763) (xy 364.719616 -275.08073) (xy 364.719107 -275.106697)
			(xy 364.999271 -275.106697) (xy 364.999271 -275.054763) (xy 365.007396 -275.003468) (xy 365.023444 -274.954075)
			(xy 365.047022 -274.907801) (xy 365.077548 -274.865785) (xy 365.114271 -274.829062) (xy 365.156287 -274.798536)
			(xy 365.202561 -274.774958) (xy 365.251954 -274.75891) (xy 365.303249 -274.750785) (xy 365.355183 -274.750785)
			(xy 365.406478 -274.75891) (xy 365.455871 -274.774958) (xy 365.502145 -274.798536) (xy 365.544161 -274.829062)
			(xy 365.580884 -274.865785) (xy 365.61141 -274.907801) (xy 365.634988 -274.954075) (xy 365.651036 -275.003468)
			(xy 365.659161 -275.054763) (xy 365.65967 -275.08073) (xy 365.659161 -275.106697) (xy 365.651036 -275.157992)
			(xy 365.634988 -275.207385) (xy 365.61141 -275.253659) (xy 365.580884 -275.295675) (xy 365.544161 -275.332398)
			(xy 365.502145 -275.362924) (xy 365.455871 -275.386502) (xy 365.406478 -275.40255) (xy 365.355183 -275.410675)
			(xy 365.303249 -275.410675) (xy 365.251954 -275.40255) (xy 365.202561 -275.386502) (xy 365.156287 -275.362924)
			(xy 365.114271 -275.332398) (xy 365.077548 -275.295675) (xy 365.047022 -275.253659) (xy 365.023444 -275.207385)
			(xy 365.007396 -275.157992) (xy 364.999271 -275.106697) (xy 364.719107 -275.106697) (xy 364.710982 -275.157992)
			(xy 364.694934 -275.207385) (xy 364.671356 -275.253659) (xy 364.64083 -275.295675) (xy 364.604107 -275.332398)
			(xy 364.562091 -275.362924) (xy 364.515817 -275.386502) (xy 364.466424 -275.40255) (xy 364.415129 -275.410675)
			(xy 364.363195 -275.410675) (xy 364.3119 -275.40255) (xy 364.262507 -275.386502) (xy 364.216233 -275.362924)
			(xy 364.174217 -275.332398) (xy 364.137494 -275.295675) (xy 364.106968 -275.253659) (xy 364.08339 -275.207385)
			(xy 364.067342 -275.157992) (xy 364.059217 -275.106697) (xy 363.779053 -275.106697) (xy 363.770928 -275.157992)
			(xy 363.75488 -275.207385) (xy 363.731302 -275.253659) (xy 363.700776 -275.295675) (xy 363.664053 -275.332398)
			(xy 363.622037 -275.362924) (xy 363.575763 -275.386502) (xy 363.52637 -275.40255) (xy 363.475075 -275.410675)
			(xy 363.423141 -275.410675) (xy 363.371846 -275.40255) (xy 363.322453 -275.386502) (xy 363.276179 -275.362924)
			(xy 363.234163 -275.332398) (xy 363.19744 -275.295675) (xy 363.166914 -275.253659) (xy 363.143336 -275.207385)
			(xy 363.127288 -275.157992) (xy 363.119163 -275.106697) (xy 362.839253 -275.106697) (xy 362.831128 -275.157992)
			(xy 362.81508 -275.207385) (xy 362.791502 -275.253659) (xy 362.760976 -275.295675) (xy 362.724253 -275.332398)
			(xy 362.682237 -275.362924) (xy 362.635963 -275.386502) (xy 362.58657 -275.40255) (xy 362.535275 -275.410675)
			(xy 362.483341 -275.410675) (xy 362.432046 -275.40255) (xy 362.382653 -275.386502) (xy 362.336379 -275.362924)
			(xy 362.294363 -275.332398) (xy 362.25764 -275.295675) (xy 362.227114 -275.253659) (xy 362.203536 -275.207385)
			(xy 362.187488 -275.157992) (xy 362.179363 -275.106697) (xy 361.899707 -275.106697) (xy 361.891582 -275.157992)
			(xy 361.875534 -275.207385) (xy 361.851956 -275.253659) (xy 361.82143 -275.295675) (xy 361.784707 -275.332398)
			(xy 361.742691 -275.362924) (xy 361.696417 -275.386502) (xy 361.647024 -275.40255) (xy 361.595729 -275.410675)
			(xy 361.543795 -275.410675) (xy 361.4925 -275.40255) (xy 361.443107 -275.386502) (xy 361.396833 -275.362924)
			(xy 361.354817 -275.332398) (xy 361.318094 -275.295675) (xy 361.287568 -275.253659) (xy 361.26399 -275.207385)
			(xy 361.247942 -275.157992) (xy 361.239817 -275.106697) (xy 358.401462 -275.106697) (xy 358.413638 -275.122579)
			(xy 358.471789 -275.210558) (xy 358.522742 -275.302892) (xy 358.566172 -275.398994) (xy 358.601804 -275.498253)
			(xy 358.62941 -275.600035) (xy 358.648814 -275.703695) (xy 358.659893 -275.808571) (xy 358.661716 -275.861272)
			(xy 358.661716 -275.864066) (xy 358.661716 -275.8948) (xy 358.661482 -275.920767) (xy 361.709971 -275.920767)
			(xy 361.709971 -275.868833) (xy 361.718096 -275.817538) (xy 361.734144 -275.768145) (xy 361.757722 -275.721871)
			(xy 361.788248 -275.679855) (xy 361.824971 -275.643132) (xy 361.866987 -275.612606) (xy 361.913261 -275.589028)
			(xy 361.962654 -275.57298) (xy 362.013949 -275.564855) (xy 362.065883 -275.564855) (xy 362.117178 -275.57298)
			(xy 362.166571 -275.589028) (xy 362.212845 -275.612606) (xy 362.254861 -275.643132) (xy 362.291584 -275.679855)
			(xy 362.32211 -275.721871) (xy 362.345688 -275.768145) (xy 362.361736 -275.817538) (xy 362.369861 -275.868833)
			(xy 362.37037 -275.8948) (xy 362.369861 -275.920767) (xy 362.649517 -275.920767) (xy 362.649517 -275.868833)
			(xy 362.657642 -275.817538) (xy 362.67369 -275.768145) (xy 362.697268 -275.721871) (xy 362.727794 -275.679855)
			(xy 362.764517 -275.643132) (xy 362.806533 -275.612606) (xy 362.852807 -275.589028) (xy 362.9022 -275.57298)
			(xy 362.953495 -275.564855) (xy 363.005429 -275.564855) (xy 363.056724 -275.57298) (xy 363.106117 -275.589028)
			(xy 363.152391 -275.612606) (xy 363.194407 -275.643132) (xy 363.23113 -275.679855) (xy 363.261656 -275.721871)
			(xy 363.285234 -275.768145) (xy 363.301282 -275.817538) (xy 363.309407 -275.868833) (xy 363.309916 -275.8948)
			(xy 363.309407 -275.920767) (xy 363.589317 -275.920767) (xy 363.589317 -275.868833) (xy 363.597442 -275.817538)
			(xy 363.61349 -275.768145) (xy 363.637068 -275.721871) (xy 363.667594 -275.679855) (xy 363.704317 -275.643132)
			(xy 363.746333 -275.612606) (xy 363.792607 -275.589028) (xy 363.842 -275.57298) (xy 363.893295 -275.564855)
			(xy 363.945229 -275.564855) (xy 363.996524 -275.57298) (xy 364.045917 -275.589028) (xy 364.092191 -275.612606)
			(xy 364.134207 -275.643132) (xy 364.17093 -275.679855) (xy 364.201456 -275.721871) (xy 364.225034 -275.768145)
			(xy 364.241082 -275.817538) (xy 364.249207 -275.868833) (xy 364.249716 -275.8948) (xy 364.249212 -275.920513)
			(xy 364.529371 -275.920513) (xy 364.529371 -275.868579) (xy 364.537496 -275.817284) (xy 364.553544 -275.767891)
			(xy 364.577122 -275.721617) (xy 364.607648 -275.679601) (xy 364.644371 -275.642878) (xy 364.686387 -275.612352)
			(xy 364.732661 -275.588774) (xy 364.782054 -275.572726) (xy 364.833349 -275.564601) (xy 364.885283 -275.564601)
			(xy 364.936578 -275.572726) (xy 364.985971 -275.588774) (xy 365.032245 -275.612352) (xy 365.074261 -275.642878)
			(xy 365.110984 -275.679601) (xy 365.14151 -275.721617) (xy 365.165088 -275.767891) (xy 365.181136 -275.817284)
			(xy 365.189261 -275.868579) (xy 365.18977 -275.894546) (xy 365.189261 -275.920513) (xy 365.189221 -275.920767)
			(xy 365.468917 -275.920767) (xy 365.468917 -275.868833) (xy 365.477042 -275.817538) (xy 365.49309 -275.768145)
			(xy 365.516668 -275.721871) (xy 365.547194 -275.679855) (xy 365.583917 -275.643132) (xy 365.625933 -275.612606)
			(xy 365.672207 -275.589028) (xy 365.7216 -275.57298) (xy 365.772895 -275.564855) (xy 365.824829 -275.564855)
			(xy 365.876124 -275.57298) (xy 365.925517 -275.589028) (xy 365.971791 -275.612606) (xy 366.013807 -275.643132)
			(xy 366.05053 -275.679855) (xy 366.081056 -275.721871) (xy 366.104634 -275.768145) (xy 366.120682 -275.817538)
			(xy 366.128807 -275.868833) (xy 366.129316 -275.8948) (xy 366.128807 -275.920767) (xy 366.120682 -275.972062)
			(xy 366.104634 -276.021455) (xy 366.081056 -276.067729) (xy 366.05053 -276.109745) (xy 366.013807 -276.146468)
			(xy 365.971791 -276.176994) (xy 365.925517 -276.200572) (xy 365.876124 -276.21662) (xy 365.824829 -276.224745)
			(xy 365.772895 -276.224745) (xy 365.7216 -276.21662) (xy 365.672207 -276.200572) (xy 365.625933 -276.176994)
			(xy 365.583917 -276.146468) (xy 365.547194 -276.109745) (xy 365.516668 -276.067729) (xy 365.49309 -276.021455)
			(xy 365.477042 -275.972062) (xy 365.468917 -275.920767) (xy 365.189221 -275.920767) (xy 365.181136 -275.971808)
			(xy 365.165088 -276.021201) (xy 365.14151 -276.067475) (xy 365.110984 -276.109491) (xy 365.074261 -276.146214)
			(xy 365.032245 -276.17674) (xy 364.985971 -276.200318) (xy 364.936578 -276.216366) (xy 364.885283 -276.224491)
			(xy 364.833349 -276.224491) (xy 364.782054 -276.216366) (xy 364.732661 -276.200318) (xy 364.686387 -276.17674)
			(xy 364.644371 -276.146214) (xy 364.607648 -276.109491) (xy 364.577122 -276.067475) (xy 364.553544 -276.021201)
			(xy 364.537496 -275.971808) (xy 364.529371 -275.920513) (xy 364.249212 -275.920513) (xy 364.249207 -275.920767)
			(xy 364.241082 -275.972062) (xy 364.225034 -276.021455) (xy 364.201456 -276.067729) (xy 364.17093 -276.109745)
			(xy 364.134207 -276.146468) (xy 364.092191 -276.176994) (xy 364.045917 -276.200572) (xy 363.996524 -276.21662)
			(xy 363.945229 -276.224745) (xy 363.893295 -276.224745) (xy 363.842 -276.21662) (xy 363.792607 -276.200572)
			(xy 363.746333 -276.176994) (xy 363.704317 -276.146468) (xy 363.667594 -276.109745) (xy 363.637068 -276.067729)
			(xy 363.61349 -276.021455) (xy 363.597442 -275.972062) (xy 363.589317 -275.920767) (xy 363.309407 -275.920767)
			(xy 363.301282 -275.972062) (xy 363.285234 -276.021455) (xy 363.261656 -276.067729) (xy 363.23113 -276.109745)
			(xy 363.194407 -276.146468) (xy 363.152391 -276.176994) (xy 363.106117 -276.200572) (xy 363.056724 -276.21662)
			(xy 363.005429 -276.224745) (xy 362.953495 -276.224745) (xy 362.9022 -276.21662) (xy 362.852807 -276.200572)
			(xy 362.806533 -276.176994) (xy 362.764517 -276.146468) (xy 362.727794 -276.109745) (xy 362.697268 -276.067729)
			(xy 362.67369 -276.021455) (xy 362.657642 -275.972062) (xy 362.649517 -275.920767) (xy 362.369861 -275.920767)
			(xy 362.361736 -275.972062) (xy 362.345688 -276.021455) (xy 362.32211 -276.067729) (xy 362.291584 -276.109745)
			(xy 362.254861 -276.146468) (xy 362.212845 -276.176994) (xy 362.166571 -276.200572) (xy 362.117178 -276.21662)
			(xy 362.065883 -276.224745) (xy 362.013949 -276.224745) (xy 361.962654 -276.21662) (xy 361.913261 -276.200572)
			(xy 361.866987 -276.176994) (xy 361.824971 -276.146468) (xy 361.788248 -276.109745) (xy 361.757722 -276.067729)
			(xy 361.734144 -276.021455) (xy 361.718096 -275.972062) (xy 361.709971 -275.920767) (xy 358.661482 -275.920767)
			(xy 358.661277 -275.94351) (xy 358.654117 -276.040665) (xy 358.63982 -276.137029) (xy 358.618464 -276.232079)
			(xy 358.590166 -276.325297) (xy 358.555078 -276.416178) (xy 358.513392 -276.504227) (xy 358.465335 -276.588968)
			(xy 358.411166 -276.669938) (xy 358.381554 -276.708616) (xy 358.401447 -276.734583) (xy 362.179871 -276.734583)
			(xy 362.179871 -276.682649) (xy 362.187996 -276.631354) (xy 362.204044 -276.581961) (xy 362.227622 -276.535687)
			(xy 362.258148 -276.493671) (xy 362.294871 -276.456948) (xy 362.336887 -276.426422) (xy 362.383161 -276.402844)
			(xy 362.432554 -276.386796) (xy 362.483849 -276.378671) (xy 362.535783 -276.378671) (xy 362.587078 -276.386796)
			(xy 362.636471 -276.402844) (xy 362.682745 -276.426422) (xy 362.724761 -276.456948) (xy 362.761484 -276.493671)
			(xy 362.79201 -276.535687) (xy 362.815588 -276.581961) (xy 362.831636 -276.631354) (xy 362.839761 -276.682649)
			(xy 362.84027 -276.708616) (xy 362.839766 -276.734329) (xy 363.119417 -276.734329) (xy 363.119417 -276.682395)
			(xy 363.127542 -276.6311) (xy 363.14359 -276.581707) (xy 363.167168 -276.535433) (xy 363.197694 -276.493417)
			(xy 363.234417 -276.456694) (xy 363.276433 -276.426168) (xy 363.322707 -276.40259) (xy 363.3721 -276.386542)
			(xy 363.423395 -276.378417) (xy 363.475329 -276.378417) (xy 363.526624 -276.386542) (xy 363.576017 -276.40259)
			(xy 363.622291 -276.426168) (xy 363.664307 -276.456694) (xy 363.70103 -276.493417) (xy 363.731556 -276.535433)
			(xy 363.755134 -276.581707) (xy 363.771182 -276.6311) (xy 363.779307 -276.682395) (xy 363.779816 -276.708362)
			(xy 363.779307 -276.734329) (xy 364.059217 -276.734329) (xy 364.059217 -276.682395) (xy 364.067342 -276.6311)
			(xy 364.08339 -276.581707) (xy 364.106968 -276.535433) (xy 364.137494 -276.493417) (xy 364.174217 -276.456694)
			(xy 364.216233 -276.426168) (xy 364.262507 -276.40259) (xy 364.3119 -276.386542) (xy 364.363195 -276.378417)
			(xy 364.415129 -276.378417) (xy 364.466424 -276.386542) (xy 364.515817 -276.40259) (xy 364.562091 -276.426168)
			(xy 364.604107 -276.456694) (xy 364.64083 -276.493417) (xy 364.671356 -276.535433) (xy 364.694934 -276.581707)
			(xy 364.710982 -276.6311) (xy 364.719107 -276.682395) (xy 364.719616 -276.708362) (xy 364.719107 -276.734329)
			(xy 364.999017 -276.734329) (xy 364.999017 -276.682395) (xy 365.007142 -276.6311) (xy 365.02319 -276.581707)
			(xy 365.046768 -276.535433) (xy 365.077294 -276.493417) (xy 365.114017 -276.456694) (xy 365.156033 -276.426168)
			(xy 365.202307 -276.40259) (xy 365.2517 -276.386542) (xy 365.302995 -276.378417) (xy 365.354929 -276.378417)
			(xy 365.406224 -276.386542) (xy 365.455617 -276.40259) (xy 365.501891 -276.426168) (xy 365.543907 -276.456694)
			(xy 365.58063 -276.493417) (xy 365.611156 -276.535433) (xy 365.634734 -276.581707) (xy 365.650782 -276.6311)
			(xy 365.658907 -276.682395) (xy 365.659416 -276.708362) (xy 365.658907 -276.734329) (xy 365.938817 -276.734329)
			(xy 365.938817 -276.682395) (xy 365.946942 -276.6311) (xy 365.96299 -276.581707) (xy 365.986568 -276.535433)
			(xy 366.017094 -276.493417) (xy 366.053817 -276.456694) (xy 366.095833 -276.426168) (xy 366.142107 -276.40259)
			(xy 366.1915 -276.386542) (xy 366.242795 -276.378417) (xy 366.294729 -276.378417) (xy 366.346024 -276.386542)
			(xy 366.395417 -276.40259) (xy 366.441691 -276.426168) (xy 366.483707 -276.456694) (xy 366.52043 -276.493417)
			(xy 366.550956 -276.535433) (xy 366.574534 -276.581707) (xy 366.590582 -276.6311) (xy 366.598707 -276.682395)
			(xy 366.599216 -276.708362) (xy 366.598707 -276.734329) (xy 366.590582 -276.785624) (xy 366.574534 -276.835017)
			(xy 366.550956 -276.881291) (xy 366.52043 -276.923307) (xy 366.483707 -276.96003) (xy 366.441691 -276.990556)
			(xy 366.395417 -277.014134) (xy 366.346024 -277.030182) (xy 366.294729 -277.038307) (xy 366.242795 -277.038307)
			(xy 366.1915 -277.030182) (xy 366.142107 -277.014134) (xy 366.095833 -276.990556) (xy 366.053817 -276.96003)
			(xy 366.017094 -276.923307) (xy 365.986568 -276.881291) (xy 365.96299 -276.835017) (xy 365.946942 -276.785624)
			(xy 365.938817 -276.734329) (xy 365.658907 -276.734329) (xy 365.650782 -276.785624) (xy 365.634734 -276.835017)
			(xy 365.611156 -276.881291) (xy 365.58063 -276.923307) (xy 365.543907 -276.96003) (xy 365.501891 -276.990556)
			(xy 365.455617 -277.014134) (xy 365.406224 -277.030182) (xy 365.354929 -277.038307) (xy 365.302995 -277.038307)
			(xy 365.2517 -277.030182) (xy 365.202307 -277.014134) (xy 365.156033 -276.990556) (xy 365.114017 -276.96003)
			(xy 365.077294 -276.923307) (xy 365.046768 -276.881291) (xy 365.02319 -276.835017) (xy 365.007142 -276.785624)
			(xy 364.999017 -276.734329) (xy 364.719107 -276.734329) (xy 364.710982 -276.785624) (xy 364.694934 -276.835017)
			(xy 364.671356 -276.881291) (xy 364.64083 -276.923307) (xy 364.604107 -276.96003) (xy 364.562091 -276.990556)
			(xy 364.515817 -277.014134) (xy 364.466424 -277.030182) (xy 364.415129 -277.038307) (xy 364.363195 -277.038307)
			(xy 364.3119 -277.030182) (xy 364.262507 -277.014134) (xy 364.216233 -276.990556) (xy 364.174217 -276.96003)
			(xy 364.137494 -276.923307) (xy 364.106968 -276.881291) (xy 364.08339 -276.835017) (xy 364.067342 -276.785624)
			(xy 364.059217 -276.734329) (xy 363.779307 -276.734329) (xy 363.771182 -276.785624) (xy 363.755134 -276.835017)
			(xy 363.731556 -276.881291) (xy 363.70103 -276.923307) (xy 363.664307 -276.96003) (xy 363.622291 -276.990556)
			(xy 363.576017 -277.014134) (xy 363.526624 -277.030182) (xy 363.475329 -277.038307) (xy 363.423395 -277.038307)
			(xy 363.3721 -277.030182) (xy 363.322707 -277.014134) (xy 363.276433 -276.990556) (xy 363.234417 -276.96003)
			(xy 363.197694 -276.923307) (xy 363.167168 -276.881291) (xy 363.14359 -276.835017) (xy 363.127542 -276.785624)
			(xy 363.119417 -276.734329) (xy 362.839766 -276.734329) (xy 362.839761 -276.734583) (xy 362.831636 -276.785878)
			(xy 362.815588 -276.835271) (xy 362.79201 -276.881545) (xy 362.761484 -276.923561) (xy 362.724761 -276.960284)
			(xy 362.682745 -276.99081) (xy 362.636471 -277.014388) (xy 362.587078 -277.030436) (xy 362.535783 -277.038561)
			(xy 362.483849 -277.038561) (xy 362.432554 -277.030436) (xy 362.383161 -277.014388) (xy 362.336887 -276.99081)
			(xy 362.294871 -276.960284) (xy 362.258148 -276.923561) (xy 362.227622 -276.881545) (xy 362.204044 -276.835271)
			(xy 362.187996 -276.785878) (xy 362.179871 -276.734583) (xy 358.401447 -276.734583) (xy 358.414007 -276.750977)
			(xy 358.472747 -276.840078) (xy 358.524107 -276.933629) (xy 358.567752 -277.031018) (xy 358.603397 -277.13161)
			(xy 358.63081 -277.234751) (xy 358.649812 -277.339767) (xy 358.660279 -277.445974) (xy 358.661716 -277.499318)
			(xy 358.661716 -277.540974) (xy 358.661623 -277.548399) (xy 362.649517 -277.548399) (xy 362.649517 -277.496465)
			(xy 362.657642 -277.44517) (xy 362.67369 -277.395777) (xy 362.697268 -277.349503) (xy 362.727794 -277.307487)
			(xy 362.764517 -277.270764) (xy 362.806533 -277.240238) (xy 362.852807 -277.21666) (xy 362.9022 -277.200612)
			(xy 362.953495 -277.192487) (xy 363.005429 -277.192487) (xy 363.056724 -277.200612) (xy 363.106117 -277.21666)
			(xy 363.152391 -277.240238) (xy 363.194407 -277.270764) (xy 363.23113 -277.307487) (xy 363.261656 -277.349503)
			(xy 363.285234 -277.395777) (xy 363.301282 -277.44517) (xy 363.309407 -277.496465) (xy 363.309916 -277.522432)
			(xy 363.309412 -277.548145) (xy 363.589571 -277.548145) (xy 363.589571 -277.496211) (xy 363.597696 -277.444916)
			(xy 363.613744 -277.395523) (xy 363.637322 -277.349249) (xy 363.667848 -277.307233) (xy 363.704571 -277.27051)
			(xy 363.746587 -277.239984) (xy 363.792861 -277.216406) (xy 363.842254 -277.200358) (xy 363.893549 -277.192233)
			(xy 363.945483 -277.192233) (xy 363.996778 -277.200358) (xy 364.046171 -277.216406) (xy 364.092445 -277.239984)
			(xy 364.134461 -277.27051) (xy 364.171184 -277.307233) (xy 364.20171 -277.349249) (xy 364.225288 -277.395523)
			(xy 364.241336 -277.444916) (xy 364.249461 -277.496211) (xy 364.24997 -277.522178) (xy 364.249461 -277.548145)
			(xy 364.249421 -277.548399) (xy 364.529117 -277.548399) (xy 364.529117 -277.496465) (xy 364.537242 -277.44517)
			(xy 364.55329 -277.395777) (xy 364.576868 -277.349503) (xy 364.607394 -277.307487) (xy 364.644117 -277.270764)
			(xy 364.686133 -277.240238) (xy 364.732407 -277.21666) (xy 364.7818 -277.200612) (xy 364.833095 -277.192487)
			(xy 364.885029 -277.192487) (xy 364.936324 -277.200612) (xy 364.985717 -277.21666) (xy 365.031991 -277.240238)
			(xy 365.074007 -277.270764) (xy 365.11073 -277.307487) (xy 365.141256 -277.349503) (xy 365.164834 -277.395777)
			(xy 365.180882 -277.44517) (xy 365.189007 -277.496465) (xy 365.189516 -277.522432) (xy 365.189012 -277.548145)
			(xy 365.469171 -277.548145) (xy 365.469171 -277.496211) (xy 365.477296 -277.444916) (xy 365.493344 -277.395523)
			(xy 365.516922 -277.349249) (xy 365.547448 -277.307233) (xy 365.584171 -277.27051) (xy 365.626187 -277.239984)
			(xy 365.672461 -277.216406) (xy 365.721854 -277.200358) (xy 365.773149 -277.192233) (xy 365.825083 -277.192233)
			(xy 365.876378 -277.200358) (xy 365.925771 -277.216406) (xy 365.972045 -277.239984) (xy 366.014061 -277.27051)
			(xy 366.050784 -277.307233) (xy 366.08131 -277.349249) (xy 366.104888 -277.395523) (xy 366.120936 -277.444916)
			(xy 366.129061 -277.496211) (xy 366.12957 -277.522178) (xy 366.129061 -277.548145) (xy 366.120936 -277.59944)
			(xy 366.104888 -277.648833) (xy 366.08131 -277.695107) (xy 366.050784 -277.737123) (xy 366.014061 -277.773846)
			(xy 365.972045 -277.804372) (xy 365.925771 -277.82795) (xy 365.876378 -277.843998) (xy 365.825083 -277.852123)
			(xy 365.773149 -277.852123) (xy 365.721854 -277.843998) (xy 365.672461 -277.82795) (xy 365.626187 -277.804372)
			(xy 365.584171 -277.773846) (xy 365.547448 -277.737123) (xy 365.516922 -277.695107) (xy 365.493344 -277.648833)
			(xy 365.477296 -277.59944) (xy 365.469171 -277.548145) (xy 365.189012 -277.548145) (xy 365.189007 -277.548399)
			(xy 365.180882 -277.599694) (xy 365.164834 -277.649087) (xy 365.141256 -277.695361) (xy 365.11073 -277.737377)
			(xy 365.074007 -277.7741) (xy 365.031991 -277.804626) (xy 364.985717 -277.828204) (xy 364.936324 -277.844252)
			(xy 364.885029 -277.852377) (xy 364.833095 -277.852377) (xy 364.7818 -277.844252) (xy 364.732407 -277.828204)
			(xy 364.686133 -277.804626) (xy 364.644117 -277.7741) (xy 364.607394 -277.737377) (xy 364.576868 -277.695361)
			(xy 364.55329 -277.649087) (xy 364.537242 -277.599694) (xy 364.529117 -277.548399) (xy 364.249421 -277.548399)
			(xy 364.241336 -277.59944) (xy 364.225288 -277.648833) (xy 364.20171 -277.695107) (xy 364.171184 -277.737123)
			(xy 364.134461 -277.773846) (xy 364.092445 -277.804372) (xy 364.046171 -277.82795) (xy 363.996778 -277.843998)
			(xy 363.945483 -277.852123) (xy 363.893549 -277.852123) (xy 363.842254 -277.843998) (xy 363.792861 -277.82795)
			(xy 363.746587 -277.804372) (xy 363.704571 -277.773846) (xy 363.667848 -277.737123) (xy 363.637322 -277.695107)
			(xy 363.613744 -277.648833) (xy 363.597696 -277.59944) (xy 363.589571 -277.548145) (xy 363.309412 -277.548145)
			(xy 363.309407 -277.548399) (xy 363.301282 -277.599694) (xy 363.285234 -277.649087) (xy 363.261656 -277.695361)
			(xy 363.23113 -277.737377) (xy 363.194407 -277.7741) (xy 363.152391 -277.804626) (xy 363.106117 -277.828204)
			(xy 363.056724 -277.844252) (xy 363.005429 -277.852377) (xy 362.953495 -277.852377) (xy 362.9022 -277.844252)
			(xy 362.852807 -277.828204) (xy 362.806533 -277.804626) (xy 362.764517 -277.7741) (xy 362.727794 -277.737377)
			(xy 362.697268 -277.695361) (xy 362.67369 -277.649087) (xy 362.657642 -277.599694) (xy 362.649517 -277.548399)
			(xy 358.661623 -277.548399) (xy 358.661462 -277.561294) (xy 358.661462 -277.566628) (xy 358.659269 -277.617584)
			(xy 358.648007 -277.718962) (xy 358.628964 -277.819171) (xy 358.602252 -277.917613) (xy 358.568031 -278.013703)
			(xy 358.526505 -278.106869) (xy 358.47792 -278.196557) (xy 358.422566 -278.282232) (xy 358.361664 -278.362215)
			(xy 362.179617 -278.362215) (xy 362.179617 -278.310281) (xy 362.187742 -278.258986) (xy 362.20379 -278.209593)
			(xy 362.227368 -278.163319) (xy 362.257894 -278.121303) (xy 362.294617 -278.08458) (xy 362.336633 -278.054054)
			(xy 362.382907 -278.030476) (xy 362.4323 -278.014428) (xy 362.483595 -278.006303) (xy 362.535529 -278.006303)
			(xy 362.586824 -278.014428) (xy 362.636217 -278.030476) (xy 362.682491 -278.054054) (xy 362.724507 -278.08458)
			(xy 362.76123 -278.121303) (xy 362.791756 -278.163319) (xy 362.815334 -278.209593) (xy 362.831382 -278.258986)
			(xy 362.839507 -278.310281) (xy 362.840016 -278.336248) (xy 362.839507 -278.362215) (xy 363.119417 -278.362215)
			(xy 363.119417 -278.310281) (xy 363.127542 -278.258986) (xy 363.14359 -278.209593) (xy 363.167168 -278.163319)
			(xy 363.197694 -278.121303) (xy 363.234417 -278.08458) (xy 363.276433 -278.054054) (xy 363.322707 -278.030476)
			(xy 363.3721 -278.014428) (xy 363.423395 -278.006303) (xy 363.475329 -278.006303) (xy 363.526624 -278.014428)
			(xy 363.576017 -278.030476) (xy 363.622291 -278.054054) (xy 363.664307 -278.08458) (xy 363.70103 -278.121303)
			(xy 363.731556 -278.163319) (xy 363.755134 -278.209593) (xy 363.771182 -278.258986) (xy 363.779307 -278.310281)
			(xy 363.779816 -278.336248) (xy 363.779307 -278.362215) (xy 364.059217 -278.362215) (xy 364.059217 -278.310281)
			(xy 364.067342 -278.258986) (xy 364.08339 -278.209593) (xy 364.106968 -278.163319) (xy 364.137494 -278.121303)
			(xy 364.174217 -278.08458) (xy 364.216233 -278.054054) (xy 364.262507 -278.030476) (xy 364.3119 -278.014428)
			(xy 364.363195 -278.006303) (xy 364.415129 -278.006303) (xy 364.466424 -278.014428) (xy 364.515817 -278.030476)
			(xy 364.562091 -278.054054) (xy 364.604107 -278.08458) (xy 364.64083 -278.121303) (xy 364.671356 -278.163319)
			(xy 364.694934 -278.209593) (xy 364.710982 -278.258986) (xy 364.719107 -278.310281) (xy 364.719616 -278.336248)
			(xy 364.719107 -278.362215) (xy 364.999017 -278.362215) (xy 364.999017 -278.310281) (xy 365.007142 -278.258986)
			(xy 365.02319 -278.209593) (xy 365.046768 -278.163319) (xy 365.077294 -278.121303) (xy 365.114017 -278.08458)
			(xy 365.156033 -278.054054) (xy 365.202307 -278.030476) (xy 365.2517 -278.014428) (xy 365.302995 -278.006303)
			(xy 365.354929 -278.006303) (xy 365.406224 -278.014428) (xy 365.455617 -278.030476) (xy 365.501891 -278.054054)
			(xy 365.543907 -278.08458) (xy 365.58063 -278.121303) (xy 365.611156 -278.163319) (xy 365.634734 -278.209593)
			(xy 365.650782 -278.258986) (xy 365.658907 -278.310281) (xy 365.659416 -278.336248) (xy 365.658907 -278.362215)
			(xy 365.938817 -278.362215) (xy 365.938817 -278.310281) (xy 365.946942 -278.258986) (xy 365.96299 -278.209593)
			(xy 365.986568 -278.163319) (xy 366.017094 -278.121303) (xy 366.053817 -278.08458) (xy 366.095833 -278.054054)
			(xy 366.142107 -278.030476) (xy 366.1915 -278.014428) (xy 366.242795 -278.006303) (xy 366.294729 -278.006303)
			(xy 366.346024 -278.014428) (xy 366.395417 -278.030476) (xy 366.441691 -278.054054) (xy 366.483707 -278.08458)
			(xy 366.52043 -278.121303) (xy 366.550956 -278.163319) (xy 366.574534 -278.209593) (xy 366.590582 -278.258986)
			(xy 366.598707 -278.310281) (xy 366.599216 -278.336248) (xy 366.598707 -278.362215) (xy 366.590582 -278.41351)
			(xy 366.574534 -278.462903) (xy 366.550956 -278.509177) (xy 366.52043 -278.551193) (xy 366.483707 -278.587916)
			(xy 366.441691 -278.618442) (xy 366.395417 -278.64202) (xy 366.346024 -278.658068) (xy 366.294729 -278.666193)
			(xy 366.242795 -278.666193) (xy 366.1915 -278.658068) (xy 366.142107 -278.64202) (xy 366.095833 -278.618442)
			(xy 366.053817 -278.587916) (xy 366.017094 -278.551193) (xy 365.986568 -278.509177) (xy 365.96299 -278.462903)
			(xy 365.946942 -278.41351) (xy 365.938817 -278.362215) (xy 365.658907 -278.362215) (xy 365.650782 -278.41351)
			(xy 365.634734 -278.462903) (xy 365.611156 -278.509177) (xy 365.58063 -278.551193) (xy 365.543907 -278.587916)
			(xy 365.501891 -278.618442) (xy 365.455617 -278.64202) (xy 365.406224 -278.658068) (xy 365.354929 -278.666193)
			(xy 365.302995 -278.666193) (xy 365.2517 -278.658068) (xy 365.202307 -278.64202) (xy 365.156033 -278.618442)
			(xy 365.114017 -278.587916) (xy 365.077294 -278.551193) (xy 365.046768 -278.509177) (xy 365.02319 -278.462903)
			(xy 365.007142 -278.41351) (xy 364.999017 -278.362215) (xy 364.719107 -278.362215) (xy 364.710982 -278.41351)
			(xy 364.694934 -278.462903) (xy 364.671356 -278.509177) (xy 364.64083 -278.551193) (xy 364.604107 -278.587916)
			(xy 364.562091 -278.618442) (xy 364.515817 -278.64202) (xy 364.466424 -278.658068) (xy 364.415129 -278.666193)
			(xy 364.363195 -278.666193) (xy 364.3119 -278.658068) (xy 364.262507 -278.64202) (xy 364.216233 -278.618442)
			(xy 364.174217 -278.587916) (xy 364.137494 -278.551193) (xy 364.106968 -278.509177) (xy 364.08339 -278.462903)
			(xy 364.067342 -278.41351) (xy 364.059217 -278.362215) (xy 363.779307 -278.362215) (xy 363.771182 -278.41351)
			(xy 363.755134 -278.462903) (xy 363.731556 -278.509177) (xy 363.70103 -278.551193) (xy 363.664307 -278.587916)
			(xy 363.622291 -278.618442) (xy 363.576017 -278.64202) (xy 363.526624 -278.658068) (xy 363.475329 -278.666193)
			(xy 363.423395 -278.666193) (xy 363.3721 -278.658068) (xy 363.322707 -278.64202) (xy 363.276433 -278.618442)
			(xy 363.234417 -278.587916) (xy 363.197694 -278.551193) (xy 363.167168 -278.509177) (xy 363.14359 -278.462903)
			(xy 363.127542 -278.41351) (xy 363.119417 -278.362215) (xy 362.839507 -278.362215) (xy 362.831382 -278.41351)
			(xy 362.815334 -278.462903) (xy 362.791756 -278.509177) (xy 362.76123 -278.551193) (xy 362.724507 -278.587916)
			(xy 362.682491 -278.618442) (xy 362.636217 -278.64202) (xy 362.586824 -278.658068) (xy 362.535529 -278.666193)
			(xy 362.483595 -278.666193) (xy 362.4323 -278.658068) (xy 362.382907 -278.64202) (xy 362.336633 -278.618442)
			(xy 362.294617 -278.587916) (xy 362.257894 -278.551193) (xy 362.227368 -278.509177) (xy 362.20379 -278.462903)
			(xy 362.187742 -278.41351) (xy 362.179617 -278.362215) (xy 358.361664 -278.362215) (xy 358.360772 -278.363386)
			(xy 358.327198 -278.40178) (xy 358.314244 -278.416258) (xy 358.314244 -278.821134) (xy 358.341061 -278.824429)
			(xy 358.393194 -278.838607) (xy 358.442333 -278.861065) (xy 358.487172 -278.891204) (xy 358.526521 -278.928225)
			(xy 358.559335 -278.971145) (xy 358.584744 -279.018824) (xy 358.602072 -279.069997) (xy 358.610859 -279.123305)
			(xy 358.611424 -279.150318) (xy 358.610913 -279.176285) (xy 362.649517 -279.176285) (xy 362.649517 -279.124351)
			(xy 362.657642 -279.073056) (xy 362.67369 -279.023663) (xy 362.697268 -278.977389) (xy 362.727794 -278.935373)
			(xy 362.764517 -278.89865) (xy 362.806533 -278.868124) (xy 362.852807 -278.844546) (xy 362.9022 -278.828498)
			(xy 362.953495 -278.820373) (xy 363.005429 -278.820373) (xy 363.056724 -278.828498) (xy 363.106117 -278.844546)
			(xy 363.152391 -278.868124) (xy 363.194407 -278.89865) (xy 363.23113 -278.935373) (xy 363.261656 -278.977389)
			(xy 363.285234 -279.023663) (xy 363.301282 -279.073056) (xy 363.309407 -279.124351) (xy 363.309916 -279.150318)
			(xy 363.309407 -279.176285) (xy 363.589317 -279.176285) (xy 363.589317 -279.124351) (xy 363.597442 -279.073056)
			(xy 363.61349 -279.023663) (xy 363.637068 -278.977389) (xy 363.667594 -278.935373) (xy 363.704317 -278.89865)
			(xy 363.746333 -278.868124) (xy 363.792607 -278.844546) (xy 363.842 -278.828498) (xy 363.893295 -278.820373)
			(xy 363.945229 -278.820373) (xy 363.996524 -278.828498) (xy 364.045917 -278.844546) (xy 364.092191 -278.868124)
			(xy 364.134207 -278.89865) (xy 364.17093 -278.935373) (xy 364.201456 -278.977389) (xy 364.225034 -279.023663)
			(xy 364.241082 -279.073056) (xy 364.249207 -279.124351) (xy 364.249716 -279.150318) (xy 364.249212 -279.176031)
			(xy 364.529371 -279.176031) (xy 364.529371 -279.124097) (xy 364.537496 -279.072802) (xy 364.553544 -279.023409)
			(xy 364.577122 -278.977135) (xy 364.607648 -278.935119) (xy 364.644371 -278.898396) (xy 364.686387 -278.86787)
			(xy 364.732661 -278.844292) (xy 364.782054 -278.828244) (xy 364.833349 -278.820119) (xy 364.885283 -278.820119)
			(xy 364.936578 -278.828244) (xy 364.985971 -278.844292) (xy 365.032245 -278.86787) (xy 365.074261 -278.898396)
			(xy 365.110984 -278.935119) (xy 365.14151 -278.977135) (xy 365.165088 -279.023409) (xy 365.181136 -279.072802)
			(xy 365.189261 -279.124097) (xy 365.18977 -279.150064) (xy 365.189261 -279.176031) (xy 365.189221 -279.176285)
			(xy 365.469171 -279.176285) (xy 365.469171 -279.124351) (xy 365.477296 -279.073056) (xy 365.493344 -279.023663)
			(xy 365.516922 -278.977389) (xy 365.547448 -278.935373) (xy 365.584171 -278.89865) (xy 365.626187 -278.868124)
			(xy 365.672461 -278.844546) (xy 365.721854 -278.828498) (xy 365.773149 -278.820373) (xy 365.825083 -278.820373)
			(xy 365.876378 -278.828498) (xy 365.925771 -278.844546) (xy 365.972045 -278.868124) (xy 366.014061 -278.89865)
			(xy 366.050784 -278.935373) (xy 366.08131 -278.977389) (xy 366.104888 -279.023663) (xy 366.120936 -279.073056)
			(xy 366.129061 -279.124351) (xy 366.12957 -279.150318) (xy 366.129061 -279.176285) (xy 366.120936 -279.22758)
			(xy 366.104888 -279.276973) (xy 366.08131 -279.323247) (xy 366.050784 -279.365263) (xy 366.014061 -279.401986)
			(xy 365.972045 -279.432512) (xy 365.925771 -279.45609) (xy 365.876378 -279.472138) (xy 365.825083 -279.480263)
			(xy 365.773149 -279.480263) (xy 365.721854 -279.472138) (xy 365.672461 -279.45609) (xy 365.626187 -279.432512)
			(xy 365.584171 -279.401986) (xy 365.547448 -279.365263) (xy 365.516922 -279.323247) (xy 365.493344 -279.276973)
			(xy 365.477296 -279.22758) (xy 365.469171 -279.176285) (xy 365.189221 -279.176285) (xy 365.181136 -279.227326)
			(xy 365.165088 -279.276719) (xy 365.14151 -279.322993) (xy 365.110984 -279.365009) (xy 365.074261 -279.401732)
			(xy 365.032245 -279.432258) (xy 364.985971 -279.455836) (xy 364.936578 -279.471884) (xy 364.885283 -279.480009)
			(xy 364.833349 -279.480009) (xy 364.782054 -279.471884) (xy 364.732661 -279.455836) (xy 364.686387 -279.432258)
			(xy 364.644371 -279.401732) (xy 364.607648 -279.365009) (xy 364.577122 -279.322993) (xy 364.553544 -279.276719)
			(xy 364.537496 -279.227326) (xy 364.529371 -279.176031) (xy 364.249212 -279.176031) (xy 364.249207 -279.176285)
			(xy 364.241082 -279.22758) (xy 364.225034 -279.276973) (xy 364.201456 -279.323247) (xy 364.17093 -279.365263)
			(xy 364.134207 -279.401986) (xy 364.092191 -279.432512) (xy 364.045917 -279.45609) (xy 363.996524 -279.472138)
			(xy 363.945229 -279.480263) (xy 363.893295 -279.480263) (xy 363.842 -279.472138) (xy 363.792607 -279.45609)
			(xy 363.746333 -279.432512) (xy 363.704317 -279.401986) (xy 363.667594 -279.365263) (xy 363.637068 -279.323247)
			(xy 363.61349 -279.276973) (xy 363.597442 -279.22758) (xy 363.589317 -279.176285) (xy 363.309407 -279.176285)
			(xy 363.301282 -279.22758) (xy 363.285234 -279.276973) (xy 363.261656 -279.323247) (xy 363.23113 -279.365263)
			(xy 363.194407 -279.401986) (xy 363.152391 -279.432512) (xy 363.106117 -279.45609) (xy 363.056724 -279.472138)
			(xy 363.005429 -279.480263) (xy 362.953495 -279.480263) (xy 362.9022 -279.472138) (xy 362.852807 -279.45609)
			(xy 362.806533 -279.432512) (xy 362.764517 -279.401986) (xy 362.727794 -279.365263) (xy 362.697268 -279.323247)
			(xy 362.67369 -279.276973) (xy 362.657642 -279.22758) (xy 362.649517 -279.176285) (xy 358.610913 -279.176285)
			(xy 358.610913 -279.176305) (xy 358.60278 -279.227638) (xy 358.586718 -279.277067) (xy 358.563121 -279.323375)
			(xy 358.532572 -279.365422) (xy 358.495821 -279.402173) (xy 358.453774 -279.432723) (xy 358.407465 -279.456319)
			(xy 358.358036 -279.472381) (xy 358.306703 -279.480513) (xy 358.280716 -279.481026) (xy 358.277922 -279.481026)
			(xy 358.25684 -279.480772) (xy 358.140508 -279.597104) (xy 358.147874 -279.625552) (xy 358.160994 -279.677134)
			(xy 358.179909 -279.781884) (xy 358.190345 -279.887816) (xy 358.191816 -279.94102) (xy 358.191816 -279.982676)
			(xy 358.191723 -279.990101) (xy 361.239817 -279.990101) (xy 361.239817 -279.938167) (xy 361.247942 -279.886872)
			(xy 361.26399 -279.837479) (xy 361.287568 -279.791205) (xy 361.318094 -279.749189) (xy 361.354817 -279.712466)
			(xy 361.396833 -279.68194) (xy 361.443107 -279.658362) (xy 361.4925 -279.642314) (xy 361.543795 -279.634189)
			(xy 361.595729 -279.634189) (xy 361.647024 -279.642314) (xy 361.696417 -279.658362) (xy 361.742691 -279.68194)
			(xy 361.784707 -279.712466) (xy 361.82143 -279.749189) (xy 361.851956 -279.791205) (xy 361.875534 -279.837479)
			(xy 361.891582 -279.886872) (xy 361.899707 -279.938167) (xy 361.900216 -279.964134) (xy 361.899707 -279.990101)
			(xy 364.059471 -279.990101) (xy 364.059471 -279.938167) (xy 364.067596 -279.886872) (xy 364.083644 -279.837479)
			(xy 364.107222 -279.791205) (xy 364.137748 -279.749189) (xy 364.174471 -279.712466) (xy 364.216487 -279.68194)
			(xy 364.262761 -279.658362) (xy 364.312154 -279.642314) (xy 364.363449 -279.634189) (xy 364.415383 -279.634189)
			(xy 364.466678 -279.642314) (xy 364.516071 -279.658362) (xy 364.562345 -279.68194) (xy 364.604361 -279.712466)
			(xy 364.641084 -279.749189) (xy 364.67161 -279.791205) (xy 364.695188 -279.837479) (xy 364.711236 -279.886872)
			(xy 364.719361 -279.938167) (xy 364.71987 -279.964134) (xy 364.719361 -279.990101) (xy 364.999271 -279.990101)
			(xy 364.999271 -279.938167) (xy 365.007396 -279.886872) (xy 365.023444 -279.837479) (xy 365.047022 -279.791205)
			(xy 365.077548 -279.749189) (xy 365.114271 -279.712466) (xy 365.156287 -279.68194) (xy 365.202561 -279.658362)
			(xy 365.251954 -279.642314) (xy 365.303249 -279.634189) (xy 365.355183 -279.634189) (xy 365.406478 -279.642314)
			(xy 365.455871 -279.658362) (xy 365.502145 -279.68194) (xy 365.544161 -279.712466) (xy 365.580884 -279.749189)
			(xy 365.61141 -279.791205) (xy 365.634988 -279.837479) (xy 365.651036 -279.886872) (xy 365.659161 -279.938167)
			(xy 365.65967 -279.964134) (xy 365.659161 -279.990101) (xy 365.938817 -279.990101) (xy 365.938817 -279.938167)
			(xy 365.946942 -279.886872) (xy 365.96299 -279.837479) (xy 365.986568 -279.791205) (xy 366.017094 -279.749189)
			(xy 366.053817 -279.712466) (xy 366.095833 -279.68194) (xy 366.142107 -279.658362) (xy 366.1915 -279.642314)
			(xy 366.242795 -279.634189) (xy 366.294729 -279.634189) (xy 366.346024 -279.642314) (xy 366.395417 -279.658362)
			(xy 366.441691 -279.68194) (xy 366.483707 -279.712466) (xy 366.52043 -279.749189) (xy 366.550956 -279.791205)
			(xy 366.574534 -279.837479) (xy 366.590582 -279.886872) (xy 366.598707 -279.938167) (xy 366.599216 -279.964134)
			(xy 366.598707 -279.990101) (xy 366.590582 -280.041396) (xy 366.574534 -280.090789) (xy 366.550956 -280.137063)
			(xy 366.52043 -280.179079) (xy 366.483707 -280.215802) (xy 366.441691 -280.246328) (xy 366.395417 -280.269906)
			(xy 366.346024 -280.285954) (xy 366.294729 -280.294079) (xy 366.242795 -280.294079) (xy 366.1915 -280.285954)
			(xy 366.142107 -280.269906) (xy 366.095833 -280.246328) (xy 366.053817 -280.215802) (xy 366.017094 -280.179079)
			(xy 365.986568 -280.137063) (xy 365.96299 -280.090789) (xy 365.946942 -280.041396) (xy 365.938817 -279.990101)
			(xy 365.659161 -279.990101) (xy 365.651036 -280.041396) (xy 365.634988 -280.090789) (xy 365.61141 -280.137063)
			(xy 365.580884 -280.179079) (xy 365.544161 -280.215802) (xy 365.502145 -280.246328) (xy 365.455871 -280.269906)
			(xy 365.406478 -280.285954) (xy 365.355183 -280.294079) (xy 365.303249 -280.294079) (xy 365.251954 -280.285954)
			(xy 365.202561 -280.269906) (xy 365.156287 -280.246328) (xy 365.114271 -280.215802) (xy 365.077548 -280.179079)
			(xy 365.047022 -280.137063) (xy 365.023444 -280.090789) (xy 365.007396 -280.041396) (xy 364.999271 -279.990101)
			(xy 364.719361 -279.990101) (xy 364.711236 -280.041396) (xy 364.695188 -280.090789) (xy 364.67161 -280.137063)
			(xy 364.641084 -280.179079) (xy 364.604361 -280.215802) (xy 364.562345 -280.246328) (xy 364.516071 -280.269906)
			(xy 364.466678 -280.285954) (xy 364.415383 -280.294079) (xy 364.363449 -280.294079) (xy 364.312154 -280.285954)
			(xy 364.262761 -280.269906) (xy 364.216487 -280.246328) (xy 364.174471 -280.215802) (xy 364.137748 -280.179079)
			(xy 364.107222 -280.137063) (xy 364.083644 -280.090789) (xy 364.067596 -280.041396) (xy 364.059471 -279.990101)
			(xy 361.899707 -279.990101) (xy 361.891582 -280.041396) (xy 361.875534 -280.090789) (xy 361.851956 -280.137063)
			(xy 361.82143 -280.179079) (xy 361.784707 -280.215802) (xy 361.742691 -280.246328) (xy 361.696417 -280.269906)
			(xy 361.647024 -280.285954) (xy 361.595729 -280.294079) (xy 361.543795 -280.294079) (xy 361.4925 -280.285954)
			(xy 361.443107 -280.269906) (xy 361.396833 -280.246328) (xy 361.354817 -280.215802) (xy 361.318094 -280.179079)
			(xy 361.287568 -280.137063) (xy 361.26399 -280.090789) (xy 361.247942 -280.041396) (xy 361.239817 -279.990101)
			(xy 358.191723 -279.990101) (xy 358.191562 -280.002996) (xy 358.191562 -280.007568) (xy 358.191308 -280.012902)
			(xy 358.188897 -280.064863) (xy 358.17691 -280.168198) (xy 358.156831 -280.27027) (xy 358.143302 -280.320496)
			(xy 358.143048 -280.321258) (xy 358.139786 -280.334894) (xy 358.140038 -280.362921) (xy 358.147904 -280.389823)
			(xy 358.162792 -280.413571) (xy 358.183578 -280.432373) (xy 358.208695 -280.444811) (xy 358.236248 -280.449948)
			(xy 358.250236 -280.44902) (xy 358.280462 -280.44775) (xy 358.306433 -280.44823) (xy 358.357736 -280.45635)
			(xy 358.407137 -280.472396) (xy 358.453419 -280.495974) (xy 358.495443 -280.526502) (xy 358.532174 -280.563228)
			(xy 358.562706 -280.605248) (xy 358.586289 -280.651528) (xy 358.602341 -280.700927) (xy 358.610467 -280.752229)
			(xy 358.610467 -280.804171) (xy 364.529371 -280.804171) (xy 364.529371 -280.752237) (xy 364.537496 -280.700942)
			(xy 364.553544 -280.651549) (xy 364.577122 -280.605275) (xy 364.607648 -280.563259) (xy 364.644371 -280.526536)
			(xy 364.686387 -280.49601) (xy 364.732661 -280.472432) (xy 364.782054 -280.456384) (xy 364.833349 -280.448259)
			(xy 364.885283 -280.448259) (xy 364.936578 -280.456384) (xy 364.985971 -280.472432) (xy 365.032245 -280.49601)
			(xy 365.074261 -280.526536) (xy 365.110984 -280.563259) (xy 365.14151 -280.605275) (xy 365.165088 -280.651549)
			(xy 365.181136 -280.700942) (xy 365.189261 -280.752237) (xy 365.18977 -280.778204) (xy 365.189261 -280.804171)
			(xy 365.469171 -280.804171) (xy 365.469171 -280.752237) (xy 365.477296 -280.700942) (xy 365.493344 -280.651549)
			(xy 365.516922 -280.605275) (xy 365.547448 -280.563259) (xy 365.584171 -280.526536) (xy 365.626187 -280.49601)
			(xy 365.672461 -280.472432) (xy 365.721854 -280.456384) (xy 365.773149 -280.448259) (xy 365.825083 -280.448259)
			(xy 365.876378 -280.456384) (xy 365.925771 -280.472432) (xy 365.972045 -280.49601) (xy 366.014061 -280.526536)
			(xy 366.050784 -280.563259) (xy 366.08131 -280.605275) (xy 366.104888 -280.651549) (xy 366.120936 -280.700942)
			(xy 366.129061 -280.752237) (xy 366.12957 -280.778204) (xy 366.129061 -280.804171) (xy 366.120936 -280.855466)
			(xy 366.104888 -280.904859) (xy 366.08131 -280.951133) (xy 366.050784 -280.993149) (xy 366.014061 -281.029872)
			(xy 365.972045 -281.060398) (xy 365.925771 -281.083976) (xy 365.876378 -281.100024) (xy 365.825083 -281.108149)
			(xy 365.773149 -281.108149) (xy 365.721854 -281.100024) (xy 365.672461 -281.083976) (xy 365.626187 -281.060398)
			(xy 365.584171 -281.029872) (xy 365.547448 -280.993149) (xy 365.516922 -280.951133) (xy 365.493344 -280.904859)
			(xy 365.477296 -280.855466) (xy 365.469171 -280.804171) (xy 365.189261 -280.804171) (xy 365.181136 -280.855466)
			(xy 365.165088 -280.904859) (xy 365.14151 -280.951133) (xy 365.110984 -280.993149) (xy 365.074261 -281.029872)
			(xy 365.032245 -281.060398) (xy 364.985971 -281.083976) (xy 364.936578 -281.100024) (xy 364.885283 -281.108149)
			(xy 364.833349 -281.108149) (xy 364.782054 -281.100024) (xy 364.732661 -281.083976) (xy 364.686387 -281.060398)
			(xy 364.644371 -281.029872) (xy 364.607648 -280.993149) (xy 364.577122 -280.951133) (xy 364.553544 -280.904859)
			(xy 364.537496 -280.855466) (xy 364.529371 -280.804171) (xy 358.610467 -280.804171) (xy 358.602341 -280.855473)
			(xy 358.586289 -280.904872) (xy 358.562706 -280.951152) (xy 358.532174 -280.993172) (xy 358.495443 -281.029898)
			(xy 358.453419 -281.060426) (xy 358.407137 -281.084004) (xy 358.357736 -281.10005) (xy 358.306433 -281.10817)
			(xy 358.280462 -281.108658) (xy 358.250236 -281.107388) (xy 358.236463 -281.106577) (xy 358.209326 -281.111484)
			(xy 358.184491 -281.123474) (xy 358.16377 -281.141672) (xy 358.148674 -281.164751) (xy 358.140304 -281.191027)
			(xy 358.13927 -281.218586) (xy 358.142032 -281.232102) (xy 358.156941 -281.287028) (xy 358.178409 -281.398806)
			(xy 358.190189 -281.512015) (xy 358.191816 -281.568906) (xy 358.191816 -281.601926) (xy 358.191816 -281.615134)
			(xy 358.191736 -281.617987) (xy 361.239817 -281.617987) (xy 361.239817 -281.566053) (xy 361.247942 -281.514758)
			(xy 361.26399 -281.465365) (xy 361.287568 -281.419091) (xy 361.318094 -281.377075) (xy 361.354817 -281.340352)
			(xy 361.396833 -281.309826) (xy 361.443107 -281.286248) (xy 361.4925 -281.2702) (xy 361.543795 -281.262075)
			(xy 361.595729 -281.262075) (xy 361.647024 -281.2702) (xy 361.696417 -281.286248) (xy 361.742691 -281.309826)
			(xy 361.784707 -281.340352) (xy 361.82143 -281.377075) (xy 361.851956 -281.419091) (xy 361.875534 -281.465365)
			(xy 361.891582 -281.514758) (xy 361.899707 -281.566053) (xy 361.900216 -281.59202) (xy 361.899707 -281.617987)
			(xy 364.999271 -281.617987) (xy 364.999271 -281.566053) (xy 365.007396 -281.514758) (xy 365.023444 -281.465365)
			(xy 365.047022 -281.419091) (xy 365.077548 -281.377075) (xy 365.114271 -281.340352) (xy 365.156287 -281.309826)
			(xy 365.202561 -281.286248) (xy 365.251954 -281.2702) (xy 365.303249 -281.262075) (xy 365.355183 -281.262075)
			(xy 365.406478 -281.2702) (xy 365.455871 -281.286248) (xy 365.502145 -281.309826) (xy 365.544161 -281.340352)
			(xy 365.580884 -281.377075) (xy 365.61141 -281.419091) (xy 365.634988 -281.465365) (xy 365.651036 -281.514758)
			(xy 365.659161 -281.566053) (xy 365.65967 -281.59202) (xy 365.659161 -281.617987) (xy 365.938817 -281.617987)
			(xy 365.938817 -281.566053) (xy 365.946942 -281.514758) (xy 365.96299 -281.465365) (xy 365.986568 -281.419091)
			(xy 366.017094 -281.377075) (xy 366.053817 -281.340352) (xy 366.095833 -281.309826) (xy 366.142107 -281.286248)
			(xy 366.1915 -281.2702) (xy 366.242795 -281.262075) (xy 366.294729 -281.262075) (xy 366.346024 -281.2702)
			(xy 366.395417 -281.286248) (xy 366.441691 -281.309826) (xy 366.483707 -281.340352) (xy 366.52043 -281.377075)
			(xy 366.550956 -281.419091) (xy 366.574534 -281.465365) (xy 366.590582 -281.514758) (xy 366.598707 -281.566053)
			(xy 366.599216 -281.59202) (xy 366.598707 -281.617987) (xy 366.590582 -281.669282) (xy 366.574534 -281.718675)
			(xy 366.550956 -281.764949) (xy 366.52043 -281.806965) (xy 366.483707 -281.843688) (xy 366.441691 -281.874214)
			(xy 366.395417 -281.897792) (xy 366.346024 -281.91384) (xy 366.294729 -281.921965) (xy 366.242795 -281.921965)
			(xy 366.1915 -281.91384) (xy 366.142107 -281.897792) (xy 366.095833 -281.874214) (xy 366.053817 -281.843688)
			(xy 366.017094 -281.806965) (xy 365.986568 -281.764949) (xy 365.96299 -281.718675) (xy 365.946942 -281.669282)
			(xy 365.938817 -281.617987) (xy 365.659161 -281.617987) (xy 365.651036 -281.669282) (xy 365.634988 -281.718675)
			(xy 365.61141 -281.764949) (xy 365.580884 -281.806965) (xy 365.544161 -281.843688) (xy 365.502145 -281.874214)
			(xy 365.455871 -281.897792) (xy 365.406478 -281.91384) (xy 365.355183 -281.921965) (xy 365.303249 -281.921965)
			(xy 365.251954 -281.91384) (xy 365.202561 -281.897792) (xy 365.156287 -281.874214) (xy 365.114271 -281.843688)
			(xy 365.077548 -281.806965) (xy 365.047022 -281.764949) (xy 365.023444 -281.718675) (xy 365.007396 -281.669282)
			(xy 364.999271 -281.617987) (xy 361.899707 -281.617987) (xy 361.891582 -281.669282) (xy 361.875534 -281.718675)
			(xy 361.851956 -281.764949) (xy 361.82143 -281.806965) (xy 361.784707 -281.843688) (xy 361.742691 -281.874214)
			(xy 361.696417 -281.897792) (xy 361.647024 -281.91384) (xy 361.595729 -281.921965) (xy 361.543795 -281.921965)
			(xy 361.4925 -281.91384) (xy 361.443107 -281.897792) (xy 361.396833 -281.874214) (xy 361.354817 -281.843688)
			(xy 361.318094 -281.806965) (xy 361.287568 -281.764949) (xy 361.26399 -281.718675) (xy 361.247942 -281.669282)
			(xy 361.239817 -281.617987) (xy 358.191736 -281.617987) (xy 358.190225 -281.672027) (xy 358.178448 -281.785239)
			(xy 358.156966 -281.897017) (xy 358.142032 -281.951938) (xy 358.139264 -281.965464) (xy 358.140262 -281.993044)
			(xy 358.148614 -282.019348) (xy 358.163709 -282.042452) (xy 358.184443 -282.060665) (xy 358.2093 -282.072656)
			(xy 358.236461 -282.077548) (xy 358.250236 -282.076652) (xy 358.280462 -282.075382) (xy 358.30643 -282.075862)
			(xy 358.357729 -282.083981) (xy 358.407125 -282.100026) (xy 358.453403 -282.123601) (xy 358.495422 -282.154126)
			(xy 358.532149 -282.190849) (xy 358.562679 -282.232865) (xy 358.586259 -282.27914) (xy 358.60231 -282.328534)
			(xy 358.610435 -282.379832) (xy 358.610435 -282.431768) (xy 358.610429 -282.431803) (xy 365.469171 -282.431803)
			(xy 365.469171 -282.379869) (xy 365.477296 -282.328574) (xy 365.493344 -282.279181) (xy 365.516922 -282.232907)
			(xy 365.547448 -282.190891) (xy 365.584171 -282.154168) (xy 365.626187 -282.123642) (xy 365.672461 -282.100064)
			(xy 365.721854 -282.084016) (xy 365.773149 -282.075891) (xy 365.825083 -282.075891) (xy 365.876378 -282.084016)
			(xy 365.925771 -282.100064) (xy 365.972045 -282.123642) (xy 366.014061 -282.154168) (xy 366.050784 -282.190891)
			(xy 366.08131 -282.232907) (xy 366.104888 -282.279181) (xy 366.120936 -282.328574) (xy 366.129061 -282.379869)
			(xy 366.12957 -282.405836) (xy 366.129061 -282.431803) (xy 366.120936 -282.483098) (xy 366.104888 -282.532491)
			(xy 366.08131 -282.578765) (xy 366.050784 -282.620781) (xy 366.014061 -282.657504) (xy 365.972045 -282.68803)
			(xy 365.925771 -282.711608) (xy 365.876378 -282.727656) (xy 365.825083 -282.735781) (xy 365.773149 -282.735781)
			(xy 365.721854 -282.727656) (xy 365.672461 -282.711608) (xy 365.626187 -282.68803) (xy 365.584171 -282.657504)
			(xy 365.547448 -282.620781) (xy 365.516922 -282.578765) (xy 365.493344 -282.532491) (xy 365.477296 -282.483098)
			(xy 365.469171 -282.431803) (xy 358.610429 -282.431803) (xy 358.60231 -282.483066) (xy 358.586259 -282.53246)
			(xy 358.562679 -282.578735) (xy 358.532149 -282.620751) (xy 358.495422 -282.657474) (xy 358.453403 -282.687999)
			(xy 358.407125 -282.711574) (xy 358.357729 -282.727619) (xy 358.30643 -282.735738) (xy 358.280462 -282.73629)
			(xy 358.250236 -282.73502) (xy 358.236238 -282.734215) (xy 358.208694 -282.739402) (xy 358.183594 -282.751876)
			(xy 358.162827 -282.770699) (xy 358.147953 -282.794455) (xy 358.140093 -282.821359) (xy 358.139836 -282.849386)
			(xy 358.143048 -282.863036) (xy 358.156964 -282.914569) (xy 358.177422 -283.019342) (xy 358.189357 -283.125425)
			(xy 358.191562 -283.178758) (xy 358.191562 -283.181044) (xy 358.191816 -283.201364) (xy 358.191816 -283.229812)
			(xy 358.191816 -283.24302) (xy 358.191736 -283.245873) (xy 361.239817 -283.245873) (xy 361.239817 -283.193939)
			(xy 361.247942 -283.142644) (xy 361.26399 -283.093251) (xy 361.287568 -283.046977) (xy 361.318094 -283.004961)
			(xy 361.354817 -282.968238) (xy 361.396833 -282.937712) (xy 361.443107 -282.914134) (xy 361.4925 -282.898086)
			(xy 361.543795 -282.889961) (xy 361.595729 -282.889961) (xy 361.647024 -282.898086) (xy 361.696417 -282.914134)
			(xy 361.742691 -282.937712) (xy 361.784707 -282.968238) (xy 361.82143 -283.004961) (xy 361.851956 -283.046977)
			(xy 361.875534 -283.093251) (xy 361.891582 -283.142644) (xy 361.899707 -283.193939) (xy 361.900216 -283.219906)
			(xy 361.899707 -283.245873) (xy 364.059471 -283.245873) (xy 364.059471 -283.193939) (xy 364.067596 -283.142644)
			(xy 364.083644 -283.093251) (xy 364.107222 -283.046977) (xy 364.137748 -283.004961) (xy 364.174471 -282.968238)
			(xy 364.216487 -282.937712) (xy 364.262761 -282.914134) (xy 364.312154 -282.898086) (xy 364.363449 -282.889961)
			(xy 364.415383 -282.889961) (xy 364.466678 -282.898086) (xy 364.516071 -282.914134) (xy 364.562345 -282.937712)
			(xy 364.604361 -282.968238) (xy 364.641084 -283.004961) (xy 364.67161 -283.046977) (xy 364.695188 -283.093251)
			(xy 364.711236 -283.142644) (xy 364.719361 -283.193939) (xy 364.71987 -283.219906) (xy 364.719361 -283.245873)
			(xy 365.939071 -283.245873) (xy 365.939071 -283.193939) (xy 365.947196 -283.142644) (xy 365.963244 -283.093251)
			(xy 365.986822 -283.046977) (xy 366.017348 -283.004961) (xy 366.054071 -282.968238) (xy 366.096087 -282.937712)
			(xy 366.142361 -282.914134) (xy 366.191754 -282.898086) (xy 366.243049 -282.889961) (xy 366.294983 -282.889961)
			(xy 366.346278 -282.898086) (xy 366.395671 -282.914134) (xy 366.441945 -282.937712) (xy 366.483961 -282.968238)
			(xy 366.520684 -283.004961) (xy 366.55121 -283.046977) (xy 366.574788 -283.093251) (xy 366.590836 -283.142644)
			(xy 366.598961 -283.193939) (xy 366.59947 -283.219906) (xy 366.598961 -283.245873) (xy 366.590836 -283.297168)
			(xy 366.574788 -283.346561) (xy 366.55121 -283.392835) (xy 366.520684 -283.434851) (xy 366.483961 -283.471574)
			(xy 366.441945 -283.5021) (xy 366.395671 -283.525678) (xy 366.346278 -283.541726) (xy 366.294983 -283.549851)
			(xy 366.243049 -283.549851) (xy 366.191754 -283.541726) (xy 366.142361 -283.525678) (xy 366.096087 -283.5021)
			(xy 366.054071 -283.471574) (xy 366.017348 -283.434851) (xy 365.986822 -283.392835) (xy 365.963244 -283.346561)
			(xy 365.947196 -283.297168) (xy 365.939071 -283.245873) (xy 364.719361 -283.245873) (xy 364.711236 -283.297168)
			(xy 364.695188 -283.346561) (xy 364.67161 -283.392835) (xy 364.641084 -283.434851) (xy 364.604361 -283.471574)
			(xy 364.562345 -283.5021) (xy 364.516071 -283.525678) (xy 364.466678 -283.541726) (xy 364.415383 -283.549851)
			(xy 364.363449 -283.549851) (xy 364.312154 -283.541726) (xy 364.262761 -283.525678) (xy 364.216487 -283.5021)
			(xy 364.174471 -283.471574) (xy 364.137748 -283.434851) (xy 364.107222 -283.392835) (xy 364.083644 -283.346561)
			(xy 364.067596 -283.297168) (xy 364.059471 -283.245873) (xy 361.899707 -283.245873) (xy 361.891582 -283.297168)
			(xy 361.875534 -283.346561) (xy 361.851956 -283.392835) (xy 361.82143 -283.434851) (xy 361.784707 -283.471574)
			(xy 361.742691 -283.5021) (xy 361.696417 -283.525678) (xy 361.647024 -283.541726) (xy 361.595729 -283.549851)
			(xy 361.543795 -283.549851) (xy 361.4925 -283.541726) (xy 361.443107 -283.525678) (xy 361.396833 -283.5021)
			(xy 361.354817 -283.471574) (xy 361.318094 -283.434851) (xy 361.287568 -283.392835) (xy 361.26399 -283.346561)
			(xy 361.247942 -283.297168) (xy 361.239817 -283.245873) (xy 358.191736 -283.245873) (xy 358.190226 -283.299913)
			(xy 358.17845 -283.413126) (xy 358.156969 -283.524904) (xy 358.142032 -283.579824) (xy 358.139262 -283.593351)
			(xy 358.140257 -283.620934) (xy 358.148607 -283.647242) (xy 358.163702 -283.670349) (xy 358.184438 -283.688566)
			(xy 358.209297 -283.700559) (xy 358.236461 -283.705451) (xy 358.250236 -283.704538) (xy 358.280462 -283.703268)
			(xy 358.306432 -283.703748) (xy 358.357732 -283.711868) (xy 358.40713 -283.727913) (xy 358.45341 -283.751489)
			(xy 358.495432 -283.782015) (xy 358.53216 -283.818739) (xy 358.562691 -283.860758) (xy 358.586272 -283.907035)
			(xy 358.602323 -283.956431) (xy 358.610449 -284.007731) (xy 358.610449 -284.059669) (xy 358.602323 -284.110969)
			(xy 358.586272 -284.160365) (xy 358.562691 -284.206642) (xy 358.53216 -284.248661) (xy 358.495432 -284.285385)
			(xy 358.45341 -284.315911) (xy 358.40713 -284.339487) (xy 358.357732 -284.355532) (xy 358.306432 -284.363652)
			(xy 358.280462 -284.364176) (xy 358.251735 -284.363562) (xy 358.195145 -284.353628) (xy 358.141129 -284.33405)
			(xy 358.091316 -284.305419) (xy 358.06888 -284.287468) (xy 358.05745 -284.27877) (xy 358.031038 -284.267518)
			(xy 358.002539 -284.264059) (xy 357.974202 -284.268665) (xy 357.948266 -284.280973) (xy 357.926778 -284.300012)
			(xy 357.911435 -284.324278) (xy 357.90345 -284.351854) (xy 357.903018 -284.366208) (xy 357.903018 -284.543246)
			(xy 357.633778 -284.812486) (xy 357.633778 -284.873505) (xy 361.239817 -284.873505) (xy 361.239817 -284.821571)
			(xy 361.247942 -284.770276) (xy 361.26399 -284.720883) (xy 361.287568 -284.674609) (xy 361.318094 -284.632593)
			(xy 361.354817 -284.59587) (xy 361.396833 -284.565344) (xy 361.443107 -284.541766) (xy 361.4925 -284.525718)
			(xy 361.543795 -284.517593) (xy 361.595729 -284.517593) (xy 361.647024 -284.525718) (xy 361.696417 -284.541766)
			(xy 361.742691 -284.565344) (xy 361.784707 -284.59587) (xy 361.82143 -284.632593) (xy 361.851956 -284.674609)
			(xy 361.875534 -284.720883) (xy 361.891582 -284.770276) (xy 361.899707 -284.821571) (xy 361.900216 -284.847538)
			(xy 361.899707 -284.873505) (xy 364.059471 -284.873505) (xy 364.059471 -284.821571) (xy 364.067596 -284.770276)
			(xy 364.083644 -284.720883) (xy 364.107222 -284.674609) (xy 364.137748 -284.632593) (xy 364.174471 -284.59587)
			(xy 364.216487 -284.565344) (xy 364.262761 -284.541766) (xy 364.312154 -284.525718) (xy 364.363449 -284.517593)
			(xy 364.415383 -284.517593) (xy 364.466678 -284.525718) (xy 364.516071 -284.541766) (xy 364.562345 -284.565344)
			(xy 364.604361 -284.59587) (xy 364.641084 -284.632593) (xy 364.67161 -284.674609) (xy 364.695188 -284.720883)
			(xy 364.711236 -284.770276) (xy 364.719361 -284.821571) (xy 364.71987 -284.847538) (xy 364.719361 -284.873505)
			(xy 365.939071 -284.873505) (xy 365.939071 -284.821571) (xy 365.947196 -284.770276) (xy 365.963244 -284.720883)
			(xy 365.986822 -284.674609) (xy 366.017348 -284.632593) (xy 366.054071 -284.59587) (xy 366.096087 -284.565344)
			(xy 366.142361 -284.541766) (xy 366.191754 -284.525718) (xy 366.243049 -284.517593) (xy 366.294983 -284.517593)
			(xy 366.346278 -284.525718) (xy 366.395671 -284.541766) (xy 366.441945 -284.565344) (xy 366.483961 -284.59587)
			(xy 366.520684 -284.632593) (xy 366.55121 -284.674609) (xy 366.574788 -284.720883) (xy 366.590836 -284.770276)
			(xy 366.598961 -284.821571) (xy 366.59947 -284.847538) (xy 366.598961 -284.873505) (xy 366.590836 -284.9248)
			(xy 366.574788 -284.974193) (xy 366.55121 -285.020467) (xy 366.520684 -285.062483) (xy 366.483961 -285.099206)
			(xy 366.441945 -285.129732) (xy 366.395671 -285.15331) (xy 366.346278 -285.169358) (xy 366.294983 -285.177483)
			(xy 366.243049 -285.177483) (xy 366.191754 -285.169358) (xy 366.142361 -285.15331) (xy 366.096087 -285.129732)
			(xy 366.054071 -285.099206) (xy 366.017348 -285.062483) (xy 365.986822 -285.020467) (xy 365.963244 -284.974193)
			(xy 365.947196 -284.9248) (xy 365.939071 -284.873505) (xy 364.719361 -284.873505) (xy 364.711236 -284.9248)
			(xy 364.695188 -284.974193) (xy 364.67161 -285.020467) (xy 364.641084 -285.062483) (xy 364.604361 -285.099206)
			(xy 364.562345 -285.129732) (xy 364.516071 -285.15331) (xy 364.466678 -285.169358) (xy 364.415383 -285.177483)
			(xy 364.363449 -285.177483) (xy 364.312154 -285.169358) (xy 364.262761 -285.15331) (xy 364.216487 -285.129732)
			(xy 364.174471 -285.099206) (xy 364.137748 -285.062483) (xy 364.107222 -285.020467) (xy 364.083644 -284.974193)
			(xy 364.067596 -284.9248) (xy 364.059471 -284.873505) (xy 361.899707 -284.873505) (xy 361.891582 -284.9248)
			(xy 361.875534 -284.974193) (xy 361.851956 -285.020467) (xy 361.82143 -285.062483) (xy 361.784707 -285.099206)
			(xy 361.742691 -285.129732) (xy 361.696417 -285.15331) (xy 361.647024 -285.169358) (xy 361.595729 -285.177483)
			(xy 361.543795 -285.177483) (xy 361.4925 -285.169358) (xy 361.443107 -285.15331) (xy 361.396833 -285.129732)
			(xy 361.354817 -285.099206) (xy 361.318094 -285.062483) (xy 361.287568 -285.020467) (xy 361.26399 -284.974193)
			(xy 361.247942 -284.9248) (xy 361.239817 -284.873505) (xy 357.633778 -284.873505) (xy 357.633778 -285.185612)
			(xy 357.63708 -285.194248) (xy 357.653536 -285.239018) (xy 357.680732 -285.330453) (xy 357.701265 -285.423611)
			(xy 357.71503 -285.518007) (xy 357.721954 -285.613149) (xy 357.722424 -285.660846) (xy 357.722424 -285.675578)
			(xy 357.722267 -285.687321) (xy 357.950517 -285.687321) (xy 357.950517 -285.635387) (xy 357.958642 -285.584092)
			(xy 357.97469 -285.534699) (xy 357.998268 -285.488425) (xy 358.028794 -285.446409) (xy 358.065517 -285.409686)
			(xy 358.107533 -285.37916) (xy 358.153807 -285.355582) (xy 358.2032 -285.339534) (xy 358.254495 -285.331409)
			(xy 358.306429 -285.331409) (xy 358.357724 -285.339534) (xy 358.407117 -285.355582) (xy 358.453391 -285.37916)
			(xy 358.495407 -285.409686) (xy 358.53213 -285.446409) (xy 358.562656 -285.488425) (xy 358.586234 -285.534699)
			(xy 358.602282 -285.584092) (xy 358.610407 -285.635387) (xy 358.610916 -285.661354) (xy 358.610407 -285.687321)
			(xy 358.602282 -285.738616) (xy 358.586234 -285.788009) (xy 358.562656 -285.834283) (xy 358.53213 -285.876299)
			(xy 358.495407 -285.913022) (xy 358.453391 -285.943548) (xy 358.407117 -285.967126) (xy 358.357724 -285.983174)
			(xy 358.306429 -285.991299) (xy 358.254495 -285.991299) (xy 358.2032 -285.983174) (xy 358.153807 -285.967126)
			(xy 358.107533 -285.943548) (xy 358.065517 -285.913022) (xy 358.028794 -285.876299) (xy 357.998268 -285.834283)
			(xy 357.97469 -285.788009) (xy 357.958642 -285.738616) (xy 357.950517 -285.687321) (xy 357.722267 -285.687321)
			(xy 357.72217 -285.694628) (xy 357.72217 -285.694882) (xy 357.721916 -285.700978) (xy 357.719719 -285.755704)
			(xy 357.70738 -285.864541) (xy 357.686068 -285.971983) (xy 357.65593 -286.07729) (xy 357.63708 -286.128714)
			(xy 357.633778 -286.137604) (xy 357.633778 -286.501391) (xy 361.239817 -286.501391) (xy 361.239817 -286.449457)
			(xy 361.247942 -286.398162) (xy 361.26399 -286.348769) (xy 361.287568 -286.302495) (xy 361.318094 -286.260479)
			(xy 361.354817 -286.223756) (xy 361.396833 -286.19323) (xy 361.443107 -286.169652) (xy 361.4925 -286.153604)
			(xy 361.543795 -286.145479) (xy 361.595729 -286.145479) (xy 361.647024 -286.153604) (xy 361.696417 -286.169652)
			(xy 361.742691 -286.19323) (xy 361.784707 -286.223756) (xy 361.82143 -286.260479) (xy 361.851956 -286.302495)
			(xy 361.875534 -286.348769) (xy 361.891582 -286.398162) (xy 361.899707 -286.449457) (xy 361.900216 -286.475424)
			(xy 361.899707 -286.501391) (xy 364.059471 -286.501391) (xy 364.059471 -286.449457) (xy 364.067596 -286.398162)
			(xy 364.083644 -286.348769) (xy 364.107222 -286.302495) (xy 364.137748 -286.260479) (xy 364.174471 -286.223756)
			(xy 364.216487 -286.19323) (xy 364.262761 -286.169652) (xy 364.312154 -286.153604) (xy 364.363449 -286.145479)
			(xy 364.415383 -286.145479) (xy 364.466678 -286.153604) (xy 364.516071 -286.169652) (xy 364.562345 -286.19323)
			(xy 364.604361 -286.223756) (xy 364.641084 -286.260479) (xy 364.67161 -286.302495) (xy 364.695188 -286.348769)
			(xy 364.711236 -286.398162) (xy 364.719361 -286.449457) (xy 364.71987 -286.475424) (xy 364.719361 -286.501391)
			(xy 364.711236 -286.552686) (xy 364.695188 -286.602079) (xy 364.67161 -286.648353) (xy 364.641084 -286.690369)
			(xy 364.604361 -286.727092) (xy 364.562345 -286.757618) (xy 364.516071 -286.781196) (xy 364.466678 -286.797244)
			(xy 364.415383 -286.805369) (xy 364.363449 -286.805369) (xy 364.312154 -286.797244) (xy 364.262761 -286.781196)
			(xy 364.216487 -286.757618) (xy 364.174471 -286.727092) (xy 364.137748 -286.690369) (xy 364.107222 -286.648353)
			(xy 364.083644 -286.602079) (xy 364.067596 -286.552686) (xy 364.059471 -286.501391) (xy 361.899707 -286.501391)
			(xy 361.891582 -286.552686) (xy 361.875534 -286.602079) (xy 361.851956 -286.648353) (xy 361.82143 -286.690369)
			(xy 361.784707 -286.727092) (xy 361.742691 -286.757618) (xy 361.696417 -286.781196) (xy 361.647024 -286.797244)
			(xy 361.595729 -286.805369) (xy 361.543795 -286.805369) (xy 361.4925 -286.797244) (xy 361.443107 -286.781196)
			(xy 361.396833 -286.757618) (xy 361.354817 -286.727092) (xy 361.318094 -286.690369) (xy 361.287568 -286.648353)
			(xy 361.26399 -286.602079) (xy 361.247942 -286.552686) (xy 361.239817 -286.501391) (xy 357.633778 -286.501391)
			(xy 357.633778 -286.814006) (xy 357.63708 -286.822642) (xy 357.6553 -286.872408) (xy 357.68466 -286.974248)
			(xy 357.705766 -287.078113) (xy 357.718484 -287.183335) (xy 357.72273 -287.289237) (xy 357.721687 -287.315207)
			(xy 357.950517 -287.315207) (xy 357.950517 -287.263273) (xy 357.958642 -287.211978) (xy 357.97469 -287.162585)
			(xy 357.998268 -287.116311) (xy 358.028794 -287.074295) (xy 358.065517 -287.037572) (xy 358.107533 -287.007046)
			(xy 358.153807 -286.983468) (xy 358.2032 -286.96742) (xy 358.254495 -286.959295) (xy 358.306429 -286.959295)
			(xy 358.357724 -286.96742) (xy 358.407117 -286.983468) (xy 358.453391 -287.007046) (xy 358.495407 -287.037572)
			(xy 358.53213 -287.074295) (xy 358.562656 -287.116311) (xy 358.586234 -287.162585) (xy 358.602282 -287.211978)
			(xy 358.610407 -287.263273) (xy 358.610916 -287.28924) (xy 358.610407 -287.315207) (xy 358.602282 -287.366502)
			(xy 358.586234 -287.415895) (xy 358.562656 -287.462169) (xy 358.53213 -287.504185) (xy 358.495407 -287.540908)
			(xy 358.453391 -287.571434) (xy 358.407117 -287.595012) (xy 358.357724 -287.61106) (xy 358.306429 -287.619185)
			(xy 358.254495 -287.619185) (xy 358.2032 -287.61106) (xy 358.153807 -287.595012) (xy 358.107533 -287.571434)
			(xy 358.065517 -287.540908) (xy 358.028794 -287.504185) (xy 357.998268 -287.462169) (xy 357.97469 -287.415895)
			(xy 357.958642 -287.366502) (xy 357.950517 -287.315207) (xy 357.721687 -287.315207) (xy 357.718478 -287.39514)
			(xy 357.705754 -287.500361) (xy 357.684642 -287.604225) (xy 357.655276 -287.706063) (xy 357.63708 -287.755838)
			(xy 357.633778 -287.764474) (xy 357.633778 -288.129023) (xy 361.239817 -288.129023) (xy 361.239817 -288.077089)
			(xy 361.247942 -288.025794) (xy 361.26399 -287.976401) (xy 361.287568 -287.930127) (xy 361.318094 -287.888111)
			(xy 361.354817 -287.851388) (xy 361.396833 -287.820862) (xy 361.443107 -287.797284) (xy 361.4925 -287.781236)
			(xy 361.543795 -287.773111) (xy 361.595729 -287.773111) (xy 361.647024 -287.781236) (xy 361.696417 -287.797284)
			(xy 361.742691 -287.820862) (xy 361.784707 -287.851388) (xy 361.82143 -287.888111) (xy 361.851956 -287.930127)
			(xy 361.875534 -287.976401) (xy 361.891582 -288.025794) (xy 361.899707 -288.077089) (xy 361.900216 -288.103056)
			(xy 361.899707 -288.129023) (xy 364.059471 -288.129023) (xy 364.059471 -288.077089) (xy 364.067596 -288.025794)
			(xy 364.083644 -287.976401) (xy 364.107222 -287.930127) (xy 364.137748 -287.888111) (xy 364.174471 -287.851388)
			(xy 364.216487 -287.820862) (xy 364.262761 -287.797284) (xy 364.312154 -287.781236) (xy 364.363449 -287.773111)
			(xy 364.415383 -287.773111) (xy 364.466678 -287.781236) (xy 364.516071 -287.797284) (xy 364.562345 -287.820862)
			(xy 364.604361 -287.851388) (xy 364.641084 -287.888111) (xy 364.67161 -287.930127) (xy 364.695188 -287.976401)
			(xy 364.711236 -288.025794) (xy 364.719361 -288.077089) (xy 364.71987 -288.103056) (xy 364.719361 -288.129023)
			(xy 364.711236 -288.180318) (xy 364.695188 -288.229711) (xy 364.67161 -288.275985) (xy 364.641084 -288.318001)
			(xy 364.604361 -288.354724) (xy 364.562345 -288.38525) (xy 364.516071 -288.408828) (xy 364.466678 -288.424876)
			(xy 364.415383 -288.433001) (xy 364.363449 -288.433001) (xy 364.312154 -288.424876) (xy 364.262761 -288.408828)
			(xy 364.216487 -288.38525) (xy 364.174471 -288.354724) (xy 364.137748 -288.318001) (xy 364.107222 -288.275985)
			(xy 364.083644 -288.229711) (xy 364.067596 -288.180318) (xy 364.059471 -288.129023) (xy 361.899707 -288.129023)
			(xy 361.891582 -288.180318) (xy 361.875534 -288.229711) (xy 361.851956 -288.275985) (xy 361.82143 -288.318001)
			(xy 361.784707 -288.354724) (xy 361.742691 -288.38525) (xy 361.696417 -288.408828) (xy 361.647024 -288.424876)
			(xy 361.595729 -288.433001) (xy 361.543795 -288.433001) (xy 361.4925 -288.424876) (xy 361.443107 -288.408828)
			(xy 361.396833 -288.38525) (xy 361.354817 -288.354724) (xy 361.318094 -288.318001) (xy 361.287568 -288.275985)
			(xy 361.26399 -288.229711) (xy 361.247942 -288.180318) (xy 361.239817 -288.129023) (xy 357.633778 -288.129023)
			(xy 357.633778 -288.436558) (xy 357.637334 -288.445702) (xy 357.65706 -288.496194) (xy 357.689224 -288.599725)
			(xy 357.712872 -288.705527) (xy 357.7209 -288.759138) (xy 357.724247 -288.785043) (xy 357.727804 -288.837159)
			(xy 357.728012 -288.863278) (xy 357.72725 -288.8996) (xy 357.726996 -288.905188) (xy 357.7209 -289.014916)
			(xy 357.72066 -289.019293) (xy 357.950771 -289.019293) (xy 357.950771 -288.967359) (xy 357.958896 -288.916064)
			(xy 357.974944 -288.866671) (xy 357.998522 -288.820397) (xy 358.029048 -288.778381) (xy 358.065771 -288.741658)
			(xy 358.107787 -288.711132) (xy 358.154061 -288.687554) (xy 358.203454 -288.671506) (xy 358.254749 -288.663381)
			(xy 358.306683 -288.663381) (xy 358.357978 -288.671506) (xy 358.407371 -288.687554) (xy 358.453645 -288.711132)
			(xy 358.495661 -288.741658) (xy 358.532384 -288.778381) (xy 358.56291 -288.820397) (xy 358.586488 -288.866671)
			(xy 358.602536 -288.916064) (xy 358.606817 -288.943093) (xy 367.348771 -288.943093) (xy 367.348771 -288.891159)
			(xy 367.356896 -288.839864) (xy 367.372944 -288.790471) (xy 367.396522 -288.744197) (xy 367.427048 -288.702181)
			(xy 367.463771 -288.665458) (xy 367.505787 -288.634932) (xy 367.552061 -288.611354) (xy 367.601454 -288.595306)
			(xy 367.652749 -288.587181) (xy 367.704683 -288.587181) (xy 367.755978 -288.595306) (xy 367.805371 -288.611354)
			(xy 367.851645 -288.634932) (xy 367.893661 -288.665458) (xy 367.930384 -288.702181) (xy 367.96091 -288.744197)
			(xy 367.984488 -288.790471) (xy 368.000536 -288.839864) (xy 368.008661 -288.891159) (xy 368.00917 -288.917126)
			(xy 368.008661 -288.943093) (xy 368.000536 -288.994388) (xy 367.984488 -289.043781) (xy 367.96091 -289.090055)
			(xy 367.930384 -289.132071) (xy 367.893661 -289.168794) (xy 367.851645 -289.19932) (xy 367.805371 -289.222898)
			(xy 367.755978 -289.238946) (xy 367.704683 -289.247071) (xy 367.652749 -289.247071) (xy 367.601454 -289.238946)
			(xy 367.552061 -289.222898) (xy 367.505787 -289.19932) (xy 367.463771 -289.168794) (xy 367.427048 -289.132071)
			(xy 367.396522 -289.090055) (xy 367.372944 -289.043781) (xy 367.356896 -288.994388) (xy 367.348771 -288.943093)
			(xy 358.606817 -288.943093) (xy 358.610661 -288.967359) (xy 358.61117 -288.993326) (xy 358.610661 -289.019293)
			(xy 358.602536 -289.070588) (xy 358.586488 -289.119981) (xy 358.56291 -289.166255) (xy 358.532384 -289.208271)
			(xy 358.495661 -289.244994) (xy 358.453645 -289.27552) (xy 358.407371 -289.299098) (xy 358.357978 -289.315146)
			(xy 358.306683 -289.323271) (xy 358.254749 -289.323271) (xy 358.203454 -289.315146) (xy 358.154061 -289.299098)
			(xy 358.107787 -289.27552) (xy 358.065771 -289.244994) (xy 358.029048 -289.208271) (xy 357.998522 -289.166255)
			(xy 357.974944 -289.119981) (xy 357.958896 -289.070588) (xy 357.950771 -289.019293) (xy 357.72066 -289.019293)
			(xy 357.712264 -289.172142) (xy 357.710017 -289.206414) (xy 357.700093 -289.274379) (xy 357.684047 -289.341164)
			(xy 357.673402 -289.373818) (xy 357.672386 -289.376866) (xy 357.672386 -289.37712) (xy 357.664942 -289.398434)
			(xy 357.64881 -289.440607) (xy 357.640128 -289.461448) (xy 357.633778 -289.476688) (xy 357.633778 -289.833109)
			(xy 366.878617 -289.833109) (xy 366.878617 -289.781175) (xy 366.886742 -289.72988) (xy 366.90279 -289.680487)
			(xy 366.926368 -289.634213) (xy 366.956894 -289.592197) (xy 366.993617 -289.555474) (xy 367.035633 -289.524948)
			(xy 367.081907 -289.50137) (xy 367.1313 -289.485322) (xy 367.182595 -289.477197) (xy 367.234529 -289.477197)
			(xy 367.285824 -289.485322) (xy 367.335217 -289.50137) (xy 367.381491 -289.524948) (xy 367.423507 -289.555474)
			(xy 367.46023 -289.592197) (xy 367.490756 -289.634213) (xy 367.514334 -289.680487) (xy 367.530382 -289.72988)
			(xy 367.538507 -289.781175) (xy 367.539016 -289.807142) (xy 367.538507 -289.833109) (xy 367.530382 -289.884404)
			(xy 367.514334 -289.933797) (xy 367.490756 -289.980071) (xy 367.46023 -290.022087) (xy 367.423507 -290.05881)
			(xy 367.381491 -290.089336) (xy 367.335217 -290.112914) (xy 367.285824 -290.128962) (xy 367.234529 -290.137087)
			(xy 367.182595 -290.137087) (xy 367.1313 -290.128962) (xy 367.081907 -290.112914) (xy 367.035633 -290.089336)
			(xy 366.993617 -290.05881) (xy 366.956894 -290.022087) (xy 366.926368 -289.980071) (xy 366.90279 -289.933797)
			(xy 366.886742 -289.884404) (xy 366.878617 -289.833109) (xy 357.633778 -289.833109) (xy 357.633778 -292.572694)
			(xy 357.669084 -292.57879) (xy 357.69576 -292.583453) (xy 357.747534 -292.599332) (xy 357.796536 -292.622383)
			(xy 357.84178 -292.652142) (xy 357.862378 -292.669722) (xy 357.873542 -292.678405) (xy 357.899402 -292.689831)
			(xy 357.927402 -292.69374) (xy 357.955402 -292.689831) (xy 357.981262 -292.678405) (xy 357.992426 -292.669722)
			(xy 358.013444 -292.651823) (xy 358.059668 -292.62164) (xy 358.109758 -292.598434) (xy 358.162671 -292.582689)
			(xy 358.217299 -292.574733) (xy 358.244902 -292.574218) (xy 358.272151 -292.574704) (xy 358.326095 -292.582461)
			(xy 358.378386 -292.597815) (xy 358.427959 -292.620454) (xy 358.473806 -292.649919) (xy 358.514994 -292.685608)
			(xy 358.550682 -292.726795) (xy 358.580146 -292.772642) (xy 358.602786 -292.822216) (xy 358.61814 -292.874507)
			(xy 358.625896 -292.928451) (xy 358.625896 -292.982949) (xy 363.686604 -292.982949) (xy 363.686604 -292.928451)
			(xy 363.69436 -292.874507) (xy 363.709714 -292.822216) (xy 363.732354 -292.772642) (xy 363.761818 -292.726795)
			(xy 363.797506 -292.685608) (xy 363.838694 -292.649919) (xy 363.884541 -292.620454) (xy 363.934114 -292.597815)
			(xy 363.986405 -292.582461) (xy 364.040349 -292.574704) (xy 364.067598 -292.574218) (xy 364.094968 -292.574681)
			(xy 364.149148 -292.582499) (xy 364.201651 -292.597988) (xy 364.251398 -292.620831) (xy 364.297365 -292.650556)
			(xy 364.318296 -292.668198) (xy 364.329624 -292.677434) (xy 364.356181 -292.68961) (xy 364.385098 -292.693783)
			(xy 364.414015 -292.68961) (xy 364.440572 -292.677434) (xy 364.4519 -292.668198) (xy 364.472821 -292.650545)
			(xy 364.518797 -292.620835) (xy 364.568547 -292.598002) (xy 364.62105 -292.582514) (xy 364.675228 -292.57469)
			(xy 364.702598 -292.574218) (xy 364.729853 -292.574629) (xy 364.783808 -292.582386) (xy 364.836109 -292.597743)
			(xy 364.885693 -292.620387) (xy 364.93155 -292.649857) (xy 364.972746 -292.685553) (xy 365.008442 -292.726749)
			(xy 365.037912 -292.772605) (xy 365.060556 -292.822189) (xy 365.075914 -292.87449) (xy 365.083671 -292.928445)
			(xy 365.083671 -292.982955) (xy 365.075914 -293.03691) (xy 365.060556 -293.089211) (xy 365.037912 -293.138795)
			(xy 365.008442 -293.184651) (xy 364.972746 -293.225847) (xy 364.93155 -293.261543) (xy 364.885693 -293.291013)
			(xy 364.836109 -293.313657) (xy 364.783808 -293.329014) (xy 364.729853 -293.336771) (xy 364.702598 -293.337234)
			(xy 364.675227 -293.336785) (xy 364.621046 -293.328966) (xy 364.568543 -293.313473) (xy 364.518796 -293.290627)
			(xy 364.47283 -293.260898) (xy 364.4519 -293.243254) (xy 364.440572 -293.234018) (xy 364.414015 -293.221842)
			(xy 364.385098 -293.217669) (xy 364.356181 -293.221842) (xy 364.329624 -293.234018) (xy 364.318296 -293.243254)
			(xy 364.29737 -293.260901) (xy 364.251397 -293.290613) (xy 364.201647 -293.313449) (xy 364.149145 -293.328938)
			(xy 364.094968 -293.336762) (xy 364.067598 -293.337234) (xy 364.040349 -293.336696) (xy 363.986405 -293.328939)
			(xy 363.934114 -293.313585) (xy 363.884541 -293.290946) (xy 363.838694 -293.261481) (xy 363.797506 -293.225792)
			(xy 363.761818 -293.184605) (xy 363.732354 -293.138758) (xy 363.709714 -293.089184) (xy 363.69436 -293.036893)
			(xy 363.686604 -292.982949) (xy 358.625896 -292.982949) (xy 358.61814 -293.036893) (xy 358.602786 -293.089184)
			(xy 358.580146 -293.138758) (xy 358.550682 -293.184605) (xy 358.514994 -293.225792) (xy 358.473806 -293.261481)
			(xy 358.427959 -293.290946) (xy 358.378386 -293.313585) (xy 358.326095 -293.328939) (xy 358.272151 -293.336696)
			(xy 358.244902 -293.337234) (xy 358.217298 -293.336745) (xy 358.162668 -293.328787) (xy 358.109755 -293.313035)
			(xy 358.059666 -293.289821) (xy 358.013447 -293.259627) (xy 357.992426 -293.24173) (xy 357.981262 -293.233047)
			(xy 357.955402 -293.221621) (xy 357.927402 -293.217712) (xy 357.899402 -293.221621) (xy 357.873542 -293.233047)
			(xy 357.862378 -293.24173) (xy 357.842416 -293.258749) (xy 357.798687 -293.287722) (xy 357.751401 -293.31043)
			(xy 357.701449 -293.326444) (xy 357.675688 -293.331392) (xy 357.633778 -293.338758) (xy 357.633778 -294.655494)
			(xy 357.675688 -294.66286) (xy 357.704788 -294.668478) (xy 357.760909 -294.687525) (xy 357.813403 -294.715033)
			(xy 357.861003 -294.750339) (xy 357.88219 -294.771064) (xy 357.893834 -294.781543) (xy 357.921864 -294.795489)
			(xy 357.952802 -294.800289) (xy 357.98374 -294.795489) (xy 358.01177 -294.781543) (xy 358.023414 -294.771064)
			(xy 358.045095 -294.749848) (xy 358.09393 -294.713869) (xy 358.147843 -294.68607) (xy 358.205474 -294.667149)
			(xy 358.265373 -294.657585) (xy 358.295702 -294.657018) (xy 358.322951 -294.657504) (xy 358.376895 -294.665261)
			(xy 358.429186 -294.680615) (xy 358.478759 -294.703254) (xy 358.524606 -294.732719) (xy 358.565794 -294.768408)
			(xy 358.601482 -294.809595) (xy 358.630946 -294.855442) (xy 358.653586 -294.905016) (xy 358.66894 -294.957307)
			(xy 358.676696 -295.011251) (xy 358.676696 -295.065749) (xy 363.572304 -295.065749) (xy 363.572304 -295.011251)
			(xy 363.58006 -294.957307) (xy 363.595414 -294.905016) (xy 363.618054 -294.855442) (xy 363.647518 -294.809595)
			(xy 363.683206 -294.768408) (xy 363.724394 -294.732719) (xy 363.770241 -294.703254) (xy 363.819814 -294.680615)
			(xy 363.872105 -294.665261) (xy 363.926049 -294.657504) (xy 363.953298 -294.657018) (xy 363.980668 -294.657481)
			(xy 364.034848 -294.665299) (xy 364.087351 -294.680788) (xy 364.137098 -294.703631) (xy 364.183065 -294.733356)
			(xy 364.203996 -294.750998) (xy 364.215324 -294.760234) (xy 364.241881 -294.77241) (xy 364.270798 -294.776583)
			(xy 364.299715 -294.77241) (xy 364.326272 -294.760234) (xy 364.3376 -294.750998) (xy 364.358521 -294.733345)
			(xy 364.404497 -294.703635) (xy 364.454247 -294.680802) (xy 364.50675 -294.665314) (xy 364.560928 -294.65749)
			(xy 364.588298 -294.657018) (xy 364.615553 -294.657429) (xy 364.669508 -294.665186) (xy 364.721809 -294.680543)
			(xy 364.771393 -294.703187) (xy 364.81725 -294.732657) (xy 364.858446 -294.768353) (xy 364.894142 -294.809549)
			(xy 364.923612 -294.855405) (xy 364.946256 -294.904989) (xy 364.961614 -294.95729) (xy 364.969371 -295.011245)
			(xy 364.969371 -295.038526) (xy 370.181376 -295.038526) (xy 370.185447 -294.982904) (xy 370.197573 -294.928467)
			(xy 370.217496 -294.876376) (xy 370.244792 -294.827741) (xy 370.278878 -294.783598) (xy 370.319027 -294.744889)
			(xy 370.364385 -294.712438) (xy 370.413985 -294.686937) (xy 370.466769 -294.66893) (xy 370.521612 -294.6588)
			(xy 370.577346 -294.656763) (xy 370.632783 -294.662863) (xy 370.68674 -294.676969) (xy 370.738069 -294.698781)
			(xy 370.785675 -294.727835) (xy 370.828543 -294.76351) (xy 370.86576 -294.805047) (xy 370.896533 -294.85156)
			(xy 370.920205 -294.902057) (xy 370.936273 -294.955464) (xy 370.944393 -295.01064) (xy 370.944902 -295.038526)
			(xy 370.944393 -295.066412) (xy 370.936273 -295.121588) (xy 370.920205 -295.174995) (xy 370.896533 -295.225492)
			(xy 370.86576 -295.272005) (xy 370.828543 -295.313542) (xy 370.785675 -295.349217) (xy 370.738069 -295.378271)
			(xy 370.68674 -295.400083) (xy 370.632783 -295.414189) (xy 370.577346 -295.420289) (xy 370.521612 -295.418252)
			(xy 370.466769 -295.408122) (xy 370.413985 -295.390115) (xy 370.364385 -295.364614) (xy 370.319027 -295.332163)
			(xy 370.278878 -295.293454) (xy 370.244792 -295.249311) (xy 370.217496 -295.200676) (xy 370.197573 -295.148585)
			(xy 370.185447 -295.094148) (xy 370.181376 -295.038526) (xy 364.969371 -295.038526) (xy 364.969371 -295.065755)
			(xy 364.961614 -295.11971) (xy 364.946256 -295.172011) (xy 364.923612 -295.221595) (xy 364.894142 -295.267451)
			(xy 364.858446 -295.308647) (xy 364.81725 -295.344343) (xy 364.771393 -295.373813) (xy 364.721809 -295.396457)
			(xy 364.669508 -295.411814) (xy 364.615553 -295.419571) (xy 364.588298 -295.420034) (xy 364.560927 -295.419585)
			(xy 364.506746 -295.411766) (xy 364.454243 -295.396273) (xy 364.404496 -295.373427) (xy 364.35853 -295.343698)
			(xy 364.3376 -295.326054) (xy 364.326272 -295.316818) (xy 364.299715 -295.304642) (xy 364.270798 -295.300469)
			(xy 364.241881 -295.304642) (xy 364.215324 -295.316818) (xy 364.203996 -295.326054) (xy 364.18307 -295.343701)
			(xy 364.137097 -295.373413) (xy 364.087347 -295.396249) (xy 364.034845 -295.411738) (xy 363.980668 -295.419562)
			(xy 363.953298 -295.420034) (xy 363.926049 -295.419496) (xy 363.872105 -295.411739) (xy 363.819814 -295.396385)
			(xy 363.770241 -295.373746) (xy 363.724394 -295.344281) (xy 363.683206 -295.308592) (xy 363.647518 -295.267405)
			(xy 363.618054 -295.221558) (xy 363.595414 -295.171984) (xy 363.58006 -295.119693) (xy 363.572304 -295.065749)
			(xy 358.676696 -295.065749) (xy 358.66894 -295.119693) (xy 358.653586 -295.171984) (xy 358.630946 -295.221558)
			(xy 358.601482 -295.267405) (xy 358.565794 -295.308592) (xy 358.524606 -295.344281) (xy 358.478759 -295.373746)
			(xy 358.429186 -295.396385) (xy 358.376895 -295.411739) (xy 358.322951 -295.419496) (xy 358.295702 -295.420034)
			(xy 358.265371 -295.419473) (xy 358.205467 -295.409919) (xy 358.14783 -295.391005) (xy 358.093914 -295.363206)
			(xy 358.045077 -295.327224) (xy 358.023414 -295.305988) (xy 358.01177 -295.295509) (xy 357.98374 -295.281563)
			(xy 357.952802 -295.276763) (xy 357.921864 -295.281563) (xy 357.893834 -295.295509) (xy 357.88219 -295.305988)
			(xy 357.860396 -295.327306) (xy 357.811293 -295.363433) (xy 357.757071 -295.391296) (xy 357.69911 -295.410186)
			(xy 357.669084 -295.415462) (xy 357.633778 -295.421558) (xy 357.633778 -296.628566) (xy 357.61041 -296.684954)
			(xy 357.605275 -296.698594) (xy 357.602187 -296.727565) (xy 357.6074 -296.756229) (xy 357.62049 -296.782257)
			(xy 357.640394 -296.803533) (xy 357.665493 -296.818327) (xy 357.679498 -296.822368) (xy 357.690674 -296.824654)
			(xy 357.717668 -296.830998) (xy 357.769602 -296.850433) (xy 357.818177 -296.877178) (xy 357.862372 -296.910668)
			(xy 357.88219 -296.930064) (xy 357.893834 -296.940543) (xy 357.921864 -296.954489) (xy 357.952802 -296.959289)
			(xy 357.98374 -296.954489) (xy 358.01177 -296.940543) (xy 358.023414 -296.930064) (xy 358.045095 -296.908848)
			(xy 358.09393 -296.872869) (xy 358.147843 -296.84507) (xy 358.205474 -296.826149) (xy 358.265373 -296.816585)
			(xy 358.295702 -296.816018) (xy 358.322951 -296.816504) (xy 358.376895 -296.824261) (xy 358.429186 -296.839615)
			(xy 358.478759 -296.862254) (xy 358.524606 -296.891719) (xy 358.565794 -296.927408) (xy 358.601482 -296.968595)
			(xy 358.630946 -297.014442) (xy 358.653586 -297.064016) (xy 358.66894 -297.116307) (xy 358.676696 -297.170251)
			(xy 358.676696 -297.224749) (xy 363.572304 -297.224749) (xy 363.572304 -297.170251) (xy 363.58006 -297.116307)
			(xy 363.595414 -297.064016) (xy 363.618054 -297.014442) (xy 363.647518 -296.968595) (xy 363.683206 -296.927408)
			(xy 363.724394 -296.891719) (xy 363.770241 -296.862254) (xy 363.819814 -296.839615) (xy 363.872105 -296.824261)
			(xy 363.926049 -296.816504) (xy 363.953298 -296.816018) (xy 363.980668 -296.816481) (xy 364.034848 -296.824299)
			(xy 364.087351 -296.839788) (xy 364.137098 -296.862631) (xy 364.183065 -296.892356) (xy 364.203996 -296.909998)
			(xy 364.215324 -296.919234) (xy 364.241881 -296.93141) (xy 364.270798 -296.935583) (xy 364.299715 -296.93141)
			(xy 364.326272 -296.919234) (xy 364.3376 -296.909998) (xy 364.358521 -296.892345) (xy 364.404497 -296.862635)
			(xy 364.454247 -296.839802) (xy 364.50675 -296.824314) (xy 364.560928 -296.81649) (xy 364.588298 -296.816018)
			(xy 364.615553 -296.816429) (xy 364.669508 -296.824186) (xy 364.721809 -296.839543) (xy 364.771393 -296.862187)
			(xy 364.81725 -296.891657) (xy 364.858446 -296.927353) (xy 364.894142 -296.968549) (xy 364.923612 -297.014405)
			(xy 364.946256 -297.063989) (xy 364.961614 -297.11629) (xy 364.969371 -297.170245) (xy 364.969371 -297.197526)
			(xy 370.181376 -297.197526) (xy 370.185447 -297.141904) (xy 370.197573 -297.087467) (xy 370.217496 -297.035376)
			(xy 370.244792 -296.986741) (xy 370.278878 -296.942598) (xy 370.319027 -296.903889) (xy 370.364385 -296.871438)
			(xy 370.413985 -296.845937) (xy 370.466769 -296.82793) (xy 370.521612 -296.8178) (xy 370.577346 -296.815763)
			(xy 370.632783 -296.821863) (xy 370.68674 -296.835969) (xy 370.738069 -296.857781) (xy 370.785675 -296.886835)
			(xy 370.828543 -296.92251) (xy 370.86576 -296.964047) (xy 370.896533 -297.01056) (xy 370.920205 -297.061057)
			(xy 370.936273 -297.114464) (xy 370.944393 -297.16964) (xy 370.944902 -297.197526) (xy 370.944393 -297.225412)
			(xy 370.936273 -297.280588) (xy 370.920205 -297.333995) (xy 370.896533 -297.384492) (xy 370.86576 -297.431005)
			(xy 370.828543 -297.472542) (xy 370.785675 -297.508217) (xy 370.774518 -297.515026) (xy 379.13565 -297.515026)
			(xy 379.139631 -297.382006) (xy 379.15156 -297.249461) (xy 379.171395 -297.117868) (xy 379.199064 -296.987696)
			(xy 379.234468 -296.859411) (xy 379.277481 -296.733474) (xy 379.327948 -296.610335) (xy 379.385689 -296.490434)
			(xy 379.450498 -296.374201) (xy 379.522142 -296.262051) (xy 379.600364 -296.154387) (xy 379.684885 -296.051594)
			(xy 379.775403 -295.954039) (xy 379.871592 -295.862073) (xy 379.97311 -295.776023) (xy 380.079591 -295.696199)
			(xy 380.190656 -295.622886) (xy 380.305907 -295.556346) (xy 380.424931 -295.496817) (xy 380.547302 -295.444513)
			(xy 380.672581 -295.399621) (xy 380.800322 -295.362302) (xy 380.930065 -295.332689) (xy 381.061347 -295.310888)
			(xy 381.193698 -295.296978) (xy 381.326644 -295.291007) (xy 381.459709 -295.292998) (xy 381.592417 -295.302943)
			(xy 381.724293 -295.320807) (xy 381.854864 -295.346525) (xy 381.983664 -295.380006) (xy 382.11023 -295.42113)
			(xy 382.234111 -295.46975) (xy 382.354862 -295.525691) (xy 382.472052 -295.588753) (xy 382.585261 -295.658711)
			(xy 382.694083 -295.735315) (xy 382.798129 -295.818289) (xy 382.897027 -295.907337) (xy 382.990422 -296.00214)
			(xy 383.07798 -296.102358) (xy 383.159389 -296.207634) (xy 383.234355 -296.31759) (xy 383.302612 -296.431832)
			(xy 383.363914 -296.549952) (xy 383.418043 -296.671527) (xy 383.464804 -296.796121) (xy 383.50403 -296.923289)
			(xy 383.53558 -297.052575) (xy 383.559343 -297.183516) (xy 383.575232 -297.315644) (xy 383.58319 -297.448486)
			(xy 383.583688 -297.515026) (xy 383.58319 -297.581566) (xy 383.575232 -297.714408) (xy 383.559343 -297.846536)
			(xy 383.53558 -297.977477) (xy 383.50403 -298.106763) (xy 383.464804 -298.233931) (xy 383.418043 -298.358525)
			(xy 383.363914 -298.4801) (xy 383.302612 -298.59822) (xy 383.234355 -298.712462) (xy 383.159389 -298.822418)
			(xy 383.07798 -298.927694) (xy 382.990422 -299.027912) (xy 382.897027 -299.122715) (xy 382.798129 -299.211763)
			(xy 382.694083 -299.294737) (xy 382.585261 -299.371341) (xy 382.472052 -299.441299) (xy 382.354862 -299.504361)
			(xy 382.234111 -299.560302) (xy 382.11023 -299.608922) (xy 381.983664 -299.650046) (xy 381.854864 -299.683527)
			(xy 381.724293 -299.709245) (xy 381.592417 -299.727109) (xy 381.459709 -299.737054) (xy 381.326644 -299.739045)
			(xy 381.193698 -299.733074) (xy 381.061347 -299.719164) (xy 380.930065 -299.697363) (xy 380.800322 -299.66775)
			(xy 380.672581 -299.630431) (xy 380.547302 -299.585539) (xy 380.424931 -299.533235) (xy 380.305907 -299.473706)
			(xy 380.190656 -299.407166) (xy 380.079591 -299.333853) (xy 379.97311 -299.254029) (xy 379.871592 -299.167979)
			(xy 379.775403 -299.076013) (xy 379.684885 -298.978458) (xy 379.600364 -298.875665) (xy 379.522142 -298.768001)
			(xy 379.450498 -298.655851) (xy 379.385689 -298.539618) (xy 379.327948 -298.419717) (xy 379.277481 -298.296578)
			(xy 379.234468 -298.170641) (xy 379.199064 -298.042356) (xy 379.171395 -297.912184) (xy 379.15156 -297.780591)
			(xy 379.139631 -297.648046) (xy 379.13565 -297.515026) (xy 370.774518 -297.515026) (xy 370.738069 -297.537271)
			(xy 370.68674 -297.559083) (xy 370.632783 -297.573189) (xy 370.577346 -297.579289) (xy 370.521612 -297.577252)
			(xy 370.466769 -297.567122) (xy 370.413985 -297.549115) (xy 370.364385 -297.523614) (xy 370.319027 -297.491163)
			(xy 370.278878 -297.452454) (xy 370.244792 -297.408311) (xy 370.217496 -297.359676) (xy 370.197573 -297.307585)
			(xy 370.185447 -297.253148) (xy 370.181376 -297.197526) (xy 364.969371 -297.197526) (xy 364.969371 -297.224755)
			(xy 364.961614 -297.27871) (xy 364.946256 -297.331011) (xy 364.923612 -297.380595) (xy 364.894142 -297.426451)
			(xy 364.858446 -297.467647) (xy 364.81725 -297.503343) (xy 364.771393 -297.532813) (xy 364.721809 -297.555457)
			(xy 364.669508 -297.570814) (xy 364.615553 -297.578571) (xy 364.588298 -297.579034) (xy 364.560927 -297.578585)
			(xy 364.506746 -297.570766) (xy 364.454243 -297.555273) (xy 364.404496 -297.532427) (xy 364.35853 -297.502698)
			(xy 364.3376 -297.485054) (xy 364.326272 -297.475818) (xy 364.299715 -297.463642) (xy 364.270798 -297.459469)
			(xy 364.241881 -297.463642) (xy 364.215324 -297.475818) (xy 364.203996 -297.485054) (xy 364.18307 -297.502701)
			(xy 364.137097 -297.532413) (xy 364.087347 -297.555249) (xy 364.034845 -297.570738) (xy 363.980668 -297.578562)
			(xy 363.953298 -297.579034) (xy 363.926049 -297.578496) (xy 363.872105 -297.570739) (xy 363.819814 -297.555385)
			(xy 363.770241 -297.532746) (xy 363.724394 -297.503281) (xy 363.683206 -297.467592) (xy 363.647518 -297.426405)
			(xy 363.618054 -297.380558) (xy 363.595414 -297.330984) (xy 363.58006 -297.278693) (xy 363.572304 -297.224749)
			(xy 358.676696 -297.224749) (xy 358.66894 -297.278693) (xy 358.653586 -297.330984) (xy 358.630946 -297.380558)
			(xy 358.601482 -297.426405) (xy 358.565794 -297.467592) (xy 358.524606 -297.503281) (xy 358.478759 -297.532746)
			(xy 358.429186 -297.555385) (xy 358.376895 -297.570739) (xy 358.322951 -297.578496) (xy 358.295702 -297.579034)
			(xy 358.265371 -297.578473) (xy 358.205467 -297.568919) (xy 358.14783 -297.550005) (xy 358.093914 -297.522206)
			(xy 358.045077 -297.486224) (xy 358.023414 -297.464988) (xy 358.01177 -297.454509) (xy 357.98374 -297.440563)
			(xy 357.952802 -297.435763) (xy 357.921864 -297.440563) (xy 357.893834 -297.454509) (xy 357.88219 -297.464988)
			(xy 357.86051 -297.486206) (xy 357.811676 -297.52219) (xy 357.757764 -297.549994) (xy 357.700132 -297.568917)
			(xy 357.640232 -297.578484) (xy 357.609902 -297.579034) (xy 357.584452 -297.578593) (xy 357.534007 -297.571789)
			(xy 357.484914 -297.558341) (xy 357.461312 -297.548808) (xy 357.447995 -297.544153) (xy 357.419912 -297.541573)
			(xy 357.392195 -297.546771) (xy 357.366955 -297.55935) (xy 357.346118 -297.578352) (xy 357.331271 -297.602328)
			(xy 357.323546 -297.62945) (xy 357.323136 -297.64355) (xy 357.323136 -299.115734) (xy 357.322647 -299.154288)
			(xy 357.31506 -299.231023) (xy 357.299991 -299.306646) (xy 357.277587 -299.380429) (xy 357.248061 -299.451661)
			(xy 357.211698 -299.519658) (xy 357.168849 -299.583766) (xy 357.119925 -299.643367) (xy 357.093012 -299.670978)
			(xy 355.87559 -300.888146) (xy 355.852476 -300.944026) (xy 343.393268 -313.396376) (xy 339.670136 -314.907168)
			(xy 338.856174 -315.709738) (xy 345.576648 -315.709738) (xy 345.576648 -315.625042) (xy 345.584699 -315.540728)
			(xy 345.600728 -315.457562) (xy 345.624589 -315.376295) (xy 345.656068 -315.297665) (xy 345.694879 -315.222384)
			(xy 345.740669 -315.151132) (xy 345.793025 -315.084556) (xy 345.851473 -315.023258) (xy 345.915483 -314.967793)
			(xy 345.984475 -314.918664) (xy 346.057825 -314.876315) (xy 346.134868 -314.841131) (xy 346.214907 -314.813429)
			(xy 346.297216 -314.793461) (xy 346.381051 -314.781408) (xy 346.465652 -314.777378) (xy 346.550253 -314.781408)
			(xy 346.634088 -314.793461) (xy 346.716397 -314.813429) (xy 346.796436 -314.841131) (xy 346.873479 -314.876315)
			(xy 346.946829 -314.918664) (xy 347.015821 -314.967793) (xy 347.079831 -315.023258) (xy 347.138279 -315.084556)
			(xy 347.190635 -315.151132) (xy 347.236425 -315.222384) (xy 347.275236 -315.297665) (xy 347.306715 -315.376295)
			(xy 347.330576 -315.457562) (xy 347.346605 -315.540728) (xy 347.354656 -315.625042) (xy 347.35516 -315.66739)
			(xy 347.550237 -315.66739) (xy 347.554259 -315.58167) (xy 347.56629 -315.496702) (xy 347.586226 -315.413235)
			(xy 347.613889 -315.332001) (xy 347.649038 -315.253715) (xy 347.691364 -315.179064) (xy 347.740493 -315.108705)
			(xy 347.795996 -315.043255) (xy 347.857383 -314.983291) (xy 347.924116 -314.929338) (xy 347.995608 -314.881871)
			(xy 348.07123 -314.841307) (xy 348.150319 -314.808003) (xy 348.232179 -314.782251) (xy 348.31609 -314.764278)
			(xy 348.401316 -314.754242) (xy 348.487108 -314.75223) (xy 348.57271 -314.758261) (xy 348.657372 -314.772281)
			(xy 348.740349 -314.794167) (xy 348.820912 -314.823728) (xy 348.898352 -314.860702) (xy 348.971991 -314.904766)
			(xy 349.041179 -314.955532) (xy 349.10531 -315.012553) (xy 349.163819 -315.075329) (xy 349.216192 -315.143309)
			(xy 349.26197 -315.215894) (xy 349.30075 -315.292446) (xy 349.332191 -315.372294) (xy 349.356017 -315.454735)
			(xy 349.372018 -315.539045) (xy 349.380053 -315.624483) (xy 349.380556 -315.66739) (xy 349.38006 -315.709738)
			(xy 351.774248 -315.709738) (xy 351.774248 -315.625042) (xy 351.782299 -315.540728) (xy 351.798328 -315.457562)
			(xy 351.822189 -315.376295) (xy 351.853668 -315.297665) (xy 351.892479 -315.222384) (xy 351.938269 -315.151132)
			(xy 351.990625 -315.084556) (xy 352.049073 -315.023258) (xy 352.113083 -314.967793) (xy 352.182075 -314.918664)
			(xy 352.255425 -314.876315) (xy 352.332468 -314.841131) (xy 352.412507 -314.813429) (xy 352.494816 -314.793461)
			(xy 352.578651 -314.781408) (xy 352.663252 -314.777378) (xy 352.747853 -314.781408) (xy 352.831688 -314.793461)
			(xy 352.913997 -314.813429) (xy 352.994036 -314.841131) (xy 353.071079 -314.876315) (xy 353.144429 -314.918664)
			(xy 353.213421 -314.967793) (xy 353.277431 -315.023258) (xy 353.335879 -315.084556) (xy 353.388235 -315.151132)
			(xy 353.434025 -315.222384) (xy 353.472836 -315.297665) (xy 353.504315 -315.376295) (xy 353.528176 -315.457562)
			(xy 353.544205 -315.540728) (xy 353.552256 -315.625042) (xy 353.55276 -315.66739) (xy 353.747837 -315.66739)
			(xy 353.751859 -315.58167) (xy 353.76389 -315.496702) (xy 353.783826 -315.413235) (xy 353.811489 -315.332001)
			(xy 353.846638 -315.253715) (xy 353.888964 -315.179064) (xy 353.938093 -315.108705) (xy 353.993596 -315.043255)
			(xy 354.054983 -314.983291) (xy 354.121716 -314.929338) (xy 354.193208 -314.881871) (xy 354.26883 -314.841307)
			(xy 354.347919 -314.808003) (xy 354.429779 -314.782251) (xy 354.51369 -314.764278) (xy 354.598916 -314.754242)
			(xy 354.684708 -314.75223) (xy 354.77031 -314.758261) (xy 354.854972 -314.772281) (xy 354.937949 -314.794167)
			(xy 355.018512 -314.823728) (xy 355.095952 -314.860702) (xy 355.169591 -314.904766) (xy 355.238779 -314.955532)
			(xy 355.30291 -315.012553) (xy 355.361419 -315.075329) (xy 355.413792 -315.143309) (xy 355.45957 -315.215894)
			(xy 355.49835 -315.292446) (xy 355.529791 -315.372294) (xy 355.553617 -315.454735) (xy 355.569618 -315.539045)
			(xy 355.577653 -315.624483) (xy 355.578156 -315.66739) (xy 355.57766 -315.709738) (xy 357.952036 -315.709738)
			(xy 357.952036 -315.625042) (xy 357.960087 -315.540728) (xy 357.976116 -315.457562) (xy 357.999977 -315.376295)
			(xy 358.031456 -315.297665) (xy 358.070267 -315.222384) (xy 358.116057 -315.151132) (xy 358.168413 -315.084556)
			(xy 358.226861 -315.023258) (xy 358.290871 -314.967793) (xy 358.359863 -314.918664) (xy 358.433213 -314.876315)
			(xy 358.510256 -314.841131) (xy 358.590295 -314.813429) (xy 358.672604 -314.793461) (xy 358.756439 -314.781408)
			(xy 358.84104 -314.777378) (xy 358.925641 -314.781408) (xy 359.009476 -314.793461) (xy 359.091785 -314.813429)
			(xy 359.171824 -314.841131) (xy 359.248867 -314.876315) (xy 359.322217 -314.918664) (xy 359.391209 -314.967793)
			(xy 359.455219 -315.023258) (xy 359.513667 -315.084556) (xy 359.566023 -315.151132) (xy 359.611813 -315.222384)
			(xy 359.650624 -315.297665) (xy 359.682103 -315.376295) (xy 359.705964 -315.457562) (xy 359.721993 -315.540728)
			(xy 359.730044 -315.625042) (xy 359.730548 -315.66739) (xy 359.925625 -315.66739) (xy 359.929647 -315.58167)
			(xy 359.941678 -315.496702) (xy 359.961614 -315.413235) (xy 359.989277 -315.332001) (xy 360.024426 -315.253715)
			(xy 360.066752 -315.179064) (xy 360.115881 -315.108705) (xy 360.171384 -315.043255) (xy 360.232771 -314.983291)
			(xy 360.299504 -314.929338) (xy 360.370996 -314.881871) (xy 360.446618 -314.841307) (xy 360.525707 -314.808003)
			(xy 360.607567 -314.782251) (xy 360.691478 -314.764278) (xy 360.776704 -314.754242) (xy 360.862496 -314.75223)
			(xy 360.948098 -314.758261) (xy 361.03276 -314.772281) (xy 361.115737 -314.794167) (xy 361.1963 -314.823728)
			(xy 361.27374 -314.860702) (xy 361.347379 -314.904766) (xy 361.416567 -314.955532) (xy 361.480698 -315.012553)
			(xy 361.539207 -315.075329) (xy 361.59158 -315.143309) (xy 361.637358 -315.215894) (xy 361.676138 -315.292446)
			(xy 361.707579 -315.372294) (xy 361.731405 -315.454735) (xy 361.747406 -315.539045) (xy 361.755441 -315.624483)
			(xy 361.755944 -315.66739) (xy 361.755448 -315.709738) (xy 364.149636 -315.709738) (xy 364.149636 -315.625042)
			(xy 364.157687 -315.540728) (xy 364.173716 -315.457562) (xy 364.197577 -315.376295) (xy 364.229056 -315.297665)
			(xy 364.267867 -315.222384) (xy 364.313657 -315.151132) (xy 364.366013 -315.084556) (xy 364.424461 -315.023258)
			(xy 364.488471 -314.967793) (xy 364.557463 -314.918664) (xy 364.630813 -314.876315) (xy 364.707856 -314.841131)
			(xy 364.787895 -314.813429) (xy 364.870204 -314.793461) (xy 364.954039 -314.781408) (xy 365.03864 -314.777378)
			(xy 365.123241 -314.781408) (xy 365.207076 -314.793461) (xy 365.289385 -314.813429) (xy 365.369424 -314.841131)
			(xy 365.446467 -314.876315) (xy 365.519817 -314.918664) (xy 365.588809 -314.967793) (xy 365.652819 -315.023258)
			(xy 365.711267 -315.084556) (xy 365.763623 -315.151132) (xy 365.809413 -315.222384) (xy 365.848224 -315.297665)
			(xy 365.879703 -315.376295) (xy 365.903564 -315.457562) (xy 365.919593 -315.540728) (xy 365.927644 -315.625042)
			(xy 365.928148 -315.66739) (xy 366.123225 -315.66739) (xy 366.127247 -315.58167) (xy 366.139278 -315.496702)
			(xy 366.159214 -315.413235) (xy 366.186877 -315.332001) (xy 366.222026 -315.253715) (xy 366.264352 -315.179064)
			(xy 366.313481 -315.108705) (xy 366.368984 -315.043255) (xy 366.430371 -314.983291) (xy 366.497104 -314.929338)
			(xy 366.568596 -314.881871) (xy 366.644218 -314.841307) (xy 366.723307 -314.808003) (xy 366.805167 -314.782251)
			(xy 366.889078 -314.764278) (xy 366.974304 -314.754242) (xy 367.060096 -314.75223) (xy 367.145698 -314.758261)
			(xy 367.23036 -314.772281) (xy 367.313337 -314.794167) (xy 367.3939 -314.823728) (xy 367.47134 -314.860702)
			(xy 367.544979 -314.904766) (xy 367.614167 -314.955532) (xy 367.678298 -315.012553) (xy 367.736807 -315.075329)
			(xy 367.78918 -315.143309) (xy 367.834958 -315.215894) (xy 367.873738 -315.292446) (xy 367.905179 -315.372294)
			(xy 367.929005 -315.454735) (xy 367.945006 -315.539045) (xy 367.953041 -315.624483) (xy 367.953544 -315.66739)
			(xy 367.953048 -315.709738) (xy 370.347236 -315.709738) (xy 370.347236 -315.625042) (xy 370.355287 -315.540728)
			(xy 370.371316 -315.457562) (xy 370.395177 -315.376295) (xy 370.426656 -315.297665) (xy 370.465467 -315.222384)
			(xy 370.511257 -315.151132) (xy 370.563613 -315.084556) (xy 370.622061 -315.023258) (xy 370.686071 -314.967793)
			(xy 370.755063 -314.918664) (xy 370.828413 -314.876315) (xy 370.905456 -314.841131) (xy 370.985495 -314.813429)
			(xy 371.067804 -314.793461) (xy 371.151639 -314.781408) (xy 371.23624 -314.777378) (xy 371.320841 -314.781408)
			(xy 371.404676 -314.793461) (xy 371.486985 -314.813429) (xy 371.567024 -314.841131) (xy 371.644067 -314.876315)
			(xy 371.717417 -314.918664) (xy 371.786409 -314.967793) (xy 371.850419 -315.023258) (xy 371.908867 -315.084556)
			(xy 371.961223 -315.151132) (xy 372.007013 -315.222384) (xy 372.045824 -315.297665) (xy 372.077303 -315.376295)
			(xy 372.101164 -315.457562) (xy 372.117193 -315.540728) (xy 372.125244 -315.625042) (xy 372.125748 -315.66739)
			(xy 372.320825 -315.66739) (xy 372.324847 -315.58167) (xy 372.336878 -315.496702) (xy 372.356814 -315.413235)
			(xy 372.384477 -315.332001) (xy 372.419626 -315.253715) (xy 372.461952 -315.179064) (xy 372.511081 -315.108705)
			(xy 372.566584 -315.043255) (xy 372.627971 -314.983291) (xy 372.694704 -314.929338) (xy 372.766196 -314.881871)
			(xy 372.841818 -314.841307) (xy 372.920907 -314.808003) (xy 373.002767 -314.782251) (xy 373.086678 -314.764278)
			(xy 373.171904 -314.754242) (xy 373.257696 -314.75223) (xy 373.343298 -314.758261) (xy 373.42796 -314.772281)
			(xy 373.510937 -314.794167) (xy 373.5915 -314.823728) (xy 373.66894 -314.860702) (xy 373.742579 -314.904766)
			(xy 373.811767 -314.955532) (xy 373.875898 -315.012553) (xy 373.934407 -315.075329) (xy 373.98678 -315.143309)
			(xy 374.032558 -315.215894) (xy 374.071338 -315.292446) (xy 374.102779 -315.372294) (xy 374.126605 -315.454735)
			(xy 374.142606 -315.539045) (xy 374.150641 -315.624483) (xy 374.151144 -315.66739) (xy 374.150641 -315.710297)
			(xy 374.142606 -315.795735) (xy 374.126605 -315.880045) (xy 374.102779 -315.962486) (xy 374.071338 -316.042334)
			(xy 374.032558 -316.118886) (xy 373.98678 -316.191471) (xy 373.934407 -316.259451) (xy 373.875898 -316.322227)
			(xy 373.811767 -316.379248) (xy 373.742579 -316.430014) (xy 373.66894 -316.474078) (xy 373.5915 -316.511052)
			(xy 373.510937 -316.540613) (xy 373.42796 -316.562499) (xy 373.343298 -316.576519) (xy 373.257696 -316.58255)
			(xy 373.171904 -316.580538) (xy 373.086678 -316.570502) (xy 373.002767 -316.552529) (xy 372.920907 -316.526777)
			(xy 372.841818 -316.493473) (xy 372.766196 -316.452909) (xy 372.694704 -316.405442) (xy 372.627971 -316.351489)
			(xy 372.566584 -316.291525) (xy 372.511081 -316.226075) (xy 372.461952 -316.155716) (xy 372.419626 -316.081065)
			(xy 372.384477 -316.002779) (xy 372.356814 -315.921545) (xy 372.336878 -315.838078) (xy 372.324847 -315.75311)
			(xy 372.320825 -315.66739) (xy 372.125748 -315.66739) (xy 372.125244 -315.709738) (xy 372.117193 -315.794052)
			(xy 372.101164 -315.877218) (xy 372.077303 -315.958485) (xy 372.045824 -316.037115) (xy 372.007013 -316.112396)
			(xy 371.961223 -316.183648) (xy 371.908867 -316.250224) (xy 371.850419 -316.311522) (xy 371.786409 -316.366987)
			(xy 371.717417 -316.416116) (xy 371.644067 -316.458465) (xy 371.567024 -316.493649) (xy 371.486985 -316.521351)
			(xy 371.404676 -316.541319) (xy 371.320841 -316.553372) (xy 371.23624 -316.557403) (xy 371.151639 -316.553372)
			(xy 371.067804 -316.541319) (xy 370.985495 -316.521351) (xy 370.905456 -316.493649) (xy 370.828413 -316.458465)
			(xy 370.755063 -316.416116) (xy 370.686071 -316.366987) (xy 370.622061 -316.311522) (xy 370.563613 -316.250224)
			(xy 370.511257 -316.183648) (xy 370.465467 -316.112396) (xy 370.426656 -316.037115) (xy 370.395177 -315.958485)
			(xy 370.371316 -315.877218) (xy 370.355287 -315.794052) (xy 370.347236 -315.709738) (xy 367.953048 -315.709738)
			(xy 367.953041 -315.710297) (xy 367.945006 -315.795735) (xy 367.929005 -315.880045) (xy 367.905179 -315.962486)
			(xy 367.873738 -316.042334) (xy 367.834958 -316.118886) (xy 367.78918 -316.191471) (xy 367.736807 -316.259451)
			(xy 367.678298 -316.322227) (xy 367.614167 -316.379248) (xy 367.544979 -316.430014) (xy 367.47134 -316.474078)
			(xy 367.3939 -316.511052) (xy 367.313337 -316.540613) (xy 367.23036 -316.562499) (xy 367.145698 -316.576519)
			(xy 367.060096 -316.58255) (xy 366.974304 -316.580538) (xy 366.889078 -316.570502) (xy 366.805167 -316.552529)
			(xy 366.723307 -316.526777) (xy 366.644218 -316.493473) (xy 366.568596 -316.452909) (xy 366.497104 -316.405442)
			(xy 366.430371 -316.351489) (xy 366.368984 -316.291525) (xy 366.313481 -316.226075) (xy 366.264352 -316.155716)
			(xy 366.222026 -316.081065) (xy 366.186877 -316.002779) (xy 366.159214 -315.921545) (xy 366.139278 -315.838078)
			(xy 366.127247 -315.75311) (xy 366.123225 -315.66739) (xy 365.928148 -315.66739) (xy 365.927644 -315.709738)
			(xy 365.919593 -315.794052) (xy 365.903564 -315.877218) (xy 365.879703 -315.958485) (xy 365.848224 -316.037115)
			(xy 365.809413 -316.112396) (xy 365.763623 -316.183648) (xy 365.711267 -316.250224) (xy 365.652819 -316.311522)
			(xy 365.588809 -316.366987) (xy 365.519817 -316.416116) (xy 365.446467 -316.458465) (xy 365.369424 -316.493649)
			(xy 365.289385 -316.521351) (xy 365.207076 -316.541319) (xy 365.123241 -316.553372) (xy 365.03864 -316.557403)
			(xy 364.954039 -316.553372) (xy 364.870204 -316.541319) (xy 364.787895 -316.521351) (xy 364.707856 -316.493649)
			(xy 364.630813 -316.458465) (xy 364.557463 -316.416116) (xy 364.488471 -316.366987) (xy 364.424461 -316.311522)
			(xy 364.366013 -316.250224) (xy 364.313657 -316.183648) (xy 364.267867 -316.112396) (xy 364.229056 -316.037115)
			(xy 364.197577 -315.958485) (xy 364.173716 -315.877218) (xy 364.157687 -315.794052) (xy 364.149636 -315.709738)
			(xy 361.755448 -315.709738) (xy 361.755441 -315.710297) (xy 361.747406 -315.795735) (xy 361.731405 -315.880045)
			(xy 361.707579 -315.962486) (xy 361.676138 -316.042334) (xy 361.637358 -316.118886) (xy 361.59158 -316.191471)
			(xy 361.539207 -316.259451) (xy 361.480698 -316.322227) (xy 361.416567 -316.379248) (xy 361.347379 -316.430014)
			(xy 361.27374 -316.474078) (xy 361.1963 -316.511052) (xy 361.115737 -316.540613) (xy 361.03276 -316.562499)
			(xy 360.948098 -316.576519) (xy 360.862496 -316.58255) (xy 360.776704 -316.580538) (xy 360.691478 -316.570502)
			(xy 360.607567 -316.552529) (xy 360.525707 -316.526777) (xy 360.446618 -316.493473) (xy 360.370996 -316.452909)
			(xy 360.299504 -316.405442) (xy 360.232771 -316.351489) (xy 360.171384 -316.291525) (xy 360.115881 -316.226075)
			(xy 360.066752 -316.155716) (xy 360.024426 -316.081065) (xy 359.989277 -316.002779) (xy 359.961614 -315.921545)
			(xy 359.941678 -315.838078) (xy 359.929647 -315.75311) (xy 359.925625 -315.66739) (xy 359.730548 -315.66739)
			(xy 359.730044 -315.709738) (xy 359.721993 -315.794052) (xy 359.705964 -315.877218) (xy 359.682103 -315.958485)
			(xy 359.650624 -316.037115) (xy 359.611813 -316.112396) (xy 359.566023 -316.183648) (xy 359.513667 -316.250224)
			(xy 359.455219 -316.311522) (xy 359.391209 -316.366987) (xy 359.322217 -316.416116) (xy 359.248867 -316.458465)
			(xy 359.171824 -316.493649) (xy 359.091785 -316.521351) (xy 359.009476 -316.541319) (xy 358.925641 -316.553372)
			(xy 358.84104 -316.557403) (xy 358.756439 -316.553372) (xy 358.672604 -316.541319) (xy 358.590295 -316.521351)
			(xy 358.510256 -316.493649) (xy 358.433213 -316.458465) (xy 358.359863 -316.416116) (xy 358.290871 -316.366987)
			(xy 358.226861 -316.311522) (xy 358.168413 -316.250224) (xy 358.116057 -316.183648) (xy 358.070267 -316.112396)
			(xy 358.031456 -316.037115) (xy 357.999977 -315.958485) (xy 357.976116 -315.877218) (xy 357.960087 -315.794052)
			(xy 357.952036 -315.709738) (xy 355.57766 -315.709738) (xy 355.577653 -315.710297) (xy 355.569618 -315.795735)
			(xy 355.553617 -315.880045) (xy 355.529791 -315.962486) (xy 355.49835 -316.042334) (xy 355.45957 -316.118886)
			(xy 355.413792 -316.191471) (xy 355.361419 -316.259451) (xy 355.30291 -316.322227) (xy 355.238779 -316.379248)
			(xy 355.169591 -316.430014) (xy 355.095952 -316.474078) (xy 355.018512 -316.511052) (xy 354.937949 -316.540613)
			(xy 354.854972 -316.562499) (xy 354.77031 -316.576519) (xy 354.684708 -316.58255) (xy 354.598916 -316.580538)
			(xy 354.51369 -316.570502) (xy 354.429779 -316.552529) (xy 354.347919 -316.526777) (xy 354.26883 -316.493473)
			(xy 354.193208 -316.452909) (xy 354.121716 -316.405442) (xy 354.054983 -316.351489) (xy 353.993596 -316.291525)
			(xy 353.938093 -316.226075) (xy 353.888964 -316.155716) (xy 353.846638 -316.081065) (xy 353.811489 -316.002779)
			(xy 353.783826 -315.921545) (xy 353.76389 -315.838078) (xy 353.751859 -315.75311) (xy 353.747837 -315.66739)
			(xy 353.55276 -315.66739) (xy 353.552256 -315.709738) (xy 353.544205 -315.794052) (xy 353.528176 -315.877218)
			(xy 353.504315 -315.958485) (xy 353.472836 -316.037115) (xy 353.434025 -316.112396) (xy 353.388235 -316.183648)
			(xy 353.335879 -316.250224) (xy 353.277431 -316.311522) (xy 353.213421 -316.366987) (xy 353.144429 -316.416116)
			(xy 353.071079 -316.458465) (xy 352.994036 -316.493649) (xy 352.913997 -316.521351) (xy 352.831688 -316.541319)
			(xy 352.747853 -316.553372) (xy 352.663252 -316.557403) (xy 352.578651 -316.553372) (xy 352.494816 -316.541319)
			(xy 352.412507 -316.521351) (xy 352.332468 -316.493649) (xy 352.255425 -316.458465) (xy 352.182075 -316.416116)
			(xy 352.113083 -316.366987) (xy 352.049073 -316.311522) (xy 351.990625 -316.250224) (xy 351.938269 -316.183648)
			(xy 351.892479 -316.112396) (xy 351.853668 -316.037115) (xy 351.822189 -315.958485) (xy 351.798328 -315.877218)
			(xy 351.782299 -315.794052) (xy 351.774248 -315.709738) (xy 349.38006 -315.709738) (xy 349.380053 -315.710297)
			(xy 349.372018 -315.795735) (xy 349.356017 -315.880045) (xy 349.332191 -315.962486) (xy 349.30075 -316.042334)
			(xy 349.26197 -316.118886) (xy 349.216192 -316.191471) (xy 349.163819 -316.259451) (xy 349.10531 -316.322227)
			(xy 349.041179 -316.379248) (xy 348.971991 -316.430014) (xy 348.898352 -316.474078) (xy 348.820912 -316.511052)
			(xy 348.740349 -316.540613) (xy 348.657372 -316.562499) (xy 348.57271 -316.576519) (xy 348.487108 -316.58255)
			(xy 348.401316 -316.580538) (xy 348.31609 -316.570502) (xy 348.232179 -316.552529) (xy 348.150319 -316.526777)
			(xy 348.07123 -316.493473) (xy 347.995608 -316.452909) (xy 347.924116 -316.405442) (xy 347.857383 -316.351489)
			(xy 347.795996 -316.291525) (xy 347.740493 -316.226075) (xy 347.691364 -316.155716) (xy 347.649038 -316.081065)
			(xy 347.613889 -316.002779) (xy 347.586226 -315.921545) (xy 347.56629 -315.838078) (xy 347.554259 -315.75311)
			(xy 347.550237 -315.66739) (xy 347.35516 -315.66739) (xy 347.354656 -315.709738) (xy 347.346605 -315.794052)
			(xy 347.330576 -315.877218) (xy 347.306715 -315.958485) (xy 347.275236 -316.037115) (xy 347.236425 -316.112396)
			(xy 347.190635 -316.183648) (xy 347.138279 -316.250224) (xy 347.079831 -316.311522) (xy 347.015821 -316.366987)
			(xy 346.946829 -316.416116) (xy 346.873479 -316.458465) (xy 346.796436 -316.493649) (xy 346.716397 -316.521351)
			(xy 346.634088 -316.541319) (xy 346.550253 -316.553372) (xy 346.465652 -316.557403) (xy 346.381051 -316.553372)
			(xy 346.297216 -316.541319) (xy 346.214907 -316.521351) (xy 346.134868 -316.493649) (xy 346.057825 -316.458465)
			(xy 345.984475 -316.416116) (xy 345.915483 -316.366987) (xy 345.851473 -316.311522) (xy 345.793025 -316.250224)
			(xy 345.740669 -316.183648) (xy 345.694879 -316.112396) (xy 345.656068 -316.037115) (xy 345.624589 -315.958485)
			(xy 345.600728 -315.877218) (xy 345.584699 -315.794052) (xy 345.576648 -315.709738) (xy 338.856174 -315.709738)
			(xy 324.752208 -329.616308) (xy 324.61073 -330.010516) (xy 324.61073 -332.454504) (xy 324.912228 -332.756002)
			(xy 336.390234 -332.756002)
		)
		(stroke
			(width 0)
			(type solid)
		)
		(fill yes)
		(layer "In6.Cu")
		(net "PVCCIN_CPU0")
	)
	(gr_poly
		(pts
			(xy 84.514944 -332.072234) (xy 84.514944 -331.015594) (xy 86.260686 -329.269852) (xy 91.853766 -329.269852)
			(xy 95.125286 -325.998332) (xy 124.093986 -325.998332) (xy 127.472186 -329.376532) (xy 132.079746 -329.376532)
			(xy 133.949186 -331.245972) (xy 133.949186 -332.047342) (xy 134.29107 -332.389226) (xy 148.301202 -332.389226)
			(xy 149.11832 -331.572108) (xy 149.11832 -303.375568) (xy 135.318754 -289.576002) (xy 133.69671 -289.576002)
			(xy 133.65734 -289.65017) (xy 133.6675 -289.672776) (xy 133.676497 -289.694022) (xy 133.689182 -289.738381)
			(xy 133.695576 -289.784073) (xy 133.695948 -289.807142) (xy 133.695439 -289.833109) (xy 133.687314 -289.884404)
			(xy 133.671266 -289.933797) (xy 133.647688 -289.980071) (xy 133.617162 -290.022087) (xy 133.580439 -290.05881)
			(xy 133.538423 -290.089336) (xy 133.492149 -290.112914) (xy 133.442756 -290.128962) (xy 133.391461 -290.137087)
			(xy 133.339527 -290.137087) (xy 133.288232 -290.128962) (xy 133.238839 -290.112914) (xy 133.192565 -290.089336)
			(xy 133.150549 -290.05881) (xy 133.113826 -290.022087) (xy 133.0833 -289.980071) (xy 133.059722 -289.933797)
			(xy 133.043674 -289.884404) (xy 133.035549 -289.833109) (xy 133.03504 -289.807142) (xy 133.035532 -289.781977)
			(xy 133.043184 -289.732231) (xy 133.05028 -289.708082) (xy 133.053956 -289.694939) (xy 133.054956 -289.667677)
			(xy 133.048697 -289.641124) (xy 133.035627 -289.617178) (xy 133.01668 -289.597551) (xy 132.993209 -289.583646)
			(xy 132.966893 -289.576456) (xy 132.953252 -289.576002) (xy 132.837936 -289.576002) (xy 132.824304 -289.576446)
			(xy 132.798015 -289.583673) (xy 132.774573 -289.597594) (xy 132.755647 -289.617219) (xy 132.742585 -289.64115)
			(xy 132.736316 -289.667684) (xy 132.737287 -289.694931) (xy 132.740908 -289.708082) (xy 132.74802 -289.732227)
			(xy 132.755666 -289.781976) (xy 132.756148 -289.807142) (xy 132.755639 -289.833109) (xy 132.747514 -289.884404)
			(xy 132.731466 -289.933797) (xy 132.707888 -289.980071) (xy 132.677362 -290.022087) (xy 132.640639 -290.05881)
			(xy 132.598623 -290.089336) (xy 132.552349 -290.112914) (xy 132.502956 -290.128962) (xy 132.451661 -290.137087)
			(xy 132.399727 -290.137087) (xy 132.348432 -290.128962) (xy 132.299039 -290.112914) (xy 132.252765 -290.089336)
			(xy 132.210749 -290.05881) (xy 132.174026 -290.022087) (xy 132.1435 -289.980071) (xy 132.119922 -289.933797)
			(xy 132.103874 -289.884404) (xy 132.095749 -289.833109) (xy 132.09524 -289.807142) (xy 132.095732 -289.781977)
			(xy 132.103384 -289.732231) (xy 132.11048 -289.708082) (xy 132.114156 -289.694939) (xy 132.115156 -289.667677)
			(xy 132.108897 -289.641124) (xy 132.095827 -289.617178) (xy 132.07688 -289.597551) (xy 132.053409 -289.583646)
			(xy 132.027093 -289.576456) (xy 132.013452 -289.576002) (xy 131.81711 -289.576002) (xy 131.77774 -289.65017)
			(xy 131.7879 -289.672776) (xy 131.796897 -289.694022) (xy 131.809582 -289.738381) (xy 131.815976 -289.784073)
			(xy 131.816348 -289.807142) (xy 131.815839 -289.833109) (xy 131.807714 -289.884404) (xy 131.791666 -289.933797)
			(xy 131.768088 -289.980071) (xy 131.737562 -290.022087) (xy 131.700839 -290.05881) (xy 131.658823 -290.089336)
			(xy 131.612549 -290.112914) (xy 131.563156 -290.128962) (xy 131.511861 -290.137087) (xy 131.459927 -290.137087)
			(xy 131.408632 -290.128962) (xy 131.359239 -290.112914) (xy 131.312965 -290.089336) (xy 131.270949 -290.05881)
			(xy 131.234226 -290.022087) (xy 131.2037 -289.980071) (xy 131.180122 -289.933797) (xy 131.164074 -289.884404)
			(xy 131.155949 -289.833109) (xy 131.15544 -289.807142) (xy 131.155932 -289.781977) (xy 131.163584 -289.732231)
			(xy 131.17068 -289.708082) (xy 131.174356 -289.694939) (xy 131.175356 -289.667677) (xy 131.169097 -289.641124)
			(xy 131.156027 -289.617178) (xy 131.13708 -289.597551) (xy 131.113609 -289.583646) (xy 131.087293 -289.576456)
			(xy 131.073652 -289.576002) (xy 130.958336 -289.576002) (xy 130.944704 -289.576446) (xy 130.918415 -289.583673)
			(xy 130.894973 -289.597594) (xy 130.876047 -289.617219) (xy 130.862985 -289.64115) (xy 130.856716 -289.667684)
			(xy 130.857687 -289.694931) (xy 130.861308 -289.708082) (xy 130.86842 -289.732227) (xy 130.876066 -289.781976)
			(xy 130.876548 -289.807142) (xy 130.876039 -289.833109) (xy 130.867914 -289.884404) (xy 130.851866 -289.933797)
			(xy 130.828288 -289.980071) (xy 130.797762 -290.022087) (xy 130.761039 -290.05881) (xy 130.719023 -290.089336)
			(xy 130.672749 -290.112914) (xy 130.623356 -290.128962) (xy 130.572061 -290.137087) (xy 130.520127 -290.137087)
			(xy 130.468832 -290.128962) (xy 130.419439 -290.112914) (xy 130.373165 -290.089336) (xy 130.331149 -290.05881)
			(xy 130.294426 -290.022087) (xy 130.2639 -289.980071) (xy 130.240322 -289.933797) (xy 130.224274 -289.884404)
			(xy 130.216149 -289.833109) (xy 130.21564 -289.807142) (xy 130.216132 -289.781977) (xy 130.223784 -289.732231)
			(xy 130.23088 -289.708082) (xy 130.234556 -289.694939) (xy 130.235556 -289.667677) (xy 130.229297 -289.641124)
			(xy 130.216227 -289.617178) (xy 130.19728 -289.597551) (xy 130.173809 -289.583646) (xy 130.147493 -289.576456)
			(xy 130.133852 -289.576002) (xy 129.93751 -289.576002) (xy 129.89814 -289.65017) (xy 129.9083 -289.672776)
			(xy 129.917297 -289.694022) (xy 129.929982 -289.738381) (xy 129.936376 -289.784073) (xy 129.936748 -289.807142)
			(xy 129.936239 -289.833109) (xy 129.928114 -289.884404) (xy 129.912066 -289.933797) (xy 129.888488 -289.980071)
			(xy 129.857962 -290.022087) (xy 129.821239 -290.05881) (xy 129.779223 -290.089336) (xy 129.732949 -290.112914)
			(xy 129.683556 -290.128962) (xy 129.632261 -290.137087) (xy 129.580327 -290.137087) (xy 129.529032 -290.128962)
			(xy 129.479639 -290.112914) (xy 129.433365 -290.089336) (xy 129.391349 -290.05881) (xy 129.354626 -290.022087)
			(xy 129.3241 -289.980071) (xy 129.300522 -289.933797) (xy 129.284474 -289.884404) (xy 129.276349 -289.833109)
			(xy 129.27584 -289.807142) (xy 129.276332 -289.781977) (xy 129.283984 -289.732231) (xy 129.29108 -289.708082)
			(xy 129.294756 -289.694939) (xy 129.295756 -289.667677) (xy 129.289497 -289.641124) (xy 129.276427 -289.617178)
			(xy 129.25748 -289.597551) (xy 129.234009 -289.583646) (xy 129.207693 -289.576456) (xy 129.194052 -289.576002)
			(xy 129.078736 -289.576002) (xy 129.065104 -289.576446) (xy 129.038815 -289.583673) (xy 129.015373 -289.597594)
			(xy 128.996447 -289.617219) (xy 128.983385 -289.64115) (xy 128.977116 -289.667684) (xy 128.978087 -289.694931)
			(xy 128.981708 -289.708082) (xy 128.98882 -289.732227) (xy 128.996466 -289.781976) (xy 128.996948 -289.807142)
			(xy 128.996439 -289.833109) (xy 128.988314 -289.884404) (xy 128.972266 -289.933797) (xy 128.948688 -289.980071)
			(xy 128.918162 -290.022087) (xy 128.881439 -290.05881) (xy 128.839423 -290.089336) (xy 128.793149 -290.112914)
			(xy 128.743756 -290.128962) (xy 128.692461 -290.137087) (xy 128.640527 -290.137087) (xy 128.589232 -290.128962)
			(xy 128.539839 -290.112914) (xy 128.493565 -290.089336) (xy 128.451549 -290.05881) (xy 128.414826 -290.022087)
			(xy 128.3843 -289.980071) (xy 128.360722 -289.933797) (xy 128.344674 -289.884404) (xy 128.336549 -289.833109)
			(xy 128.33604 -289.807142) (xy 128.336532 -289.781977) (xy 128.344184 -289.732231) (xy 128.35128 -289.708082)
			(xy 128.354956 -289.694939) (xy 128.355956 -289.667677) (xy 128.349697 -289.641124) (xy 128.336627 -289.617178)
			(xy 128.31768 -289.597551) (xy 128.294209 -289.583646) (xy 128.267893 -289.576456) (xy 128.254252 -289.576002)
			(xy 128.05791 -289.576002) (xy 128.01854 -289.65017) (xy 128.0287 -289.672776) (xy 128.037697 -289.694022)
			(xy 128.050382 -289.738381) (xy 128.056776 -289.784073) (xy 128.057148 -289.807142) (xy 128.056639 -289.833109)
			(xy 128.048514 -289.884404) (xy 128.032466 -289.933797) (xy 128.008888 -289.980071) (xy 127.978362 -290.022087)
			(xy 127.941639 -290.05881) (xy 127.899623 -290.089336) (xy 127.853349 -290.112914) (xy 127.803956 -290.128962)
			(xy 127.752661 -290.137087) (xy 127.700727 -290.137087) (xy 127.649432 -290.128962) (xy 127.600039 -290.112914)
			(xy 127.553765 -290.089336) (xy 127.511749 -290.05881) (xy 127.475026 -290.022087) (xy 127.4445 -289.980071)
			(xy 127.420922 -289.933797) (xy 127.404874 -289.884404) (xy 127.396749 -289.833109) (xy 127.39624 -289.807142)
			(xy 127.396732 -289.781977) (xy 127.404384 -289.732231) (xy 127.41148 -289.708082) (xy 127.415156 -289.694939)
			(xy 127.416156 -289.667677) (xy 127.409897 -289.641124) (xy 127.396827 -289.617178) (xy 127.37788 -289.597551)
			(xy 127.354409 -289.583646) (xy 127.328093 -289.576456) (xy 127.314452 -289.576002) (xy 127.199136 -289.576002)
			(xy 127.185504 -289.576446) (xy 127.159215 -289.583673) (xy 127.135773 -289.597594) (xy 127.116847 -289.617219)
			(xy 127.103785 -289.64115) (xy 127.097516 -289.667684) (xy 127.098487 -289.694931) (xy 127.102108 -289.708082)
			(xy 127.10922 -289.732227) (xy 127.116866 -289.781976) (xy 127.117348 -289.807142) (xy 127.116839 -289.833109)
			(xy 127.108714 -289.884404) (xy 127.092666 -289.933797) (xy 127.069088 -289.980071) (xy 127.038562 -290.022087)
			(xy 127.001839 -290.05881) (xy 126.959823 -290.089336) (xy 126.913549 -290.112914) (xy 126.864156 -290.128962)
			(xy 126.812861 -290.137087) (xy 126.760927 -290.137087) (xy 126.709632 -290.128962) (xy 126.660239 -290.112914)
			(xy 126.613965 -290.089336) (xy 126.571949 -290.05881) (xy 126.535226 -290.022087) (xy 126.5047 -289.980071)
			(xy 126.481122 -289.933797) (xy 126.465074 -289.884404) (xy 126.456949 -289.833109) (xy 126.45644 -289.807142)
			(xy 126.456932 -289.781977) (xy 126.464584 -289.732231) (xy 126.47168 -289.708082) (xy 126.475356 -289.694939)
			(xy 126.476356 -289.667677) (xy 126.470097 -289.641124) (xy 126.457027 -289.617178) (xy 126.43808 -289.597551)
			(xy 126.414609 -289.583646) (xy 126.388293 -289.576456) (xy 126.374652 -289.576002) (xy 126.17831 -289.576002)
			(xy 126.13894 -289.65017) (xy 126.1491 -289.672776) (xy 126.158097 -289.694022) (xy 126.170782 -289.738381)
			(xy 126.177176 -289.784073) (xy 126.177548 -289.807142) (xy 126.177039 -289.833109) (xy 126.168914 -289.884404)
			(xy 126.152866 -289.933797) (xy 126.129288 -289.980071) (xy 126.098762 -290.022087) (xy 126.062039 -290.05881)
			(xy 126.020023 -290.089336) (xy 125.973749 -290.112914) (xy 125.924356 -290.128962) (xy 125.873061 -290.137087)
			(xy 125.821127 -290.137087) (xy 125.769832 -290.128962) (xy 125.720439 -290.112914) (xy 125.674165 -290.089336)
			(xy 125.632149 -290.05881) (xy 125.595426 -290.022087) (xy 125.5649 -289.980071) (xy 125.541322 -289.933797)
			(xy 125.525274 -289.884404) (xy 125.517149 -289.833109) (xy 125.51664 -289.807142) (xy 125.517132 -289.781977)
			(xy 125.524784 -289.732231) (xy 125.53188 -289.708082) (xy 125.535556 -289.694939) (xy 125.536556 -289.667677)
			(xy 125.530297 -289.641124) (xy 125.517227 -289.617178) (xy 125.49828 -289.597551) (xy 125.474809 -289.583646)
			(xy 125.448493 -289.576456) (xy 125.434852 -289.576002) (xy 125.319536 -289.576002) (xy 125.305904 -289.576446)
			(xy 125.279615 -289.583673) (xy 125.256173 -289.597594) (xy 125.237247 -289.617219) (xy 125.224185 -289.64115)
			(xy 125.217916 -289.667684) (xy 125.218887 -289.694931) (xy 125.222508 -289.708082) (xy 125.22962 -289.732227)
			(xy 125.237266 -289.781976) (xy 125.237748 -289.807142) (xy 125.237239 -289.833109) (xy 125.229114 -289.884404)
			(xy 125.213066 -289.933797) (xy 125.189488 -289.980071) (xy 125.158962 -290.022087) (xy 125.122239 -290.05881)
			(xy 125.080223 -290.089336) (xy 125.033949 -290.112914) (xy 124.984556 -290.128962) (xy 124.933261 -290.137087)
			(xy 124.881327 -290.137087) (xy 124.830032 -290.128962) (xy 124.780639 -290.112914) (xy 124.734365 -290.089336)
			(xy 124.692349 -290.05881) (xy 124.655626 -290.022087) (xy 124.6251 -289.980071) (xy 124.601522 -289.933797)
			(xy 124.585474 -289.884404) (xy 124.577349 -289.833109) (xy 124.57684 -289.807142) (xy 124.577332 -289.781977)
			(xy 124.584984 -289.732231) (xy 124.59208 -289.708082) (xy 124.595756 -289.694939) (xy 124.596756 -289.667677)
			(xy 124.590497 -289.641124) (xy 124.577427 -289.617178) (xy 124.55848 -289.597551) (xy 124.535009 -289.583646)
			(xy 124.508693 -289.576456) (xy 124.495052 -289.576002) (xy 124.29871 -289.576002) (xy 124.25934 -289.65017)
			(xy 124.2695 -289.672776) (xy 124.278497 -289.694022) (xy 124.291182 -289.738381) (xy 124.297576 -289.784073)
			(xy 124.297948 -289.807142) (xy 124.297439 -289.833109) (xy 124.289314 -289.884404) (xy 124.273266 -289.933797)
			(xy 124.249688 -289.980071) (xy 124.219162 -290.022087) (xy 124.182439 -290.05881) (xy 124.140423 -290.089336)
			(xy 124.094149 -290.112914) (xy 124.044756 -290.128962) (xy 123.993461 -290.137087) (xy 123.941527 -290.137087)
			(xy 123.890232 -290.128962) (xy 123.840839 -290.112914) (xy 123.794565 -290.089336) (xy 123.752549 -290.05881)
			(xy 123.715826 -290.022087) (xy 123.6853 -289.980071) (xy 123.661722 -289.933797) (xy 123.645674 -289.884404)
			(xy 123.637549 -289.833109) (xy 123.63704 -289.807142) (xy 123.637532 -289.781977) (xy 123.645184 -289.732231)
			(xy 123.65228 -289.708082) (xy 123.655956 -289.694939) (xy 123.656956 -289.667677) (xy 123.650697 -289.641124)
			(xy 123.637627 -289.617178) (xy 123.61868 -289.597551) (xy 123.595209 -289.583646) (xy 123.568893 -289.576456)
			(xy 123.555252 -289.576002) (xy 123.439936 -289.576002) (xy 123.426304 -289.576446) (xy 123.400015 -289.583673)
			(xy 123.376573 -289.597594) (xy 123.357647 -289.617219) (xy 123.344585 -289.64115) (xy 123.338316 -289.667684)
			(xy 123.339287 -289.694931) (xy 123.342908 -289.708082) (xy 123.35002 -289.732227) (xy 123.357666 -289.781976)
			(xy 123.358148 -289.807142) (xy 123.357639 -289.833109) (xy 123.349514 -289.884404) (xy 123.333466 -289.933797)
			(xy 123.309888 -289.980071) (xy 123.279362 -290.022087) (xy 123.242639 -290.05881) (xy 123.200623 -290.089336)
			(xy 123.154349 -290.112914) (xy 123.104956 -290.128962) (xy 123.053661 -290.137087) (xy 123.001727 -290.137087)
			(xy 122.950432 -290.128962) (xy 122.901039 -290.112914) (xy 122.854765 -290.089336) (xy 122.812749 -290.05881)
			(xy 122.776026 -290.022087) (xy 122.7455 -289.980071) (xy 122.721922 -289.933797) (xy 122.705874 -289.884404)
			(xy 122.697749 -289.833109) (xy 122.69724 -289.807142) (xy 122.697732 -289.781977) (xy 122.705384 -289.732231)
			(xy 122.71248 -289.708082) (xy 122.716156 -289.694939) (xy 122.717156 -289.667677) (xy 122.710897 -289.641124)
			(xy 122.697827 -289.617178) (xy 122.67888 -289.597551) (xy 122.655409 -289.583646) (xy 122.629093 -289.576456)
			(xy 122.615452 -289.576002) (xy 122.41911 -289.576002) (xy 122.37974 -289.65017) (xy 122.3899 -289.672776)
			(xy 122.398897 -289.694022) (xy 122.411582 -289.738381) (xy 122.417976 -289.784073) (xy 122.418348 -289.807142)
			(xy 122.417839 -289.833109) (xy 122.409714 -289.884404) (xy 122.393666 -289.933797) (xy 122.370088 -289.980071)
			(xy 122.339562 -290.022087) (xy 122.302839 -290.05881) (xy 122.260823 -290.089336) (xy 122.214549 -290.112914)
			(xy 122.165156 -290.128962) (xy 122.113861 -290.137087) (xy 122.061927 -290.137087) (xy 122.010632 -290.128962)
			(xy 121.961239 -290.112914) (xy 121.914965 -290.089336) (xy 121.872949 -290.05881) (xy 121.836226 -290.022087)
			(xy 121.8057 -289.980071) (xy 121.782122 -289.933797) (xy 121.766074 -289.884404) (xy 121.757949 -289.833109)
			(xy 121.75744 -289.807142) (xy 121.757921 -289.781599) (xy 121.765791 -289.731122) (xy 121.781337 -289.682457)
			(xy 121.804186 -289.636765) (xy 121.833795 -289.595133) (xy 121.869458 -289.558554) (xy 121.910325 -289.527899)
			(xy 121.955423 -289.503899) (xy 122.003678 -289.487124) (xy 122.028712 -289.482022) (xy 122.052842 -289.477704)
			(xy 122.095768 -289.396678) (xy 121.852944 -289.153854) (xy 121.817638 -289.180524) (xy 121.795987 -289.196293)
			(xy 121.748647 -289.221346) (xy 121.697884 -289.238425) (xy 121.645028 -289.247082) (xy 121.618248 -289.24758)
			(xy 121.592275 -289.247101) (xy 121.540969 -289.238982) (xy 121.491564 -289.222937) (xy 121.445278 -289.19936)
			(xy 121.40325 -289.168832) (xy 121.366516 -289.132106) (xy 121.335979 -289.090085) (xy 121.312392 -289.043804)
			(xy 121.296335 -288.994403) (xy 121.288205 -288.943098) (xy 121.287794 -288.917126) (xy 121.288405 -288.889145)
			(xy 121.297852 -288.833986) (xy 121.30659 -288.807398) (xy 121.31421 -288.7853) (xy 121.110502 -288.43224)
			(xy 121.087388 -288.427922) (xy 121.061405 -288.422523) (xy 121.011476 -288.404546) (xy 120.965065 -288.378815)
			(xy 120.923368 -288.345992) (xy 120.887458 -288.306922) (xy 120.85826 -288.26261) (xy 120.836525 -288.214199)
			(xy 120.822814 -288.162935) (xy 120.819672 -288.136584) (xy 120.817894 -288.118804) (xy 120.711722 -288.012632)
			(xy 120.701823 -288.003391) (xy 120.678281 -287.990027) (xy 120.652054 -287.98332) (xy 120.624986 -287.983743)
			(xy 120.598981 -287.991265) (xy 120.575868 -288.005359) (xy 120.557272 -288.025031) (xy 120.544501 -288.0489)
			(xy 120.538453 -288.075287) (xy 120.538494 -288.088832) (xy 120.538748 -288.103056) (xy 120.538269 -288.129026)
			(xy 120.53015 -288.180326) (xy 120.514106 -288.229725) (xy 120.490532 -288.276006) (xy 120.460008 -288.318029)
			(xy 120.423286 -288.354759) (xy 120.38127 -288.385293) (xy 120.334995 -288.408878) (xy 120.285599 -288.424933)
			(xy 120.234301 -288.433063) (xy 120.182362 -288.433068) (xy 120.131062 -288.424947) (xy 120.081663 -288.408902)
			(xy 120.035384 -288.385326) (xy 119.993362 -288.3548) (xy 119.956633 -288.318076) (xy 119.926101 -288.276059)
			(xy 119.902518 -288.229783) (xy 119.886464 -288.180387) (xy 119.878336 -288.129088) (xy 119.878333 -288.077149)
			(xy 119.886456 -288.025849) (xy 119.902503 -287.976452) (xy 119.926081 -287.930173) (xy 119.956608 -287.888152)
			(xy 119.993333 -287.851424) (xy 120.035352 -287.820894) (xy 120.081629 -287.797313) (xy 120.131025 -287.781261)
			(xy 120.182325 -287.773135) (xy 120.208294 -287.772602) (xy 120.222518 -287.772856) (xy 120.236082 -287.773014)
			(xy 120.262524 -287.767007) (xy 120.28645 -287.754246) (xy 120.30617 -287.735634) (xy 120.320291 -287.712485)
			(xy 120.327814 -287.686433) (xy 120.32821 -287.65932) (xy 120.32145 -287.63306) (xy 120.308012 -287.609508)
			(xy 120.298718 -287.599628) (xy 120.164352 -287.465262) (xy 120.153539 -287.455146) (xy 120.127499 -287.441078)
			(xy 120.098518 -287.43507) (xy 120.069031 -287.437627) (xy 120.041516 -287.448533) (xy 120.018285 -287.466872)
			(xy 120.009412 -287.478724) (xy 119.993816 -287.500103) (xy 119.956955 -287.53807) (xy 119.914515 -287.569677)
			(xy 119.867579 -287.594115) (xy 119.817348 -287.61076) (xy 119.765106 -287.619186) (xy 119.738648 -287.619694)
			(xy 119.712675 -287.619215) (xy 119.661368 -287.611096) (xy 119.611962 -287.595051) (xy 119.565675 -287.571474)
			(xy 119.523646 -287.540947) (xy 119.48691 -287.504221) (xy 119.456372 -287.4622) (xy 119.432783 -287.415919)
			(xy 119.416725 -287.366518) (xy 119.408592 -287.315213) (xy 119.408194 -287.28924) (xy 119.408719 -287.262784)
			(xy 119.417156 -287.210549) (xy 119.433806 -287.160324) (xy 119.458242 -287.113392) (xy 119.489841 -287.070952)
			(xy 119.527797 -287.034086) (xy 119.549164 -287.018476) (xy 119.560968 -287.009553) (xy 119.579271 -286.986317)
			(xy 119.59016 -286.958816) (xy 119.592726 -286.929349) (xy 119.586755 -286.90038) (xy 119.572746 -286.87433)
			(xy 119.562626 -286.863536) (xy 119.451882 -286.752792) (xy 119.419116 -286.76981) (xy 119.395706 -286.781196)
			(xy 119.346195 -286.797274) (xy 119.294776 -286.805394) (xy 119.268748 -286.805878) (xy 119.242776 -286.805399)
			(xy 119.191469 -286.79728) (xy 119.142065 -286.781235) (xy 119.095779 -286.757658) (xy 119.053751 -286.72713)
			(xy 119.017016 -286.690404) (xy 118.98648 -286.648383) (xy 118.962893 -286.602102) (xy 118.946837 -286.552701)
			(xy 118.938707 -286.501396) (xy 118.938294 -286.475424) (xy 118.938764 -286.449395) (xy 118.946892 -286.397978)
			(xy 118.962982 -286.34847) (xy 118.974362 -286.325056) (xy 118.99138 -286.29229) (xy 118.660926 -285.961836)
			(xy 118.653306 -285.958026) (xy 118.629111 -285.94554) (xy 118.584823 -285.913875) (xy 118.546326 -285.875379)
			(xy 118.514662 -285.831091) (xy 118.502176 -285.806896) (xy 118.498366 -285.799276) (xy 118.065804 -285.366714)
			(xy 118.065804 -285.047436) (xy 118.049973 -285.025738) (xy 118.02482 -284.978283) (xy 118.007673 -284.927385)
			(xy 117.998982 -284.874385) (xy 117.998977 -284.820676) (xy 118.007658 -284.767674) (xy 118.024796 -284.716773)
			(xy 118.049941 -284.669314) (xy 118.065804 -284.64764) (xy 118.065804 -283.419804) (xy 118.049976 -283.398105)
			(xy 118.024829 -283.350652) (xy 118.007686 -283.299756) (xy 117.999 -283.246757) (xy 117.998999 -283.193052)
			(xy 118.007684 -283.140054) (xy 118.024825 -283.089157) (xy 118.049971 -283.041703) (xy 118.065804 -283.020008)
			(xy 118.065804 -282.824936) (xy 118.065274 -282.809521) (xy 118.056095 -282.780091) (xy 118.038559 -282.754735)
			(xy 118.014263 -282.735758) (xy 117.985414 -282.724888) (xy 117.954637 -282.723111) (xy 117.939566 -282.726384)
			(xy 117.91976 -282.73102) (xy 117.879387 -282.735985) (xy 117.859048 -282.73629) (xy 117.833073 -282.735811)
			(xy 117.781763 -282.727691) (xy 117.732355 -282.711643) (xy 117.686065 -282.688064) (xy 117.644035 -282.657532)
			(xy 117.607299 -282.620802) (xy 117.576761 -282.578776) (xy 117.553175 -282.53249) (xy 117.53712 -282.483084)
			(xy 117.528993 -282.431775) (xy 117.528993 -282.379825) (xy 117.53712 -282.328516) (xy 117.553175 -282.27911)
			(xy 117.576761 -282.232824) (xy 117.607299 -282.190798) (xy 117.644035 -282.154068) (xy 117.686065 -282.123536)
			(xy 117.732355 -282.099957) (xy 117.781763 -282.083909) (xy 117.833073 -282.075789) (xy 117.859048 -282.075382)
			(xy 117.879388 -282.075668) (xy 117.919762 -282.08064) (xy 117.939566 -282.085288) (xy 117.954645 -282.088505)
			(xy 117.985412 -282.086728) (xy 118.014253 -282.075864) (xy 118.038546 -282.056901) (xy 118.056086 -282.031561)
			(xy 118.065279 -282.002145) (xy 118.065804 -281.986736) (xy 118.065804 -281.792172) (xy 118.049919 -281.770461)
			(xy 118.024674 -281.722959) (xy 118.007463 -281.671994) (xy 117.998741 -281.618912) (xy 117.998738 -281.565119)
			(xy 118.007455 -281.512037) (xy 118.024662 -281.46107) (xy 118.049902 -281.413566) (xy 118.065804 -281.391868)
			(xy 118.065804 -281.197304) (xy 118.06527 -281.181893) (xy 118.056085 -281.152471) (xy 118.038549 -281.127123)
			(xy 118.014255 -281.108154) (xy 117.985412 -281.097287) (xy 117.954641 -281.09551) (xy 117.939566 -281.098752)
			(xy 117.91976 -281.103387) (xy 117.879387 -281.108351) (xy 117.859048 -281.108658) (xy 117.833076 -281.108179)
			(xy 117.78177 -281.10006) (xy 117.732367 -281.084014) (xy 117.686082 -281.060436) (xy 117.644056 -281.029908)
			(xy 117.607323 -280.993181) (xy 117.576789 -280.951159) (xy 117.553205 -280.904878) (xy 117.537152 -280.855476)
			(xy 117.529025 -280.804172) (xy 117.529025 -280.752228) (xy 117.537152 -280.700924) (xy 117.553205 -280.651522)
			(xy 117.576789 -280.605241) (xy 117.607323 -280.563219) (xy 117.644056 -280.526492) (xy 117.686082 -280.495964)
			(xy 117.732367 -280.472386) (xy 117.78177 -280.45634) (xy 117.833076 -280.448221) (xy 117.859048 -280.44775)
			(xy 117.879388 -280.448036) (xy 117.919762 -280.453007) (xy 117.939566 -280.457656) (xy 117.954644 -280.460873)
			(xy 117.985408 -280.459097) (xy 118.014245 -280.448233) (xy 118.038534 -280.429268) (xy 118.056068 -280.403927)
			(xy 118.065252 -280.374512) (xy 118.065804 -280.359104) (xy 118.065804 -280.164286) (xy 118.049918 -280.142575)
			(xy 118.024671 -280.095073) (xy 118.007457 -280.044107) (xy 117.998733 -279.991024) (xy 117.998729 -279.93723)
			(xy 118.007444 -279.884146) (xy 118.024649 -279.833177) (xy 118.049889 -279.785671) (xy 118.065804 -279.763982)
			(xy 118.065804 -279.569418) (xy 118.065272 -279.554005) (xy 118.056089 -279.52458) (xy 118.038553 -279.499228)
			(xy 118.014259 -279.480256) (xy 117.985413 -279.469387) (xy 117.954639 -279.467611) (xy 117.939566 -279.470866)
			(xy 117.91976 -279.475501) (xy 117.879387 -279.480465) (xy 117.859048 -279.480772) (xy 117.833075 -279.480293)
			(xy 117.781767 -279.472173) (xy 117.732361 -279.456127) (xy 117.686075 -279.432548) (xy 117.644047 -279.402019)
			(xy 117.607312 -279.36529) (xy 117.576777 -279.323266) (xy 117.553192 -279.276983) (xy 117.537138 -279.22758)
			(xy 117.529011 -279.176273) (xy 117.529011 -279.124327) (xy 117.537138 -279.07302) (xy 117.553192 -279.023617)
			(xy 117.576777 -278.977334) (xy 117.607312 -278.93531) (xy 117.644047 -278.898581) (xy 117.686075 -278.868052)
			(xy 117.732361 -278.844473) (xy 117.781767 -278.828427) (xy 117.833075 -278.820307) (xy 117.859048 -278.819864)
			(xy 117.879388 -278.82015) (xy 117.919762 -278.825121) (xy 117.939566 -278.82977) (xy 117.954644 -278.832987)
			(xy 117.98541 -278.83121) (xy 118.014248 -278.820346) (xy 118.038539 -278.801382) (xy 118.056076 -278.776042)
			(xy 118.065264 -278.746626) (xy 118.065804 -278.731218) (xy 118.065804 -278.5364) (xy 118.049917 -278.514688)
			(xy 118.024668 -278.467186) (xy 118.007452 -278.416219) (xy 117.998726 -278.363136) (xy 117.998719 -278.30934)
			(xy 118.007433 -278.256255) (xy 118.024637 -278.205284) (xy 118.049876 -278.157776) (xy 118.065804 -278.136096)
			(xy 118.065804 -277.941278) (xy 118.065266 -277.92587) (xy 118.056077 -277.896455) (xy 118.03854 -277.871114)
			(xy 118.014249 -277.852151) (xy 117.98541 -277.841287) (xy 117.954645 -277.83951) (xy 117.939566 -277.842726)
			(xy 117.91976 -277.847361) (xy 117.879387 -277.852326) (xy 117.859048 -277.852632) (xy 117.833078 -277.852153)
			(xy 117.781776 -277.844034) (xy 117.732377 -277.82799) (xy 117.686096 -277.804414) (xy 117.644073 -277.773888)
			(xy 117.607343 -277.737164) (xy 117.576811 -277.695145) (xy 117.553229 -277.648868) (xy 117.537177 -277.59947)
			(xy 117.529051 -277.54817) (xy 117.529051 -277.49623) (xy 117.537177 -277.44493) (xy 117.553229 -277.395532)
			(xy 117.576811 -277.349255) (xy 117.607343 -277.307236) (xy 117.644073 -277.270512) (xy 117.686096 -277.239986)
			(xy 117.732377 -277.21641) (xy 117.781776 -277.200366) (xy 117.833078 -277.192247) (xy 117.859048 -277.191724)
			(xy 117.879388 -277.19201) (xy 117.919762 -277.196982) (xy 117.939566 -277.20163) (xy 117.954642 -277.204848)
			(xy 117.985405 -277.203072) (xy 118.014239 -277.192207) (xy 118.038524 -277.173242) (xy 118.056053 -277.1479)
			(xy 118.065231 -277.118485) (xy 118.065804 -277.103078) (xy 118.065804 -276.908514) (xy 118.049924 -276.886803)
			(xy 118.024688 -276.839303) (xy 118.007486 -276.78834) (xy 117.998772 -276.735264) (xy 117.998777 -276.681476)
			(xy 118.007501 -276.628401) (xy 118.024712 -276.577442) (xy 118.049957 -276.529946) (xy 118.065804 -276.50821)
			(xy 118.065804 -276.3139) (xy 118.065267 -276.298462) (xy 118.056058 -276.268991) (xy 118.038478 -276.243607)
			(xy 118.014127 -276.224623) (xy 117.985222 -276.213766) (xy 117.954395 -276.212023) (xy 117.939312 -276.215348)
			(xy 117.919506 -276.219986) (xy 117.879133 -276.224956) (xy 117.858794 -276.225254) (xy 117.832827 -276.224744)
			(xy 117.781533 -276.216619) (xy 117.732141 -276.20057) (xy 117.685868 -276.176992) (xy 117.643853 -276.146466)
			(xy 117.60713 -276.109743) (xy 117.576605 -276.067727) (xy 117.553028 -276.021453) (xy 117.536979 -275.972061)
			(xy 117.528855 -275.920767) (xy 117.528855 -275.868833) (xy 117.536979 -275.817539) (xy 117.553028 -275.768147)
			(xy 117.576605 -275.721873) (xy 117.60713 -275.679857) (xy 117.643853 -275.643134) (xy 117.685868 -275.612608)
			(xy 117.732141 -275.58903) (xy 117.781533 -275.572981) (xy 117.832827 -275.564856) (xy 117.858794 -275.564346)
			(xy 117.879134 -275.564628) (xy 117.91951 -275.569593) (xy 117.939312 -275.574252) (xy 117.954407 -275.577512)
			(xy 117.985225 -275.575796) (xy 118.014125 -275.564955) (xy 118.03847 -275.54598) (xy 118.056037 -275.520601)
			(xy 118.065225 -275.491134) (xy 118.065804 -275.4757) (xy 118.065804 -275.280628) (xy 118.049975 -275.258929)
			(xy 118.024823 -275.211475) (xy 118.007676 -275.160578) (xy 117.998987 -275.107578) (xy 117.998983 -275.05387)
			(xy 118.007665 -275.000869) (xy 118.024804 -274.949969) (xy 118.049949 -274.902511) (xy 118.065804 -274.880832)
			(xy 118.065804 -274.686014) (xy 118.065271 -274.670602) (xy 118.056088 -274.641177) (xy 118.038552 -274.615827)
			(xy 118.014258 -274.596855) (xy 117.985413 -274.585987) (xy 117.95464 -274.58421) (xy 117.939566 -274.587462)
			(xy 117.91976 -274.592097) (xy 117.879387 -274.597061) (xy 117.859048 -274.597368) (xy 117.833075 -274.596889)
			(xy 117.781768 -274.588769) (xy 117.732363 -274.572723) (xy 117.686077 -274.549145) (xy 117.644049 -274.518616)
			(xy 117.607315 -274.481887) (xy 117.57678 -274.439864) (xy 117.553195 -274.393581) (xy 117.537142 -274.344179)
			(xy 117.529015 -274.292873) (xy 117.529015 -274.240927) (xy 117.537142 -274.189621) (xy 117.553195 -274.140219)
			(xy 117.57678 -274.093936) (xy 117.607315 -274.051913) (xy 117.644049 -274.015184) (xy 117.686077 -273.984655)
			(xy 117.732363 -273.961077) (xy 117.781768 -273.945031) (xy 117.833075 -273.936911) (xy 117.859048 -273.93646)
			(xy 117.879388 -273.936746) (xy 117.919762 -273.941717) (xy 117.939566 -273.946366) (xy 117.954644 -273.949583)
			(xy 117.985409 -273.947806) (xy 118.014247 -273.936942) (xy 118.038538 -273.917978) (xy 118.056073 -273.892637)
			(xy 118.065261 -273.863222) (xy 118.065804 -273.847814) (xy 118.065804 -273.652996) (xy 118.049977 -273.631297)
			(xy 118.02483 -273.583844) (xy 118.007689 -273.532948) (xy 117.999004 -273.479951) (xy 117.999004 -273.426246)
			(xy 118.00769 -273.373249) (xy 118.024832 -273.322353) (xy 118.049979 -273.2749) (xy 118.065804 -273.2532)
			(xy 118.065804 -273.058382) (xy 118.065264 -273.042946) (xy 118.056052 -273.013479) (xy 118.038472 -272.988101)
			(xy 118.014123 -272.969121) (xy 117.985221 -272.958265) (xy 117.954397 -272.956523) (xy 117.939312 -272.95983)
			(xy 117.919506 -272.964468) (xy 117.879133 -272.969438) (xy 117.858794 -272.969736) (xy 117.832829 -272.969226)
			(xy 117.781537 -272.961102) (xy 117.732148 -272.945053) (xy 117.685877 -272.921477) (xy 117.643865 -272.890952)
			(xy 117.607144 -272.854231) (xy 117.57662 -272.812218) (xy 117.553044 -272.765947) (xy 117.536997 -272.716557)
			(xy 117.528873 -272.665266) (xy 117.528873 -272.613334) (xy 117.536997 -272.562043) (xy 117.553044 -272.512653)
			(xy 117.57662 -272.466382) (xy 117.607144 -272.424369) (xy 117.643865 -272.387648) (xy 117.685877 -272.357123)
			(xy 117.732148 -272.333547) (xy 117.781537 -272.317498) (xy 117.832829 -272.309374) (xy 117.858794 -272.308828)
			(xy 117.879134 -272.30911) (xy 117.91951 -272.314077) (xy 117.939312 -272.318734) (xy 117.954411 -272.321992)
			(xy 117.985236 -272.320275) (xy 118.014144 -272.309436) (xy 118.0385 -272.290464) (xy 118.056084 -272.265087)
			(xy 118.065293 -272.235619) (xy 118.065804 -272.220182) (xy 118.065804 -272.025872) (xy 118.049865 -272.004112)
			(xy 118.024529 -271.956496) (xy 118.007255 -271.9054) (xy 117.998502 -271.852178) (xy 117.9985 -271.798241)
			(xy 118.007251 -271.745019) (xy 118.024521 -271.693922) (xy 118.049854 -271.646304) (xy 118.065804 -271.624552)
			(xy 118.065804 -271.430496) (xy 118.065266 -271.415058) (xy 118.056056 -271.385588) (xy 118.038476 -271.360206)
			(xy 118.014126 -271.341222) (xy 117.985222 -271.330365) (xy 117.954395 -271.328623) (xy 117.939312 -271.331944)
			(xy 117.919506 -271.336582) (xy 117.879133 -271.341552) (xy 117.858794 -271.34185) (xy 117.832827 -271.34134)
			(xy 117.781534 -271.333215) (xy 117.732143 -271.317166) (xy 117.68587 -271.293589) (xy 117.643856 -271.263063)
			(xy 117.607134 -271.22634) (xy 117.576608 -271.184325) (xy 117.553031 -271.138052) (xy 117.536983 -271.08866)
			(xy 117.528859 -271.037367) (xy 117.528859 -270.985433) (xy 117.536983 -270.93414) (xy 117.553031 -270.884748)
			(xy 117.576608 -270.838475) (xy 117.607134 -270.79646) (xy 117.643856 -270.759737) (xy 117.68587 -270.729211)
			(xy 117.732143 -270.705634) (xy 117.781534 -270.689585) (xy 117.832827 -270.68146) (xy 117.858794 -270.680942)
			(xy 117.879134 -270.681224) (xy 117.91951 -270.686189) (xy 117.939312 -270.690848) (xy 117.954406 -270.694108)
			(xy 117.985224 -270.692392) (xy 118.014124 -270.681551) (xy 118.038468 -270.662576) (xy 118.056035 -270.637197)
			(xy 118.065222 -270.60773) (xy 118.065804 -270.592296) (xy 118.065804 -270.397478) (xy 118.049979 -270.375779)
			(xy 118.024835 -270.328326) (xy 118.007696 -270.277432) (xy 117.999014 -270.224436) (xy 117.999016 -270.170733)
			(xy 118.007704 -270.117737) (xy 118.024847 -270.066844) (xy 118.049996 -270.019394) (xy 118.065804 -269.997682)
			(xy 118.065804 -269.80261) (xy 118.065271 -269.787198) (xy 118.056087 -269.757775) (xy 118.038551 -269.732425)
			(xy 118.014257 -269.713455) (xy 117.985412 -269.702587) (xy 117.95464 -269.70081) (xy 117.939566 -269.704058)
			(xy 117.91976 -269.708693) (xy 117.879387 -269.713657) (xy 117.859048 -269.713964) (xy 117.833075 -269.713485)
			(xy 117.781769 -269.705365) (xy 117.732365 -269.689319) (xy 117.686079 -269.665742) (xy 117.644052 -269.635213)
			(xy 117.607319 -269.598485) (xy 117.576784 -269.556462) (xy 117.553199 -269.51018) (xy 117.537146 -269.460778)
			(xy 117.529019 -269.409472) (xy 117.529019 -269.357528) (xy 117.537146 -269.306222) (xy 117.553199 -269.25682)
			(xy 117.576784 -269.210538) (xy 117.607319 -269.168515) (xy 117.644052 -269.131787) (xy 117.686079 -269.101258)
			(xy 117.732365 -269.077681) (xy 117.781769 -269.061635) (xy 117.833075 -269.053515) (xy 117.859048 -269.053056)
			(xy 117.879388 -269.053342) (xy 117.919762 -269.058313) (xy 117.939566 -269.062962) (xy 117.954644 -269.066179)
			(xy 117.985409 -269.064403) (xy 118.014247 -269.053538) (xy 118.038536 -269.034574) (xy 118.056071 -269.009233)
			(xy 118.065257 -268.979818) (xy 118.065804 -268.96441) (xy 118.065804 -268.769592) (xy 118.049977 -268.747893)
			(xy 118.024831 -268.70044) (xy 118.007691 -268.649545) (xy 117.999006 -268.596547) (xy 117.999007 -268.542843)
			(xy 118.007693 -268.489846) (xy 118.024835 -268.438951) (xy 118.049983 -268.391499) (xy 118.065804 -268.369796)
			(xy 118.065804 -268.174978) (xy 118.065264 -268.159542) (xy 118.056051 -268.130077) (xy 118.03847 -268.1047)
			(xy 118.014122 -268.08572) (xy 117.985221 -268.074865) (xy 117.954398 -268.073123) (xy 117.939312 -268.076426)
			(xy 117.919506 -268.081064) (xy 117.879133 -268.086034) (xy 117.858794 -268.086332) (xy 117.832829 -268.085822)
			(xy 117.781538 -268.077698) (xy 117.732149 -268.06165) (xy 117.685879 -268.038073) (xy 117.643867 -268.007549)
			(xy 117.607147 -267.970828) (xy 117.576624 -267.928815) (xy 117.553048 -267.882545) (xy 117.537001 -267.833156)
			(xy 117.528877 -267.781865) (xy 117.528877 -267.729935) (xy 117.537001 -267.678644) (xy 117.553048 -267.629255)
			(xy 117.576624 -267.582985) (xy 117.607147 -267.540972) (xy 117.643867 -267.504251) (xy 117.685879 -267.473727)
			(xy 117.732149 -267.45015) (xy 117.781538 -267.434102) (xy 117.832829 -267.425978) (xy 117.858794 -267.425424)
			(xy 117.879134 -267.425706) (xy 117.91951 -267.430673) (xy 117.939312 -267.43533) (xy 117.95441 -267.438588)
			(xy 117.985236 -267.436871) (xy 118.014143 -267.426032) (xy 118.038499 -267.40706) (xy 118.056082 -267.381683)
			(xy 118.06529 -267.352215) (xy 118.065804 -267.336778) (xy 118.065804 -267.142468) (xy 118.049865 -267.120708)
			(xy 118.02453 -267.073092) (xy 118.007257 -267.021996) (xy 117.998504 -266.968775) (xy 117.998503 -266.914838)
			(xy 118.007254 -266.861616) (xy 118.024525 -266.81052) (xy 118.049858 -266.762903) (xy 118.065804 -266.741148)
			(xy 118.065804 -266.547346) (xy 118.065259 -266.531914) (xy 118.056041 -266.502457) (xy 118.03846 -266.477088)
			(xy 118.014114 -266.458116) (xy 117.985219 -266.447265) (xy 117.954402 -266.445522) (xy 117.939312 -266.448794)
			(xy 117.919507 -266.453433) (xy 117.879133 -266.458403) (xy 117.858794 -266.4587) (xy 117.832823 -266.45819)
			(xy 117.781522 -266.450064) (xy 117.732123 -266.434013) (xy 117.685844 -266.410431) (xy 117.643823 -266.379901)
			(xy 117.607096 -266.343172) (xy 117.576566 -266.301151) (xy 117.552985 -266.254871) (xy 117.536935 -266.205472)
			(xy 117.528809 -266.154171) (xy 117.528809 -266.102229) (xy 117.536935 -266.050928) (xy 117.552985 -266.001529)
			(xy 117.576566 -265.955249) (xy 117.607096 -265.913228) (xy 117.643823 -265.876499) (xy 117.685844 -265.845969)
			(xy 117.732123 -265.822387) (xy 117.781522 -265.806336) (xy 117.832823 -265.79821) (xy 117.858794 -265.797792)
			(xy 117.879134 -265.798074) (xy 117.91951 -265.80304) (xy 117.939312 -265.807698) (xy 117.954409 -265.810957)
			(xy 117.985231 -265.80924) (xy 118.014136 -265.7984) (xy 118.038487 -265.779427) (xy 118.056063 -265.754049)
			(xy 118.065263 -265.724581) (xy 118.065804 -265.709146) (xy 118.065804 -265.514328) (xy 118.049919 -265.492618)
			(xy 118.024673 -265.445118) (xy 118.007463 -265.394153) (xy 117.998744 -265.341072) (xy 117.99824 -265.314176)
			(xy 117.998693 -265.289289) (xy 118.006161 -265.240078) (xy 118.020925 -265.192544) (xy 118.042651 -265.147762)
			(xy 118.070848 -265.106745) (xy 118.104877 -265.07042) (xy 118.143969 -265.03961) (xy 118.165372 -265.026902)
			(xy 118.19128 -265.01217) (xy 118.19128 -264.94867) (xy 118.498112 -264.641584) (xy 118.487444 -264.611358)
			(xy 118.478458 -264.584492) (xy 118.468752 -264.528683) (xy 118.46814 -264.50036) (xy 118.468652 -264.474395)
			(xy 118.476781 -264.423104) (xy 118.492834 -264.373717) (xy 118.516413 -264.327448) (xy 118.54694 -264.285437)
			(xy 118.583663 -264.248718) (xy 118.625677 -264.218196) (xy 118.671948 -264.194621) (xy 118.721337 -264.178574)
			(xy 118.772629 -264.17045) (xy 118.798594 -264.169906) (xy 118.829328 -264.17143) (xy 118.843437 -264.172276)
			(xy 118.871207 -264.167077) (xy 118.896493 -264.154472) (xy 118.91736 -264.135426) (xy 118.932215 -264.111393)
			(xy 118.93992 -264.084211) (xy 118.940326 -264.070084) (xy 118.940326 -263.779254) (xy 118.939892 -263.765676)
			(xy 118.932728 -263.739481) (xy 118.918918 -263.716097) (xy 118.899438 -263.697176) (xy 118.875662 -263.684053)
			(xy 118.84927 -263.677654) (xy 118.822124 -263.678433) (xy 118.809008 -263.681972) (xy 118.785451 -263.688724)
			(xy 118.73699 -263.695997) (xy 118.712488 -263.69645) (xy 118.686522 -263.69594) (xy 118.635229 -263.687814)
			(xy 118.585838 -263.671765) (xy 118.539567 -263.648187) (xy 118.497553 -263.61766) (xy 118.460832 -263.580938)
			(xy 118.430307 -263.538923) (xy 118.406731 -263.492651) (xy 118.390683 -263.44326) (xy 118.382559 -263.391966)
			(xy 118.382559 -263.340034) (xy 118.390683 -263.28874) (xy 118.406731 -263.239349) (xy 118.430307 -263.193077)
			(xy 118.460832 -263.151062) (xy 118.497553 -263.11434) (xy 118.539567 -263.083813) (xy 118.585838 -263.060235)
			(xy 118.635229 -263.044186) (xy 118.686522 -263.03606) (xy 118.712488 -263.035542) (xy 118.736989 -263.036006)
			(xy 118.78545 -263.043274) (xy 118.809008 -263.05002) (xy 118.82213 -263.053594) (xy 118.849302 -263.054422)
			(xy 118.87573 -263.048049) (xy 118.899537 -263.034925) (xy 118.919036 -263.015982) (xy 118.932842 -262.992563)
			(xy 118.939977 -262.966331) (xy 118.940326 -262.952738) (xy 118.940326 -260.193282) (xy 119.988838 -259.14477)
			(xy 119.988838 -258.07543) (xy 119.988317 -258.060491) (xy 119.979678 -258.03189) (xy 119.96313 -258.007014)
			(xy 119.940089 -257.987993) (xy 119.91253 -257.976455) (xy 119.88281 -257.973387) (xy 119.853475 -257.979054)
			(xy 119.839994 -257.985514) (xy 119.816086 -257.997517) (xy 119.765359 -258.014499) (xy 119.712563 -258.023111)
			(xy 119.685816 -258.023614) (xy 119.661289 -258.023167) (xy 119.612774 -258.015913) (xy 119.565867 -258.001561)
			(xy 119.521598 -257.980428) (xy 119.480943 -257.952978) (xy 119.46255 -257.936746) (xy 119.450965 -257.926901)
			(xy 119.423508 -257.913885) (xy 119.393436 -257.909529) (xy 119.363415 -257.914217) (xy 119.336103 -257.927535)
			(xy 119.324628 -257.937508) (xy 119.306172 -257.954081) (xy 119.265226 -257.982076) (xy 119.220559 -258.003645)
			(xy 119.173174 -258.018306) (xy 119.124131 -258.025729) (xy 119.09933 -258.026154) (xy 119.074975 -258.025722)
			(xy 119.026793 -258.018576) (xy 118.980182 -258.004435) (xy 118.936152 -257.983605) (xy 118.895656 -257.956536)
			(xy 118.859573 -257.923817) (xy 118.843806 -257.90525) (xy 118.833949 -257.893992) (xy 118.809147 -257.877278)
			(xy 118.780566 -257.868467) (xy 118.750658 -257.868315) (xy 118.721989 -257.876836) (xy 118.697019 -257.893297)
			(xy 118.687088 -257.904488) (xy 118.671297 -257.922771) (xy 118.635318 -257.955007) (xy 118.59503 -257.981663)
			(xy 118.551292 -258.002172) (xy 118.505034 -258.016097) (xy 118.457242 -258.02314) (xy 118.433088 -258.023614)
			(xy 118.407228 -258.023113) (xy 118.356138 -258.015057) (xy 118.306926 -257.999143) (xy 118.260792 -257.975761)
			(xy 118.218862 -257.945479) (xy 118.20017 -257.927602) (xy 118.190455 -257.918557) (xy 118.167446 -257.905345)
			(xy 118.141809 -257.898508) (xy 118.115275 -257.898508) (xy 118.089638 -257.905345) (xy 118.066629 -257.918557)
			(xy 118.056914 -257.927602) (xy 118.038216 -257.945474) (xy 117.996293 -257.975765) (xy 117.950162 -257.999153)
			(xy 117.900948 -258.015063) (xy 117.849857 -258.023109) (xy 117.823996 -258.023614) (xy 117.798032 -258.023105)
			(xy 117.746744 -258.014981) (xy 117.697358 -257.998934) (xy 117.65109 -257.975359) (xy 117.60908 -257.944836)
			(xy 117.572361 -257.908117) (xy 117.541839 -257.866107) (xy 117.518265 -257.819839) (xy 117.502218 -257.770452)
			(xy 117.494095 -257.719164) (xy 117.494095 -257.667236) (xy 117.502218 -257.615948) (xy 117.518265 -257.566561)
			(xy 117.541839 -257.520293) (xy 117.572361 -257.478283) (xy 117.60908 -257.441564) (xy 117.65109 -257.411041)
			(xy 117.697358 -257.387466) (xy 117.746744 -257.371419) (xy 117.798032 -257.363295) (xy 117.823996 -257.362706)
			(xy 117.849857 -257.363206) (xy 117.900948 -257.37126) (xy 117.950161 -257.387173) (xy 117.996295 -257.410555)
			(xy 118.038226 -257.440836) (xy 118.056914 -257.458718) (xy 118.066629 -257.467763) (xy 118.089638 -257.480975)
			(xy 118.115275 -257.487812) (xy 118.141809 -257.487812) (xy 118.167446 -257.480975) (xy 118.190455 -257.467763)
			(xy 118.20017 -257.458718) (xy 118.218867 -257.440844) (xy 118.260789 -257.410549) (xy 118.30692 -257.387158)
			(xy 118.356134 -257.371244) (xy 118.407227 -257.363195) (xy 118.433088 -257.362706) (xy 118.457442 -257.363139)
			(xy 118.505624 -257.370286) (xy 118.552235 -257.384429) (xy 118.596265 -257.405259) (xy 118.63676 -257.432326)
			(xy 118.672845 -257.465044) (xy 118.688612 -257.48361) (xy 118.698467 -257.494869) (xy 118.723266 -257.511585)
			(xy 118.751846 -257.520395) (xy 118.781753 -257.520543) (xy 118.810418 -257.512017) (xy 118.835382 -257.495548)
			(xy 118.84533 -257.484372) (xy 118.86112 -257.466086) (xy 118.897098 -257.433845) (xy 118.937385 -257.407182)
			(xy 118.981123 -257.386665) (xy 119.027381 -257.372731) (xy 119.075175 -257.365676) (xy 119.09933 -257.365246)
			(xy 119.123859 -257.365689) (xy 119.172378 -257.372935) (xy 119.219292 -257.38728) (xy 119.263567 -257.408406)
			(xy 119.30423 -257.43585) (xy 119.322596 -257.452114) (xy 119.334179 -257.461955) (xy 119.361632 -257.474963)
			(xy 119.391697 -257.479311) (xy 119.42171 -257.474612) (xy 119.449008 -257.461283) (xy 119.460518 -257.451352)
			(xy 119.478976 -257.434784) (xy 119.519924 -257.406798) (xy 119.564591 -257.385237) (xy 119.611976 -257.370585)
			(xy 119.661017 -257.363169) (xy 119.685816 -257.362706) (xy 119.712566 -257.363196) (xy 119.765371 -257.371777)
			(xy 119.816097 -257.388777) (xy 119.839994 -257.400806) (xy 119.853458 -257.407283) (xy 119.882783 -257.412923)
			(xy 119.912486 -257.409839) (xy 119.940027 -257.398293) (xy 119.96305 -257.379274) (xy 119.979587 -257.354408)
			(xy 119.988223 -257.325821) (xy 119.988838 -257.31089) (xy 119.988838 -249.89155) (xy 118.401338 -248.30405)
			(xy 118.401338 -246.99087) (xy 118.36146 -246.98198) (xy 118.339452 -246.976734) (xy 118.297023 -246.961026)
			(xy 118.257137 -246.93967) (xy 118.220541 -246.913066) (xy 118.20398 -246.897652) (xy 118.194115 -246.888775)
			(xy 118.170891 -246.87595) (xy 118.14515 -246.869533) (xy 118.118624 -246.869955) (xy 118.0931 -246.877188)
			(xy 118.070296 -246.890745) (xy 118.060724 -246.899938) (xy 118.041943 -246.918519) (xy 117.999565 -246.95006)
			(xy 117.952706 -246.974452) (xy 117.902561 -246.991073) (xy 117.85041 -246.999499) (xy 117.823996 -247.000014)
			(xy 117.798032 -246.999505) (xy 117.746744 -246.991381) (xy 117.697358 -246.975334) (xy 117.65109 -246.951759)
			(xy 117.60908 -246.921236) (xy 117.572361 -246.884517) (xy 117.541839 -246.842507) (xy 117.518265 -246.796239)
			(xy 117.502218 -246.746852) (xy 117.494095 -246.695564) (xy 117.494095 -246.643636) (xy 117.502218 -246.592348)
			(xy 117.518265 -246.542961) (xy 117.541839 -246.496693) (xy 117.572361 -246.454683) (xy 117.60908 -246.417964)
			(xy 117.65109 -246.387441) (xy 117.697358 -246.363866) (xy 117.746744 -246.347819) (xy 117.798032 -246.339695)
			(xy 117.823996 -246.339106) (xy 117.849318 -246.339588) (xy 117.899372 -246.347308) (xy 117.947663 -246.362566)
			(xy 117.993065 -246.385007) (xy 118.034515 -246.414107) (xy 118.053104 -246.431308) (xy 118.062968 -246.44019)
			(xy 118.086192 -246.453024) (xy 118.111937 -246.459448) (xy 118.138468 -246.459028) (xy 118.163996 -246.451794)
			(xy 118.186803 -246.438233) (xy 118.19636 -246.429022) (xy 118.213386 -246.412126) (xy 118.251445 -246.382933)
			(xy 118.293326 -246.359552) (xy 118.338149 -246.342474) (xy 118.36146 -246.33682) (xy 118.401338 -246.32793)
			(xy 118.401338 -245.90883) (xy 120.070372 -244.239796) (xy 120.070372 -239.69218) (xy 120.06986 -239.67734)
			(xy 120.061331 -239.648913) (xy 120.044997 -239.624133) (xy 120.022234 -239.605089) (xy 119.99496 -239.593384)
			(xy 119.965474 -239.590005) (xy 119.936259 -239.595237) (xy 119.922798 -239.601502) (xy 119.899554 -239.612699)
			(xy 119.850457 -239.628544) (xy 119.799495 -239.636571) (xy 119.7737 -239.637062) (xy 119.75049 -239.636673)
			(xy 119.704526 -239.630175) (xy 119.659929 -239.617293) (xy 119.61758 -239.598282) (xy 119.578316 -239.573518)
			(xy 119.56034 -239.55883) (xy 119.548414 -239.549491) (xy 119.520571 -239.537601) (xy 119.490467 -239.534391)
			(xy 119.460743 -239.54014) (xy 119.434007 -239.554345) (xy 119.422926 -239.564672) (xy 119.404221 -239.58259)
			(xy 119.362268 -239.612965) (xy 119.316088 -239.636421) (xy 119.266813 -239.652383) (xy 119.215652 -239.660459)
			(xy 119.189754 -239.660938) (xy 119.16268 -239.660368) (xy 119.109263 -239.651488) (xy 119.058007 -239.634024)
			(xy 119.010282 -239.60844) (xy 118.967363 -239.575422) (xy 118.948454 -239.556036) (xy 118.939104 -239.546682)
			(xy 118.916675 -239.532682) (xy 118.891407 -239.524901) (xy 118.864988 -239.523859) (xy 118.839185 -239.529625)
			(xy 118.815723 -239.541814) (xy 118.805706 -239.550448) (xy 118.787333 -239.56665) (xy 118.746703 -239.594013)
			(xy 118.70248 -239.615081) (xy 118.655633 -239.629393) (xy 118.607186 -239.636635) (xy 118.582694 -239.637062)
			(xy 118.55814 -239.636634) (xy 118.509568 -239.629406) (xy 118.462602 -239.615065) (xy 118.418277 -239.593929)
			(xy 118.377571 -239.566461) (xy 118.359174 -239.550194) (xy 118.347685 -239.540391) (xy 118.320448 -239.527377)
			(xy 118.290594 -239.522909) (xy 118.26074 -239.527377) (xy 118.233503 -239.540391) (xy 118.222014 -239.550194)
			(xy 118.20361 -239.566452) (xy 118.162899 -239.59391) (xy 118.118576 -239.615045) (xy 118.071614 -239.629394)
			(xy 118.023047 -239.63664) (xy 117.998494 -239.637062) (xy 117.97394 -239.636634) (xy 117.925368 -239.629406)
			(xy 117.878402 -239.615065) (xy 117.834077 -239.593929) (xy 117.793371 -239.566461) (xy 117.774974 -239.550194)
			(xy 117.763485 -239.540391) (xy 117.736248 -239.527377) (xy 117.706394 -239.522909) (xy 117.67654 -239.527377)
			(xy 117.649303 -239.540391) (xy 117.637814 -239.550194) (xy 117.61941 -239.566452) (xy 117.578699 -239.59391)
			(xy 117.534376 -239.615045) (xy 117.487414 -239.629394) (xy 117.438847 -239.63664) (xy 117.414294 -239.637062)
			(xy 117.388326 -239.636552) (xy 117.337031 -239.628427) (xy 117.287638 -239.612377) (xy 117.241364 -239.588799)
			(xy 117.199348 -239.558272) (xy 117.162624 -239.521548) (xy 117.132098 -239.479531) (xy 117.10852 -239.433256)
			(xy 117.092472 -239.383863) (xy 117.084347 -239.332568) (xy 117.084347 -239.280632) (xy 117.092472 -239.229337)
			(xy 117.10852 -239.179944) (xy 117.132098 -239.133669) (xy 117.162624 -239.091652) (xy 117.199348 -239.054928)
			(xy 117.241364 -239.024401) (xy 117.287638 -239.000823) (xy 117.337031 -238.984773) (xy 117.388326 -238.976648)
			(xy 117.414294 -238.976154) (xy 117.438848 -238.976581) (xy 117.48742 -238.983808) (xy 117.534387 -238.998148)
			(xy 117.578713 -239.019284) (xy 117.61942 -239.046751) (xy 117.637814 -239.063022) (xy 117.649303 -239.072825)
			(xy 117.67654 -239.085839) (xy 117.706394 -239.090307) (xy 117.736248 -239.085839) (xy 117.763485 -239.072825)
			(xy 117.774974 -239.063022) (xy 117.793379 -239.046768) (xy 117.834092 -239.01932) (xy 117.878416 -238.998195)
			(xy 117.925378 -238.983858) (xy 117.973943 -238.976625) (xy 117.998494 -238.976154) (xy 118.023048 -238.976581)
			(xy 118.07162 -238.983808) (xy 118.118587 -238.998148) (xy 118.162913 -239.019284) (xy 118.20362 -239.046751)
			(xy 118.222014 -239.063022) (xy 118.233503 -239.072825) (xy 118.26074 -239.085839) (xy 118.290594 -239.090307)
			(xy 118.320448 -239.085839) (xy 118.347685 -239.072825) (xy 118.359174 -239.063022) (xy 118.377579 -239.046768)
			(xy 118.418292 -239.01932) (xy 118.462616 -238.998195) (xy 118.509578 -238.983858) (xy 118.558143 -238.976625)
			(xy 118.582694 -238.976154) (xy 118.60977 -238.97672) (xy 118.663192 -238.985592) (xy 118.714453 -239.003051)
			(xy 118.762185 -239.028629) (xy 118.805111 -239.061643) (xy 118.823994 -239.081056) (xy 118.833344 -239.090405)
			(xy 118.85577 -239.104393) (xy 118.881033 -239.112164) (xy 118.907444 -239.113197) (xy 118.933236 -239.107423)
			(xy 118.956686 -239.09523) (xy 118.966742 -239.086644) (xy 118.985116 -239.070445) (xy 119.025747 -239.043089)
			(xy 119.069971 -239.022028) (xy 119.116818 -239.007723) (xy 119.165263 -239.000488) (xy 119.189754 -239.00003)
			(xy 119.212966 -239.000416) (xy 119.258932 -239.006908) (xy 119.303533 -239.019785) (xy 119.345887 -239.038791)
			(xy 119.385156 -239.063551) (xy 119.403114 -239.078262) (xy 119.415039 -239.087594) (xy 119.442877 -239.099468)
			(xy 119.472971 -239.102666) (xy 119.502683 -239.096907) (xy 119.529403 -239.082696) (xy 119.540528 -239.07242)
			(xy 119.559235 -239.054506) (xy 119.60119 -239.024138) (xy 119.64737 -239.00069) (xy 119.696644 -238.984737)
			(xy 119.747804 -238.97667) (xy 119.7737 -238.976154) (xy 119.799495 -238.976651) (xy 119.850457 -238.984673)
			(xy 119.899552 -239.000522) (xy 119.922798 -239.011714) (xy 119.936268 -239.01798) (xy 119.965493 -239.023243)
			(xy 119.994997 -239.019882) (xy 120.022289 -239.00818) (xy 120.045065 -238.989127) (xy 120.061402 -238.96433)
			(xy 120.069921 -238.935884) (xy 120.070372 -238.921036) (xy 120.070372 -237.978696) (xy 119.623332 -237.531656)
			(xy 113.829846 -237.531656) (xy 113.815622 -237.559596) (xy 113.803496 -237.582756) (xy 113.773059 -237.625255)
			(xy 113.736305 -237.662427) (xy 113.694154 -237.693345) (xy 113.647658 -237.717235) (xy 113.597979 -237.733502)
			(xy 113.546357 -237.741738) (xy 113.494083 -237.741738) (xy 113.442461 -237.733502) (xy 113.392782 -237.717235)
			(xy 113.346286 -237.693345) (xy 113.304135 -237.662427) (xy 113.267381 -237.625255) (xy 113.236944 -237.582756)
			(xy 113.224818 -237.559596) (xy 113.210594 -237.531656) (xy 112.890046 -237.531656) (xy 112.875822 -237.559596)
			(xy 112.863696 -237.582756) (xy 112.833259 -237.625255) (xy 112.796505 -237.662427) (xy 112.754354 -237.693345)
			(xy 112.707858 -237.717235) (xy 112.658179 -237.733502) (xy 112.606557 -237.741738) (xy 112.554283 -237.741738)
			(xy 112.502661 -237.733502) (xy 112.452982 -237.717235) (xy 112.406486 -237.693345) (xy 112.364335 -237.662427)
			(xy 112.327581 -237.625255) (xy 112.297144 -237.582756) (xy 112.285018 -237.559596) (xy 112.270794 -237.531656)
			(xy 111.950246 -237.531656) (xy 111.936022 -237.559596) (xy 111.923896 -237.582756) (xy 111.893459 -237.625255)
			(xy 111.856705 -237.662427) (xy 111.814554 -237.693345) (xy 111.768058 -237.717235) (xy 111.718379 -237.733502)
			(xy 111.666757 -237.741738) (xy 111.614483 -237.741738) (xy 111.562861 -237.733502) (xy 111.513182 -237.717235)
			(xy 111.466686 -237.693345) (xy 111.424535 -237.662427) (xy 111.387781 -237.625255) (xy 111.357344 -237.582756)
			(xy 111.345218 -237.559596) (xy 111.330994 -237.531656) (xy 111.010446 -237.531656) (xy 110.996222 -237.559596)
			(xy 110.984096 -237.582756) (xy 110.953659 -237.625255) (xy 110.916905 -237.662427) (xy 110.874754 -237.693345)
			(xy 110.828258 -237.717235) (xy 110.778579 -237.733502) (xy 110.726957 -237.741738) (xy 110.674683 -237.741738)
			(xy 110.623061 -237.733502) (xy 110.573382 -237.717235) (xy 110.526886 -237.693345) (xy 110.484735 -237.662427)
			(xy 110.447981 -237.625255) (xy 110.417544 -237.582756) (xy 110.405418 -237.559596) (xy 110.391194 -237.531656)
			(xy 110.070646 -237.531656) (xy 110.056422 -237.559596) (xy 110.044296 -237.582756) (xy 110.013859 -237.625255)
			(xy 109.977105 -237.662427) (xy 109.934954 -237.693345) (xy 109.888458 -237.717235) (xy 109.838779 -237.733502)
			(xy 109.787157 -237.741738) (xy 109.734883 -237.741738) (xy 109.683261 -237.733502) (xy 109.633582 -237.717235)
			(xy 109.587086 -237.693345) (xy 109.544935 -237.662427) (xy 109.508181 -237.625255) (xy 109.477744 -237.582756)
			(xy 109.465618 -237.559596) (xy 109.451394 -237.531656) (xy 109.04601 -237.531656) (xy 109.032455 -237.532094)
			(xy 109.006306 -237.53925) (xy 108.982962 -237.553035) (xy 108.964067 -237.572476) (xy 108.950954 -237.596204)
			(xy 108.944546 -237.622546) (xy 108.945295 -237.649646) (xy 108.953148 -237.675595) (xy 108.959904 -237.687358)
			(xy 108.973881 -237.710538) (xy 108.994898 -237.760416) (xy 109.007494 -237.813055) (xy 109.009942 -237.840012)
			(xy 109.011367 -237.85397) (xy 109.020868 -237.88036) (xy 109.037189 -237.903171) (xy 109.059099 -237.920681)
			(xy 109.084947 -237.931571) (xy 109.112782 -237.935019) (xy 109.140505 -237.930765) (xy 109.153452 -237.925356)
			(xy 109.175119 -237.915913) (xy 109.220459 -237.902572) (xy 109.267235 -237.895809) (xy 109.290866 -237.895384)
			(xy 109.316834 -237.895864) (xy 109.368131 -237.903984) (xy 109.417527 -237.920029) (xy 109.463804 -237.943604)
			(xy 109.505823 -237.974129) (xy 109.542549 -238.010851) (xy 109.573078 -238.052867) (xy 109.596658 -238.099142)
			(xy 109.612708 -238.148535) (xy 109.620833 -238.199832) (xy 109.620833 -238.251768) (xy 109.620827 -238.251805)
			(xy 109.900721 -238.251805) (xy 109.900721 -238.199871) (xy 109.908846 -238.148576) (xy 109.924894 -238.099183)
			(xy 109.948472 -238.052909) (xy 109.978998 -238.010893) (xy 110.015721 -237.97417) (xy 110.057737 -237.943644)
			(xy 110.104011 -237.920066) (xy 110.153404 -237.904018) (xy 110.204699 -237.895893) (xy 110.256633 -237.895893)
			(xy 110.307928 -237.904018) (xy 110.357321 -237.920066) (xy 110.403595 -237.943644) (xy 110.445611 -237.97417)
			(xy 110.482334 -238.010893) (xy 110.51286 -238.052909) (xy 110.536438 -238.099183) (xy 110.552486 -238.148576)
			(xy 110.560611 -238.199871) (xy 110.56112 -238.225838) (xy 110.560611 -238.251805) (xy 110.840521 -238.251805)
			(xy 110.840521 -238.199871) (xy 110.848646 -238.148576) (xy 110.864694 -238.099183) (xy 110.888272 -238.052909)
			(xy 110.918798 -238.010893) (xy 110.955521 -237.97417) (xy 110.997537 -237.943644) (xy 111.043811 -237.920066)
			(xy 111.093204 -237.904018) (xy 111.144499 -237.895893) (xy 111.196433 -237.895893) (xy 111.247728 -237.904018)
			(xy 111.297121 -237.920066) (xy 111.343395 -237.943644) (xy 111.385411 -237.97417) (xy 111.422134 -238.010893)
			(xy 111.45266 -238.052909) (xy 111.476238 -238.099183) (xy 111.492286 -238.148576) (xy 111.500411 -238.199871)
			(xy 111.50092 -238.225838) (xy 111.500411 -238.251805) (xy 111.780321 -238.251805) (xy 111.780321 -238.199871)
			(xy 111.788446 -238.148576) (xy 111.804494 -238.099183) (xy 111.828072 -238.052909) (xy 111.858598 -238.010893)
			(xy 111.895321 -237.97417) (xy 111.937337 -237.943644) (xy 111.983611 -237.920066) (xy 112.033004 -237.904018)
			(xy 112.084299 -237.895893) (xy 112.136233 -237.895893) (xy 112.187528 -237.904018) (xy 112.236921 -237.920066)
			(xy 112.283195 -237.943644) (xy 112.325211 -237.97417) (xy 112.361934 -238.010893) (xy 112.39246 -238.052909)
			(xy 112.416038 -238.099183) (xy 112.432086 -238.148576) (xy 112.440211 -238.199871) (xy 112.44072 -238.225838)
			(xy 112.440211 -238.251805) (xy 112.720121 -238.251805) (xy 112.720121 -238.199871) (xy 112.728246 -238.148576)
			(xy 112.744294 -238.099183) (xy 112.767872 -238.052909) (xy 112.798398 -238.010893) (xy 112.835121 -237.97417)
			(xy 112.877137 -237.943644) (xy 112.923411 -237.920066) (xy 112.972804 -237.904018) (xy 113.024099 -237.895893)
			(xy 113.076033 -237.895893) (xy 113.127328 -237.904018) (xy 113.176721 -237.920066) (xy 113.222995 -237.943644)
			(xy 113.265011 -237.97417) (xy 113.301734 -238.010893) (xy 113.33226 -238.052909) (xy 113.355838 -238.099183)
			(xy 113.371886 -238.148576) (xy 113.380011 -238.199871) (xy 113.38052 -238.225838) (xy 113.380011 -238.251805)
			(xy 113.659921 -238.251805) (xy 113.659921 -238.199871) (xy 113.668046 -238.148576) (xy 113.684094 -238.099183)
			(xy 113.707672 -238.052909) (xy 113.738198 -238.010893) (xy 113.774921 -237.97417) (xy 113.816937 -237.943644)
			(xy 113.863211 -237.920066) (xy 113.912604 -237.904018) (xy 113.963899 -237.895893) (xy 114.015833 -237.895893)
			(xy 114.067128 -237.904018) (xy 114.116521 -237.920066) (xy 114.162795 -237.943644) (xy 114.204811 -237.97417)
			(xy 114.241534 -238.010893) (xy 114.27206 -238.052909) (xy 114.295638 -238.099183) (xy 114.311686 -238.148576)
			(xy 114.319811 -238.199871) (xy 114.32032 -238.225838) (xy 114.319811 -238.251805) (xy 114.311686 -238.3031)
			(xy 114.295638 -238.352493) (xy 114.27206 -238.398767) (xy 114.241534 -238.440783) (xy 114.204811 -238.477506)
			(xy 114.162795 -238.508032) (xy 114.116521 -238.53161) (xy 114.067128 -238.547658) (xy 114.015833 -238.555783)
			(xy 113.963899 -238.555783) (xy 113.912604 -238.547658) (xy 113.863211 -238.53161) (xy 113.816937 -238.508032)
			(xy 113.774921 -238.477506) (xy 113.738198 -238.440783) (xy 113.707672 -238.398767) (xy 113.684094 -238.352493)
			(xy 113.668046 -238.3031) (xy 113.659921 -238.251805) (xy 113.380011 -238.251805) (xy 113.371886 -238.3031)
			(xy 113.355838 -238.352493) (xy 113.33226 -238.398767) (xy 113.301734 -238.440783) (xy 113.265011 -238.477506)
			(xy 113.222995 -238.508032) (xy 113.176721 -238.53161) (xy 113.127328 -238.547658) (xy 113.076033 -238.555783)
			(xy 113.024099 -238.555783) (xy 112.972804 -238.547658) (xy 112.923411 -238.53161) (xy 112.877137 -238.508032)
			(xy 112.835121 -238.477506) (xy 112.798398 -238.440783) (xy 112.767872 -238.398767) (xy 112.744294 -238.352493)
			(xy 112.728246 -238.3031) (xy 112.720121 -238.251805) (xy 112.440211 -238.251805) (xy 112.432086 -238.3031)
			(xy 112.416038 -238.352493) (xy 112.39246 -238.398767) (xy 112.361934 -238.440783) (xy 112.325211 -238.477506)
			(xy 112.283195 -238.508032) (xy 112.236921 -238.53161) (xy 112.187528 -238.547658) (xy 112.136233 -238.555783)
			(xy 112.084299 -238.555783) (xy 112.033004 -238.547658) (xy 111.983611 -238.53161) (xy 111.937337 -238.508032)
			(xy 111.895321 -238.477506) (xy 111.858598 -238.440783) (xy 111.828072 -238.398767) (xy 111.804494 -238.352493)
			(xy 111.788446 -238.3031) (xy 111.780321 -238.251805) (xy 111.500411 -238.251805) (xy 111.492286 -238.3031)
			(xy 111.476238 -238.352493) (xy 111.45266 -238.398767) (xy 111.422134 -238.440783) (xy 111.385411 -238.477506)
			(xy 111.343395 -238.508032) (xy 111.297121 -238.53161) (xy 111.247728 -238.547658) (xy 111.196433 -238.555783)
			(xy 111.144499 -238.555783) (xy 111.093204 -238.547658) (xy 111.043811 -238.53161) (xy 110.997537 -238.508032)
			(xy 110.955521 -238.477506) (xy 110.918798 -238.440783) (xy 110.888272 -238.398767) (xy 110.864694 -238.352493)
			(xy 110.848646 -238.3031) (xy 110.840521 -238.251805) (xy 110.560611 -238.251805) (xy 110.552486 -238.3031)
			(xy 110.536438 -238.352493) (xy 110.51286 -238.398767) (xy 110.482334 -238.440783) (xy 110.445611 -238.477506)
			(xy 110.403595 -238.508032) (xy 110.357321 -238.53161) (xy 110.307928 -238.547658) (xy 110.256633 -238.555783)
			(xy 110.204699 -238.555783) (xy 110.153404 -238.547658) (xy 110.104011 -238.53161) (xy 110.057737 -238.508032)
			(xy 110.015721 -238.477506) (xy 109.978998 -238.440783) (xy 109.948472 -238.398767) (xy 109.924894 -238.352493)
			(xy 109.908846 -238.3031) (xy 109.900721 -238.251805) (xy 109.620827 -238.251805) (xy 109.612708 -238.303065)
			(xy 109.596658 -238.352458) (xy 109.573078 -238.398733) (xy 109.542549 -238.440749) (xy 109.505823 -238.477471)
			(xy 109.463804 -238.507996) (xy 109.417527 -238.531571) (xy 109.368131 -238.547616) (xy 109.316834 -238.555736)
			(xy 109.290866 -238.556292) (xy 109.266066 -238.555846) (xy 109.217024 -238.548431) (xy 109.16964 -238.533773)
			(xy 109.124977 -238.512201) (xy 109.084039 -238.484198) (xy 109.047743 -238.450394) (xy 109.016904 -238.411547)
			(xy 108.992215 -238.368529) (xy 108.974229 -238.322305) (xy 108.963351 -238.273914) (xy 108.961174 -238.249206)
			(xy 108.959751 -238.235244) (xy 108.950253 -238.208847) (xy 108.933932 -238.18603) (xy 108.91202 -238.168513)
			(xy 108.886168 -238.157618) (xy 108.858328 -238.154166) (xy 108.830598 -238.158419) (xy 108.817664 -238.163862)
			(xy 108.795996 -238.173299) (xy 108.750655 -238.186628) (xy 108.70388 -238.193379) (xy 108.68025 -238.193834)
			(xy 108.654286 -238.193321) (xy 108.602998 -238.18519) (xy 108.553614 -238.169137) (xy 108.507348 -238.145556)
			(xy 108.465341 -238.115029) (xy 108.428626 -238.078306) (xy 108.398107 -238.036292) (xy 108.374536 -237.990022)
			(xy 108.358493 -237.940634) (xy 108.350374 -237.889344) (xy 108.349796 -237.86338) (xy 108.350191 -237.840165)
			(xy 108.356696 -237.794194) (xy 108.369575 -237.749586) (xy 108.388573 -237.707221) (xy 108.400596 -237.687358)
			(xy 108.407453 -237.675646) (xy 108.415329 -237.649684) (xy 108.416087 -237.622564) (xy 108.409672 -237.596203)
			(xy 108.396538 -237.572464) (xy 108.377613 -237.553024) (xy 108.354235 -237.539258) (xy 108.328056 -237.532138)
			(xy 108.31449 -237.531656) (xy 104.192578 -237.531656) (xy 103.646478 -238.077756) (xy 103.646478 -238.999776)
			(xy 103.674672 -239.013746) (xy 103.695332 -239.024413) (xy 103.733701 -239.050675) (xy 103.751126 -239.06607)
			(xy 103.762615 -239.075873) (xy 103.789852 -239.088887) (xy 103.819706 -239.093355) (xy 103.84956 -239.088887)
			(xy 103.876797 -239.075873) (xy 103.888286 -239.06607) (xy 103.906689 -239.049809) (xy 103.947398 -239.022346)
			(xy 103.991721 -239.001207) (xy 104.038684 -238.986855) (xy 104.087253 -238.979607) (xy 104.111806 -238.979202)
			(xy 104.137776 -238.979712) (xy 104.189077 -238.987838) (xy 104.238476 -239.003889) (xy 104.284755 -239.02747)
			(xy 104.326776 -239.058001) (xy 104.363503 -239.094729) (xy 104.394033 -239.13675) (xy 104.417613 -239.18303)
			(xy 104.433663 -239.232428) (xy 104.441789 -239.28373) (xy 104.441789 -239.318871) (xy 104.849621 -239.318871)
			(xy 104.849621 -239.266929) (xy 104.857747 -239.215626) (xy 104.873798 -239.166227) (xy 104.897381 -239.119947)
			(xy 104.927912 -239.077925) (xy 104.964642 -239.041198) (xy 105.006665 -239.010669) (xy 105.052947 -238.98709)
			(xy 105.102348 -238.971042) (xy 105.153651 -238.962919) (xy 105.179622 -238.962438) (xy 105.204173 -238.962903)
			(xy 105.252738 -238.970139) (xy 105.2997 -238.984477) (xy 105.344024 -239.005603) (xy 105.384737 -239.033052)
			(xy 105.403142 -239.049306) (xy 105.414631 -239.059109) (xy 105.441868 -239.072123) (xy 105.471722 -239.076591)
			(xy 105.501576 -239.072123) (xy 105.528813 -239.059109) (xy 105.540302 -239.049306) (xy 105.558687 -239.033025)
			(xy 105.599397 -239.00556) (xy 105.643725 -238.984426) (xy 105.690694 -238.970088) (xy 105.739267 -238.962864)
			(xy 105.763822 -238.962438) (xy 105.788373 -238.962903) (xy 105.836938 -238.970139) (xy 105.8839 -238.984477)
			(xy 105.928224 -239.005603) (xy 105.968937 -239.033052) (xy 105.987342 -239.049306) (xy 105.998831 -239.059109)
			(xy 106.026068 -239.072123) (xy 106.055922 -239.076591) (xy 106.085776 -239.072123) (xy 106.113013 -239.059109)
			(xy 106.124502 -239.049306) (xy 106.142887 -239.033025) (xy 106.183597 -239.00556) (xy 106.227925 -238.984426)
			(xy 106.274894 -238.970088) (xy 106.323467 -238.962864) (xy 106.348022 -238.962438) (xy 106.373987 -238.962965)
			(xy 106.425279 -238.971092) (xy 106.474667 -238.987142) (xy 106.520937 -239.01072) (xy 106.562949 -239.041246)
			(xy 106.587322 -239.065621) (xy 113.190021 -239.065621) (xy 113.190021 -239.013687) (xy 113.198146 -238.962392)
			(xy 113.214194 -238.912999) (xy 113.237772 -238.866725) (xy 113.268298 -238.824709) (xy 113.305021 -238.787986)
			(xy 113.347037 -238.75746) (xy 113.393311 -238.733882) (xy 113.442704 -238.717834) (xy 113.493999 -238.709709)
			(xy 113.545933 -238.709709) (xy 113.597228 -238.717834) (xy 113.646621 -238.733882) (xy 113.692895 -238.75746)
			(xy 113.734911 -238.787986) (xy 113.771634 -238.824709) (xy 113.80216 -238.866725) (xy 113.825738 -238.912999)
			(xy 113.841786 -238.962392) (xy 113.849911 -239.013687) (xy 113.85042 -239.039654) (xy 113.849911 -239.065621)
			(xy 113.841786 -239.116916) (xy 113.825738 -239.166309) (xy 113.80216 -239.212583) (xy 113.771634 -239.254599)
			(xy 113.734911 -239.291322) (xy 113.692895 -239.321848) (xy 113.646621 -239.345426) (xy 113.597228 -239.361474)
			(xy 113.545933 -239.369599) (xy 113.493999 -239.369599) (xy 113.442704 -239.361474) (xy 113.393311 -239.345426)
			(xy 113.347037 -239.321848) (xy 113.305021 -239.291322) (xy 113.268298 -239.254599) (xy 113.237772 -239.212583)
			(xy 113.214194 -239.166309) (xy 113.198146 -239.116916) (xy 113.190021 -239.065621) (xy 106.587322 -239.065621)
			(xy 106.599668 -239.077968) (xy 106.630191 -239.119982) (xy 106.653767 -239.166253) (xy 106.669813 -239.215643)
			(xy 106.677937 -239.266935) (xy 106.677937 -239.318865) (xy 106.669813 -239.370157) (xy 106.653767 -239.419547)
			(xy 106.630191 -239.465818) (xy 106.599668 -239.507832) (xy 106.562949 -239.544554) (xy 106.520937 -239.57508)
			(xy 106.474667 -239.598658) (xy 106.425279 -239.614708) (xy 106.373987 -239.622835) (xy 106.348022 -239.623346)
			(xy 106.32347 -239.622919) (xy 106.274902 -239.615674) (xy 106.22794 -239.601327) (xy 106.183617 -239.580193)
			(xy 106.142906 -239.552736) (xy 106.124502 -239.536478) (xy 106.113013 -239.526675) (xy 106.085776 -239.513661)
			(xy 106.055922 -239.509193) (xy 106.026068 -239.513661) (xy 105.998831 -239.526675) (xy 105.987342 -239.536478)
			(xy 105.968937 -239.552735) (xy 105.928233 -239.580204) (xy 105.88391 -239.601344) (xy 105.836946 -239.615686)
			(xy 105.788375 -239.622917) (xy 105.763822 -239.623346) (xy 105.73927 -239.622919) (xy 105.690702 -239.615674)
			(xy 105.64374 -239.601327) (xy 105.599417 -239.580193) (xy 105.558706 -239.552736) (xy 105.540302 -239.536478)
			(xy 105.528813 -239.526675) (xy 105.501576 -239.513661) (xy 105.471722 -239.509193) (xy 105.441868 -239.513661)
			(xy 105.414631 -239.526675) (xy 105.403142 -239.536478) (xy 105.384737 -239.552735) (xy 105.344033 -239.580204)
			(xy 105.29971 -239.601344) (xy 105.252746 -239.615686) (xy 105.204175 -239.622917) (xy 105.179622 -239.623346)
			(xy 105.153651 -239.622881) (xy 105.102348 -239.614758) (xy 105.052947 -239.59871) (xy 105.006665 -239.575131)
			(xy 104.964642 -239.544602) (xy 104.927912 -239.507875) (xy 104.897381 -239.465853) (xy 104.873798 -239.419573)
			(xy 104.857747 -239.370174) (xy 104.849621 -239.318871) (xy 104.441789 -239.318871) (xy 104.441789 -239.33567)
			(xy 104.433663 -239.386972) (xy 104.417613 -239.43637) (xy 104.394033 -239.48265) (xy 104.363503 -239.524671)
			(xy 104.326776 -239.561399) (xy 104.284755 -239.59193) (xy 104.238476 -239.615511) (xy 104.189077 -239.631562)
			(xy 104.137776 -239.639688) (xy 104.111806 -239.64011) (xy 104.087252 -239.639683) (xy 104.03868 -239.632455)
			(xy 103.991714 -239.618114) (xy 103.94739 -239.596976) (xy 103.906685 -239.569507) (xy 103.888286 -239.553242)
			(xy 103.876797 -239.543439) (xy 103.84956 -239.530425) (xy 103.819706 -239.525957) (xy 103.789852 -239.530425)
			(xy 103.762615 -239.543439) (xy 103.751126 -239.553242) (xy 103.733704 -239.56864) (xy 103.695334 -239.594902)
			(xy 103.674672 -239.605566) (xy 103.646478 -239.619536) (xy 103.646478 -239.879437) (xy 109.900975 -239.879437)
			(xy 109.900975 -239.827503) (xy 109.9091 -239.776208) (xy 109.925148 -239.726815) (xy 109.948726 -239.680541)
			(xy 109.979252 -239.638525) (xy 110.015975 -239.601802) (xy 110.057991 -239.571276) (xy 110.104265 -239.547698)
			(xy 110.153658 -239.53165) (xy 110.204953 -239.523525) (xy 110.256887 -239.523525) (xy 110.308182 -239.53165)
			(xy 110.357575 -239.547698) (xy 110.403849 -239.571276) (xy 110.445865 -239.601802) (xy 110.482588 -239.638525)
			(xy 110.513114 -239.680541) (xy 110.536692 -239.726815) (xy 110.55274 -239.776208) (xy 110.560865 -239.827503)
			(xy 110.561374 -239.85347) (xy 110.560865 -239.879437) (xy 110.55274 -239.930732) (xy 110.536692 -239.980125)
			(xy 110.513114 -240.026399) (xy 110.482588 -240.068415) (xy 110.445865 -240.105138) (xy 110.403849 -240.135664)
			(xy 110.357575 -240.159242) (xy 110.308182 -240.17529) (xy 110.256887 -240.183415) (xy 110.204953 -240.183415)
			(xy 110.153658 -240.17529) (xy 110.104265 -240.159242) (xy 110.057991 -240.135664) (xy 110.015975 -240.105138)
			(xy 109.979252 -240.068415) (xy 109.948726 -240.026399) (xy 109.925148 -239.980125) (xy 109.9091 -239.930732)
			(xy 109.900975 -239.879437) (xy 103.646478 -239.879437) (xy 103.646478 -241.172746) (xy 108.095796 -241.172746)
			(xy 108.096227 -241.148194) (xy 108.103469 -241.099626) (xy 108.117814 -241.052664) (xy 108.138948 -241.00834)
			(xy 108.166406 -240.967629) (xy 108.182664 -240.949226) (xy 108.192424 -240.937702) (xy 108.205444 -240.910478)
			(xy 108.209922 -240.880634) (xy 108.205464 -240.850787) (xy 108.192462 -240.823554) (xy 108.182664 -240.812066)
			(xy 108.166425 -240.793645) (xy 108.138952 -240.752946) (xy 108.117808 -240.708627) (xy 108.103461 -240.661666)
			(xy 108.096227 -240.613098) (xy 108.095796 -240.588546) (xy 108.096305 -240.562579) (xy 108.10443 -240.511284)
			(xy 108.120478 -240.461891) (xy 108.144056 -240.415617) (xy 108.174582 -240.373601) (xy 108.211305 -240.336878)
			(xy 108.253321 -240.306352) (xy 108.299595 -240.282774) (xy 108.348988 -240.266726) (xy 108.400283 -240.258601)
			(xy 108.452217 -240.258601) (xy 108.503512 -240.266726) (xy 108.552905 -240.282774) (xy 108.599179 -240.306352)
			(xy 108.641195 -240.336878) (xy 108.677918 -240.373601) (xy 108.708444 -240.415617) (xy 108.732022 -240.461891)
			(xy 108.74807 -240.511284) (xy 108.756195 -240.562579) (xy 108.756704 -240.588546) (xy 108.756268 -240.613098)
			(xy 108.749028 -240.661666) (xy 108.739302 -240.693507) (xy 113.190275 -240.693507) (xy 113.190275 -240.641573)
			(xy 113.1984 -240.590278) (xy 113.214448 -240.540885) (xy 113.238026 -240.494611) (xy 113.268552 -240.452595)
			(xy 113.305275 -240.415872) (xy 113.347291 -240.385346) (xy 113.393565 -240.361768) (xy 113.442958 -240.34572)
			(xy 113.494253 -240.337595) (xy 113.546187 -240.337595) (xy 113.597482 -240.34572) (xy 113.646875 -240.361768)
			(xy 113.693149 -240.385346) (xy 113.735165 -240.415872) (xy 113.771888 -240.452595) (xy 113.802414 -240.494611)
			(xy 113.825992 -240.540885) (xy 113.84204 -240.590278) (xy 113.850165 -240.641573) (xy 113.850674 -240.66754)
			(xy 113.850165 -240.693507) (xy 113.84204 -240.744802) (xy 113.825992 -240.794195) (xy 113.802414 -240.840469)
			(xy 113.771888 -240.882485) (xy 113.735165 -240.919208) (xy 113.693149 -240.949734) (xy 113.646875 -240.973312)
			(xy 113.597482 -240.98936) (xy 113.546187 -240.997485) (xy 113.494253 -240.997485) (xy 113.442958 -240.98936)
			(xy 113.393565 -240.973312) (xy 113.347291 -240.949734) (xy 113.305275 -240.919208) (xy 113.268552 -240.882485)
			(xy 113.238026 -240.840469) (xy 113.214448 -240.794195) (xy 113.1984 -240.744802) (xy 113.190275 -240.693507)
			(xy 108.739302 -240.693507) (xy 108.734683 -240.708628) (xy 108.71355 -240.752952) (xy 108.686094 -240.793662)
			(xy 108.669836 -240.812066) (xy 108.659987 -240.823519) (xy 108.646977 -240.850769) (xy 108.642516 -240.880634)
			(xy 108.646997 -240.910496) (xy 108.660025 -240.937737) (xy 108.669836 -240.949226) (xy 108.686071 -240.96765)
			(xy 108.713545 -241.008348) (xy 108.734689 -241.052666) (xy 108.749037 -241.099627) (xy 108.756273 -241.148194)
			(xy 108.756704 -241.172746) (xy 108.756195 -241.198713) (xy 108.74807 -241.250008) (xy 108.732022 -241.299401)
			(xy 108.708444 -241.345675) (xy 108.677918 -241.387691) (xy 108.641195 -241.424414) (xy 108.599179 -241.45494)
			(xy 108.552905 -241.478518) (xy 108.503512 -241.494566) (xy 108.452217 -241.502691) (xy 108.400283 -241.502691)
			(xy 108.348988 -241.494566) (xy 108.299595 -241.478518) (xy 108.253321 -241.45494) (xy 108.211305 -241.424414)
			(xy 108.174582 -241.387691) (xy 108.144056 -241.345675) (xy 108.120478 -241.299401) (xy 108.10443 -241.250008)
			(xy 108.096305 -241.198713) (xy 108.095796 -241.172746) (xy 103.646478 -241.172746) (xy 103.646478 -241.507323)
			(xy 109.900975 -241.507323) (xy 109.900975 -241.455389) (xy 109.9091 -241.404094) (xy 109.925148 -241.354701)
			(xy 109.948726 -241.308427) (xy 109.979252 -241.266411) (xy 110.015975 -241.229688) (xy 110.057991 -241.199162)
			(xy 110.104265 -241.175584) (xy 110.153658 -241.159536) (xy 110.204953 -241.151411) (xy 110.256887 -241.151411)
			(xy 110.308182 -241.159536) (xy 110.357575 -241.175584) (xy 110.403849 -241.199162) (xy 110.445865 -241.229688)
			(xy 110.482588 -241.266411) (xy 110.513114 -241.308427) (xy 110.536692 -241.354701) (xy 110.55274 -241.404094)
			(xy 110.560865 -241.455389) (xy 110.561374 -241.481356) (xy 110.560865 -241.507323) (xy 110.55274 -241.558618)
			(xy 110.536692 -241.608011) (xy 110.513114 -241.654285) (xy 110.504962 -241.665506) (xy 115.092988 -241.665506)
			(xy 115.093397 -241.640953) (xy 115.100644 -241.592384) (xy 115.114995 -241.545422) (xy 115.136134 -241.501098)
			(xy 115.163596 -241.460389) (xy 115.179856 -241.441986) (xy 115.189655 -241.430493) (xy 115.202672 -241.403258)
			(xy 115.207143 -241.373404) (xy 115.202675 -241.343551) (xy 115.18966 -241.316314) (xy 115.179856 -241.304826)
			(xy 115.163597 -241.286422) (xy 115.136127 -241.245718) (xy 115.114987 -241.201395) (xy 115.100645 -241.15443)
			(xy 115.093416 -241.105859) (xy 115.092988 -241.081306) (xy 115.093497 -241.055339) (xy 115.101622 -241.004044)
			(xy 115.11767 -240.954651) (xy 115.141248 -240.908377) (xy 115.171774 -240.866361) (xy 115.208497 -240.829638)
			(xy 115.250513 -240.799112) (xy 115.296787 -240.775534) (xy 115.34618 -240.759486) (xy 115.397475 -240.751361)
			(xy 115.449409 -240.751361) (xy 115.500704 -240.759486) (xy 115.550097 -240.775534) (xy 115.596371 -240.799112)
			(xy 115.638387 -240.829638) (xy 115.67511 -240.866361) (xy 115.705636 -240.908377) (xy 115.729214 -240.954651)
			(xy 115.745262 -241.004044) (xy 115.753387 -241.055339) (xy 115.753896 -241.081306) (xy 115.753438 -241.105857)
			(xy 115.746203 -241.154424) (xy 115.731864 -241.201386) (xy 115.710736 -241.24571) (xy 115.683284 -241.286422)
			(xy 115.667028 -241.304826) (xy 115.657218 -241.31631) (xy 115.644205 -241.343549) (xy 115.639737 -241.373404)
			(xy 115.644208 -241.403259) (xy 115.657223 -241.430497) (xy 115.667028 -241.441986) (xy 115.683307 -241.460373)
			(xy 115.710771 -241.501083) (xy 115.731905 -241.54541) (xy 115.746243 -241.592378) (xy 115.753469 -241.640952)
			(xy 115.753896 -241.665506) (xy 115.753387 -241.691473) (xy 115.745262 -241.742768) (xy 115.729214 -241.792161)
			(xy 115.705636 -241.838435) (xy 115.67511 -241.880451) (xy 115.638387 -241.917174) (xy 115.596371 -241.9477)
			(xy 115.550097 -241.971278) (xy 115.500704 -241.987326) (xy 115.449409 -241.995451) (xy 115.397475 -241.995451)
			(xy 115.34618 -241.987326) (xy 115.296787 -241.971278) (xy 115.250513 -241.9477) (xy 115.208497 -241.917174)
			(xy 115.171774 -241.880451) (xy 115.141248 -241.838435) (xy 115.11767 -241.792161) (xy 115.101622 -241.742768)
			(xy 115.093497 -241.691473) (xy 115.092988 -241.665506) (xy 110.504962 -241.665506) (xy 110.482588 -241.696301)
			(xy 110.445865 -241.733024) (xy 110.403849 -241.76355) (xy 110.357575 -241.787128) (xy 110.308182 -241.803176)
			(xy 110.256887 -241.811301) (xy 110.204953 -241.811301) (xy 110.153658 -241.803176) (xy 110.104265 -241.787128)
			(xy 110.057991 -241.76355) (xy 110.015975 -241.733024) (xy 109.979252 -241.696301) (xy 109.948726 -241.654285)
			(xy 109.925148 -241.608011) (xy 109.9091 -241.558618) (xy 109.900975 -241.507323) (xy 103.646478 -241.507323)
			(xy 103.646478 -242.321139) (xy 113.190275 -242.321139) (xy 113.190275 -242.269205) (xy 113.1984 -242.21791)
			(xy 113.214448 -242.168517) (xy 113.238026 -242.122243) (xy 113.268552 -242.080227) (xy 113.305275 -242.043504)
			(xy 113.347291 -242.012978) (xy 113.393565 -241.9894) (xy 113.442958 -241.973352) (xy 113.494253 -241.965227)
			(xy 113.546187 -241.965227) (xy 113.597482 -241.973352) (xy 113.646875 -241.9894) (xy 113.693149 -242.012978)
			(xy 113.735165 -242.043504) (xy 113.771888 -242.080227) (xy 113.802414 -242.122243) (xy 113.825992 -242.168517)
			(xy 113.84204 -242.21791) (xy 113.850165 -242.269205) (xy 113.850674 -242.295172) (xy 113.850165 -242.321139)
			(xy 113.84204 -242.372434) (xy 113.825992 -242.421827) (xy 113.802414 -242.468101) (xy 113.771888 -242.510117)
			(xy 113.735165 -242.54684) (xy 113.693149 -242.577366) (xy 113.646875 -242.600944) (xy 113.597482 -242.616992)
			(xy 113.546187 -242.625117) (xy 113.494253 -242.625117) (xy 113.442958 -242.616992) (xy 113.393565 -242.600944)
			(xy 113.347291 -242.577366) (xy 113.305275 -242.54684) (xy 113.268552 -242.510117) (xy 113.238026 -242.468101)
			(xy 113.214448 -242.421827) (xy 113.1984 -242.372434) (xy 113.190275 -242.321139) (xy 103.646478 -242.321139)
			(xy 103.646478 -243.135209) (xy 109.900975 -243.135209) (xy 109.900975 -243.083275) (xy 109.9091 -243.03198)
			(xy 109.925148 -242.982587) (xy 109.948726 -242.936313) (xy 109.979252 -242.894297) (xy 110.015975 -242.857574)
			(xy 110.057991 -242.827048) (xy 110.104265 -242.80347) (xy 110.153658 -242.787422) (xy 110.204953 -242.779297)
			(xy 110.256887 -242.779297) (xy 110.308182 -242.787422) (xy 110.357575 -242.80347) (xy 110.403849 -242.827048)
			(xy 110.445865 -242.857574) (xy 110.482588 -242.894297) (xy 110.513114 -242.936313) (xy 110.536692 -242.982587)
			(xy 110.538181 -242.98717) (xy 117.494015 -242.98717) (xy 117.494015 -242.93523) (xy 117.502141 -242.883929)
			(xy 117.518191 -242.834531) (xy 117.541771 -242.788252) (xy 117.572301 -242.746231) (xy 117.609028 -242.709503)
			(xy 117.651048 -242.678973) (xy 117.697327 -242.655392) (xy 117.746725 -242.639341) (xy 117.798026 -242.631216)
			(xy 117.823996 -242.630706) (xy 117.849857 -242.631205) (xy 117.900949 -242.639252) (xy 117.950163 -242.655163)
			(xy 117.996294 -242.678552) (xy 118.038216 -242.708845) (xy 118.056914 -242.726718) (xy 118.066629 -242.735763)
			(xy 118.089638 -242.748975) (xy 118.115275 -242.755812) (xy 118.141809 -242.755812) (xy 118.167446 -242.748975)
			(xy 118.190455 -242.735763) (xy 118.20017 -242.726718) (xy 118.218865 -242.708844) (xy 118.260794 -242.678561)
			(xy 118.306927 -242.655178) (xy 118.356138 -242.639264) (xy 118.407228 -242.631207) (xy 118.433088 -242.630706)
			(xy 118.459055 -242.631268) (xy 118.510349 -242.63939) (xy 118.559741 -242.655437) (xy 118.606015 -242.679013)
			(xy 118.648031 -242.709538) (xy 118.684754 -242.74626) (xy 118.71528 -242.788275) (xy 118.738858 -242.834548)
			(xy 118.754907 -242.883939) (xy 118.763031 -242.935233) (xy 118.763031 -242.987167) (xy 118.754907 -243.038461)
			(xy 118.738858 -243.087852) (xy 118.71528 -243.134125) (xy 118.684754 -243.17614) (xy 118.648031 -243.212862)
			(xy 118.606015 -243.243387) (xy 118.559741 -243.266963) (xy 118.510349 -243.28301) (xy 118.459055 -243.291132)
			(xy 118.433088 -243.291614) (xy 118.407227 -243.291119) (xy 118.356135 -243.283071) (xy 118.306921 -243.267158)
			(xy 118.26079 -243.243768) (xy 118.218868 -243.213475) (xy 118.20017 -243.195602) (xy 118.190455 -243.186557)
			(xy 118.167446 -243.173345) (xy 118.141809 -243.166508) (xy 118.115275 -243.166508) (xy 118.089638 -243.173345)
			(xy 118.066629 -243.186557) (xy 118.056914 -243.195602) (xy 118.038229 -243.213487) (xy 117.996297 -243.243767)
			(xy 117.950162 -243.267149) (xy 117.900948 -243.28306) (xy 117.849857 -243.291114) (xy 117.823996 -243.291614)
			(xy 117.798026 -243.291184) (xy 117.746725 -243.283059) (xy 117.697327 -243.267008) (xy 117.651048 -243.243427)
			(xy 117.609028 -243.212897) (xy 117.572301 -243.176169) (xy 117.541771 -243.134148) (xy 117.518191 -243.087869)
			(xy 117.502141 -243.038471) (xy 117.494015 -242.98717) (xy 110.538181 -242.98717) (xy 110.55274 -243.03198)
			(xy 110.560865 -243.083275) (xy 110.561374 -243.109242) (xy 110.560865 -243.135209) (xy 110.55274 -243.186504)
			(xy 110.536692 -243.235897) (xy 110.513114 -243.282171) (xy 110.482588 -243.324187) (xy 110.445865 -243.36091)
			(xy 110.403849 -243.391436) (xy 110.357575 -243.415014) (xy 110.308182 -243.431062) (xy 110.256887 -243.439187)
			(xy 110.204953 -243.439187) (xy 110.153658 -243.431062) (xy 110.104265 -243.415014) (xy 110.057991 -243.391436)
			(xy 110.015975 -243.36091) (xy 109.979252 -243.324187) (xy 109.948726 -243.282171) (xy 109.925148 -243.235897)
			(xy 109.9091 -243.186504) (xy 109.900975 -243.135209) (xy 103.646478 -243.135209) (xy 103.646478 -243.29771)
			(xy 104.297793 -243.949025) (xy 113.190275 -243.949025) (xy 113.190275 -243.897091) (xy 113.1984 -243.845796)
			(xy 113.214448 -243.796403) (xy 113.238026 -243.750129) (xy 113.268552 -243.708113) (xy 113.305275 -243.67139)
			(xy 113.347291 -243.640864) (xy 113.393565 -243.617286) (xy 113.442958 -243.601238) (xy 113.494253 -243.593113)
			(xy 113.546187 -243.593113) (xy 113.597482 -243.601238) (xy 113.646875 -243.617286) (xy 113.693149 -243.640864)
			(xy 113.735165 -243.67139) (xy 113.771888 -243.708113) (xy 113.802414 -243.750129) (xy 113.825992 -243.796403)
			(xy 113.84204 -243.845796) (xy 113.850165 -243.897091) (xy 113.850674 -243.923058) (xy 113.850165 -243.949025)
			(xy 113.84204 -244.00032) (xy 113.825992 -244.049713) (xy 113.802414 -244.095987) (xy 113.771888 -244.138003)
			(xy 113.735165 -244.174726) (xy 113.693149 -244.205252) (xy 113.646875 -244.22883) (xy 113.597482 -244.244878)
			(xy 113.546187 -244.253003) (xy 113.494253 -244.253003) (xy 113.442958 -244.244878) (xy 113.393565 -244.22883)
			(xy 113.347291 -244.205252) (xy 113.305275 -244.174726) (xy 113.268552 -244.138003) (xy 113.238026 -244.095987)
			(xy 113.214448 -244.049713) (xy 113.1984 -244.00032) (xy 113.190275 -243.949025) (xy 104.297793 -243.949025)
			(xy 105.183178 -244.83441) (xy 105.183178 -245.34749) (xy 108.103416 -245.34749) (xy 108.103868 -245.322938)
			(xy 108.111104 -245.274371) (xy 108.125444 -245.227409) (xy 108.146574 -245.183085) (xy 108.174028 -245.142374)
			(xy 108.190284 -245.12397) (xy 108.200096 -245.112488) (xy 108.213108 -245.085248) (xy 108.217574 -245.055393)
			(xy 108.213104 -245.025538) (xy 108.200088 -244.9983) (xy 108.190284 -244.98681) (xy 108.174005 -244.968423)
			(xy 108.146541 -244.927713) (xy 108.125406 -244.883386) (xy 108.111068 -244.836418) (xy 108.103843 -244.787844)
			(xy 108.103416 -244.76329) (xy 108.103925 -244.737323) (xy 108.11205 -244.686028) (xy 108.128098 -244.636635)
			(xy 108.151676 -244.590361) (xy 108.182202 -244.548345) (xy 108.218925 -244.511622) (xy 108.260941 -244.481096)
			(xy 108.307215 -244.457518) (xy 108.356608 -244.44147) (xy 108.407903 -244.433345) (xy 108.459837 -244.433345)
			(xy 108.511132 -244.44147) (xy 108.560525 -244.457518) (xy 108.606799 -244.481096) (xy 108.648815 -244.511622)
			(xy 108.685538 -244.548345) (xy 108.716064 -244.590361) (xy 108.739642 -244.636635) (xy 108.75569 -244.686028)
			(xy 108.763815 -244.737323) (xy 108.764315 -244.762841) (xy 109.900975 -244.762841) (xy 109.900975 -244.710907)
			(xy 109.9091 -244.659612) (xy 109.925148 -244.610219) (xy 109.948726 -244.563945) (xy 109.979252 -244.521929)
			(xy 110.015975 -244.485206) (xy 110.057991 -244.45468) (xy 110.104265 -244.431102) (xy 110.153658 -244.415054)
			(xy 110.204953 -244.406929) (xy 110.256887 -244.406929) (xy 110.308182 -244.415054) (xy 110.357575 -244.431102)
			(xy 110.403849 -244.45468) (xy 110.445865 -244.485206) (xy 110.482588 -244.521929) (xy 110.513114 -244.563945)
			(xy 110.536692 -244.610219) (xy 110.55274 -244.659612) (xy 110.560865 -244.710907) (xy 110.561374 -244.736874)
			(xy 110.560865 -244.762841) (xy 110.55274 -244.814136) (xy 110.536692 -244.863529) (xy 110.513114 -244.909803)
			(xy 110.482588 -244.951819) (xy 110.445865 -244.988542) (xy 110.403849 -245.019068) (xy 110.357575 -245.042646)
			(xy 110.308182 -245.058694) (xy 110.256887 -245.066819) (xy 110.204953 -245.066819) (xy 110.153658 -245.058694)
			(xy 110.104265 -245.042646) (xy 110.057991 -245.019068) (xy 110.015975 -244.988542) (xy 109.979252 -244.951819)
			(xy 109.948726 -244.909803) (xy 109.925148 -244.863529) (xy 109.9091 -244.814136) (xy 109.900975 -244.762841)
			(xy 108.764315 -244.762841) (xy 108.764324 -244.76329) (xy 108.763909 -244.787843) (xy 108.756663 -244.836411)
			(xy 108.742313 -244.883373) (xy 108.721176 -244.927697) (xy 108.693715 -244.968407) (xy 108.677456 -244.98681)
			(xy 108.66766 -244.998306) (xy 108.654641 -245.02554) (xy 108.650169 -245.055393) (xy 108.654636 -245.085246)
			(xy 108.667651 -245.112482) (xy 108.677456 -245.12397) (xy 108.693715 -245.142374) (xy 108.721185 -245.183078)
			(xy 108.742324 -245.227401) (xy 108.756666 -245.274366) (xy 108.763896 -245.322937) (xy 108.764324 -245.34749)
			(xy 108.763815 -245.373457) (xy 108.75569 -245.424752) (xy 108.739642 -245.474145) (xy 108.716064 -245.520419)
			(xy 108.685538 -245.562435) (xy 108.671062 -245.576911) (xy 113.190275 -245.576911) (xy 113.190275 -245.524977)
			(xy 113.1984 -245.473682) (xy 113.214448 -245.424289) (xy 113.238026 -245.378015) (xy 113.268552 -245.335999)
			(xy 113.305275 -245.299276) (xy 113.347291 -245.26875) (xy 113.393565 -245.245172) (xy 113.442958 -245.229124)
			(xy 113.494253 -245.220999) (xy 113.546187 -245.220999) (xy 113.597482 -245.229124) (xy 113.646875 -245.245172)
			(xy 113.693149 -245.26875) (xy 113.735165 -245.299276) (xy 113.771888 -245.335999) (xy 113.802414 -245.378015)
			(xy 113.811968 -245.396766) (xy 115.085368 -245.396766) (xy 115.085818 -245.372214) (xy 115.093056 -245.323648)
			(xy 115.107398 -245.276686) (xy 115.128527 -245.232362) (xy 115.15598 -245.19165) (xy 115.172236 -245.173246)
			(xy 115.182076 -245.161784) (xy 115.195091 -245.134538) (xy 115.199555 -245.104675) (xy 115.195076 -245.074814)
			(xy 115.182048 -245.047574) (xy 115.172236 -245.036086) (xy 115.155954 -245.017701) (xy 115.128488 -244.976992)
			(xy 115.107354 -244.932664) (xy 115.093016 -244.885695) (xy 115.085793 -244.837121) (xy 115.085368 -244.812566)
			(xy 115.085877 -244.786599) (xy 115.094002 -244.735304) (xy 115.11005 -244.685911) (xy 115.133628 -244.639637)
			(xy 115.164154 -244.597621) (xy 115.200877 -244.560898) (xy 115.242893 -244.530372) (xy 115.289167 -244.506794)
			(xy 115.33856 -244.490746) (xy 115.389855 -244.482621) (xy 115.441789 -244.482621) (xy 115.493084 -244.490746)
			(xy 115.542477 -244.506794) (xy 115.588751 -244.530372) (xy 115.630767 -244.560898) (xy 115.66749 -244.597621)
			(xy 115.698016 -244.639637) (xy 115.721594 -244.685911) (xy 115.737642 -244.735304) (xy 115.745767 -244.786599)
			(xy 115.746276 -244.812566) (xy 115.745833 -244.837118) (xy 115.738592 -244.885684) (xy 115.724248 -244.932646)
			(xy 115.703117 -244.976969) (xy 115.675664 -245.017681) (xy 115.659408 -245.036086) (xy 115.649639 -245.047602)
			(xy 115.636624 -245.07483) (xy 115.63215 -245.104675) (xy 115.636609 -245.134522) (xy 115.649611 -245.161757)
			(xy 115.659408 -245.173246) (xy 115.675664 -245.191652) (xy 115.703133 -245.232356) (xy 115.724271 -245.276679)
			(xy 115.738615 -245.323643) (xy 115.745846 -245.372213) (xy 115.746276 -245.396766) (xy 115.745767 -245.422733)
			(xy 115.737642 -245.474028) (xy 115.721594 -245.523421) (xy 115.698016 -245.569695) (xy 115.66749 -245.611711)
			(xy 115.630767 -245.648434) (xy 115.588751 -245.67896) (xy 115.542477 -245.702538) (xy 115.493084 -245.718586)
			(xy 115.441789 -245.726711) (xy 115.389855 -245.726711) (xy 115.33856 -245.718586) (xy 115.289167 -245.702538)
			(xy 115.242893 -245.67896) (xy 115.200877 -245.648434) (xy 115.164154 -245.611711) (xy 115.133628 -245.569695)
			(xy 115.11005 -245.523421) (xy 115.094002 -245.474028) (xy 115.085877 -245.422733) (xy 115.085368 -245.396766)
			(xy 113.811968 -245.396766) (xy 113.825992 -245.424289) (xy 113.84204 -245.473682) (xy 113.850165 -245.524977)
			(xy 113.850674 -245.550944) (xy 113.850165 -245.576911) (xy 113.84204 -245.628206) (xy 113.825992 -245.677599)
			(xy 113.802414 -245.723873) (xy 113.771888 -245.765889) (xy 113.735165 -245.802612) (xy 113.693149 -245.833138)
			(xy 113.646875 -245.856716) (xy 113.597482 -245.872764) (xy 113.546187 -245.880889) (xy 113.494253 -245.880889)
			(xy 113.442958 -245.872764) (xy 113.393565 -245.856716) (xy 113.347291 -245.833138) (xy 113.305275 -245.802612)
			(xy 113.268552 -245.765889) (xy 113.238026 -245.723873) (xy 113.214448 -245.677599) (xy 113.1984 -245.628206)
			(xy 113.190275 -245.576911) (xy 108.671062 -245.576911) (xy 108.648815 -245.599158) (xy 108.606799 -245.629684)
			(xy 108.560525 -245.653262) (xy 108.511132 -245.66931) (xy 108.459837 -245.677435) (xy 108.407903 -245.677435)
			(xy 108.356608 -245.66931) (xy 108.307215 -245.653262) (xy 108.260941 -245.629684) (xy 108.218925 -245.599158)
			(xy 108.182202 -245.562435) (xy 108.151676 -245.520419) (xy 108.128098 -245.474145) (xy 108.11205 -245.424752)
			(xy 108.103925 -245.373457) (xy 108.103416 -245.34749) (xy 105.183178 -245.34749) (xy 105.183178 -246.23903)
			(xy 105.183736 -246.254188) (xy 105.192621 -246.283174) (xy 105.209605 -246.308288) (xy 105.233198 -246.327327)
			(xy 105.261332 -246.338624) (xy 105.276396 -246.340376) (xy 105.304968 -246.343376) (xy 105.360528 -246.357975)
			(xy 105.412725 -246.381966) (xy 105.459983 -246.414625) (xy 105.480866 -246.434356) (xy 105.490556 -246.443349)
			(xy 105.513488 -246.456481) (xy 105.539027 -246.463276) (xy 105.565453 -246.463276) (xy 105.590992 -246.456481)
			(xy 105.613924 -246.443349) (xy 105.623614 -246.434356) (xy 105.642287 -246.416612) (xy 105.684113 -246.386549)
			(xy 105.730098 -246.363342) (xy 105.779129 -246.347555) (xy 105.830015 -246.339571) (xy 105.85577 -246.339106)
			(xy 105.881744 -246.339587) (xy 105.933053 -246.347709) (xy 105.982459 -246.363758) (xy 106.028747 -246.387339)
			(xy 106.033411 -246.390727) (xy 109.900975 -246.390727) (xy 109.900975 -246.338793) (xy 109.9091 -246.287498)
			(xy 109.925148 -246.238105) (xy 109.948726 -246.191831) (xy 109.979252 -246.149815) (xy 110.015975 -246.113092)
			(xy 110.057991 -246.082566) (xy 110.104265 -246.058988) (xy 110.153658 -246.04294) (xy 110.204953 -246.034815)
			(xy 110.256887 -246.034815) (xy 110.308182 -246.04294) (xy 110.357575 -246.058988) (xy 110.403849 -246.082566)
			(xy 110.445865 -246.113092) (xy 110.482588 -246.149815) (xy 110.513114 -246.191831) (xy 110.536692 -246.238105)
			(xy 110.55274 -246.287498) (xy 110.560865 -246.338793) (xy 110.561374 -246.36476) (xy 110.560865 -246.390727)
			(xy 110.55274 -246.442022) (xy 110.536692 -246.491415) (xy 110.513114 -246.537689) (xy 110.482588 -246.579705)
			(xy 110.445865 -246.616428) (xy 110.403849 -246.646954) (xy 110.357575 -246.670532) (xy 110.308182 -246.68658)
			(xy 110.256887 -246.694705) (xy 110.204953 -246.694705) (xy 110.153658 -246.68658) (xy 110.104265 -246.670532)
			(xy 110.057991 -246.646954) (xy 110.015975 -246.616428) (xy 109.979252 -246.579705) (xy 109.948726 -246.537689)
			(xy 109.925148 -246.491415) (xy 109.9091 -246.442022) (xy 109.900975 -246.390727) (xy 106.033411 -246.390727)
			(xy 106.070775 -246.417871) (xy 106.10751 -246.454602) (xy 106.138045 -246.496628) (xy 106.16163 -246.542913)
			(xy 106.177684 -246.592318) (xy 106.185811 -246.643626) (xy 106.185811 -246.695574) (xy 106.177684 -246.746882)
			(xy 106.16163 -246.796287) (xy 106.138045 -246.842572) (xy 106.10751 -246.884598) (xy 106.070775 -246.921329)
			(xy 106.028747 -246.951861) (xy 105.982459 -246.975442) (xy 105.933053 -246.991491) (xy 105.881744 -246.999613)
			(xy 105.85577 -247.000014) (xy 105.830018 -246.99952) (xy 105.779137 -246.991528) (xy 105.73011 -246.975743)
			(xy 105.684125 -246.952546) (xy 105.642294 -246.922498) (xy 105.623614 -246.904764) (xy 105.613924 -246.895771)
			(xy 105.590992 -246.882639) (xy 105.565453 -246.875844) (xy 105.539027 -246.875844) (xy 105.513488 -246.882639)
			(xy 105.490556 -246.895771) (xy 105.480866 -246.904764) (xy 105.459977 -246.924485) (xy 105.412713 -246.957128)
			(xy 105.360518 -246.98111) (xy 105.304963 -246.995711) (xy 105.276396 -246.998744) (xy 105.261333 -247.000542)
			(xy 105.233177 -247.011789) (xy 105.209567 -247.030812) (xy 105.192587 -247.055931) (xy 105.183735 -247.084929)
			(xy 105.183178 -247.10009) (xy 105.183178 -247.204543) (xy 113.190275 -247.204543) (xy 113.190275 -247.152609)
			(xy 113.1984 -247.101314) (xy 113.214448 -247.051921) (xy 113.238026 -247.005647) (xy 113.268552 -246.963631)
			(xy 113.305275 -246.926908) (xy 113.347291 -246.896382) (xy 113.393565 -246.872804) (xy 113.442958 -246.856756)
			(xy 113.494253 -246.848631) (xy 113.546187 -246.848631) (xy 113.597482 -246.856756) (xy 113.646875 -246.872804)
			(xy 113.693149 -246.896382) (xy 113.735165 -246.926908) (xy 113.771888 -246.963631) (xy 113.802414 -247.005647)
			(xy 113.825992 -247.051921) (xy 113.84204 -247.101314) (xy 113.850165 -247.152609) (xy 113.850674 -247.178576)
			(xy 113.850165 -247.204543) (xy 113.84204 -247.255838) (xy 113.825992 -247.305231) (xy 113.802414 -247.351505)
			(xy 113.771888 -247.393521) (xy 113.735165 -247.430244) (xy 113.693149 -247.46077) (xy 113.646875 -247.484348)
			(xy 113.597482 -247.500396) (xy 113.546187 -247.508521) (xy 113.494253 -247.508521) (xy 113.442958 -247.500396)
			(xy 113.393565 -247.484348) (xy 113.347291 -247.46077) (xy 113.305275 -247.430244) (xy 113.268552 -247.393521)
			(xy 113.238026 -247.351505) (xy 113.214448 -247.305231) (xy 113.1984 -247.255838) (xy 113.190275 -247.204543)
			(xy 105.183178 -247.204543) (xy 105.183178 -248.018359) (xy 109.900975 -248.018359) (xy 109.900975 -247.966425)
			(xy 109.9091 -247.91513) (xy 109.925148 -247.865737) (xy 109.948726 -247.819463) (xy 109.979252 -247.777447)
			(xy 110.015975 -247.740724) (xy 110.057991 -247.710198) (xy 110.104265 -247.68662) (xy 110.153658 -247.670572)
			(xy 110.204953 -247.662447) (xy 110.256887 -247.662447) (xy 110.308182 -247.670572) (xy 110.357575 -247.68662)
			(xy 110.403849 -247.710198) (xy 110.445865 -247.740724) (xy 110.482588 -247.777447) (xy 110.513114 -247.819463)
			(xy 110.536692 -247.865737) (xy 110.55274 -247.91513) (xy 110.560865 -247.966425) (xy 110.561374 -247.992392)
			(xy 110.560865 -248.018359) (xy 110.55274 -248.069654) (xy 110.536692 -248.119047) (xy 110.513114 -248.165321)
			(xy 110.482588 -248.207337) (xy 110.445865 -248.24406) (xy 110.403849 -248.274586) (xy 110.357575 -248.298164)
			(xy 110.308182 -248.314212) (xy 110.256887 -248.322337) (xy 110.204953 -248.322337) (xy 110.153658 -248.314212)
			(xy 110.104265 -248.298164) (xy 110.057991 -248.274586) (xy 110.015975 -248.24406) (xy 109.979252 -248.207337)
			(xy 109.948726 -248.165321) (xy 109.925148 -248.119047) (xy 109.9091 -248.069654) (xy 109.900975 -248.018359)
			(xy 105.183178 -248.018359) (xy 105.183178 -248.97715) (xy 105.154984 -249.005344) (xy 108.103416 -249.005344)
			(xy 108.103841 -248.980791) (xy 108.111083 -248.932223) (xy 108.12543 -248.885261) (xy 108.146565 -248.840937)
			(xy 108.174025 -248.800227) (xy 108.190284 -248.781824) (xy 108.200044 -248.770301) (xy 108.213061 -248.743076)
			(xy 108.217538 -248.713233) (xy 108.21308 -248.683386) (xy 108.20008 -248.656153) (xy 108.190284 -248.644664)
			(xy 108.174031 -248.626255) (xy 108.146563 -248.585552) (xy 108.125423 -248.54123) (xy 108.111079 -248.494266)
			(xy 108.103847 -248.445697) (xy 108.103416 -248.421144) (xy 108.103925 -248.395177) (xy 108.11205 -248.343882)
			(xy 108.128098 -248.294489) (xy 108.151676 -248.248215) (xy 108.182202 -248.206199) (xy 108.218925 -248.169476)
			(xy 108.260941 -248.13895) (xy 108.307215 -248.115372) (xy 108.356608 -248.099324) (xy 108.407903 -248.091199)
			(xy 108.459837 -248.091199) (xy 108.511132 -248.099324) (xy 108.560525 -248.115372) (xy 108.606799 -248.13895)
			(xy 108.648815 -248.169476) (xy 108.685538 -248.206199) (xy 108.716064 -248.248215) (xy 108.739642 -248.294489)
			(xy 108.75569 -248.343882) (xy 108.763815 -248.395177) (xy 108.764324 -248.421144) (xy 108.763882 -248.445696)
			(xy 108.756642 -248.494263) (xy 108.742299 -248.541225) (xy 108.721167 -248.585549) (xy 108.693713 -248.62626)
			(xy 108.677456 -248.644664) (xy 108.667607 -248.656118) (xy 108.654594 -248.683367) (xy 108.650132 -248.713233)
			(xy 108.654613 -248.743095) (xy 108.667643 -248.770336) (xy 108.677456 -248.781824) (xy 108.693694 -248.800246)
			(xy 108.715418 -248.832429) (xy 113.190275 -248.832429) (xy 113.190275 -248.780495) (xy 113.1984 -248.7292)
			(xy 113.214448 -248.679807) (xy 113.238026 -248.633533) (xy 113.268552 -248.591517) (xy 113.305275 -248.554794)
			(xy 113.347291 -248.524268) (xy 113.393565 -248.50069) (xy 113.442958 -248.484642) (xy 113.494253 -248.476517)
			(xy 113.546187 -248.476517) (xy 113.597482 -248.484642) (xy 113.646875 -248.50069) (xy 113.693149 -248.524268)
			(xy 113.735165 -248.554794) (xy 113.771888 -248.591517) (xy 113.802414 -248.633533) (xy 113.825992 -248.679807)
			(xy 113.84204 -248.7292) (xy 113.850165 -248.780495) (xy 113.850674 -248.806462) (xy 113.850165 -248.832429)
			(xy 113.84204 -248.883724) (xy 113.825992 -248.933117) (xy 113.802414 -248.979391) (xy 113.771888 -249.021407)
			(xy 113.735165 -249.05813) (xy 113.693149 -249.088656) (xy 113.646875 -249.112234) (xy 113.597482 -249.128282)
			(xy 113.546187 -249.136407) (xy 113.494253 -249.136407) (xy 113.442958 -249.128282) (xy 113.393565 -249.112234)
			(xy 113.347291 -249.088656) (xy 113.305275 -249.05813) (xy 113.268552 -249.021407) (xy 113.238026 -248.979391)
			(xy 113.214448 -248.933117) (xy 113.1984 -248.883724) (xy 113.190275 -248.832429) (xy 108.715418 -248.832429)
			(xy 108.721166 -248.840945) (xy 108.74231 -248.885264) (xy 108.756657 -248.932224) (xy 108.763892 -248.980792)
			(xy 108.764324 -249.005344) (xy 108.763815 -249.031311) (xy 108.75569 -249.082606) (xy 108.739642 -249.131999)
			(xy 108.716064 -249.178273) (xy 108.685538 -249.220289) (xy 108.678741 -249.227086) (xy 115.052348 -249.227086)
			(xy 115.052816 -249.202535) (xy 115.06005 -249.15397) (xy 115.074388 -249.107008) (xy 115.095514 -249.062684)
			(xy 115.122962 -249.021971) (xy 115.139216 -249.003566) (xy 115.14903 -248.992086) (xy 115.162037 -248.964845)
			(xy 115.166501 -248.93499) (xy 115.162031 -248.905135) (xy 115.149018 -248.877896) (xy 115.139216 -248.866406)
			(xy 115.122941 -248.848016) (xy 115.095474 -248.807308) (xy 115.074339 -248.762981) (xy 115.06 -248.716013)
			(xy 115.052774 -248.66744) (xy 115.052348 -248.642886) (xy 115.052857 -248.616919) (xy 115.060982 -248.565624)
			(xy 115.07703 -248.516231) (xy 115.100608 -248.469957) (xy 115.131134 -248.427941) (xy 115.167857 -248.391218)
			(xy 115.209873 -248.360692) (xy 115.256147 -248.337114) (xy 115.30554 -248.321066) (xy 115.356835 -248.312941)
			(xy 115.408769 -248.312941) (xy 115.460064 -248.321066) (xy 115.509457 -248.337114) (xy 115.555731 -248.360692)
			(xy 115.597747 -248.391218) (xy 115.63447 -248.427941) (xy 115.664996 -248.469957) (xy 115.688574 -248.516231)
			(xy 115.704622 -248.565624) (xy 115.712747 -248.616919) (xy 115.713256 -248.642886) (xy 115.712831 -248.667438)
			(xy 115.705586 -248.716006) (xy 115.691238 -248.762968) (xy 115.670103 -248.807291) (xy 115.642646 -248.848002)
			(xy 115.626388 -248.866406) (xy 115.616601 -248.877907) (xy 115.603591 -248.905141) (xy 115.599121 -248.93499)
			(xy 115.603585 -248.964839) (xy 115.61659 -248.992076) (xy 115.626388 -249.003566) (xy 115.642651 -249.021967)
			(xy 115.670119 -249.062672) (xy 115.691257 -249.106996) (xy 115.705598 -249.153961) (xy 115.712828 -249.202533)
			(xy 115.713256 -249.227086) (xy 115.712747 -249.253053) (xy 115.704622 -249.304348) (xy 115.688574 -249.353741)
			(xy 115.664996 -249.400015) (xy 115.63447 -249.442031) (xy 115.597747 -249.478754) (xy 115.555731 -249.50928)
			(xy 115.509457 -249.532858) (xy 115.460064 -249.548906) (xy 115.408769 -249.557031) (xy 115.356835 -249.557031)
			(xy 115.30554 -249.548906) (xy 115.256147 -249.532858) (xy 115.209873 -249.50928) (xy 115.167857 -249.478754)
			(xy 115.131134 -249.442031) (xy 115.100608 -249.400015) (xy 115.07703 -249.353741) (xy 115.060982 -249.304348)
			(xy 115.052857 -249.253053) (xy 115.052348 -249.227086) (xy 108.678741 -249.227086) (xy 108.648815 -249.257012)
			(xy 108.606799 -249.287538) (xy 108.560525 -249.311116) (xy 108.511132 -249.327164) (xy 108.459837 -249.335289)
			(xy 108.407903 -249.335289) (xy 108.356608 -249.327164) (xy 108.307215 -249.311116) (xy 108.260941 -249.287538)
			(xy 108.218925 -249.257012) (xy 108.182202 -249.220289) (xy 108.151676 -249.178273) (xy 108.128098 -249.131999)
			(xy 108.11205 -249.082606) (xy 108.103925 -249.031311) (xy 108.103416 -249.005344) (xy 105.154984 -249.005344)
			(xy 104.514083 -249.646245) (xy 109.900975 -249.646245) (xy 109.900975 -249.594311) (xy 109.9091 -249.543016)
			(xy 109.925148 -249.493623) (xy 109.948726 -249.447349) (xy 109.979252 -249.405333) (xy 110.015975 -249.36861)
			(xy 110.057991 -249.338084) (xy 110.104265 -249.314506) (xy 110.153658 -249.298458) (xy 110.204953 -249.290333)
			(xy 110.256887 -249.290333) (xy 110.308182 -249.298458) (xy 110.357575 -249.314506) (xy 110.403849 -249.338084)
			(xy 110.445865 -249.36861) (xy 110.482588 -249.405333) (xy 110.513114 -249.447349) (xy 110.536692 -249.493623)
			(xy 110.55274 -249.543016) (xy 110.560865 -249.594311) (xy 110.561374 -249.620278) (xy 110.560865 -249.646245)
			(xy 110.55274 -249.69754) (xy 110.536692 -249.746933) (xy 110.513114 -249.793207) (xy 110.482588 -249.835223)
			(xy 110.445865 -249.871946) (xy 110.403849 -249.902472) (xy 110.357575 -249.92605) (xy 110.308182 -249.942098)
			(xy 110.256887 -249.950223) (xy 110.204953 -249.950223) (xy 110.153658 -249.942098) (xy 110.104265 -249.92605)
			(xy 110.057991 -249.902472) (xy 110.015975 -249.871946) (xy 109.979252 -249.835223) (xy 109.948726 -249.793207)
			(xy 109.925148 -249.746933) (xy 109.9091 -249.69754) (xy 109.900975 -249.646245) (xy 104.514083 -249.646245)
			(xy 103.844598 -250.31573) (xy 103.844598 -250.363265) (xy 105.127075 -250.363265) (xy 105.127075 -250.311335)
			(xy 105.135199 -250.260044) (xy 105.151246 -250.210655) (xy 105.174821 -250.164385) (xy 105.205345 -250.122372)
			(xy 105.242064 -250.085651) (xy 105.284076 -250.055126) (xy 105.330346 -250.03155) (xy 105.379734 -250.015501)
			(xy 105.431025 -250.007376) (xy 105.45699 -250.006866) (xy 105.482743 -250.007367) (xy 105.533628 -250.015345)
			(xy 105.582657 -250.031124) (xy 105.628643 -250.054321) (xy 105.670471 -250.084376) (xy 105.689146 -250.102116)
			(xy 105.698836 -250.111109) (xy 105.721768 -250.124241) (xy 105.747307 -250.131036) (xy 105.773733 -250.131036)
			(xy 105.799272 -250.124241) (xy 105.822204 -250.111109) (xy 105.831894 -250.102116) (xy 105.850579 -250.084388)
			(xy 105.89241 -250.05434) (xy 105.938394 -250.031143) (xy 105.987418 -250.015356) (xy 106.038298 -250.007362)
			(xy 106.06405 -250.006866) (xy 106.090023 -250.007305) (xy 106.141332 -250.015424) (xy 106.190738 -250.031471)
			(xy 106.237025 -250.055049) (xy 106.279054 -250.085579) (xy 106.315788 -250.122308) (xy 106.346325 -250.164332)
			(xy 106.36991 -250.210616) (xy 106.385964 -250.26002) (xy 106.394091 -250.311327) (xy 106.394091 -250.363265)
			(xy 117.494075 -250.363265) (xy 117.494075 -250.311335) (xy 117.502199 -250.260043) (xy 117.518246 -250.210654)
			(xy 117.541822 -250.164383) (xy 117.572346 -250.12237) (xy 117.609067 -250.085649) (xy 117.651079 -250.055124)
			(xy 117.69735 -250.031548) (xy 117.746739 -250.0155) (xy 117.798031 -250.007375) (xy 117.823996 -250.006866)
			(xy 117.849856 -250.007377) (xy 117.900948 -250.015422) (xy 117.95016 -250.031332) (xy 117.996292 -250.054717)
			(xy 118.038215 -250.085007) (xy 118.056914 -250.102878) (xy 118.066629 -250.111923) (xy 118.089638 -250.125135)
			(xy 118.115275 -250.131972) (xy 118.141809 -250.131972) (xy 118.167446 -250.125135) (xy 118.190455 -250.111923)
			(xy 118.20017 -250.102878) (xy 118.218859 -250.084997) (xy 118.26079 -250.054717) (xy 118.306925 -250.031335)
			(xy 118.356137 -250.015423) (xy 118.407227 -250.007367) (xy 118.433088 -250.006866) (xy 118.459059 -250.007308)
			(xy 118.510363 -250.015432) (xy 118.559764 -250.031482) (xy 118.606046 -250.055062) (xy 118.64807 -250.085593)
			(xy 118.6848 -250.122321) (xy 118.715332 -250.164343) (xy 118.738914 -250.210625) (xy 118.754965 -250.260025)
			(xy 118.763091 -250.311329) (xy 118.763091 -250.363271) (xy 118.754965 -250.414575) (xy 118.738914 -250.463975)
			(xy 118.715332 -250.510257) (xy 118.6848 -250.552279) (xy 118.64807 -250.589007) (xy 118.606046 -250.619538)
			(xy 118.559764 -250.643118) (xy 118.510363 -250.659168) (xy 118.459059 -250.667292) (xy 118.433088 -250.667774)
			(xy 118.407228 -250.667262) (xy 118.356137 -250.659216) (xy 118.306925 -250.643306) (xy 118.260793 -250.619921)
			(xy 118.218869 -250.589632) (xy 118.20017 -250.571762) (xy 118.190455 -250.562717) (xy 118.167446 -250.549505)
			(xy 118.141809 -250.542668) (xy 118.115275 -250.542668) (xy 118.089638 -250.549505) (xy 118.066629 -250.562717)
			(xy 118.056914 -250.571762) (xy 118.038222 -250.58964) (xy 117.996293 -250.619923) (xy 117.95016 -250.643306)
			(xy 117.900947 -250.659219) (xy 117.849857 -250.667274) (xy 117.823996 -250.667774) (xy 117.798031 -250.667225)
			(xy 117.746739 -250.6591) (xy 117.69735 -250.643052) (xy 117.651079 -250.619476) (xy 117.609067 -250.588951)
			(xy 117.572346 -250.55223) (xy 117.541822 -250.510217) (xy 117.518246 -250.463946) (xy 117.502199 -250.414557)
			(xy 117.494075 -250.363265) (xy 106.394091 -250.363265) (xy 106.394091 -250.363273) (xy 106.385964 -250.41458)
			(xy 106.36991 -250.463984) (xy 106.346325 -250.510268) (xy 106.315788 -250.552292) (xy 106.279054 -250.589021)
			(xy 106.237025 -250.619551) (xy 106.190738 -250.643129) (xy 106.141332 -250.659176) (xy 106.090023 -250.667295)
			(xy 106.06405 -250.667774) (xy 106.038295 -250.667328) (xy 105.987407 -250.659339) (xy 105.938376 -250.643548)
			(xy 105.892391 -250.620338) (xy 105.850566 -250.590271) (xy 105.831894 -250.572524) (xy 105.822204 -250.563531)
			(xy 105.799272 -250.550399) (xy 105.773733 -250.543604) (xy 105.747307 -250.543604) (xy 105.721768 -250.550399)
			(xy 105.698836 -250.563531) (xy 105.689146 -250.572524) (xy 105.670494 -250.590288) (xy 105.628654 -250.620329)
			(xy 105.582661 -250.64352) (xy 105.533629 -250.659298) (xy 105.482744 -250.667283) (xy 105.45699 -250.667774)
			(xy 105.431025 -250.667224) (xy 105.379734 -250.659099) (xy 105.330346 -250.64305) (xy 105.284076 -250.619474)
			(xy 105.242064 -250.588949) (xy 105.205345 -250.552228) (xy 105.174821 -250.510215) (xy 105.151246 -250.463945)
			(xy 105.135199 -250.414556) (xy 105.127075 -250.363265) (xy 103.844598 -250.363265) (xy 103.844598 -252.659388)
			(xy 108.103416 -252.659388) (xy 108.103867 -252.634836) (xy 108.111103 -252.586269) (xy 108.125444 -252.539307)
			(xy 108.146573 -252.494983) (xy 108.174027 -252.454272) (xy 108.190284 -252.435868) (xy 108.200098 -252.424388)
			(xy 108.21311 -252.397147) (xy 108.217575 -252.367291) (xy 108.213104 -252.337436) (xy 108.200088 -252.310198)
			(xy 108.190284 -252.298708) (xy 108.174004 -252.280322) (xy 108.14654 -252.239612) (xy 108.125406 -252.195284)
			(xy 108.111068 -252.148316) (xy 108.103842 -252.099742) (xy 108.103416 -252.075188) (xy 108.103925 -252.049221)
			(xy 108.11205 -251.997926) (xy 108.128098 -251.948533) (xy 108.151676 -251.902259) (xy 108.182202 -251.860243)
			(xy 108.218925 -251.82352) (xy 108.260941 -251.792994) (xy 108.307215 -251.769416) (xy 108.356608 -251.753368)
			(xy 108.407903 -251.745243) (xy 108.459837 -251.745243) (xy 108.511132 -251.753368) (xy 108.560525 -251.769416)
			(xy 108.606799 -251.792994) (xy 108.648815 -251.82352) (xy 108.685538 -251.860243) (xy 108.716064 -251.902259)
			(xy 108.739642 -251.948533) (xy 108.75569 -251.997926) (xy 108.763815 -252.049221) (xy 108.764324 -252.075188)
			(xy 108.763908 -252.099741) (xy 108.756662 -252.148309) (xy 108.742313 -252.195271) (xy 108.721175 -252.239595)
			(xy 108.693715 -252.280305) (xy 108.677456 -252.298708) (xy 108.667662 -252.310205) (xy 108.654642 -252.337439)
			(xy 108.65017 -252.367291) (xy 108.654637 -252.397144) (xy 108.667652 -252.42438) (xy 108.677456 -252.435868)
			(xy 108.693714 -252.454272) (xy 108.721184 -252.494976) (xy 108.742324 -252.539299) (xy 108.756666 -252.586264)
			(xy 108.763896 -252.634835) (xy 108.764324 -252.659388) (xy 108.763815 -252.685355) (xy 108.75569 -252.73665)
			(xy 108.739642 -252.786043) (xy 108.729501 -252.805946) (xy 115.103148 -252.805946) (xy 115.103591 -252.781394)
			(xy 115.110832 -252.732828) (xy 115.125175 -252.685866) (xy 115.146306 -252.641542) (xy 115.17376 -252.60083)
			(xy 115.190016 -252.582426) (xy 115.199771 -252.5709) (xy 115.212785 -252.543675) (xy 115.21726 -252.513834)
			(xy 115.212805 -252.48399) (xy 115.199809 -252.456756) (xy 115.190016 -252.445266) (xy 115.173769 -252.426852)
			(xy 115.146299 -252.38615) (xy 115.125158 -252.34183) (xy 115.110812 -252.294867) (xy 115.103579 -252.246299)
			(xy 115.103148 -252.221746) (xy 115.103657 -252.195779) (xy 115.111782 -252.144484) (xy 115.12783 -252.095091)
			(xy 115.151408 -252.048817) (xy 115.181934 -252.006801) (xy 115.218657 -251.970078) (xy 115.260673 -251.939552)
			(xy 115.306947 -251.915974) (xy 115.35634 -251.899926) (xy 115.407635 -251.891801) (xy 115.459569 -251.891801)
			(xy 115.510864 -251.899926) (xy 115.560257 -251.915974) (xy 115.606531 -251.939552) (xy 115.648547 -251.970078)
			(xy 115.68527 -252.006801) (xy 115.715796 -252.048817) (xy 115.739374 -252.095091) (xy 115.755422 -252.144484)
			(xy 115.763547 -252.195779) (xy 115.764056 -252.221746) (xy 115.763607 -252.246298) (xy 115.756367 -252.294864)
			(xy 115.742025 -252.341825) (xy 115.720896 -252.386149) (xy 115.693443 -252.426861) (xy 115.677188 -252.445266)
			(xy 115.667342 -252.456721) (xy 115.654339 -252.483971) (xy 115.64988 -252.513834) (xy 115.654358 -252.543694)
			(xy 115.667381 -252.570935) (xy 115.677188 -252.582426) (xy 115.693432 -252.600843) (xy 115.720902 -252.641544)
			(xy 115.742044 -252.685864) (xy 115.75639 -252.732825) (xy 115.763625 -252.781394) (xy 115.764056 -252.805946)
			(xy 115.763547 -252.831913) (xy 115.755422 -252.883208) (xy 115.739374 -252.932601) (xy 115.715796 -252.978875)
			(xy 115.68527 -253.020891) (xy 115.648547 -253.057614) (xy 115.606531 -253.08814) (xy 115.560257 -253.111718)
			(xy 115.510864 -253.127766) (xy 115.459569 -253.135891) (xy 115.407635 -253.135891) (xy 115.35634 -253.127766)
			(xy 115.306947 -253.111718) (xy 115.260673 -253.08814) (xy 115.218657 -253.057614) (xy 115.181934 -253.020891)
			(xy 115.151408 -252.978875) (xy 115.12783 -252.932601) (xy 115.111782 -252.883208) (xy 115.103657 -252.831913)
			(xy 115.103148 -252.805946) (xy 108.729501 -252.805946) (xy 108.716064 -252.832317) (xy 108.685538 -252.874333)
			(xy 108.648815 -252.911056) (xy 108.606799 -252.941582) (xy 108.560525 -252.96516) (xy 108.511132 -252.981208)
			(xy 108.459837 -252.989333) (xy 108.407903 -252.989333) (xy 108.356608 -252.981208) (xy 108.307215 -252.96516)
			(xy 108.260941 -252.941582) (xy 108.218925 -252.911056) (xy 108.182202 -252.874333) (xy 108.151676 -252.832317)
			(xy 108.128098 -252.786043) (xy 108.11205 -252.73665) (xy 108.103925 -252.685355) (xy 108.103416 -252.659388)
			(xy 103.844598 -252.659388) (xy 103.844598 -254.041164) (xy 105.127095 -254.041164) (xy 105.127095 -253.989236)
			(xy 105.135218 -253.937949) (xy 105.151264 -253.888563) (xy 105.174838 -253.842295) (xy 105.20536 -253.800285)
			(xy 105.242077 -253.763566) (xy 105.284087 -253.733043) (xy 105.330354 -253.709468) (xy 105.379739 -253.69342)
			(xy 105.431026 -253.685296) (xy 105.45699 -253.684786) (xy 105.482743 -253.685281) (xy 105.533628 -253.693259)
			(xy 105.582658 -253.709039) (xy 105.628644 -253.732239) (xy 105.670472 -253.762295) (xy 105.689146 -253.780036)
			(xy 105.698836 -253.789029) (xy 105.721768 -253.802161) (xy 105.747307 -253.808956) (xy 105.773733 -253.808956)
			(xy 105.799272 -253.802161) (xy 105.822204 -253.789029) (xy 105.831894 -253.780036) (xy 105.850582 -253.762311)
			(xy 105.892412 -253.732263) (xy 105.938395 -253.709064) (xy 105.987419 -253.693276) (xy 106.038298 -253.685282)
			(xy 106.06405 -253.684786) (xy 106.090025 -253.685185) (xy 106.141336 -253.693305) (xy 106.190746 -253.709352)
			(xy 106.237036 -253.732932) (xy 106.279067 -253.763464) (xy 106.315804 -253.800195) (xy 106.346342 -253.842222)
			(xy 106.369928 -253.888508) (xy 106.385983 -253.937915) (xy 106.387257 -253.945957) (xy 113.300003 -253.945957)
			(xy 113.300003 -253.894023) (xy 113.308128 -253.842728) (xy 113.324176 -253.793335) (xy 113.347754 -253.747061)
			(xy 113.37828 -253.705045) (xy 113.415003 -253.668322) (xy 113.457019 -253.637796) (xy 113.503293 -253.614218)
			(xy 113.552686 -253.59817) (xy 113.603981 -253.590045) (xy 113.655915 -253.590045) (xy 113.70721 -253.59817)
			(xy 113.756603 -253.614218) (xy 113.802877 -253.637796) (xy 113.844893 -253.668322) (xy 113.881616 -253.705045)
			(xy 113.912142 -253.747061) (xy 113.93572 -253.793335) (xy 113.951768 -253.842728) (xy 113.959893 -253.894023)
			(xy 113.960402 -253.91999) (xy 113.959893 -253.945957) (xy 113.951768 -253.997252) (xy 113.937501 -254.041164)
			(xy 117.494095 -254.041164) (xy 117.494095 -253.989236) (xy 117.502218 -253.937948) (xy 117.518265 -253.888561)
			(xy 117.541839 -253.842293) (xy 117.572361 -253.800283) (xy 117.60908 -253.763564) (xy 117.65109 -253.733041)
			(xy 117.697358 -253.709466) (xy 117.746744 -253.693419) (xy 117.798032 -253.685295) (xy 117.823996 -253.684786)
			(xy 117.849857 -253.685291) (xy 117.900948 -253.693337) (xy 117.950162 -253.709247) (xy 117.996293 -253.732635)
			(xy 118.038216 -253.762926) (xy 118.056914 -253.780798) (xy 118.066629 -253.789843) (xy 118.089638 -253.803055)
			(xy 118.115275 -253.809892) (xy 118.141809 -253.809892) (xy 118.167446 -253.803055) (xy 118.190455 -253.789843)
			(xy 118.20017 -253.780798) (xy 118.218862 -253.762921) (xy 118.260792 -253.732639) (xy 118.306926 -253.709257)
			(xy 118.356138 -253.693343) (xy 118.407228 -253.685287) (xy 118.433088 -253.684786) (xy 118.459061 -253.685188)
			(xy 118.510368 -253.693313) (xy 118.559772 -253.709363) (xy 118.606057 -253.732945) (xy 118.648083 -253.763477)
			(xy 118.684815 -253.800208) (xy 118.715349 -253.842233) (xy 118.738932 -253.888517) (xy 118.754985 -253.93792)
			(xy 118.763111 -253.989227) (xy 118.763111 -254.041173) (xy 118.754985 -254.09248) (xy 118.738932 -254.141883)
			(xy 118.715349 -254.188167) (xy 118.684815 -254.230192) (xy 118.648083 -254.266923) (xy 118.606057 -254.297455)
			(xy 118.559772 -254.321037) (xy 118.510368 -254.337087) (xy 118.459061 -254.345212) (xy 118.433088 -254.345694)
			(xy 118.407227 -254.345205) (xy 118.356134 -254.337156) (xy 118.30692 -254.321242) (xy 118.260789 -254.297851)
			(xy 118.218867 -254.267556) (xy 118.20017 -254.249682) (xy 118.190455 -254.240637) (xy 118.167446 -254.227425)
			(xy 118.141809 -254.220588) (xy 118.115275 -254.220588) (xy 118.089638 -254.227425) (xy 118.066629 -254.240637)
			(xy 118.056914 -254.249682) (xy 118.038226 -254.267564) (xy 117.996295 -254.297845) (xy 117.950161 -254.321227)
			(xy 117.900948 -254.33714) (xy 117.849857 -254.345194) (xy 117.823996 -254.345694) (xy 117.798032 -254.345105)
			(xy 117.746744 -254.336981) (xy 117.697358 -254.320934) (xy 117.65109 -254.297359) (xy 117.60908 -254.266836)
			(xy 117.572361 -254.230117) (xy 117.541839 -254.188107) (xy 117.518265 -254.141839) (xy 117.502218 -254.092452)
			(xy 117.494095 -254.041164) (xy 113.937501 -254.041164) (xy 113.93572 -254.046645) (xy 113.912142 -254.092919)
			(xy 113.881616 -254.134935) (xy 113.844893 -254.171658) (xy 113.802877 -254.202184) (xy 113.756603 -254.225762)
			(xy 113.70721 -254.24181) (xy 113.655915 -254.249935) (xy 113.603981 -254.249935) (xy 113.552686 -254.24181)
			(xy 113.503293 -254.225762) (xy 113.457019 -254.202184) (xy 113.415003 -254.171658) (xy 113.37828 -254.134935)
			(xy 113.347754 -254.092919) (xy 113.324176 -254.046645) (xy 113.308128 -253.997252) (xy 113.300003 -253.945957)
			(xy 106.387257 -253.945957) (xy 106.394111 -253.989225) (xy 106.394111 -254.041175) (xy 106.385983 -254.092485)
			(xy 106.369928 -254.141892) (xy 106.346342 -254.188178) (xy 106.315804 -254.230205) (xy 106.279067 -254.266936)
			(xy 106.237036 -254.297468) (xy 106.190746 -254.321048) (xy 106.141336 -254.337095) (xy 106.090025 -254.345215)
			(xy 106.06405 -254.345694) (xy 106.038295 -254.345242) (xy 105.987408 -254.337254) (xy 105.938377 -254.321464)
			(xy 105.892392 -254.298255) (xy 105.850567 -254.26819) (xy 105.831894 -254.250444) (xy 105.822204 -254.241451)
			(xy 105.799272 -254.228319) (xy 105.773733 -254.221524) (xy 105.747307 -254.221524) (xy 105.721768 -254.228319)
			(xy 105.698836 -254.241451) (xy 105.689146 -254.250444) (xy 105.670481 -254.268194) (xy 105.628645 -254.29824)
			(xy 105.582657 -254.321435) (xy 105.533627 -254.337216) (xy 105.482743 -254.345203) (xy 105.45699 -254.345694)
			(xy 105.431026 -254.345104) (xy 105.379739 -254.33698) (xy 105.330354 -254.320932) (xy 105.284087 -254.297357)
			(xy 105.242077 -254.266834) (xy 105.20536 -254.230115) (xy 105.174838 -254.188105) (xy 105.151264 -254.141837)
			(xy 105.135218 -254.092451) (xy 105.127095 -254.041164) (xy 103.844598 -254.041164) (xy 103.844598 -254.759773)
			(xy 110.010703 -254.759773) (xy 110.010703 -254.707839) (xy 110.018828 -254.656544) (xy 110.034876 -254.607151)
			(xy 110.058454 -254.560877) (xy 110.08898 -254.518861) (xy 110.125703 -254.482138) (xy 110.167719 -254.451612)
			(xy 110.213993 -254.428034) (xy 110.263386 -254.411986) (xy 110.314681 -254.403861) (xy 110.366615 -254.403861)
			(xy 110.41791 -254.411986) (xy 110.467303 -254.428034) (xy 110.513577 -254.451612) (xy 110.555593 -254.482138)
			(xy 110.592316 -254.518861) (xy 110.622842 -254.560877) (xy 110.64642 -254.607151) (xy 110.662468 -254.656544)
			(xy 110.670593 -254.707839) (xy 110.671102 -254.733806) (xy 110.670593 -254.759773) (xy 110.662468 -254.811068)
			(xy 110.64642 -254.860461) (xy 110.622842 -254.906735) (xy 110.592316 -254.948751) (xy 110.555593 -254.985474)
			(xy 110.513577 -255.016) (xy 110.467303 -255.039578) (xy 110.41791 -255.055626) (xy 110.366615 -255.063751)
			(xy 110.314681 -255.063751) (xy 110.263386 -255.055626) (xy 110.213993 -255.039578) (xy 110.167719 -255.016)
			(xy 110.125703 -254.985474) (xy 110.08898 -254.948751) (xy 110.058454 -254.906735) (xy 110.034876 -254.860461)
			(xy 110.018828 -254.811068) (xy 110.010703 -254.759773) (xy 103.844598 -254.759773) (xy 103.844598 -256.33045)
			(xy 108.103416 -256.33045) (xy 108.103844 -256.305897) (xy 108.111086 -256.257329) (xy 108.125432 -256.210367)
			(xy 108.146567 -256.166043) (xy 108.174025 -256.125333) (xy 108.190284 -256.10693) (xy 108.200038 -256.095402)
			(xy 108.213056 -256.068179) (xy 108.217534 -256.038337) (xy 108.213078 -256.008492) (xy 108.200079 -255.981259)
			(xy 108.190284 -255.96977) (xy 108.174034 -255.951359) (xy 108.146565 -255.910656) (xy 108.125425 -255.866334)
			(xy 108.11108 -255.819372) (xy 108.103847 -255.770803) (xy 108.103416 -255.74625) (xy 108.103925 -255.720283)
			(xy 108.11205 -255.668988) (xy 108.128098 -255.619595) (xy 108.151676 -255.573321) (xy 108.182202 -255.531305)
			(xy 108.218925 -255.494582) (xy 108.260941 -255.464056) (xy 108.307215 -255.440478) (xy 108.356608 -255.42443)
			(xy 108.407903 -255.416305) (xy 108.459837 -255.416305) (xy 108.511132 -255.42443) (xy 108.560525 -255.440478)
			(xy 108.606799 -255.464056) (xy 108.648815 -255.494582) (xy 108.685538 -255.531305) (xy 108.716064 -255.573321)
			(xy 108.71633 -255.573843) (xy 113.300003 -255.573843) (xy 113.300003 -255.521909) (xy 113.308128 -255.470614)
			(xy 113.324176 -255.421221) (xy 113.347754 -255.374947) (xy 113.37828 -255.332931) (xy 113.415003 -255.296208)
			(xy 113.457019 -255.265682) (xy 113.503293 -255.242104) (xy 113.552686 -255.226056) (xy 113.603981 -255.217931)
			(xy 113.655915 -255.217931) (xy 113.70721 -255.226056) (xy 113.756603 -255.242104) (xy 113.802877 -255.265682)
			(xy 113.844893 -255.296208) (xy 113.881616 -255.332931) (xy 113.912142 -255.374947) (xy 113.93572 -255.421221)
			(xy 113.951768 -255.470614) (xy 113.959893 -255.521909) (xy 113.960402 -255.547876) (xy 113.959893 -255.573843)
			(xy 113.951768 -255.625138) (xy 113.93572 -255.674531) (xy 113.912142 -255.720805) (xy 113.881616 -255.762821)
			(xy 113.844893 -255.799544) (xy 113.802877 -255.83007) (xy 113.756603 -255.853648) (xy 113.70721 -255.869696)
			(xy 113.655915 -255.877821) (xy 113.603981 -255.877821) (xy 113.552686 -255.869696) (xy 113.503293 -255.853648)
			(xy 113.457019 -255.83007) (xy 113.415003 -255.799544) (xy 113.37828 -255.762821) (xy 113.347754 -255.720805)
			(xy 113.324176 -255.674531) (xy 113.308128 -255.625138) (xy 113.300003 -255.573843) (xy 108.71633 -255.573843)
			(xy 108.739642 -255.619595) (xy 108.75569 -255.668988) (xy 108.763815 -255.720283) (xy 108.764324 -255.74625)
			(xy 108.763885 -255.770802) (xy 108.756645 -255.819369) (xy 108.742301 -255.866331) (xy 108.721168 -255.910655)
			(xy 108.693713 -255.951366) (xy 108.677456 -255.96977) (xy 108.667601 -255.98122) (xy 108.654589 -256.00847)
			(xy 108.650128 -256.038337) (xy 108.654611 -256.068201) (xy 108.667643 -256.095442) (xy 108.677456 -256.10693)
			(xy 108.693696 -256.12535) (xy 108.721169 -256.166049) (xy 108.742312 -256.210368) (xy 108.756658 -256.25733)
			(xy 108.763893 -256.305898) (xy 108.764324 -256.33045) (xy 108.763815 -256.356417) (xy 108.758866 -256.387659)
			(xy 110.010449 -256.387659) (xy 110.010449 -256.335725) (xy 110.018574 -256.28443) (xy 110.034622 -256.235037)
			(xy 110.0582 -256.188763) (xy 110.088726 -256.146747) (xy 110.125449 -256.110024) (xy 110.167465 -256.079498)
			(xy 110.213739 -256.05592) (xy 110.263132 -256.039872) (xy 110.314427 -256.031747) (xy 110.366361 -256.031747)
			(xy 110.417656 -256.039872) (xy 110.467049 -256.05592) (xy 110.513323 -256.079498) (xy 110.555339 -256.110024)
			(xy 110.592062 -256.146747) (xy 110.622588 -256.188763) (xy 110.646166 -256.235037) (xy 110.662214 -256.28443)
			(xy 110.670339 -256.335725) (xy 110.670848 -256.361692) (xy 110.670339 -256.387659) (xy 110.669986 -256.389886)
			(xy 115.098068 -256.389886) (xy 115.09853 -256.365335) (xy 115.105765 -256.316769) (xy 115.120104 -256.269807)
			(xy 115.141231 -256.225483) (xy 115.168681 -256.184771) (xy 115.184936 -256.166366) (xy 115.194756 -256.154889)
			(xy 115.207774 -256.127648) (xy 115.212241 -256.09779) (xy 115.207768 -256.067932) (xy 115.194745 -256.040694)
			(xy 115.184936 -256.029206) (xy 115.168664 -256.010813) (xy 115.141196 -255.970106) (xy 115.12006 -255.92578)
			(xy 115.10572 -255.878813) (xy 115.098494 -255.83024) (xy 115.098068 -255.805686) (xy 115.098577 -255.779719)
			(xy 115.106702 -255.728424) (xy 115.12275 -255.679031) (xy 115.146328 -255.632757) (xy 115.176854 -255.590741)
			(xy 115.213577 -255.554018) (xy 115.255593 -255.523492) (xy 115.301867 -255.499914) (xy 115.35126 -255.483866)
			(xy 115.402555 -255.475741) (xy 115.454489 -255.475741) (xy 115.505784 -255.483866) (xy 115.555177 -255.499914)
			(xy 115.601451 -255.523492) (xy 115.643467 -255.554018) (xy 115.68019 -255.590741) (xy 115.710716 -255.632757)
			(xy 115.734294 -255.679031) (xy 115.750342 -255.728424) (xy 115.758467 -255.779719) (xy 115.758976 -255.805686)
			(xy 115.758546 -255.830238) (xy 115.751301 -255.878805) (xy 115.736954 -255.925767) (xy 115.71582 -255.97009)
			(xy 115.688365 -256.010802) (xy 115.672108 -256.029206) (xy 115.66232 -256.040706) (xy 115.649307 -256.06794)
			(xy 115.644836 -256.09779) (xy 115.6493 -256.12764) (xy 115.662308 -256.154876) (xy 115.672108 -256.166366)
			(xy 115.688374 -256.184764) (xy 115.715841 -256.22547) (xy 115.736978 -256.269795) (xy 115.751319 -256.316761)
			(xy 115.758548 -256.365332) (xy 115.758976 -256.389886) (xy 115.758467 -256.415853) (xy 115.750342 -256.467148)
			(xy 115.734294 -256.516541) (xy 115.710716 -256.562815) (xy 115.68019 -256.604831) (xy 115.643467 -256.641554)
			(xy 115.601451 -256.67208) (xy 115.555177 -256.695658) (xy 115.505784 -256.711706) (xy 115.454489 -256.719831)
			(xy 115.402555 -256.719831) (xy 115.35126 -256.711706) (xy 115.301867 -256.695658) (xy 115.255593 -256.67208)
			(xy 115.213577 -256.641554) (xy 115.176854 -256.604831) (xy 115.146328 -256.562815) (xy 115.12275 -256.516541)
			(xy 115.106702 -256.467148) (xy 115.098577 -256.415853) (xy 115.098068 -256.389886) (xy 110.669986 -256.389886)
			(xy 110.662214 -256.438954) (xy 110.646166 -256.488347) (xy 110.622588 -256.534621) (xy 110.592062 -256.576637)
			(xy 110.555339 -256.61336) (xy 110.513323 -256.643886) (xy 110.467049 -256.667464) (xy 110.417656 -256.683512)
			(xy 110.366361 -256.691637) (xy 110.314427 -256.691637) (xy 110.263132 -256.683512) (xy 110.213739 -256.667464)
			(xy 110.167465 -256.643886) (xy 110.125449 -256.61336) (xy 110.088726 -256.576637) (xy 110.0582 -256.534621)
			(xy 110.034622 -256.488347) (xy 110.018574 -256.438954) (xy 110.010449 -256.387659) (xy 108.758866 -256.387659)
			(xy 108.75569 -256.407712) (xy 108.739642 -256.457105) (xy 108.716064 -256.503379) (xy 108.685538 -256.545395)
			(xy 108.648815 -256.582118) (xy 108.606799 -256.612644) (xy 108.560525 -256.636222) (xy 108.511132 -256.65227)
			(xy 108.459837 -256.660395) (xy 108.407903 -256.660395) (xy 108.356608 -256.65227) (xy 108.307215 -256.636222)
			(xy 108.260941 -256.612644) (xy 108.218925 -256.582118) (xy 108.182202 -256.545395) (xy 108.151676 -256.503379)
			(xy 108.128098 -256.457105) (xy 108.11205 -256.407712) (xy 108.103925 -256.356417) (xy 108.103416 -256.33045)
			(xy 103.844598 -256.33045) (xy 103.844598 -257.201475) (xy 113.300003 -257.201475) (xy 113.300003 -257.149541)
			(xy 113.308128 -257.098246) (xy 113.324176 -257.048853) (xy 113.347754 -257.002579) (xy 113.37828 -256.960563)
			(xy 113.415003 -256.92384) (xy 113.457019 -256.893314) (xy 113.503293 -256.869736) (xy 113.552686 -256.853688)
			(xy 113.603981 -256.845563) (xy 113.655915 -256.845563) (xy 113.70721 -256.853688) (xy 113.756603 -256.869736)
			(xy 113.802877 -256.893314) (xy 113.844893 -256.92384) (xy 113.881616 -256.960563) (xy 113.912142 -257.002579)
			(xy 113.93572 -257.048853) (xy 113.951768 -257.098246) (xy 113.959893 -257.149541) (xy 113.960402 -257.175508)
			(xy 113.959893 -257.201475) (xy 113.951768 -257.25277) (xy 113.93572 -257.302163) (xy 113.912142 -257.348437)
			(xy 113.881616 -257.390453) (xy 113.844893 -257.427176) (xy 113.802877 -257.457702) (xy 113.756603 -257.48128)
			(xy 113.70721 -257.497328) (xy 113.655915 -257.505453) (xy 113.603981 -257.505453) (xy 113.552686 -257.497328)
			(xy 113.503293 -257.48128) (xy 113.457019 -257.457702) (xy 113.415003 -257.427176) (xy 113.37828 -257.390453)
			(xy 113.347754 -257.348437) (xy 113.324176 -257.302163) (xy 113.308128 -257.25277) (xy 113.300003 -257.201475)
			(xy 103.844598 -257.201475) (xy 103.844598 -257.26263) (xy 103.845004 -257.276722) (xy 103.852621 -257.303852)
			(xy 103.867376 -257.32786) (xy 103.888142 -257.346911) (xy 103.91333 -257.359546) (xy 103.941015 -257.364802)
			(xy 103.955088 -257.363976) (xy 103.98379 -257.362706) (xy 104.008344 -257.363133) (xy 104.056918 -257.370358)
			(xy 104.103886 -257.384696) (xy 104.148214 -257.40583) (xy 104.188924 -257.433294) (xy 104.20731 -257.449574)
			(xy 104.218799 -257.459377) (xy 104.246036 -257.472391) (xy 104.27589 -257.476859) (xy 104.305744 -257.472391)
			(xy 104.332981 -257.459377) (xy 104.34447 -257.449574) (xy 104.362874 -257.433318) (xy 104.403585 -257.405865)
			(xy 104.44791 -257.384736) (xy 104.494872 -257.370396) (xy 104.543438 -257.363161) (xy 104.56799 -257.362706)
			(xy 104.593963 -257.363188) (xy 104.645269 -257.371313) (xy 104.694673 -257.387364) (xy 104.740958 -257.410946)
			(xy 104.782984 -257.441478) (xy 104.819715 -257.478209) (xy 104.850249 -257.520234) (xy 104.873832 -257.566517)
			(xy 104.889885 -257.615921) (xy 104.898011 -257.667227) (xy 104.898011 -257.71917) (xy 105.127015 -257.71917)
			(xy 105.127015 -257.66723) (xy 105.13514 -257.61593) (xy 105.15119 -257.566532) (xy 105.17477 -257.520253)
			(xy 105.205299 -257.478233) (xy 105.242025 -257.441505) (xy 105.284045 -257.410975) (xy 105.330323 -257.387394)
			(xy 105.37972 -257.371343) (xy 105.43102 -257.363216) (xy 105.45699 -257.362706) (xy 105.482744 -257.363196)
			(xy 105.533629 -257.371174) (xy 105.582659 -257.386955) (xy 105.628645 -257.410156) (xy 105.670472 -257.440214)
			(xy 105.689146 -257.457956) (xy 105.698836 -257.466949) (xy 105.721768 -257.480081) (xy 105.747307 -257.486876)
			(xy 105.773733 -257.486876) (xy 105.799272 -257.480081) (xy 105.822204 -257.466949) (xy 105.831894 -257.457956)
			(xy 105.850585 -257.440235) (xy 105.892413 -257.410185) (xy 105.938396 -257.386985) (xy 105.987419 -257.371197)
			(xy 106.038298 -257.363202) (xy 106.06405 -257.362706) (xy 106.090019 -257.363265) (xy 106.141318 -257.371383)
			(xy 106.190715 -257.387426) (xy 106.236994 -257.411) (xy 106.279015 -257.441525) (xy 106.315743 -257.478247)
			(xy 106.346273 -257.520263) (xy 106.369855 -257.566539) (xy 106.385906 -257.615934) (xy 106.394031 -257.667231)
			(xy 106.394031 -257.719169) (xy 106.385906 -257.770466) (xy 106.369855 -257.819861) (xy 106.346273 -257.866137)
			(xy 106.315743 -257.908153) (xy 106.279015 -257.944875) (xy 106.236994 -257.9754) (xy 106.190715 -257.998974)
			(xy 106.141318 -258.015017) (xy 106.139587 -258.015291) (xy 110.010703 -258.015291) (xy 110.010703 -257.963357)
			(xy 110.018828 -257.912062) (xy 110.034876 -257.862669) (xy 110.058454 -257.816395) (xy 110.08898 -257.774379)
			(xy 110.125703 -257.737656) (xy 110.167719 -257.70713) (xy 110.213993 -257.683552) (xy 110.263386 -257.667504)
			(xy 110.314681 -257.659379) (xy 110.366615 -257.659379) (xy 110.41791 -257.667504) (xy 110.467303 -257.683552)
			(xy 110.513577 -257.70713) (xy 110.555593 -257.737656) (xy 110.592316 -257.774379) (xy 110.622842 -257.816395)
			(xy 110.64642 -257.862669) (xy 110.662468 -257.912062) (xy 110.670593 -257.963357) (xy 110.671102 -257.989324)
			(xy 110.670593 -258.015291) (xy 110.662468 -258.066586) (xy 110.64642 -258.115979) (xy 110.622842 -258.162253)
			(xy 110.592316 -258.204269) (xy 110.555593 -258.240992) (xy 110.513577 -258.271518) (xy 110.467303 -258.295096)
			(xy 110.41791 -258.311144) (xy 110.366615 -258.319269) (xy 110.314681 -258.319269) (xy 110.263386 -258.311144)
			(xy 110.213993 -258.295096) (xy 110.167719 -258.271518) (xy 110.125703 -258.240992) (xy 110.08898 -258.204269)
			(xy 110.058454 -258.162253) (xy 110.034876 -258.115979) (xy 110.018828 -258.066586) (xy 110.010703 -258.015291)
			(xy 106.139587 -258.015291) (xy 106.090019 -258.023135) (xy 106.06405 -258.023614) (xy 106.038295 -258.023156)
			(xy 105.987408 -258.015169) (xy 105.938378 -257.99938) (xy 105.892393 -257.976172) (xy 105.850567 -257.946109)
			(xy 105.831894 -257.928364) (xy 105.822204 -257.919371) (xy 105.799272 -257.906239) (xy 105.773733 -257.899444)
			(xy 105.747307 -257.899444) (xy 105.721768 -257.906239) (xy 105.698836 -257.919371) (xy 105.689146 -257.928364)
			(xy 105.670484 -257.946117) (xy 105.628647 -257.976162) (xy 105.582658 -257.999356) (xy 105.533628 -258.015137)
			(xy 105.482744 -258.023123) (xy 105.45699 -258.023614) (xy 105.43102 -258.023184) (xy 105.37972 -258.015057)
			(xy 105.330323 -257.999006) (xy 105.284045 -257.975425) (xy 105.242025 -257.944895) (xy 105.205299 -257.908167)
			(xy 105.17477 -257.866147) (xy 105.15119 -257.819868) (xy 105.13514 -257.77047) (xy 105.127015 -257.71917)
			(xy 104.898011 -257.71917) (xy 104.898011 -257.719173) (xy 104.889885 -257.770479) (xy 104.873832 -257.819883)
			(xy 104.850249 -257.866166) (xy 104.819715 -257.908191) (xy 104.782984 -257.944922) (xy 104.740958 -257.975454)
			(xy 104.694673 -257.999036) (xy 104.645269 -258.015087) (xy 104.593963 -258.023212) (xy 104.56799 -258.023614)
			(xy 104.543437 -258.023186) (xy 104.494866 -258.015956) (xy 104.447901 -258.001614) (xy 104.403579 -257.980474)
			(xy 104.362875 -257.953004) (xy 104.34447 -257.936746) (xy 104.332981 -257.926943) (xy 104.305744 -257.913929)
			(xy 104.27589 -257.909461) (xy 104.246036 -257.913929) (xy 104.218799 -257.926943) (xy 104.20731 -257.936746)
			(xy 104.188907 -257.953006) (xy 104.148197 -257.980467) (xy 104.103874 -258.001605) (xy 104.056911 -258.015955)
			(xy 104.008343 -258.023202) (xy 103.98379 -258.023614) (xy 103.955088 -258.022344) (xy 103.941029 -258.021577)
			(xy 103.91339 -258.026887) (xy 103.888249 -258.039537) (xy 103.867514 -258.058568) (xy 103.852758 -258.082534)
			(xy 103.845102 -258.109617) (xy 103.844598 -258.12369) (xy 103.844598 -259.578602) (xy 108.103416 -259.578602)
			(xy 108.103815 -259.554048) (xy 108.111064 -259.505479) (xy 108.125417 -259.458516) (xy 108.146558 -259.414193)
			(xy 108.174022 -259.373484) (xy 108.190284 -259.355082) (xy 108.200085 -259.343591) (xy 108.213098 -259.316354)
			(xy 108.217566 -259.286501) (xy 108.213098 -259.256648) (xy 108.200086 -259.229411) (xy 108.190284 -259.217922)
			(xy 108.174011 -259.19953) (xy 108.146546 -259.158822) (xy 108.12541 -259.114496) (xy 108.111071 -259.067529)
			(xy 108.103843 -259.018956) (xy 108.103416 -258.994402) (xy 108.103925 -258.968435) (xy 108.11205 -258.91714)
			(xy 108.128098 -258.867747) (xy 108.151676 -258.821473) (xy 108.182202 -258.779457) (xy 108.218925 -258.742734)
			(xy 108.260941 -258.712208) (xy 108.307215 -258.68863) (xy 108.356608 -258.672582) (xy 108.407903 -258.664457)
			(xy 108.459837 -258.664457) (xy 108.511132 -258.672582) (xy 108.560525 -258.68863) (xy 108.606799 -258.712208)
			(xy 108.648815 -258.742734) (xy 108.685538 -258.779457) (xy 108.716064 -258.821473) (xy 108.720083 -258.829361)
			(xy 113.300003 -258.829361) (xy 113.300003 -258.777427) (xy 113.308128 -258.726132) (xy 113.324176 -258.676739)
			(xy 113.347754 -258.630465) (xy 113.37828 -258.588449) (xy 113.415003 -258.551726) (xy 113.457019 -258.5212)
			(xy 113.503293 -258.497622) (xy 113.552686 -258.481574) (xy 113.603981 -258.473449) (xy 113.655915 -258.473449)
			(xy 113.70721 -258.481574) (xy 113.756603 -258.497622) (xy 113.802877 -258.5212) (xy 113.844893 -258.551726)
			(xy 113.881616 -258.588449) (xy 113.912142 -258.630465) (xy 113.93572 -258.676739) (xy 113.951768 -258.726132)
			(xy 113.959893 -258.777427) (xy 113.960402 -258.803394) (xy 113.959893 -258.829361) (xy 113.951768 -258.880656)
			(xy 113.93572 -258.930049) (xy 113.912142 -258.976323) (xy 113.881616 -259.018339) (xy 113.844893 -259.055062)
			(xy 113.802877 -259.085588) (xy 113.756603 -259.109166) (xy 113.70721 -259.125214) (xy 113.655915 -259.133339)
			(xy 113.603981 -259.133339) (xy 113.552686 -259.125214) (xy 113.503293 -259.109166) (xy 113.457019 -259.085588)
			(xy 113.415003 -259.055062) (xy 113.37828 -259.018339) (xy 113.347754 -258.976323) (xy 113.324176 -258.930049)
			(xy 113.308128 -258.880656) (xy 113.300003 -258.829361) (xy 108.720083 -258.829361) (xy 108.739642 -258.867747)
			(xy 108.75569 -258.91714) (xy 108.763815 -258.968435) (xy 108.764324 -258.994402) (xy 108.763917 -259.018955)
			(xy 108.756669 -259.067524) (xy 108.742317 -259.114486) (xy 108.721178 -259.158809) (xy 108.693716 -259.199519)
			(xy 108.677456 -259.217922) (xy 108.667648 -259.229408) (xy 108.65463 -259.256646) (xy 108.650161 -259.286501)
			(xy 108.654631 -259.316357) (xy 108.66765 -259.343594) (xy 108.677456 -259.355082) (xy 108.693721 -259.373481)
			(xy 108.72119 -259.414186) (xy 108.742328 -259.458511) (xy 108.756669 -259.505476) (xy 108.763897 -259.554048)
			(xy 108.764324 -259.578602) (xy 108.763815 -259.604569) (xy 108.7577 -259.643177) (xy 110.010449 -259.643177)
			(xy 110.010449 -259.591243) (xy 110.018574 -259.539948) (xy 110.034622 -259.490555) (xy 110.0582 -259.444281)
			(xy 110.088726 -259.402265) (xy 110.125449 -259.365542) (xy 110.167465 -259.335016) (xy 110.213739 -259.311438)
			(xy 110.263132 -259.29539) (xy 110.314427 -259.287265) (xy 110.366361 -259.287265) (xy 110.417656 -259.29539)
			(xy 110.467049 -259.311438) (xy 110.513323 -259.335016) (xy 110.555339 -259.365542) (xy 110.592062 -259.402265)
			(xy 110.622588 -259.444281) (xy 110.646166 -259.490555) (xy 110.662214 -259.539948) (xy 110.670339 -259.591243)
			(xy 110.670848 -259.61721) (xy 110.670495 -259.635244) (xy 115.095782 -259.635244) (xy 115.096215 -259.610692)
			(xy 115.103457 -259.562124) (xy 115.117802 -259.515162) (xy 115.138936 -259.470838) (xy 115.166392 -259.430128)
			(xy 115.18265 -259.411724) (xy 115.192413 -259.400202) (xy 115.205435 -259.372977) (xy 115.209913 -259.343133)
			(xy 115.205454 -259.313285) (xy 115.192449 -259.286052) (xy 115.18265 -259.274564) (xy 115.166408 -259.256146)
			(xy 115.138935 -259.215446) (xy 115.117793 -259.171126) (xy 115.103447 -259.124165) (xy 115.096213 -259.075596)
			(xy 115.095782 -259.051044) (xy 115.096291 -259.025077) (xy 115.104416 -258.973782) (xy 115.120464 -258.924389)
			(xy 115.144042 -258.878115) (xy 115.174568 -258.836099) (xy 115.211291 -258.799376) (xy 115.253307 -258.76885)
			(xy 115.299581 -258.745272) (xy 115.348974 -258.729224) (xy 115.400269 -258.721099) (xy 115.452203 -258.721099)
			(xy 115.503498 -258.729224) (xy 115.552891 -258.745272) (xy 115.599165 -258.76885) (xy 115.641181 -258.799376)
			(xy 115.677904 -258.836099) (xy 115.70843 -258.878115) (xy 115.732008 -258.924389) (xy 115.748056 -258.973782)
			(xy 115.756181 -259.025077) (xy 115.75669 -259.051044) (xy 115.756257 -259.075596) (xy 115.749016 -259.124164)
			(xy 115.734671 -259.171126) (xy 115.713538 -259.21545) (xy 115.68608 -259.256161) (xy 115.669822 -259.274564)
			(xy 115.659975 -259.286019) (xy 115.646967 -259.313269) (xy 115.642507 -259.343133) (xy 115.646986 -259.372994)
			(xy 115.660012 -259.400235) (xy 115.669822 -259.411724) (xy 115.68607 -259.430137) (xy 115.713539 -259.470839)
			(xy 115.734679 -259.51516) (xy 115.749024 -259.562123) (xy 115.756259 -259.610691) (xy 115.75669 -259.635244)
			(xy 115.756181 -259.661211) (xy 115.748056 -259.712506) (xy 115.732008 -259.761899) (xy 115.70843 -259.808173)
			(xy 115.677904 -259.850189) (xy 115.641181 -259.886912) (xy 115.599165 -259.917438) (xy 115.552891 -259.941016)
			(xy 115.503498 -259.957064) (xy 115.452203 -259.965189) (xy 115.400269 -259.965189) (xy 115.348974 -259.957064)
			(xy 115.299581 -259.941016) (xy 115.253307 -259.917438) (xy 115.211291 -259.886912) (xy 115.174568 -259.850189)
			(xy 115.144042 -259.808173) (xy 115.120464 -259.761899) (xy 115.104416 -259.712506) (xy 115.096291 -259.661211)
			(xy 115.095782 -259.635244) (xy 110.670495 -259.635244) (xy 110.670339 -259.643177) (xy 110.662214 -259.694472)
			(xy 110.646166 -259.743865) (xy 110.622588 -259.790139) (xy 110.592062 -259.832155) (xy 110.555339 -259.868878)
			(xy 110.513323 -259.899404) (xy 110.467049 -259.922982) (xy 110.417656 -259.93903) (xy 110.366361 -259.947155)
			(xy 110.314427 -259.947155) (xy 110.263132 -259.93903) (xy 110.213739 -259.922982) (xy 110.167465 -259.899404)
			(xy 110.125449 -259.868878) (xy 110.088726 -259.832155) (xy 110.0582 -259.790139) (xy 110.034622 -259.743865)
			(xy 110.018574 -259.694472) (xy 110.010449 -259.643177) (xy 108.7577 -259.643177) (xy 108.75569 -259.655864)
			(xy 108.739642 -259.705257) (xy 108.716064 -259.751531) (xy 108.685538 -259.793547) (xy 108.648815 -259.83027)
			(xy 108.606799 -259.860796) (xy 108.560525 -259.884374) (xy 108.511132 -259.900422) (xy 108.459837 -259.908547)
			(xy 108.407903 -259.908547) (xy 108.356608 -259.900422) (xy 108.307215 -259.884374) (xy 108.260941 -259.860796)
			(xy 108.218925 -259.83027) (xy 108.182202 -259.793547) (xy 108.151676 -259.751531) (xy 108.128098 -259.705257)
			(xy 108.11205 -259.655864) (xy 108.103925 -259.604569) (xy 108.103416 -259.578602) (xy 103.844598 -259.578602)
			(xy 103.844598 -260.456993) (xy 113.300003 -260.456993) (xy 113.300003 -260.405059) (xy 113.308128 -260.353764)
			(xy 113.324176 -260.304371) (xy 113.347754 -260.258097) (xy 113.37828 -260.216081) (xy 113.415003 -260.179358)
			(xy 113.457019 -260.148832) (xy 113.503293 -260.125254) (xy 113.552686 -260.109206) (xy 113.603981 -260.101081)
			(xy 113.655915 -260.101081) (xy 113.70721 -260.109206) (xy 113.756603 -260.125254) (xy 113.802877 -260.148832)
			(xy 113.844893 -260.179358) (xy 113.881616 -260.216081) (xy 113.912142 -260.258097) (xy 113.93572 -260.304371)
			(xy 113.951768 -260.353764) (xy 113.959893 -260.405059) (xy 113.960402 -260.431026) (xy 113.959893 -260.456993)
			(xy 113.951768 -260.508288) (xy 113.93572 -260.557681) (xy 113.912142 -260.603955) (xy 113.881616 -260.645971)
			(xy 113.844893 -260.682694) (xy 113.802877 -260.71322) (xy 113.756603 -260.736798) (xy 113.70721 -260.752846)
			(xy 113.655915 -260.760971) (xy 113.603981 -260.760971) (xy 113.552686 -260.752846) (xy 113.503293 -260.736798)
			(xy 113.457019 -260.71322) (xy 113.415003 -260.682694) (xy 113.37828 -260.645971) (xy 113.347754 -260.603955)
			(xy 113.324176 -260.557681) (xy 113.308128 -260.508288) (xy 113.300003 -260.456993) (xy 103.844598 -260.456993)
			(xy 103.844598 -261.011162) (xy 103.500591 -261.355169) (xy 104.308125 -261.355169) (xy 104.308125 -261.303231)
			(xy 104.31625 -261.251932) (xy 104.3323 -261.202535) (xy 104.355879 -261.156257) (xy 104.386408 -261.114238)
			(xy 104.423133 -261.077512) (xy 104.465152 -261.046982) (xy 104.51143 -261.023402) (xy 104.560826 -261.007352)
			(xy 104.612125 -260.999226) (xy 104.638094 -260.998716) (xy 104.665392 -260.999268) (xy 104.719244 -261.008248)
			(xy 104.770885 -261.025964) (xy 104.818909 -261.051933) (xy 104.862006 -261.085449) (xy 104.880918 -261.105142)
			(xy 104.890751 -261.115122) (xy 104.914635 -261.129748) (xy 104.941591 -261.137347) (xy 104.969597 -261.137347)
			(xy 104.996553 -261.129748) (xy 105.020437 -261.115122) (xy 105.03027 -261.105142) (xy 105.047415 -261.087197)
			(xy 105.086131 -261.056145) (xy 105.129058 -261.031237) (xy 105.175229 -261.013034) (xy 105.223604 -261.001945)
			(xy 105.273094 -260.998221) (xy 105.322584 -261.001945) (xy 105.370959 -261.013034) (xy 105.41713 -261.031237)
			(xy 105.460057 -261.056145) (xy 105.498773 -261.087197) (xy 105.515918 -261.105142) (xy 105.525751 -261.115122)
			(xy 105.549635 -261.129748) (xy 105.576591 -261.137347) (xy 105.604597 -261.137347) (xy 105.631553 -261.129748)
			(xy 105.655437 -261.115122) (xy 105.66527 -261.105142) (xy 105.682415 -261.087197) (xy 105.721131 -261.056145)
			(xy 105.764058 -261.031237) (xy 105.810229 -261.013034) (xy 105.858604 -261.001945) (xy 105.908094 -260.998221)
			(xy 105.957584 -261.001945) (xy 106.005959 -261.013034) (xy 106.05213 -261.031237) (xy 106.095057 -261.056145)
			(xy 106.133773 -261.087197) (xy 106.150918 -261.105142) (xy 106.160751 -261.115122) (xy 106.184635 -261.129748)
			(xy 106.211591 -261.137347) (xy 106.239597 -261.137347) (xy 106.266553 -261.129748) (xy 106.290437 -261.115122)
			(xy 106.30027 -261.105142) (xy 106.317415 -261.087197) (xy 106.356131 -261.056145) (xy 106.399058 -261.031237)
			(xy 106.445229 -261.013034) (xy 106.493604 -261.001945) (xy 106.543094 -260.998221) (xy 106.592584 -261.001945)
			(xy 106.640959 -261.013034) (xy 106.68713 -261.031237) (xy 106.730057 -261.056145) (xy 106.768773 -261.087197)
			(xy 106.785918 -261.105142) (xy 106.795751 -261.115122) (xy 106.819635 -261.129748) (xy 106.846591 -261.137347)
			(xy 106.874597 -261.137347) (xy 106.901553 -261.129748) (xy 106.925437 -261.115122) (xy 106.93527 -261.105142)
			(xy 106.954176 -261.085444) (xy 106.997278 -261.051935) (xy 107.045303 -261.025971) (xy 107.096945 -261.008258)
			(xy 107.150797 -260.999279) (xy 107.178094 -260.998716) (xy 107.204061 -260.999258) (xy 107.255356 -261.007382)
			(xy 107.304749 -261.02343) (xy 107.351024 -261.047007) (xy 107.39304 -261.077533) (xy 107.429763 -261.114256)
			(xy 107.46029 -261.156271) (xy 107.483868 -261.202545) (xy 107.499917 -261.251938) (xy 107.502946 -261.271063)
			(xy 110.010449 -261.271063) (xy 110.010449 -261.219129) (xy 110.018574 -261.167834) (xy 110.034622 -261.118441)
			(xy 110.0582 -261.072167) (xy 110.088726 -261.030151) (xy 110.125449 -260.993428) (xy 110.167465 -260.962902)
			(xy 110.213739 -260.939324) (xy 110.263132 -260.923276) (xy 110.314427 -260.915151) (xy 110.366361 -260.915151)
			(xy 110.417656 -260.923276) (xy 110.467049 -260.939324) (xy 110.513323 -260.962902) (xy 110.555339 -260.993428)
			(xy 110.592062 -261.030151) (xy 110.622588 -261.072167) (xy 110.646166 -261.118441) (xy 110.662214 -261.167834)
			(xy 110.670339 -261.219129) (xy 110.670848 -261.245096) (xy 110.670339 -261.271063) (xy 110.662214 -261.322358)
			(xy 110.651552 -261.355173) (xy 116.047699 -261.355173) (xy 116.047699 -261.303227) (xy 116.055825 -261.251922)
			(xy 116.071878 -261.202519) (xy 116.095461 -261.156236) (xy 116.125995 -261.114212) (xy 116.162727 -261.077482)
			(xy 116.204753 -261.046951) (xy 116.251037 -261.02337) (xy 116.300441 -261.007321) (xy 116.351747 -260.999197)
			(xy 116.37772 -260.998716) (xy 116.405016 -260.999316) (xy 116.458865 -261.008284) (xy 116.510506 -261.025989)
			(xy 116.55853 -261.051948) (xy 116.60163 -261.085454) (xy 116.620544 -261.105142) (xy 116.630377 -261.115122)
			(xy 116.654261 -261.129748) (xy 116.681217 -261.137347) (xy 116.709223 -261.137347) (xy 116.736179 -261.129748)
			(xy 116.760063 -261.115122) (xy 116.769896 -261.105142) (xy 116.787041 -261.087197) (xy 116.825757 -261.056145)
			(xy 116.868684 -261.031237) (xy 116.914855 -261.013034) (xy 116.96323 -261.001945) (xy 117.01272 -260.998221)
			(xy 117.06221 -261.001945) (xy 117.110585 -261.013034) (xy 117.156756 -261.031237) (xy 117.199683 -261.056145)
			(xy 117.238399 -261.087197) (xy 117.255544 -261.105142) (xy 117.265377 -261.115122) (xy 117.289261 -261.129748)
			(xy 117.316217 -261.137347) (xy 117.344223 -261.137347) (xy 117.371179 -261.129748) (xy 117.395063 -261.115122)
			(xy 117.404896 -261.105142) (xy 117.422041 -261.087197) (xy 117.460757 -261.056145) (xy 117.503684 -261.031237)
			(xy 117.549855 -261.013034) (xy 117.59823 -261.001945) (xy 117.64772 -260.998221) (xy 117.69721 -261.001945)
			(xy 117.745585 -261.013034) (xy 117.791756 -261.031237) (xy 117.834683 -261.056145) (xy 117.873399 -261.087197)
			(xy 117.890544 -261.105142) (xy 117.900377 -261.115122) (xy 117.924261 -261.129748) (xy 117.951217 -261.137347)
			(xy 117.979223 -261.137347) (xy 118.006179 -261.129748) (xy 118.030063 -261.115122) (xy 118.039896 -261.105142)
			(xy 118.058789 -261.085431) (xy 118.101895 -261.051924) (xy 118.149923 -261.025962) (xy 118.201568 -261.008252)
			(xy 118.255422 -260.999276) (xy 118.28272 -260.998716) (xy 118.308684 -260.999287) (xy 118.359972 -261.007413)
			(xy 118.409357 -261.023462) (xy 118.455624 -261.047038) (xy 118.497633 -261.077562) (xy 118.534351 -261.114282)
			(xy 118.564872 -261.156293) (xy 118.588446 -261.202561) (xy 118.604492 -261.251948) (xy 118.612615 -261.303236)
			(xy 118.612615 -261.355164) (xy 118.604492 -261.406452) (xy 118.588446 -261.455839) (xy 118.564872 -261.502107)
			(xy 118.534351 -261.544118) (xy 118.497633 -261.580838) (xy 118.455624 -261.611362) (xy 118.409357 -261.634938)
			(xy 118.359972 -261.650987) (xy 118.308684 -261.659113) (xy 118.28272 -261.659624) (xy 118.255422 -261.659082)
			(xy 118.201568 -261.650102) (xy 118.149926 -261.632385) (xy 118.101903 -261.606413) (xy 118.058807 -261.572893)
			(xy 118.039896 -261.553198) (xy 118.030063 -261.543218) (xy 118.006179 -261.528592) (xy 117.979223 -261.520993)
			(xy 117.951217 -261.520993) (xy 117.924261 -261.528592) (xy 117.900377 -261.543218) (xy 117.890544 -261.553198)
			(xy 117.873399 -261.571143) (xy 117.834683 -261.602195) (xy 117.791756 -261.627103) (xy 117.745585 -261.645306)
			(xy 117.69721 -261.656395) (xy 117.64772 -261.660119) (xy 117.59823 -261.656395) (xy 117.549855 -261.645306)
			(xy 117.503684 -261.627103) (xy 117.460757 -261.602195) (xy 117.422041 -261.571143) (xy 117.404896 -261.553198)
			(xy 117.395063 -261.543218) (xy 117.371179 -261.528592) (xy 117.344223 -261.520993) (xy 117.316217 -261.520993)
			(xy 117.289261 -261.528592) (xy 117.265377 -261.543218) (xy 117.255544 -261.553198) (xy 117.238399 -261.571143)
			(xy 117.199683 -261.602195) (xy 117.156756 -261.627103) (xy 117.110585 -261.645306) (xy 117.06221 -261.656395)
			(xy 117.01272 -261.660119) (xy 116.96323 -261.656395) (xy 116.914855 -261.645306) (xy 116.868684 -261.627103)
			(xy 116.825757 -261.602195) (xy 116.787041 -261.571143) (xy 116.769896 -261.553198) (xy 116.760063 -261.543218)
			(xy 116.736179 -261.528592) (xy 116.709223 -261.520993) (xy 116.681217 -261.520993) (xy 116.654261 -261.528592)
			(xy 116.630377 -261.543218) (xy 116.620544 -261.553198) (xy 116.60162 -261.572878) (xy 116.558524 -261.606392)
			(xy 116.510504 -261.632361) (xy 116.458865 -261.650078) (xy 116.405016 -261.65906) (xy 116.37772 -261.659624)
			(xy 116.351747 -261.659203) (xy 116.300441 -261.651079) (xy 116.251037 -261.63503) (xy 116.204753 -261.611449)
			(xy 116.162727 -261.580918) (xy 116.125995 -261.544188) (xy 116.095461 -261.502164) (xy 116.071878 -261.455881)
			(xy 116.055825 -261.406478) (xy 116.047699 -261.355173) (xy 110.651552 -261.355173) (xy 110.646166 -261.371751)
			(xy 110.622588 -261.418025) (xy 110.592062 -261.460041) (xy 110.555339 -261.496764) (xy 110.513323 -261.52729)
			(xy 110.467049 -261.550868) (xy 110.417656 -261.566916) (xy 110.366361 -261.575041) (xy 110.314427 -261.575041)
			(xy 110.263132 -261.566916) (xy 110.213739 -261.550868) (xy 110.167465 -261.52729) (xy 110.125449 -261.496764)
			(xy 110.088726 -261.460041) (xy 110.0582 -261.418025) (xy 110.034622 -261.371751) (xy 110.018574 -261.322358)
			(xy 110.010449 -261.271063) (xy 107.502946 -261.271063) (xy 107.508041 -261.303233) (xy 107.508041 -261.355167)
			(xy 107.499917 -261.406462) (xy 107.483868 -261.455855) (xy 107.46029 -261.502129) (xy 107.429763 -261.544144)
			(xy 107.39304 -261.580867) (xy 107.351024 -261.611393) (xy 107.304749 -261.63497) (xy 107.255356 -261.651018)
			(xy 107.204061 -261.659142) (xy 107.178094 -261.659624) (xy 107.150795 -261.659099) (xy 107.096941 -261.650116)
			(xy 107.045298 -261.632394) (xy 106.997275 -261.606418) (xy 106.95418 -261.572895) (xy 106.93527 -261.553198)
			(xy 106.925437 -261.543218) (xy 106.901553 -261.528592) (xy 106.874597 -261.520993) (xy 106.846591 -261.520993)
			(xy 106.819635 -261.528592) (xy 106.795751 -261.543218) (xy 106.785918 -261.553198) (xy 106.768773 -261.571143)
			(xy 106.730057 -261.602195) (xy 106.68713 -261.627103) (xy 106.640959 -261.645306) (xy 106.592584 -261.656395)
			(xy 106.543094 -261.660119) (xy 106.493604 -261.656395) (xy 106.445229 -261.645306) (xy 106.399058 -261.627103)
			(xy 106.356131 -261.602195) (xy 106.317415 -261.571143) (xy 106.30027 -261.553198) (xy 106.290437 -261.543218)
			(xy 106.266553 -261.528592) (xy 106.239597 -261.520993) (xy 106.211591 -261.520993) (xy 106.184635 -261.528592)
			(xy 106.160751 -261.543218) (xy 106.150918 -261.553198) (xy 106.133773 -261.571143) (xy 106.095057 -261.602195)
			(xy 106.05213 -261.627103) (xy 106.005959 -261.645306) (xy 105.957584 -261.656395) (xy 105.908094 -261.660119)
			(xy 105.858604 -261.656395) (xy 105.810229 -261.645306) (xy 105.764058 -261.627103) (xy 105.721131 -261.602195)
			(xy 105.682415 -261.571143) (xy 105.66527 -261.553198) (xy 105.655437 -261.543218) (xy 105.631553 -261.528592)
			(xy 105.604597 -261.520993) (xy 105.576591 -261.520993) (xy 105.549635 -261.528592) (xy 105.525751 -261.543218)
			(xy 105.515918 -261.553198) (xy 105.498773 -261.571143) (xy 105.460057 -261.602195) (xy 105.41713 -261.627103)
			(xy 105.370959 -261.645306) (xy 105.322584 -261.656395) (xy 105.273094 -261.660119) (xy 105.223604 -261.656395)
			(xy 105.175229 -261.645306) (xy 105.129058 -261.627103) (xy 105.086131 -261.602195) (xy 105.047415 -261.571143)
			(xy 105.03027 -261.553198) (xy 105.020437 -261.543218) (xy 104.996553 -261.528592) (xy 104.969597 -261.520993)
			(xy 104.941591 -261.520993) (xy 104.914635 -261.528592) (xy 104.890751 -261.543218) (xy 104.880918 -261.553198)
			(xy 104.862007 -261.572891) (xy 104.818908 -261.606403) (xy 104.770884 -261.63237) (xy 104.719243 -261.650084)
			(xy 104.665391 -261.659062) (xy 104.638094 -261.659624) (xy 104.612125 -261.659174) (xy 104.560826 -261.651048)
			(xy 104.51143 -261.634998) (xy 104.465152 -261.611418) (xy 104.423133 -261.580888) (xy 104.386408 -261.544162)
			(xy 104.355879 -261.502143) (xy 104.3323 -261.455865) (xy 104.31625 -261.406468) (xy 104.308125 -261.355169)
			(xy 103.500591 -261.355169) (xy 102.65537 -262.20039) (xy 102.65537 -262.704834) (xy 103.384096 -262.704834)
			(xy 103.38452 -262.680281) (xy 103.391763 -262.631713) (xy 103.40611 -262.584751) (xy 103.427246 -262.540427)
			(xy 103.454705 -262.499717) (xy 103.470964 -262.481314) (xy 103.480735 -262.469799) (xy 103.493754 -262.442572)
			(xy 103.49823 -262.412725) (xy 103.493769 -262.382877) (xy 103.480763 -262.355642) (xy 103.470964 -262.344154)
			(xy 103.454719 -262.325738) (xy 103.427247 -262.285038) (xy 103.406105 -262.240718) (xy 103.391759 -262.193755)
			(xy 103.384526 -262.145187) (xy 103.384096 -262.120634) (xy 103.384605 -262.094667) (xy 103.39273 -262.043372)
			(xy 103.408778 -261.993979) (xy 103.432356 -261.947705) (xy 103.462882 -261.905689) (xy 103.499605 -261.868966)
			(xy 103.541621 -261.83844) (xy 103.587895 -261.814862) (xy 103.637288 -261.798814) (xy 103.688583 -261.790689)
			(xy 103.740517 -261.790689) (xy 103.791812 -261.798814) (xy 103.841205 -261.814862) (xy 103.887479 -261.83844)
			(xy 103.929495 -261.868966) (xy 103.966218 -261.905689) (xy 103.996744 -261.947705) (xy 104.020322 -261.993979)
			(xy 104.03637 -262.043372) (xy 104.042945 -262.084879) (xy 113.300003 -262.084879) (xy 113.300003 -262.032945)
			(xy 113.308128 -261.98165) (xy 113.324176 -261.932257) (xy 113.347754 -261.885983) (xy 113.37828 -261.843967)
			(xy 113.415003 -261.807244) (xy 113.457019 -261.776718) (xy 113.503293 -261.75314) (xy 113.552686 -261.737092)
			(xy 113.603981 -261.728967) (xy 113.655915 -261.728967) (xy 113.70721 -261.737092) (xy 113.756603 -261.75314)
			(xy 113.802877 -261.776718) (xy 113.844893 -261.807244) (xy 113.881616 -261.843967) (xy 113.912142 -261.885983)
			(xy 113.93572 -261.932257) (xy 113.951768 -261.98165) (xy 113.959893 -262.032945) (xy 113.960402 -262.058912)
			(xy 113.959893 -262.084879) (xy 113.951768 -262.136174) (xy 113.93572 -262.185567) (xy 113.912142 -262.231841)
			(xy 113.881616 -262.273857) (xy 113.844893 -262.31058) (xy 113.802877 -262.341106) (xy 113.756603 -262.364684)
			(xy 113.70721 -262.380732) (xy 113.655915 -262.388857) (xy 113.603981 -262.388857) (xy 113.552686 -262.380732)
			(xy 113.503293 -262.364684) (xy 113.457019 -262.341106) (xy 113.415003 -262.31058) (xy 113.37828 -262.273857)
			(xy 113.347754 -262.231841) (xy 113.324176 -262.185567) (xy 113.308128 -262.136174) (xy 113.300003 -262.084879)
			(xy 104.042945 -262.084879) (xy 104.044495 -262.094667) (xy 104.045004 -262.120634) (xy 104.044561 -262.145186)
			(xy 104.037322 -262.193753) (xy 104.022979 -262.240715) (xy 104.001848 -262.285039) (xy 103.974393 -262.32575)
			(xy 103.958136 -262.344154) (xy 103.948298 -262.355617) (xy 103.935287 -262.382863) (xy 103.930824 -262.412725)
			(xy 103.935302 -262.442585) (xy 103.948327 -262.469825) (xy 103.958136 -262.481314) (xy 103.974413 -262.499703)
			(xy 104.001881 -262.540411) (xy 104.023017 -262.584737) (xy 104.037355 -262.631706) (xy 104.044579 -262.68028)
			(xy 104.045004 -262.704834) (xy 104.044495 -262.730801) (xy 104.03637 -262.782096) (xy 104.020322 -262.831489)
			(xy 103.996744 -262.877763) (xy 103.981536 -262.898695) (xy 110.010703 -262.898695) (xy 110.010703 -262.846761)
			(xy 110.018828 -262.795466) (xy 110.034876 -262.746073) (xy 110.058454 -262.699799) (xy 110.08898 -262.657783)
			(xy 110.125703 -262.62106) (xy 110.167719 -262.590534) (xy 110.213993 -262.566956) (xy 110.263386 -262.550908)
			(xy 110.314681 -262.542783) (xy 110.366615 -262.542783) (xy 110.41791 -262.550908) (xy 110.467303 -262.566956)
			(xy 110.513577 -262.590534) (xy 110.555593 -262.62106) (xy 110.592316 -262.657783) (xy 110.622842 -262.699799)
			(xy 110.643268 -262.739886) (xy 115.986814 -262.739886) (xy 115.987353 -262.712588) (xy 115.996336 -262.658735)
			(xy 116.014055 -262.607094) (xy 116.040028 -262.559071) (xy 116.073546 -262.515974) (xy 116.09324 -262.497062)
			(xy 116.103238 -262.487244) (xy 116.117871 -262.463358) (xy 116.125471 -262.436397) (xy 116.125469 -262.408384)
			(xy 116.117863 -262.381425) (xy 116.103226 -262.357541) (xy 116.09324 -262.34771) (xy 116.073532 -262.328814)
			(xy 116.040024 -262.28571) (xy 116.014062 -262.237681) (xy 115.996351 -262.186037) (xy 115.987375 -262.132184)
			(xy 115.986814 -262.104886) (xy 115.987323 -262.078919) (xy 115.995448 -262.027624) (xy 116.011496 -261.978231)
			(xy 116.035074 -261.931957) (xy 116.0656 -261.889941) (xy 116.102323 -261.853218) (xy 116.144339 -261.822692)
			(xy 116.190613 -261.799114) (xy 116.240006 -261.783066) (xy 116.291301 -261.774941) (xy 116.343235 -261.774941)
			(xy 116.39453 -261.783066) (xy 116.443923 -261.799114) (xy 116.490197 -261.822692) (xy 116.532213 -261.853218)
			(xy 116.568936 -261.889941) (xy 116.599462 -261.931957) (xy 116.62304 -261.978231) (xy 116.639088 -262.027624)
			(xy 116.647213 -262.078919) (xy 116.647722 -262.104886) (xy 116.647184 -262.132185) (xy 116.638204 -262.186038)
			(xy 116.620486 -262.23768) (xy 116.594512 -262.285704) (xy 116.560992 -262.328799) (xy 116.541296 -262.34771)
			(xy 116.531331 -262.357557) (xy 116.516706 -262.381437) (xy 116.509108 -262.408389) (xy 116.509105 -262.436392)
			(xy 116.516699 -262.463345) (xy 116.531319 -262.487228) (xy 116.541296 -262.497062) (xy 116.560979 -262.515983)
			(xy 116.594492 -262.55908) (xy 116.620461 -262.607101) (xy 116.638177 -262.65874) (xy 116.647159 -262.712589)
			(xy 116.647722 -262.739886) (xy 116.647117 -262.767911) (xy 116.637657 -262.823157) (xy 116.619005 -262.876012)
			(xy 116.591698 -262.924961) (xy 116.57457 -262.94715) (xy 116.566363 -262.958175) (xy 116.555485 -262.983397)
			(xy 116.551734 -263.010608) (xy 116.555382 -263.037833) (xy 116.566166 -263.063097) (xy 116.583302 -263.084565)
			(xy 116.605546 -263.10068) (xy 116.618258 -263.1059) (xy 116.647801 -263.117707) (xy 116.702028 -263.150969)
			(xy 116.725954 -263.17194) (xy 116.737443 -263.181743) (xy 116.76468 -263.194757) (xy 116.794534 -263.199225)
			(xy 116.824388 -263.194757) (xy 116.851625 -263.181743) (xy 116.863114 -263.17194) (xy 116.881499 -263.155659)
			(xy 116.922208 -263.128193) (xy 116.966536 -263.107058) (xy 117.013505 -263.09272) (xy 117.062079 -263.085497)
			(xy 117.086634 -263.085072) (xy 117.111186 -263.085521) (xy 117.159752 -263.092759) (xy 117.206714 -263.107101)
			(xy 117.251038 -263.128231) (xy 117.29175 -263.155684) (xy 117.310154 -263.17194) (xy 117.321643 -263.181743)
			(xy 117.34888 -263.194757) (xy 117.378734 -263.199225) (xy 117.408588 -263.194757) (xy 117.435825 -263.181743)
			(xy 117.447314 -263.17194) (xy 117.465699 -263.155659) (xy 117.506408 -263.128193) (xy 117.550736 -263.107058)
			(xy 117.597705 -263.09272) (xy 117.646279 -263.085497) (xy 117.670834 -263.085072) (xy 117.696802 -263.085532)
			(xy 117.748096 -263.093661) (xy 117.797488 -263.109714) (xy 117.843761 -263.133295) (xy 117.885776 -263.163825)
			(xy 117.922497 -263.20055) (xy 117.953022 -263.242568) (xy 117.976599 -263.288843) (xy 117.992647 -263.338237)
			(xy 118.000771 -263.389532) (xy 118.000771 -263.441468) (xy 117.992647 -263.492763) (xy 117.976599 -263.542157)
			(xy 117.953022 -263.588432) (xy 117.922497 -263.63045) (xy 117.885776 -263.667175) (xy 117.843761 -263.697705)
			(xy 117.797488 -263.721286) (xy 117.748096 -263.737339) (xy 117.696802 -263.745468) (xy 117.670834 -263.74598)
			(xy 117.646281 -263.745562) (xy 117.597713 -263.738318) (xy 117.55075 -263.72397) (xy 117.506426 -263.702833)
			(xy 117.465717 -263.675372) (xy 117.447314 -263.659112) (xy 117.435825 -263.649309) (xy 117.408588 -263.636295)
			(xy 117.378734 -263.631827) (xy 117.34888 -263.636295) (xy 117.321643 -263.649309) (xy 117.310154 -263.659112)
			(xy 117.291749 -263.675369) (xy 117.251044 -263.702837) (xy 117.206721 -263.723976) (xy 117.159757 -263.738319)
			(xy 117.111187 -263.74555) (xy 117.086634 -263.74598) (xy 117.062081 -263.745562) (xy 117.013513 -263.738318)
			(xy 116.96655 -263.72397) (xy 116.922226 -263.702833) (xy 116.881517 -263.675372) (xy 116.863114 -263.659112)
			(xy 116.851625 -263.649309) (xy 116.824388 -263.636295) (xy 116.794534 -263.631827) (xy 116.76468 -263.636295)
			(xy 116.737443 -263.649309) (xy 116.725954 -263.659112) (xy 116.707549 -263.675369) (xy 116.666844 -263.702837)
			(xy 116.622521 -263.723976) (xy 116.575557 -263.738319) (xy 116.526987 -263.74555) (xy 116.502434 -263.74598)
			(xy 116.476467 -263.74544) (xy 116.425171 -263.737321) (xy 116.375778 -263.721277) (xy 116.329502 -263.697704)
			(xy 116.287483 -263.667182) (xy 116.250757 -263.630462) (xy 116.220227 -263.588449) (xy 116.196646 -263.542178)
			(xy 116.180593 -263.492787) (xy 116.172465 -263.441493) (xy 116.17198 -263.415526) (xy 116.172591 -263.387501)
			(xy 116.182049 -263.332256) (xy 116.200699 -263.2794) (xy 116.228004 -263.230452) (xy 116.245132 -263.208262)
			(xy 116.253443 -263.197311) (xy 116.264313 -263.172066) (xy 116.26805 -263.144836) (xy 116.264385 -263.117597)
			(xy 116.253584 -263.092323) (xy 116.236429 -263.070848) (xy 116.214165 -263.054731) (xy 116.201444 -263.049512)
			(xy 116.178144 -263.040261) (xy 116.134391 -263.015793) (xy 116.094834 -262.984999) (xy 116.06038 -262.948586)
			(xy 116.031819 -262.907389) (xy 116.009805 -262.862351) (xy 115.994843 -262.814506) (xy 115.987277 -262.764951)
			(xy 115.986814 -262.739886) (xy 110.643268 -262.739886) (xy 110.64642 -262.746073) (xy 110.662468 -262.795466)
			(xy 110.670593 -262.846761) (xy 110.671102 -262.872728) (xy 110.670593 -262.898695) (xy 110.662468 -262.94999)
			(xy 110.64642 -262.999383) (xy 110.622842 -263.045657) (xy 110.592316 -263.087673) (xy 110.555593 -263.124396)
			(xy 110.513577 -263.154922) (xy 110.467303 -263.1785) (xy 110.41791 -263.194548) (xy 110.366615 -263.202673)
			(xy 110.314681 -263.202673) (xy 110.263386 -263.194548) (xy 110.213993 -263.1785) (xy 110.167719 -263.154922)
			(xy 110.125703 -263.124396) (xy 110.08898 -263.087673) (xy 110.058454 -263.045657) (xy 110.034876 -262.999383)
			(xy 110.018828 -262.94999) (xy 110.010703 -262.898695) (xy 103.981536 -262.898695) (xy 103.966218 -262.919779)
			(xy 103.929495 -262.956502) (xy 103.887479 -262.987028) (xy 103.841205 -263.010606) (xy 103.791812 -263.026654)
			(xy 103.740517 -263.034779) (xy 103.688583 -263.034779) (xy 103.637288 -263.026654) (xy 103.587895 -263.010606)
			(xy 103.541621 -262.987028) (xy 103.499605 -262.956502) (xy 103.462882 -262.919779) (xy 103.432356 -262.877763)
			(xy 103.408778 -262.831489) (xy 103.39273 -262.782096) (xy 103.384605 -262.730801) (xy 103.384096 -262.704834)
			(xy 102.65537 -262.704834) (xy 102.65537 -263.554464) (xy 102.658926 -263.563354) (xy 102.670073 -263.592923)
			(xy 102.682103 -263.654952) (xy 102.682802 -263.686544) (xy 102.682158 -263.712511) (xy 113.299495 -263.712511)
			(xy 113.299495 -263.660577) (xy 113.30762 -263.609282) (xy 113.323668 -263.559889) (xy 113.347246 -263.513615)
			(xy 113.377772 -263.471599) (xy 113.414495 -263.434876) (xy 113.456511 -263.40435) (xy 113.502785 -263.380772)
			(xy 113.552178 -263.364724) (xy 113.603473 -263.356599) (xy 113.655407 -263.356599) (xy 113.706702 -263.364724)
			(xy 113.756095 -263.380772) (xy 113.802369 -263.40435) (xy 113.844385 -263.434876) (xy 113.881108 -263.471599)
			(xy 113.911634 -263.513615) (xy 113.935212 -263.559889) (xy 113.95126 -263.609282) (xy 113.959385 -263.660577)
			(xy 113.959894 -263.686544) (xy 113.959385 -263.712511) (xy 115.179603 -263.712511) (xy 115.179603 -263.660577)
			(xy 115.187728 -263.609282) (xy 115.203776 -263.559889) (xy 115.227354 -263.513615) (xy 115.25788 -263.471599)
			(xy 115.294603 -263.434876) (xy 115.336619 -263.40435) (xy 115.382893 -263.380772) (xy 115.432286 -263.364724)
			(xy 115.483581 -263.356599) (xy 115.535515 -263.356599) (xy 115.58681 -263.364724) (xy 115.636203 -263.380772)
			(xy 115.682477 -263.40435) (xy 115.724493 -263.434876) (xy 115.761216 -263.471599) (xy 115.791742 -263.513615)
			(xy 115.81532 -263.559889) (xy 115.831368 -263.609282) (xy 115.839493 -263.660577) (xy 115.840002 -263.686544)
			(xy 115.839493 -263.712511) (xy 115.831368 -263.763806) (xy 115.81532 -263.813199) (xy 115.791742 -263.859473)
			(xy 115.761216 -263.901489) (xy 115.724493 -263.938212) (xy 115.682477 -263.968738) (xy 115.636203 -263.992316)
			(xy 115.58681 -264.008364) (xy 115.535515 -264.016489) (xy 115.483581 -264.016489) (xy 115.432286 -264.008364)
			(xy 115.382893 -263.992316) (xy 115.336619 -263.968738) (xy 115.294603 -263.938212) (xy 115.25788 -263.901489)
			(xy 115.227354 -263.859473) (xy 115.203776 -263.813199) (xy 115.187728 -263.763806) (xy 115.179603 -263.712511)
			(xy 113.959385 -263.712511) (xy 113.95126 -263.763806) (xy 113.935212 -263.813199) (xy 113.911634 -263.859473)
			(xy 113.881108 -263.901489) (xy 113.844385 -263.938212) (xy 113.802369 -263.968738) (xy 113.756095 -263.992316)
			(xy 113.706702 -264.008364) (xy 113.655407 -264.016489) (xy 113.603473 -264.016489) (xy 113.552178 -264.008364)
			(xy 113.502785 -263.992316) (xy 113.456511 -263.968738) (xy 113.414495 -263.938212) (xy 113.377772 -263.901489)
			(xy 113.347246 -263.859473) (xy 113.323668 -263.813199) (xy 113.30762 -263.763806) (xy 113.299495 -263.712511)
			(xy 102.682158 -263.712511) (xy 102.682019 -263.718128) (xy 102.670002 -263.780145) (xy 102.658926 -263.809734)
			(xy 102.65537 -263.818624) (xy 102.65537 -264.073132) (xy 102.655798 -264.087763) (xy 102.664002 -264.115848)
			(xy 102.679842 -264.140449) (xy 102.702013 -264.159541) (xy 102.728691 -264.171554) (xy 102.757683 -264.1755)
			(xy 102.77221 -264.173716) (xy 102.78458 -264.171941) (xy 102.809498 -264.170037) (xy 102.821994 -264.169906)
			(xy 102.847967 -264.170389) (xy 102.899273 -264.178514) (xy 102.948676 -264.194565) (xy 102.99496 -264.218147)
			(xy 103.036985 -264.24868) (xy 103.073717 -264.28541) (xy 103.10425 -264.327435) (xy 103.127833 -264.373718)
			(xy 103.143885 -264.423121) (xy 103.152011 -264.474427) (xy 103.152011 -264.526327) (xy 103.431849 -264.526327)
			(xy 103.431849 -264.474393) (xy 103.439974 -264.423098) (xy 103.456022 -264.373705) (xy 103.4796 -264.327431)
			(xy 103.510126 -264.285415) (xy 103.546849 -264.248692) (xy 103.588865 -264.218166) (xy 103.635139 -264.194588)
			(xy 103.684532 -264.17854) (xy 103.735827 -264.170415) (xy 103.787761 -264.170415) (xy 103.839056 -264.17854)
			(xy 103.888449 -264.194588) (xy 103.934723 -264.218166) (xy 103.976739 -264.248692) (xy 104.013462 -264.285415)
			(xy 104.043988 -264.327431) (xy 104.067566 -264.373705) (xy 104.083614 -264.423098) (xy 104.091739 -264.474393)
			(xy 104.092248 -264.50036) (xy 104.091739 -264.526327) (xy 104.371649 -264.526327) (xy 104.371649 -264.474393)
			(xy 104.379774 -264.423098) (xy 104.395822 -264.373705) (xy 104.4194 -264.327431) (xy 104.449926 -264.285415)
			(xy 104.486649 -264.248692) (xy 104.528665 -264.218166) (xy 104.574939 -264.194588) (xy 104.624332 -264.17854)
			(xy 104.675627 -264.170415) (xy 104.727561 -264.170415) (xy 104.778856 -264.17854) (xy 104.828249 -264.194588)
			(xy 104.874523 -264.218166) (xy 104.916539 -264.248692) (xy 104.953262 -264.285415) (xy 104.983788 -264.327431)
			(xy 105.007366 -264.373705) (xy 105.023414 -264.423098) (xy 105.031539 -264.474393) (xy 105.032048 -264.50036)
			(xy 105.031539 -264.526327) (xy 105.311449 -264.526327) (xy 105.311449 -264.474393) (xy 105.319574 -264.423098)
			(xy 105.335622 -264.373705) (xy 105.3592 -264.327431) (xy 105.389726 -264.285415) (xy 105.426449 -264.248692)
			(xy 105.468465 -264.218166) (xy 105.514739 -264.194588) (xy 105.564132 -264.17854) (xy 105.615427 -264.170415)
			(xy 105.667361 -264.170415) (xy 105.718656 -264.17854) (xy 105.768049 -264.194588) (xy 105.814323 -264.218166)
			(xy 105.856339 -264.248692) (xy 105.893062 -264.285415) (xy 105.923588 -264.327431) (xy 105.947166 -264.373705)
			(xy 105.963214 -264.423098) (xy 105.971339 -264.474393) (xy 105.971848 -264.50036) (xy 105.971339 -264.526327)
			(xy 106.251249 -264.526327) (xy 106.251249 -264.474393) (xy 106.259374 -264.423098) (xy 106.275422 -264.373705)
			(xy 106.299 -264.327431) (xy 106.329526 -264.285415) (xy 106.366249 -264.248692) (xy 106.408265 -264.218166)
			(xy 106.454539 -264.194588) (xy 106.503932 -264.17854) (xy 106.555227 -264.170415) (xy 106.607161 -264.170415)
			(xy 106.658456 -264.17854) (xy 106.707849 -264.194588) (xy 106.754123 -264.218166) (xy 106.796139 -264.248692)
			(xy 106.832862 -264.285415) (xy 106.863388 -264.327431) (xy 106.886966 -264.373705) (xy 106.903014 -264.423098)
			(xy 106.911139 -264.474393) (xy 106.911648 -264.50036) (xy 106.911139 -264.526327) (xy 107.191303 -264.526327)
			(xy 107.191303 -264.474393) (xy 107.199428 -264.423098) (xy 107.215476 -264.373705) (xy 107.239054 -264.327431)
			(xy 107.26958 -264.285415) (xy 107.306303 -264.248692) (xy 107.348319 -264.218166) (xy 107.394593 -264.194588)
			(xy 107.443986 -264.17854) (xy 107.495281 -264.170415) (xy 107.547215 -264.170415) (xy 107.59851 -264.17854)
			(xy 107.647903 -264.194588) (xy 107.694177 -264.218166) (xy 107.736193 -264.248692) (xy 107.772916 -264.285415)
			(xy 107.803442 -264.327431) (xy 107.82702 -264.373705) (xy 107.843068 -264.423098) (xy 107.851193 -264.474393)
			(xy 107.851702 -264.50036) (xy 107.851193 -264.526327) (xy 108.131103 -264.526327) (xy 108.131103 -264.474393)
			(xy 108.139228 -264.423098) (xy 108.155276 -264.373705) (xy 108.178854 -264.327431) (xy 108.20938 -264.285415)
			(xy 108.246103 -264.248692) (xy 108.288119 -264.218166) (xy 108.334393 -264.194588) (xy 108.383786 -264.17854)
			(xy 108.435081 -264.170415) (xy 108.487015 -264.170415) (xy 108.53831 -264.17854) (xy 108.587703 -264.194588)
			(xy 108.633977 -264.218166) (xy 108.675993 -264.248692) (xy 108.712716 -264.285415) (xy 108.743242 -264.327431)
			(xy 108.76682 -264.373705) (xy 108.782868 -264.423098) (xy 108.790993 -264.474393) (xy 108.791502 -264.50036)
			(xy 108.790993 -264.526327) (xy 114.709449 -264.526327) (xy 114.709449 -264.474393) (xy 114.717574 -264.423098)
			(xy 114.733622 -264.373705) (xy 114.7572 -264.327431) (xy 114.787726 -264.285415) (xy 114.824449 -264.248692)
			(xy 114.866465 -264.218166) (xy 114.912739 -264.194588) (xy 114.962132 -264.17854) (xy 115.013427 -264.170415)
			(xy 115.065361 -264.170415) (xy 115.116656 -264.17854) (xy 115.166049 -264.194588) (xy 115.212323 -264.218166)
			(xy 115.254339 -264.248692) (xy 115.291062 -264.285415) (xy 115.321588 -264.327431) (xy 115.345166 -264.373705)
			(xy 115.361214 -264.423098) (xy 115.369339 -264.474393) (xy 115.369848 -264.50036) (xy 115.369339 -264.526327)
			(xy 115.649249 -264.526327) (xy 115.649249 -264.474393) (xy 115.657374 -264.423098) (xy 115.673422 -264.373705)
			(xy 115.697 -264.327431) (xy 115.727526 -264.285415) (xy 115.764249 -264.248692) (xy 115.806265 -264.218166)
			(xy 115.852539 -264.194588) (xy 115.901932 -264.17854) (xy 115.953227 -264.170415) (xy 116.005161 -264.170415)
			(xy 116.056456 -264.17854) (xy 116.105849 -264.194588) (xy 116.152123 -264.218166) (xy 116.194139 -264.248692)
			(xy 116.230862 -264.285415) (xy 116.261388 -264.327431) (xy 116.284966 -264.373705) (xy 116.301014 -264.423098)
			(xy 116.309139 -264.474393) (xy 116.309648 -264.50036) (xy 116.309139 -264.526327) (xy 116.589049 -264.526327)
			(xy 116.589049 -264.474393) (xy 116.597174 -264.423098) (xy 116.613222 -264.373705) (xy 116.6368 -264.327431)
			(xy 116.667326 -264.285415) (xy 116.704049 -264.248692) (xy 116.746065 -264.218166) (xy 116.792339 -264.194588)
			(xy 116.841732 -264.17854) (xy 116.893027 -264.170415) (xy 116.944961 -264.170415) (xy 116.996256 -264.17854)
			(xy 117.045649 -264.194588) (xy 117.091923 -264.218166) (xy 117.133939 -264.248692) (xy 117.170662 -264.285415)
			(xy 117.201188 -264.327431) (xy 117.224766 -264.373705) (xy 117.240814 -264.423098) (xy 117.248939 -264.474393)
			(xy 117.249448 -264.50036) (xy 117.248939 -264.526327) (xy 117.528849 -264.526327) (xy 117.528849 -264.474393)
			(xy 117.536974 -264.423098) (xy 117.553022 -264.373705) (xy 117.5766 -264.327431) (xy 117.607126 -264.285415)
			(xy 117.643849 -264.248692) (xy 117.685865 -264.218166) (xy 117.732139 -264.194588) (xy 117.781532 -264.17854)
			(xy 117.832827 -264.170415) (xy 117.884761 -264.170415) (xy 117.936056 -264.17854) (xy 117.985449 -264.194588)
			(xy 118.031723 -264.218166) (xy 118.073739 -264.248692) (xy 118.110462 -264.285415) (xy 118.140988 -264.327431)
			(xy 118.164566 -264.373705) (xy 118.180614 -264.423098) (xy 118.188739 -264.474393) (xy 118.189248 -264.50036)
			(xy 118.188739 -264.526327) (xy 118.180614 -264.577622) (xy 118.164566 -264.627015) (xy 118.140988 -264.673289)
			(xy 118.110462 -264.715305) (xy 118.073739 -264.752028) (xy 118.031723 -264.782554) (xy 117.985449 -264.806132)
			(xy 117.936056 -264.82218) (xy 117.884761 -264.830305) (xy 117.832827 -264.830305) (xy 117.781532 -264.82218)
			(xy 117.732139 -264.806132) (xy 117.685865 -264.782554) (xy 117.643849 -264.752028) (xy 117.607126 -264.715305)
			(xy 117.5766 -264.673289) (xy 117.553022 -264.627015) (xy 117.536974 -264.577622) (xy 117.528849 -264.526327)
			(xy 117.248939 -264.526327) (xy 117.240814 -264.577622) (xy 117.224766 -264.627015) (xy 117.201188 -264.673289)
			(xy 117.170662 -264.715305) (xy 117.133939 -264.752028) (xy 117.091923 -264.782554) (xy 117.045649 -264.806132)
			(xy 116.996256 -264.82218) (xy 116.944961 -264.830305) (xy 116.893027 -264.830305) (xy 116.841732 -264.82218)
			(xy 116.792339 -264.806132) (xy 116.746065 -264.782554) (xy 116.704049 -264.752028) (xy 116.667326 -264.715305)
			(xy 116.6368 -264.673289) (xy 116.613222 -264.627015) (xy 116.597174 -264.577622) (xy 116.589049 -264.526327)
			(xy 116.309139 -264.526327) (xy 116.301014 -264.577622) (xy 116.284966 -264.627015) (xy 116.261388 -264.673289)
			(xy 116.230862 -264.715305) (xy 116.194139 -264.752028) (xy 116.152123 -264.782554) (xy 116.105849 -264.806132)
			(xy 116.056456 -264.82218) (xy 116.005161 -264.830305) (xy 115.953227 -264.830305) (xy 115.901932 -264.82218)
			(xy 115.852539 -264.806132) (xy 115.806265 -264.782554) (xy 115.764249 -264.752028) (xy 115.727526 -264.715305)
			(xy 115.697 -264.673289) (xy 115.673422 -264.627015) (xy 115.657374 -264.577622) (xy 115.649249 -264.526327)
			(xy 115.369339 -264.526327) (xy 115.361214 -264.577622) (xy 115.345166 -264.627015) (xy 115.321588 -264.673289)
			(xy 115.291062 -264.715305) (xy 115.254339 -264.752028) (xy 115.212323 -264.782554) (xy 115.166049 -264.806132)
			(xy 115.116656 -264.82218) (xy 115.065361 -264.830305) (xy 115.013427 -264.830305) (xy 114.962132 -264.82218)
			(xy 114.912739 -264.806132) (xy 114.866465 -264.782554) (xy 114.824449 -264.752028) (xy 114.787726 -264.715305)
			(xy 114.7572 -264.673289) (xy 114.733622 -264.627015) (xy 114.717574 -264.577622) (xy 114.709449 -264.526327)
			(xy 108.790993 -264.526327) (xy 108.782868 -264.577622) (xy 108.76682 -264.627015) (xy 108.743242 -264.673289)
			(xy 108.712716 -264.715305) (xy 108.675993 -264.752028) (xy 108.633977 -264.782554) (xy 108.587703 -264.806132)
			(xy 108.53831 -264.82218) (xy 108.487015 -264.830305) (xy 108.435081 -264.830305) (xy 108.383786 -264.82218)
			(xy 108.334393 -264.806132) (xy 108.288119 -264.782554) (xy 108.246103 -264.752028) (xy 108.20938 -264.715305)
			(xy 108.178854 -264.673289) (xy 108.155276 -264.627015) (xy 108.139228 -264.577622) (xy 108.131103 -264.526327)
			(xy 107.851193 -264.526327) (xy 107.843068 -264.577622) (xy 107.82702 -264.627015) (xy 107.803442 -264.673289)
			(xy 107.772916 -264.715305) (xy 107.736193 -264.752028) (xy 107.694177 -264.782554) (xy 107.647903 -264.806132)
			(xy 107.59851 -264.82218) (xy 107.547215 -264.830305) (xy 107.495281 -264.830305) (xy 107.443986 -264.82218)
			(xy 107.394593 -264.806132) (xy 107.348319 -264.782554) (xy 107.306303 -264.752028) (xy 107.26958 -264.715305)
			(xy 107.239054 -264.673289) (xy 107.215476 -264.627015) (xy 107.199428 -264.577622) (xy 107.191303 -264.526327)
			(xy 106.911139 -264.526327) (xy 106.903014 -264.577622) (xy 106.886966 -264.627015) (xy 106.863388 -264.673289)
			(xy 106.832862 -264.715305) (xy 106.796139 -264.752028) (xy 106.754123 -264.782554) (xy 106.707849 -264.806132)
			(xy 106.658456 -264.82218) (xy 106.607161 -264.830305) (xy 106.555227 -264.830305) (xy 106.503932 -264.82218)
			(xy 106.454539 -264.806132) (xy 106.408265 -264.782554) (xy 106.366249 -264.752028) (xy 106.329526 -264.715305)
			(xy 106.299 -264.673289) (xy 106.275422 -264.627015) (xy 106.259374 -264.577622) (xy 106.251249 -264.526327)
			(xy 105.971339 -264.526327) (xy 105.963214 -264.577622) (xy 105.947166 -264.627015) (xy 105.923588 -264.673289)
			(xy 105.893062 -264.715305) (xy 105.856339 -264.752028) (xy 105.814323 -264.782554) (xy 105.768049 -264.806132)
			(xy 105.718656 -264.82218) (xy 105.667361 -264.830305) (xy 105.615427 -264.830305) (xy 105.564132 -264.82218)
			(xy 105.514739 -264.806132) (xy 105.468465 -264.782554) (xy 105.426449 -264.752028) (xy 105.389726 -264.715305)
			(xy 105.3592 -264.673289) (xy 105.335622 -264.627015) (xy 105.319574 -264.577622) (xy 105.311449 -264.526327)
			(xy 105.031539 -264.526327) (xy 105.023414 -264.577622) (xy 105.007366 -264.627015) (xy 104.983788 -264.673289)
			(xy 104.953262 -264.715305) (xy 104.916539 -264.752028) (xy 104.874523 -264.782554) (xy 104.828249 -264.806132)
			(xy 104.778856 -264.82218) (xy 104.727561 -264.830305) (xy 104.675627 -264.830305) (xy 104.624332 -264.82218)
			(xy 104.574939 -264.806132) (xy 104.528665 -264.782554) (xy 104.486649 -264.752028) (xy 104.449926 -264.715305)
			(xy 104.4194 -264.673289) (xy 104.395822 -264.627015) (xy 104.379774 -264.577622) (xy 104.371649 -264.526327)
			(xy 104.091739 -264.526327) (xy 104.083614 -264.577622) (xy 104.067566 -264.627015) (xy 104.043988 -264.673289)
			(xy 104.013462 -264.715305) (xy 103.976739 -264.752028) (xy 103.934723 -264.782554) (xy 103.888449 -264.806132)
			(xy 103.839056 -264.82218) (xy 103.787761 -264.830305) (xy 103.735827 -264.830305) (xy 103.684532 -264.82218)
			(xy 103.635139 -264.806132) (xy 103.588865 -264.782554) (xy 103.546849 -264.752028) (xy 103.510126 -264.715305)
			(xy 103.4796 -264.673289) (xy 103.456022 -264.627015) (xy 103.439974 -264.577622) (xy 103.431849 -264.526327)
			(xy 103.152011 -264.526327) (xy 103.152011 -264.526373) (xy 103.143885 -264.577679) (xy 103.127833 -264.627082)
			(xy 103.10425 -264.673365) (xy 103.073717 -264.71539) (xy 103.036985 -264.75212) (xy 102.99496 -264.782653)
			(xy 102.948676 -264.806235) (xy 102.899273 -264.822286) (xy 102.847967 -264.830411) (xy 102.821994 -264.830814)
			(xy 102.809498 -264.830685) (xy 102.78458 -264.828775) (xy 102.77221 -264.827004) (xy 102.757687 -264.825288)
			(xy 102.728727 -264.829274) (xy 102.70208 -264.841293) (xy 102.679925 -264.860364) (xy 102.664074 -264.884927)
			(xy 102.655823 -264.912971) (xy 102.65537 -264.927588) (xy 102.65537 -265.182096) (xy 102.658926 -265.190986)
			(xy 102.67007 -265.220555) (xy 102.682094 -265.282584) (xy 102.682802 -265.314176) (xy 102.682156 -265.340143)
			(xy 102.962203 -265.340143) (xy 102.962203 -265.288209) (xy 102.970328 -265.236914) (xy 102.986376 -265.187521)
			(xy 103.009954 -265.141247) (xy 103.04048 -265.099231) (xy 103.077203 -265.062508) (xy 103.119219 -265.031982)
			(xy 103.165493 -265.008404) (xy 103.214886 -264.992356) (xy 103.266181 -264.984231) (xy 103.318115 -264.984231)
			(xy 103.36941 -264.992356) (xy 103.418803 -265.008404) (xy 103.465077 -265.031982) (xy 103.507093 -265.062508)
			(xy 103.543816 -265.099231) (xy 103.574342 -265.141247) (xy 103.59792 -265.187521) (xy 103.613968 -265.236914)
			(xy 103.622093 -265.288209) (xy 103.622602 -265.314176) (xy 103.622093 -265.340143) (xy 103.902003 -265.340143)
			(xy 103.902003 -265.288209) (xy 103.910128 -265.236914) (xy 103.926176 -265.187521) (xy 103.949754 -265.141247)
			(xy 103.98028 -265.099231) (xy 104.017003 -265.062508) (xy 104.059019 -265.031982) (xy 104.105293 -265.008404)
			(xy 104.154686 -264.992356) (xy 104.205981 -264.984231) (xy 104.257915 -264.984231) (xy 104.30921 -264.992356)
			(xy 104.358603 -265.008404) (xy 104.404877 -265.031982) (xy 104.446893 -265.062508) (xy 104.483616 -265.099231)
			(xy 104.514142 -265.141247) (xy 104.53772 -265.187521) (xy 104.553768 -265.236914) (xy 104.561893 -265.288209)
			(xy 104.562402 -265.314176) (xy 104.561893 -265.340143) (xy 104.841803 -265.340143) (xy 104.841803 -265.288209)
			(xy 104.849928 -265.236914) (xy 104.865976 -265.187521) (xy 104.889554 -265.141247) (xy 104.92008 -265.099231)
			(xy 104.956803 -265.062508) (xy 104.998819 -265.031982) (xy 105.045093 -265.008404) (xy 105.094486 -264.992356)
			(xy 105.145781 -264.984231) (xy 105.197715 -264.984231) (xy 105.24901 -264.992356) (xy 105.298403 -265.008404)
			(xy 105.344677 -265.031982) (xy 105.386693 -265.062508) (xy 105.423416 -265.099231) (xy 105.453942 -265.141247)
			(xy 105.47752 -265.187521) (xy 105.493568 -265.236914) (xy 105.501693 -265.288209) (xy 105.502202 -265.314176)
			(xy 105.501693 -265.340143) (xy 105.781603 -265.340143) (xy 105.781603 -265.288209) (xy 105.789728 -265.236914)
			(xy 105.805776 -265.187521) (xy 105.829354 -265.141247) (xy 105.85988 -265.099231) (xy 105.896603 -265.062508)
			(xy 105.938619 -265.031982) (xy 105.984893 -265.008404) (xy 106.034286 -264.992356) (xy 106.085581 -264.984231)
			(xy 106.137515 -264.984231) (xy 106.18881 -264.992356) (xy 106.238203 -265.008404) (xy 106.284477 -265.031982)
			(xy 106.326493 -265.062508) (xy 106.363216 -265.099231) (xy 106.393742 -265.141247) (xy 106.41732 -265.187521)
			(xy 106.433368 -265.236914) (xy 106.441493 -265.288209) (xy 106.442002 -265.314176) (xy 106.441493 -265.340143)
			(xy 106.721403 -265.340143) (xy 106.721403 -265.288209) (xy 106.729528 -265.236914) (xy 106.745576 -265.187521)
			(xy 106.769154 -265.141247) (xy 106.79968 -265.099231) (xy 106.836403 -265.062508) (xy 106.878419 -265.031982)
			(xy 106.924693 -265.008404) (xy 106.974086 -264.992356) (xy 107.025381 -264.984231) (xy 107.077315 -264.984231)
			(xy 107.12861 -264.992356) (xy 107.178003 -265.008404) (xy 107.224277 -265.031982) (xy 107.266293 -265.062508)
			(xy 107.303016 -265.099231) (xy 107.333542 -265.141247) (xy 107.35712 -265.187521) (xy 107.373168 -265.236914)
			(xy 107.381293 -265.288209) (xy 107.381802 -265.314176) (xy 107.381293 -265.340143) (xy 107.661203 -265.340143)
			(xy 107.661203 -265.288209) (xy 107.669328 -265.236914) (xy 107.685376 -265.187521) (xy 107.708954 -265.141247)
			(xy 107.73948 -265.099231) (xy 107.776203 -265.062508) (xy 107.818219 -265.031982) (xy 107.864493 -265.008404)
			(xy 107.913886 -264.992356) (xy 107.965181 -264.984231) (xy 108.017115 -264.984231) (xy 108.06841 -264.992356)
			(xy 108.117803 -265.008404) (xy 108.164077 -265.031982) (xy 108.206093 -265.062508) (xy 108.242816 -265.099231)
			(xy 108.273342 -265.141247) (xy 108.29692 -265.187521) (xy 108.312968 -265.236914) (xy 108.321093 -265.288209)
			(xy 108.321602 -265.314176) (xy 108.321093 -265.340143) (xy 108.601003 -265.340143) (xy 108.601003 -265.288209)
			(xy 108.609128 -265.236914) (xy 108.625176 -265.187521) (xy 108.648754 -265.141247) (xy 108.67928 -265.099231)
			(xy 108.716003 -265.062508) (xy 108.758019 -265.031982) (xy 108.804293 -265.008404) (xy 108.853686 -264.992356)
			(xy 108.904981 -264.984231) (xy 108.956915 -264.984231) (xy 109.00821 -264.992356) (xy 109.057603 -265.008404)
			(xy 109.103877 -265.031982) (xy 109.145893 -265.062508) (xy 109.182616 -265.099231) (xy 109.213142 -265.141247)
			(xy 109.23672 -265.187521) (xy 109.252768 -265.236914) (xy 109.260893 -265.288209) (xy 109.261402 -265.314176)
			(xy 109.260893 -265.340143) (xy 114.239549 -265.340143) (xy 114.239549 -265.288209) (xy 114.247674 -265.236914)
			(xy 114.263722 -265.187521) (xy 114.2873 -265.141247) (xy 114.317826 -265.099231) (xy 114.354549 -265.062508)
			(xy 114.396565 -265.031982) (xy 114.442839 -265.008404) (xy 114.492232 -264.992356) (xy 114.543527 -264.984231)
			(xy 114.595461 -264.984231) (xy 114.646756 -264.992356) (xy 114.696149 -265.008404) (xy 114.742423 -265.031982)
			(xy 114.784439 -265.062508) (xy 114.821162 -265.099231) (xy 114.851688 -265.141247) (xy 114.875266 -265.187521)
			(xy 114.891314 -265.236914) (xy 114.899439 -265.288209) (xy 114.899948 -265.314176) (xy 114.899439 -265.340143)
			(xy 115.179603 -265.340143) (xy 115.179603 -265.288209) (xy 115.187728 -265.236914) (xy 115.203776 -265.187521)
			(xy 115.227354 -265.141247) (xy 115.25788 -265.099231) (xy 115.294603 -265.062508) (xy 115.336619 -265.031982)
			(xy 115.382893 -265.008404) (xy 115.432286 -264.992356) (xy 115.483581 -264.984231) (xy 115.535515 -264.984231)
			(xy 115.58681 -264.992356) (xy 115.636203 -265.008404) (xy 115.682477 -265.031982) (xy 115.724493 -265.062508)
			(xy 115.761216 -265.099231) (xy 115.791742 -265.141247) (xy 115.81532 -265.187521) (xy 115.831368 -265.236914)
			(xy 115.839493 -265.288209) (xy 115.840002 -265.314176) (xy 115.839493 -265.340143) (xy 116.119403 -265.340143)
			(xy 116.119403 -265.288209) (xy 116.127528 -265.236914) (xy 116.143576 -265.187521) (xy 116.167154 -265.141247)
			(xy 116.19768 -265.099231) (xy 116.234403 -265.062508) (xy 116.276419 -265.031982) (xy 116.322693 -265.008404)
			(xy 116.372086 -264.992356) (xy 116.423381 -264.984231) (xy 116.475315 -264.984231) (xy 116.52661 -264.992356)
			(xy 116.576003 -265.008404) (xy 116.622277 -265.031982) (xy 116.664293 -265.062508) (xy 116.701016 -265.099231)
			(xy 116.731542 -265.141247) (xy 116.75512 -265.187521) (xy 116.771168 -265.236914) (xy 116.779293 -265.288209)
			(xy 116.779802 -265.314176) (xy 116.779293 -265.340143) (xy 117.059203 -265.340143) (xy 117.059203 -265.288209)
			(xy 117.067328 -265.236914) (xy 117.083376 -265.187521) (xy 117.106954 -265.141247) (xy 117.13748 -265.099231)
			(xy 117.174203 -265.062508) (xy 117.216219 -265.031982) (xy 117.262493 -265.008404) (xy 117.311886 -264.992356)
			(xy 117.363181 -264.984231) (xy 117.415115 -264.984231) (xy 117.46641 -264.992356) (xy 117.515803 -265.008404)
			(xy 117.562077 -265.031982) (xy 117.604093 -265.062508) (xy 117.640816 -265.099231) (xy 117.671342 -265.141247)
			(xy 117.69492 -265.187521) (xy 117.710968 -265.236914) (xy 117.719093 -265.288209) (xy 117.719602 -265.314176)
			(xy 117.719093 -265.340143) (xy 117.710968 -265.391438) (xy 117.69492 -265.440831) (xy 117.671342 -265.487105)
			(xy 117.640816 -265.529121) (xy 117.604093 -265.565844) (xy 117.562077 -265.59637) (xy 117.515803 -265.619948)
			(xy 117.46641 -265.635996) (xy 117.415115 -265.644121) (xy 117.363181 -265.644121) (xy 117.311886 -265.635996)
			(xy 117.262493 -265.619948) (xy 117.216219 -265.59637) (xy 117.174203 -265.565844) (xy 117.13748 -265.529121)
			(xy 117.106954 -265.487105) (xy 117.083376 -265.440831) (xy 117.067328 -265.391438) (xy 117.059203 -265.340143)
			(xy 116.779293 -265.340143) (xy 116.771168 -265.391438) (xy 116.75512 -265.440831) (xy 116.731542 -265.487105)
			(xy 116.701016 -265.529121) (xy 116.664293 -265.565844) (xy 116.622277 -265.59637) (xy 116.576003 -265.619948)
			(xy 116.52661 -265.635996) (xy 116.475315 -265.644121) (xy 116.423381 -265.644121) (xy 116.372086 -265.635996)
			(xy 116.322693 -265.619948) (xy 116.276419 -265.59637) (xy 116.234403 -265.565844) (xy 116.19768 -265.529121)
			(xy 116.167154 -265.487105) (xy 116.143576 -265.440831) (xy 116.127528 -265.391438) (xy 116.119403 -265.340143)
			(xy 115.839493 -265.340143) (xy 115.831368 -265.391438) (xy 115.81532 -265.440831) (xy 115.791742 -265.487105)
			(xy 115.761216 -265.529121) (xy 115.724493 -265.565844) (xy 115.682477 -265.59637) (xy 115.636203 -265.619948)
			(xy 115.58681 -265.635996) (xy 115.535515 -265.644121) (xy 115.483581 -265.644121) (xy 115.432286 -265.635996)
			(xy 115.382893 -265.619948) (xy 115.336619 -265.59637) (xy 115.294603 -265.565844) (xy 115.25788 -265.529121)
			(xy 115.227354 -265.487105) (xy 115.203776 -265.440831) (xy 115.187728 -265.391438) (xy 115.179603 -265.340143)
			(xy 114.899439 -265.340143) (xy 114.891314 -265.391438) (xy 114.875266 -265.440831) (xy 114.851688 -265.487105)
			(xy 114.821162 -265.529121) (xy 114.784439 -265.565844) (xy 114.742423 -265.59637) (xy 114.696149 -265.619948)
			(xy 114.646756 -265.635996) (xy 114.595461 -265.644121) (xy 114.543527 -265.644121) (xy 114.492232 -265.635996)
			(xy 114.442839 -265.619948) (xy 114.396565 -265.59637) (xy 114.354549 -265.565844) (xy 114.317826 -265.529121)
			(xy 114.2873 -265.487105) (xy 114.263722 -265.440831) (xy 114.247674 -265.391438) (xy 114.239549 -265.340143)
			(xy 109.260893 -265.340143) (xy 109.252768 -265.391438) (xy 109.23672 -265.440831) (xy 109.213142 -265.487105)
			(xy 109.182616 -265.529121) (xy 109.145893 -265.565844) (xy 109.103877 -265.59637) (xy 109.057603 -265.619948)
			(xy 109.00821 -265.635996) (xy 108.956915 -265.644121) (xy 108.904981 -265.644121) (xy 108.853686 -265.635996)
			(xy 108.804293 -265.619948) (xy 108.758019 -265.59637) (xy 108.716003 -265.565844) (xy 108.67928 -265.529121)
			(xy 108.648754 -265.487105) (xy 108.625176 -265.440831) (xy 108.609128 -265.391438) (xy 108.601003 -265.340143)
			(xy 108.321093 -265.340143) (xy 108.312968 -265.391438) (xy 108.29692 -265.440831) (xy 108.273342 -265.487105)
			(xy 108.242816 -265.529121) (xy 108.206093 -265.565844) (xy 108.164077 -265.59637) (xy 108.117803 -265.619948)
			(xy 108.06841 -265.635996) (xy 108.017115 -265.644121) (xy 107.965181 -265.644121) (xy 107.913886 -265.635996)
			(xy 107.864493 -265.619948) (xy 107.818219 -265.59637) (xy 107.776203 -265.565844) (xy 107.73948 -265.529121)
			(xy 107.708954 -265.487105) (xy 107.685376 -265.440831) (xy 107.669328 -265.391438) (xy 107.661203 -265.340143)
			(xy 107.381293 -265.340143) (xy 107.373168 -265.391438) (xy 107.35712 -265.440831) (xy 107.333542 -265.487105)
			(xy 107.303016 -265.529121) (xy 107.266293 -265.565844) (xy 107.224277 -265.59637) (xy 107.178003 -265.619948)
			(xy 107.12861 -265.635996) (xy 107.077315 -265.644121) (xy 107.025381 -265.644121) (xy 106.974086 -265.635996)
			(xy 106.924693 -265.619948) (xy 106.878419 -265.59637) (xy 106.836403 -265.565844) (xy 106.79968 -265.529121)
			(xy 106.769154 -265.487105) (xy 106.745576 -265.440831) (xy 106.729528 -265.391438) (xy 106.721403 -265.340143)
			(xy 106.441493 -265.340143) (xy 106.433368 -265.391438) (xy 106.41732 -265.440831) (xy 106.393742 -265.487105)
			(xy 106.363216 -265.529121) (xy 106.326493 -265.565844) (xy 106.284477 -265.59637) (xy 106.238203 -265.619948)
			(xy 106.18881 -265.635996) (xy 106.137515 -265.644121) (xy 106.085581 -265.644121) (xy 106.034286 -265.635996)
			(xy 105.984893 -265.619948) (xy 105.938619 -265.59637) (xy 105.896603 -265.565844) (xy 105.85988 -265.529121)
			(xy 105.829354 -265.487105) (xy 105.805776 -265.440831) (xy 105.789728 -265.391438) (xy 105.781603 -265.340143)
			(xy 105.501693 -265.340143) (xy 105.493568 -265.391438) (xy 105.47752 -265.440831) (xy 105.453942 -265.487105)
			(xy 105.423416 -265.529121) (xy 105.386693 -265.565844) (xy 105.344677 -265.59637) (xy 105.298403 -265.619948)
			(xy 105.24901 -265.635996) (xy 105.197715 -265.644121) (xy 105.145781 -265.644121) (xy 105.094486 -265.635996)
			(xy 105.045093 -265.619948) (xy 104.998819 -265.59637) (xy 104.956803 -265.565844) (xy 104.92008 -265.529121)
			(xy 104.889554 -265.487105) (xy 104.865976 -265.440831) (xy 104.849928 -265.391438) (xy 104.841803 -265.340143)
			(xy 104.561893 -265.340143) (xy 104.553768 -265.391438) (xy 104.53772 -265.440831) (xy 104.514142 -265.487105)
			(xy 104.483616 -265.529121) (xy 104.446893 -265.565844) (xy 104.404877 -265.59637) (xy 104.358603 -265.619948)
			(xy 104.30921 -265.635996) (xy 104.257915 -265.644121) (xy 104.205981 -265.644121) (xy 104.154686 -265.635996)
			(xy 104.105293 -265.619948) (xy 104.059019 -265.59637) (xy 104.017003 -265.565844) (xy 103.98028 -265.529121)
			(xy 103.949754 -265.487105) (xy 103.926176 -265.440831) (xy 103.910128 -265.391438) (xy 103.902003 -265.340143)
			(xy 103.622093 -265.340143) (xy 103.613968 -265.391438) (xy 103.59792 -265.440831) (xy 103.574342 -265.487105)
			(xy 103.543816 -265.529121) (xy 103.507093 -265.565844) (xy 103.465077 -265.59637) (xy 103.418803 -265.619948)
			(xy 103.36941 -265.635996) (xy 103.318115 -265.644121) (xy 103.266181 -265.644121) (xy 103.214886 -265.635996)
			(xy 103.165493 -265.619948) (xy 103.119219 -265.59637) (xy 103.077203 -265.565844) (xy 103.04048 -265.529121)
			(xy 103.009954 -265.487105) (xy 102.986376 -265.440831) (xy 102.970328 -265.391438) (xy 102.962203 -265.340143)
			(xy 102.682156 -265.340143) (xy 102.682016 -265.34576) (xy 102.669994 -265.407774) (xy 102.658926 -265.437366)
			(xy 102.65537 -265.446256) (xy 102.65537 -265.701018) (xy 102.655797 -265.71565) (xy 102.663998 -265.743739)
			(xy 102.679837 -265.768343) (xy 102.702009 -265.787439) (xy 102.72869 -265.799454) (xy 102.757684 -265.8034)
			(xy 102.77221 -265.801602) (xy 102.78458 -265.799827) (xy 102.809498 -265.797923) (xy 102.821994 -265.797792)
			(xy 102.84796 -265.798274) (xy 102.899253 -265.806397) (xy 102.948643 -265.822445) (xy 102.994915 -265.846021)
			(xy 103.036929 -265.876545) (xy 103.073651 -265.913266) (xy 103.104176 -265.95528) (xy 103.127753 -266.001551)
			(xy 103.143801 -266.050941) (xy 103.151925 -266.102234) (xy 103.151925 -266.154166) (xy 103.151918 -266.154213)
			(xy 103.431849 -266.154213) (xy 103.431849 -266.102279) (xy 103.439974 -266.050984) (xy 103.456022 -266.001591)
			(xy 103.4796 -265.955317) (xy 103.510126 -265.913301) (xy 103.546849 -265.876578) (xy 103.588865 -265.846052)
			(xy 103.635139 -265.822474) (xy 103.684532 -265.806426) (xy 103.735827 -265.798301) (xy 103.787761 -265.798301)
			(xy 103.839056 -265.806426) (xy 103.888449 -265.822474) (xy 103.934723 -265.846052) (xy 103.976739 -265.876578)
			(xy 104.013462 -265.913301) (xy 104.043988 -265.955317) (xy 104.067566 -266.001591) (xy 104.083614 -266.050984)
			(xy 104.091739 -266.102279) (xy 104.092248 -266.128246) (xy 104.091739 -266.154213) (xy 104.371649 -266.154213)
			(xy 104.371649 -266.102279) (xy 104.379774 -266.050984) (xy 104.395822 -266.001591) (xy 104.4194 -265.955317)
			(xy 104.449926 -265.913301) (xy 104.486649 -265.876578) (xy 104.528665 -265.846052) (xy 104.574939 -265.822474)
			(xy 104.624332 -265.806426) (xy 104.675627 -265.798301) (xy 104.727561 -265.798301) (xy 104.778856 -265.806426)
			(xy 104.828249 -265.822474) (xy 104.874523 -265.846052) (xy 104.916539 -265.876578) (xy 104.953262 -265.913301)
			(xy 104.983788 -265.955317) (xy 105.007366 -266.001591) (xy 105.023414 -266.050984) (xy 105.031539 -266.102279)
			(xy 105.032048 -266.128246) (xy 105.031539 -266.154213) (xy 105.311449 -266.154213) (xy 105.311449 -266.102279)
			(xy 105.319574 -266.050984) (xy 105.335622 -266.001591) (xy 105.3592 -265.955317) (xy 105.389726 -265.913301)
			(xy 105.426449 -265.876578) (xy 105.468465 -265.846052) (xy 105.514739 -265.822474) (xy 105.564132 -265.806426)
			(xy 105.615427 -265.798301) (xy 105.667361 -265.798301) (xy 105.718656 -265.806426) (xy 105.768049 -265.822474)
			(xy 105.814323 -265.846052) (xy 105.856339 -265.876578) (xy 105.893062 -265.913301) (xy 105.923588 -265.955317)
			(xy 105.947166 -266.001591) (xy 105.963214 -266.050984) (xy 105.971339 -266.102279) (xy 105.971848 -266.128246)
			(xy 105.971339 -266.154213) (xy 106.251249 -266.154213) (xy 106.251249 -266.102279) (xy 106.259374 -266.050984)
			(xy 106.275422 -266.001591) (xy 106.299 -265.955317) (xy 106.329526 -265.913301) (xy 106.366249 -265.876578)
			(xy 106.408265 -265.846052) (xy 106.454539 -265.822474) (xy 106.503932 -265.806426) (xy 106.555227 -265.798301)
			(xy 106.607161 -265.798301) (xy 106.658456 -265.806426) (xy 106.707849 -265.822474) (xy 106.754123 -265.846052)
			(xy 106.796139 -265.876578) (xy 106.832862 -265.913301) (xy 106.863388 -265.955317) (xy 106.886966 -266.001591)
			(xy 106.903014 -266.050984) (xy 106.911139 -266.102279) (xy 106.911648 -266.128246) (xy 106.911139 -266.154213)
			(xy 107.191049 -266.154213) (xy 107.191049 -266.102279) (xy 107.199174 -266.050984) (xy 107.215222 -266.001591)
			(xy 107.2388 -265.955317) (xy 107.269326 -265.913301) (xy 107.306049 -265.876578) (xy 107.348065 -265.846052)
			(xy 107.394339 -265.822474) (xy 107.443732 -265.806426) (xy 107.495027 -265.798301) (xy 107.546961 -265.798301)
			(xy 107.598256 -265.806426) (xy 107.647649 -265.822474) (xy 107.693923 -265.846052) (xy 107.735939 -265.876578)
			(xy 107.772662 -265.913301) (xy 107.803188 -265.955317) (xy 107.826766 -266.001591) (xy 107.842814 -266.050984)
			(xy 107.850939 -266.102279) (xy 107.851448 -266.128246) (xy 107.850939 -266.154213) (xy 108.130849 -266.154213)
			(xy 108.130849 -266.102279) (xy 108.138974 -266.050984) (xy 108.155022 -266.001591) (xy 108.1786 -265.955317)
			(xy 108.209126 -265.913301) (xy 108.245849 -265.876578) (xy 108.287865 -265.846052) (xy 108.334139 -265.822474)
			(xy 108.383532 -265.806426) (xy 108.434827 -265.798301) (xy 108.486761 -265.798301) (xy 108.538056 -265.806426)
			(xy 108.587449 -265.822474) (xy 108.633723 -265.846052) (xy 108.675739 -265.876578) (xy 108.712462 -265.913301)
			(xy 108.742988 -265.955317) (xy 108.766566 -266.001591) (xy 108.782614 -266.050984) (xy 108.790739 -266.102279)
			(xy 108.791248 -266.128246) (xy 108.790739 -266.154213) (xy 109.070903 -266.154213) (xy 109.070903 -266.102279)
			(xy 109.079028 -266.050984) (xy 109.095076 -266.001591) (xy 109.118654 -265.955317) (xy 109.14918 -265.913301)
			(xy 109.185903 -265.876578) (xy 109.227919 -265.846052) (xy 109.274193 -265.822474) (xy 109.323586 -265.806426)
			(xy 109.374881 -265.798301) (xy 109.426815 -265.798301) (xy 109.47811 -265.806426) (xy 109.527503 -265.822474)
			(xy 109.573777 -265.846052) (xy 109.615793 -265.876578) (xy 109.652516 -265.913301) (xy 109.683042 -265.955317)
			(xy 109.70662 -266.001591) (xy 109.722668 -266.050984) (xy 109.730793 -266.102279) (xy 109.731302 -266.128246)
			(xy 109.730793 -266.154213) (xy 113.769649 -266.154213) (xy 113.769649 -266.102279) (xy 113.777774 -266.050984)
			(xy 113.793822 -266.001591) (xy 113.8174 -265.955317) (xy 113.847926 -265.913301) (xy 113.884649 -265.876578)
			(xy 113.926665 -265.846052) (xy 113.972939 -265.822474) (xy 114.022332 -265.806426) (xy 114.073627 -265.798301)
			(xy 114.125561 -265.798301) (xy 114.176856 -265.806426) (xy 114.226249 -265.822474) (xy 114.272523 -265.846052)
			(xy 114.314539 -265.876578) (xy 114.351262 -265.913301) (xy 114.381788 -265.955317) (xy 114.405366 -266.001591)
			(xy 114.421414 -266.050984) (xy 114.429539 -266.102279) (xy 114.430048 -266.128246) (xy 114.429539 -266.154213)
			(xy 114.709449 -266.154213) (xy 114.709449 -266.102279) (xy 114.717574 -266.050984) (xy 114.733622 -266.001591)
			(xy 114.7572 -265.955317) (xy 114.787726 -265.913301) (xy 114.824449 -265.876578) (xy 114.866465 -265.846052)
			(xy 114.912739 -265.822474) (xy 114.962132 -265.806426) (xy 115.013427 -265.798301) (xy 115.065361 -265.798301)
			(xy 115.116656 -265.806426) (xy 115.166049 -265.822474) (xy 115.212323 -265.846052) (xy 115.254339 -265.876578)
			(xy 115.291062 -265.913301) (xy 115.321588 -265.955317) (xy 115.345166 -266.001591) (xy 115.361214 -266.050984)
			(xy 115.369339 -266.102279) (xy 115.369848 -266.128246) (xy 115.369339 -266.154213) (xy 115.649249 -266.154213)
			(xy 115.649249 -266.102279) (xy 115.657374 -266.050984) (xy 115.673422 -266.001591) (xy 115.697 -265.955317)
			(xy 115.727526 -265.913301) (xy 115.764249 -265.876578) (xy 115.806265 -265.846052) (xy 115.852539 -265.822474)
			(xy 115.901932 -265.806426) (xy 115.953227 -265.798301) (xy 116.005161 -265.798301) (xy 116.056456 -265.806426)
			(xy 116.105849 -265.822474) (xy 116.152123 -265.846052) (xy 116.194139 -265.876578) (xy 116.230862 -265.913301)
			(xy 116.261388 -265.955317) (xy 116.284966 -266.001591) (xy 116.301014 -266.050984) (xy 116.309139 -266.102279)
			(xy 116.309648 -266.128246) (xy 116.309139 -266.154213) (xy 116.309099 -266.154467) (xy 116.589049 -266.154467)
			(xy 116.589049 -266.102533) (xy 116.597174 -266.051238) (xy 116.613222 -266.001845) (xy 116.6368 -265.955571)
			(xy 116.667326 -265.913555) (xy 116.704049 -265.876832) (xy 116.746065 -265.846306) (xy 116.792339 -265.822728)
			(xy 116.841732 -265.80668) (xy 116.893027 -265.798555) (xy 116.944961 -265.798555) (xy 116.996256 -265.80668)
			(xy 117.045649 -265.822728) (xy 117.091923 -265.846306) (xy 117.133939 -265.876832) (xy 117.170662 -265.913555)
			(xy 117.201188 -265.955571) (xy 117.224766 -266.001845) (xy 117.240814 -266.051238) (xy 117.248939 -266.102533)
			(xy 117.249448 -266.1285) (xy 117.248939 -266.154467) (xy 117.240814 -266.205762) (xy 117.224766 -266.255155)
			(xy 117.201188 -266.301429) (xy 117.170662 -266.343445) (xy 117.133939 -266.380168) (xy 117.091923 -266.410694)
			(xy 117.045649 -266.434272) (xy 116.996256 -266.45032) (xy 116.944961 -266.458445) (xy 116.893027 -266.458445)
			(xy 116.841732 -266.45032) (xy 116.792339 -266.434272) (xy 116.746065 -266.410694) (xy 116.704049 -266.380168)
			(xy 116.667326 -266.343445) (xy 116.6368 -266.301429) (xy 116.613222 -266.255155) (xy 116.597174 -266.205762)
			(xy 116.589049 -266.154467) (xy 116.309099 -266.154467) (xy 116.301014 -266.205508) (xy 116.284966 -266.254901)
			(xy 116.261388 -266.301175) (xy 116.230862 -266.343191) (xy 116.194139 -266.379914) (xy 116.152123 -266.41044)
			(xy 116.105849 -266.434018) (xy 116.056456 -266.450066) (xy 116.005161 -266.458191) (xy 115.953227 -266.458191)
			(xy 115.901932 -266.450066) (xy 115.852539 -266.434018) (xy 115.806265 -266.41044) (xy 115.764249 -266.379914)
			(xy 115.727526 -266.343191) (xy 115.697 -266.301175) (xy 115.673422 -266.254901) (xy 115.657374 -266.205508)
			(xy 115.649249 -266.154213) (xy 115.369339 -266.154213) (xy 115.361214 -266.205508) (xy 115.345166 -266.254901)
			(xy 115.321588 -266.301175) (xy 115.291062 -266.343191) (xy 115.254339 -266.379914) (xy 115.212323 -266.41044)
			(xy 115.166049 -266.434018) (xy 115.116656 -266.450066) (xy 115.065361 -266.458191) (xy 115.013427 -266.458191)
			(xy 114.962132 -266.450066) (xy 114.912739 -266.434018) (xy 114.866465 -266.41044) (xy 114.824449 -266.379914)
			(xy 114.787726 -266.343191) (xy 114.7572 -266.301175) (xy 114.733622 -266.254901) (xy 114.717574 -266.205508)
			(xy 114.709449 -266.154213) (xy 114.429539 -266.154213) (xy 114.421414 -266.205508) (xy 114.405366 -266.254901)
			(xy 114.381788 -266.301175) (xy 114.351262 -266.343191) (xy 114.314539 -266.379914) (xy 114.272523 -266.41044)
			(xy 114.226249 -266.434018) (xy 114.176856 -266.450066) (xy 114.125561 -266.458191) (xy 114.073627 -266.458191)
			(xy 114.022332 -266.450066) (xy 113.972939 -266.434018) (xy 113.926665 -266.41044) (xy 113.884649 -266.379914)
			(xy 113.847926 -266.343191) (xy 113.8174 -266.301175) (xy 113.793822 -266.254901) (xy 113.777774 -266.205508)
			(xy 113.769649 -266.154213) (xy 109.730793 -266.154213) (xy 109.722668 -266.205508) (xy 109.70662 -266.254901)
			(xy 109.683042 -266.301175) (xy 109.652516 -266.343191) (xy 109.615793 -266.379914) (xy 109.573777 -266.41044)
			(xy 109.527503 -266.434018) (xy 109.47811 -266.450066) (xy 109.426815 -266.458191) (xy 109.374881 -266.458191)
			(xy 109.323586 -266.450066) (xy 109.274193 -266.434018) (xy 109.227919 -266.41044) (xy 109.185903 -266.379914)
			(xy 109.14918 -266.343191) (xy 109.118654 -266.301175) (xy 109.095076 -266.254901) (xy 109.079028 -266.205508)
			(xy 109.070903 -266.154213) (xy 108.790739 -266.154213) (xy 108.782614 -266.205508) (xy 108.766566 -266.254901)
			(xy 108.742988 -266.301175) (xy 108.712462 -266.343191) (xy 108.675739 -266.379914) (xy 108.633723 -266.41044)
			(xy 108.587449 -266.434018) (xy 108.538056 -266.450066) (xy 108.486761 -266.458191) (xy 108.434827 -266.458191)
			(xy 108.383532 -266.450066) (xy 108.334139 -266.434018) (xy 108.287865 -266.41044) (xy 108.245849 -266.379914)
			(xy 108.209126 -266.343191) (xy 108.1786 -266.301175) (xy 108.155022 -266.254901) (xy 108.138974 -266.205508)
			(xy 108.130849 -266.154213) (xy 107.850939 -266.154213) (xy 107.842814 -266.205508) (xy 107.826766 -266.254901)
			(xy 107.803188 -266.301175) (xy 107.772662 -266.343191) (xy 107.735939 -266.379914) (xy 107.693923 -266.41044)
			(xy 107.647649 -266.434018) (xy 107.598256 -266.450066) (xy 107.546961 -266.458191) (xy 107.495027 -266.458191)
			(xy 107.443732 -266.450066) (xy 107.394339 -266.434018) (xy 107.348065 -266.41044) (xy 107.306049 -266.379914)
			(xy 107.269326 -266.343191) (xy 107.2388 -266.301175) (xy 107.215222 -266.254901) (xy 107.199174 -266.205508)
			(xy 107.191049 -266.154213) (xy 106.911139 -266.154213) (xy 106.903014 -266.205508) (xy 106.886966 -266.254901)
			(xy 106.863388 -266.301175) (xy 106.832862 -266.343191) (xy 106.796139 -266.379914) (xy 106.754123 -266.41044)
			(xy 106.707849 -266.434018) (xy 106.658456 -266.450066) (xy 106.607161 -266.458191) (xy 106.555227 -266.458191)
			(xy 106.503932 -266.450066) (xy 106.454539 -266.434018) (xy 106.408265 -266.41044) (xy 106.366249 -266.379914)
			(xy 106.329526 -266.343191) (xy 106.299 -266.301175) (xy 106.275422 -266.254901) (xy 106.259374 -266.205508)
			(xy 106.251249 -266.154213) (xy 105.971339 -266.154213) (xy 105.963214 -266.205508) (xy 105.947166 -266.254901)
			(xy 105.923588 -266.301175) (xy 105.893062 -266.343191) (xy 105.856339 -266.379914) (xy 105.814323 -266.41044)
			(xy 105.768049 -266.434018) (xy 105.718656 -266.450066) (xy 105.667361 -266.458191) (xy 105.615427 -266.458191)
			(xy 105.564132 -266.450066) (xy 105.514739 -266.434018) (xy 105.468465 -266.41044) (xy 105.426449 -266.379914)
			(xy 105.389726 -266.343191) (xy 105.3592 -266.301175) (xy 105.335622 -266.254901) (xy 105.319574 -266.205508)
			(xy 105.311449 -266.154213) (xy 105.031539 -266.154213) (xy 105.023414 -266.205508) (xy 105.007366 -266.254901)
			(xy 104.983788 -266.301175) (xy 104.953262 -266.343191) (xy 104.916539 -266.379914) (xy 104.874523 -266.41044)
			(xy 104.828249 -266.434018) (xy 104.778856 -266.450066) (xy 104.727561 -266.458191) (xy 104.675627 -266.458191)
			(xy 104.624332 -266.450066) (xy 104.574939 -266.434018) (xy 104.528665 -266.41044) (xy 104.486649 -266.379914)
			(xy 104.449926 -266.343191) (xy 104.4194 -266.301175) (xy 104.395822 -266.254901) (xy 104.379774 -266.205508)
			(xy 104.371649 -266.154213) (xy 104.091739 -266.154213) (xy 104.083614 -266.205508) (xy 104.067566 -266.254901)
			(xy 104.043988 -266.301175) (xy 104.013462 -266.343191) (xy 103.976739 -266.379914) (xy 103.934723 -266.41044)
			(xy 103.888449 -266.434018) (xy 103.839056 -266.450066) (xy 103.787761 -266.458191) (xy 103.735827 -266.458191)
			(xy 103.684532 -266.450066) (xy 103.635139 -266.434018) (xy 103.588865 -266.41044) (xy 103.546849 -266.379914)
			(xy 103.510126 -266.343191) (xy 103.4796 -266.301175) (xy 103.456022 -266.254901) (xy 103.439974 -266.205508)
			(xy 103.431849 -266.154213) (xy 103.151918 -266.154213) (xy 103.143801 -266.205459) (xy 103.127753 -266.254849)
			(xy 103.104176 -266.30112) (xy 103.073651 -266.343134) (xy 103.036929 -266.379855) (xy 102.994915 -266.410379)
			(xy 102.948643 -266.433955) (xy 102.899253 -266.450003) (xy 102.84796 -266.458126) (xy 102.821994 -266.4587)
			(xy 102.809498 -266.458571) (xy 102.78458 -266.456661) (xy 102.77221 -266.45489) (xy 102.757686 -266.453174)
			(xy 102.728725 -266.45716) (xy 102.702076 -266.469179) (xy 102.679919 -266.48825) (xy 102.664065 -266.512812)
			(xy 102.655811 -266.540857) (xy 102.65537 -266.555474) (xy 102.65537 -266.809728) (xy 102.658926 -266.818618)
			(xy 102.670067 -266.848188) (xy 102.682085 -266.910217) (xy 102.682802 -266.941808) (xy 102.682153 -266.967775)
			(xy 102.962203 -266.967775) (xy 102.962203 -266.915841) (xy 102.970328 -266.864546) (xy 102.986376 -266.815153)
			(xy 103.009954 -266.768879) (xy 103.04048 -266.726863) (xy 103.077203 -266.69014) (xy 103.119219 -266.659614)
			(xy 103.165493 -266.636036) (xy 103.214886 -266.619988) (xy 103.266181 -266.611863) (xy 103.318115 -266.611863)
			(xy 103.36941 -266.619988) (xy 103.418803 -266.636036) (xy 103.465077 -266.659614) (xy 103.507093 -266.69014)
			(xy 103.543816 -266.726863) (xy 103.574342 -266.768879) (xy 103.59792 -266.815153) (xy 103.613968 -266.864546)
			(xy 103.622093 -266.915841) (xy 103.622602 -266.941808) (xy 103.622093 -266.967775) (xy 103.901749 -266.967775)
			(xy 103.901749 -266.915841) (xy 103.909874 -266.864546) (xy 103.925922 -266.815153) (xy 103.9495 -266.768879)
			(xy 103.980026 -266.726863) (xy 104.016749 -266.69014) (xy 104.058765 -266.659614) (xy 104.105039 -266.636036)
			(xy 104.154432 -266.619988) (xy 104.205727 -266.611863) (xy 104.257661 -266.611863) (xy 104.308956 -266.619988)
			(xy 104.358349 -266.636036) (xy 104.404623 -266.659614) (xy 104.446639 -266.69014) (xy 104.483362 -266.726863)
			(xy 104.513888 -266.768879) (xy 104.537466 -266.815153) (xy 104.553514 -266.864546) (xy 104.561639 -266.915841)
			(xy 104.562148 -266.941808) (xy 104.561639 -266.967775) (xy 104.841295 -266.967775) (xy 104.841295 -266.915841)
			(xy 104.84942 -266.864546) (xy 104.865468 -266.815153) (xy 104.889046 -266.768879) (xy 104.919572 -266.726863)
			(xy 104.956295 -266.69014) (xy 104.998311 -266.659614) (xy 105.044585 -266.636036) (xy 105.093978 -266.619988)
			(xy 105.145273 -266.611863) (xy 105.197207 -266.611863) (xy 105.248502 -266.619988) (xy 105.297895 -266.636036)
			(xy 105.344169 -266.659614) (xy 105.386185 -266.69014) (xy 105.422908 -266.726863) (xy 105.453434 -266.768879)
			(xy 105.477012 -266.815153) (xy 105.49306 -266.864546) (xy 105.501185 -266.915841) (xy 105.501694 -266.941808)
			(xy 105.501185 -266.967775) (xy 105.781349 -266.967775) (xy 105.781349 -266.915841) (xy 105.789474 -266.864546)
			(xy 105.805522 -266.815153) (xy 105.8291 -266.768879) (xy 105.859626 -266.726863) (xy 105.896349 -266.69014)
			(xy 105.938365 -266.659614) (xy 105.984639 -266.636036) (xy 106.034032 -266.619988) (xy 106.085327 -266.611863)
			(xy 106.137261 -266.611863) (xy 106.188556 -266.619988) (xy 106.237949 -266.636036) (xy 106.284223 -266.659614)
			(xy 106.326239 -266.69014) (xy 106.362962 -266.726863) (xy 106.393488 -266.768879) (xy 106.417066 -266.815153)
			(xy 106.433114 -266.864546) (xy 106.441239 -266.915841) (xy 106.441748 -266.941808) (xy 106.441239 -266.967775)
			(xy 106.721403 -266.967775) (xy 106.721403 -266.915841) (xy 106.729528 -266.864546) (xy 106.745576 -266.815153)
			(xy 106.769154 -266.768879) (xy 106.79968 -266.726863) (xy 106.836403 -266.69014) (xy 106.878419 -266.659614)
			(xy 106.924693 -266.636036) (xy 106.974086 -266.619988) (xy 107.025381 -266.611863) (xy 107.077315 -266.611863)
			(xy 107.12861 -266.619988) (xy 107.178003 -266.636036) (xy 107.224277 -266.659614) (xy 107.266293 -266.69014)
			(xy 107.303016 -266.726863) (xy 107.333542 -266.768879) (xy 107.35712 -266.815153) (xy 107.373168 -266.864546)
			(xy 107.381293 -266.915841) (xy 107.381802 -266.941808) (xy 107.381293 -266.967775) (xy 107.661203 -266.967775)
			(xy 107.661203 -266.915841) (xy 107.669328 -266.864546) (xy 107.685376 -266.815153) (xy 107.708954 -266.768879)
			(xy 107.73948 -266.726863) (xy 107.776203 -266.69014) (xy 107.818219 -266.659614) (xy 107.864493 -266.636036)
			(xy 107.913886 -266.619988) (xy 107.965181 -266.611863) (xy 108.017115 -266.611863) (xy 108.06841 -266.619988)
			(xy 108.117803 -266.636036) (xy 108.164077 -266.659614) (xy 108.206093 -266.69014) (xy 108.242816 -266.726863)
			(xy 108.273342 -266.768879) (xy 108.29692 -266.815153) (xy 108.312968 -266.864546) (xy 108.321093 -266.915841)
			(xy 108.321602 -266.941808) (xy 108.321093 -266.967775) (xy 108.601003 -266.967775) (xy 108.601003 -266.915841)
			(xy 108.609128 -266.864546) (xy 108.625176 -266.815153) (xy 108.648754 -266.768879) (xy 108.67928 -266.726863)
			(xy 108.716003 -266.69014) (xy 108.758019 -266.659614) (xy 108.804293 -266.636036) (xy 108.853686 -266.619988)
			(xy 108.904981 -266.611863) (xy 108.956915 -266.611863) (xy 109.00821 -266.619988) (xy 109.057603 -266.636036)
			(xy 109.103877 -266.659614) (xy 109.145893 -266.69014) (xy 109.182616 -266.726863) (xy 109.213142 -266.768879)
			(xy 109.23672 -266.815153) (xy 109.252768 -266.864546) (xy 109.260893 -266.915841) (xy 109.261402 -266.941808)
			(xy 109.260893 -266.967775) (xy 109.540549 -266.967775) (xy 109.540549 -266.915841) (xy 109.548674 -266.864546)
			(xy 109.564722 -266.815153) (xy 109.5883 -266.768879) (xy 109.618826 -266.726863) (xy 109.655549 -266.69014)
			(xy 109.697565 -266.659614) (xy 109.743839 -266.636036) (xy 109.793232 -266.619988) (xy 109.844527 -266.611863)
			(xy 109.896461 -266.611863) (xy 109.947756 -266.619988) (xy 109.997149 -266.636036) (xy 110.043423 -266.659614)
			(xy 110.085439 -266.69014) (xy 110.122162 -266.726863) (xy 110.152688 -266.768879) (xy 110.176266 -266.815153)
			(xy 110.192314 -266.864546) (xy 110.200439 -266.915841) (xy 110.200948 -266.941808) (xy 110.200439 -266.967775)
			(xy 113.299749 -266.967775) (xy 113.299749 -266.915841) (xy 113.307874 -266.864546) (xy 113.323922 -266.815153)
			(xy 113.3475 -266.768879) (xy 113.378026 -266.726863) (xy 113.414749 -266.69014) (xy 113.456765 -266.659614)
			(xy 113.503039 -266.636036) (xy 113.552432 -266.619988) (xy 113.603727 -266.611863) (xy 113.655661 -266.611863)
			(xy 113.706956 -266.619988) (xy 113.756349 -266.636036) (xy 113.802623 -266.659614) (xy 113.844639 -266.69014)
			(xy 113.881362 -266.726863) (xy 113.911888 -266.768879) (xy 113.935466 -266.815153) (xy 113.951514 -266.864546)
			(xy 113.959639 -266.915841) (xy 113.960148 -266.941808) (xy 113.959639 -266.967775) (xy 114.239803 -266.967775)
			(xy 114.239803 -266.915841) (xy 114.247928 -266.864546) (xy 114.263976 -266.815153) (xy 114.287554 -266.768879)
			(xy 114.31808 -266.726863) (xy 114.354803 -266.69014) (xy 114.396819 -266.659614) (xy 114.443093 -266.636036)
			(xy 114.492486 -266.619988) (xy 114.543781 -266.611863) (xy 114.595715 -266.611863) (xy 114.64701 -266.619988)
			(xy 114.696403 -266.636036) (xy 114.742677 -266.659614) (xy 114.784693 -266.69014) (xy 114.821416 -266.726863)
			(xy 114.851942 -266.768879) (xy 114.87552 -266.815153) (xy 114.891568 -266.864546) (xy 114.899693 -266.915841)
			(xy 114.900202 -266.941808) (xy 114.899693 -266.967775) (xy 115.179603 -266.967775) (xy 115.179603 -266.915841)
			(xy 115.187728 -266.864546) (xy 115.203776 -266.815153) (xy 115.227354 -266.768879) (xy 115.25788 -266.726863)
			(xy 115.294603 -266.69014) (xy 115.336619 -266.659614) (xy 115.382893 -266.636036) (xy 115.432286 -266.619988)
			(xy 115.483581 -266.611863) (xy 115.535515 -266.611863) (xy 115.58681 -266.619988) (xy 115.636203 -266.636036)
			(xy 115.682477 -266.659614) (xy 115.724493 -266.69014) (xy 115.761216 -266.726863) (xy 115.791742 -266.768879)
			(xy 115.81532 -266.815153) (xy 115.831368 -266.864546) (xy 115.839493 -266.915841) (xy 115.840002 -266.941808)
			(xy 115.839493 -266.967775) (xy 116.118895 -266.967775) (xy 116.118895 -266.915841) (xy 116.12702 -266.864546)
			(xy 116.143068 -266.815153) (xy 116.166646 -266.768879) (xy 116.197172 -266.726863) (xy 116.233895 -266.69014)
			(xy 116.275911 -266.659614) (xy 116.322185 -266.636036) (xy 116.371578 -266.619988) (xy 116.422873 -266.611863)
			(xy 116.474807 -266.611863) (xy 116.526102 -266.619988) (xy 116.575495 -266.636036) (xy 116.621769 -266.659614)
			(xy 116.663785 -266.69014) (xy 116.700508 -266.726863) (xy 116.731034 -266.768879) (xy 116.754612 -266.815153)
			(xy 116.77066 -266.864546) (xy 116.778785 -266.915841) (xy 116.779294 -266.941808) (xy 116.778785 -266.967775)
			(xy 117.059203 -266.967775) (xy 117.059203 -266.915841) (xy 117.067328 -266.864546) (xy 117.083376 -266.815153)
			(xy 117.106954 -266.768879) (xy 117.13748 -266.726863) (xy 117.174203 -266.69014) (xy 117.216219 -266.659614)
			(xy 117.262493 -266.636036) (xy 117.311886 -266.619988) (xy 117.363181 -266.611863) (xy 117.415115 -266.611863)
			(xy 117.46641 -266.619988) (xy 117.515803 -266.636036) (xy 117.562077 -266.659614) (xy 117.604093 -266.69014)
			(xy 117.640816 -266.726863) (xy 117.671342 -266.768879) (xy 117.69492 -266.815153) (xy 117.710968 -266.864546)
			(xy 117.719093 -266.915841) (xy 117.719602 -266.941808) (xy 117.719093 -266.967775) (xy 117.710968 -267.01907)
			(xy 117.69492 -267.068463) (xy 117.671342 -267.114737) (xy 117.640816 -267.156753) (xy 117.604093 -267.193476)
			(xy 117.562077 -267.224002) (xy 117.515803 -267.24758) (xy 117.46641 -267.263628) (xy 117.415115 -267.271753)
			(xy 117.363181 -267.271753) (xy 117.311886 -267.263628) (xy 117.262493 -267.24758) (xy 117.216219 -267.224002)
			(xy 117.174203 -267.193476) (xy 117.13748 -267.156753) (xy 117.106954 -267.114737) (xy 117.083376 -267.068463)
			(xy 117.067328 -267.01907) (xy 117.059203 -266.967775) (xy 116.778785 -266.967775) (xy 116.77066 -267.01907)
			(xy 116.754612 -267.068463) (xy 116.731034 -267.114737) (xy 116.700508 -267.156753) (xy 116.663785 -267.193476)
			(xy 116.621769 -267.224002) (xy 116.575495 -267.24758) (xy 116.526102 -267.263628) (xy 116.474807 -267.271753)
			(xy 116.422873 -267.271753) (xy 116.371578 -267.263628) (xy 116.322185 -267.24758) (xy 116.275911 -267.224002)
			(xy 116.233895 -267.193476) (xy 116.197172 -267.156753) (xy 116.166646 -267.114737) (xy 116.143068 -267.068463)
			(xy 116.12702 -267.01907) (xy 116.118895 -266.967775) (xy 115.839493 -266.967775) (xy 115.831368 -267.01907)
			(xy 115.81532 -267.068463) (xy 115.791742 -267.114737) (xy 115.761216 -267.156753) (xy 115.724493 -267.193476)
			(xy 115.682477 -267.224002) (xy 115.636203 -267.24758) (xy 115.58681 -267.263628) (xy 115.535515 -267.271753)
			(xy 115.483581 -267.271753) (xy 115.432286 -267.263628) (xy 115.382893 -267.24758) (xy 115.336619 -267.224002)
			(xy 115.294603 -267.193476) (xy 115.25788 -267.156753) (xy 115.227354 -267.114737) (xy 115.203776 -267.068463)
			(xy 115.187728 -267.01907) (xy 115.179603 -266.967775) (xy 114.899693 -266.967775) (xy 114.891568 -267.01907)
			(xy 114.87552 -267.068463) (xy 114.851942 -267.114737) (xy 114.821416 -267.156753) (xy 114.784693 -267.193476)
			(xy 114.742677 -267.224002) (xy 114.696403 -267.24758) (xy 114.64701 -267.263628) (xy 114.595715 -267.271753)
			(xy 114.543781 -267.271753) (xy 114.492486 -267.263628) (xy 114.443093 -267.24758) (xy 114.396819 -267.224002)
			(xy 114.354803 -267.193476) (xy 114.31808 -267.156753) (xy 114.287554 -267.114737) (xy 114.263976 -267.068463)
			(xy 114.247928 -267.01907) (xy 114.239803 -266.967775) (xy 113.959639 -266.967775) (xy 113.951514 -267.01907)
			(xy 113.935466 -267.068463) (xy 113.911888 -267.114737) (xy 113.881362 -267.156753) (xy 113.844639 -267.193476)
			(xy 113.802623 -267.224002) (xy 113.756349 -267.24758) (xy 113.706956 -267.263628) (xy 113.655661 -267.271753)
			(xy 113.603727 -267.271753) (xy 113.552432 -267.263628) (xy 113.503039 -267.24758) (xy 113.456765 -267.224002)
			(xy 113.414749 -267.193476) (xy 113.378026 -267.156753) (xy 113.3475 -267.114737) (xy 113.323922 -267.068463)
			(xy 113.307874 -267.01907) (xy 113.299749 -266.967775) (xy 110.200439 -266.967775) (xy 110.192314 -267.01907)
			(xy 110.176266 -267.068463) (xy 110.152688 -267.114737) (xy 110.122162 -267.156753) (xy 110.085439 -267.193476)
			(xy 110.043423 -267.224002) (xy 109.997149 -267.24758) (xy 109.947756 -267.263628) (xy 109.896461 -267.271753)
			(xy 109.844527 -267.271753) (xy 109.793232 -267.263628) (xy 109.743839 -267.24758) (xy 109.697565 -267.224002)
			(xy 109.655549 -267.193476) (xy 109.618826 -267.156753) (xy 109.5883 -267.114737) (xy 109.564722 -267.068463)
			(xy 109.548674 -267.01907) (xy 109.540549 -266.967775) (xy 109.260893 -266.967775) (xy 109.252768 -267.01907)
			(xy 109.23672 -267.068463) (xy 109.213142 -267.114737) (xy 109.182616 -267.156753) (xy 109.145893 -267.193476)
			(xy 109.103877 -267.224002) (xy 109.057603 -267.24758) (xy 109.00821 -267.263628) (xy 108.956915 -267.271753)
			(xy 108.904981 -267.271753) (xy 108.853686 -267.263628) (xy 108.804293 -267.24758) (xy 108.758019 -267.224002)
			(xy 108.716003 -267.193476) (xy 108.67928 -267.156753) (xy 108.648754 -267.114737) (xy 108.625176 -267.068463)
			(xy 108.609128 -267.01907) (xy 108.601003 -266.967775) (xy 108.321093 -266.967775) (xy 108.312968 -267.01907)
			(xy 108.29692 -267.068463) (xy 108.273342 -267.114737) (xy 108.242816 -267.156753) (xy 108.206093 -267.193476)
			(xy 108.164077 -267.224002) (xy 108.117803 -267.24758) (xy 108.06841 -267.263628) (xy 108.017115 -267.271753)
			(xy 107.965181 -267.271753) (xy 107.913886 -267.263628) (xy 107.864493 -267.24758) (xy 107.818219 -267.224002)
			(xy 107.776203 -267.193476) (xy 107.73948 -267.156753) (xy 107.708954 -267.114737) (xy 107.685376 -267.068463)
			(xy 107.669328 -267.01907) (xy 107.661203 -266.967775) (xy 107.381293 -266.967775) (xy 107.373168 -267.01907)
			(xy 107.35712 -267.068463) (xy 107.333542 -267.114737) (xy 107.303016 -267.156753) (xy 107.266293 -267.193476)
			(xy 107.224277 -267.224002) (xy 107.178003 -267.24758) (xy 107.12861 -267.263628) (xy 107.077315 -267.271753)
			(xy 107.025381 -267.271753) (xy 106.974086 -267.263628) (xy 106.924693 -267.24758) (xy 106.878419 -267.224002)
			(xy 106.836403 -267.193476) (xy 106.79968 -267.156753) (xy 106.769154 -267.114737) (xy 106.745576 -267.068463)
			(xy 106.729528 -267.01907) (xy 106.721403 -266.967775) (xy 106.441239 -266.967775) (xy 106.433114 -267.01907)
			(xy 106.417066 -267.068463) (xy 106.393488 -267.114737) (xy 106.362962 -267.156753) (xy 106.326239 -267.193476)
			(xy 106.284223 -267.224002) (xy 106.237949 -267.24758) (xy 106.188556 -267.263628) (xy 106.137261 -267.271753)
			(xy 106.085327 -267.271753) (xy 106.034032 -267.263628) (xy 105.984639 -267.24758) (xy 105.938365 -267.224002)
			(xy 105.896349 -267.193476) (xy 105.859626 -267.156753) (xy 105.8291 -267.114737) (xy 105.805522 -267.068463)
			(xy 105.789474 -267.01907) (xy 105.781349 -266.967775) (xy 105.501185 -266.967775) (xy 105.49306 -267.01907)
			(xy 105.477012 -267.068463) (xy 105.453434 -267.114737) (xy 105.422908 -267.156753) (xy 105.386185 -267.193476)
			(xy 105.344169 -267.224002) (xy 105.297895 -267.24758) (xy 105.248502 -267.263628) (xy 105.197207 -267.271753)
			(xy 105.145273 -267.271753) (xy 105.093978 -267.263628) (xy 105.044585 -267.24758) (xy 104.998311 -267.224002)
			(xy 104.956295 -267.193476) (xy 104.919572 -267.156753) (xy 104.889046 -267.114737) (xy 104.865468 -267.068463)
			(xy 104.84942 -267.01907) (xy 104.841295 -266.967775) (xy 104.561639 -266.967775) (xy 104.553514 -267.01907)
			(xy 104.537466 -267.068463) (xy 104.513888 -267.114737) (xy 104.483362 -267.156753) (xy 104.446639 -267.193476)
			(xy 104.404623 -267.224002) (xy 104.358349 -267.24758) (xy 104.308956 -267.263628) (xy 104.257661 -267.271753)
			(xy 104.205727 -267.271753) (xy 104.154432 -267.263628) (xy 104.105039 -267.24758) (xy 104.058765 -267.224002)
			(xy 104.016749 -267.193476) (xy 103.980026 -267.156753) (xy 103.9495 -267.114737) (xy 103.925922 -267.068463)
			(xy 103.909874 -267.01907) (xy 103.901749 -266.967775) (xy 103.622093 -266.967775) (xy 103.613968 -267.01907)
			(xy 103.59792 -267.068463) (xy 103.574342 -267.114737) (xy 103.543816 -267.156753) (xy 103.507093 -267.193476)
			(xy 103.465077 -267.224002) (xy 103.418803 -267.24758) (xy 103.36941 -267.263628) (xy 103.318115 -267.271753)
			(xy 103.266181 -267.271753) (xy 103.214886 -267.263628) (xy 103.165493 -267.24758) (xy 103.119219 -267.224002)
			(xy 103.077203 -267.193476) (xy 103.04048 -267.156753) (xy 103.009954 -267.114737) (xy 102.986376 -267.068463)
			(xy 102.970328 -267.01907) (xy 102.962203 -266.967775) (xy 102.682153 -266.967775) (xy 102.682013 -266.973391)
			(xy 102.669985 -267.035403) (xy 102.658926 -267.064998) (xy 102.65537 -267.073888) (xy 102.65537 -267.32865)
			(xy 102.655801 -267.343279) (xy 102.664008 -267.37136) (xy 102.679848 -267.395956) (xy 102.702018 -267.415044)
			(xy 102.728694 -267.427055) (xy 102.757682 -267.431) (xy 102.77221 -267.429234) (xy 102.78458 -267.427459)
			(xy 102.809498 -267.425555) (xy 102.821994 -267.425424) (xy 102.847965 -267.425906) (xy 102.899269 -267.434031)
			(xy 102.948669 -267.450082) (xy 102.994951 -267.473663) (xy 103.036974 -267.504193) (xy 103.073703 -267.540922)
			(xy 103.104234 -267.582944) (xy 103.127816 -267.629225) (xy 103.143867 -267.678626) (xy 103.151993 -267.729929)
			(xy 103.151993 -267.781845) (xy 103.431849 -267.781845) (xy 103.431849 -267.729911) (xy 103.439974 -267.678616)
			(xy 103.456022 -267.629223) (xy 103.4796 -267.582949) (xy 103.510126 -267.540933) (xy 103.546849 -267.50421)
			(xy 103.588865 -267.473684) (xy 103.635139 -267.450106) (xy 103.684532 -267.434058) (xy 103.735827 -267.425933)
			(xy 103.787761 -267.425933) (xy 103.839056 -267.434058) (xy 103.888449 -267.450106) (xy 103.934723 -267.473684)
			(xy 103.976739 -267.50421) (xy 104.013462 -267.540933) (xy 104.043988 -267.582949) (xy 104.067566 -267.629223)
			(xy 104.083614 -267.678616) (xy 104.091739 -267.729911) (xy 104.092248 -267.755878) (xy 104.091739 -267.781845)
			(xy 104.371649 -267.781845) (xy 104.371649 -267.729911) (xy 104.379774 -267.678616) (xy 104.395822 -267.629223)
			(xy 104.4194 -267.582949) (xy 104.449926 -267.540933) (xy 104.486649 -267.50421) (xy 104.528665 -267.473684)
			(xy 104.574939 -267.450106) (xy 104.624332 -267.434058) (xy 104.675627 -267.425933) (xy 104.727561 -267.425933)
			(xy 104.778856 -267.434058) (xy 104.828249 -267.450106) (xy 104.874523 -267.473684) (xy 104.916539 -267.50421)
			(xy 104.953262 -267.540933) (xy 104.983788 -267.582949) (xy 105.007366 -267.629223) (xy 105.023414 -267.678616)
			(xy 105.031539 -267.729911) (xy 105.032048 -267.755878) (xy 105.031539 -267.781845) (xy 105.311449 -267.781845)
			(xy 105.311449 -267.729911) (xy 105.319574 -267.678616) (xy 105.335622 -267.629223) (xy 105.3592 -267.582949)
			(xy 105.389726 -267.540933) (xy 105.426449 -267.50421) (xy 105.468465 -267.473684) (xy 105.514739 -267.450106)
			(xy 105.564132 -267.434058) (xy 105.615427 -267.425933) (xy 105.667361 -267.425933) (xy 105.718656 -267.434058)
			(xy 105.768049 -267.450106) (xy 105.814323 -267.473684) (xy 105.856339 -267.50421) (xy 105.893062 -267.540933)
			(xy 105.923588 -267.582949) (xy 105.947166 -267.629223) (xy 105.963214 -267.678616) (xy 105.971339 -267.729911)
			(xy 105.971848 -267.755878) (xy 105.971339 -267.781845) (xy 106.251249 -267.781845) (xy 106.251249 -267.729911)
			(xy 106.259374 -267.678616) (xy 106.275422 -267.629223) (xy 106.299 -267.582949) (xy 106.329526 -267.540933)
			(xy 106.366249 -267.50421) (xy 106.408265 -267.473684) (xy 106.454539 -267.450106) (xy 106.503932 -267.434058)
			(xy 106.555227 -267.425933) (xy 106.607161 -267.425933) (xy 106.658456 -267.434058) (xy 106.707849 -267.450106)
			(xy 106.754123 -267.473684) (xy 106.796139 -267.50421) (xy 106.832862 -267.540933) (xy 106.863388 -267.582949)
			(xy 106.886966 -267.629223) (xy 106.903014 -267.678616) (xy 106.911139 -267.729911) (xy 106.911648 -267.755878)
			(xy 106.911139 -267.781845) (xy 107.191049 -267.781845) (xy 107.191049 -267.729911) (xy 107.199174 -267.678616)
			(xy 107.215222 -267.629223) (xy 107.2388 -267.582949) (xy 107.269326 -267.540933) (xy 107.306049 -267.50421)
			(xy 107.348065 -267.473684) (xy 107.394339 -267.450106) (xy 107.443732 -267.434058) (xy 107.495027 -267.425933)
			(xy 107.546961 -267.425933) (xy 107.598256 -267.434058) (xy 107.647649 -267.450106) (xy 107.693923 -267.473684)
			(xy 107.735939 -267.50421) (xy 107.772662 -267.540933) (xy 107.803188 -267.582949) (xy 107.826766 -267.629223)
			(xy 107.842814 -267.678616) (xy 107.850939 -267.729911) (xy 107.851448 -267.755878) (xy 107.850939 -267.781845)
			(xy 108.130849 -267.781845) (xy 108.130849 -267.729911) (xy 108.138974 -267.678616) (xy 108.155022 -267.629223)
			(xy 108.1786 -267.582949) (xy 108.209126 -267.540933) (xy 108.245849 -267.50421) (xy 108.287865 -267.473684)
			(xy 108.334139 -267.450106) (xy 108.383532 -267.434058) (xy 108.434827 -267.425933) (xy 108.486761 -267.425933)
			(xy 108.538056 -267.434058) (xy 108.587449 -267.450106) (xy 108.633723 -267.473684) (xy 108.675739 -267.50421)
			(xy 108.712462 -267.540933) (xy 108.742988 -267.582949) (xy 108.766566 -267.629223) (xy 108.782614 -267.678616)
			(xy 108.790739 -267.729911) (xy 108.791248 -267.755878) (xy 108.790739 -267.781845) (xy 109.070649 -267.781845)
			(xy 109.070649 -267.729911) (xy 109.078774 -267.678616) (xy 109.094822 -267.629223) (xy 109.1184 -267.582949)
			(xy 109.148926 -267.540933) (xy 109.185649 -267.50421) (xy 109.227665 -267.473684) (xy 109.273939 -267.450106)
			(xy 109.323332 -267.434058) (xy 109.374627 -267.425933) (xy 109.426561 -267.425933) (xy 109.477856 -267.434058)
			(xy 109.527249 -267.450106) (xy 109.573523 -267.473684) (xy 109.615539 -267.50421) (xy 109.652262 -267.540933)
			(xy 109.682788 -267.582949) (xy 109.706366 -267.629223) (xy 109.722414 -267.678616) (xy 109.730539 -267.729911)
			(xy 109.731048 -267.755878) (xy 109.730539 -267.781845) (xy 110.010449 -267.781845) (xy 110.010449 -267.729911)
			(xy 110.018574 -267.678616) (xy 110.034622 -267.629223) (xy 110.0582 -267.582949) (xy 110.088726 -267.540933)
			(xy 110.125449 -267.50421) (xy 110.167465 -267.473684) (xy 110.213739 -267.450106) (xy 110.263132 -267.434058)
			(xy 110.314427 -267.425933) (xy 110.366361 -267.425933) (xy 110.417656 -267.434058) (xy 110.467049 -267.450106)
			(xy 110.513323 -267.473684) (xy 110.555339 -267.50421) (xy 110.592062 -267.540933) (xy 110.622588 -267.582949)
			(xy 110.646166 -267.629223) (xy 110.662214 -267.678616) (xy 110.670339 -267.729911) (xy 110.670848 -267.755878)
			(xy 110.670339 -267.781845) (xy 113.769649 -267.781845) (xy 113.769649 -267.729911) (xy 113.777774 -267.678616)
			(xy 113.793822 -267.629223) (xy 113.8174 -267.582949) (xy 113.847926 -267.540933) (xy 113.884649 -267.50421)
			(xy 113.926665 -267.473684) (xy 113.972939 -267.450106) (xy 114.022332 -267.434058) (xy 114.073627 -267.425933)
			(xy 114.125561 -267.425933) (xy 114.176856 -267.434058) (xy 114.226249 -267.450106) (xy 114.272523 -267.473684)
			(xy 114.314539 -267.50421) (xy 114.351262 -267.540933) (xy 114.381788 -267.582949) (xy 114.405366 -267.629223)
			(xy 114.421414 -267.678616) (xy 114.429539 -267.729911) (xy 114.430048 -267.755878) (xy 114.429539 -267.781845)
			(xy 114.709449 -267.781845) (xy 114.709449 -267.729911) (xy 114.717574 -267.678616) (xy 114.733622 -267.629223)
			(xy 114.7572 -267.582949) (xy 114.787726 -267.540933) (xy 114.824449 -267.50421) (xy 114.866465 -267.473684)
			(xy 114.912739 -267.450106) (xy 114.962132 -267.434058) (xy 115.013427 -267.425933) (xy 115.065361 -267.425933)
			(xy 115.116656 -267.434058) (xy 115.166049 -267.450106) (xy 115.212323 -267.473684) (xy 115.254339 -267.50421)
			(xy 115.291062 -267.540933) (xy 115.321588 -267.582949) (xy 115.345166 -267.629223) (xy 115.361214 -267.678616)
			(xy 115.369339 -267.729911) (xy 115.369848 -267.755878) (xy 115.369339 -267.781845) (xy 115.649249 -267.781845)
			(xy 115.649249 -267.729911) (xy 115.657374 -267.678616) (xy 115.673422 -267.629223) (xy 115.697 -267.582949)
			(xy 115.727526 -267.540933) (xy 115.764249 -267.50421) (xy 115.806265 -267.473684) (xy 115.852539 -267.450106)
			(xy 115.901932 -267.434058) (xy 115.953227 -267.425933) (xy 116.005161 -267.425933) (xy 116.056456 -267.434058)
			(xy 116.105849 -267.450106) (xy 116.152123 -267.473684) (xy 116.194139 -267.50421) (xy 116.230862 -267.540933)
			(xy 116.261388 -267.582949) (xy 116.284966 -267.629223) (xy 116.301014 -267.678616) (xy 116.309139 -267.729911)
			(xy 116.309648 -267.755878) (xy 116.309139 -267.781845) (xy 116.589303 -267.781845) (xy 116.589303 -267.729911)
			(xy 116.597428 -267.678616) (xy 116.613476 -267.629223) (xy 116.637054 -267.582949) (xy 116.66758 -267.540933)
			(xy 116.704303 -267.50421) (xy 116.746319 -267.473684) (xy 116.792593 -267.450106) (xy 116.841986 -267.434058)
			(xy 116.893281 -267.425933) (xy 116.945215 -267.425933) (xy 116.99651 -267.434058) (xy 117.045903 -267.450106)
			(xy 117.092177 -267.473684) (xy 117.134193 -267.50421) (xy 117.170916 -267.540933) (xy 117.201442 -267.582949)
			(xy 117.22502 -267.629223) (xy 117.241068 -267.678616) (xy 117.249193 -267.729911) (xy 117.249702 -267.755878)
			(xy 117.249193 -267.781845) (xy 117.241068 -267.83314) (xy 117.22502 -267.882533) (xy 117.201442 -267.928807)
			(xy 117.170916 -267.970823) (xy 117.134193 -268.007546) (xy 117.092177 -268.038072) (xy 117.045903 -268.06165)
			(xy 116.99651 -268.077698) (xy 116.945215 -268.085823) (xy 116.893281 -268.085823) (xy 116.841986 -268.077698)
			(xy 116.792593 -268.06165) (xy 116.746319 -268.038072) (xy 116.704303 -268.007546) (xy 116.66758 -267.970823)
			(xy 116.637054 -267.928807) (xy 116.613476 -267.882533) (xy 116.597428 -267.83314) (xy 116.589303 -267.781845)
			(xy 116.309139 -267.781845) (xy 116.301014 -267.83314) (xy 116.284966 -267.882533) (xy 116.261388 -267.928807)
			(xy 116.230862 -267.970823) (xy 116.194139 -268.007546) (xy 116.152123 -268.038072) (xy 116.105849 -268.06165)
			(xy 116.056456 -268.077698) (xy 116.005161 -268.085823) (xy 115.953227 -268.085823) (xy 115.901932 -268.077698)
			(xy 115.852539 -268.06165) (xy 115.806265 -268.038072) (xy 115.764249 -268.007546) (xy 115.727526 -267.970823)
			(xy 115.697 -267.928807) (xy 115.673422 -267.882533) (xy 115.657374 -267.83314) (xy 115.649249 -267.781845)
			(xy 115.369339 -267.781845) (xy 115.361214 -267.83314) (xy 115.345166 -267.882533) (xy 115.321588 -267.928807)
			(xy 115.291062 -267.970823) (xy 115.254339 -268.007546) (xy 115.212323 -268.038072) (xy 115.166049 -268.06165)
			(xy 115.116656 -268.077698) (xy 115.065361 -268.085823) (xy 115.013427 -268.085823) (xy 114.962132 -268.077698)
			(xy 114.912739 -268.06165) (xy 114.866465 -268.038072) (xy 114.824449 -268.007546) (xy 114.787726 -267.970823)
			(xy 114.7572 -267.928807) (xy 114.733622 -267.882533) (xy 114.717574 -267.83314) (xy 114.709449 -267.781845)
			(xy 114.429539 -267.781845) (xy 114.421414 -267.83314) (xy 114.405366 -267.882533) (xy 114.381788 -267.928807)
			(xy 114.351262 -267.970823) (xy 114.314539 -268.007546) (xy 114.272523 -268.038072) (xy 114.226249 -268.06165)
			(xy 114.176856 -268.077698) (xy 114.125561 -268.085823) (xy 114.073627 -268.085823) (xy 114.022332 -268.077698)
			(xy 113.972939 -268.06165) (xy 113.926665 -268.038072) (xy 113.884649 -268.007546) (xy 113.847926 -267.970823)
			(xy 113.8174 -267.928807) (xy 113.793822 -267.882533) (xy 113.777774 -267.83314) (xy 113.769649 -267.781845)
			(xy 110.670339 -267.781845) (xy 110.662214 -267.83314) (xy 110.646166 -267.882533) (xy 110.622588 -267.928807)
			(xy 110.592062 -267.970823) (xy 110.555339 -268.007546) (xy 110.513323 -268.038072) (xy 110.467049 -268.06165)
			(xy 110.417656 -268.077698) (xy 110.366361 -268.085823) (xy 110.314427 -268.085823) (xy 110.263132 -268.077698)
			(xy 110.213739 -268.06165) (xy 110.167465 -268.038072) (xy 110.125449 -268.007546) (xy 110.088726 -267.970823)
			(xy 110.0582 -267.928807) (xy 110.034622 -267.882533) (xy 110.018574 -267.83314) (xy 110.010449 -267.781845)
			(xy 109.730539 -267.781845) (xy 109.722414 -267.83314) (xy 109.706366 -267.882533) (xy 109.682788 -267.928807)
			(xy 109.652262 -267.970823) (xy 109.615539 -268.007546) (xy 109.573523 -268.038072) (xy 109.527249 -268.06165)
			(xy 109.477856 -268.077698) (xy 109.426561 -268.085823) (xy 109.374627 -268.085823) (xy 109.323332 -268.077698)
			(xy 109.273939 -268.06165) (xy 109.227665 -268.038072) (xy 109.185649 -268.007546) (xy 109.148926 -267.970823)
			(xy 109.1184 -267.928807) (xy 109.094822 -267.882533) (xy 109.078774 -267.83314) (xy 109.070649 -267.781845)
			(xy 108.790739 -267.781845) (xy 108.782614 -267.83314) (xy 108.766566 -267.882533) (xy 108.742988 -267.928807)
			(xy 108.712462 -267.970823) (xy 108.675739 -268.007546) (xy 108.633723 -268.038072) (xy 108.587449 -268.06165)
			(xy 108.538056 -268.077698) (xy 108.486761 -268.085823) (xy 108.434827 -268.085823) (xy 108.383532 -268.077698)
			(xy 108.334139 -268.06165) (xy 108.287865 -268.038072) (xy 108.245849 -268.007546) (xy 108.209126 -267.970823)
			(xy 108.1786 -267.928807) (xy 108.155022 -267.882533) (xy 108.138974 -267.83314) (xy 108.130849 -267.781845)
			(xy 107.850939 -267.781845) (xy 107.842814 -267.83314) (xy 107.826766 -267.882533) (xy 107.803188 -267.928807)
			(xy 107.772662 -267.970823) (xy 107.735939 -268.007546) (xy 107.693923 -268.038072) (xy 107.647649 -268.06165)
			(xy 107.598256 -268.077698) (xy 107.546961 -268.085823) (xy 107.495027 -268.085823) (xy 107.443732 -268.077698)
			(xy 107.394339 -268.06165) (xy 107.348065 -268.038072) (xy 107.306049 -268.007546) (xy 107.269326 -267.970823)
			(xy 107.2388 -267.928807) (xy 107.215222 -267.882533) (xy 107.199174 -267.83314) (xy 107.191049 -267.781845)
			(xy 106.911139 -267.781845) (xy 106.903014 -267.83314) (xy 106.886966 -267.882533) (xy 106.863388 -267.928807)
			(xy 106.832862 -267.970823) (xy 106.796139 -268.007546) (xy 106.754123 -268.038072) (xy 106.707849 -268.06165)
			(xy 106.658456 -268.077698) (xy 106.607161 -268.085823) (xy 106.555227 -268.085823) (xy 106.503932 -268.077698)
			(xy 106.454539 -268.06165) (xy 106.408265 -268.038072) (xy 106.366249 -268.007546) (xy 106.329526 -267.970823)
			(xy 106.299 -267.928807) (xy 106.275422 -267.882533) (xy 106.259374 -267.83314) (xy 106.251249 -267.781845)
			(xy 105.971339 -267.781845) (xy 105.963214 -267.83314) (xy 105.947166 -267.882533) (xy 105.923588 -267.928807)
			(xy 105.893062 -267.970823) (xy 105.856339 -268.007546) (xy 105.814323 -268.038072) (xy 105.768049 -268.06165)
			(xy 105.718656 -268.077698) (xy 105.667361 -268.085823) (xy 105.615427 -268.085823) (xy 105.564132 -268.077698)
			(xy 105.514739 -268.06165) (xy 105.468465 -268.038072) (xy 105.426449 -268.007546) (xy 105.389726 -267.970823)
			(xy 105.3592 -267.928807) (xy 105.335622 -267.882533) (xy 105.319574 -267.83314) (xy 105.311449 -267.781845)
			(xy 105.031539 -267.781845) (xy 105.023414 -267.83314) (xy 105.007366 -267.882533) (xy 104.983788 -267.928807)
			(xy 104.953262 -267.970823) (xy 104.916539 -268.007546) (xy 104.874523 -268.038072) (xy 104.828249 -268.06165)
			(xy 104.778856 -268.077698) (xy 104.727561 -268.085823) (xy 104.675627 -268.085823) (xy 104.624332 -268.077698)
			(xy 104.574939 -268.06165) (xy 104.528665 -268.038072) (xy 104.486649 -268.007546) (xy 104.449926 -267.970823)
			(xy 104.4194 -267.928807) (xy 104.395822 -267.882533) (xy 104.379774 -267.83314) (xy 104.371649 -267.781845)
			(xy 104.091739 -267.781845) (xy 104.083614 -267.83314) (xy 104.067566 -267.882533) (xy 104.043988 -267.928807)
			(xy 104.013462 -267.970823) (xy 103.976739 -268.007546) (xy 103.934723 -268.038072) (xy 103.888449 -268.06165)
			(xy 103.839056 -268.077698) (xy 103.787761 -268.085823) (xy 103.735827 -268.085823) (xy 103.684532 -268.077698)
			(xy 103.635139 -268.06165) (xy 103.588865 -268.038072) (xy 103.546849 -268.007546) (xy 103.510126 -267.970823)
			(xy 103.4796 -267.928807) (xy 103.456022 -267.882533) (xy 103.439974 -267.83314) (xy 103.431849 -267.781845)
			(xy 103.151993 -267.781845) (xy 103.151993 -267.781871) (xy 103.143867 -267.833174) (xy 103.127816 -267.882575)
			(xy 103.104234 -267.928856) (xy 103.073703 -267.970878) (xy 103.036974 -268.007607) (xy 102.994951 -268.038137)
			(xy 102.948669 -268.061718) (xy 102.899269 -268.077769) (xy 102.847965 -268.085894) (xy 102.821994 -268.086332)
			(xy 102.809498 -268.086203) (xy 102.78458 -268.084293) (xy 102.77221 -268.082522) (xy 102.757688 -268.080806)
			(xy 102.72873 -268.084791) (xy 102.702084 -268.096812) (xy 102.679932 -268.115883) (xy 102.664084 -268.140446)
			(xy 102.655839 -268.16849) (xy 102.65537 -268.183106) (xy 102.65537 -268.437614) (xy 102.658926 -268.446504)
			(xy 102.670069 -268.476074) (xy 102.682089 -268.538102) (xy 102.682802 -268.569694) (xy 102.682154 -268.595661)
			(xy 102.962203 -268.595661) (xy 102.962203 -268.543727) (xy 102.970328 -268.492432) (xy 102.986376 -268.443039)
			(xy 103.009954 -268.396765) (xy 103.04048 -268.354749) (xy 103.077203 -268.318026) (xy 103.119219 -268.2875)
			(xy 103.165493 -268.263922) (xy 103.214886 -268.247874) (xy 103.266181 -268.239749) (xy 103.318115 -268.239749)
			(xy 103.36941 -268.247874) (xy 103.418803 -268.263922) (xy 103.465077 -268.2875) (xy 103.507093 -268.318026)
			(xy 103.543816 -268.354749) (xy 103.574342 -268.396765) (xy 103.59792 -268.443039) (xy 103.613968 -268.492432)
			(xy 103.622093 -268.543727) (xy 103.622602 -268.569694) (xy 103.622093 -268.595661) (xy 103.902003 -268.595661)
			(xy 103.902003 -268.543727) (xy 103.910128 -268.492432) (xy 103.926176 -268.443039) (xy 103.949754 -268.396765)
			(xy 103.98028 -268.354749) (xy 104.017003 -268.318026) (xy 104.059019 -268.2875) (xy 104.105293 -268.263922)
			(xy 104.154686 -268.247874) (xy 104.205981 -268.239749) (xy 104.257915 -268.239749) (xy 104.30921 -268.247874)
			(xy 104.358603 -268.263922) (xy 104.404877 -268.2875) (xy 104.446893 -268.318026) (xy 104.483616 -268.354749)
			(xy 104.514142 -268.396765) (xy 104.53772 -268.443039) (xy 104.553768 -268.492432) (xy 104.561893 -268.543727)
			(xy 104.562402 -268.569694) (xy 104.561893 -268.595661) (xy 104.841803 -268.595661) (xy 104.841803 -268.543727)
			(xy 104.849928 -268.492432) (xy 104.865976 -268.443039) (xy 104.889554 -268.396765) (xy 104.92008 -268.354749)
			(xy 104.956803 -268.318026) (xy 104.998819 -268.2875) (xy 105.045093 -268.263922) (xy 105.094486 -268.247874)
			(xy 105.145781 -268.239749) (xy 105.197715 -268.239749) (xy 105.24901 -268.247874) (xy 105.298403 -268.263922)
			(xy 105.344677 -268.2875) (xy 105.386693 -268.318026) (xy 105.423416 -268.354749) (xy 105.453942 -268.396765)
			(xy 105.47752 -268.443039) (xy 105.493568 -268.492432) (xy 105.501693 -268.543727) (xy 105.502202 -268.569694)
			(xy 105.501693 -268.595661) (xy 105.781603 -268.595661) (xy 105.781603 -268.543727) (xy 105.789728 -268.492432)
			(xy 105.805776 -268.443039) (xy 105.829354 -268.396765) (xy 105.85988 -268.354749) (xy 105.896603 -268.318026)
			(xy 105.938619 -268.2875) (xy 105.984893 -268.263922) (xy 106.034286 -268.247874) (xy 106.085581 -268.239749)
			(xy 106.137515 -268.239749) (xy 106.18881 -268.247874) (xy 106.238203 -268.263922) (xy 106.284477 -268.2875)
			(xy 106.326493 -268.318026) (xy 106.363216 -268.354749) (xy 106.393742 -268.396765) (xy 106.41732 -268.443039)
			(xy 106.433368 -268.492432) (xy 106.441493 -268.543727) (xy 106.442002 -268.569694) (xy 106.441493 -268.595661)
			(xy 106.721403 -268.595661) (xy 106.721403 -268.543727) (xy 106.729528 -268.492432) (xy 106.745576 -268.443039)
			(xy 106.769154 -268.396765) (xy 106.79968 -268.354749) (xy 106.836403 -268.318026) (xy 106.878419 -268.2875)
			(xy 106.924693 -268.263922) (xy 106.974086 -268.247874) (xy 107.025381 -268.239749) (xy 107.077315 -268.239749)
			(xy 107.12861 -268.247874) (xy 107.178003 -268.263922) (xy 107.224277 -268.2875) (xy 107.266293 -268.318026)
			(xy 107.303016 -268.354749) (xy 107.333542 -268.396765) (xy 107.35712 -268.443039) (xy 107.373168 -268.492432)
			(xy 107.381293 -268.543727) (xy 107.381802 -268.569694) (xy 107.381293 -268.595661) (xy 107.661203 -268.595661)
			(xy 107.661203 -268.543727) (xy 107.669328 -268.492432) (xy 107.685376 -268.443039) (xy 107.708954 -268.396765)
			(xy 107.73948 -268.354749) (xy 107.776203 -268.318026) (xy 107.818219 -268.2875) (xy 107.864493 -268.263922)
			(xy 107.913886 -268.247874) (xy 107.965181 -268.239749) (xy 108.017115 -268.239749) (xy 108.06841 -268.247874)
			(xy 108.117803 -268.263922) (xy 108.164077 -268.2875) (xy 108.206093 -268.318026) (xy 108.242816 -268.354749)
			(xy 108.273342 -268.396765) (xy 108.29692 -268.443039) (xy 108.312968 -268.492432) (xy 108.321093 -268.543727)
			(xy 108.321602 -268.569694) (xy 108.321093 -268.595661) (xy 108.600749 -268.595661) (xy 108.600749 -268.543727)
			(xy 108.608874 -268.492432) (xy 108.624922 -268.443039) (xy 108.6485 -268.396765) (xy 108.679026 -268.354749)
			(xy 108.715749 -268.318026) (xy 108.757765 -268.2875) (xy 108.804039 -268.263922) (xy 108.853432 -268.247874)
			(xy 108.904727 -268.239749) (xy 108.956661 -268.239749) (xy 109.007956 -268.247874) (xy 109.057349 -268.263922)
			(xy 109.103623 -268.2875) (xy 109.145639 -268.318026) (xy 109.182362 -268.354749) (xy 109.212888 -268.396765)
			(xy 109.236466 -268.443039) (xy 109.252514 -268.492432) (xy 109.260639 -268.543727) (xy 109.261148 -268.569694)
			(xy 109.260639 -268.595661) (xy 109.540549 -268.595661) (xy 109.540549 -268.543727) (xy 109.548674 -268.492432)
			(xy 109.564722 -268.443039) (xy 109.5883 -268.396765) (xy 109.618826 -268.354749) (xy 109.655549 -268.318026)
			(xy 109.697565 -268.2875) (xy 109.743839 -268.263922) (xy 109.793232 -268.247874) (xy 109.844527 -268.239749)
			(xy 109.896461 -268.239749) (xy 109.947756 -268.247874) (xy 109.997149 -268.263922) (xy 110.043423 -268.2875)
			(xy 110.085439 -268.318026) (xy 110.122162 -268.354749) (xy 110.152688 -268.396765) (xy 110.176266 -268.443039)
			(xy 110.192314 -268.492432) (xy 110.200439 -268.543727) (xy 110.200948 -268.569694) (xy 110.200439 -268.595661)
			(xy 113.299749 -268.595661) (xy 113.299749 -268.543727) (xy 113.307874 -268.492432) (xy 113.323922 -268.443039)
			(xy 113.3475 -268.396765) (xy 113.378026 -268.354749) (xy 113.414749 -268.318026) (xy 113.456765 -268.2875)
			(xy 113.503039 -268.263922) (xy 113.552432 -268.247874) (xy 113.603727 -268.239749) (xy 113.655661 -268.239749)
			(xy 113.706956 -268.247874) (xy 113.756349 -268.263922) (xy 113.802623 -268.2875) (xy 113.844639 -268.318026)
			(xy 113.881362 -268.354749) (xy 113.911888 -268.396765) (xy 113.935466 -268.443039) (xy 113.951514 -268.492432)
			(xy 113.959639 -268.543727) (xy 113.960148 -268.569694) (xy 113.959639 -268.595661) (xy 114.239803 -268.595661)
			(xy 114.239803 -268.543727) (xy 114.247928 -268.492432) (xy 114.263976 -268.443039) (xy 114.287554 -268.396765)
			(xy 114.31808 -268.354749) (xy 114.354803 -268.318026) (xy 114.396819 -268.2875) (xy 114.443093 -268.263922)
			(xy 114.492486 -268.247874) (xy 114.543781 -268.239749) (xy 114.595715 -268.239749) (xy 114.64701 -268.247874)
			(xy 114.696403 -268.263922) (xy 114.742677 -268.2875) (xy 114.784693 -268.318026) (xy 114.821416 -268.354749)
			(xy 114.851942 -268.396765) (xy 114.87552 -268.443039) (xy 114.891568 -268.492432) (xy 114.899693 -268.543727)
			(xy 114.900202 -268.569694) (xy 114.899693 -268.595661) (xy 115.179603 -268.595661) (xy 115.179603 -268.543727)
			(xy 115.187728 -268.492432) (xy 115.203776 -268.443039) (xy 115.227354 -268.396765) (xy 115.25788 -268.354749)
			(xy 115.294603 -268.318026) (xy 115.336619 -268.2875) (xy 115.382893 -268.263922) (xy 115.432286 -268.247874)
			(xy 115.483581 -268.239749) (xy 115.535515 -268.239749) (xy 115.58681 -268.247874) (xy 115.636203 -268.263922)
			(xy 115.682477 -268.2875) (xy 115.724493 -268.318026) (xy 115.761216 -268.354749) (xy 115.791742 -268.396765)
			(xy 115.81532 -268.443039) (xy 115.831368 -268.492432) (xy 115.839493 -268.543727) (xy 115.840002 -268.569694)
			(xy 115.839493 -268.595661) (xy 116.119403 -268.595661) (xy 116.119403 -268.543727) (xy 116.127528 -268.492432)
			(xy 116.143576 -268.443039) (xy 116.167154 -268.396765) (xy 116.19768 -268.354749) (xy 116.234403 -268.318026)
			(xy 116.276419 -268.2875) (xy 116.322693 -268.263922) (xy 116.372086 -268.247874) (xy 116.423381 -268.239749)
			(xy 116.475315 -268.239749) (xy 116.52661 -268.247874) (xy 116.576003 -268.263922) (xy 116.622277 -268.2875)
			(xy 116.664293 -268.318026) (xy 116.701016 -268.354749) (xy 116.731542 -268.396765) (xy 116.75512 -268.443039)
			(xy 116.771168 -268.492432) (xy 116.779293 -268.543727) (xy 116.779802 -268.569694) (xy 116.779293 -268.595661)
			(xy 117.058949 -268.595661) (xy 117.058949 -268.543727) (xy 117.067074 -268.492432) (xy 117.083122 -268.443039)
			(xy 117.1067 -268.396765) (xy 117.137226 -268.354749) (xy 117.173949 -268.318026) (xy 117.215965 -268.2875)
			(xy 117.262239 -268.263922) (xy 117.311632 -268.247874) (xy 117.362927 -268.239749) (xy 117.414861 -268.239749)
			(xy 117.466156 -268.247874) (xy 117.515549 -268.263922) (xy 117.561823 -268.2875) (xy 117.603839 -268.318026)
			(xy 117.640562 -268.354749) (xy 117.671088 -268.396765) (xy 117.694666 -268.443039) (xy 117.710714 -268.492432)
			(xy 117.718839 -268.543727) (xy 117.719348 -268.569694) (xy 117.718839 -268.595661) (xy 117.710714 -268.646956)
			(xy 117.694666 -268.696349) (xy 117.671088 -268.742623) (xy 117.640562 -268.784639) (xy 117.603839 -268.821362)
			(xy 117.561823 -268.851888) (xy 117.515549 -268.875466) (xy 117.466156 -268.891514) (xy 117.414861 -268.899639)
			(xy 117.362927 -268.899639) (xy 117.311632 -268.891514) (xy 117.262239 -268.875466) (xy 117.215965 -268.851888)
			(xy 117.173949 -268.821362) (xy 117.137226 -268.784639) (xy 117.1067 -268.742623) (xy 117.083122 -268.696349)
			(xy 117.067074 -268.646956) (xy 117.058949 -268.595661) (xy 116.779293 -268.595661) (xy 116.771168 -268.646956)
			(xy 116.75512 -268.696349) (xy 116.731542 -268.742623) (xy 116.701016 -268.784639) (xy 116.664293 -268.821362)
			(xy 116.622277 -268.851888) (xy 116.576003 -268.875466) (xy 116.52661 -268.891514) (xy 116.475315 -268.899639)
			(xy 116.423381 -268.899639) (xy 116.372086 -268.891514) (xy 116.322693 -268.875466) (xy 116.276419 -268.851888)
			(xy 116.234403 -268.821362) (xy 116.19768 -268.784639) (xy 116.167154 -268.742623) (xy 116.143576 -268.696349)
			(xy 116.127528 -268.646956) (xy 116.119403 -268.595661) (xy 115.839493 -268.595661) (xy 115.831368 -268.646956)
			(xy 115.81532 -268.696349) (xy 115.791742 -268.742623) (xy 115.761216 -268.784639) (xy 115.724493 -268.821362)
			(xy 115.682477 -268.851888) (xy 115.636203 -268.875466) (xy 115.58681 -268.891514) (xy 115.535515 -268.899639)
			(xy 115.483581 -268.899639) (xy 115.432286 -268.891514) (xy 115.382893 -268.875466) (xy 115.336619 -268.851888)
			(xy 115.294603 -268.821362) (xy 115.25788 -268.784639) (xy 115.227354 -268.742623) (xy 115.203776 -268.696349)
			(xy 115.187728 -268.646956) (xy 115.179603 -268.595661) (xy 114.899693 -268.595661) (xy 114.891568 -268.646956)
			(xy 114.87552 -268.696349) (xy 114.851942 -268.742623) (xy 114.821416 -268.784639) (xy 114.784693 -268.821362)
			(xy 114.742677 -268.851888) (xy 114.696403 -268.875466) (xy 114.64701 -268.891514) (xy 114.595715 -268.899639)
			(xy 114.543781 -268.899639) (xy 114.492486 -268.891514) (xy 114.443093 -268.875466) (xy 114.396819 -268.851888)
			(xy 114.354803 -268.821362) (xy 114.31808 -268.784639) (xy 114.287554 -268.742623) (xy 114.263976 -268.696349)
			(xy 114.247928 -268.646956) (xy 114.239803 -268.595661) (xy 113.959639 -268.595661) (xy 113.951514 -268.646956)
			(xy 113.935466 -268.696349) (xy 113.911888 -268.742623) (xy 113.881362 -268.784639) (xy 113.844639 -268.821362)
			(xy 113.802623 -268.851888) (xy 113.756349 -268.875466) (xy 113.706956 -268.891514) (xy 113.655661 -268.899639)
			(xy 113.603727 -268.899639) (xy 113.552432 -268.891514) (xy 113.503039 -268.875466) (xy 113.456765 -268.851888)
			(xy 113.414749 -268.821362) (xy 113.378026 -268.784639) (xy 113.3475 -268.742623) (xy 113.323922 -268.696349)
			(xy 113.307874 -268.646956) (xy 113.299749 -268.595661) (xy 110.200439 -268.595661) (xy 110.192314 -268.646956)
			(xy 110.176266 -268.696349) (xy 110.152688 -268.742623) (xy 110.122162 -268.784639) (xy 110.085439 -268.821362)
			(xy 110.043423 -268.851888) (xy 109.997149 -268.875466) (xy 109.947756 -268.891514) (xy 109.896461 -268.899639)
			(xy 109.844527 -268.899639) (xy 109.793232 -268.891514) (xy 109.743839 -268.875466) (xy 109.697565 -268.851888)
			(xy 109.655549 -268.821362) (xy 109.618826 -268.784639) (xy 109.5883 -268.742623) (xy 109.564722 -268.696349)
			(xy 109.548674 -268.646956) (xy 109.540549 -268.595661) (xy 109.260639 -268.595661) (xy 109.252514 -268.646956)
			(xy 109.236466 -268.696349) (xy 109.212888 -268.742623) (xy 109.182362 -268.784639) (xy 109.145639 -268.821362)
			(xy 109.103623 -268.851888) (xy 109.057349 -268.875466) (xy 109.007956 -268.891514) (xy 108.956661 -268.899639)
			(xy 108.904727 -268.899639) (xy 108.853432 -268.891514) (xy 108.804039 -268.875466) (xy 108.757765 -268.851888)
			(xy 108.715749 -268.821362) (xy 108.679026 -268.784639) (xy 108.6485 -268.742623) (xy 108.624922 -268.696349)
			(xy 108.608874 -268.646956) (xy 108.600749 -268.595661) (xy 108.321093 -268.595661) (xy 108.312968 -268.646956)
			(xy 108.29692 -268.696349) (xy 108.273342 -268.742623) (xy 108.242816 -268.784639) (xy 108.206093 -268.821362)
			(xy 108.164077 -268.851888) (xy 108.117803 -268.875466) (xy 108.06841 -268.891514) (xy 108.017115 -268.899639)
			(xy 107.965181 -268.899639) (xy 107.913886 -268.891514) (xy 107.864493 -268.875466) (xy 107.818219 -268.851888)
			(xy 107.776203 -268.821362) (xy 107.73948 -268.784639) (xy 107.708954 -268.742623) (xy 107.685376 -268.696349)
			(xy 107.669328 -268.646956) (xy 107.661203 -268.595661) (xy 107.381293 -268.595661) (xy 107.373168 -268.646956)
			(xy 107.35712 -268.696349) (xy 107.333542 -268.742623) (xy 107.303016 -268.784639) (xy 107.266293 -268.821362)
			(xy 107.224277 -268.851888) (xy 107.178003 -268.875466) (xy 107.12861 -268.891514) (xy 107.077315 -268.899639)
			(xy 107.025381 -268.899639) (xy 106.974086 -268.891514) (xy 106.924693 -268.875466) (xy 106.878419 -268.851888)
			(xy 106.836403 -268.821362) (xy 106.79968 -268.784639) (xy 106.769154 -268.742623) (xy 106.745576 -268.696349)
			(xy 106.729528 -268.646956) (xy 106.721403 -268.595661) (xy 106.441493 -268.595661) (xy 106.433368 -268.646956)
			(xy 106.41732 -268.696349) (xy 106.393742 -268.742623) (xy 106.363216 -268.784639) (xy 106.326493 -268.821362)
			(xy 106.284477 -268.851888) (xy 106.238203 -268.875466) (xy 106.18881 -268.891514) (xy 106.137515 -268.899639)
			(xy 106.085581 -268.899639) (xy 106.034286 -268.891514) (xy 105.984893 -268.875466) (xy 105.938619 -268.851888)
			(xy 105.896603 -268.821362) (xy 105.85988 -268.784639) (xy 105.829354 -268.742623) (xy 105.805776 -268.696349)
			(xy 105.789728 -268.646956) (xy 105.781603 -268.595661) (xy 105.501693 -268.595661) (xy 105.493568 -268.646956)
			(xy 105.47752 -268.696349) (xy 105.453942 -268.742623) (xy 105.423416 -268.784639) (xy 105.386693 -268.821362)
			(xy 105.344677 -268.851888) (xy 105.298403 -268.875466) (xy 105.24901 -268.891514) (xy 105.197715 -268.899639)
			(xy 105.145781 -268.899639) (xy 105.094486 -268.891514) (xy 105.045093 -268.875466) (xy 104.998819 -268.851888)
			(xy 104.956803 -268.821362) (xy 104.92008 -268.784639) (xy 104.889554 -268.742623) (xy 104.865976 -268.696349)
			(xy 104.849928 -268.646956) (xy 104.841803 -268.595661) (xy 104.561893 -268.595661) (xy 104.553768 -268.646956)
			(xy 104.53772 -268.696349) (xy 104.514142 -268.742623) (xy 104.483616 -268.784639) (xy 104.446893 -268.821362)
			(xy 104.404877 -268.851888) (xy 104.358603 -268.875466) (xy 104.30921 -268.891514) (xy 104.257915 -268.899639)
			(xy 104.205981 -268.899639) (xy 104.154686 -268.891514) (xy 104.105293 -268.875466) (xy 104.059019 -268.851888)
			(xy 104.017003 -268.821362) (xy 103.98028 -268.784639) (xy 103.949754 -268.742623) (xy 103.926176 -268.696349)
			(xy 103.910128 -268.646956) (xy 103.902003 -268.595661) (xy 103.622093 -268.595661) (xy 103.613968 -268.646956)
			(xy 103.59792 -268.696349) (xy 103.574342 -268.742623) (xy 103.543816 -268.784639) (xy 103.507093 -268.821362)
			(xy 103.465077 -268.851888) (xy 103.418803 -268.875466) (xy 103.36941 -268.891514) (xy 103.318115 -268.899639)
			(xy 103.266181 -268.899639) (xy 103.214886 -268.891514) (xy 103.165493 -268.875466) (xy 103.119219 -268.851888)
			(xy 103.077203 -268.821362) (xy 103.04048 -268.784639) (xy 103.009954 -268.742623) (xy 102.986376 -268.696349)
			(xy 102.970328 -268.646956) (xy 102.962203 -268.595661) (xy 102.682154 -268.595661) (xy 102.682014 -268.601277)
			(xy 102.669989 -268.663291) (xy 102.658926 -268.692884) (xy 102.65537 -268.701774) (xy 102.65537 -268.956282)
			(xy 102.655805 -268.970908) (xy 102.664017 -268.998981) (xy 102.679859 -269.023568) (xy 102.702027 -269.04265)
			(xy 102.728698 -269.054656) (xy 102.75768 -269.0586) (xy 102.77221 -269.056866) (xy 102.78458 -269.055092)
			(xy 102.809498 -269.053187) (xy 102.821994 -269.053056) (xy 102.847963 -269.053538) (xy 102.899261 -269.061662)
			(xy 102.948657 -269.077711) (xy 102.994934 -269.10129) (xy 103.036953 -269.131818) (xy 103.073679 -269.168543)
			(xy 103.104207 -269.210561) (xy 103.127786 -269.256837) (xy 103.143836 -269.306233) (xy 103.151961 -269.357531)
			(xy 103.151961 -269.409469) (xy 103.15196 -269.409477) (xy 103.431849 -269.409477) (xy 103.431849 -269.357543)
			(xy 103.439974 -269.306248) (xy 103.456022 -269.256855) (xy 103.4796 -269.210581) (xy 103.510126 -269.168565)
			(xy 103.546849 -269.131842) (xy 103.588865 -269.101316) (xy 103.635139 -269.077738) (xy 103.684532 -269.06169)
			(xy 103.735827 -269.053565) (xy 103.787761 -269.053565) (xy 103.839056 -269.06169) (xy 103.888449 -269.077738)
			(xy 103.934723 -269.101316) (xy 103.976739 -269.131842) (xy 104.013462 -269.168565) (xy 104.043988 -269.210581)
			(xy 104.067566 -269.256855) (xy 104.083614 -269.306248) (xy 104.091739 -269.357543) (xy 104.092248 -269.38351)
			(xy 104.091739 -269.409477) (xy 104.371649 -269.409477) (xy 104.371649 -269.357543) (xy 104.379774 -269.306248)
			(xy 104.395822 -269.256855) (xy 104.4194 -269.210581) (xy 104.449926 -269.168565) (xy 104.486649 -269.131842)
			(xy 104.528665 -269.101316) (xy 104.574939 -269.077738) (xy 104.624332 -269.06169) (xy 104.675627 -269.053565)
			(xy 104.727561 -269.053565) (xy 104.778856 -269.06169) (xy 104.828249 -269.077738) (xy 104.874523 -269.101316)
			(xy 104.916539 -269.131842) (xy 104.953262 -269.168565) (xy 104.983788 -269.210581) (xy 105.007366 -269.256855)
			(xy 105.023414 -269.306248) (xy 105.031539 -269.357543) (xy 105.032048 -269.38351) (xy 105.031539 -269.409477)
			(xy 105.311449 -269.409477) (xy 105.311449 -269.357543) (xy 105.319574 -269.306248) (xy 105.335622 -269.256855)
			(xy 105.3592 -269.210581) (xy 105.389726 -269.168565) (xy 105.426449 -269.131842) (xy 105.468465 -269.101316)
			(xy 105.514739 -269.077738) (xy 105.564132 -269.06169) (xy 105.615427 -269.053565) (xy 105.667361 -269.053565)
			(xy 105.718656 -269.06169) (xy 105.768049 -269.077738) (xy 105.814323 -269.101316) (xy 105.856339 -269.131842)
			(xy 105.893062 -269.168565) (xy 105.923588 -269.210581) (xy 105.947166 -269.256855) (xy 105.963214 -269.306248)
			(xy 105.971339 -269.357543) (xy 105.971848 -269.38351) (xy 105.971339 -269.409477) (xy 106.251249 -269.409477)
			(xy 106.251249 -269.357543) (xy 106.259374 -269.306248) (xy 106.275422 -269.256855) (xy 106.299 -269.210581)
			(xy 106.329526 -269.168565) (xy 106.366249 -269.131842) (xy 106.408265 -269.101316) (xy 106.454539 -269.077738)
			(xy 106.503932 -269.06169) (xy 106.555227 -269.053565) (xy 106.607161 -269.053565) (xy 106.658456 -269.06169)
			(xy 106.707849 -269.077738) (xy 106.754123 -269.101316) (xy 106.796139 -269.131842) (xy 106.832862 -269.168565)
			(xy 106.863388 -269.210581) (xy 106.886966 -269.256855) (xy 106.903014 -269.306248) (xy 106.911139 -269.357543)
			(xy 106.911648 -269.38351) (xy 106.911139 -269.409477) (xy 107.191049 -269.409477) (xy 107.191049 -269.357543)
			(xy 107.199174 -269.306248) (xy 107.215222 -269.256855) (xy 107.2388 -269.210581) (xy 107.269326 -269.168565)
			(xy 107.306049 -269.131842) (xy 107.348065 -269.101316) (xy 107.394339 -269.077738) (xy 107.443732 -269.06169)
			(xy 107.495027 -269.053565) (xy 107.546961 -269.053565) (xy 107.598256 -269.06169) (xy 107.647649 -269.077738)
			(xy 107.693923 -269.101316) (xy 107.735939 -269.131842) (xy 107.772662 -269.168565) (xy 107.803188 -269.210581)
			(xy 107.826766 -269.256855) (xy 107.842814 -269.306248) (xy 107.850939 -269.357543) (xy 107.851448 -269.38351)
			(xy 107.850939 -269.409477) (xy 108.130849 -269.409477) (xy 108.130849 -269.357543) (xy 108.138974 -269.306248)
			(xy 108.155022 -269.256855) (xy 108.1786 -269.210581) (xy 108.209126 -269.168565) (xy 108.245849 -269.131842)
			(xy 108.287865 -269.101316) (xy 108.334139 -269.077738) (xy 108.383532 -269.06169) (xy 108.434827 -269.053565)
			(xy 108.486761 -269.053565) (xy 108.538056 -269.06169) (xy 108.587449 -269.077738) (xy 108.633723 -269.101316)
			(xy 108.675739 -269.131842) (xy 108.712462 -269.168565) (xy 108.742988 -269.210581) (xy 108.766566 -269.256855)
			(xy 108.782614 -269.306248) (xy 108.790739 -269.357543) (xy 108.791248 -269.38351) (xy 108.790739 -269.409477)
			(xy 109.070649 -269.409477) (xy 109.070649 -269.357543) (xy 109.078774 -269.306248) (xy 109.094822 -269.256855)
			(xy 109.1184 -269.210581) (xy 109.148926 -269.168565) (xy 109.185649 -269.131842) (xy 109.227665 -269.101316)
			(xy 109.273939 -269.077738) (xy 109.323332 -269.06169) (xy 109.374627 -269.053565) (xy 109.426561 -269.053565)
			(xy 109.477856 -269.06169) (xy 109.527249 -269.077738) (xy 109.573523 -269.101316) (xy 109.615539 -269.131842)
			(xy 109.652262 -269.168565) (xy 109.682788 -269.210581) (xy 109.706366 -269.256855) (xy 109.722414 -269.306248)
			(xy 109.730539 -269.357543) (xy 109.731048 -269.38351) (xy 109.730539 -269.409477) (xy 110.010449 -269.409477)
			(xy 110.010449 -269.357543) (xy 110.018574 -269.306248) (xy 110.034622 -269.256855) (xy 110.0582 -269.210581)
			(xy 110.088726 -269.168565) (xy 110.125449 -269.131842) (xy 110.167465 -269.101316) (xy 110.213739 -269.077738)
			(xy 110.263132 -269.06169) (xy 110.314427 -269.053565) (xy 110.366361 -269.053565) (xy 110.417656 -269.06169)
			(xy 110.467049 -269.077738) (xy 110.513323 -269.101316) (xy 110.555339 -269.131842) (xy 110.592062 -269.168565)
			(xy 110.622588 -269.210581) (xy 110.646166 -269.256855) (xy 110.662214 -269.306248) (xy 110.670339 -269.357543)
			(xy 110.670848 -269.38351) (xy 110.670339 -269.409477) (xy 113.770157 -269.409477) (xy 113.770157 -269.357543)
			(xy 113.778282 -269.306248) (xy 113.79433 -269.256855) (xy 113.817908 -269.210581) (xy 113.848434 -269.168565)
			(xy 113.885157 -269.131842) (xy 113.927173 -269.101316) (xy 113.973447 -269.077738) (xy 114.02284 -269.06169)
			(xy 114.074135 -269.053565) (xy 114.126069 -269.053565) (xy 114.177364 -269.06169) (xy 114.226757 -269.077738)
			(xy 114.273031 -269.101316) (xy 114.315047 -269.131842) (xy 114.35177 -269.168565) (xy 114.382296 -269.210581)
			(xy 114.405874 -269.256855) (xy 114.421922 -269.306248) (xy 114.430047 -269.357543) (xy 114.430556 -269.38351)
			(xy 114.430047 -269.409477) (xy 114.709449 -269.409477) (xy 114.709449 -269.357543) (xy 114.717574 -269.306248)
			(xy 114.733622 -269.256855) (xy 114.7572 -269.210581) (xy 114.787726 -269.168565) (xy 114.824449 -269.131842)
			(xy 114.866465 -269.101316) (xy 114.912739 -269.077738) (xy 114.962132 -269.06169) (xy 115.013427 -269.053565)
			(xy 115.065361 -269.053565) (xy 115.116656 -269.06169) (xy 115.166049 -269.077738) (xy 115.212323 -269.101316)
			(xy 115.254339 -269.131842) (xy 115.291062 -269.168565) (xy 115.321588 -269.210581) (xy 115.345166 -269.256855)
			(xy 115.361214 -269.306248) (xy 115.369339 -269.357543) (xy 115.369848 -269.38351) (xy 115.369339 -269.409477)
			(xy 115.649249 -269.409477) (xy 115.649249 -269.357543) (xy 115.657374 -269.306248) (xy 115.673422 -269.256855)
			(xy 115.697 -269.210581) (xy 115.727526 -269.168565) (xy 115.764249 -269.131842) (xy 115.806265 -269.101316)
			(xy 115.852539 -269.077738) (xy 115.901932 -269.06169) (xy 115.953227 -269.053565) (xy 116.005161 -269.053565)
			(xy 116.056456 -269.06169) (xy 116.105849 -269.077738) (xy 116.152123 -269.101316) (xy 116.194139 -269.131842)
			(xy 116.230862 -269.168565) (xy 116.261388 -269.210581) (xy 116.284966 -269.256855) (xy 116.301014 -269.306248)
			(xy 116.309139 -269.357543) (xy 116.309648 -269.38351) (xy 116.309139 -269.409477) (xy 116.589049 -269.409477)
			(xy 116.589049 -269.357543) (xy 116.597174 -269.306248) (xy 116.613222 -269.256855) (xy 116.6368 -269.210581)
			(xy 116.667326 -269.168565) (xy 116.704049 -269.131842) (xy 116.746065 -269.101316) (xy 116.792339 -269.077738)
			(xy 116.841732 -269.06169) (xy 116.893027 -269.053565) (xy 116.944961 -269.053565) (xy 116.996256 -269.06169)
			(xy 117.045649 -269.077738) (xy 117.091923 -269.101316) (xy 117.133939 -269.131842) (xy 117.170662 -269.168565)
			(xy 117.201188 -269.210581) (xy 117.224766 -269.256855) (xy 117.240814 -269.306248) (xy 117.248939 -269.357543)
			(xy 117.249448 -269.38351) (xy 117.248939 -269.409477) (xy 117.240814 -269.460772) (xy 117.224766 -269.510165)
			(xy 117.201188 -269.556439) (xy 117.170662 -269.598455) (xy 117.133939 -269.635178) (xy 117.091923 -269.665704)
			(xy 117.045649 -269.689282) (xy 116.996256 -269.70533) (xy 116.944961 -269.713455) (xy 116.893027 -269.713455)
			(xy 116.841732 -269.70533) (xy 116.792339 -269.689282) (xy 116.746065 -269.665704) (xy 116.704049 -269.635178)
			(xy 116.667326 -269.598455) (xy 116.6368 -269.556439) (xy 116.613222 -269.510165) (xy 116.597174 -269.460772)
			(xy 116.589049 -269.409477) (xy 116.309139 -269.409477) (xy 116.301014 -269.460772) (xy 116.284966 -269.510165)
			(xy 116.261388 -269.556439) (xy 116.230862 -269.598455) (xy 116.194139 -269.635178) (xy 116.152123 -269.665704)
			(xy 116.105849 -269.689282) (xy 116.056456 -269.70533) (xy 116.005161 -269.713455) (xy 115.953227 -269.713455)
			(xy 115.901932 -269.70533) (xy 115.852539 -269.689282) (xy 115.806265 -269.665704) (xy 115.764249 -269.635178)
			(xy 115.727526 -269.598455) (xy 115.697 -269.556439) (xy 115.673422 -269.510165) (xy 115.657374 -269.460772)
			(xy 115.649249 -269.409477) (xy 115.369339 -269.409477) (xy 115.361214 -269.460772) (xy 115.345166 -269.510165)
			(xy 115.321588 -269.556439) (xy 115.291062 -269.598455) (xy 115.254339 -269.635178) (xy 115.212323 -269.665704)
			(xy 115.166049 -269.689282) (xy 115.116656 -269.70533) (xy 115.065361 -269.713455) (xy 115.013427 -269.713455)
			(xy 114.962132 -269.70533) (xy 114.912739 -269.689282) (xy 114.866465 -269.665704) (xy 114.824449 -269.635178)
			(xy 114.787726 -269.598455) (xy 114.7572 -269.556439) (xy 114.733622 -269.510165) (xy 114.717574 -269.460772)
			(xy 114.709449 -269.409477) (xy 114.430047 -269.409477) (xy 114.421922 -269.460772) (xy 114.405874 -269.510165)
			(xy 114.382296 -269.556439) (xy 114.35177 -269.598455) (xy 114.315047 -269.635178) (xy 114.273031 -269.665704)
			(xy 114.226757 -269.689282) (xy 114.177364 -269.70533) (xy 114.126069 -269.713455) (xy 114.074135 -269.713455)
			(xy 114.02284 -269.70533) (xy 113.973447 -269.689282) (xy 113.927173 -269.665704) (xy 113.885157 -269.635178)
			(xy 113.848434 -269.598455) (xy 113.817908 -269.556439) (xy 113.79433 -269.510165) (xy 113.778282 -269.460772)
			(xy 113.770157 -269.409477) (xy 110.670339 -269.409477) (xy 110.662214 -269.460772) (xy 110.646166 -269.510165)
			(xy 110.622588 -269.556439) (xy 110.592062 -269.598455) (xy 110.555339 -269.635178) (xy 110.513323 -269.665704)
			(xy 110.467049 -269.689282) (xy 110.417656 -269.70533) (xy 110.366361 -269.713455) (xy 110.314427 -269.713455)
			(xy 110.263132 -269.70533) (xy 110.213739 -269.689282) (xy 110.167465 -269.665704) (xy 110.125449 -269.635178)
			(xy 110.088726 -269.598455) (xy 110.0582 -269.556439) (xy 110.034622 -269.510165) (xy 110.018574 -269.460772)
			(xy 110.010449 -269.409477) (xy 109.730539 -269.409477) (xy 109.722414 -269.460772) (xy 109.706366 -269.510165)
			(xy 109.682788 -269.556439) (xy 109.652262 -269.598455) (xy 109.615539 -269.635178) (xy 109.573523 -269.665704)
			(xy 109.527249 -269.689282) (xy 109.477856 -269.70533) (xy 109.426561 -269.713455) (xy 109.374627 -269.713455)
			(xy 109.323332 -269.70533) (xy 109.273939 -269.689282) (xy 109.227665 -269.665704) (xy 109.185649 -269.635178)
			(xy 109.148926 -269.598455) (xy 109.1184 -269.556439) (xy 109.094822 -269.510165) (xy 109.078774 -269.460772)
			(xy 109.070649 -269.409477) (xy 108.790739 -269.409477) (xy 108.782614 -269.460772) (xy 108.766566 -269.510165)
			(xy 108.742988 -269.556439) (xy 108.712462 -269.598455) (xy 108.675739 -269.635178) (xy 108.633723 -269.665704)
			(xy 108.587449 -269.689282) (xy 108.538056 -269.70533) (xy 108.486761 -269.713455) (xy 108.434827 -269.713455)
			(xy 108.383532 -269.70533) (xy 108.334139 -269.689282) (xy 108.287865 -269.665704) (xy 108.245849 -269.635178)
			(xy 108.209126 -269.598455) (xy 108.1786 -269.556439) (xy 108.155022 -269.510165) (xy 108.138974 -269.460772)
			(xy 108.130849 -269.409477) (xy 107.850939 -269.409477) (xy 107.842814 -269.460772) (xy 107.826766 -269.510165)
			(xy 107.803188 -269.556439) (xy 107.772662 -269.598455) (xy 107.735939 -269.635178) (xy 107.693923 -269.665704)
			(xy 107.647649 -269.689282) (xy 107.598256 -269.70533) (xy 107.546961 -269.713455) (xy 107.495027 -269.713455)
			(xy 107.443732 -269.70533) (xy 107.394339 -269.689282) (xy 107.348065 -269.665704) (xy 107.306049 -269.635178)
			(xy 107.269326 -269.598455) (xy 107.2388 -269.556439) (xy 107.215222 -269.510165) (xy 107.199174 -269.460772)
			(xy 107.191049 -269.409477) (xy 106.911139 -269.409477) (xy 106.903014 -269.460772) (xy 106.886966 -269.510165)
			(xy 106.863388 -269.556439) (xy 106.832862 -269.598455) (xy 106.796139 -269.635178) (xy 106.754123 -269.665704)
			(xy 106.707849 -269.689282) (xy 106.658456 -269.70533) (xy 106.607161 -269.713455) (xy 106.555227 -269.713455)
			(xy 106.503932 -269.70533) (xy 106.454539 -269.689282) (xy 106.408265 -269.665704) (xy 106.366249 -269.635178)
			(xy 106.329526 -269.598455) (xy 106.299 -269.556439) (xy 106.275422 -269.510165) (xy 106.259374 -269.460772)
			(xy 106.251249 -269.409477) (xy 105.971339 -269.409477) (xy 105.963214 -269.460772) (xy 105.947166 -269.510165)
			(xy 105.923588 -269.556439) (xy 105.893062 -269.598455) (xy 105.856339 -269.635178) (xy 105.814323 -269.665704)
			(xy 105.768049 -269.689282) (xy 105.718656 -269.70533) (xy 105.667361 -269.713455) (xy 105.615427 -269.713455)
			(xy 105.564132 -269.70533) (xy 105.514739 -269.689282) (xy 105.468465 -269.665704) (xy 105.426449 -269.635178)
			(xy 105.389726 -269.598455) (xy 105.3592 -269.556439) (xy 105.335622 -269.510165) (xy 105.319574 -269.460772)
			(xy 105.311449 -269.409477) (xy 105.031539 -269.409477) (xy 105.023414 -269.460772) (xy 105.007366 -269.510165)
			(xy 104.983788 -269.556439) (xy 104.953262 -269.598455) (xy 104.916539 -269.635178) (xy 104.874523 -269.665704)
			(xy 104.828249 -269.689282) (xy 104.778856 -269.70533) (xy 104.727561 -269.713455) (xy 104.675627 -269.713455)
			(xy 104.624332 -269.70533) (xy 104.574939 -269.689282) (xy 104.528665 -269.665704) (xy 104.486649 -269.635178)
			(xy 104.449926 -269.598455) (xy 104.4194 -269.556439) (xy 104.395822 -269.510165) (xy 104.379774 -269.460772)
			(xy 104.371649 -269.409477) (xy 104.091739 -269.409477) (xy 104.083614 -269.460772) (xy 104.067566 -269.510165)
			(xy 104.043988 -269.556439) (xy 104.013462 -269.598455) (xy 103.976739 -269.635178) (xy 103.934723 -269.665704)
			(xy 103.888449 -269.689282) (xy 103.839056 -269.70533) (xy 103.787761 -269.713455) (xy 103.735827 -269.713455)
			(xy 103.684532 -269.70533) (xy 103.635139 -269.689282) (xy 103.588865 -269.665704) (xy 103.546849 -269.635178)
			(xy 103.510126 -269.598455) (xy 103.4796 -269.556439) (xy 103.456022 -269.510165) (xy 103.439974 -269.460772)
			(xy 103.431849 -269.409477) (xy 103.15196 -269.409477) (xy 103.143836 -269.460767) (xy 103.127786 -269.510163)
			(xy 103.104207 -269.556439) (xy 103.073679 -269.598457) (xy 103.036953 -269.635182) (xy 102.994934 -269.66571)
			(xy 102.948657 -269.689289) (xy 102.899261 -269.705338) (xy 102.847963 -269.713462) (xy 102.821994 -269.713964)
			(xy 102.809498 -269.713835) (xy 102.78458 -269.711925) (xy 102.77221 -269.710154) (xy 102.757685 -269.708438)
			(xy 102.72872 -269.712424) (xy 102.702067 -269.724442) (xy 102.679904 -269.743512) (xy 102.664043 -269.768073)
			(xy 102.65578 -269.796119) (xy 102.65537 -269.810738) (xy 102.65537 -270.0655) (xy 102.658926 -270.07439)
			(xy 102.67007 -270.10396) (xy 102.682093 -270.165988) (xy 102.682802 -270.19758) (xy 102.682156 -270.223547)
			(xy 102.962203 -270.223547) (xy 102.962203 -270.171613) (xy 102.970328 -270.120318) (xy 102.986376 -270.070925)
			(xy 103.009954 -270.024651) (xy 103.04048 -269.982635) (xy 103.077203 -269.945912) (xy 103.119219 -269.915386)
			(xy 103.165493 -269.891808) (xy 103.214886 -269.87576) (xy 103.266181 -269.867635) (xy 103.318115 -269.867635)
			(xy 103.36941 -269.87576) (xy 103.418803 -269.891808) (xy 103.465077 -269.915386) (xy 103.507093 -269.945912)
			(xy 103.543816 -269.982635) (xy 103.574342 -270.024651) (xy 103.59792 -270.070925) (xy 103.613968 -270.120318)
			(xy 103.622093 -270.171613) (xy 103.622602 -270.19758) (xy 103.622093 -270.223547) (xy 103.902003 -270.223547)
			(xy 103.902003 -270.171613) (xy 103.910128 -270.120318) (xy 103.926176 -270.070925) (xy 103.949754 -270.024651)
			(xy 103.98028 -269.982635) (xy 104.017003 -269.945912) (xy 104.059019 -269.915386) (xy 104.105293 -269.891808)
			(xy 104.154686 -269.87576) (xy 104.205981 -269.867635) (xy 104.257915 -269.867635) (xy 104.30921 -269.87576)
			(xy 104.358603 -269.891808) (xy 104.404877 -269.915386) (xy 104.446893 -269.945912) (xy 104.483616 -269.982635)
			(xy 104.514142 -270.024651) (xy 104.53772 -270.070925) (xy 104.553768 -270.120318) (xy 104.561893 -270.171613)
			(xy 104.562402 -270.19758) (xy 104.561893 -270.223547) (xy 104.841803 -270.223547) (xy 104.841803 -270.171613)
			(xy 104.849928 -270.120318) (xy 104.865976 -270.070925) (xy 104.889554 -270.024651) (xy 104.92008 -269.982635)
			(xy 104.956803 -269.945912) (xy 104.998819 -269.915386) (xy 105.045093 -269.891808) (xy 105.094486 -269.87576)
			(xy 105.145781 -269.867635) (xy 105.197715 -269.867635) (xy 105.24901 -269.87576) (xy 105.298403 -269.891808)
			(xy 105.344677 -269.915386) (xy 105.386693 -269.945912) (xy 105.423416 -269.982635) (xy 105.453942 -270.024651)
			(xy 105.47752 -270.070925) (xy 105.493568 -270.120318) (xy 105.501693 -270.171613) (xy 105.502202 -270.19758)
			(xy 105.501693 -270.223547) (xy 105.781603 -270.223547) (xy 105.781603 -270.171613) (xy 105.789728 -270.120318)
			(xy 105.805776 -270.070925) (xy 105.829354 -270.024651) (xy 105.85988 -269.982635) (xy 105.896603 -269.945912)
			(xy 105.938619 -269.915386) (xy 105.984893 -269.891808) (xy 106.034286 -269.87576) (xy 106.085581 -269.867635)
			(xy 106.137515 -269.867635) (xy 106.18881 -269.87576) (xy 106.238203 -269.891808) (xy 106.284477 -269.915386)
			(xy 106.326493 -269.945912) (xy 106.363216 -269.982635) (xy 106.393742 -270.024651) (xy 106.41732 -270.070925)
			(xy 106.433368 -270.120318) (xy 106.441493 -270.171613) (xy 106.442002 -270.19758) (xy 106.441493 -270.223547)
			(xy 106.721403 -270.223547) (xy 106.721403 -270.171613) (xy 106.729528 -270.120318) (xy 106.745576 -270.070925)
			(xy 106.769154 -270.024651) (xy 106.79968 -269.982635) (xy 106.836403 -269.945912) (xy 106.878419 -269.915386)
			(xy 106.924693 -269.891808) (xy 106.974086 -269.87576) (xy 107.025381 -269.867635) (xy 107.077315 -269.867635)
			(xy 107.12861 -269.87576) (xy 107.178003 -269.891808) (xy 107.224277 -269.915386) (xy 107.266293 -269.945912)
			(xy 107.303016 -269.982635) (xy 107.333542 -270.024651) (xy 107.35712 -270.070925) (xy 107.373168 -270.120318)
			(xy 107.381293 -270.171613) (xy 107.381802 -270.19758) (xy 107.381293 -270.223547) (xy 107.661203 -270.223547)
			(xy 107.661203 -270.171613) (xy 107.669328 -270.120318) (xy 107.685376 -270.070925) (xy 107.708954 -270.024651)
			(xy 107.73948 -269.982635) (xy 107.776203 -269.945912) (xy 107.818219 -269.915386) (xy 107.864493 -269.891808)
			(xy 107.913886 -269.87576) (xy 107.965181 -269.867635) (xy 108.017115 -269.867635) (xy 108.06841 -269.87576)
			(xy 108.117803 -269.891808) (xy 108.164077 -269.915386) (xy 108.206093 -269.945912) (xy 108.242816 -269.982635)
			(xy 108.273342 -270.024651) (xy 108.29692 -270.070925) (xy 108.312968 -270.120318) (xy 108.321093 -270.171613)
			(xy 108.321602 -270.19758) (xy 108.321093 -270.223547) (xy 108.600749 -270.223547) (xy 108.600749 -270.171613)
			(xy 108.608874 -270.120318) (xy 108.624922 -270.070925) (xy 108.6485 -270.024651) (xy 108.679026 -269.982635)
			(xy 108.715749 -269.945912) (xy 108.757765 -269.915386) (xy 108.804039 -269.891808) (xy 108.853432 -269.87576)
			(xy 108.904727 -269.867635) (xy 108.956661 -269.867635) (xy 109.007956 -269.87576) (xy 109.057349 -269.891808)
			(xy 109.103623 -269.915386) (xy 109.145639 -269.945912) (xy 109.182362 -269.982635) (xy 109.212888 -270.024651)
			(xy 109.236466 -270.070925) (xy 109.252514 -270.120318) (xy 109.260639 -270.171613) (xy 109.261148 -270.19758)
			(xy 109.260639 -270.223547) (xy 113.299749 -270.223547) (xy 113.299749 -270.171613) (xy 113.307874 -270.120318)
			(xy 113.323922 -270.070925) (xy 113.3475 -270.024651) (xy 113.378026 -269.982635) (xy 113.414749 -269.945912)
			(xy 113.456765 -269.915386) (xy 113.503039 -269.891808) (xy 113.552432 -269.87576) (xy 113.603727 -269.867635)
			(xy 113.655661 -269.867635) (xy 113.706956 -269.87576) (xy 113.756349 -269.891808) (xy 113.802623 -269.915386)
			(xy 113.844639 -269.945912) (xy 113.881362 -269.982635) (xy 113.911888 -270.024651) (xy 113.935466 -270.070925)
			(xy 113.951514 -270.120318) (xy 113.959639 -270.171613) (xy 113.960148 -270.19758) (xy 113.959639 -270.223547)
			(xy 114.239549 -270.223547) (xy 114.239549 -270.171613) (xy 114.247674 -270.120318) (xy 114.263722 -270.070925)
			(xy 114.2873 -270.024651) (xy 114.317826 -269.982635) (xy 114.354549 -269.945912) (xy 114.396565 -269.915386)
			(xy 114.442839 -269.891808) (xy 114.492232 -269.87576) (xy 114.543527 -269.867635) (xy 114.595461 -269.867635)
			(xy 114.646756 -269.87576) (xy 114.696149 -269.891808) (xy 114.742423 -269.915386) (xy 114.784439 -269.945912)
			(xy 114.821162 -269.982635) (xy 114.851688 -270.024651) (xy 114.875266 -270.070925) (xy 114.891314 -270.120318)
			(xy 114.899439 -270.171613) (xy 114.899948 -270.19758) (xy 114.899439 -270.223547) (xy 115.179349 -270.223547)
			(xy 115.179349 -270.171613) (xy 115.187474 -270.120318) (xy 115.203522 -270.070925) (xy 115.2271 -270.024651)
			(xy 115.257626 -269.982635) (xy 115.294349 -269.945912) (xy 115.336365 -269.915386) (xy 115.382639 -269.891808)
			(xy 115.432032 -269.87576) (xy 115.483327 -269.867635) (xy 115.535261 -269.867635) (xy 115.586556 -269.87576)
			(xy 115.635949 -269.891808) (xy 115.682223 -269.915386) (xy 115.724239 -269.945912) (xy 115.760962 -269.982635)
			(xy 115.791488 -270.024651) (xy 115.815066 -270.070925) (xy 115.831114 -270.120318) (xy 115.839239 -270.171613)
			(xy 115.839748 -270.19758) (xy 115.839239 -270.223547) (xy 116.119403 -270.223547) (xy 116.119403 -270.171613)
			(xy 116.127528 -270.120318) (xy 116.143576 -270.070925) (xy 116.167154 -270.024651) (xy 116.19768 -269.982635)
			(xy 116.234403 -269.945912) (xy 116.276419 -269.915386) (xy 116.322693 -269.891808) (xy 116.372086 -269.87576)
			(xy 116.423381 -269.867635) (xy 116.475315 -269.867635) (xy 116.52661 -269.87576) (xy 116.576003 -269.891808)
			(xy 116.622277 -269.915386) (xy 116.664293 -269.945912) (xy 116.701016 -269.982635) (xy 116.731542 -270.024651)
			(xy 116.75512 -270.070925) (xy 116.771168 -270.120318) (xy 116.779293 -270.171613) (xy 116.779802 -270.19758)
			(xy 116.779293 -270.223547) (xy 117.058949 -270.223547) (xy 117.058949 -270.171613) (xy 117.067074 -270.120318)
			(xy 117.083122 -270.070925) (xy 117.1067 -270.024651) (xy 117.137226 -269.982635) (xy 117.173949 -269.945912)
			(xy 117.215965 -269.915386) (xy 117.262239 -269.891808) (xy 117.311632 -269.87576) (xy 117.362927 -269.867635)
			(xy 117.414861 -269.867635) (xy 117.466156 -269.87576) (xy 117.515549 -269.891808) (xy 117.561823 -269.915386)
			(xy 117.603839 -269.945912) (xy 117.640562 -269.982635) (xy 117.671088 -270.024651) (xy 117.694666 -270.070925)
			(xy 117.710714 -270.120318) (xy 117.718839 -270.171613) (xy 117.719348 -270.19758) (xy 117.718839 -270.223547)
			(xy 117.710714 -270.274842) (xy 117.694666 -270.324235) (xy 117.671088 -270.370509) (xy 117.640562 -270.412525)
			(xy 117.603839 -270.449248) (xy 117.561823 -270.479774) (xy 117.515549 -270.503352) (xy 117.466156 -270.5194)
			(xy 117.414861 -270.527525) (xy 117.362927 -270.527525) (xy 117.311632 -270.5194) (xy 117.262239 -270.503352)
			(xy 117.215965 -270.479774) (xy 117.173949 -270.449248) (xy 117.137226 -270.412525) (xy 117.1067 -270.370509)
			(xy 117.083122 -270.324235) (xy 117.067074 -270.274842) (xy 117.058949 -270.223547) (xy 116.779293 -270.223547)
			(xy 116.771168 -270.274842) (xy 116.75512 -270.324235) (xy 116.731542 -270.370509) (xy 116.701016 -270.412525)
			(xy 116.664293 -270.449248) (xy 116.622277 -270.479774) (xy 116.576003 -270.503352) (xy 116.52661 -270.5194)
			(xy 116.475315 -270.527525) (xy 116.423381 -270.527525) (xy 116.372086 -270.5194) (xy 116.322693 -270.503352)
			(xy 116.276419 -270.479774) (xy 116.234403 -270.449248) (xy 116.19768 -270.412525) (xy 116.167154 -270.370509)
			(xy 116.143576 -270.324235) (xy 116.127528 -270.274842) (xy 116.119403 -270.223547) (xy 115.839239 -270.223547)
			(xy 115.831114 -270.274842) (xy 115.815066 -270.324235) (xy 115.791488 -270.370509) (xy 115.760962 -270.412525)
			(xy 115.724239 -270.449248) (xy 115.682223 -270.479774) (xy 115.635949 -270.503352) (xy 115.586556 -270.5194)
			(xy 115.535261 -270.527525) (xy 115.483327 -270.527525) (xy 115.432032 -270.5194) (xy 115.382639 -270.503352)
			(xy 115.336365 -270.479774) (xy 115.294349 -270.449248) (xy 115.257626 -270.412525) (xy 115.2271 -270.370509)
			(xy 115.203522 -270.324235) (xy 115.187474 -270.274842) (xy 115.179349 -270.223547) (xy 114.899439 -270.223547)
			(xy 114.891314 -270.274842) (xy 114.875266 -270.324235) (xy 114.851688 -270.370509) (xy 114.821162 -270.412525)
			(xy 114.784439 -270.449248) (xy 114.742423 -270.479774) (xy 114.696149 -270.503352) (xy 114.646756 -270.5194)
			(xy 114.595461 -270.527525) (xy 114.543527 -270.527525) (xy 114.492232 -270.5194) (xy 114.442839 -270.503352)
			(xy 114.396565 -270.479774) (xy 114.354549 -270.449248) (xy 114.317826 -270.412525) (xy 114.2873 -270.370509)
			(xy 114.263722 -270.324235) (xy 114.247674 -270.274842) (xy 114.239549 -270.223547) (xy 113.959639 -270.223547)
			(xy 113.951514 -270.274842) (xy 113.935466 -270.324235) (xy 113.911888 -270.370509) (xy 113.881362 -270.412525)
			(xy 113.844639 -270.449248) (xy 113.802623 -270.479774) (xy 113.756349 -270.503352) (xy 113.706956 -270.5194)
			(xy 113.655661 -270.527525) (xy 113.603727 -270.527525) (xy 113.552432 -270.5194) (xy 113.503039 -270.503352)
			(xy 113.456765 -270.479774) (xy 113.414749 -270.449248) (xy 113.378026 -270.412525) (xy 113.3475 -270.370509)
			(xy 113.323922 -270.324235) (xy 113.307874 -270.274842) (xy 113.299749 -270.223547) (xy 109.260639 -270.223547)
			(xy 109.252514 -270.274842) (xy 109.236466 -270.324235) (xy 109.212888 -270.370509) (xy 109.182362 -270.412525)
			(xy 109.145639 -270.449248) (xy 109.103623 -270.479774) (xy 109.057349 -270.503352) (xy 109.007956 -270.5194)
			(xy 108.956661 -270.527525) (xy 108.904727 -270.527525) (xy 108.853432 -270.5194) (xy 108.804039 -270.503352)
			(xy 108.757765 -270.479774) (xy 108.715749 -270.449248) (xy 108.679026 -270.412525) (xy 108.6485 -270.370509)
			(xy 108.624922 -270.324235) (xy 108.608874 -270.274842) (xy 108.600749 -270.223547) (xy 108.321093 -270.223547)
			(xy 108.312968 -270.274842) (xy 108.29692 -270.324235) (xy 108.273342 -270.370509) (xy 108.242816 -270.412525)
			(xy 108.206093 -270.449248) (xy 108.164077 -270.479774) (xy 108.117803 -270.503352) (xy 108.06841 -270.5194)
			(xy 108.017115 -270.527525) (xy 107.965181 -270.527525) (xy 107.913886 -270.5194) (xy 107.864493 -270.503352)
			(xy 107.818219 -270.479774) (xy 107.776203 -270.449248) (xy 107.73948 -270.412525) (xy 107.708954 -270.370509)
			(xy 107.685376 -270.324235) (xy 107.669328 -270.274842) (xy 107.661203 -270.223547) (xy 107.381293 -270.223547)
			(xy 107.373168 -270.274842) (xy 107.35712 -270.324235) (xy 107.333542 -270.370509) (xy 107.303016 -270.412525)
			(xy 107.266293 -270.449248) (xy 107.224277 -270.479774) (xy 107.178003 -270.503352) (xy 107.12861 -270.5194)
			(xy 107.077315 -270.527525) (xy 107.025381 -270.527525) (xy 106.974086 -270.5194) (xy 106.924693 -270.503352)
			(xy 106.878419 -270.479774) (xy 106.836403 -270.449248) (xy 106.79968 -270.412525) (xy 106.769154 -270.370509)
			(xy 106.745576 -270.324235) (xy 106.729528 -270.274842) (xy 106.721403 -270.223547) (xy 106.441493 -270.223547)
			(xy 106.433368 -270.274842) (xy 106.41732 -270.324235) (xy 106.393742 -270.370509) (xy 106.363216 -270.412525)
			(xy 106.326493 -270.449248) (xy 106.284477 -270.479774) (xy 106.238203 -270.503352) (xy 106.18881 -270.5194)
			(xy 106.137515 -270.527525) (xy 106.085581 -270.527525) (xy 106.034286 -270.5194) (xy 105.984893 -270.503352)
			(xy 105.938619 -270.479774) (xy 105.896603 -270.449248) (xy 105.85988 -270.412525) (xy 105.829354 -270.370509)
			(xy 105.805776 -270.324235) (xy 105.789728 -270.274842) (xy 105.781603 -270.223547) (xy 105.501693 -270.223547)
			(xy 105.493568 -270.274842) (xy 105.47752 -270.324235) (xy 105.453942 -270.370509) (xy 105.423416 -270.412525)
			(xy 105.386693 -270.449248) (xy 105.344677 -270.479774) (xy 105.298403 -270.503352) (xy 105.24901 -270.5194)
			(xy 105.197715 -270.527525) (xy 105.145781 -270.527525) (xy 105.094486 -270.5194) (xy 105.045093 -270.503352)
			(xy 104.998819 -270.479774) (xy 104.956803 -270.449248) (xy 104.92008 -270.412525) (xy 104.889554 -270.370509)
			(xy 104.865976 -270.324235) (xy 104.849928 -270.274842) (xy 104.841803 -270.223547) (xy 104.561893 -270.223547)
			(xy 104.553768 -270.274842) (xy 104.53772 -270.324235) (xy 104.514142 -270.370509) (xy 104.483616 -270.412525)
			(xy 104.446893 -270.449248) (xy 104.404877 -270.479774) (xy 104.358603 -270.503352) (xy 104.30921 -270.5194)
			(xy 104.257915 -270.527525) (xy 104.205981 -270.527525) (xy 104.154686 -270.5194) (xy 104.105293 -270.503352)
			(xy 104.059019 -270.479774) (xy 104.017003 -270.449248) (xy 103.98028 -270.412525) (xy 103.949754 -270.370509)
			(xy 103.926176 -270.324235) (xy 103.910128 -270.274842) (xy 103.902003 -270.223547) (xy 103.622093 -270.223547)
			(xy 103.613968 -270.274842) (xy 103.59792 -270.324235) (xy 103.574342 -270.370509) (xy 103.543816 -270.412525)
			(xy 103.507093 -270.449248) (xy 103.465077 -270.479774) (xy 103.418803 -270.503352) (xy 103.36941 -270.5194)
			(xy 103.318115 -270.527525) (xy 103.266181 -270.527525) (xy 103.214886 -270.5194) (xy 103.165493 -270.503352)
			(xy 103.119219 -270.479774) (xy 103.077203 -270.449248) (xy 103.04048 -270.412525) (xy 103.009954 -270.370509)
			(xy 102.986376 -270.324235) (xy 102.970328 -270.274842) (xy 102.962203 -270.223547) (xy 102.682156 -270.223547)
			(xy 102.682016 -270.229164) (xy 102.669993 -270.291178) (xy 102.658926 -270.32077) (xy 102.65537 -270.32966)
			(xy 102.65537 -270.584168) (xy 102.655803 -270.598795) (xy 102.664013 -270.626871) (xy 102.679854 -270.651463)
			(xy 102.702023 -270.670547) (xy 102.728696 -270.682556) (xy 102.757681 -270.6865) (xy 102.77221 -270.684752)
			(xy 102.78458 -270.682978) (xy 102.809498 -270.681073) (xy 102.821994 -270.680942) (xy 102.847964 -270.681424)
			(xy 102.899264 -270.689549) (xy 102.948662 -270.705598) (xy 102.994941 -270.729178) (xy 103.036962 -270.759707)
			(xy 103.073689 -270.796434) (xy 103.104219 -270.838454) (xy 103.127799 -270.884732) (xy 103.14385 -270.93413)
			(xy 103.151975 -270.98543) (xy 103.151975 -271.037363) (xy 103.431849 -271.037363) (xy 103.431849 -270.985429)
			(xy 103.439974 -270.934134) (xy 103.456022 -270.884741) (xy 103.4796 -270.838467) (xy 103.510126 -270.796451)
			(xy 103.546849 -270.759728) (xy 103.588865 -270.729202) (xy 103.635139 -270.705624) (xy 103.684532 -270.689576)
			(xy 103.735827 -270.681451) (xy 103.787761 -270.681451) (xy 103.839056 -270.689576) (xy 103.888449 -270.705624)
			(xy 103.934723 -270.729202) (xy 103.976739 -270.759728) (xy 104.013462 -270.796451) (xy 104.043988 -270.838467)
			(xy 104.067566 -270.884741) (xy 104.083614 -270.934134) (xy 104.091739 -270.985429) (xy 104.092248 -271.011396)
			(xy 104.091739 -271.037363) (xy 104.371649 -271.037363) (xy 104.371649 -270.985429) (xy 104.379774 -270.934134)
			(xy 104.395822 -270.884741) (xy 104.4194 -270.838467) (xy 104.449926 -270.796451) (xy 104.486649 -270.759728)
			(xy 104.528665 -270.729202) (xy 104.574939 -270.705624) (xy 104.624332 -270.689576) (xy 104.675627 -270.681451)
			(xy 104.727561 -270.681451) (xy 104.778856 -270.689576) (xy 104.828249 -270.705624) (xy 104.874523 -270.729202)
			(xy 104.916539 -270.759728) (xy 104.953262 -270.796451) (xy 104.983788 -270.838467) (xy 105.007366 -270.884741)
			(xy 105.023414 -270.934134) (xy 105.031539 -270.985429) (xy 105.032048 -271.011396) (xy 105.031539 -271.037363)
			(xy 105.311449 -271.037363) (xy 105.311449 -270.985429) (xy 105.319574 -270.934134) (xy 105.335622 -270.884741)
			(xy 105.3592 -270.838467) (xy 105.389726 -270.796451) (xy 105.426449 -270.759728) (xy 105.468465 -270.729202)
			(xy 105.514739 -270.705624) (xy 105.564132 -270.689576) (xy 105.615427 -270.681451) (xy 105.667361 -270.681451)
			(xy 105.718656 -270.689576) (xy 105.768049 -270.705624) (xy 105.814323 -270.729202) (xy 105.856339 -270.759728)
			(xy 105.893062 -270.796451) (xy 105.923588 -270.838467) (xy 105.947166 -270.884741) (xy 105.963214 -270.934134)
			(xy 105.971339 -270.985429) (xy 105.971848 -271.011396) (xy 105.971339 -271.037363) (xy 106.251249 -271.037363)
			(xy 106.251249 -270.985429) (xy 106.259374 -270.934134) (xy 106.275422 -270.884741) (xy 106.299 -270.838467)
			(xy 106.329526 -270.796451) (xy 106.366249 -270.759728) (xy 106.408265 -270.729202) (xy 106.454539 -270.705624)
			(xy 106.503932 -270.689576) (xy 106.555227 -270.681451) (xy 106.607161 -270.681451) (xy 106.658456 -270.689576)
			(xy 106.707849 -270.705624) (xy 106.754123 -270.729202) (xy 106.796139 -270.759728) (xy 106.832862 -270.796451)
			(xy 106.863388 -270.838467) (xy 106.886966 -270.884741) (xy 106.903014 -270.934134) (xy 106.911139 -270.985429)
			(xy 106.911648 -271.011396) (xy 106.911139 -271.037363) (xy 107.191049 -271.037363) (xy 107.191049 -270.985429)
			(xy 107.199174 -270.934134) (xy 107.215222 -270.884741) (xy 107.2388 -270.838467) (xy 107.269326 -270.796451)
			(xy 107.306049 -270.759728) (xy 107.348065 -270.729202) (xy 107.394339 -270.705624) (xy 107.443732 -270.689576)
			(xy 107.495027 -270.681451) (xy 107.546961 -270.681451) (xy 107.598256 -270.689576) (xy 107.647649 -270.705624)
			(xy 107.693923 -270.729202) (xy 107.735939 -270.759728) (xy 107.772662 -270.796451) (xy 107.803188 -270.838467)
			(xy 107.826766 -270.884741) (xy 107.842814 -270.934134) (xy 107.850939 -270.985429) (xy 107.851448 -271.011396)
			(xy 107.850939 -271.037363) (xy 108.130849 -271.037363) (xy 108.130849 -270.985429) (xy 108.138974 -270.934134)
			(xy 108.155022 -270.884741) (xy 108.1786 -270.838467) (xy 108.209126 -270.796451) (xy 108.245849 -270.759728)
			(xy 108.287865 -270.729202) (xy 108.334139 -270.705624) (xy 108.383532 -270.689576) (xy 108.434827 -270.681451)
			(xy 108.486761 -270.681451) (xy 108.538056 -270.689576) (xy 108.587449 -270.705624) (xy 108.633723 -270.729202)
			(xy 108.675739 -270.759728) (xy 108.712462 -270.796451) (xy 108.742988 -270.838467) (xy 108.766566 -270.884741)
			(xy 108.782614 -270.934134) (xy 108.790739 -270.985429) (xy 108.791248 -271.011396) (xy 108.790739 -271.037363)
			(xy 109.070649 -271.037363) (xy 109.070649 -270.985429) (xy 109.078774 -270.934134) (xy 109.094822 -270.884741)
			(xy 109.1184 -270.838467) (xy 109.148926 -270.796451) (xy 109.185649 -270.759728) (xy 109.227665 -270.729202)
			(xy 109.273939 -270.705624) (xy 109.323332 -270.689576) (xy 109.374627 -270.681451) (xy 109.426561 -270.681451)
			(xy 109.477856 -270.689576) (xy 109.527249 -270.705624) (xy 109.573523 -270.729202) (xy 109.615539 -270.759728)
			(xy 109.652262 -270.796451) (xy 109.682788 -270.838467) (xy 109.706366 -270.884741) (xy 109.722414 -270.934134)
			(xy 109.730539 -270.985429) (xy 109.731048 -271.011396) (xy 109.730539 -271.037363) (xy 110.010449 -271.037363)
			(xy 110.010449 -270.985429) (xy 110.018574 -270.934134) (xy 110.034622 -270.884741) (xy 110.0582 -270.838467)
			(xy 110.088726 -270.796451) (xy 110.125449 -270.759728) (xy 110.167465 -270.729202) (xy 110.213739 -270.705624)
			(xy 110.263132 -270.689576) (xy 110.314427 -270.681451) (xy 110.366361 -270.681451) (xy 110.417656 -270.689576)
			(xy 110.467049 -270.705624) (xy 110.513323 -270.729202) (xy 110.555339 -270.759728) (xy 110.592062 -270.796451)
			(xy 110.622588 -270.838467) (xy 110.646166 -270.884741) (xy 110.662214 -270.934134) (xy 110.670339 -270.985429)
			(xy 110.670848 -271.011396) (xy 110.670339 -271.037363) (xy 113.769649 -271.037363) (xy 113.769649 -270.985429)
			(xy 113.777774 -270.934134) (xy 113.793822 -270.884741) (xy 113.8174 -270.838467) (xy 113.847926 -270.796451)
			(xy 113.884649 -270.759728) (xy 113.926665 -270.729202) (xy 113.972939 -270.705624) (xy 114.022332 -270.689576)
			(xy 114.073627 -270.681451) (xy 114.125561 -270.681451) (xy 114.176856 -270.689576) (xy 114.226249 -270.705624)
			(xy 114.272523 -270.729202) (xy 114.314539 -270.759728) (xy 114.351262 -270.796451) (xy 114.381788 -270.838467)
			(xy 114.405366 -270.884741) (xy 114.421414 -270.934134) (xy 114.429539 -270.985429) (xy 114.430048 -271.011396)
			(xy 114.429539 -271.037363) (xy 114.709449 -271.037363) (xy 114.709449 -270.985429) (xy 114.717574 -270.934134)
			(xy 114.733622 -270.884741) (xy 114.7572 -270.838467) (xy 114.787726 -270.796451) (xy 114.824449 -270.759728)
			(xy 114.866465 -270.729202) (xy 114.912739 -270.705624) (xy 114.962132 -270.689576) (xy 115.013427 -270.681451)
			(xy 115.065361 -270.681451) (xy 115.116656 -270.689576) (xy 115.166049 -270.705624) (xy 115.212323 -270.729202)
			(xy 115.254339 -270.759728) (xy 115.291062 -270.796451) (xy 115.321588 -270.838467) (xy 115.345166 -270.884741)
			(xy 115.361214 -270.934134) (xy 115.369339 -270.985429) (xy 115.369848 -271.011396) (xy 115.369339 -271.037363)
			(xy 115.649249 -271.037363) (xy 115.649249 -270.985429) (xy 115.657374 -270.934134) (xy 115.673422 -270.884741)
			(xy 115.697 -270.838467) (xy 115.727526 -270.796451) (xy 115.764249 -270.759728) (xy 115.806265 -270.729202)
			(xy 115.852539 -270.705624) (xy 115.901932 -270.689576) (xy 115.953227 -270.681451) (xy 116.005161 -270.681451)
			(xy 116.056456 -270.689576) (xy 116.105849 -270.705624) (xy 116.152123 -270.729202) (xy 116.194139 -270.759728)
			(xy 116.230862 -270.796451) (xy 116.261388 -270.838467) (xy 116.284966 -270.884741) (xy 116.301014 -270.934134)
			(xy 116.309139 -270.985429) (xy 116.309648 -271.011396) (xy 116.309139 -271.037363) (xy 116.589049 -271.037363)
			(xy 116.589049 -270.985429) (xy 116.597174 -270.934134) (xy 116.613222 -270.884741) (xy 116.6368 -270.838467)
			(xy 116.667326 -270.796451) (xy 116.704049 -270.759728) (xy 116.746065 -270.729202) (xy 116.792339 -270.705624)
			(xy 116.841732 -270.689576) (xy 116.893027 -270.681451) (xy 116.944961 -270.681451) (xy 116.996256 -270.689576)
			(xy 117.045649 -270.705624) (xy 117.091923 -270.729202) (xy 117.133939 -270.759728) (xy 117.170662 -270.796451)
			(xy 117.201188 -270.838467) (xy 117.224766 -270.884741) (xy 117.240814 -270.934134) (xy 117.248939 -270.985429)
			(xy 117.249448 -271.011396) (xy 117.248939 -271.037363) (xy 117.240814 -271.088658) (xy 117.224766 -271.138051)
			(xy 117.201188 -271.184325) (xy 117.170662 -271.226341) (xy 117.133939 -271.263064) (xy 117.091923 -271.29359)
			(xy 117.045649 -271.317168) (xy 116.996256 -271.333216) (xy 116.944961 -271.341341) (xy 116.893027 -271.341341)
			(xy 116.841732 -271.333216) (xy 116.792339 -271.317168) (xy 116.746065 -271.29359) (xy 116.704049 -271.263064)
			(xy 116.667326 -271.226341) (xy 116.6368 -271.184325) (xy 116.613222 -271.138051) (xy 116.597174 -271.088658)
			(xy 116.589049 -271.037363) (xy 116.309139 -271.037363) (xy 116.301014 -271.088658) (xy 116.284966 -271.138051)
			(xy 116.261388 -271.184325) (xy 116.230862 -271.226341) (xy 116.194139 -271.263064) (xy 116.152123 -271.29359)
			(xy 116.105849 -271.317168) (xy 116.056456 -271.333216) (xy 116.005161 -271.341341) (xy 115.953227 -271.341341)
			(xy 115.901932 -271.333216) (xy 115.852539 -271.317168) (xy 115.806265 -271.29359) (xy 115.764249 -271.263064)
			(xy 115.727526 -271.226341) (xy 115.697 -271.184325) (xy 115.673422 -271.138051) (xy 115.657374 -271.088658)
			(xy 115.649249 -271.037363) (xy 115.369339 -271.037363) (xy 115.361214 -271.088658) (xy 115.345166 -271.138051)
			(xy 115.321588 -271.184325) (xy 115.291062 -271.226341) (xy 115.254339 -271.263064) (xy 115.212323 -271.29359)
			(xy 115.166049 -271.317168) (xy 115.116656 -271.333216) (xy 115.065361 -271.341341) (xy 115.013427 -271.341341)
			(xy 114.962132 -271.333216) (xy 114.912739 -271.317168) (xy 114.866465 -271.29359) (xy 114.824449 -271.263064)
			(xy 114.787726 -271.226341) (xy 114.7572 -271.184325) (xy 114.733622 -271.138051) (xy 114.717574 -271.088658)
			(xy 114.709449 -271.037363) (xy 114.429539 -271.037363) (xy 114.421414 -271.088658) (xy 114.405366 -271.138051)
			(xy 114.381788 -271.184325) (xy 114.351262 -271.226341) (xy 114.314539 -271.263064) (xy 114.272523 -271.29359)
			(xy 114.226249 -271.317168) (xy 114.176856 -271.333216) (xy 114.125561 -271.341341) (xy 114.073627 -271.341341)
			(xy 114.022332 -271.333216) (xy 113.972939 -271.317168) (xy 113.926665 -271.29359) (xy 113.884649 -271.263064)
			(xy 113.847926 -271.226341) (xy 113.8174 -271.184325) (xy 113.793822 -271.138051) (xy 113.777774 -271.088658)
			(xy 113.769649 -271.037363) (xy 110.670339 -271.037363) (xy 110.662214 -271.088658) (xy 110.646166 -271.138051)
			(xy 110.622588 -271.184325) (xy 110.592062 -271.226341) (xy 110.555339 -271.263064) (xy 110.513323 -271.29359)
			(xy 110.467049 -271.317168) (xy 110.417656 -271.333216) (xy 110.366361 -271.341341) (xy 110.314427 -271.341341)
			(xy 110.263132 -271.333216) (xy 110.213739 -271.317168) (xy 110.167465 -271.29359) (xy 110.125449 -271.263064)
			(xy 110.088726 -271.226341) (xy 110.0582 -271.184325) (xy 110.034622 -271.138051) (xy 110.018574 -271.088658)
			(xy 110.010449 -271.037363) (xy 109.730539 -271.037363) (xy 109.722414 -271.088658) (xy 109.706366 -271.138051)
			(xy 109.682788 -271.184325) (xy 109.652262 -271.226341) (xy 109.615539 -271.263064) (xy 109.573523 -271.29359)
			(xy 109.527249 -271.317168) (xy 109.477856 -271.333216) (xy 109.426561 -271.341341) (xy 109.374627 -271.341341)
			(xy 109.323332 -271.333216) (xy 109.273939 -271.317168) (xy 109.227665 -271.29359) (xy 109.185649 -271.263064)
			(xy 109.148926 -271.226341) (xy 109.1184 -271.184325) (xy 109.094822 -271.138051) (xy 109.078774 -271.088658)
			(xy 109.070649 -271.037363) (xy 108.790739 -271.037363) (xy 108.782614 -271.088658) (xy 108.766566 -271.138051)
			(xy 108.742988 -271.184325) (xy 108.712462 -271.226341) (xy 108.675739 -271.263064) (xy 108.633723 -271.29359)
			(xy 108.587449 -271.317168) (xy 108.538056 -271.333216) (xy 108.486761 -271.341341) (xy 108.434827 -271.341341)
			(xy 108.383532 -271.333216) (xy 108.334139 -271.317168) (xy 108.287865 -271.29359) (xy 108.245849 -271.263064)
			(xy 108.209126 -271.226341) (xy 108.1786 -271.184325) (xy 108.155022 -271.138051) (xy 108.138974 -271.088658)
			(xy 108.130849 -271.037363) (xy 107.850939 -271.037363) (xy 107.842814 -271.088658) (xy 107.826766 -271.138051)
			(xy 107.803188 -271.184325) (xy 107.772662 -271.226341) (xy 107.735939 -271.263064) (xy 107.693923 -271.29359)
			(xy 107.647649 -271.317168) (xy 107.598256 -271.333216) (xy 107.546961 -271.341341) (xy 107.495027 -271.341341)
			(xy 107.443732 -271.333216) (xy 107.394339 -271.317168) (xy 107.348065 -271.29359) (xy 107.306049 -271.263064)
			(xy 107.269326 -271.226341) (xy 107.2388 -271.184325) (xy 107.215222 -271.138051) (xy 107.199174 -271.088658)
			(xy 107.191049 -271.037363) (xy 106.911139 -271.037363) (xy 106.903014 -271.088658) (xy 106.886966 -271.138051)
			(xy 106.863388 -271.184325) (xy 106.832862 -271.226341) (xy 106.796139 -271.263064) (xy 106.754123 -271.29359)
			(xy 106.707849 -271.317168) (xy 106.658456 -271.333216) (xy 106.607161 -271.341341) (xy 106.555227 -271.341341)
			(xy 106.503932 -271.333216) (xy 106.454539 -271.317168) (xy 106.408265 -271.29359) (xy 106.366249 -271.263064)
			(xy 106.329526 -271.226341) (xy 106.299 -271.184325) (xy 106.275422 -271.138051) (xy 106.259374 -271.088658)
			(xy 106.251249 -271.037363) (xy 105.971339 -271.037363) (xy 105.963214 -271.088658) (xy 105.947166 -271.138051)
			(xy 105.923588 -271.184325) (xy 105.893062 -271.226341) (xy 105.856339 -271.263064) (xy 105.814323 -271.29359)
			(xy 105.768049 -271.317168) (xy 105.718656 -271.333216) (xy 105.667361 -271.341341) (xy 105.615427 -271.341341)
			(xy 105.564132 -271.333216) (xy 105.514739 -271.317168) (xy 105.468465 -271.29359) (xy 105.426449 -271.263064)
			(xy 105.389726 -271.226341) (xy 105.3592 -271.184325) (xy 105.335622 -271.138051) (xy 105.319574 -271.088658)
			(xy 105.311449 -271.037363) (xy 105.031539 -271.037363) (xy 105.023414 -271.088658) (xy 105.007366 -271.138051)
			(xy 104.983788 -271.184325) (xy 104.953262 -271.226341) (xy 104.916539 -271.263064) (xy 104.874523 -271.29359)
			(xy 104.828249 -271.317168) (xy 104.778856 -271.333216) (xy 104.727561 -271.341341) (xy 104.675627 -271.341341)
			(xy 104.624332 -271.333216) (xy 104.574939 -271.317168) (xy 104.528665 -271.29359) (xy 104.486649 -271.263064)
			(xy 104.449926 -271.226341) (xy 104.4194 -271.184325) (xy 104.395822 -271.138051) (xy 104.379774 -271.088658)
			(xy 104.371649 -271.037363) (xy 104.091739 -271.037363) (xy 104.083614 -271.088658) (xy 104.067566 -271.138051)
			(xy 104.043988 -271.184325) (xy 104.013462 -271.226341) (xy 103.976739 -271.263064) (xy 103.934723 -271.29359)
			(xy 103.888449 -271.317168) (xy 103.839056 -271.333216) (xy 103.787761 -271.341341) (xy 103.735827 -271.341341)
			(xy 103.684532 -271.333216) (xy 103.635139 -271.317168) (xy 103.588865 -271.29359) (xy 103.546849 -271.263064)
			(xy 103.510126 -271.226341) (xy 103.4796 -271.184325) (xy 103.456022 -271.138051) (xy 103.439974 -271.088658)
			(xy 103.431849 -271.037363) (xy 103.151975 -271.037363) (xy 103.151975 -271.03737) (xy 103.14385 -271.08867)
			(xy 103.127799 -271.138068) (xy 103.104219 -271.184346) (xy 103.073689 -271.226366) (xy 103.036962 -271.263093)
			(xy 102.994941 -271.293622) (xy 102.948662 -271.317202) (xy 102.899264 -271.333251) (xy 102.847964 -271.341376)
			(xy 102.821994 -271.34185) (xy 102.809498 -271.341721) (xy 102.78458 -271.339811) (xy 102.77221 -271.33804)
			(xy 102.757684 -271.336324) (xy 102.728718 -271.34031) (xy 102.702063 -271.352328) (xy 102.679898 -271.371397)
			(xy 102.664035 -271.395958) (xy 102.655769 -271.424004) (xy 102.65537 -271.438624) (xy 102.65537 -271.693132)
			(xy 102.658926 -271.702022) (xy 102.670067 -271.731592) (xy 102.682084 -271.793621) (xy 102.682802 -271.825212)
			(xy 102.682153 -271.851179) (xy 102.962203 -271.851179) (xy 102.962203 -271.799245) (xy 102.970328 -271.74795)
			(xy 102.986376 -271.698557) (xy 103.009954 -271.652283) (xy 103.04048 -271.610267) (xy 103.077203 -271.573544)
			(xy 103.119219 -271.543018) (xy 103.165493 -271.51944) (xy 103.214886 -271.503392) (xy 103.266181 -271.495267)
			(xy 103.318115 -271.495267) (xy 103.36941 -271.503392) (xy 103.418803 -271.51944) (xy 103.465077 -271.543018)
			(xy 103.507093 -271.573544) (xy 103.543816 -271.610267) (xy 103.574342 -271.652283) (xy 103.59792 -271.698557)
			(xy 103.613968 -271.74795) (xy 103.622093 -271.799245) (xy 103.622602 -271.825212) (xy 103.622093 -271.851179)
			(xy 103.902003 -271.851179) (xy 103.902003 -271.799245) (xy 103.910128 -271.74795) (xy 103.926176 -271.698557)
			(xy 103.949754 -271.652283) (xy 103.98028 -271.610267) (xy 104.017003 -271.573544) (xy 104.059019 -271.543018)
			(xy 104.105293 -271.51944) (xy 104.154686 -271.503392) (xy 104.205981 -271.495267) (xy 104.257915 -271.495267)
			(xy 104.30921 -271.503392) (xy 104.358603 -271.51944) (xy 104.404877 -271.543018) (xy 104.446893 -271.573544)
			(xy 104.483616 -271.610267) (xy 104.514142 -271.652283) (xy 104.53772 -271.698557) (xy 104.553768 -271.74795)
			(xy 104.561893 -271.799245) (xy 104.562402 -271.825212) (xy 104.561893 -271.851179) (xy 104.841803 -271.851179)
			(xy 104.841803 -271.799245) (xy 104.849928 -271.74795) (xy 104.865976 -271.698557) (xy 104.889554 -271.652283)
			(xy 104.92008 -271.610267) (xy 104.956803 -271.573544) (xy 104.998819 -271.543018) (xy 105.045093 -271.51944)
			(xy 105.094486 -271.503392) (xy 105.145781 -271.495267) (xy 105.197715 -271.495267) (xy 105.24901 -271.503392)
			(xy 105.298403 -271.51944) (xy 105.344677 -271.543018) (xy 105.386693 -271.573544) (xy 105.423416 -271.610267)
			(xy 105.453942 -271.652283) (xy 105.47752 -271.698557) (xy 105.493568 -271.74795) (xy 105.501693 -271.799245)
			(xy 105.502202 -271.825212) (xy 105.501693 -271.851179) (xy 105.781603 -271.851179) (xy 105.781603 -271.799245)
			(xy 105.789728 -271.74795) (xy 105.805776 -271.698557) (xy 105.829354 -271.652283) (xy 105.85988 -271.610267)
			(xy 105.896603 -271.573544) (xy 105.938619 -271.543018) (xy 105.984893 -271.51944) (xy 106.034286 -271.503392)
			(xy 106.085581 -271.495267) (xy 106.137515 -271.495267) (xy 106.18881 -271.503392) (xy 106.238203 -271.51944)
			(xy 106.284477 -271.543018) (xy 106.326493 -271.573544) (xy 106.363216 -271.610267) (xy 106.393742 -271.652283)
			(xy 106.41732 -271.698557) (xy 106.433368 -271.74795) (xy 106.441493 -271.799245) (xy 106.442002 -271.825212)
			(xy 106.441493 -271.851179) (xy 106.721403 -271.851179) (xy 106.721403 -271.799245) (xy 106.729528 -271.74795)
			(xy 106.745576 -271.698557) (xy 106.769154 -271.652283) (xy 106.79968 -271.610267) (xy 106.836403 -271.573544)
			(xy 106.878419 -271.543018) (xy 106.924693 -271.51944) (xy 106.974086 -271.503392) (xy 107.025381 -271.495267)
			(xy 107.077315 -271.495267) (xy 107.12861 -271.503392) (xy 107.178003 -271.51944) (xy 107.224277 -271.543018)
			(xy 107.266293 -271.573544) (xy 107.303016 -271.610267) (xy 107.333542 -271.652283) (xy 107.35712 -271.698557)
			(xy 107.373168 -271.74795) (xy 107.381293 -271.799245) (xy 107.381802 -271.825212) (xy 107.381293 -271.851179)
			(xy 107.661203 -271.851179) (xy 107.661203 -271.799245) (xy 107.669328 -271.74795) (xy 107.685376 -271.698557)
			(xy 107.708954 -271.652283) (xy 107.73948 -271.610267) (xy 107.776203 -271.573544) (xy 107.818219 -271.543018)
			(xy 107.864493 -271.51944) (xy 107.913886 -271.503392) (xy 107.965181 -271.495267) (xy 108.017115 -271.495267)
			(xy 108.06841 -271.503392) (xy 108.117803 -271.51944) (xy 108.164077 -271.543018) (xy 108.206093 -271.573544)
			(xy 108.242816 -271.610267) (xy 108.273342 -271.652283) (xy 108.29692 -271.698557) (xy 108.312968 -271.74795)
			(xy 108.321093 -271.799245) (xy 108.321602 -271.825212) (xy 108.321093 -271.851179) (xy 108.601003 -271.851179)
			(xy 108.601003 -271.799245) (xy 108.609128 -271.74795) (xy 108.625176 -271.698557) (xy 108.648754 -271.652283)
			(xy 108.67928 -271.610267) (xy 108.716003 -271.573544) (xy 108.758019 -271.543018) (xy 108.804293 -271.51944)
			(xy 108.853686 -271.503392) (xy 108.904981 -271.495267) (xy 108.956915 -271.495267) (xy 109.00821 -271.503392)
			(xy 109.057603 -271.51944) (xy 109.103877 -271.543018) (xy 109.145893 -271.573544) (xy 109.182616 -271.610267)
			(xy 109.213142 -271.652283) (xy 109.23672 -271.698557) (xy 109.252768 -271.74795) (xy 109.260893 -271.799245)
			(xy 109.261402 -271.825212) (xy 109.260893 -271.851179) (xy 109.540295 -271.851179) (xy 109.540295 -271.799245)
			(xy 109.54842 -271.74795) (xy 109.564468 -271.698557) (xy 109.588046 -271.652283) (xy 109.618572 -271.610267)
			(xy 109.655295 -271.573544) (xy 109.697311 -271.543018) (xy 109.743585 -271.51944) (xy 109.792978 -271.503392)
			(xy 109.844273 -271.495267) (xy 109.896207 -271.495267) (xy 109.947502 -271.503392) (xy 109.996895 -271.51944)
			(xy 110.043169 -271.543018) (xy 110.085185 -271.573544) (xy 110.121908 -271.610267) (xy 110.152434 -271.652283)
			(xy 110.176012 -271.698557) (xy 110.19206 -271.74795) (xy 110.200185 -271.799245) (xy 110.200694 -271.825212)
			(xy 110.200185 -271.851179) (xy 113.299749 -271.851179) (xy 113.299749 -271.799245) (xy 113.307874 -271.74795)
			(xy 113.323922 -271.698557) (xy 113.3475 -271.652283) (xy 113.378026 -271.610267) (xy 113.414749 -271.573544)
			(xy 113.456765 -271.543018) (xy 113.503039 -271.51944) (xy 113.552432 -271.503392) (xy 113.603727 -271.495267)
			(xy 113.655661 -271.495267) (xy 113.706956 -271.503392) (xy 113.756349 -271.51944) (xy 113.802623 -271.543018)
			(xy 113.844639 -271.573544) (xy 113.881362 -271.610267) (xy 113.911888 -271.652283) (xy 113.935466 -271.698557)
			(xy 113.951514 -271.74795) (xy 113.959639 -271.799245) (xy 113.960148 -271.825212) (xy 113.959639 -271.851179)
			(xy 114.239803 -271.851179) (xy 114.239803 -271.799245) (xy 114.247928 -271.74795) (xy 114.263976 -271.698557)
			(xy 114.287554 -271.652283) (xy 114.31808 -271.610267) (xy 114.354803 -271.573544) (xy 114.396819 -271.543018)
			(xy 114.443093 -271.51944) (xy 114.492486 -271.503392) (xy 114.543781 -271.495267) (xy 114.595715 -271.495267)
			(xy 114.64701 -271.503392) (xy 114.696403 -271.51944) (xy 114.742677 -271.543018) (xy 114.784693 -271.573544)
			(xy 114.821416 -271.610267) (xy 114.851942 -271.652283) (xy 114.87552 -271.698557) (xy 114.891568 -271.74795)
			(xy 114.899693 -271.799245) (xy 114.900202 -271.825212) (xy 114.899693 -271.851179) (xy 115.179603 -271.851179)
			(xy 115.179603 -271.799245) (xy 115.187728 -271.74795) (xy 115.203776 -271.698557) (xy 115.227354 -271.652283)
			(xy 115.25788 -271.610267) (xy 115.294603 -271.573544) (xy 115.336619 -271.543018) (xy 115.382893 -271.51944)
			(xy 115.432286 -271.503392) (xy 115.483581 -271.495267) (xy 115.535515 -271.495267) (xy 115.58681 -271.503392)
			(xy 115.636203 -271.51944) (xy 115.682477 -271.543018) (xy 115.724493 -271.573544) (xy 115.761216 -271.610267)
			(xy 115.791742 -271.652283) (xy 115.81532 -271.698557) (xy 115.831368 -271.74795) (xy 115.839493 -271.799245)
			(xy 115.840002 -271.825212) (xy 115.839493 -271.851179) (xy 116.118895 -271.851179) (xy 116.118895 -271.799245)
			(xy 116.12702 -271.74795) (xy 116.143068 -271.698557) (xy 116.166646 -271.652283) (xy 116.197172 -271.610267)
			(xy 116.233895 -271.573544) (xy 116.275911 -271.543018) (xy 116.322185 -271.51944) (xy 116.371578 -271.503392)
			(xy 116.422873 -271.495267) (xy 116.474807 -271.495267) (xy 116.526102 -271.503392) (xy 116.575495 -271.51944)
			(xy 116.621769 -271.543018) (xy 116.663785 -271.573544) (xy 116.700508 -271.610267) (xy 116.731034 -271.652283)
			(xy 116.754612 -271.698557) (xy 116.77066 -271.74795) (xy 116.778785 -271.799245) (xy 116.779294 -271.825212)
			(xy 116.778785 -271.851179) (xy 117.059203 -271.851179) (xy 117.059203 -271.799245) (xy 117.067328 -271.74795)
			(xy 117.083376 -271.698557) (xy 117.106954 -271.652283) (xy 117.13748 -271.610267) (xy 117.174203 -271.573544)
			(xy 117.216219 -271.543018) (xy 117.262493 -271.51944) (xy 117.311886 -271.503392) (xy 117.363181 -271.495267)
			(xy 117.415115 -271.495267) (xy 117.46641 -271.503392) (xy 117.515803 -271.51944) (xy 117.562077 -271.543018)
			(xy 117.604093 -271.573544) (xy 117.640816 -271.610267) (xy 117.671342 -271.652283) (xy 117.69492 -271.698557)
			(xy 117.710968 -271.74795) (xy 117.719093 -271.799245) (xy 117.719602 -271.825212) (xy 117.719093 -271.851179)
			(xy 117.710968 -271.902474) (xy 117.69492 -271.951867) (xy 117.671342 -271.998141) (xy 117.640816 -272.040157)
			(xy 117.604093 -272.07688) (xy 117.562077 -272.107406) (xy 117.515803 -272.130984) (xy 117.46641 -272.147032)
			(xy 117.415115 -272.155157) (xy 117.363181 -272.155157) (xy 117.311886 -272.147032) (xy 117.262493 -272.130984)
			(xy 117.216219 -272.107406) (xy 117.174203 -272.07688) (xy 117.13748 -272.040157) (xy 117.106954 -271.998141)
			(xy 117.083376 -271.951867) (xy 117.067328 -271.902474) (xy 117.059203 -271.851179) (xy 116.778785 -271.851179)
			(xy 116.77066 -271.902474) (xy 116.754612 -271.951867) (xy 116.731034 -271.998141) (xy 116.700508 -272.040157)
			(xy 116.663785 -272.07688) (xy 116.621769 -272.107406) (xy 116.575495 -272.130984) (xy 116.526102 -272.147032)
			(xy 116.474807 -272.155157) (xy 116.422873 -272.155157) (xy 116.371578 -272.147032) (xy 116.322185 -272.130984)
			(xy 116.275911 -272.107406) (xy 116.233895 -272.07688) (xy 116.197172 -272.040157) (xy 116.166646 -271.998141)
			(xy 116.143068 -271.951867) (xy 116.12702 -271.902474) (xy 116.118895 -271.851179) (xy 115.839493 -271.851179)
			(xy 115.831368 -271.902474) (xy 115.81532 -271.951867) (xy 115.791742 -271.998141) (xy 115.761216 -272.040157)
			(xy 115.724493 -272.07688) (xy 115.682477 -272.107406) (xy 115.636203 -272.130984) (xy 115.58681 -272.147032)
			(xy 115.535515 -272.155157) (xy 115.483581 -272.155157) (xy 115.432286 -272.147032) (xy 115.382893 -272.130984)
			(xy 115.336619 -272.107406) (xy 115.294603 -272.07688) (xy 115.25788 -272.040157) (xy 115.227354 -271.998141)
			(xy 115.203776 -271.951867) (xy 115.187728 -271.902474) (xy 115.179603 -271.851179) (xy 114.899693 -271.851179)
			(xy 114.891568 -271.902474) (xy 114.87552 -271.951867) (xy 114.851942 -271.998141) (xy 114.821416 -272.040157)
			(xy 114.784693 -272.07688) (xy 114.742677 -272.107406) (xy 114.696403 -272.130984) (xy 114.64701 -272.147032)
			(xy 114.595715 -272.155157) (xy 114.543781 -272.155157) (xy 114.492486 -272.147032) (xy 114.443093 -272.130984)
			(xy 114.396819 -272.107406) (xy 114.354803 -272.07688) (xy 114.31808 -272.040157) (xy 114.287554 -271.998141)
			(xy 114.263976 -271.951867) (xy 114.247928 -271.902474) (xy 114.239803 -271.851179) (xy 113.959639 -271.851179)
			(xy 113.951514 -271.902474) (xy 113.935466 -271.951867) (xy 113.911888 -271.998141) (xy 113.881362 -272.040157)
			(xy 113.844639 -272.07688) (xy 113.802623 -272.107406) (xy 113.756349 -272.130984) (xy 113.706956 -272.147032)
			(xy 113.655661 -272.155157) (xy 113.603727 -272.155157) (xy 113.552432 -272.147032) (xy 113.503039 -272.130984)
			(xy 113.456765 -272.107406) (xy 113.414749 -272.07688) (xy 113.378026 -272.040157) (xy 113.3475 -271.998141)
			(xy 113.323922 -271.951867) (xy 113.307874 -271.902474) (xy 113.299749 -271.851179) (xy 110.200185 -271.851179)
			(xy 110.19206 -271.902474) (xy 110.176012 -271.951867) (xy 110.152434 -271.998141) (xy 110.121908 -272.040157)
			(xy 110.085185 -272.07688) (xy 110.043169 -272.107406) (xy 109.996895 -272.130984) (xy 109.947502 -272.147032)
			(xy 109.896207 -272.155157) (xy 109.844273 -272.155157) (xy 109.792978 -272.147032) (xy 109.743585 -272.130984)
			(xy 109.697311 -272.107406) (xy 109.655295 -272.07688) (xy 109.618572 -272.040157) (xy 109.588046 -271.998141)
			(xy 109.564468 -271.951867) (xy 109.54842 -271.902474) (xy 109.540295 -271.851179) (xy 109.260893 -271.851179)
			(xy 109.252768 -271.902474) (xy 109.23672 -271.951867) (xy 109.213142 -271.998141) (xy 109.182616 -272.040157)
			(xy 109.145893 -272.07688) (xy 109.103877 -272.107406) (xy 109.057603 -272.130984) (xy 109.00821 -272.147032)
			(xy 108.956915 -272.155157) (xy 108.904981 -272.155157) (xy 108.853686 -272.147032) (xy 108.804293 -272.130984)
			(xy 108.758019 -272.107406) (xy 108.716003 -272.07688) (xy 108.67928 -272.040157) (xy 108.648754 -271.998141)
			(xy 108.625176 -271.951867) (xy 108.609128 -271.902474) (xy 108.601003 -271.851179) (xy 108.321093 -271.851179)
			(xy 108.312968 -271.902474) (xy 108.29692 -271.951867) (xy 108.273342 -271.998141) (xy 108.242816 -272.040157)
			(xy 108.206093 -272.07688) (xy 108.164077 -272.107406) (xy 108.117803 -272.130984) (xy 108.06841 -272.147032)
			(xy 108.017115 -272.155157) (xy 107.965181 -272.155157) (xy 107.913886 -272.147032) (xy 107.864493 -272.130984)
			(xy 107.818219 -272.107406) (xy 107.776203 -272.07688) (xy 107.73948 -272.040157) (xy 107.708954 -271.998141)
			(xy 107.685376 -271.951867) (xy 107.669328 -271.902474) (xy 107.661203 -271.851179) (xy 107.381293 -271.851179)
			(xy 107.373168 -271.902474) (xy 107.35712 -271.951867) (xy 107.333542 -271.998141) (xy 107.303016 -272.040157)
			(xy 107.266293 -272.07688) (xy 107.224277 -272.107406) (xy 107.178003 -272.130984) (xy 107.12861 -272.147032)
			(xy 107.077315 -272.155157) (xy 107.025381 -272.155157) (xy 106.974086 -272.147032) (xy 106.924693 -272.130984)
			(xy 106.878419 -272.107406) (xy 106.836403 -272.07688) (xy 106.79968 -272.040157) (xy 106.769154 -271.998141)
			(xy 106.745576 -271.951867) (xy 106.729528 -271.902474) (xy 106.721403 -271.851179) (xy 106.441493 -271.851179)
			(xy 106.433368 -271.902474) (xy 106.41732 -271.951867) (xy 106.393742 -271.998141) (xy 106.363216 -272.040157)
			(xy 106.326493 -272.07688) (xy 106.284477 -272.107406) (xy 106.238203 -272.130984) (xy 106.18881 -272.147032)
			(xy 106.137515 -272.155157) (xy 106.085581 -272.155157) (xy 106.034286 -272.147032) (xy 105.984893 -272.130984)
			(xy 105.938619 -272.107406) (xy 105.896603 -272.07688) (xy 105.85988 -272.040157) (xy 105.829354 -271.998141)
			(xy 105.805776 -271.951867) (xy 105.789728 -271.902474) (xy 105.781603 -271.851179) (xy 105.501693 -271.851179)
			(xy 105.493568 -271.902474) (xy 105.47752 -271.951867) (xy 105.453942 -271.998141) (xy 105.423416 -272.040157)
			(xy 105.386693 -272.07688) (xy 105.344677 -272.107406) (xy 105.298403 -272.130984) (xy 105.24901 -272.147032)
			(xy 105.197715 -272.155157) (xy 105.145781 -272.155157) (xy 105.094486 -272.147032) (xy 105.045093 -272.130984)
			(xy 104.998819 -272.107406) (xy 104.956803 -272.07688) (xy 104.92008 -272.040157) (xy 104.889554 -271.998141)
			(xy 104.865976 -271.951867) (xy 104.849928 -271.902474) (xy 104.841803 -271.851179) (xy 104.561893 -271.851179)
			(xy 104.553768 -271.902474) (xy 104.53772 -271.951867) (xy 104.514142 -271.998141) (xy 104.483616 -272.040157)
			(xy 104.446893 -272.07688) (xy 104.404877 -272.107406) (xy 104.358603 -272.130984) (xy 104.30921 -272.147032)
			(xy 104.257915 -272.155157) (xy 104.205981 -272.155157) (xy 104.154686 -272.147032) (xy 104.105293 -272.130984)
			(xy 104.059019 -272.107406) (xy 104.017003 -272.07688) (xy 103.98028 -272.040157) (xy 103.949754 -271.998141)
			(xy 103.926176 -271.951867) (xy 103.910128 -271.902474) (xy 103.902003 -271.851179) (xy 103.622093 -271.851179)
			(xy 103.613968 -271.902474) (xy 103.59792 -271.951867) (xy 103.574342 -271.998141) (xy 103.543816 -272.040157)
			(xy 103.507093 -272.07688) (xy 103.465077 -272.107406) (xy 103.418803 -272.130984) (xy 103.36941 -272.147032)
			(xy 103.318115 -272.155157) (xy 103.266181 -272.155157) (xy 103.214886 -272.147032) (xy 103.165493 -272.130984)
			(xy 103.119219 -272.107406) (xy 103.077203 -272.07688) (xy 103.04048 -272.040157) (xy 103.009954 -271.998141)
			(xy 102.986376 -271.951867) (xy 102.970328 -271.902474) (xy 102.962203 -271.851179) (xy 102.682153 -271.851179)
			(xy 102.682013 -271.856795) (xy 102.669984 -271.918807) (xy 102.658926 -271.948402) (xy 102.65537 -271.957292)
			(xy 102.65537 -272.212054) (xy 102.655801 -272.226683) (xy 102.664009 -272.254762) (xy 102.679849 -272.279357)
			(xy 102.702019 -272.298445) (xy 102.728694 -272.310455) (xy 102.757682 -272.3144) (xy 102.77221 -272.312638)
			(xy 102.78458 -272.310863) (xy 102.809498 -272.308959) (xy 102.821994 -272.308828) (xy 102.847965 -272.30931)
			(xy 102.899268 -272.317435) (xy 102.948668 -272.333485) (xy 102.994949 -272.357066) (xy 103.036971 -272.387596)
			(xy 103.0737 -272.424324) (xy 103.104231 -272.466346) (xy 103.127812 -272.512627) (xy 103.143863 -272.562026)
			(xy 103.151989 -272.613329) (xy 103.151989 -272.665249) (xy 103.431849 -272.665249) (xy 103.431849 -272.613315)
			(xy 103.439974 -272.56202) (xy 103.456022 -272.512627) (xy 103.4796 -272.466353) (xy 103.510126 -272.424337)
			(xy 103.546849 -272.387614) (xy 103.588865 -272.357088) (xy 103.635139 -272.33351) (xy 103.684532 -272.317462)
			(xy 103.735827 -272.309337) (xy 103.787761 -272.309337) (xy 103.839056 -272.317462) (xy 103.888449 -272.33351)
			(xy 103.934723 -272.357088) (xy 103.976739 -272.387614) (xy 104.013462 -272.424337) (xy 104.043988 -272.466353)
			(xy 104.067566 -272.512627) (xy 104.083614 -272.56202) (xy 104.091739 -272.613315) (xy 104.092248 -272.639282)
			(xy 104.091739 -272.665249) (xy 104.371649 -272.665249) (xy 104.371649 -272.613315) (xy 104.379774 -272.56202)
			(xy 104.395822 -272.512627) (xy 104.4194 -272.466353) (xy 104.449926 -272.424337) (xy 104.486649 -272.387614)
			(xy 104.528665 -272.357088) (xy 104.574939 -272.33351) (xy 104.624332 -272.317462) (xy 104.675627 -272.309337)
			(xy 104.727561 -272.309337) (xy 104.778856 -272.317462) (xy 104.828249 -272.33351) (xy 104.874523 -272.357088)
			(xy 104.916539 -272.387614) (xy 104.953262 -272.424337) (xy 104.983788 -272.466353) (xy 105.007366 -272.512627)
			(xy 105.023414 -272.56202) (xy 105.031539 -272.613315) (xy 105.032048 -272.639282) (xy 105.031539 -272.665249)
			(xy 105.311449 -272.665249) (xy 105.311449 -272.613315) (xy 105.319574 -272.56202) (xy 105.335622 -272.512627)
			(xy 105.3592 -272.466353) (xy 105.389726 -272.424337) (xy 105.426449 -272.387614) (xy 105.468465 -272.357088)
			(xy 105.514739 -272.33351) (xy 105.564132 -272.317462) (xy 105.615427 -272.309337) (xy 105.667361 -272.309337)
			(xy 105.718656 -272.317462) (xy 105.768049 -272.33351) (xy 105.814323 -272.357088) (xy 105.856339 -272.387614)
			(xy 105.893062 -272.424337) (xy 105.923588 -272.466353) (xy 105.947166 -272.512627) (xy 105.963214 -272.56202)
			(xy 105.971339 -272.613315) (xy 105.971848 -272.639282) (xy 105.971339 -272.665249) (xy 106.251249 -272.665249)
			(xy 106.251249 -272.613315) (xy 106.259374 -272.56202) (xy 106.275422 -272.512627) (xy 106.299 -272.466353)
			(xy 106.329526 -272.424337) (xy 106.366249 -272.387614) (xy 106.408265 -272.357088) (xy 106.454539 -272.33351)
			(xy 106.503932 -272.317462) (xy 106.555227 -272.309337) (xy 106.607161 -272.309337) (xy 106.658456 -272.317462)
			(xy 106.707849 -272.33351) (xy 106.754123 -272.357088) (xy 106.796139 -272.387614) (xy 106.832862 -272.424337)
			(xy 106.863388 -272.466353) (xy 106.886966 -272.512627) (xy 106.903014 -272.56202) (xy 106.911139 -272.613315)
			(xy 106.911648 -272.639282) (xy 106.911139 -272.665249) (xy 107.191049 -272.665249) (xy 107.191049 -272.613315)
			(xy 107.199174 -272.56202) (xy 107.215222 -272.512627) (xy 107.2388 -272.466353) (xy 107.269326 -272.424337)
			(xy 107.306049 -272.387614) (xy 107.348065 -272.357088) (xy 107.394339 -272.33351) (xy 107.443732 -272.317462)
			(xy 107.495027 -272.309337) (xy 107.546961 -272.309337) (xy 107.598256 -272.317462) (xy 107.647649 -272.33351)
			(xy 107.693923 -272.357088) (xy 107.735939 -272.387614) (xy 107.772662 -272.424337) (xy 107.803188 -272.466353)
			(xy 107.826766 -272.512627) (xy 107.842814 -272.56202) (xy 107.850939 -272.613315) (xy 107.851448 -272.639282)
			(xy 107.850939 -272.665249) (xy 108.130849 -272.665249) (xy 108.130849 -272.613315) (xy 108.138974 -272.56202)
			(xy 108.155022 -272.512627) (xy 108.1786 -272.466353) (xy 108.209126 -272.424337) (xy 108.245849 -272.387614)
			(xy 108.287865 -272.357088) (xy 108.334139 -272.33351) (xy 108.383532 -272.317462) (xy 108.434827 -272.309337)
			(xy 108.486761 -272.309337) (xy 108.538056 -272.317462) (xy 108.587449 -272.33351) (xy 108.633723 -272.357088)
			(xy 108.675739 -272.387614) (xy 108.712462 -272.424337) (xy 108.742988 -272.466353) (xy 108.766566 -272.512627)
			(xy 108.782614 -272.56202) (xy 108.790739 -272.613315) (xy 108.791248 -272.639282) (xy 108.790739 -272.665249)
			(xy 109.070649 -272.665249) (xy 109.070649 -272.613315) (xy 109.078774 -272.56202) (xy 109.094822 -272.512627)
			(xy 109.1184 -272.466353) (xy 109.148926 -272.424337) (xy 109.185649 -272.387614) (xy 109.227665 -272.357088)
			(xy 109.273939 -272.33351) (xy 109.323332 -272.317462) (xy 109.374627 -272.309337) (xy 109.426561 -272.309337)
			(xy 109.477856 -272.317462) (xy 109.527249 -272.33351) (xy 109.573523 -272.357088) (xy 109.615539 -272.387614)
			(xy 109.652262 -272.424337) (xy 109.682788 -272.466353) (xy 109.706366 -272.512627) (xy 109.722414 -272.56202)
			(xy 109.730539 -272.613315) (xy 109.731048 -272.639282) (xy 109.730539 -272.665249) (xy 110.010449 -272.665249)
			(xy 110.010449 -272.613315) (xy 110.018574 -272.56202) (xy 110.034622 -272.512627) (xy 110.0582 -272.466353)
			(xy 110.088726 -272.424337) (xy 110.125449 -272.387614) (xy 110.167465 -272.357088) (xy 110.213739 -272.33351)
			(xy 110.263132 -272.317462) (xy 110.314427 -272.309337) (xy 110.366361 -272.309337) (xy 110.417656 -272.317462)
			(xy 110.467049 -272.33351) (xy 110.513323 -272.357088) (xy 110.555339 -272.387614) (xy 110.592062 -272.424337)
			(xy 110.622588 -272.466353) (xy 110.646166 -272.512627) (xy 110.662214 -272.56202) (xy 110.670339 -272.613315)
			(xy 110.670848 -272.639282) (xy 110.670339 -272.665249) (xy 113.769649 -272.665249) (xy 113.769649 -272.613315)
			(xy 113.777774 -272.56202) (xy 113.793822 -272.512627) (xy 113.8174 -272.466353) (xy 113.847926 -272.424337)
			(xy 113.884649 -272.387614) (xy 113.926665 -272.357088) (xy 113.972939 -272.33351) (xy 114.022332 -272.317462)
			(xy 114.073627 -272.309337) (xy 114.125561 -272.309337) (xy 114.176856 -272.317462) (xy 114.226249 -272.33351)
			(xy 114.272523 -272.357088) (xy 114.314539 -272.387614) (xy 114.351262 -272.424337) (xy 114.381788 -272.466353)
			(xy 114.405366 -272.512627) (xy 114.421414 -272.56202) (xy 114.429539 -272.613315) (xy 114.430048 -272.639282)
			(xy 114.429539 -272.665249) (xy 114.709449 -272.665249) (xy 114.709449 -272.613315) (xy 114.717574 -272.56202)
			(xy 114.733622 -272.512627) (xy 114.7572 -272.466353) (xy 114.787726 -272.424337) (xy 114.824449 -272.387614)
			(xy 114.866465 -272.357088) (xy 114.912739 -272.33351) (xy 114.962132 -272.317462) (xy 115.013427 -272.309337)
			(xy 115.065361 -272.309337) (xy 115.116656 -272.317462) (xy 115.166049 -272.33351) (xy 115.212323 -272.357088)
			(xy 115.254339 -272.387614) (xy 115.291062 -272.424337) (xy 115.321588 -272.466353) (xy 115.345166 -272.512627)
			(xy 115.361214 -272.56202) (xy 115.369339 -272.613315) (xy 115.369848 -272.639282) (xy 115.369339 -272.665249)
			(xy 115.649249 -272.665249) (xy 115.649249 -272.613315) (xy 115.657374 -272.56202) (xy 115.673422 -272.512627)
			(xy 115.697 -272.466353) (xy 115.727526 -272.424337) (xy 115.764249 -272.387614) (xy 115.806265 -272.357088)
			(xy 115.852539 -272.33351) (xy 115.901932 -272.317462) (xy 115.953227 -272.309337) (xy 116.005161 -272.309337)
			(xy 116.056456 -272.317462) (xy 116.105849 -272.33351) (xy 116.152123 -272.357088) (xy 116.194139 -272.387614)
			(xy 116.230862 -272.424337) (xy 116.261388 -272.466353) (xy 116.284966 -272.512627) (xy 116.301014 -272.56202)
			(xy 116.309139 -272.613315) (xy 116.309648 -272.639282) (xy 116.309139 -272.665249) (xy 116.589049 -272.665249)
			(xy 116.589049 -272.613315) (xy 116.597174 -272.56202) (xy 116.613222 -272.512627) (xy 116.6368 -272.466353)
			(xy 116.667326 -272.424337) (xy 116.704049 -272.387614) (xy 116.746065 -272.357088) (xy 116.792339 -272.33351)
			(xy 116.841732 -272.317462) (xy 116.893027 -272.309337) (xy 116.944961 -272.309337) (xy 116.996256 -272.317462)
			(xy 117.045649 -272.33351) (xy 117.091923 -272.357088) (xy 117.133939 -272.387614) (xy 117.170662 -272.424337)
			(xy 117.201188 -272.466353) (xy 117.224766 -272.512627) (xy 117.240814 -272.56202) (xy 117.248939 -272.613315)
			(xy 117.249448 -272.639282) (xy 117.248939 -272.665249) (xy 117.240814 -272.716544) (xy 117.224766 -272.765937)
			(xy 117.201188 -272.812211) (xy 117.170662 -272.854227) (xy 117.133939 -272.89095) (xy 117.091923 -272.921476)
			(xy 117.045649 -272.945054) (xy 116.996256 -272.961102) (xy 116.944961 -272.969227) (xy 116.893027 -272.969227)
			(xy 116.841732 -272.961102) (xy 116.792339 -272.945054) (xy 116.746065 -272.921476) (xy 116.704049 -272.89095)
			(xy 116.667326 -272.854227) (xy 116.6368 -272.812211) (xy 116.613222 -272.765937) (xy 116.597174 -272.716544)
			(xy 116.589049 -272.665249) (xy 116.309139 -272.665249) (xy 116.301014 -272.716544) (xy 116.284966 -272.765937)
			(xy 116.261388 -272.812211) (xy 116.230862 -272.854227) (xy 116.194139 -272.89095) (xy 116.152123 -272.921476)
			(xy 116.105849 -272.945054) (xy 116.056456 -272.961102) (xy 116.005161 -272.969227) (xy 115.953227 -272.969227)
			(xy 115.901932 -272.961102) (xy 115.852539 -272.945054) (xy 115.806265 -272.921476) (xy 115.764249 -272.89095)
			(xy 115.727526 -272.854227) (xy 115.697 -272.812211) (xy 115.673422 -272.765937) (xy 115.657374 -272.716544)
			(xy 115.649249 -272.665249) (xy 115.369339 -272.665249) (xy 115.361214 -272.716544) (xy 115.345166 -272.765937)
			(xy 115.321588 -272.812211) (xy 115.291062 -272.854227) (xy 115.254339 -272.89095) (xy 115.212323 -272.921476)
			(xy 115.166049 -272.945054) (xy 115.116656 -272.961102) (xy 115.065361 -272.969227) (xy 115.013427 -272.969227)
			(xy 114.962132 -272.961102) (xy 114.912739 -272.945054) (xy 114.866465 -272.921476) (xy 114.824449 -272.89095)
			(xy 114.787726 -272.854227) (xy 114.7572 -272.812211) (xy 114.733622 -272.765937) (xy 114.717574 -272.716544)
			(xy 114.709449 -272.665249) (xy 114.429539 -272.665249) (xy 114.421414 -272.716544) (xy 114.405366 -272.765937)
			(xy 114.381788 -272.812211) (xy 114.351262 -272.854227) (xy 114.314539 -272.89095) (xy 114.272523 -272.921476)
			(xy 114.226249 -272.945054) (xy 114.176856 -272.961102) (xy 114.125561 -272.969227) (xy 114.073627 -272.969227)
			(xy 114.022332 -272.961102) (xy 113.972939 -272.945054) (xy 113.926665 -272.921476) (xy 113.884649 -272.89095)
			(xy 113.847926 -272.854227) (xy 113.8174 -272.812211) (xy 113.793822 -272.765937) (xy 113.777774 -272.716544)
			(xy 113.769649 -272.665249) (xy 110.670339 -272.665249) (xy 110.662214 -272.716544) (xy 110.646166 -272.765937)
			(xy 110.622588 -272.812211) (xy 110.592062 -272.854227) (xy 110.555339 -272.89095) (xy 110.513323 -272.921476)
			(xy 110.467049 -272.945054) (xy 110.417656 -272.961102) (xy 110.366361 -272.969227) (xy 110.314427 -272.969227)
			(xy 110.263132 -272.961102) (xy 110.213739 -272.945054) (xy 110.167465 -272.921476) (xy 110.125449 -272.89095)
			(xy 110.088726 -272.854227) (xy 110.0582 -272.812211) (xy 110.034622 -272.765937) (xy 110.018574 -272.716544)
			(xy 110.010449 -272.665249) (xy 109.730539 -272.665249) (xy 109.722414 -272.716544) (xy 109.706366 -272.765937)
			(xy 109.682788 -272.812211) (xy 109.652262 -272.854227) (xy 109.615539 -272.89095) (xy 109.573523 -272.921476)
			(xy 109.527249 -272.945054) (xy 109.477856 -272.961102) (xy 109.426561 -272.969227) (xy 109.374627 -272.969227)
			(xy 109.323332 -272.961102) (xy 109.273939 -272.945054) (xy 109.227665 -272.921476) (xy 109.185649 -272.89095)
			(xy 109.148926 -272.854227) (xy 109.1184 -272.812211) (xy 109.094822 -272.765937) (xy 109.078774 -272.716544)
			(xy 109.070649 -272.665249) (xy 108.790739 -272.665249) (xy 108.782614 -272.716544) (xy 108.766566 -272.765937)
			(xy 108.742988 -272.812211) (xy 108.712462 -272.854227) (xy 108.675739 -272.89095) (xy 108.633723 -272.921476)
			(xy 108.587449 -272.945054) (xy 108.538056 -272.961102) (xy 108.486761 -272.969227) (xy 108.434827 -272.969227)
			(xy 108.383532 -272.961102) (xy 108.334139 -272.945054) (xy 108.287865 -272.921476) (xy 108.245849 -272.89095)
			(xy 108.209126 -272.854227) (xy 108.1786 -272.812211) (xy 108.155022 -272.765937) (xy 108.138974 -272.716544)
			(xy 108.130849 -272.665249) (xy 107.850939 -272.665249) (xy 107.842814 -272.716544) (xy 107.826766 -272.765937)
			(xy 107.803188 -272.812211) (xy 107.772662 -272.854227) (xy 107.735939 -272.89095) (xy 107.693923 -272.921476)
			(xy 107.647649 -272.945054) (xy 107.598256 -272.961102) (xy 107.546961 -272.969227) (xy 107.495027 -272.969227)
			(xy 107.443732 -272.961102) (xy 107.394339 -272.945054) (xy 107.348065 -272.921476) (xy 107.306049 -272.89095)
			(xy 107.269326 -272.854227) (xy 107.2388 -272.812211) (xy 107.215222 -272.765937) (xy 107.199174 -272.716544)
			(xy 107.191049 -272.665249) (xy 106.911139 -272.665249) (xy 106.903014 -272.716544) (xy 106.886966 -272.765937)
			(xy 106.863388 -272.812211) (xy 106.832862 -272.854227) (xy 106.796139 -272.89095) (xy 106.754123 -272.921476)
			(xy 106.707849 -272.945054) (xy 106.658456 -272.961102) (xy 106.607161 -272.969227) (xy 106.555227 -272.969227)
			(xy 106.503932 -272.961102) (xy 106.454539 -272.945054) (xy 106.408265 -272.921476) (xy 106.366249 -272.89095)
			(xy 106.329526 -272.854227) (xy 106.299 -272.812211) (xy 106.275422 -272.765937) (xy 106.259374 -272.716544)
			(xy 106.251249 -272.665249) (xy 105.971339 -272.665249) (xy 105.963214 -272.716544) (xy 105.947166 -272.765937)
			(xy 105.923588 -272.812211) (xy 105.893062 -272.854227) (xy 105.856339 -272.89095) (xy 105.814323 -272.921476)
			(xy 105.768049 -272.945054) (xy 105.718656 -272.961102) (xy 105.667361 -272.969227) (xy 105.615427 -272.969227)
			(xy 105.564132 -272.961102) (xy 105.514739 -272.945054) (xy 105.468465 -272.921476) (xy 105.426449 -272.89095)
			(xy 105.389726 -272.854227) (xy 105.3592 -272.812211) (xy 105.335622 -272.765937) (xy 105.319574 -272.716544)
			(xy 105.311449 -272.665249) (xy 105.031539 -272.665249) (xy 105.023414 -272.716544) (xy 105.007366 -272.765937)
			(xy 104.983788 -272.812211) (xy 104.953262 -272.854227) (xy 104.916539 -272.89095) (xy 104.874523 -272.921476)
			(xy 104.828249 -272.945054) (xy 104.778856 -272.961102) (xy 104.727561 -272.969227) (xy 104.675627 -272.969227)
			(xy 104.624332 -272.961102) (xy 104.574939 -272.945054) (xy 104.528665 -272.921476) (xy 104.486649 -272.89095)
			(xy 104.449926 -272.854227) (xy 104.4194 -272.812211) (xy 104.395822 -272.765937) (xy 104.379774 -272.716544)
			(xy 104.371649 -272.665249) (xy 104.091739 -272.665249) (xy 104.083614 -272.716544) (xy 104.067566 -272.765937)
			(xy 104.043988 -272.812211) (xy 104.013462 -272.854227) (xy 103.976739 -272.89095) (xy 103.934723 -272.921476)
			(xy 103.888449 -272.945054) (xy 103.839056 -272.961102) (xy 103.787761 -272.969227) (xy 103.735827 -272.969227)
			(xy 103.684532 -272.961102) (xy 103.635139 -272.945054) (xy 103.588865 -272.921476) (xy 103.546849 -272.89095)
			(xy 103.510126 -272.854227) (xy 103.4796 -272.812211) (xy 103.456022 -272.765937) (xy 103.439974 -272.716544)
			(xy 103.431849 -272.665249) (xy 103.151989 -272.665249) (xy 103.151989 -272.665271) (xy 103.143863 -272.716574)
			(xy 103.127812 -272.765973) (xy 103.104231 -272.812254) (xy 103.0737 -272.854276) (xy 103.036971 -272.891004)
			(xy 102.994949 -272.921534) (xy 102.948668 -272.945115) (xy 102.899268 -272.961165) (xy 102.847965 -272.96929)
			(xy 102.821994 -272.969736) (xy 102.809498 -272.969607) (xy 102.78458 -272.967697) (xy 102.77221 -272.965926)
			(xy 102.757688 -272.96421) (xy 102.72873 -272.968195) (xy 102.702085 -272.980216) (xy 102.679933 -272.999287)
			(xy 102.664087 -273.02385) (xy 102.655842 -273.051894) (xy 102.65537 -273.06651) (xy 102.65537 -273.165316)
			(xy 102.829614 -273.33956) (xy 102.839759 -273.349114) (xy 102.864031 -273.362784) (xy 102.891092 -273.369396)
			(xy 102.918933 -273.368458) (xy 102.945487 -273.360039) (xy 102.968783 -273.344764) (xy 102.987092 -273.323768)
			(xy 102.993444 -273.311366) (xy 103.00535 -273.287549) (xy 103.035611 -273.243741) (xy 103.072504 -273.20535)
			(xy 103.115073 -273.17337) (xy 103.162218 -273.148627) (xy 103.21272 -273.131761) (xy 103.265272 -273.123209)
			(xy 103.291894 -273.122644) (xy 103.318925 -273.12319) (xy 103.372266 -273.132) (xy 103.423463 -273.14937)
			(xy 103.471152 -273.174838) (xy 103.514063 -273.207724) (xy 103.551052 -273.247153) (xy 103.581134 -273.292074)
			(xy 103.603508 -273.34129) (xy 103.617578 -273.39349) (xy 103.620824 -273.420332) (xy 103.622909 -273.43564)
			(xy 103.63503 -273.464043) (xy 103.655065 -273.487543) (xy 103.681193 -273.504003) (xy 103.71104 -273.511927)
			(xy 103.726488 -273.511772) (xy 103.761794 -273.510756) (xy 103.797354 -273.511772) (xy 103.8128 -273.51191)
			(xy 103.842643 -273.503996) (xy 103.868767 -273.487539) (xy 103.88879 -273.464038) (xy 103.900891 -273.435634)
			(xy 103.903018 -273.420332) (xy 103.906229 -273.393479) (xy 103.920268 -273.341254) (xy 103.942625 -273.292013)
			(xy 103.972702 -273.247069) (xy 104.009697 -273.207624) (xy 104.052621 -273.17473) (xy 104.100329 -273.149266)
			(xy 104.151548 -273.13191) (xy 104.204908 -273.123127) (xy 104.231948 -273.122644) (xy 104.257913 -273.123157)
			(xy 104.309202 -273.131287) (xy 104.358588 -273.14734) (xy 104.404856 -273.17092) (xy 104.446865 -273.201447)
			(xy 104.483583 -273.23817) (xy 104.514104 -273.280183) (xy 104.537678 -273.326454) (xy 104.553724 -273.375843)
			(xy 104.561847 -273.427133) (xy 104.562402 -273.453098) (xy 104.561909 -273.479065) (xy 105.781603 -273.479065)
			(xy 105.781603 -273.427131) (xy 105.789728 -273.375836) (xy 105.805776 -273.326443) (xy 105.829354 -273.280169)
			(xy 105.85988 -273.238153) (xy 105.896603 -273.20143) (xy 105.938619 -273.170904) (xy 105.984893 -273.147326)
			(xy 106.034286 -273.131278) (xy 106.085581 -273.123153) (xy 106.137515 -273.123153) (xy 106.18881 -273.131278)
			(xy 106.238203 -273.147326) (xy 106.284477 -273.170904) (xy 106.326493 -273.20143) (xy 106.363216 -273.238153)
			(xy 106.393742 -273.280169) (xy 106.41732 -273.326443) (xy 106.433368 -273.375836) (xy 106.441493 -273.427131)
			(xy 106.442002 -273.453098) (xy 106.441493 -273.479065) (xy 106.721403 -273.479065) (xy 106.721403 -273.427131)
			(xy 106.729528 -273.375836) (xy 106.745576 -273.326443) (xy 106.769154 -273.280169) (xy 106.79968 -273.238153)
			(xy 106.836403 -273.20143) (xy 106.878419 -273.170904) (xy 106.924693 -273.147326) (xy 106.974086 -273.131278)
			(xy 107.025381 -273.123153) (xy 107.077315 -273.123153) (xy 107.12861 -273.131278) (xy 107.178003 -273.147326)
			(xy 107.224277 -273.170904) (xy 107.266293 -273.20143) (xy 107.303016 -273.238153) (xy 107.333542 -273.280169)
			(xy 107.35712 -273.326443) (xy 107.373168 -273.375836) (xy 107.381293 -273.427131) (xy 107.381802 -273.453098)
			(xy 107.381293 -273.479065) (xy 107.373168 -273.53036) (xy 107.35712 -273.579753) (xy 107.333542 -273.626027)
			(xy 107.303016 -273.668043) (xy 107.266293 -273.704766) (xy 107.224277 -273.735292) (xy 107.178003 -273.75887)
			(xy 107.12861 -273.774918) (xy 107.077315 -273.783043) (xy 107.025381 -273.783043) (xy 106.974086 -273.774918)
			(xy 106.924693 -273.75887) (xy 106.878419 -273.735292) (xy 106.836403 -273.704766) (xy 106.79968 -273.668043)
			(xy 106.769154 -273.626027) (xy 106.745576 -273.579753) (xy 106.729528 -273.53036) (xy 106.721403 -273.479065)
			(xy 106.441493 -273.479065) (xy 106.433368 -273.53036) (xy 106.41732 -273.579753) (xy 106.393742 -273.626027)
			(xy 106.363216 -273.668043) (xy 106.326493 -273.704766) (xy 106.284477 -273.735292) (xy 106.238203 -273.75887)
			(xy 106.18881 -273.774918) (xy 106.137515 -273.783043) (xy 106.085581 -273.783043) (xy 106.034286 -273.774918)
			(xy 105.984893 -273.75887) (xy 105.938619 -273.735292) (xy 105.896603 -273.704766) (xy 105.85988 -273.668043)
			(xy 105.829354 -273.626027) (xy 105.805776 -273.579753) (xy 105.789728 -273.53036) (xy 105.781603 -273.479065)
			(xy 104.561909 -273.479065) (xy 104.561906 -273.479236) (xy 104.553672 -273.530859) (xy 104.537409 -273.580541)
			(xy 104.513524 -273.627041) (xy 104.482612 -273.669198) (xy 104.445446 -273.70596) (xy 104.42448 -273.721576)
			(xy 104.412237 -273.731045) (xy 104.393666 -273.755787) (xy 104.383343 -273.78495) (xy 104.382214 -273.815866)
			(xy 104.39038 -273.845705) (xy 104.398318 -273.85899) (xy 104.416606 -273.888962) (xy 104.436672 -273.923506)
			(xy 104.444616 -273.936174) (xy 104.466433 -273.9566) (xy 104.493222 -273.969849) (xy 104.522697 -273.974793)
			(xy 104.552343 -273.971007) (xy 104.566212 -273.965416) (xy 104.58759 -273.956247) (xy 104.632277 -273.943335)
			(xy 104.678336 -273.936835) (xy 104.701594 -273.93646) (xy 104.728625 -273.937006) (xy 104.781965 -273.945816)
			(xy 104.833161 -273.963187) (xy 104.880848 -273.988655) (xy 104.923758 -274.021541) (xy 104.960746 -274.06097)
			(xy 104.990826 -274.105891) (xy 105.013198 -274.155108) (xy 105.027265 -274.207308) (xy 105.030524 -274.234148)
			(xy 105.032555 -274.249482) (xy 105.044614 -274.277951) (xy 105.064651 -274.301497) (xy 105.090822 -274.317956)
			(xy 105.120723 -274.325817) (xy 105.136188 -274.325588) (xy 105.171748 -274.324572) (xy 105.2068 -274.325588)
			(xy 105.222252 -274.325747) (xy 105.252114 -274.317858) (xy 105.278252 -274.301403) (xy 105.298275 -274.277886)
			(xy 105.310352 -274.249458) (xy 105.312464 -274.234148) (xy 105.315674 -274.207295) (xy 105.329712 -274.155072)
			(xy 105.352069 -274.105832) (xy 105.382146 -274.06089) (xy 105.419141 -274.021448) (xy 105.462067 -273.988557)
			(xy 105.509776 -273.963097) (xy 105.560994 -273.945747) (xy 105.614355 -273.936971) (xy 105.641394 -273.93646)
			(xy 105.667363 -273.936942) (xy 105.718662 -273.945067) (xy 105.768059 -273.961116) (xy 105.814336 -273.984696)
			(xy 105.856355 -274.015225) (xy 105.893081 -274.051951) (xy 105.923608 -274.093971) (xy 105.947187 -274.140249)
			(xy 105.963235 -274.189646) (xy 105.971358 -274.240945) (xy 105.971848 -274.266914) (xy 105.971382 -274.292308)
			(xy 105.963607 -274.342497) (xy 105.948242 -274.390905) (xy 105.925648 -274.436391) (xy 105.911396 -274.457414)
			(xy 105.903638 -274.469166) (xy 105.894283 -274.495713) (xy 105.892544 -274.523807) (xy 105.898553 -274.551306)
			(xy 105.911852 -274.576114) (xy 105.931428 -274.59634) (xy 105.955788 -274.610443) (xy 105.969308 -274.614386)
			(xy 106.005341 -274.62393) (xy 106.076377 -274.646548) (xy 106.111294 -274.659598) (xy 106.14621 -274.646545)
			(xy 106.217245 -274.623925) (xy 106.25328 -274.614386) (xy 106.26681 -274.610483) (xy 106.291162 -274.596364)
			(xy 106.31073 -274.576128) (xy 106.324023 -274.551316) (xy 106.33003 -274.523815) (xy 106.328294 -274.49572)
			(xy 106.318947 -274.469168) (xy 106.311192 -274.457414) (xy 106.296935 -274.436396) (xy 106.274356 -274.390905)
			(xy 106.259 -274.342496) (xy 106.25123 -274.292307) (xy 106.25074 -274.266914) (xy 106.251222 -274.240944)
			(xy 106.259345 -274.189643) (xy 106.275394 -274.140244) (xy 106.298972 -274.093964) (xy 106.329501 -274.051942)
			(xy 106.366227 -274.015214) (xy 106.408247 -273.984683) (xy 106.454525 -273.961101) (xy 106.503923 -273.94505)
			(xy 106.555224 -273.936923) (xy 106.581194 -273.93646) (xy 106.608095 -273.936986) (xy 106.661187 -273.945693)
			(xy 106.712169 -273.962879) (xy 106.759698 -273.988089) (xy 106.80252 -274.02066) (xy 106.839506 -274.059733)
			(xy 106.869679 -274.104276) (xy 106.881422 -274.128484) (xy 106.88772 -274.141072) (xy 106.906018 -274.162446)
			(xy 106.929449 -274.178023) (xy 106.956239 -274.186624) (xy 106.984358 -274.187597) (xy 107.011679 -274.180868)
			(xy 107.03613 -274.166948) (xy 107.046268 -274.157186) (xy 107.078 -274.12523) (xy 107.14516 -274.065219)
			(xy 107.216251 -274.009922) (xy 107.290944 -273.959595) (xy 107.329732 -273.936714) (xy 107.369034 -273.914442)
			(xy 107.450153 -273.874672) (xy 107.533797 -273.840527) (xy 107.619574 -273.812167) (xy 107.663234 -273.80057)
			(xy 107.676735 -273.796634) (xy 107.701021 -273.782477) (xy 107.720532 -273.762239) (xy 107.733791 -273.737451)
			(xy 107.739795 -273.709989) (xy 107.738089 -273.681929) (xy 107.728804 -273.655396) (xy 107.721146 -273.643598)
			(xy 107.706886 -273.62258) (xy 107.684298 -273.577091) (xy 107.668932 -273.528682) (xy 107.66115 -273.478492)
			(xy 107.660694 -273.453098) (xy 107.661203 -273.427131) (xy 107.669328 -273.375836) (xy 107.685376 -273.326443)
			(xy 107.708954 -273.280169) (xy 107.73948 -273.238153) (xy 107.776203 -273.20143) (xy 107.818219 -273.170904)
			(xy 107.864493 -273.147326) (xy 107.913886 -273.131278) (xy 107.965181 -273.123153) (xy 108.017115 -273.123153)
			(xy 108.06841 -273.131278) (xy 108.117803 -273.147326) (xy 108.164077 -273.170904) (xy 108.206093 -273.20143)
			(xy 108.242816 -273.238153) (xy 108.273342 -273.280169) (xy 108.29692 -273.326443) (xy 108.312968 -273.375836)
			(xy 108.321093 -273.427131) (xy 108.321602 -273.453098) (xy 108.321137 -273.478492) (xy 108.313363 -273.528682)
			(xy 108.297998 -273.57709) (xy 108.275404 -273.622576) (xy 108.26115 -273.643598) (xy 108.253446 -273.65536)
			(xy 108.244181 -273.681896) (xy 108.242494 -273.709952) (xy 108.248513 -273.737406) (xy 108.261781 -273.762184)
			(xy 108.281296 -273.782411) (xy 108.305583 -273.796558) (xy 108.319062 -273.80057) (xy 108.355097 -273.810109)
			(xy 108.426132 -273.832729) (xy 108.461048 -273.845782) (xy 108.495969 -273.832797) (xy 108.567004 -273.810303)
			(xy 108.603034 -273.800824) (xy 108.616586 -273.796915) (xy 108.640973 -273.782765) (xy 108.660551 -273.762476)
			(xy 108.673825 -273.737601) (xy 108.679778 -273.710043) (xy 108.677956 -273.681907) (xy 108.668498 -273.655346)
			(xy 108.660692 -273.643598) (xy 108.64643 -273.622581) (xy 108.623839 -273.577092) (xy 108.608471 -273.528683)
			(xy 108.600688 -273.478493) (xy 108.60024 -273.453098) (xy 108.600749 -273.427131) (xy 108.608874 -273.375836)
			(xy 108.624922 -273.326443) (xy 108.6485 -273.280169) (xy 108.679026 -273.238153) (xy 108.715749 -273.20143)
			(xy 108.757765 -273.170904) (xy 108.804039 -273.147326) (xy 108.853432 -273.131278) (xy 108.904727 -273.123153)
			(xy 108.956661 -273.123153) (xy 109.007956 -273.131278) (xy 109.057349 -273.147326) (xy 109.103623 -273.170904)
			(xy 109.145639 -273.20143) (xy 109.182362 -273.238153) (xy 109.212888 -273.280169) (xy 109.236466 -273.326443)
			(xy 109.252514 -273.375836) (xy 109.260639 -273.427131) (xy 109.261148 -273.453098) (xy 109.260549 -273.481018)
			(xy 109.251105 -273.536053) (xy 109.242352 -273.562572) (xy 109.234732 -273.58467) (xy 109.387894 -273.8501)
			(xy 109.427772 -273.835876) (xy 109.456176 -273.825967) (xy 109.51373 -273.808436) (xy 109.542834 -273.800824)
			(xy 109.556318 -273.796864) (xy 109.580564 -273.782672) (xy 109.600029 -273.762415) (xy 109.613244 -273.737624)
			(xy 109.619209 -273.710171) (xy 109.617475 -273.682132) (xy 109.608173 -273.655623) (xy 109.600492 -273.643852)
			(xy 109.586217 -273.622807) (xy 109.563612 -273.577256) (xy 109.54825 -273.52878) (xy 109.540494 -273.478524)
			(xy 109.54004 -273.453098) (xy 109.540549 -273.427131) (xy 109.548674 -273.375836) (xy 109.564722 -273.326443)
			(xy 109.5883 -273.280169) (xy 109.618826 -273.238153) (xy 109.655549 -273.20143) (xy 109.697565 -273.170904)
			(xy 109.743839 -273.147326) (xy 109.793232 -273.131278) (xy 109.844527 -273.123153) (xy 109.896461 -273.123153)
			(xy 109.947756 -273.131278) (xy 109.997149 -273.147326) (xy 110.043423 -273.170904) (xy 110.085439 -273.20143)
			(xy 110.122162 -273.238153) (xy 110.152688 -273.280169) (xy 110.176266 -273.326443) (xy 110.192314 -273.375836)
			(xy 110.200439 -273.427131) (xy 110.200948 -273.453098) (xy 110.200504 -273.478526) (xy 110.200421 -273.479065)
			(xy 113.299749 -273.479065) (xy 113.299749 -273.427131) (xy 113.307874 -273.375836) (xy 113.323922 -273.326443)
			(xy 113.3475 -273.280169) (xy 113.378026 -273.238153) (xy 113.414749 -273.20143) (xy 113.456765 -273.170904)
			(xy 113.503039 -273.147326) (xy 113.552432 -273.131278) (xy 113.603727 -273.123153) (xy 113.655661 -273.123153)
			(xy 113.706956 -273.131278) (xy 113.756349 -273.147326) (xy 113.802623 -273.170904) (xy 113.844639 -273.20143)
			(xy 113.881362 -273.238153) (xy 113.911888 -273.280169) (xy 113.935466 -273.326443) (xy 113.951514 -273.375836)
			(xy 113.959639 -273.427131) (xy 113.960148 -273.453098) (xy 113.959639 -273.479065) (xy 114.239549 -273.479065)
			(xy 114.239549 -273.427131) (xy 114.247674 -273.375836) (xy 114.263722 -273.326443) (xy 114.2873 -273.280169)
			(xy 114.317826 -273.238153) (xy 114.354549 -273.20143) (xy 114.396565 -273.170904) (xy 114.442839 -273.147326)
			(xy 114.492232 -273.131278) (xy 114.543527 -273.123153) (xy 114.595461 -273.123153) (xy 114.646756 -273.131278)
			(xy 114.696149 -273.147326) (xy 114.742423 -273.170904) (xy 114.784439 -273.20143) (xy 114.821162 -273.238153)
			(xy 114.851688 -273.280169) (xy 114.875266 -273.326443) (xy 114.891314 -273.375836) (xy 114.899439 -273.427131)
			(xy 114.899948 -273.453098) (xy 114.899439 -273.479065) (xy 115.179349 -273.479065) (xy 115.179349 -273.427131)
			(xy 115.187474 -273.375836) (xy 115.203522 -273.326443) (xy 115.2271 -273.280169) (xy 115.257626 -273.238153)
			(xy 115.294349 -273.20143) (xy 115.336365 -273.170904) (xy 115.382639 -273.147326) (xy 115.432032 -273.131278)
			(xy 115.483327 -273.123153) (xy 115.535261 -273.123153) (xy 115.586556 -273.131278) (xy 115.635949 -273.147326)
			(xy 115.682223 -273.170904) (xy 115.724239 -273.20143) (xy 115.760962 -273.238153) (xy 115.791488 -273.280169)
			(xy 115.815066 -273.326443) (xy 115.831114 -273.375836) (xy 115.839239 -273.427131) (xy 115.839748 -273.453098)
			(xy 115.839239 -273.479065) (xy 116.119403 -273.479065) (xy 116.119403 -273.427131) (xy 116.127528 -273.375836)
			(xy 116.143576 -273.326443) (xy 116.167154 -273.280169) (xy 116.19768 -273.238153) (xy 116.234403 -273.20143)
			(xy 116.276419 -273.170904) (xy 116.322693 -273.147326) (xy 116.372086 -273.131278) (xy 116.423381 -273.123153)
			(xy 116.475315 -273.123153) (xy 116.52661 -273.131278) (xy 116.576003 -273.147326) (xy 116.622277 -273.170904)
			(xy 116.664293 -273.20143) (xy 116.701016 -273.238153) (xy 116.731542 -273.280169) (xy 116.75512 -273.326443)
			(xy 116.771168 -273.375836) (xy 116.779293 -273.427131) (xy 116.779802 -273.453098) (xy 116.779293 -273.479065)
			(xy 117.059203 -273.479065) (xy 117.059203 -273.427131) (xy 117.067328 -273.375836) (xy 117.083376 -273.326443)
			(xy 117.106954 -273.280169) (xy 117.13748 -273.238153) (xy 117.174203 -273.20143) (xy 117.216219 -273.170904)
			(xy 117.262493 -273.147326) (xy 117.311886 -273.131278) (xy 117.363181 -273.123153) (xy 117.415115 -273.123153)
			(xy 117.46641 -273.131278) (xy 117.515803 -273.147326) (xy 117.562077 -273.170904) (xy 117.604093 -273.20143)
			(xy 117.640816 -273.238153) (xy 117.671342 -273.280169) (xy 117.69492 -273.326443) (xy 117.710968 -273.375836)
			(xy 117.719093 -273.427131) (xy 117.719602 -273.453098) (xy 117.719093 -273.479065) (xy 117.710968 -273.53036)
			(xy 117.69492 -273.579753) (xy 117.671342 -273.626027) (xy 117.640816 -273.668043) (xy 117.604093 -273.704766)
			(xy 117.562077 -273.735292) (xy 117.515803 -273.75887) (xy 117.46641 -273.774918) (xy 117.415115 -273.783043)
			(xy 117.363181 -273.783043) (xy 117.311886 -273.774918) (xy 117.262493 -273.75887) (xy 117.216219 -273.735292)
			(xy 117.174203 -273.704766) (xy 117.13748 -273.668043) (xy 117.106954 -273.626027) (xy 117.083376 -273.579753)
			(xy 117.067328 -273.53036) (xy 117.059203 -273.479065) (xy 116.779293 -273.479065) (xy 116.771168 -273.53036)
			(xy 116.75512 -273.579753) (xy 116.731542 -273.626027) (xy 116.701016 -273.668043) (xy 116.664293 -273.704766)
			(xy 116.622277 -273.735292) (xy 116.576003 -273.75887) (xy 116.52661 -273.774918) (xy 116.475315 -273.783043)
			(xy 116.423381 -273.783043) (xy 116.372086 -273.774918) (xy 116.322693 -273.75887) (xy 116.276419 -273.735292)
			(xy 116.234403 -273.704766) (xy 116.19768 -273.668043) (xy 116.167154 -273.626027) (xy 116.143576 -273.579753)
			(xy 116.127528 -273.53036) (xy 116.119403 -273.479065) (xy 115.839239 -273.479065) (xy 115.831114 -273.53036)
			(xy 115.815066 -273.579753) (xy 115.791488 -273.626027) (xy 115.760962 -273.668043) (xy 115.724239 -273.704766)
			(xy 115.682223 -273.735292) (xy 115.635949 -273.75887) (xy 115.586556 -273.774918) (xy 115.535261 -273.783043)
			(xy 115.483327 -273.783043) (xy 115.432032 -273.774918) (xy 115.382639 -273.75887) (xy 115.336365 -273.735292)
			(xy 115.294349 -273.704766) (xy 115.257626 -273.668043) (xy 115.2271 -273.626027) (xy 115.203522 -273.579753)
			(xy 115.187474 -273.53036) (xy 115.179349 -273.479065) (xy 114.899439 -273.479065) (xy 114.891314 -273.53036)
			(xy 114.875266 -273.579753) (xy 114.851688 -273.626027) (xy 114.821162 -273.668043) (xy 114.784439 -273.704766)
			(xy 114.742423 -273.735292) (xy 114.696149 -273.75887) (xy 114.646756 -273.774918) (xy 114.595461 -273.783043)
			(xy 114.543527 -273.783043) (xy 114.492232 -273.774918) (xy 114.442839 -273.75887) (xy 114.396565 -273.735292)
			(xy 114.354549 -273.704766) (xy 114.317826 -273.668043) (xy 114.2873 -273.626027) (xy 114.263722 -273.579753)
			(xy 114.247674 -273.53036) (xy 114.239549 -273.479065) (xy 113.959639 -273.479065) (xy 113.951514 -273.53036)
			(xy 113.935466 -273.579753) (xy 113.911888 -273.626027) (xy 113.881362 -273.668043) (xy 113.844639 -273.704766)
			(xy 113.802623 -273.735292) (xy 113.756349 -273.75887) (xy 113.706956 -273.774918) (xy 113.655661 -273.783043)
			(xy 113.603727 -273.783043) (xy 113.552432 -273.774918) (xy 113.503039 -273.75887) (xy 113.456765 -273.735292)
			(xy 113.414749 -273.704766) (xy 113.378026 -273.668043) (xy 113.3475 -273.626027) (xy 113.323922 -273.579753)
			(xy 113.307874 -273.53036) (xy 113.299749 -273.479065) (xy 110.200421 -273.479065) (xy 110.192756 -273.528786)
			(xy 110.177398 -273.577266) (xy 110.154792 -273.622819) (xy 110.140496 -273.643852) (xy 110.132737 -273.655591)
			(xy 110.123367 -273.682112) (xy 110.121599 -273.710184) (xy 110.127565 -273.737672) (xy 110.140813 -273.762484)
			(xy 110.160335 -273.782735) (xy 110.184646 -273.796882) (xy 110.198154 -273.800824) (xy 110.234249 -273.810295)
			(xy 110.305413 -273.832786) (xy 110.340394 -273.845782) (xy 110.389199 -273.827743) (xy 110.489061 -273.798489)
			(xy 110.590914 -273.777178) (xy 110.694127 -273.763942) (xy 110.798062 -273.758862) (xy 110.902074 -273.76197)
			(xy 111.00552 -273.773247) (xy 111.107759 -273.792623) (xy 111.208158 -273.819978) (xy 111.306095 -273.855142)
			(xy 111.400965 -273.897898) (xy 111.446818 -273.92249) (xy 111.464852 -273.93265) (xy 111.473742 -273.937984)
			(xy 111.519455 -273.965127) (xy 111.606827 -274.02571) (xy 111.689046 -274.093122) (xy 111.765578 -274.166927)
			(xy 111.835928 -274.246646) (xy 111.870536 -274.292881) (xy 113.769649 -274.292881) (xy 113.769649 -274.240947)
			(xy 113.777774 -274.189652) (xy 113.793822 -274.140259) (xy 113.8174 -274.093985) (xy 113.847926 -274.051969)
			(xy 113.884649 -274.015246) (xy 113.926665 -273.98472) (xy 113.972939 -273.961142) (xy 114.022332 -273.945094)
			(xy 114.073627 -273.936969) (xy 114.125561 -273.936969) (xy 114.176856 -273.945094) (xy 114.226249 -273.961142)
			(xy 114.272523 -273.98472) (xy 114.314539 -274.015246) (xy 114.351262 -274.051969) (xy 114.381788 -274.093985)
			(xy 114.405366 -274.140259) (xy 114.421414 -274.189652) (xy 114.429539 -274.240947) (xy 114.430048 -274.266914)
			(xy 114.429539 -274.292881) (xy 114.709449 -274.292881) (xy 114.709449 -274.240947) (xy 114.717574 -274.189652)
			(xy 114.733622 -274.140259) (xy 114.7572 -274.093985) (xy 114.787726 -274.051969) (xy 114.824449 -274.015246)
			(xy 114.866465 -273.98472) (xy 114.912739 -273.961142) (xy 114.962132 -273.945094) (xy 115.013427 -273.936969)
			(xy 115.065361 -273.936969) (xy 115.116656 -273.945094) (xy 115.166049 -273.961142) (xy 115.212323 -273.98472)
			(xy 115.254339 -274.015246) (xy 115.291062 -274.051969) (xy 115.321588 -274.093985) (xy 115.345166 -274.140259)
			(xy 115.361214 -274.189652) (xy 115.369339 -274.240947) (xy 115.369848 -274.266914) (xy 115.369339 -274.292881)
			(xy 115.649503 -274.292881) (xy 115.649503 -274.240947) (xy 115.657628 -274.189652) (xy 115.673676 -274.140259)
			(xy 115.697254 -274.093985) (xy 115.72778 -274.051969) (xy 115.764503 -274.015246) (xy 115.806519 -273.98472)
			(xy 115.852793 -273.961142) (xy 115.902186 -273.945094) (xy 115.953481 -273.936969) (xy 116.005415 -273.936969)
			(xy 116.05671 -273.945094) (xy 116.106103 -273.961142) (xy 116.152377 -273.98472) (xy 116.194393 -274.015246)
			(xy 116.231116 -274.051969) (xy 116.261642 -274.093985) (xy 116.28522 -274.140259) (xy 116.301268 -274.189652)
			(xy 116.309393 -274.240947) (xy 116.309902 -274.266914) (xy 116.309393 -274.292881) (xy 116.589303 -274.292881)
			(xy 116.589303 -274.240947) (xy 116.597428 -274.189652) (xy 116.613476 -274.140259) (xy 116.637054 -274.093985)
			(xy 116.66758 -274.051969) (xy 116.704303 -274.015246) (xy 116.746319 -273.98472) (xy 116.792593 -273.961142)
			(xy 116.841986 -273.945094) (xy 116.893281 -273.936969) (xy 116.945215 -273.936969) (xy 116.99651 -273.945094)
			(xy 117.045903 -273.961142) (xy 117.092177 -273.98472) (xy 117.134193 -274.015246) (xy 117.170916 -274.051969)
			(xy 117.201442 -274.093985) (xy 117.22502 -274.140259) (xy 117.241068 -274.189652) (xy 117.249193 -274.240947)
			(xy 117.249702 -274.266914) (xy 117.249193 -274.292881) (xy 117.241068 -274.344176) (xy 117.22502 -274.393569)
			(xy 117.201442 -274.439843) (xy 117.170916 -274.481859) (xy 117.134193 -274.518582) (xy 117.092177 -274.549108)
			(xy 117.045903 -274.572686) (xy 116.99651 -274.588734) (xy 116.945215 -274.596859) (xy 116.893281 -274.596859)
			(xy 116.841986 -274.588734) (xy 116.792593 -274.572686) (xy 116.746319 -274.549108) (xy 116.704303 -274.518582)
			(xy 116.66758 -274.481859) (xy 116.637054 -274.439843) (xy 116.613476 -274.393569) (xy 116.597428 -274.344176)
			(xy 116.589303 -274.292881) (xy 116.309393 -274.292881) (xy 116.301268 -274.344176) (xy 116.28522 -274.393569)
			(xy 116.261642 -274.439843) (xy 116.231116 -274.481859) (xy 116.194393 -274.518582) (xy 116.152377 -274.549108)
			(xy 116.106103 -274.572686) (xy 116.05671 -274.588734) (xy 116.005415 -274.596859) (xy 115.953481 -274.596859)
			(xy 115.902186 -274.588734) (xy 115.852793 -274.572686) (xy 115.806519 -274.549108) (xy 115.764503 -274.518582)
			(xy 115.72778 -274.481859) (xy 115.697254 -274.439843) (xy 115.673676 -274.393569) (xy 115.657628 -274.344176)
			(xy 115.649503 -274.292881) (xy 115.369339 -274.292881) (xy 115.361214 -274.344176) (xy 115.345166 -274.393569)
			(xy 115.321588 -274.439843) (xy 115.291062 -274.481859) (xy 115.254339 -274.518582) (xy 115.212323 -274.549108)
			(xy 115.166049 -274.572686) (xy 115.116656 -274.588734) (xy 115.065361 -274.596859) (xy 115.013427 -274.596859)
			(xy 114.962132 -274.588734) (xy 114.912739 -274.572686) (xy 114.866465 -274.549108) (xy 114.824449 -274.518582)
			(xy 114.787726 -274.481859) (xy 114.7572 -274.439843) (xy 114.733622 -274.393569) (xy 114.717574 -274.344176)
			(xy 114.709449 -274.292881) (xy 114.429539 -274.292881) (xy 114.421414 -274.344176) (xy 114.405366 -274.393569)
			(xy 114.381788 -274.439843) (xy 114.351262 -274.481859) (xy 114.314539 -274.518582) (xy 114.272523 -274.549108)
			(xy 114.226249 -274.572686) (xy 114.176856 -274.588734) (xy 114.125561 -274.596859) (xy 114.073627 -274.596859)
			(xy 114.022332 -274.588734) (xy 113.972939 -274.572686) (xy 113.926665 -274.549108) (xy 113.884649 -274.518582)
			(xy 113.847926 -274.481859) (xy 113.8174 -274.439843) (xy 113.793822 -274.393569) (xy 113.777774 -274.344176)
			(xy 113.769649 -274.292881) (xy 111.870536 -274.292881) (xy 111.89964 -274.331764) (xy 111.956302 -274.421729)
			(xy 112.005547 -274.515959) (xy 112.047055 -274.613844) (xy 112.080559 -274.714749) (xy 112.105841 -274.818021)
			(xy 112.114838 -274.870418) (xy 112.155911 -274.904535) (xy 112.233013 -274.978413) (xy 112.303899 -275.058274)
			(xy 112.340338 -275.106697) (xy 113.299749 -275.106697) (xy 113.299749 -275.054763) (xy 113.307874 -275.003468)
			(xy 113.323922 -274.954075) (xy 113.3475 -274.907801) (xy 113.378026 -274.865785) (xy 113.414749 -274.829062)
			(xy 113.456765 -274.798536) (xy 113.503039 -274.774958) (xy 113.552432 -274.75891) (xy 113.603727 -274.750785)
			(xy 113.655661 -274.750785) (xy 113.706956 -274.75891) (xy 113.756349 -274.774958) (xy 113.802623 -274.798536)
			(xy 113.844639 -274.829062) (xy 113.881362 -274.865785) (xy 113.911888 -274.907801) (xy 113.935466 -274.954075)
			(xy 113.951514 -275.003468) (xy 113.959639 -275.054763) (xy 113.960148 -275.08073) (xy 113.959639 -275.106697)
			(xy 114.239295 -275.106697) (xy 114.239295 -275.054763) (xy 114.24742 -275.003468) (xy 114.263468 -274.954075)
			(xy 114.287046 -274.907801) (xy 114.317572 -274.865785) (xy 114.354295 -274.829062) (xy 114.396311 -274.798536)
			(xy 114.442585 -274.774958) (xy 114.491978 -274.75891) (xy 114.543273 -274.750785) (xy 114.595207 -274.750785)
			(xy 114.646502 -274.75891) (xy 114.695895 -274.774958) (xy 114.742169 -274.798536) (xy 114.784185 -274.829062)
			(xy 114.820908 -274.865785) (xy 114.851434 -274.907801) (xy 114.875012 -274.954075) (xy 114.89106 -275.003468)
			(xy 114.899185 -275.054763) (xy 114.899694 -275.08073) (xy 114.899185 -275.106697) (xy 115.179095 -275.106697)
			(xy 115.179095 -275.054763) (xy 115.18722 -275.003468) (xy 115.203268 -274.954075) (xy 115.226846 -274.907801)
			(xy 115.257372 -274.865785) (xy 115.294095 -274.829062) (xy 115.336111 -274.798536) (xy 115.382385 -274.774958)
			(xy 115.431778 -274.75891) (xy 115.483073 -274.750785) (xy 115.535007 -274.750785) (xy 115.586302 -274.75891)
			(xy 115.635695 -274.774958) (xy 115.681969 -274.798536) (xy 115.723985 -274.829062) (xy 115.760708 -274.865785)
			(xy 115.791234 -274.907801) (xy 115.814812 -274.954075) (xy 115.83086 -275.003468) (xy 115.838985 -275.054763)
			(xy 115.839494 -275.08073) (xy 115.838985 -275.106697) (xy 116.119149 -275.106697) (xy 116.119149 -275.054763)
			(xy 116.127274 -275.003468) (xy 116.143322 -274.954075) (xy 116.1669 -274.907801) (xy 116.197426 -274.865785)
			(xy 116.234149 -274.829062) (xy 116.276165 -274.798536) (xy 116.322439 -274.774958) (xy 116.371832 -274.75891)
			(xy 116.423127 -274.750785) (xy 116.475061 -274.750785) (xy 116.526356 -274.75891) (xy 116.575749 -274.774958)
			(xy 116.622023 -274.798536) (xy 116.664039 -274.829062) (xy 116.700762 -274.865785) (xy 116.731288 -274.907801)
			(xy 116.754866 -274.954075) (xy 116.770914 -275.003468) (xy 116.779039 -275.054763) (xy 116.779548 -275.08073)
			(xy 116.779039 -275.106697) (xy 117.059203 -275.106697) (xy 117.059203 -275.054763) (xy 117.067328 -275.003468)
			(xy 117.083376 -274.954075) (xy 117.106954 -274.907801) (xy 117.13748 -274.865785) (xy 117.174203 -274.829062)
			(xy 117.216219 -274.798536) (xy 117.262493 -274.774958) (xy 117.311886 -274.75891) (xy 117.363181 -274.750785)
			(xy 117.415115 -274.750785) (xy 117.46641 -274.75891) (xy 117.515803 -274.774958) (xy 117.562077 -274.798536)
			(xy 117.604093 -274.829062) (xy 117.640816 -274.865785) (xy 117.671342 -274.907801) (xy 117.69492 -274.954075)
			(xy 117.710968 -275.003468) (xy 117.719093 -275.054763) (xy 117.719602 -275.08073) (xy 117.719093 -275.106697)
			(xy 117.710968 -275.157992) (xy 117.69492 -275.207385) (xy 117.671342 -275.253659) (xy 117.640816 -275.295675)
			(xy 117.604093 -275.332398) (xy 117.562077 -275.362924) (xy 117.515803 -275.386502) (xy 117.46641 -275.40255)
			(xy 117.415115 -275.410675) (xy 117.363181 -275.410675) (xy 117.311886 -275.40255) (xy 117.262493 -275.386502)
			(xy 117.216219 -275.362924) (xy 117.174203 -275.332398) (xy 117.13748 -275.295675) (xy 117.106954 -275.253659)
			(xy 117.083376 -275.207385) (xy 117.067328 -275.157992) (xy 117.059203 -275.106697) (xy 116.779039 -275.106697)
			(xy 116.770914 -275.157992) (xy 116.754866 -275.207385) (xy 116.731288 -275.253659) (xy 116.700762 -275.295675)
			(xy 116.664039 -275.332398) (xy 116.622023 -275.362924) (xy 116.575749 -275.386502) (xy 116.526356 -275.40255)
			(xy 116.475061 -275.410675) (xy 116.423127 -275.410675) (xy 116.371832 -275.40255) (xy 116.322439 -275.386502)
			(xy 116.276165 -275.362924) (xy 116.234149 -275.332398) (xy 116.197426 -275.295675) (xy 116.1669 -275.253659)
			(xy 116.143322 -275.207385) (xy 116.127274 -275.157992) (xy 116.119149 -275.106697) (xy 115.838985 -275.106697)
			(xy 115.83086 -275.157992) (xy 115.814812 -275.207385) (xy 115.791234 -275.253659) (xy 115.760708 -275.295675)
			(xy 115.723985 -275.332398) (xy 115.681969 -275.362924) (xy 115.635695 -275.386502) (xy 115.586302 -275.40255)
			(xy 115.535007 -275.410675) (xy 115.483073 -275.410675) (xy 115.431778 -275.40255) (xy 115.382385 -275.386502)
			(xy 115.336111 -275.362924) (xy 115.294095 -275.332398) (xy 115.257372 -275.295675) (xy 115.226846 -275.253659)
			(xy 115.203268 -275.207385) (xy 115.18722 -275.157992) (xy 115.179095 -275.106697) (xy 114.899185 -275.106697)
			(xy 114.89106 -275.157992) (xy 114.875012 -275.207385) (xy 114.851434 -275.253659) (xy 114.820908 -275.295675)
			(xy 114.784185 -275.332398) (xy 114.742169 -275.362924) (xy 114.695895 -275.386502) (xy 114.646502 -275.40255)
			(xy 114.595207 -275.410675) (xy 114.543273 -275.410675) (xy 114.491978 -275.40255) (xy 114.442585 -275.386502)
			(xy 114.396311 -275.362924) (xy 114.354295 -275.332398) (xy 114.317572 -275.295675) (xy 114.287046 -275.253659)
			(xy 114.263468 -275.207385) (xy 114.24742 -275.157992) (xy 114.239295 -275.106697) (xy 113.959639 -275.106697)
			(xy 113.951514 -275.157992) (xy 113.935466 -275.207385) (xy 113.911888 -275.253659) (xy 113.881362 -275.295675)
			(xy 113.844639 -275.332398) (xy 113.802623 -275.362924) (xy 113.756349 -275.386502) (xy 113.706956 -275.40255)
			(xy 113.655661 -275.410675) (xy 113.603727 -275.410675) (xy 113.552432 -275.40255) (xy 113.503039 -275.386502)
			(xy 113.456765 -275.362924) (xy 113.414749 -275.332398) (xy 113.378026 -275.295675) (xy 113.3475 -275.253659)
			(xy 113.323922 -275.207385) (xy 113.307874 -275.157992) (xy 113.299749 -275.106697) (xy 112.340338 -275.106697)
			(xy 112.368106 -275.143597) (xy 112.425216 -275.233825) (xy 112.474856 -275.328369) (xy 112.516702 -275.426612)
			(xy 112.55048 -275.527911) (xy 112.57597 -275.631608) (xy 112.584992 -275.684234) (xy 112.626037 -275.718362)
			(xy 112.703081 -275.792258) (xy 112.773908 -275.872132) (xy 112.810471 -275.920767) (xy 113.769903 -275.920767)
			(xy 113.769903 -275.868833) (xy 113.778028 -275.817538) (xy 113.794076 -275.768145) (xy 113.817654 -275.721871)
			(xy 113.84818 -275.679855) (xy 113.884903 -275.643132) (xy 113.926919 -275.612606) (xy 113.973193 -275.589028)
			(xy 114.022586 -275.57298) (xy 114.073881 -275.564855) (xy 114.125815 -275.564855) (xy 114.17711 -275.57298)
			(xy 114.226503 -275.589028) (xy 114.272777 -275.612606) (xy 114.314793 -275.643132) (xy 114.351516 -275.679855)
			(xy 114.382042 -275.721871) (xy 114.40562 -275.768145) (xy 114.421668 -275.817538) (xy 114.429793 -275.868833)
			(xy 114.430302 -275.8948) (xy 114.429793 -275.920767) (xy 114.709449 -275.920767) (xy 114.709449 -275.868833)
			(xy 114.717574 -275.817538) (xy 114.733622 -275.768145) (xy 114.7572 -275.721871) (xy 114.787726 -275.679855)
			(xy 114.824449 -275.643132) (xy 114.866465 -275.612606) (xy 114.912739 -275.589028) (xy 114.962132 -275.57298)
			(xy 115.013427 -275.564855) (xy 115.065361 -275.564855) (xy 115.116656 -275.57298) (xy 115.166049 -275.589028)
			(xy 115.212323 -275.612606) (xy 115.254339 -275.643132) (xy 115.291062 -275.679855) (xy 115.321588 -275.721871)
			(xy 115.345166 -275.768145) (xy 115.361214 -275.817538) (xy 115.369339 -275.868833) (xy 115.369848 -275.8948)
			(xy 115.369339 -275.920767) (xy 115.649249 -275.920767) (xy 115.649249 -275.868833) (xy 115.657374 -275.817538)
			(xy 115.673422 -275.768145) (xy 115.697 -275.721871) (xy 115.727526 -275.679855) (xy 115.764249 -275.643132)
			(xy 115.806265 -275.612606) (xy 115.852539 -275.589028) (xy 115.901932 -275.57298) (xy 115.953227 -275.564855)
			(xy 116.005161 -275.564855) (xy 116.056456 -275.57298) (xy 116.105849 -275.589028) (xy 116.152123 -275.612606)
			(xy 116.194139 -275.643132) (xy 116.230862 -275.679855) (xy 116.261388 -275.721871) (xy 116.284966 -275.768145)
			(xy 116.301014 -275.817538) (xy 116.309139 -275.868833) (xy 116.309648 -275.8948) (xy 116.309139 -275.920767)
			(xy 116.589049 -275.920767) (xy 116.589049 -275.868833) (xy 116.597174 -275.817538) (xy 116.613222 -275.768145)
			(xy 116.6368 -275.721871) (xy 116.667326 -275.679855) (xy 116.704049 -275.643132) (xy 116.746065 -275.612606)
			(xy 116.792339 -275.589028) (xy 116.841732 -275.57298) (xy 116.893027 -275.564855) (xy 116.944961 -275.564855)
			(xy 116.996256 -275.57298) (xy 117.045649 -275.589028) (xy 117.091923 -275.612606) (xy 117.133939 -275.643132)
			(xy 117.170662 -275.679855) (xy 117.201188 -275.721871) (xy 117.224766 -275.768145) (xy 117.240814 -275.817538)
			(xy 117.248939 -275.868833) (xy 117.249448 -275.8948) (xy 117.248939 -275.920767) (xy 117.240814 -275.972062)
			(xy 117.224766 -276.021455) (xy 117.201188 -276.067729) (xy 117.170662 -276.109745) (xy 117.133939 -276.146468)
			(xy 117.091923 -276.176994) (xy 117.045649 -276.200572) (xy 116.996256 -276.21662) (xy 116.944961 -276.224745)
			(xy 116.893027 -276.224745) (xy 116.841732 -276.21662) (xy 116.792339 -276.200572) (xy 116.746065 -276.176994)
			(xy 116.704049 -276.146468) (xy 116.667326 -276.109745) (xy 116.6368 -276.067729) (xy 116.613222 -276.021455)
			(xy 116.597174 -275.972062) (xy 116.589049 -275.920767) (xy 116.309139 -275.920767) (xy 116.301014 -275.972062)
			(xy 116.284966 -276.021455) (xy 116.261388 -276.067729) (xy 116.230862 -276.109745) (xy 116.194139 -276.146468)
			(xy 116.152123 -276.176994) (xy 116.105849 -276.200572) (xy 116.056456 -276.21662) (xy 116.005161 -276.224745)
			(xy 115.953227 -276.224745) (xy 115.901932 -276.21662) (xy 115.852539 -276.200572) (xy 115.806265 -276.176994)
			(xy 115.764249 -276.146468) (xy 115.727526 -276.109745) (xy 115.697 -276.067729) (xy 115.673422 -276.021455)
			(xy 115.657374 -275.972062) (xy 115.649249 -275.920767) (xy 115.369339 -275.920767) (xy 115.361214 -275.972062)
			(xy 115.345166 -276.021455) (xy 115.321588 -276.067729) (xy 115.291062 -276.109745) (xy 115.254339 -276.146468)
			(xy 115.212323 -276.176994) (xy 115.166049 -276.200572) (xy 115.116656 -276.21662) (xy 115.065361 -276.224745)
			(xy 115.013427 -276.224745) (xy 114.962132 -276.21662) (xy 114.912739 -276.200572) (xy 114.866465 -276.176994)
			(xy 114.824449 -276.146468) (xy 114.787726 -276.109745) (xy 114.7572 -276.067729) (xy 114.733622 -276.021455)
			(xy 114.717574 -275.972062) (xy 114.709449 -275.920767) (xy 114.429793 -275.920767) (xy 114.421668 -275.972062)
			(xy 114.40562 -276.021455) (xy 114.382042 -276.067729) (xy 114.351516 -276.109745) (xy 114.314793 -276.146468)
			(xy 114.272777 -276.176994) (xy 114.226503 -276.200572) (xy 114.17711 -276.21662) (xy 114.125815 -276.224745)
			(xy 114.073881 -276.224745) (xy 114.022586 -276.21662) (xy 113.973193 -276.200572) (xy 113.926919 -276.176994)
			(xy 113.884903 -276.146468) (xy 113.84818 -276.109745) (xy 113.817654 -276.067729) (xy 113.794076 -276.021455)
			(xy 113.778028 -275.972062) (xy 113.769903 -275.920767) (xy 112.810471 -275.920767) (xy 112.838057 -275.957462)
			(xy 112.895108 -276.047692) (xy 112.94469 -276.142233) (xy 112.986479 -276.240468) (xy 113.020202 -276.341756)
			(xy 113.045638 -276.445435) (xy 113.054638 -276.49805) (xy 113.095632 -276.532109) (xy 113.17259 -276.605855)
			(xy 113.243356 -276.685562) (xy 113.280266 -276.734583) (xy 114.239803 -276.734583) (xy 114.239803 -276.682649)
			(xy 114.247928 -276.631354) (xy 114.263976 -276.581961) (xy 114.287554 -276.535687) (xy 114.31808 -276.493671)
			(xy 114.354803 -276.456948) (xy 114.396819 -276.426422) (xy 114.443093 -276.402844) (xy 114.492486 -276.386796)
			(xy 114.543781 -276.378671) (xy 114.595715 -276.378671) (xy 114.64701 -276.386796) (xy 114.696403 -276.402844)
			(xy 114.742677 -276.426422) (xy 114.784693 -276.456948) (xy 114.821416 -276.493671) (xy 114.851942 -276.535687)
			(xy 114.87552 -276.581961) (xy 114.891568 -276.631354) (xy 114.899693 -276.682649) (xy 114.900202 -276.708616)
			(xy 114.899698 -276.734329) (xy 115.179349 -276.734329) (xy 115.179349 -276.682395) (xy 115.187474 -276.6311)
			(xy 115.203522 -276.581707) (xy 115.2271 -276.535433) (xy 115.257626 -276.493417) (xy 115.294349 -276.456694)
			(xy 115.336365 -276.426168) (xy 115.382639 -276.40259) (xy 115.432032 -276.386542) (xy 115.483327 -276.378417)
			(xy 115.535261 -276.378417) (xy 115.586556 -276.386542) (xy 115.635949 -276.40259) (xy 115.682223 -276.426168)
			(xy 115.724239 -276.456694) (xy 115.760962 -276.493417) (xy 115.791488 -276.535433) (xy 115.815066 -276.581707)
			(xy 115.831114 -276.6311) (xy 115.839239 -276.682395) (xy 115.839748 -276.708362) (xy 115.839239 -276.734329)
			(xy 116.119149 -276.734329) (xy 116.119149 -276.682395) (xy 116.127274 -276.6311) (xy 116.143322 -276.581707)
			(xy 116.1669 -276.535433) (xy 116.197426 -276.493417) (xy 116.234149 -276.456694) (xy 116.276165 -276.426168)
			(xy 116.322439 -276.40259) (xy 116.371832 -276.386542) (xy 116.423127 -276.378417) (xy 116.475061 -276.378417)
			(xy 116.526356 -276.386542) (xy 116.575749 -276.40259) (xy 116.622023 -276.426168) (xy 116.664039 -276.456694)
			(xy 116.700762 -276.493417) (xy 116.731288 -276.535433) (xy 116.754866 -276.581707) (xy 116.770914 -276.6311)
			(xy 116.779039 -276.682395) (xy 116.779548 -276.708362) (xy 116.779039 -276.734329) (xy 117.058949 -276.734329)
			(xy 117.058949 -276.682395) (xy 117.067074 -276.6311) (xy 117.083122 -276.581707) (xy 117.1067 -276.535433)
			(xy 117.137226 -276.493417) (xy 117.173949 -276.456694) (xy 117.215965 -276.426168) (xy 117.262239 -276.40259)
			(xy 117.311632 -276.386542) (xy 117.362927 -276.378417) (xy 117.414861 -276.378417) (xy 117.466156 -276.386542)
			(xy 117.515549 -276.40259) (xy 117.561823 -276.426168) (xy 117.603839 -276.456694) (xy 117.640562 -276.493417)
			(xy 117.671088 -276.535433) (xy 117.694666 -276.581707) (xy 117.710714 -276.6311) (xy 117.718839 -276.682395)
			(xy 117.719348 -276.708362) (xy 117.718839 -276.734329) (xy 117.710714 -276.785624) (xy 117.694666 -276.835017)
			(xy 117.671088 -276.881291) (xy 117.640562 -276.923307) (xy 117.603839 -276.96003) (xy 117.561823 -276.990556)
			(xy 117.515549 -277.014134) (xy 117.466156 -277.030182) (xy 117.414861 -277.038307) (xy 117.362927 -277.038307)
			(xy 117.311632 -277.030182) (xy 117.262239 -277.014134) (xy 117.215965 -276.990556) (xy 117.173949 -276.96003)
			(xy 117.137226 -276.923307) (xy 117.1067 -276.881291) (xy 117.083122 -276.835017) (xy 117.067074 -276.785624)
			(xy 117.058949 -276.734329) (xy 116.779039 -276.734329) (xy 116.770914 -276.785624) (xy 116.754866 -276.835017)
			(xy 116.731288 -276.881291) (xy 116.700762 -276.923307) (xy 116.664039 -276.96003) (xy 116.622023 -276.990556)
			(xy 116.575749 -277.014134) (xy 116.526356 -277.030182) (xy 116.475061 -277.038307) (xy 116.423127 -277.038307)
			(xy 116.371832 -277.030182) (xy 116.322439 -277.014134) (xy 116.276165 -276.990556) (xy 116.234149 -276.96003)
			(xy 116.197426 -276.923307) (xy 116.1669 -276.881291) (xy 116.143322 -276.835017) (xy 116.127274 -276.785624)
			(xy 116.119149 -276.734329) (xy 115.839239 -276.734329) (xy 115.831114 -276.785624) (xy 115.815066 -276.835017)
			(xy 115.791488 -276.881291) (xy 115.760962 -276.923307) (xy 115.724239 -276.96003) (xy 115.682223 -276.990556)
			(xy 115.635949 -277.014134) (xy 115.586556 -277.030182) (xy 115.535261 -277.038307) (xy 115.483327 -277.038307)
			(xy 115.432032 -277.030182) (xy 115.382639 -277.014134) (xy 115.336365 -276.990556) (xy 115.294349 -276.96003)
			(xy 115.257626 -276.923307) (xy 115.2271 -276.881291) (xy 115.203522 -276.835017) (xy 115.187474 -276.785624)
			(xy 115.179349 -276.734329) (xy 114.899698 -276.734329) (xy 114.899693 -276.734583) (xy 114.891568 -276.785878)
			(xy 114.87552 -276.835271) (xy 114.851942 -276.881545) (xy 114.821416 -276.923561) (xy 114.784693 -276.960284)
			(xy 114.742677 -276.99081) (xy 114.696403 -277.014388) (xy 114.64701 -277.030436) (xy 114.595715 -277.038561)
			(xy 114.543781 -277.038561) (xy 114.492486 -277.030436) (xy 114.443093 -277.014388) (xy 114.396819 -276.99081)
			(xy 114.354803 -276.960284) (xy 114.31808 -276.923561) (xy 114.287554 -276.881545) (xy 114.263976 -276.835271)
			(xy 114.247928 -276.785878) (xy 114.239803 -276.734583) (xy 113.280266 -276.734583) (xy 113.307469 -276.770712)
			(xy 113.364512 -276.860751) (xy 113.414115 -276.955094) (xy 113.455954 -277.053127) (xy 113.489758 -277.154213)
			(xy 113.515306 -277.257694) (xy 113.532433 -277.362897) (xy 113.541027 -277.469138) (xy 113.541556 -277.522432)
			(xy 113.541556 -277.536656) (xy 113.541399 -277.548399) (xy 114.709449 -277.548399) (xy 114.709449 -277.496465)
			(xy 114.717574 -277.44517) (xy 114.733622 -277.395777) (xy 114.7572 -277.349503) (xy 114.787726 -277.307487)
			(xy 114.824449 -277.270764) (xy 114.866465 -277.240238) (xy 114.912739 -277.21666) (xy 114.962132 -277.200612)
			(xy 115.013427 -277.192487) (xy 115.065361 -277.192487) (xy 115.116656 -277.200612) (xy 115.166049 -277.21666)
			(xy 115.212323 -277.240238) (xy 115.254339 -277.270764) (xy 115.291062 -277.307487) (xy 115.321588 -277.349503)
			(xy 115.345166 -277.395777) (xy 115.361214 -277.44517) (xy 115.369339 -277.496465) (xy 115.369848 -277.522432)
			(xy 115.369344 -277.548145) (xy 115.649503 -277.548145) (xy 115.649503 -277.496211) (xy 115.657628 -277.444916)
			(xy 115.673676 -277.395523) (xy 115.697254 -277.349249) (xy 115.72778 -277.307233) (xy 115.764503 -277.27051)
			(xy 115.806519 -277.239984) (xy 115.852793 -277.216406) (xy 115.902186 -277.200358) (xy 115.953481 -277.192233)
			(xy 116.005415 -277.192233) (xy 116.05671 -277.200358) (xy 116.106103 -277.216406) (xy 116.152377 -277.239984)
			(xy 116.194393 -277.27051) (xy 116.231116 -277.307233) (xy 116.261642 -277.349249) (xy 116.28522 -277.395523)
			(xy 116.301268 -277.444916) (xy 116.309393 -277.496211) (xy 116.309902 -277.522178) (xy 116.309393 -277.548145)
			(xy 116.309353 -277.548399) (xy 116.589049 -277.548399) (xy 116.589049 -277.496465) (xy 116.597174 -277.44517)
			(xy 116.613222 -277.395777) (xy 116.6368 -277.349503) (xy 116.667326 -277.307487) (xy 116.704049 -277.270764)
			(xy 116.746065 -277.240238) (xy 116.792339 -277.21666) (xy 116.841732 -277.200612) (xy 116.893027 -277.192487)
			(xy 116.944961 -277.192487) (xy 116.996256 -277.200612) (xy 117.045649 -277.21666) (xy 117.091923 -277.240238)
			(xy 117.133939 -277.270764) (xy 117.170662 -277.307487) (xy 117.201188 -277.349503) (xy 117.224766 -277.395777)
			(xy 117.240814 -277.44517) (xy 117.248939 -277.496465) (xy 117.249448 -277.522432) (xy 117.248939 -277.548399)
			(xy 117.240814 -277.599694) (xy 117.224766 -277.649087) (xy 117.201188 -277.695361) (xy 117.170662 -277.737377)
			(xy 117.133939 -277.7741) (xy 117.091923 -277.804626) (xy 117.045649 -277.828204) (xy 116.996256 -277.844252)
			(xy 116.944961 -277.852377) (xy 116.893027 -277.852377) (xy 116.841732 -277.844252) (xy 116.792339 -277.828204)
			(xy 116.746065 -277.804626) (xy 116.704049 -277.7741) (xy 116.667326 -277.737377) (xy 116.6368 -277.695361)
			(xy 116.613222 -277.649087) (xy 116.597174 -277.599694) (xy 116.589049 -277.548399) (xy 116.309353 -277.548399)
			(xy 116.301268 -277.59944) (xy 116.28522 -277.648833) (xy 116.261642 -277.695107) (xy 116.231116 -277.737123)
			(xy 116.194393 -277.773846) (xy 116.152377 -277.804372) (xy 116.106103 -277.82795) (xy 116.05671 -277.843998)
			(xy 116.005415 -277.852123) (xy 115.953481 -277.852123) (xy 115.902186 -277.843998) (xy 115.852793 -277.82795)
			(xy 115.806519 -277.804372) (xy 115.764503 -277.773846) (xy 115.72778 -277.737123) (xy 115.697254 -277.695107)
			(xy 115.673676 -277.648833) (xy 115.657628 -277.59944) (xy 115.649503 -277.548145) (xy 115.369344 -277.548145)
			(xy 115.369339 -277.548399) (xy 115.361214 -277.599694) (xy 115.345166 -277.649087) (xy 115.321588 -277.695361)
			(xy 115.291062 -277.737377) (xy 115.254339 -277.7741) (xy 115.212323 -277.804626) (xy 115.166049 -277.828204)
			(xy 115.116656 -277.844252) (xy 115.065361 -277.852377) (xy 115.013427 -277.852377) (xy 114.962132 -277.844252)
			(xy 114.912739 -277.828204) (xy 114.866465 -277.804626) (xy 114.824449 -277.7741) (xy 114.787726 -277.737377)
			(xy 114.7572 -277.695361) (xy 114.733622 -277.649087) (xy 114.717574 -277.599694) (xy 114.709449 -277.548399)
			(xy 113.541399 -277.548399) (xy 113.541302 -277.555706) (xy 113.539451 -277.608428) (xy 113.528376 -277.713349)
			(xy 113.508966 -277.817053) (xy 113.481344 -277.918877) (xy 113.445687 -278.018173) (xy 113.402222 -278.114308)
			(xy 113.351225 -278.206668) (xy 113.293022 -278.294665) (xy 113.260886 -278.336502) (xy 113.280791 -278.362469)
			(xy 114.239803 -278.362469) (xy 114.239803 -278.310535) (xy 114.247928 -278.25924) (xy 114.263976 -278.209847)
			(xy 114.287554 -278.163573) (xy 114.31808 -278.121557) (xy 114.354803 -278.084834) (xy 114.396819 -278.054308)
			(xy 114.443093 -278.03073) (xy 114.492486 -278.014682) (xy 114.543781 -278.006557) (xy 114.595715 -278.006557)
			(xy 114.64701 -278.014682) (xy 114.696403 -278.03073) (xy 114.742677 -278.054308) (xy 114.784693 -278.084834)
			(xy 114.821416 -278.121557) (xy 114.851942 -278.163573) (xy 114.87552 -278.209847) (xy 114.891568 -278.25924)
			(xy 114.899693 -278.310535) (xy 114.900202 -278.336502) (xy 114.899698 -278.362215) (xy 115.179349 -278.362215)
			(xy 115.179349 -278.310281) (xy 115.187474 -278.258986) (xy 115.203522 -278.209593) (xy 115.2271 -278.163319)
			(xy 115.257626 -278.121303) (xy 115.294349 -278.08458) (xy 115.336365 -278.054054) (xy 115.382639 -278.030476)
			(xy 115.432032 -278.014428) (xy 115.483327 -278.006303) (xy 115.535261 -278.006303) (xy 115.586556 -278.014428)
			(xy 115.635949 -278.030476) (xy 115.682223 -278.054054) (xy 115.724239 -278.08458) (xy 115.760962 -278.121303)
			(xy 115.791488 -278.163319) (xy 115.815066 -278.209593) (xy 115.831114 -278.258986) (xy 115.839239 -278.310281)
			(xy 115.839748 -278.336248) (xy 115.839239 -278.362215) (xy 116.119149 -278.362215) (xy 116.119149 -278.310281)
			(xy 116.127274 -278.258986) (xy 116.143322 -278.209593) (xy 116.1669 -278.163319) (xy 116.197426 -278.121303)
			(xy 116.234149 -278.08458) (xy 116.276165 -278.054054) (xy 116.322439 -278.030476) (xy 116.371832 -278.014428)
			(xy 116.423127 -278.006303) (xy 116.475061 -278.006303) (xy 116.526356 -278.014428) (xy 116.575749 -278.030476)
			(xy 116.622023 -278.054054) (xy 116.664039 -278.08458) (xy 116.700762 -278.121303) (xy 116.731288 -278.163319)
			(xy 116.754866 -278.209593) (xy 116.770914 -278.258986) (xy 116.779039 -278.310281) (xy 116.779548 -278.336248)
			(xy 116.779039 -278.362215) (xy 117.058949 -278.362215) (xy 117.058949 -278.310281) (xy 117.067074 -278.258986)
			(xy 117.083122 -278.209593) (xy 117.1067 -278.163319) (xy 117.137226 -278.121303) (xy 117.173949 -278.08458)
			(xy 117.215965 -278.054054) (xy 117.262239 -278.030476) (xy 117.311632 -278.014428) (xy 117.362927 -278.006303)
			(xy 117.414861 -278.006303) (xy 117.466156 -278.014428) (xy 117.515549 -278.030476) (xy 117.561823 -278.054054)
			(xy 117.603839 -278.08458) (xy 117.640562 -278.121303) (xy 117.671088 -278.163319) (xy 117.694666 -278.209593)
			(xy 117.710714 -278.258986) (xy 117.718839 -278.310281) (xy 117.719348 -278.336248) (xy 117.718839 -278.362215)
			(xy 117.710714 -278.41351) (xy 117.694666 -278.462903) (xy 117.671088 -278.509177) (xy 117.640562 -278.551193)
			(xy 117.603839 -278.587916) (xy 117.561823 -278.618442) (xy 117.515549 -278.64202) (xy 117.466156 -278.658068)
			(xy 117.414861 -278.666193) (xy 117.362927 -278.666193) (xy 117.311632 -278.658068) (xy 117.262239 -278.64202)
			(xy 117.215965 -278.618442) (xy 117.173949 -278.587916) (xy 117.137226 -278.551193) (xy 117.1067 -278.509177)
			(xy 117.083122 -278.462903) (xy 117.067074 -278.41351) (xy 117.058949 -278.362215) (xy 116.779039 -278.362215)
			(xy 116.770914 -278.41351) (xy 116.754866 -278.462903) (xy 116.731288 -278.509177) (xy 116.700762 -278.551193)
			(xy 116.664039 -278.587916) (xy 116.622023 -278.618442) (xy 116.575749 -278.64202) (xy 116.526356 -278.658068)
			(xy 116.475061 -278.666193) (xy 116.423127 -278.666193) (xy 116.371832 -278.658068) (xy 116.322439 -278.64202)
			(xy 116.276165 -278.618442) (xy 116.234149 -278.587916) (xy 116.197426 -278.551193) (xy 116.1669 -278.509177)
			(xy 116.143322 -278.462903) (xy 116.127274 -278.41351) (xy 116.119149 -278.362215) (xy 115.839239 -278.362215)
			(xy 115.831114 -278.41351) (xy 115.815066 -278.462903) (xy 115.791488 -278.509177) (xy 115.760962 -278.551193)
			(xy 115.724239 -278.587916) (xy 115.682223 -278.618442) (xy 115.635949 -278.64202) (xy 115.586556 -278.658068)
			(xy 115.535261 -278.666193) (xy 115.483327 -278.666193) (xy 115.432032 -278.658068) (xy 115.382639 -278.64202)
			(xy 115.336365 -278.618442) (xy 115.294349 -278.587916) (xy 115.257626 -278.551193) (xy 115.2271 -278.509177)
			(xy 115.203522 -278.462903) (xy 115.187474 -278.41351) (xy 115.179349 -278.362215) (xy 114.899698 -278.362215)
			(xy 114.899693 -278.362469) (xy 114.891568 -278.413764) (xy 114.87552 -278.463157) (xy 114.851942 -278.509431)
			(xy 114.821416 -278.551447) (xy 114.784693 -278.58817) (xy 114.742677 -278.618696) (xy 114.696403 -278.642274)
			(xy 114.64701 -278.658322) (xy 114.595715 -278.666447) (xy 114.543781 -278.666447) (xy 114.492486 -278.658322)
			(xy 114.443093 -278.642274) (xy 114.396819 -278.618696) (xy 114.354803 -278.58817) (xy 114.31808 -278.551447)
			(xy 114.287554 -278.509431) (xy 114.263976 -278.463157) (xy 114.247928 -278.413764) (xy 114.239803 -278.362469)
			(xy 113.280791 -278.362469) (xy 113.292256 -278.377426) (xy 113.349249 -278.46337) (xy 113.399367 -278.553496)
			(xy 113.442303 -278.647256) (xy 113.477796 -278.744079) (xy 113.505631 -278.843375) (xy 113.525637 -278.94454)
			(xy 113.537693 -279.046956) (xy 113.541725 -279.150001) (xy 113.5407 -279.176285) (xy 114.709449 -279.176285)
			(xy 114.709449 -279.124351) (xy 114.717574 -279.073056) (xy 114.733622 -279.023663) (xy 114.7572 -278.977389)
			(xy 114.787726 -278.935373) (xy 114.824449 -278.89865) (xy 114.866465 -278.868124) (xy 114.912739 -278.844546)
			(xy 114.962132 -278.828498) (xy 115.013427 -278.820373) (xy 115.065361 -278.820373) (xy 115.116656 -278.828498)
			(xy 115.166049 -278.844546) (xy 115.212323 -278.868124) (xy 115.254339 -278.89865) (xy 115.291062 -278.935373)
			(xy 115.321588 -278.977389) (xy 115.345166 -279.023663) (xy 115.361214 -279.073056) (xy 115.369339 -279.124351)
			(xy 115.369848 -279.150318) (xy 115.369339 -279.176285) (xy 115.649249 -279.176285) (xy 115.649249 -279.124351)
			(xy 115.657374 -279.073056) (xy 115.673422 -279.023663) (xy 115.697 -278.977389) (xy 115.727526 -278.935373)
			(xy 115.764249 -278.89865) (xy 115.806265 -278.868124) (xy 115.852539 -278.844546) (xy 115.901932 -278.828498)
			(xy 115.953227 -278.820373) (xy 116.005161 -278.820373) (xy 116.056456 -278.828498) (xy 116.105849 -278.844546)
			(xy 116.152123 -278.868124) (xy 116.194139 -278.89865) (xy 116.230862 -278.935373) (xy 116.261388 -278.977389)
			(xy 116.284966 -279.023663) (xy 116.301014 -279.073056) (xy 116.309139 -279.124351) (xy 116.309648 -279.150318)
			(xy 116.309144 -279.176031) (xy 116.589303 -279.176031) (xy 116.589303 -279.124097) (xy 116.597428 -279.072802)
			(xy 116.613476 -279.023409) (xy 116.637054 -278.977135) (xy 116.66758 -278.935119) (xy 116.704303 -278.898396)
			(xy 116.746319 -278.86787) (xy 116.792593 -278.844292) (xy 116.841986 -278.828244) (xy 116.893281 -278.820119)
			(xy 116.945215 -278.820119) (xy 116.99651 -278.828244) (xy 117.045903 -278.844292) (xy 117.092177 -278.86787)
			(xy 117.134193 -278.898396) (xy 117.170916 -278.935119) (xy 117.201442 -278.977135) (xy 117.22502 -279.023409)
			(xy 117.241068 -279.072802) (xy 117.249193 -279.124097) (xy 117.249702 -279.150064) (xy 117.249193 -279.176031)
			(xy 117.241068 -279.227326) (xy 117.22502 -279.276719) (xy 117.201442 -279.322993) (xy 117.170916 -279.365009)
			(xy 117.134193 -279.401732) (xy 117.092177 -279.432258) (xy 117.045903 -279.455836) (xy 116.99651 -279.471884)
			(xy 116.945215 -279.480009) (xy 116.893281 -279.480009) (xy 116.841986 -279.471884) (xy 116.792593 -279.455836)
			(xy 116.746319 -279.432258) (xy 116.704303 -279.401732) (xy 116.66758 -279.365009) (xy 116.637054 -279.322993)
			(xy 116.613476 -279.276719) (xy 116.597428 -279.227326) (xy 116.589303 -279.176031) (xy 116.309144 -279.176031)
			(xy 116.309139 -279.176285) (xy 116.301014 -279.22758) (xy 116.284966 -279.276973) (xy 116.261388 -279.323247)
			(xy 116.230862 -279.365263) (xy 116.194139 -279.401986) (xy 116.152123 -279.432512) (xy 116.105849 -279.45609)
			(xy 116.056456 -279.472138) (xy 116.005161 -279.480263) (xy 115.953227 -279.480263) (xy 115.901932 -279.472138)
			(xy 115.852539 -279.45609) (xy 115.806265 -279.432512) (xy 115.764249 -279.401986) (xy 115.727526 -279.365263)
			(xy 115.697 -279.323247) (xy 115.673422 -279.276973) (xy 115.657374 -279.22758) (xy 115.649249 -279.176285)
			(xy 115.369339 -279.176285) (xy 115.361214 -279.22758) (xy 115.345166 -279.276973) (xy 115.321588 -279.323247)
			(xy 115.291062 -279.365263) (xy 115.254339 -279.401986) (xy 115.212323 -279.432512) (xy 115.166049 -279.45609)
			(xy 115.116656 -279.472138) (xy 115.065361 -279.480263) (xy 115.013427 -279.480263) (xy 114.962132 -279.472138)
			(xy 114.912739 -279.45609) (xy 114.866465 -279.432512) (xy 114.824449 -279.401986) (xy 114.787726 -279.365263)
			(xy 114.7572 -279.323247) (xy 114.733622 -279.276973) (xy 114.717574 -279.22758) (xy 114.709449 -279.176285)
			(xy 113.5407 -279.176285) (xy 113.537708 -279.253046) (xy 113.525668 -279.355465) (xy 113.505677 -279.456632)
			(xy 113.49228 -279.506426) (xy 113.488906 -279.520104) (xy 113.488986 -279.548266) (xy 113.496761 -279.575334)
			(xy 113.51164 -279.599245) (xy 113.532488 -279.618177) (xy 113.557718 -279.630689) (xy 113.585407 -279.635827)
			(xy 113.599468 -279.63495) (xy 113.629694 -279.63368) (xy 113.655661 -279.634162) (xy 113.706956 -279.642286)
			(xy 113.756348 -279.658333) (xy 113.802621 -279.68191) (xy 113.844637 -279.712436) (xy 113.88136 -279.749158)
			(xy 113.911887 -279.791173) (xy 113.935464 -279.837447) (xy 113.951513 -279.886839) (xy 113.959637 -279.938133)
			(xy 113.959637 -279.990067) (xy 113.959632 -279.990101) (xy 116.119403 -279.990101) (xy 116.119403 -279.938167)
			(xy 116.127528 -279.886872) (xy 116.143576 -279.837479) (xy 116.167154 -279.791205) (xy 116.19768 -279.749189)
			(xy 116.234403 -279.712466) (xy 116.276419 -279.68194) (xy 116.322693 -279.658362) (xy 116.372086 -279.642314)
			(xy 116.423381 -279.634189) (xy 116.475315 -279.634189) (xy 116.52661 -279.642314) (xy 116.576003 -279.658362)
			(xy 116.622277 -279.68194) (xy 116.664293 -279.712466) (xy 116.701016 -279.749189) (xy 116.731542 -279.791205)
			(xy 116.75512 -279.837479) (xy 116.771168 -279.886872) (xy 116.779293 -279.938167) (xy 116.779802 -279.964134)
			(xy 116.779293 -279.990101) (xy 117.059203 -279.990101) (xy 117.059203 -279.938167) (xy 117.067328 -279.886872)
			(xy 117.083376 -279.837479) (xy 117.106954 -279.791205) (xy 117.13748 -279.749189) (xy 117.174203 -279.712466)
			(xy 117.216219 -279.68194) (xy 117.262493 -279.658362) (xy 117.311886 -279.642314) (xy 117.363181 -279.634189)
			(xy 117.415115 -279.634189) (xy 117.46641 -279.642314) (xy 117.515803 -279.658362) (xy 117.562077 -279.68194)
			(xy 117.604093 -279.712466) (xy 117.640816 -279.749189) (xy 117.671342 -279.791205) (xy 117.69492 -279.837479)
			(xy 117.710968 -279.886872) (xy 117.719093 -279.938167) (xy 117.719602 -279.964134) (xy 117.719093 -279.990101)
			(xy 117.710968 -280.041396) (xy 117.69492 -280.090789) (xy 117.671342 -280.137063) (xy 117.640816 -280.179079)
			(xy 117.604093 -280.215802) (xy 117.562077 -280.246328) (xy 117.515803 -280.269906) (xy 117.46641 -280.285954)
			(xy 117.415115 -280.294079) (xy 117.363181 -280.294079) (xy 117.311886 -280.285954) (xy 117.262493 -280.269906)
			(xy 117.216219 -280.246328) (xy 117.174203 -280.215802) (xy 117.13748 -280.179079) (xy 117.106954 -280.137063)
			(xy 117.083376 -280.090789) (xy 117.067328 -280.041396) (xy 117.059203 -279.990101) (xy 116.779293 -279.990101)
			(xy 116.771168 -280.041396) (xy 116.75512 -280.090789) (xy 116.731542 -280.137063) (xy 116.701016 -280.179079)
			(xy 116.664293 -280.215802) (xy 116.622277 -280.246328) (xy 116.576003 -280.269906) (xy 116.52661 -280.285954)
			(xy 116.475315 -280.294079) (xy 116.423381 -280.294079) (xy 116.372086 -280.285954) (xy 116.322693 -280.269906)
			(xy 116.276419 -280.246328) (xy 116.234403 -280.215802) (xy 116.19768 -280.179079) (xy 116.167154 -280.137063)
			(xy 116.143576 -280.090789) (xy 116.127528 -280.041396) (xy 116.119403 -279.990101) (xy 113.959632 -279.990101)
			(xy 113.951513 -280.041361) (xy 113.935464 -280.090753) (xy 113.911887 -280.137027) (xy 113.88136 -280.179042)
			(xy 113.844637 -280.215764) (xy 113.802621 -280.24629) (xy 113.756348 -280.269867) (xy 113.706956 -280.285914)
			(xy 113.655661 -280.294038) (xy 113.629694 -280.294588) (xy 113.602812 -280.294052) (xy 113.549759 -280.285329)
			(xy 113.498819 -280.268132) (xy 113.451335 -280.242913) (xy 113.408561 -280.210338) (xy 113.371627 -280.171268)
			(xy 113.341505 -280.126732) (xy 113.32972 -280.102564) (xy 113.323404 -280.089967) (xy 113.305061 -280.068588)
			(xy 113.281579 -280.053028) (xy 113.254741 -280.044469) (xy 113.226586 -280.043561) (xy 113.199253 -280.050373)
			(xy 113.174817 -280.064387) (xy 113.16462 -280.074116) (xy 113.13844 -280.100535) (xy 113.083542 -280.150729)
			(xy 113.054892 -280.174446) (xy 113.045875 -280.2271) (xy 113.020423 -280.330861) (xy 112.986673 -280.432226)
			(xy 112.944845 -280.530534) (xy 112.895213 -280.625142) (xy 112.838101 -280.715432) (xy 112.773882 -280.800814)
			(xy 112.770903 -280.804171) (xy 116.589303 -280.804171) (xy 116.589303 -280.752237) (xy 116.597428 -280.700942)
			(xy 116.613476 -280.651549) (xy 116.637054 -280.605275) (xy 116.66758 -280.563259) (xy 116.704303 -280.526536)
			(xy 116.746319 -280.49601) (xy 116.792593 -280.472432) (xy 116.841986 -280.456384) (xy 116.893281 -280.448259)
			(xy 116.945215 -280.448259) (xy 116.99651 -280.456384) (xy 117.045903 -280.472432) (xy 117.092177 -280.49601)
			(xy 117.134193 -280.526536) (xy 117.170916 -280.563259) (xy 117.201442 -280.605275) (xy 117.22502 -280.651549)
			(xy 117.241068 -280.700942) (xy 117.249193 -280.752237) (xy 117.249702 -280.778204) (xy 117.249193 -280.804171)
			(xy 117.241068 -280.855466) (xy 117.22502 -280.904859) (xy 117.201442 -280.951133) (xy 117.170916 -280.993149)
			(xy 117.134193 -281.029872) (xy 117.092177 -281.060398) (xy 117.045903 -281.083976) (xy 116.99651 -281.100024)
			(xy 116.945215 -281.108149) (xy 116.893281 -281.108149) (xy 116.841986 -281.100024) (xy 116.792593 -281.083976)
			(xy 116.746319 -281.060398) (xy 116.704303 -281.029872) (xy 116.66758 -280.993149) (xy 116.637054 -280.951133)
			(xy 116.613476 -280.904859) (xy 116.597428 -280.855466) (xy 116.589303 -280.804171) (xy 112.770903 -280.804171)
			(xy 112.702976 -280.880729) (xy 112.625847 -280.954656) (xy 112.584738 -280.98877) (xy 112.575328 -281.043424)
			(xy 112.548513 -281.151043) (xy 112.512771 -281.256037) (xy 112.468355 -281.357664) (xy 112.415575 -281.455211)
			(xy 112.354805 -281.54799) (xy 112.321086 -281.59202) (xy 112.341022 -281.617987) (xy 113.299749 -281.617987)
			(xy 113.299749 -281.566053) (xy 113.307874 -281.514758) (xy 113.323922 -281.465365) (xy 113.3475 -281.419091)
			(xy 113.378026 -281.377075) (xy 113.414749 -281.340352) (xy 113.456765 -281.309826) (xy 113.503039 -281.286248)
			(xy 113.552432 -281.2702) (xy 113.603727 -281.262075) (xy 113.655661 -281.262075) (xy 113.706956 -281.2702)
			(xy 113.756349 -281.286248) (xy 113.802623 -281.309826) (xy 113.844639 -281.340352) (xy 113.881362 -281.377075)
			(xy 113.911888 -281.419091) (xy 113.935466 -281.465365) (xy 113.951514 -281.514758) (xy 113.959639 -281.566053)
			(xy 113.960148 -281.59202) (xy 113.959639 -281.617987) (xy 117.059203 -281.617987) (xy 117.059203 -281.566053)
			(xy 117.067328 -281.514758) (xy 117.083376 -281.465365) (xy 117.106954 -281.419091) (xy 117.13748 -281.377075)
			(xy 117.174203 -281.340352) (xy 117.216219 -281.309826) (xy 117.262493 -281.286248) (xy 117.311886 -281.2702)
			(xy 117.363181 -281.262075) (xy 117.415115 -281.262075) (xy 117.46641 -281.2702) (xy 117.515803 -281.286248)
			(xy 117.562077 -281.309826) (xy 117.604093 -281.340352) (xy 117.640816 -281.377075) (xy 117.671342 -281.419091)
			(xy 117.69492 -281.465365) (xy 117.710968 -281.514758) (xy 117.719093 -281.566053) (xy 117.719602 -281.59202)
			(xy 117.719093 -281.617987) (xy 117.710968 -281.669282) (xy 117.69492 -281.718675) (xy 117.671342 -281.764949)
			(xy 117.640816 -281.806965) (xy 117.604093 -281.843688) (xy 117.562077 -281.874214) (xy 117.515803 -281.897792)
			(xy 117.46641 -281.91384) (xy 117.415115 -281.921965) (xy 117.363181 -281.921965) (xy 117.311886 -281.91384)
			(xy 117.262493 -281.897792) (xy 117.216219 -281.874214) (xy 117.174203 -281.843688) (xy 117.13748 -281.806965)
			(xy 117.106954 -281.764949) (xy 117.083376 -281.718675) (xy 117.067328 -281.669282) (xy 117.059203 -281.617987)
			(xy 113.959639 -281.617987) (xy 113.951514 -281.669282) (xy 113.935466 -281.718675) (xy 113.911888 -281.764949)
			(xy 113.881362 -281.806965) (xy 113.844639 -281.843688) (xy 113.802623 -281.874214) (xy 113.756349 -281.897792)
			(xy 113.706956 -281.91384) (xy 113.655661 -281.921965) (xy 113.603727 -281.921965) (xy 113.552432 -281.91384)
			(xy 113.503039 -281.897792) (xy 113.456765 -281.874214) (xy 113.414749 -281.843688) (xy 113.378026 -281.806965)
			(xy 113.3475 -281.764949) (xy 113.323922 -281.718675) (xy 113.307874 -281.669282) (xy 113.299749 -281.617987)
			(xy 112.341022 -281.617987) (xy 112.350756 -281.630666) (xy 112.404984 -281.711622) (xy 112.453099 -281.796354)
			(xy 112.494842 -281.8844) (xy 112.529984 -281.975282) (xy 112.558336 -282.068506) (xy 112.579742 -282.163565)
			(xy 112.594087 -282.259943) (xy 112.601292 -282.357116) (xy 112.601756 -282.405836) (xy 112.601756 -282.42006)
			(xy 112.601502 -282.43911) (xy 112.599683 -282.490865) (xy 112.588958 -282.593876) (xy 112.5702 -282.695731)
			(xy 112.543525 -282.795805) (xy 112.509097 -282.893483) (xy 112.467125 -282.988165) (xy 112.41787 -283.079271)
			(xy 112.361632 -283.16624) (xy 112.300795 -283.245873) (xy 113.299749 -283.245873) (xy 113.299749 -283.193939)
			(xy 113.307874 -283.142644) (xy 113.323922 -283.093251) (xy 113.3475 -283.046977) (xy 113.378026 -283.004961)
			(xy 113.414749 -282.968238) (xy 113.456765 -282.937712) (xy 113.503039 -282.914134) (xy 113.552432 -282.898086)
			(xy 113.603727 -282.889961) (xy 113.655661 -282.889961) (xy 113.706956 -282.898086) (xy 113.756349 -282.914134)
			(xy 113.802623 -282.937712) (xy 113.844639 -282.968238) (xy 113.881362 -283.004961) (xy 113.911888 -283.046977)
			(xy 113.935466 -283.093251) (xy 113.951514 -283.142644) (xy 113.959639 -283.193939) (xy 113.960148 -283.219906)
			(xy 113.959639 -283.245873) (xy 116.119403 -283.245873) (xy 116.119403 -283.193939) (xy 116.127528 -283.142644)
			(xy 116.143576 -283.093251) (xy 116.167154 -283.046977) (xy 116.19768 -283.004961) (xy 116.234403 -282.968238)
			(xy 116.276419 -282.937712) (xy 116.322693 -282.914134) (xy 116.372086 -282.898086) (xy 116.423381 -282.889961)
			(xy 116.475315 -282.889961) (xy 116.52661 -282.898086) (xy 116.576003 -282.914134) (xy 116.622277 -282.937712)
			(xy 116.664293 -282.968238) (xy 116.701016 -283.004961) (xy 116.731542 -283.046977) (xy 116.75512 -283.093251)
			(xy 116.771168 -283.142644) (xy 116.779293 -283.193939) (xy 116.779802 -283.219906) (xy 116.779293 -283.245873)
			(xy 116.771168 -283.297168) (xy 116.75512 -283.346561) (xy 116.731542 -283.392835) (xy 116.701016 -283.434851)
			(xy 116.664293 -283.471574) (xy 116.622277 -283.5021) (xy 116.576003 -283.525678) (xy 116.52661 -283.541726)
			(xy 116.475315 -283.549851) (xy 116.423381 -283.549851) (xy 116.372086 -283.541726) (xy 116.322693 -283.525678)
			(xy 116.276419 -283.5021) (xy 116.234403 -283.471574) (xy 116.19768 -283.434851) (xy 116.167154 -283.392835)
			(xy 116.143576 -283.346561) (xy 116.127528 -283.297168) (xy 116.119403 -283.245873) (xy 113.959639 -283.245873)
			(xy 113.951514 -283.297168) (xy 113.935466 -283.346561) (xy 113.911888 -283.392835) (xy 113.881362 -283.434851)
			(xy 113.844639 -283.471574) (xy 113.802623 -283.5021) (xy 113.756349 -283.525678) (xy 113.706956 -283.541726)
			(xy 113.655661 -283.549851) (xy 113.603727 -283.549851) (xy 113.552432 -283.541726) (xy 113.503039 -283.525678)
			(xy 113.456765 -283.5021) (xy 113.414749 -283.471574) (xy 113.378026 -283.434851) (xy 113.3475 -283.392835)
			(xy 113.323922 -283.346561) (xy 113.307874 -283.297168) (xy 113.299749 -283.245873) (xy 112.300795 -283.245873)
			(xy 112.298758 -283.248539) (xy 112.229632 -283.325662) (xy 112.154681 -283.397137) (xy 112.114838 -283.430218)
			(xy 112.105811 -283.482847) (xy 112.080348 -283.586558) (xy 112.046598 -283.687875) (xy 112.004781 -283.786137)
			(xy 111.955171 -283.880705) (xy 111.89809 -283.97096) (xy 111.833912 -284.056314) (xy 111.763055 -284.136211)
			(xy 111.68598 -284.210128) (xy 111.644938 -284.244288) (xy 111.635913 -284.296906) (xy 111.610454 -284.400595)
			(xy 111.576707 -284.501889) (xy 111.534892 -284.600128) (xy 111.485283 -284.694672) (xy 111.428204 -284.784901)
			(xy 111.364026 -284.870228) (xy 111.361119 -284.873505) (xy 113.299749 -284.873505) (xy 113.299749 -284.821571)
			(xy 113.307874 -284.770276) (xy 113.323922 -284.720883) (xy 113.3475 -284.674609) (xy 113.378026 -284.632593)
			(xy 113.414749 -284.59587) (xy 113.456765 -284.565344) (xy 113.503039 -284.541766) (xy 113.552432 -284.525718)
			(xy 113.603727 -284.517593) (xy 113.655661 -284.517593) (xy 113.706956 -284.525718) (xy 113.756349 -284.541766)
			(xy 113.802623 -284.565344) (xy 113.844639 -284.59587) (xy 113.881362 -284.632593) (xy 113.911888 -284.674609)
			(xy 113.935466 -284.720883) (xy 113.951514 -284.770276) (xy 113.959639 -284.821571) (xy 113.960148 -284.847538)
			(xy 113.959639 -284.873505) (xy 116.119403 -284.873505) (xy 116.119403 -284.821571) (xy 116.127528 -284.770276)
			(xy 116.143576 -284.720883) (xy 116.167154 -284.674609) (xy 116.19768 -284.632593) (xy 116.234403 -284.59587)
			(xy 116.276419 -284.565344) (xy 116.322693 -284.541766) (xy 116.372086 -284.525718) (xy 116.423381 -284.517593)
			(xy 116.475315 -284.517593) (xy 116.52661 -284.525718) (xy 116.576003 -284.541766) (xy 116.622277 -284.565344)
			(xy 116.664293 -284.59587) (xy 116.701016 -284.632593) (xy 116.731542 -284.674609) (xy 116.75512 -284.720883)
			(xy 116.771168 -284.770276) (xy 116.779293 -284.821571) (xy 116.779802 -284.847538) (xy 116.779293 -284.873505)
			(xy 116.771168 -284.9248) (xy 116.75512 -284.974193) (xy 116.731542 -285.020467) (xy 116.701016 -285.062483)
			(xy 116.664293 -285.099206) (xy 116.622277 -285.129732) (xy 116.576003 -285.15331) (xy 116.52661 -285.169358)
			(xy 116.475315 -285.177483) (xy 116.423381 -285.177483) (xy 116.372086 -285.169358) (xy 116.322693 -285.15331)
			(xy 116.276419 -285.129732) (xy 116.234403 -285.099206) (xy 116.19768 -285.062483) (xy 116.167154 -285.020467)
			(xy 116.143576 -284.974193) (xy 116.127528 -284.9248) (xy 116.119403 -284.873505) (xy 113.959639 -284.873505)
			(xy 113.951514 -284.9248) (xy 113.935466 -284.974193) (xy 113.911888 -285.020467) (xy 113.881362 -285.062483)
			(xy 113.844639 -285.099206) (xy 113.802623 -285.129732) (xy 113.756349 -285.15331) (xy 113.706956 -285.169358)
			(xy 113.655661 -285.177483) (xy 113.603727 -285.177483) (xy 113.552432 -285.169358) (xy 113.503039 -285.15331)
			(xy 113.456765 -285.129732) (xy 113.414749 -285.099206) (xy 113.378026 -285.062483) (xy 113.3475 -285.020467)
			(xy 113.323922 -284.974193) (xy 113.307874 -284.9248) (xy 113.299749 -284.873505) (xy 111.361119 -284.873505)
			(xy 111.29317 -284.950095) (xy 111.216097 -285.023982) (xy 111.175038 -285.058104) (xy 111.166008 -285.110721)
			(xy 111.14054 -285.214406) (xy 111.106787 -285.315697) (xy 111.06497 -285.413934) (xy 111.015361 -285.508476)
			(xy 110.958284 -285.598706) (xy 110.894112 -285.684035) (xy 110.823262 -285.763907) (xy 110.746198 -285.837801)
			(xy 110.705138 -285.87192) (xy 110.696106 -285.924557) (xy 110.67063 -286.028282) (xy 110.636862 -286.129611)
			(xy 110.595022 -286.227883) (xy 110.545385 -286.322456) (xy 110.488274 -286.412712) (xy 110.424062 -286.498063)
			(xy 110.421109 -286.501391) (xy 113.299749 -286.501391) (xy 113.299749 -286.449457) (xy 113.307874 -286.398162)
			(xy 113.323922 -286.348769) (xy 113.3475 -286.302495) (xy 113.378026 -286.260479) (xy 113.414749 -286.223756)
			(xy 113.456765 -286.19323) (xy 113.503039 -286.169652) (xy 113.552432 -286.153604) (xy 113.603727 -286.145479)
			(xy 113.655661 -286.145479) (xy 113.706956 -286.153604) (xy 113.756349 -286.169652) (xy 113.802623 -286.19323)
			(xy 113.844639 -286.223756) (xy 113.881362 -286.260479) (xy 113.911888 -286.302495) (xy 113.935466 -286.348769)
			(xy 113.951514 -286.398162) (xy 113.959639 -286.449457) (xy 113.960148 -286.475424) (xy 113.959639 -286.501391)
			(xy 116.119403 -286.501391) (xy 116.119403 -286.449457) (xy 116.127528 -286.398162) (xy 116.143576 -286.348769)
			(xy 116.167154 -286.302495) (xy 116.19768 -286.260479) (xy 116.234403 -286.223756) (xy 116.276419 -286.19323)
			(xy 116.322693 -286.169652) (xy 116.372086 -286.153604) (xy 116.423381 -286.145479) (xy 116.475315 -286.145479)
			(xy 116.52661 -286.153604) (xy 116.576003 -286.169652) (xy 116.622277 -286.19323) (xy 116.664293 -286.223756)
			(xy 116.701016 -286.260479) (xy 116.731542 -286.302495) (xy 116.75512 -286.348769) (xy 116.771168 -286.398162)
			(xy 116.779293 -286.449457) (xy 116.779802 -286.475424) (xy 116.779293 -286.501391) (xy 116.771168 -286.552686)
			(xy 116.75512 -286.602079) (xy 116.731542 -286.648353) (xy 116.701016 -286.690369) (xy 116.664293 -286.727092)
			(xy 116.622277 -286.757618) (xy 116.576003 -286.781196) (xy 116.52661 -286.797244) (xy 116.475315 -286.805369)
			(xy 116.423381 -286.805369) (xy 116.372086 -286.797244) (xy 116.322693 -286.781196) (xy 116.276419 -286.757618)
			(xy 116.234403 -286.727092) (xy 116.19768 -286.690369) (xy 116.167154 -286.648353) (xy 116.143576 -286.602079)
			(xy 116.127528 -286.552686) (xy 116.119403 -286.501391) (xy 113.959639 -286.501391) (xy 113.951514 -286.552686)
			(xy 113.935466 -286.602079) (xy 113.911888 -286.648353) (xy 113.881362 -286.690369) (xy 113.844639 -286.727092)
			(xy 113.802623 -286.757618) (xy 113.756349 -286.781196) (xy 113.706956 -286.797244) (xy 113.655661 -286.805369)
			(xy 113.603727 -286.805369) (xy 113.552432 -286.797244) (xy 113.503039 -286.781196) (xy 113.456765 -286.757618)
			(xy 113.414749 -286.727092) (xy 113.378026 -286.690369) (xy 113.3475 -286.648353) (xy 113.323922 -286.602079)
			(xy 113.307874 -286.552686) (xy 113.299749 -286.501391) (xy 110.421109 -286.501391) (xy 110.353168 -286.57795)
			(xy 110.276056 -286.651853) (xy 110.234984 -286.68599) (xy 110.228785 -286.722749) (xy 110.212773 -286.795563)
			(xy 110.20298 -286.831532) (xy 110.199607 -286.84521) (xy 110.199688 -286.873371) (xy 110.207464 -286.900436)
			(xy 110.222343 -286.924346) (xy 110.24319 -286.943277) (xy 110.268419 -286.955788) (xy 110.296107 -286.960926)
			(xy 110.310168 -286.960056) (xy 110.340394 -286.958786) (xy 110.36636 -286.959268) (xy 110.417654 -286.967392)
			(xy 110.467045 -286.983439) (xy 110.513318 -287.007015) (xy 110.555333 -287.03754) (xy 110.592056 -287.074262)
			(xy 110.622581 -287.116277) (xy 110.646159 -287.162549) (xy 110.662207 -287.21194) (xy 110.670331 -287.263234)
			(xy 110.670331 -287.315166) (xy 110.662207 -287.36646) (xy 110.646159 -287.415851) (xy 110.622581 -287.462123)
			(xy 110.592056 -287.504138) (xy 110.555333 -287.54086) (xy 110.513318 -287.571385) (xy 110.467045 -287.594961)
			(xy 110.417654 -287.611008) (xy 110.36636 -287.619132) (xy 110.340394 -287.619694) (xy 110.313512 -287.619158)
			(xy 110.260459 -287.610435) (xy 110.209518 -287.593238) (xy 110.162034 -287.568019) (xy 110.11926 -287.535445)
			(xy 110.082325 -287.496375) (xy 110.052203 -287.45184) (xy 110.04042 -287.42767) (xy 110.034105 -287.415072)
			(xy 110.015762 -287.393692) (xy 109.99228 -287.378131) (xy 109.965441 -287.369572) (xy 109.937286 -287.368663)
			(xy 109.909952 -287.375476) (xy 109.885515 -287.389491) (xy 109.87532 -287.399222) (xy 109.860974 -287.413778)
			(xy 109.831504 -287.442104) (xy 109.816392 -287.455864) (xy 109.816392 -288.129023) (xy 113.299749 -288.129023)
			(xy 113.299749 -288.077089) (xy 113.307874 -288.025794) (xy 113.323922 -287.976401) (xy 113.3475 -287.930127)
			(xy 113.378026 -287.888111) (xy 113.414749 -287.851388) (xy 113.456765 -287.820862) (xy 113.503039 -287.797284)
			(xy 113.552432 -287.781236) (xy 113.603727 -287.773111) (xy 113.655661 -287.773111) (xy 113.706956 -287.781236)
			(xy 113.756349 -287.797284) (xy 113.802623 -287.820862) (xy 113.844639 -287.851388) (xy 113.881362 -287.888111)
			(xy 113.911888 -287.930127) (xy 113.935466 -287.976401) (xy 113.951514 -288.025794) (xy 113.959639 -288.077089)
			(xy 113.960148 -288.103056) (xy 113.959639 -288.129023) (xy 116.119403 -288.129023) (xy 116.119403 -288.077089)
			(xy 116.127528 -288.025794) (xy 116.143576 -287.976401) (xy 116.167154 -287.930127) (xy 116.19768 -287.888111)
			(xy 116.234403 -287.851388) (xy 116.276419 -287.820862) (xy 116.322693 -287.797284) (xy 116.372086 -287.781236)
			(xy 116.423381 -287.773111) (xy 116.475315 -287.773111) (xy 116.52661 -287.781236) (xy 116.576003 -287.797284)
			(xy 116.622277 -287.820862) (xy 116.664293 -287.851388) (xy 116.701016 -287.888111) (xy 116.731542 -287.930127)
			(xy 116.75512 -287.976401) (xy 116.771168 -288.025794) (xy 116.779293 -288.077089) (xy 116.779802 -288.103056)
			(xy 116.779293 -288.129023) (xy 116.771168 -288.180318) (xy 116.75512 -288.229711) (xy 116.731542 -288.275985)
			(xy 116.701016 -288.318001) (xy 116.664293 -288.354724) (xy 116.622277 -288.38525) (xy 116.576003 -288.408828)
			(xy 116.52661 -288.424876) (xy 116.475315 -288.433001) (xy 116.423381 -288.433001) (xy 116.372086 -288.424876)
			(xy 116.322693 -288.408828) (xy 116.276419 -288.38525) (xy 116.234403 -288.354724) (xy 116.19768 -288.318001)
			(xy 116.167154 -288.275985) (xy 116.143576 -288.229711) (xy 116.127528 -288.180318) (xy 116.119403 -288.129023)
			(xy 113.959639 -288.129023) (xy 113.951514 -288.180318) (xy 113.935466 -288.229711) (xy 113.911888 -288.275985)
			(xy 113.881362 -288.318001) (xy 113.844639 -288.354724) (xy 113.802623 -288.38525) (xy 113.756349 -288.408828)
			(xy 113.706956 -288.424876) (xy 113.655661 -288.433001) (xy 113.603727 -288.433001) (xy 113.552432 -288.424876)
			(xy 113.503039 -288.408828) (xy 113.456765 -288.38525) (xy 113.414749 -288.354724) (xy 113.378026 -288.318001)
			(xy 113.3475 -288.275985) (xy 113.323922 -288.229711) (xy 113.307874 -288.180318) (xy 113.299749 -288.129023)
			(xy 109.816392 -288.129023) (xy 109.816392 -288.826194) (xy 109.831637 -288.84001) (xy 109.861359 -288.868464)
			(xy 109.875828 -288.88309) (xy 109.885972 -288.892831) (xy 109.910354 -288.906821) (xy 109.937628 -288.913633)
			(xy 109.965726 -288.91275) (xy 109.992518 -288.904239) (xy 110.015975 -288.888745) (xy 110.034317 -288.867441)
			(xy 110.040674 -288.854896) (xy 110.052398 -288.830691) (xy 110.082507 -288.78613) (xy 110.119442 -288.747039)
			(xy 110.162225 -288.714453) (xy 110.209726 -288.689235) (xy 110.260686 -288.672051) (xy 110.313758 -288.663356)
			(xy 110.340648 -288.662872) (xy 110.366611 -288.663385) (xy 110.417896 -288.671514) (xy 110.467278 -288.687566)
			(xy 110.513542 -288.711144) (xy 110.555548 -288.741669) (xy 110.592262 -288.778389) (xy 110.622781 -288.820399)
			(xy 110.646352 -288.866666) (xy 110.662397 -288.916051) (xy 110.66668 -288.943093) (xy 119.408703 -288.943093)
			(xy 119.408703 -288.891159) (xy 119.416828 -288.839864) (xy 119.432876 -288.790471) (xy 119.456454 -288.744197)
			(xy 119.48698 -288.702181) (xy 119.523703 -288.665458) (xy 119.565719 -288.634932) (xy 119.611993 -288.611354)
			(xy 119.661386 -288.595306) (xy 119.712681 -288.587181) (xy 119.764615 -288.587181) (xy 119.81591 -288.595306)
			(xy 119.865303 -288.611354) (xy 119.911577 -288.634932) (xy 119.953593 -288.665458) (xy 119.990316 -288.702181)
			(xy 120.020842 -288.744197) (xy 120.04442 -288.790471) (xy 120.060468 -288.839864) (xy 120.068593 -288.891159)
			(xy 120.069102 -288.917126) (xy 120.068593 -288.943093) (xy 120.060468 -288.994388) (xy 120.04442 -289.043781)
			(xy 120.020842 -289.090055) (xy 119.990316 -289.132071) (xy 119.953593 -289.168794) (xy 119.911577 -289.19932)
			(xy 119.865303 -289.222898) (xy 119.81591 -289.238946) (xy 119.764615 -289.247071) (xy 119.712681 -289.247071)
			(xy 119.661386 -289.238946) (xy 119.611993 -289.222898) (xy 119.565719 -289.19932) (xy 119.523703 -289.168794)
			(xy 119.48698 -289.132071) (xy 119.456454 -289.090055) (xy 119.432876 -289.043781) (xy 119.416828 -288.994388)
			(xy 119.408703 -288.943093) (xy 110.66668 -288.943093) (xy 110.670519 -288.967337) (xy 110.670519 -289.019263)
			(xy 110.662397 -289.070549) (xy 110.646352 -289.119934) (xy 110.622781 -289.166201) (xy 110.592262 -289.208211)
			(xy 110.555548 -289.244931) (xy 110.513542 -289.275456) (xy 110.467278 -289.299034) (xy 110.417896 -289.315086)
			(xy 110.366611 -289.323215) (xy 110.340648 -289.32378) (xy 110.310422 -289.32251) (xy 110.296364 -289.321655)
			(xy 110.268685 -289.326801) (xy 110.243466 -289.339314) (xy 110.222625 -289.358242) (xy 110.207749 -289.382144)
			(xy 110.199971 -289.409202) (xy 110.199881 -289.437355) (xy 110.203234 -289.451034) (xy 110.216218 -289.499092)
			(xy 110.235791 -289.596706) (xy 110.247965 -289.695516) (xy 110.25267 -289.794962) (xy 110.251963 -289.833109)
			(xy 118.938549 -289.833109) (xy 118.938549 -289.781175) (xy 118.946674 -289.72988) (xy 118.962722 -289.680487)
			(xy 118.9863 -289.634213) (xy 119.016826 -289.592197) (xy 119.053549 -289.555474) (xy 119.095565 -289.524948)
			(xy 119.141839 -289.50137) (xy 119.191232 -289.485322) (xy 119.242527 -289.477197) (xy 119.294461 -289.477197)
			(xy 119.345756 -289.485322) (xy 119.395149 -289.50137) (xy 119.441423 -289.524948) (xy 119.483439 -289.555474)
			(xy 119.520162 -289.592197) (xy 119.550688 -289.634213) (xy 119.574266 -289.680487) (xy 119.590314 -289.72988)
			(xy 119.598439 -289.781175) (xy 119.598948 -289.807142) (xy 119.87784 -289.807142) (xy 119.878351 -289.781597)
			(xy 119.886208 -289.731114) (xy 119.901742 -289.682443) (xy 119.924583 -289.636743) (xy 119.954186 -289.595103)
			(xy 119.989845 -289.558516) (xy 120.030711 -289.527853) (xy 120.075809 -289.503846) (xy 120.124065 -289.487067)
			(xy 120.149112 -289.482022) (xy 120.173242 -289.477704) (xy 120.386602 -289.074098) (xy 120.376442 -289.051492)
			(xy 120.367429 -289.030253) (xy 120.354744 -288.985891) (xy 120.348359 -288.940196) (xy 120.347994 -288.917126)
			(xy 120.348503 -288.891159) (xy 120.356628 -288.839864) (xy 120.372676 -288.790471) (xy 120.396254 -288.744197)
			(xy 120.42678 -288.702181) (xy 120.463503 -288.665458) (xy 120.505519 -288.634932) (xy 120.551793 -288.611354)
			(xy 120.601186 -288.595306) (xy 120.652481 -288.587181) (xy 120.704415 -288.587181) (xy 120.75571 -288.595306)
			(xy 120.805103 -288.611354) (xy 120.851377 -288.634932) (xy 120.893393 -288.665458) (xy 120.930116 -288.702181)
			(xy 120.960642 -288.744197) (xy 120.98422 -288.790471) (xy 121.000268 -288.839864) (xy 121.008393 -288.891159)
			(xy 121.008902 -288.917126) (xy 121.0085 -288.942676) (xy 121.000631 -288.993165) (xy 120.985084 -289.041842)
			(xy 120.96223 -289.087545) (xy 120.932614 -289.129186) (xy 120.896941 -289.165772) (xy 120.856061 -289.196432)
			(xy 120.81095 -289.220434) (xy 120.762682 -289.237206) (xy 120.73763 -289.242246) (xy 120.7135 -289.246564)
			(xy 120.50014 -289.65017) (xy 120.5103 -289.672776) (xy 120.519306 -289.694018) (xy 120.531993 -289.738378)
			(xy 120.538381 -289.784072) (xy 120.538748 -289.807142) (xy 120.538239 -289.833109) (xy 120.818149 -289.833109)
			(xy 120.818149 -289.781175) (xy 120.826274 -289.72988) (xy 120.842322 -289.680487) (xy 120.8659 -289.634213)
			(xy 120.896426 -289.592197) (xy 120.933149 -289.555474) (xy 120.975165 -289.524948) (xy 121.021439 -289.50137)
			(xy 121.070832 -289.485322) (xy 121.122127 -289.477197) (xy 121.174061 -289.477197) (xy 121.225356 -289.485322)
			(xy 121.274749 -289.50137) (xy 121.321023 -289.524948) (xy 121.363039 -289.555474) (xy 121.399762 -289.592197)
			(xy 121.430288 -289.634213) (xy 121.453866 -289.680487) (xy 121.469914 -289.72988) (xy 121.478039 -289.781175)
			(xy 121.478548 -289.807142) (xy 121.478039 -289.833109) (xy 121.469914 -289.884404) (xy 121.453866 -289.933797)
			(xy 121.430288 -289.980071) (xy 121.399762 -290.022087) (xy 121.363039 -290.05881) (xy 121.321023 -290.089336)
			(xy 121.274749 -290.112914) (xy 121.225356 -290.128962) (xy 121.174061 -290.137087) (xy 121.122127 -290.137087)
			(xy 121.070832 -290.128962) (xy 121.021439 -290.112914) (xy 120.975165 -290.089336) (xy 120.933149 -290.05881)
			(xy 120.896426 -290.022087) (xy 120.8659 -289.980071) (xy 120.842322 -289.933797) (xy 120.826274 -289.884404)
			(xy 120.818149 -289.833109) (xy 120.538239 -289.833109) (xy 120.530114 -289.884404) (xy 120.514066 -289.933797)
			(xy 120.490488 -289.980071) (xy 120.459962 -290.022087) (xy 120.423239 -290.05881) (xy 120.381223 -290.089336)
			(xy 120.334949 -290.112914) (xy 120.285556 -290.128962) (xy 120.234261 -290.137087) (xy 120.182327 -290.137087)
			(xy 120.131032 -290.128962) (xy 120.081639 -290.112914) (xy 120.035365 -290.089336) (xy 119.993349 -290.05881)
			(xy 119.956626 -290.022087) (xy 119.9261 -289.980071) (xy 119.902522 -289.933797) (xy 119.886474 -289.884404)
			(xy 119.878349 -289.833109) (xy 119.87784 -289.807142) (xy 119.598948 -289.807142) (xy 119.598439 -289.833109)
			(xy 119.590314 -289.884404) (xy 119.574266 -289.933797) (xy 119.550688 -289.980071) (xy 119.520162 -290.022087)
			(xy 119.483439 -290.05881) (xy 119.441423 -290.089336) (xy 119.395149 -290.112914) (xy 119.345756 -290.128962)
			(xy 119.294461 -290.137087) (xy 119.242527 -290.137087) (xy 119.191232 -290.128962) (xy 119.141839 -290.112914)
			(xy 119.095565 -290.089336) (xy 119.053549 -290.05881) (xy 119.016826 -290.022087) (xy 118.9863 -289.980071)
			(xy 118.962722 -289.933797) (xy 118.946674 -289.884404) (xy 118.938549 -289.833109) (xy 110.251963 -289.833109)
			(xy 110.251748 -289.844734) (xy 110.251748 -291.073078) (xy 110.251282 -291.110464) (xy 110.243878 -291.184868)
			(xy 110.22917 -291.258179) (xy 110.207302 -291.329682) (xy 110.178487 -291.398678) (xy 110.143006 -291.464496)
			(xy 110.122462 -291.495734) (xy 110.129471 -291.533508) (xy 110.136978 -291.609972) (xy 110.137448 -291.648388)
			(xy 110.137448 -292.35527) (xy 110.137146 -292.38267) (xy 110.133203 -292.43733) (xy 110.129574 -292.46449)
			(xy 110.1281 -292.477982) (xy 110.131519 -292.504898) (xy 110.141913 -292.529959) (xy 110.158546 -292.551394)
			(xy 110.180241 -292.567686) (xy 110.205464 -292.577683) (xy 110.23243 -292.580676) (xy 110.245906 -292.579044)
			(xy 110.260606 -292.576889) (xy 110.290231 -292.574601) (xy 110.305088 -292.574472) (xy 110.333131 -292.574947)
			(xy 110.388617 -292.583123) (xy 110.442305 -292.599344) (xy 110.493035 -292.623261) (xy 110.539711 -292.654355)
			(xy 110.560866 -292.67277) (xy 110.572308 -292.682415) (xy 110.599351 -292.695195) (xy 110.628938 -292.699581)
			(xy 110.658525 -292.695195) (xy 110.685568 -292.682415) (xy 110.69701 -292.67277) (xy 110.718164 -292.654357)
			(xy 110.764855 -292.623293) (xy 110.815587 -292.599389) (xy 110.869269 -292.583162) (xy 110.924747 -292.574959)
			(xy 110.952788 -292.574472) (xy 110.980043 -292.574934) (xy 111.033998 -292.58269) (xy 111.0863 -292.598046)
			(xy 111.135884 -292.620689) (xy 111.181741 -292.650158) (xy 111.222938 -292.685854) (xy 111.258635 -292.727049)
			(xy 111.288105 -292.772905) (xy 111.31075 -292.822489) (xy 111.326107 -292.87479) (xy 111.333865 -292.928745)
			(xy 111.333865 -292.983252) (xy 115.746758 -292.983252) (xy 115.746758 -292.928748) (xy 115.754514 -292.874799)
			(xy 115.769869 -292.822503) (xy 115.792511 -292.772924) (xy 115.821977 -292.727072) (xy 115.857669 -292.68588)
			(xy 115.898859 -292.650187) (xy 115.94471 -292.620718) (xy 115.994288 -292.598075) (xy 116.046583 -292.582718)
			(xy 116.100532 -292.574959) (xy 116.127784 -292.574472) (xy 116.155155 -292.57493) (xy 116.209335 -292.582747)
			(xy 116.261839 -292.598237) (xy 116.311586 -292.621081) (xy 116.357551 -292.650809) (xy 116.378482 -292.668452)
			(xy 116.38981 -292.677688) (xy 116.416367 -292.689864) (xy 116.445284 -292.694037) (xy 116.474201 -292.689864)
			(xy 116.500758 -292.677688) (xy 116.512086 -292.668452) (xy 116.533019 -292.650811) (xy 116.578987 -292.621087)
			(xy 116.628733 -292.598241) (xy 116.681235 -292.582745) (xy 116.735413 -292.574916) (xy 116.790155 -292.574916)
			(xy 116.844333 -292.582745) (xy 116.896835 -292.598241) (xy 116.946581 -292.621087) (xy 116.992549 -292.650811)
			(xy 117.013482 -292.668452) (xy 117.02481 -292.677688) (xy 117.051367 -292.689864) (xy 117.080284 -292.694037)
			(xy 117.109201 -292.689864) (xy 117.135758 -292.677688) (xy 117.147086 -292.668452) (xy 117.168019 -292.650814)
			(xy 117.213991 -292.6211) (xy 117.263738 -292.598263) (xy 117.316239 -292.582772) (xy 117.370415 -292.574945)
			(xy 117.397784 -292.574472) (xy 117.425036 -292.574974) (xy 117.478986 -292.582729) (xy 117.531283 -292.598083)
			(xy 117.580863 -292.620723) (xy 117.626715 -292.650189) (xy 117.667908 -292.685881) (xy 117.703601 -292.727072)
			(xy 117.733069 -292.772923) (xy 117.755712 -292.822502) (xy 117.771068 -292.874798) (xy 117.778825 -292.928748)
			(xy 117.778825 -292.95598) (xy 122.307602 -292.95598) (xy 122.311673 -292.900358) (xy 122.323799 -292.845921)
			(xy 122.343722 -292.79383) (xy 122.371018 -292.745195) (xy 122.405104 -292.701052) (xy 122.445253 -292.662343)
			(xy 122.490611 -292.629892) (xy 122.540211 -292.604391) (xy 122.592995 -292.586384) (xy 122.647838 -292.576254)
			(xy 122.703572 -292.574217) (xy 122.759009 -292.580317) (xy 122.812966 -292.594423) (xy 122.864295 -292.616235)
			(xy 122.911901 -292.645289) (xy 122.954769 -292.680964) (xy 122.991986 -292.722501) (xy 123.022759 -292.769014)
			(xy 123.046431 -292.819511) (xy 123.062499 -292.872918) (xy 123.070619 -292.928094) (xy 123.071128 -292.95598)
			(xy 123.070619 -292.983866) (xy 123.062499 -293.039042) (xy 123.046431 -293.092449) (xy 123.022759 -293.142946)
			(xy 122.991986 -293.189459) (xy 122.954769 -293.230996) (xy 122.911901 -293.266671) (xy 122.864295 -293.295725)
			(xy 122.812966 -293.317537) (xy 122.759009 -293.331643) (xy 122.703572 -293.337743) (xy 122.647838 -293.335706)
			(xy 122.592995 -293.325576) (xy 122.540211 -293.307569) (xy 122.490611 -293.282068) (xy 122.445253 -293.249617)
			(xy 122.405104 -293.210908) (xy 122.371018 -293.166765) (xy 122.343722 -293.11813) (xy 122.323799 -293.066039)
			(xy 122.311673 -293.011602) (xy 122.307602 -292.95598) (xy 117.778825 -292.95598) (xy 117.778825 -292.983252)
			(xy 117.771068 -293.037202) (xy 117.755712 -293.089498) (xy 117.733069 -293.139077) (xy 117.703601 -293.184928)
			(xy 117.667908 -293.226119) (xy 117.626715 -293.261811) (xy 117.580863 -293.291277) (xy 117.531283 -293.313917)
			(xy 117.478986 -293.329271) (xy 117.425036 -293.337026) (xy 117.397784 -293.337488) (xy 117.370413 -293.337034)
			(xy 117.316234 -293.329214) (xy 117.26373 -293.313722) (xy 117.213984 -293.290878) (xy 117.168017 -293.26115)
			(xy 117.147086 -293.243508) (xy 117.135758 -293.234272) (xy 117.109201 -293.222096) (xy 117.080284 -293.217923)
			(xy 117.051367 -293.222096) (xy 117.02481 -293.234272) (xy 117.013482 -293.243508) (xy 116.992549 -293.261149)
			(xy 116.946581 -293.290873) (xy 116.896835 -293.313719) (xy 116.844333 -293.329215) (xy 116.790155 -293.337044)
			(xy 116.735413 -293.337044) (xy 116.681235 -293.329215) (xy 116.628733 -293.313719) (xy 116.578987 -293.290873)
			(xy 116.533019 -293.261149) (xy 116.512086 -293.243508) (xy 116.500758 -293.234272) (xy 116.474201 -293.222096)
			(xy 116.445284 -293.217923) (xy 116.416367 -293.222096) (xy 116.38981 -293.234272) (xy 116.378482 -293.243508)
			(xy 116.357531 -293.261123) (xy 116.311563 -293.290838) (xy 116.26182 -293.313679) (xy 116.209324 -293.329176)
			(xy 116.155152 -293.33701) (xy 116.127784 -293.337488) (xy 116.100532 -293.337041) (xy 116.046583 -293.329282)
			(xy 115.994288 -293.313925) (xy 115.94471 -293.291282) (xy 115.898859 -293.261813) (xy 115.857669 -293.22612)
			(xy 115.821977 -293.184928) (xy 115.792511 -293.139076) (xy 115.769869 -293.089497) (xy 115.754514 -293.037201)
			(xy 115.746758 -292.983252) (xy 111.333865 -292.983252) (xy 111.333865 -292.983255) (xy 111.326107 -293.03721)
			(xy 111.31075 -293.089511) (xy 111.288105 -293.139095) (xy 111.258635 -293.184951) (xy 111.222938 -293.226146)
			(xy 111.181741 -293.261842) (xy 111.135884 -293.291311) (xy 111.0863 -293.313954) (xy 111.033998 -293.32931)
			(xy 110.980043 -293.337066) (xy 110.952788 -293.337488) (xy 110.924743 -293.337018) (xy 110.869253 -293.328852)
			(xy 110.815559 -293.312637) (xy 110.764823 -293.288726) (xy 110.718141 -293.257634) (xy 110.69701 -293.23919)
			(xy 110.685568 -293.229545) (xy 110.658525 -293.216765) (xy 110.628938 -293.212379) (xy 110.599351 -293.216765)
			(xy 110.572308 -293.229545) (xy 110.560866 -293.23919) (xy 110.539712 -293.257603) (xy 110.493021 -293.288668)
			(xy 110.442289 -293.31257) (xy 110.388607 -293.328796) (xy 110.333129 -293.336996) (xy 110.305088 -293.337488)
			(xy 110.277647 -293.336985) (xy 110.223338 -293.329078) (xy 110.170717 -293.313486) (xy 110.120866 -293.29053)
			(xy 110.09757 -293.27602) (xy 110.085877 -293.268998) (xy 110.059869 -293.260812) (xy 110.032621 -293.259802)
			(xy 110.006079 -293.266042) (xy 109.982135 -293.279085) (xy 109.962498 -293.298001) (xy 109.948569 -293.321441)
			(xy 109.941342 -293.347731) (xy 109.940852 -293.361364) (xy 109.940852 -294.633396) (xy 109.941289 -294.647031)
			(xy 109.948512 -294.673328) (xy 109.962442 -294.696771) (xy 109.982085 -294.715688) (xy 110.006037 -294.728725)
			(xy 110.032587 -294.734952) (xy 110.059837 -294.733924) (xy 110.085842 -294.725714) (xy 110.09757 -294.71874)
			(xy 110.120847 -294.704193) (xy 110.170693 -294.681214) (xy 110.223322 -294.665628) (xy 110.277644 -294.657761)
			(xy 110.305088 -294.657272) (xy 110.333131 -294.657747) (xy 110.388617 -294.665923) (xy 110.442305 -294.682144)
			(xy 110.493035 -294.706061) (xy 110.539711 -294.737155) (xy 110.560866 -294.75557) (xy 110.572308 -294.765215)
			(xy 110.599351 -294.777995) (xy 110.628938 -294.782381) (xy 110.658525 -294.777995) (xy 110.685568 -294.765215)
			(xy 110.69701 -294.75557) (xy 110.718164 -294.737157) (xy 110.764855 -294.706093) (xy 110.815587 -294.682189)
			(xy 110.869269 -294.665962) (xy 110.924747 -294.657759) (xy 110.952788 -294.657272) (xy 110.980043 -294.657734)
			(xy 111.033998 -294.66549) (xy 111.0863 -294.680846) (xy 111.135884 -294.703489) (xy 111.181741 -294.732958)
			(xy 111.222938 -294.768654) (xy 111.258635 -294.809849) (xy 111.288105 -294.855705) (xy 111.31075 -294.905289)
			(xy 111.326107 -294.95759) (xy 111.333865 -295.011545) (xy 111.333865 -295.066052) (xy 115.746758 -295.066052)
			(xy 115.746758 -295.011548) (xy 115.754514 -294.957599) (xy 115.769869 -294.905303) (xy 115.792511 -294.855724)
			(xy 115.821977 -294.809872) (xy 115.857669 -294.76868) (xy 115.898859 -294.732987) (xy 115.94471 -294.703518)
			(xy 115.994288 -294.680875) (xy 116.046583 -294.665518) (xy 116.100532 -294.657759) (xy 116.127784 -294.657272)
			(xy 116.155155 -294.65773) (xy 116.209335 -294.665547) (xy 116.261839 -294.681037) (xy 116.311586 -294.703881)
			(xy 116.357551 -294.733609) (xy 116.378482 -294.751252) (xy 116.38981 -294.760488) (xy 116.416367 -294.772664)
			(xy 116.445284 -294.776837) (xy 116.474201 -294.772664) (xy 116.500758 -294.760488) (xy 116.512086 -294.751252)
			(xy 116.533019 -294.733611) (xy 116.578987 -294.703887) (xy 116.628733 -294.681041) (xy 116.681235 -294.665545)
			(xy 116.735413 -294.657716) (xy 116.790155 -294.657716) (xy 116.844333 -294.665545) (xy 116.896835 -294.681041)
			(xy 116.946581 -294.703887) (xy 116.992549 -294.733611) (xy 117.013482 -294.751252) (xy 117.02481 -294.760488)
			(xy 117.051367 -294.772664) (xy 117.080284 -294.776837) (xy 117.109201 -294.772664) (xy 117.135758 -294.760488)
			(xy 117.147086 -294.751252) (xy 117.168019 -294.733614) (xy 117.213991 -294.7039) (xy 117.263738 -294.681063)
			(xy 117.316239 -294.665572) (xy 117.370415 -294.657745) (xy 117.397784 -294.657272) (xy 117.425036 -294.657774)
			(xy 117.478986 -294.665529) (xy 117.531283 -294.680883) (xy 117.580863 -294.703523) (xy 117.626715 -294.732989)
			(xy 117.667908 -294.768681) (xy 117.703601 -294.809872) (xy 117.733069 -294.855723) (xy 117.755712 -294.905302)
			(xy 117.771068 -294.957598) (xy 117.778825 -295.011548) (xy 117.778825 -295.03878) (xy 122.307602 -295.03878)
			(xy 122.311673 -294.983158) (xy 122.323799 -294.928721) (xy 122.343722 -294.87663) (xy 122.371018 -294.827995)
			(xy 122.405104 -294.783852) (xy 122.445253 -294.745143) (xy 122.490611 -294.712692) (xy 122.540211 -294.687191)
			(xy 122.592995 -294.669184) (xy 122.647838 -294.659054) (xy 122.703572 -294.657017) (xy 122.759009 -294.663117)
			(xy 122.812966 -294.677223) (xy 122.864295 -294.699035) (xy 122.911901 -294.728089) (xy 122.954769 -294.763764)
			(xy 122.991986 -294.805301) (xy 123.022759 -294.851814) (xy 123.046431 -294.902311) (xy 123.062499 -294.955718)
			(xy 123.070619 -295.010894) (xy 123.071128 -295.03878) (xy 123.070619 -295.066666) (xy 123.062499 -295.121842)
			(xy 123.046431 -295.175249) (xy 123.022759 -295.225746) (xy 122.991986 -295.272259) (xy 122.954769 -295.313796)
			(xy 122.911901 -295.349471) (xy 122.864295 -295.378525) (xy 122.812966 -295.400337) (xy 122.759009 -295.414443)
			(xy 122.703572 -295.420543) (xy 122.647838 -295.418506) (xy 122.592995 -295.408376) (xy 122.540211 -295.390369)
			(xy 122.490611 -295.364868) (xy 122.445253 -295.332417) (xy 122.405104 -295.293708) (xy 122.371018 -295.249565)
			(xy 122.343722 -295.20093) (xy 122.323799 -295.148839) (xy 122.311673 -295.094402) (xy 122.307602 -295.03878)
			(xy 117.778825 -295.03878) (xy 117.778825 -295.066052) (xy 117.771068 -295.120002) (xy 117.755712 -295.172298)
			(xy 117.733069 -295.221877) (xy 117.703601 -295.267728) (xy 117.667908 -295.308919) (xy 117.626715 -295.344611)
			(xy 117.580863 -295.374077) (xy 117.531283 -295.396717) (xy 117.478986 -295.412071) (xy 117.425036 -295.419826)
			(xy 117.397784 -295.420288) (xy 117.370413 -295.419834) (xy 117.316234 -295.412014) (xy 117.26373 -295.396522)
			(xy 117.213984 -295.373678) (xy 117.168017 -295.34395) (xy 117.147086 -295.326308) (xy 117.135758 -295.317072)
			(xy 117.109201 -295.304896) (xy 117.080284 -295.300723) (xy 117.051367 -295.304896) (xy 117.02481 -295.317072)
			(xy 117.013482 -295.326308) (xy 116.992549 -295.343949) (xy 116.946581 -295.373673) (xy 116.896835 -295.396519)
			(xy 116.844333 -295.412015) (xy 116.790155 -295.419844) (xy 116.735413 -295.419844) (xy 116.681235 -295.412015)
			(xy 116.628733 -295.396519) (xy 116.578987 -295.373673) (xy 116.533019 -295.343949) (xy 116.512086 -295.326308)
			(xy 116.500758 -295.317072) (xy 116.474201 -295.304896) (xy 116.445284 -295.300723) (xy 116.416367 -295.304896)
			(xy 116.38981 -295.317072) (xy 116.378482 -295.326308) (xy 116.357531 -295.343923) (xy 116.311563 -295.373638)
			(xy 116.26182 -295.396479) (xy 116.209324 -295.411976) (xy 116.155152 -295.41981) (xy 116.127784 -295.420288)
			(xy 116.100532 -295.419841) (xy 116.046583 -295.412082) (xy 115.994288 -295.396725) (xy 115.94471 -295.374082)
			(xy 115.898859 -295.344613) (xy 115.857669 -295.30892) (xy 115.821977 -295.267728) (xy 115.792511 -295.221876)
			(xy 115.769869 -295.172297) (xy 115.754514 -295.120001) (xy 115.746758 -295.066052) (xy 111.333865 -295.066052)
			(xy 111.333865 -295.066055) (xy 111.326107 -295.12001) (xy 111.31075 -295.172311) (xy 111.288105 -295.221895)
			(xy 111.258635 -295.267751) (xy 111.222938 -295.308946) (xy 111.181741 -295.344642) (xy 111.135884 -295.374111)
			(xy 111.0863 -295.396754) (xy 111.033998 -295.41211) (xy 110.980043 -295.419866) (xy 110.952788 -295.420288)
			(xy 110.924743 -295.419818) (xy 110.869253 -295.411652) (xy 110.815559 -295.395437) (xy 110.764823 -295.371526)
			(xy 110.718141 -295.340434) (xy 110.69701 -295.32199) (xy 110.685568 -295.312345) (xy 110.658525 -295.299565)
			(xy 110.628938 -295.295179) (xy 110.599351 -295.299565) (xy 110.572308 -295.312345) (xy 110.560866 -295.32199)
			(xy 110.539712 -295.340403) (xy 110.493021 -295.371468) (xy 110.442289 -295.39537) (xy 110.388607 -295.411596)
			(xy 110.333129 -295.419796) (xy 110.305088 -295.420288) (xy 110.277647 -295.419785) (xy 110.223338 -295.411878)
			(xy 110.170717 -295.396286) (xy 110.120866 -295.37333) (xy 110.09757 -295.35882) (xy 110.085877 -295.351798)
			(xy 110.059869 -295.343612) (xy 110.032621 -295.342602) (xy 110.006079 -295.348842) (xy 109.982135 -295.361885)
			(xy 109.962498 -295.380801) (xy 109.948569 -295.404241) (xy 109.941342 -295.430531) (xy 109.940852 -295.444164)
			(xy 109.940852 -296.792396) (xy 109.941289 -296.806031) (xy 109.948512 -296.832328) (xy 109.962442 -296.855771)
			(xy 109.982085 -296.874688) (xy 110.006037 -296.887725) (xy 110.032587 -296.893952) (xy 110.059837 -296.892924)
			(xy 110.085842 -296.884714) (xy 110.09757 -296.87774) (xy 110.120847 -296.863193) (xy 110.170693 -296.840214)
			(xy 110.223322 -296.824628) (xy 110.277644 -296.816761) (xy 110.305088 -296.816272) (xy 110.333131 -296.816747)
			(xy 110.388617 -296.824923) (xy 110.442305 -296.841144) (xy 110.493035 -296.865061) (xy 110.539711 -296.896155)
			(xy 110.560866 -296.91457) (xy 110.572308 -296.924215) (xy 110.599351 -296.936995) (xy 110.628938 -296.941381)
			(xy 110.658525 -296.936995) (xy 110.685568 -296.924215) (xy 110.69701 -296.91457) (xy 110.718164 -296.896157)
			(xy 110.764855 -296.865093) (xy 110.815587 -296.841189) (xy 110.869269 -296.824962) (xy 110.924747 -296.816759)
			(xy 110.952788 -296.816272) (xy 110.980043 -296.816734) (xy 111.033998 -296.82449) (xy 111.0863 -296.839846)
			(xy 111.135884 -296.862489) (xy 111.181741 -296.891958) (xy 111.222938 -296.927654) (xy 111.258635 -296.968849)
			(xy 111.288105 -297.014705) (xy 111.31075 -297.064289) (xy 111.326107 -297.11659) (xy 111.333865 -297.170545)
			(xy 111.333865 -297.225052) (xy 115.746758 -297.225052) (xy 115.746758 -297.170548) (xy 115.754514 -297.116599)
			(xy 115.769869 -297.064303) (xy 115.792511 -297.014724) (xy 115.821977 -296.968872) (xy 115.857669 -296.92768)
			(xy 115.898859 -296.891987) (xy 115.94471 -296.862518) (xy 115.994288 -296.839875) (xy 116.046583 -296.824518)
			(xy 116.100532 -296.816759) (xy 116.127784 -296.816272) (xy 116.155155 -296.81673) (xy 116.209335 -296.824547)
			(xy 116.261839 -296.840037) (xy 116.311586 -296.862881) (xy 116.357551 -296.892609) (xy 116.378482 -296.910252)
			(xy 116.38981 -296.919488) (xy 116.416367 -296.931664) (xy 116.445284 -296.935837) (xy 116.474201 -296.931664)
			(xy 116.500758 -296.919488) (xy 116.512086 -296.910252) (xy 116.533019 -296.892611) (xy 116.578987 -296.862887)
			(xy 116.628733 -296.840041) (xy 116.681235 -296.824545) (xy 116.735413 -296.816716) (xy 116.790155 -296.816716)
			(xy 116.844333 -296.824545) (xy 116.896835 -296.840041) (xy 116.946581 -296.862887) (xy 116.992549 -296.892611)
			(xy 117.013482 -296.910252) (xy 117.02481 -296.919488) (xy 117.051367 -296.931664) (xy 117.080284 -296.935837)
			(xy 117.109201 -296.931664) (xy 117.135758 -296.919488) (xy 117.147086 -296.910252) (xy 117.168019 -296.892614)
			(xy 117.213991 -296.8629) (xy 117.263738 -296.840063) (xy 117.316239 -296.824572) (xy 117.370415 -296.816745)
			(xy 117.397784 -296.816272) (xy 117.425036 -296.816774) (xy 117.478986 -296.824529) (xy 117.531283 -296.839883)
			(xy 117.580863 -296.862523) (xy 117.626715 -296.891989) (xy 117.667908 -296.927681) (xy 117.703601 -296.968872)
			(xy 117.733069 -297.014723) (xy 117.755712 -297.064302) (xy 117.771068 -297.116598) (xy 117.778825 -297.170548)
			(xy 117.778825 -297.19778) (xy 122.307602 -297.19778) (xy 122.311673 -297.142158) (xy 122.323799 -297.087721)
			(xy 122.343722 -297.03563) (xy 122.371018 -296.986995) (xy 122.405104 -296.942852) (xy 122.445253 -296.904143)
			(xy 122.490611 -296.871692) (xy 122.540211 -296.846191) (xy 122.592995 -296.828184) (xy 122.647838 -296.818054)
			(xy 122.703572 -296.816017) (xy 122.759009 -296.822117) (xy 122.812966 -296.836223) (xy 122.864295 -296.858035)
			(xy 122.911901 -296.887089) (xy 122.954769 -296.922764) (xy 122.991986 -296.964301) (xy 123.022759 -297.010814)
			(xy 123.046431 -297.061311) (xy 123.062499 -297.114718) (xy 123.070619 -297.169894) (xy 123.071128 -297.19778)
			(xy 123.070619 -297.225666) (xy 123.062499 -297.280842) (xy 123.046431 -297.334249) (xy 123.022759 -297.384746)
			(xy 122.991986 -297.431259) (xy 122.954769 -297.472796) (xy 122.911901 -297.508471) (xy 122.90116 -297.515026)
			(xy 131.195582 -297.515026) (xy 131.199563 -297.382006) (xy 131.211492 -297.249461) (xy 131.231327 -297.117868)
			(xy 131.258996 -296.987696) (xy 131.2944 -296.859411) (xy 131.337413 -296.733474) (xy 131.38788 -296.610335)
			(xy 131.445621 -296.490434) (xy 131.51043 -296.374201) (xy 131.582074 -296.262051) (xy 131.660296 -296.154387)
			(xy 131.744817 -296.051594) (xy 131.835335 -295.954039) (xy 131.931524 -295.862073) (xy 132.033042 -295.776023)
			(xy 132.139523 -295.696199) (xy 132.250588 -295.622886) (xy 132.365839 -295.556346) (xy 132.484863 -295.496817)
			(xy 132.607234 -295.444513) (xy 132.732513 -295.399621) (xy 132.860254 -295.362302) (xy 132.989997 -295.332689)
			(xy 133.121279 -295.310888) (xy 133.25363 -295.296978) (xy 133.386576 -295.291007) (xy 133.519641 -295.292998)
			(xy 133.652349 -295.302943) (xy 133.784225 -295.320807) (xy 133.914796 -295.346525) (xy 134.043596 -295.380006)
			(xy 134.170162 -295.42113) (xy 134.294043 -295.46975) (xy 134.414794 -295.525691) (xy 134.531984 -295.588753)
			(xy 134.645193 -295.658711) (xy 134.754015 -295.735315) (xy 134.858061 -295.818289) (xy 134.956959 -295.907337)
			(xy 135.050354 -296.00214) (xy 135.137912 -296.102358) (xy 135.219321 -296.207634) (xy 135.294287 -296.31759)
			(xy 135.362544 -296.431832) (xy 135.423846 -296.549952) (xy 135.477975 -296.671527) (xy 135.524736 -296.796121)
			(xy 135.563962 -296.923289) (xy 135.595512 -297.052575) (xy 135.619275 -297.183516) (xy 135.635164 -297.315644)
			(xy 135.643122 -297.448486) (xy 135.64362 -297.515026) (xy 135.643122 -297.581566) (xy 135.635164 -297.714408)
			(xy 135.619275 -297.846536) (xy 135.595512 -297.977477) (xy 135.563962 -298.106763) (xy 135.524736 -298.233931)
			(xy 135.477975 -298.358525) (xy 135.423846 -298.4801) (xy 135.362544 -298.59822) (xy 135.294287 -298.712462)
			(xy 135.219321 -298.822418) (xy 135.137912 -298.927694) (xy 135.050354 -299.027912) (xy 134.956959 -299.122715)
			(xy 134.858061 -299.211763) (xy 134.754015 -299.294737) (xy 134.645193 -299.371341) (xy 134.531984 -299.441299)
			(xy 134.414794 -299.504361) (xy 134.294043 -299.560302) (xy 134.170162 -299.608922) (xy 134.043596 -299.650046)
			(xy 133.914796 -299.683527) (xy 133.784225 -299.709245) (xy 133.652349 -299.727109) (xy 133.519641 -299.737054)
			(xy 133.386576 -299.739045) (xy 133.25363 -299.733074) (xy 133.121279 -299.719164) (xy 132.989997 -299.697363)
			(xy 132.860254 -299.66775) (xy 132.732513 -299.630431) (xy 132.607234 -299.585539) (xy 132.484863 -299.533235)
			(xy 132.365839 -299.473706) (xy 132.250588 -299.407166) (xy 132.139523 -299.333853) (xy 132.033042 -299.254029)
			(xy 131.931524 -299.167979) (xy 131.835335 -299.076013) (xy 131.744817 -298.978458) (xy 131.660296 -298.875665)
			(xy 131.582074 -298.768001) (xy 131.51043 -298.655851) (xy 131.445621 -298.539618) (xy 131.38788 -298.419717)
			(xy 131.337413 -298.296578) (xy 131.2944 -298.170641) (xy 131.258996 -298.042356) (xy 131.231327 -297.912184)
			(xy 131.211492 -297.780591) (xy 131.199563 -297.648046) (xy 131.195582 -297.515026) (xy 122.90116 -297.515026)
			(xy 122.864295 -297.537525) (xy 122.812966 -297.559337) (xy 122.759009 -297.573443) (xy 122.703572 -297.579543)
			(xy 122.647838 -297.577506) (xy 122.592995 -297.567376) (xy 122.540211 -297.549369) (xy 122.490611 -297.523868)
			(xy 122.445253 -297.491417) (xy 122.405104 -297.452708) (xy 122.371018 -297.408565) (xy 122.343722 -297.35993)
			(xy 122.323799 -297.307839) (xy 122.311673 -297.253402) (xy 122.307602 -297.19778) (xy 117.778825 -297.19778)
			(xy 117.778825 -297.225052) (xy 117.771068 -297.279002) (xy 117.755712 -297.331298) (xy 117.733069 -297.380877)
			(xy 117.703601 -297.426728) (xy 117.667908 -297.467919) (xy 117.626715 -297.503611) (xy 117.580863 -297.533077)
			(xy 117.531283 -297.555717) (xy 117.478986 -297.571071) (xy 117.425036 -297.578826) (xy 117.397784 -297.579288)
			(xy 117.370413 -297.578834) (xy 117.316234 -297.571014) (xy 117.26373 -297.555522) (xy 117.213984 -297.532678)
			(xy 117.168017 -297.50295) (xy 117.147086 -297.485308) (xy 117.135758 -297.476072) (xy 117.109201 -297.463896)
			(xy 117.080284 -297.459723) (xy 117.051367 -297.463896) (xy 117.02481 -297.476072) (xy 117.013482 -297.485308)
			(xy 116.992549 -297.502949) (xy 116.946581 -297.532673) (xy 116.896835 -297.555519) (xy 116.844333 -297.571015)
			(xy 116.790155 -297.578844) (xy 116.735413 -297.578844) (xy 116.681235 -297.571015) (xy 116.628733 -297.555519)
			(xy 116.578987 -297.532673) (xy 116.533019 -297.502949) (xy 116.512086 -297.485308) (xy 116.500758 -297.476072)
			(xy 116.474201 -297.463896) (xy 116.445284 -297.459723) (xy 116.416367 -297.463896) (xy 116.38981 -297.476072)
			(xy 116.378482 -297.485308) (xy 116.357531 -297.502923) (xy 116.311563 -297.532638) (xy 116.26182 -297.555479)
			(xy 116.209324 -297.570976) (xy 116.155152 -297.57881) (xy 116.127784 -297.579288) (xy 116.100532 -297.578841)
			(xy 116.046583 -297.571082) (xy 115.994288 -297.555725) (xy 115.94471 -297.533082) (xy 115.898859 -297.503613)
			(xy 115.857669 -297.46792) (xy 115.821977 -297.426728) (xy 115.792511 -297.380876) (xy 115.769869 -297.331297)
			(xy 115.754514 -297.279001) (xy 115.746758 -297.225052) (xy 111.333865 -297.225052) (xy 111.333865 -297.225055)
			(xy 111.326107 -297.27901) (xy 111.31075 -297.331311) (xy 111.288105 -297.380895) (xy 111.258635 -297.426751)
			(xy 111.222938 -297.467946) (xy 111.181741 -297.503642) (xy 111.135884 -297.533111) (xy 111.0863 -297.555754)
			(xy 111.033998 -297.57111) (xy 110.980043 -297.578866) (xy 110.952788 -297.579288) (xy 110.924743 -297.578818)
			(xy 110.869253 -297.570652) (xy 110.815559 -297.554437) (xy 110.764823 -297.530526) (xy 110.718141 -297.499434)
			(xy 110.69701 -297.48099) (xy 110.685568 -297.471345) (xy 110.658525 -297.458565) (xy 110.628938 -297.454179)
			(xy 110.599351 -297.458565) (xy 110.572308 -297.471345) (xy 110.560866 -297.48099) (xy 110.539712 -297.499403)
			(xy 110.493021 -297.530468) (xy 110.442289 -297.55437) (xy 110.388607 -297.570596) (xy 110.333129 -297.578796)
			(xy 110.305088 -297.579288) (xy 110.277043 -297.578818) (xy 110.221553 -297.570652) (xy 110.167859 -297.554437)
			(xy 110.117123 -297.530526) (xy 110.070441 -297.499434) (xy 110.04931 -297.48099) (xy 110.037868 -297.471345)
			(xy 110.010825 -297.458565) (xy 109.981238 -297.454179) (xy 109.951651 -297.458565) (xy 109.924608 -297.471345)
			(xy 109.913166 -297.48099) (xy 109.905354 -297.487914) (xy 109.889089 -297.501002) (xy 109.880654 -297.507152)
			(xy 109.86897 -297.515534) (xy 109.539532 -298.311824) (xy 109.520362 -298.356172) (xy 109.472733 -298.440232)
			(xy 109.444536 -298.479464) (xy 109.428026 -298.501562) (xy 108.643166 -300.333918) (xy 98.375216 -310.601868)
			(xy 95.580708 -312.380122) (xy 91.523336 -315.709738) (xy 97.636834 -315.709738) (xy 97.636834 -315.625042)
			(xy 97.644885 -315.540728) (xy 97.660914 -315.457562) (xy 97.684775 -315.376295) (xy 97.716254 -315.297665)
			(xy 97.755065 -315.222384) (xy 97.800855 -315.151132) (xy 97.853211 -315.084556) (xy 97.911659 -315.023258)
			(xy 97.975669 -314.967793) (xy 98.044661 -314.918664) (xy 98.118011 -314.876315) (xy 98.195054 -314.841131)
			(xy 98.275093 -314.813429) (xy 98.357402 -314.793461) (xy 98.441237 -314.781408) (xy 98.525838 -314.777378)
			(xy 98.610439 -314.781408) (xy 98.694274 -314.793461) (xy 98.776583 -314.813429) (xy 98.856622 -314.841131)
			(xy 98.933665 -314.876315) (xy 99.007015 -314.918664) (xy 99.076007 -314.967793) (xy 99.140017 -315.023258)
			(xy 99.198465 -315.084556) (xy 99.250821 -315.151132) (xy 99.296611 -315.222384) (xy 99.335422 -315.297665)
			(xy 99.366901 -315.376295) (xy 99.390762 -315.457562) (xy 99.406791 -315.540728) (xy 99.414842 -315.625042)
			(xy 99.415346 -315.66739) (xy 99.610423 -315.66739) (xy 99.614445 -315.58167) (xy 99.626476 -315.496702)
			(xy 99.646412 -315.413235) (xy 99.674075 -315.332001) (xy 99.709224 -315.253715) (xy 99.75155 -315.179064)
			(xy 99.800679 -315.108705) (xy 99.856182 -315.043255) (xy 99.917569 -314.983291) (xy 99.984302 -314.929338)
			(xy 100.055794 -314.881871) (xy 100.131416 -314.841307) (xy 100.210505 -314.808003) (xy 100.292365 -314.782251)
			(xy 100.376276 -314.764278) (xy 100.461502 -314.754242) (xy 100.547294 -314.75223) (xy 100.632896 -314.758261)
			(xy 100.717558 -314.772281) (xy 100.800535 -314.794167) (xy 100.881098 -314.823728) (xy 100.958538 -314.860702)
			(xy 101.032177 -314.904766) (xy 101.101365 -314.955532) (xy 101.165496 -315.012553) (xy 101.224005 -315.075329)
			(xy 101.276378 -315.143309) (xy 101.322156 -315.215894) (xy 101.360936 -315.292446) (xy 101.392377 -315.372294)
			(xy 101.416203 -315.454735) (xy 101.432204 -315.539045) (xy 101.440239 -315.624483) (xy 101.440742 -315.66739)
			(xy 101.440246 -315.709738) (xy 103.834434 -315.709738) (xy 103.834434 -315.625042) (xy 103.842485 -315.540728)
			(xy 103.858514 -315.457562) (xy 103.882375 -315.376295) (xy 103.913854 -315.297665) (xy 103.952665 -315.222384)
			(xy 103.998455 -315.151132) (xy 104.050811 -315.084556) (xy 104.109259 -315.023258) (xy 104.173269 -314.967793)
			(xy 104.242261 -314.918664) (xy 104.315611 -314.876315) (xy 104.392654 -314.841131) (xy 104.472693 -314.813429)
			(xy 104.555002 -314.793461) (xy 104.638837 -314.781408) (xy 104.723438 -314.777378) (xy 104.808039 -314.781408)
			(xy 104.891874 -314.793461) (xy 104.974183 -314.813429) (xy 105.054222 -314.841131) (xy 105.131265 -314.876315)
			(xy 105.204615 -314.918664) (xy 105.273607 -314.967793) (xy 105.337617 -315.023258) (xy 105.396065 -315.084556)
			(xy 105.448421 -315.151132) (xy 105.494211 -315.222384) (xy 105.533022 -315.297665) (xy 105.564501 -315.376295)
			(xy 105.588362 -315.457562) (xy 105.604391 -315.540728) (xy 105.612442 -315.625042) (xy 105.612946 -315.66739)
			(xy 105.808023 -315.66739) (xy 105.812045 -315.58167) (xy 105.824076 -315.496702) (xy 105.844012 -315.413235)
			(xy 105.871675 -315.332001) (xy 105.906824 -315.253715) (xy 105.94915 -315.179064) (xy 105.998279 -315.108705)
			(xy 106.053782 -315.043255) (xy 106.115169 -314.983291) (xy 106.181902 -314.929338) (xy 106.253394 -314.881871)
			(xy 106.329016 -314.841307) (xy 106.408105 -314.808003) (xy 106.489965 -314.782251) (xy 106.573876 -314.764278)
			(xy 106.659102 -314.754242) (xy 106.744894 -314.75223) (xy 106.830496 -314.758261) (xy 106.915158 -314.772281)
			(xy 106.998135 -314.794167) (xy 107.078698 -314.823728) (xy 107.156138 -314.860702) (xy 107.229777 -314.904766)
			(xy 107.298965 -314.955532) (xy 107.363096 -315.012553) (xy 107.421605 -315.075329) (xy 107.473978 -315.143309)
			(xy 107.519756 -315.215894) (xy 107.558536 -315.292446) (xy 107.589977 -315.372294) (xy 107.613803 -315.454735)
			(xy 107.629804 -315.539045) (xy 107.637839 -315.624483) (xy 107.638342 -315.66739) (xy 107.637846 -315.709738)
			(xy 110.012222 -315.709738) (xy 110.012222 -315.625042) (xy 110.020273 -315.540728) (xy 110.036302 -315.457562)
			(xy 110.060163 -315.376295) (xy 110.091642 -315.297665) (xy 110.130453 -315.222384) (xy 110.176243 -315.151132)
			(xy 110.228599 -315.084556) (xy 110.287047 -315.023258) (xy 110.351057 -314.967793) (xy 110.420049 -314.918664)
			(xy 110.493399 -314.876315) (xy 110.570442 -314.841131) (xy 110.650481 -314.813429) (xy 110.73279 -314.793461)
			(xy 110.816625 -314.781408) (xy 110.901226 -314.777378) (xy 110.985827 -314.781408) (xy 111.069662 -314.793461)
			(xy 111.151971 -314.813429) (xy 111.23201 -314.841131) (xy 111.309053 -314.876315) (xy 111.382403 -314.918664)
			(xy 111.451395 -314.967793) (xy 111.515405 -315.023258) (xy 111.573853 -315.084556) (xy 111.626209 -315.151132)
			(xy 111.671999 -315.222384) (xy 111.71081 -315.297665) (xy 111.742289 -315.376295) (xy 111.76615 -315.457562)
			(xy 111.782179 -315.540728) (xy 111.79023 -315.625042) (xy 111.790734 -315.66739) (xy 111.985811 -315.66739)
			(xy 111.989833 -315.58167) (xy 112.001864 -315.496702) (xy 112.0218 -315.413235) (xy 112.049463 -315.332001)
			(xy 112.084612 -315.253715) (xy 112.126938 -315.179064) (xy 112.176067 -315.108705) (xy 112.23157 -315.043255)
			(xy 112.292957 -314.983291) (xy 112.35969 -314.929338) (xy 112.431182 -314.881871) (xy 112.506804 -314.841307)
			(xy 112.585893 -314.808003) (xy 112.667753 -314.782251) (xy 112.751664 -314.764278) (xy 112.83689 -314.754242)
			(xy 112.922682 -314.75223) (xy 113.008284 -314.758261) (xy 113.092946 -314.772281) (xy 113.175923 -314.794167)
			(xy 113.256486 -314.823728) (xy 113.333926 -314.860702) (xy 113.407565 -314.904766) (xy 113.476753 -314.955532)
			(xy 113.540884 -315.012553) (xy 113.599393 -315.075329) (xy 113.651766 -315.143309) (xy 113.697544 -315.215894)
			(xy 113.736324 -315.292446) (xy 113.767765 -315.372294) (xy 113.791591 -315.454735) (xy 113.807592 -315.539045)
			(xy 113.815627 -315.624483) (xy 113.81613 -315.66739) (xy 113.815634 -315.709738) (xy 116.209822 -315.709738)
			(xy 116.209822 -315.625042) (xy 116.217873 -315.540728) (xy 116.233902 -315.457562) (xy 116.257763 -315.376295)
			(xy 116.289242 -315.297665) (xy 116.328053 -315.222384) (xy 116.373843 -315.151132) (xy 116.426199 -315.084556)
			(xy 116.484647 -315.023258) (xy 116.548657 -314.967793) (xy 116.617649 -314.918664) (xy 116.690999 -314.876315)
			(xy 116.768042 -314.841131) (xy 116.848081 -314.813429) (xy 116.93039 -314.793461) (xy 117.014225 -314.781408)
			(xy 117.098826 -314.777378) (xy 117.183427 -314.781408) (xy 117.267262 -314.793461) (xy 117.349571 -314.813429)
			(xy 117.42961 -314.841131) (xy 117.506653 -314.876315) (xy 117.580003 -314.918664) (xy 117.648995 -314.967793)
			(xy 117.713005 -315.023258) (xy 117.771453 -315.084556) (xy 117.823809 -315.151132) (xy 117.869599 -315.222384)
			(xy 117.90841 -315.297665) (xy 117.939889 -315.376295) (xy 117.96375 -315.457562) (xy 117.979779 -315.540728)
			(xy 117.98783 -315.625042) (xy 117.988334 -315.66739) (xy 118.183411 -315.66739) (xy 118.187433 -315.58167)
			(xy 118.199464 -315.496702) (xy 118.2194 -315.413235) (xy 118.247063 -315.332001) (xy 118.282212 -315.253715)
			(xy 118.324538 -315.179064) (xy 118.373667 -315.108705) (xy 118.42917 -315.043255) (xy 118.490557 -314.983291)
			(xy 118.55729 -314.929338) (xy 118.628782 -314.881871) (xy 118.704404 -314.841307) (xy 118.783493 -314.808003)
			(xy 118.865353 -314.782251) (xy 118.949264 -314.764278) (xy 119.03449 -314.754242) (xy 119.120282 -314.75223)
			(xy 119.205884 -314.758261) (xy 119.290546 -314.772281) (xy 119.373523 -314.794167) (xy 119.454086 -314.823728)
			(xy 119.531526 -314.860702) (xy 119.605165 -314.904766) (xy 119.674353 -314.955532) (xy 119.738484 -315.012553)
			(xy 119.796993 -315.075329) (xy 119.849366 -315.143309) (xy 119.895144 -315.215894) (xy 119.933924 -315.292446)
			(xy 119.965365 -315.372294) (xy 119.989191 -315.454735) (xy 120.005192 -315.539045) (xy 120.013227 -315.624483)
			(xy 120.01373 -315.66739) (xy 120.013234 -315.709738) (xy 122.407422 -315.709738) (xy 122.407422 -315.625042)
			(xy 122.415473 -315.540728) (xy 122.431502 -315.457562) (xy 122.455363 -315.376295) (xy 122.486842 -315.297665)
			(xy 122.525653 -315.222384) (xy 122.571443 -315.151132) (xy 122.623799 -315.084556) (xy 122.682247 -315.023258)
			(xy 122.746257 -314.967793) (xy 122.815249 -314.918664) (xy 122.888599 -314.876315) (xy 122.965642 -314.841131)
			(xy 123.045681 -314.813429) (xy 123.12799 -314.793461) (xy 123.211825 -314.781408) (xy 123.296426 -314.777378)
			(xy 123.381027 -314.781408) (xy 123.464862 -314.793461) (xy 123.547171 -314.813429) (xy 123.62721 -314.841131)
			(xy 123.704253 -314.876315) (xy 123.777603 -314.918664) (xy 123.846595 -314.967793) (xy 123.910605 -315.023258)
			(xy 123.969053 -315.084556) (xy 124.021409 -315.151132) (xy 124.067199 -315.222384) (xy 124.10601 -315.297665)
			(xy 124.137489 -315.376295) (xy 124.16135 -315.457562) (xy 124.177379 -315.540728) (xy 124.18543 -315.625042)
			(xy 124.185934 -315.66739) (xy 124.381011 -315.66739) (xy 124.385033 -315.58167) (xy 124.397064 -315.496702)
			(xy 124.417 -315.413235) (xy 124.444663 -315.332001) (xy 124.479812 -315.253715) (xy 124.522138 -315.179064)
			(xy 124.571267 -315.108705) (xy 124.62677 -315.043255) (xy 124.688157 -314.983291) (xy 124.75489 -314.929338)
			(xy 124.826382 -314.881871) (xy 124.902004 -314.841307) (xy 124.981093 -314.808003) (xy 125.062953 -314.782251)
			(xy 125.146864 -314.764278) (xy 125.23209 -314.754242) (xy 125.317882 -314.75223) (xy 125.403484 -314.758261)
			(xy 125.488146 -314.772281) (xy 125.571123 -314.794167) (xy 125.651686 -314.823728) (xy 125.729126 -314.860702)
			(xy 125.802765 -314.904766) (xy 125.871953 -314.955532) (xy 125.936084 -315.012553) (xy 125.994593 -315.075329)
			(xy 126.046966 -315.143309) (xy 126.092744 -315.215894) (xy 126.131524 -315.292446) (xy 126.162965 -315.372294)
			(xy 126.186791 -315.454735) (xy 126.202792 -315.539045) (xy 126.210827 -315.624483) (xy 126.21133 -315.66739)
			(xy 126.210827 -315.710297) (xy 126.202792 -315.795735) (xy 126.186791 -315.880045) (xy 126.162965 -315.962486)
			(xy 126.131524 -316.042334) (xy 126.092744 -316.118886) (xy 126.046966 -316.191471) (xy 125.994593 -316.259451)
			(xy 125.936084 -316.322227) (xy 125.871953 -316.379248) (xy 125.802765 -316.430014) (xy 125.729126 -316.474078)
			(xy 125.651686 -316.511052) (xy 125.571123 -316.540613) (xy 125.488146 -316.562499) (xy 125.403484 -316.576519)
			(xy 125.317882 -316.58255) (xy 125.23209 -316.580538) (xy 125.146864 -316.570502) (xy 125.062953 -316.552529)
			(xy 124.981093 -316.526777) (xy 124.902004 -316.493473) (xy 124.826382 -316.452909) (xy 124.75489 -316.405442)
			(xy 124.688157 -316.351489) (xy 124.62677 -316.291525) (xy 124.571267 -316.226075) (xy 124.522138 -316.155716)
			(xy 124.479812 -316.081065) (xy 124.444663 -316.002779) (xy 124.417 -315.921545) (xy 124.397064 -315.838078)
			(xy 124.385033 -315.75311) (xy 124.381011 -315.66739) (xy 124.185934 -315.66739) (xy 124.18543 -315.709738)
			(xy 124.177379 -315.794052) (xy 124.16135 -315.877218) (xy 124.137489 -315.958485) (xy 124.10601 -316.037115)
			(xy 124.067199 -316.112396) (xy 124.021409 -316.183648) (xy 123.969053 -316.250224) (xy 123.910605 -316.311522)
			(xy 123.846595 -316.366987) (xy 123.777603 -316.416116) (xy 123.704253 -316.458465) (xy 123.62721 -316.493649)
			(xy 123.547171 -316.521351) (xy 123.464862 -316.541319) (xy 123.381027 -316.553372) (xy 123.296426 -316.557403)
			(xy 123.211825 -316.553372) (xy 123.12799 -316.541319) (xy 123.045681 -316.521351) (xy 122.965642 -316.493649)
			(xy 122.888599 -316.458465) (xy 122.815249 -316.416116) (xy 122.746257 -316.366987) (xy 122.682247 -316.311522)
			(xy 122.623799 -316.250224) (xy 122.571443 -316.183648) (xy 122.525653 -316.112396) (xy 122.486842 -316.037115)
			(xy 122.455363 -315.958485) (xy 122.431502 -315.877218) (xy 122.415473 -315.794052) (xy 122.407422 -315.709738)
			(xy 120.013234 -315.709738) (xy 120.013227 -315.710297) (xy 120.005192 -315.795735) (xy 119.989191 -315.880045)
			(xy 119.965365 -315.962486) (xy 119.933924 -316.042334) (xy 119.895144 -316.118886) (xy 119.849366 -316.191471)
			(xy 119.796993 -316.259451) (xy 119.738484 -316.322227) (xy 119.674353 -316.379248) (xy 119.605165 -316.430014)
			(xy 119.531526 -316.474078) (xy 119.454086 -316.511052) (xy 119.373523 -316.540613) (xy 119.290546 -316.562499)
			(xy 119.205884 -316.576519) (xy 119.120282 -316.58255) (xy 119.03449 -316.580538) (xy 118.949264 -316.570502)
			(xy 118.865353 -316.552529) (xy 118.783493 -316.526777) (xy 118.704404 -316.493473) (xy 118.628782 -316.452909)
			(xy 118.55729 -316.405442) (xy 118.490557 -316.351489) (xy 118.42917 -316.291525) (xy 118.373667 -316.226075)
			(xy 118.324538 -316.155716) (xy 118.282212 -316.081065) (xy 118.247063 -316.002779) (xy 118.2194 -315.921545)
			(xy 118.199464 -315.838078) (xy 118.187433 -315.75311) (xy 118.183411 -315.66739) (xy 117.988334 -315.66739)
			(xy 117.98783 -315.709738) (xy 117.979779 -315.794052) (xy 117.96375 -315.877218) (xy 117.939889 -315.958485)
			(xy 117.90841 -316.037115) (xy 117.869599 -316.112396) (xy 117.823809 -316.183648) (xy 117.771453 -316.250224)
			(xy 117.713005 -316.311522) (xy 117.648995 -316.366987) (xy 117.580003 -316.416116) (xy 117.506653 -316.458465)
			(xy 117.42961 -316.493649) (xy 117.349571 -316.521351) (xy 117.267262 -316.541319) (xy 117.183427 -316.553372)
			(xy 117.098826 -316.557403) (xy 117.014225 -316.553372) (xy 116.93039 -316.541319) (xy 116.848081 -316.521351)
			(xy 116.768042 -316.493649) (xy 116.690999 -316.458465) (xy 116.617649 -316.416116) (xy 116.548657 -316.366987)
			(xy 116.484647 -316.311522) (xy 116.426199 -316.250224) (xy 116.373843 -316.183648) (xy 116.328053 -316.112396)
			(xy 116.289242 -316.037115) (xy 116.257763 -315.958485) (xy 116.233902 -315.877218) (xy 116.217873 -315.794052)
			(xy 116.209822 -315.709738) (xy 113.815634 -315.709738) (xy 113.815627 -315.710297) (xy 113.807592 -315.795735)
			(xy 113.791591 -315.880045) (xy 113.767765 -315.962486) (xy 113.736324 -316.042334) (xy 113.697544 -316.118886)
			(xy 113.651766 -316.191471) (xy 113.599393 -316.259451) (xy 113.540884 -316.322227) (xy 113.476753 -316.379248)
			(xy 113.407565 -316.430014) (xy 113.333926 -316.474078) (xy 113.256486 -316.511052) (xy 113.175923 -316.540613)
			(xy 113.092946 -316.562499) (xy 113.008284 -316.576519) (xy 112.922682 -316.58255) (xy 112.83689 -316.580538)
			(xy 112.751664 -316.570502) (xy 112.667753 -316.552529) (xy 112.585893 -316.526777) (xy 112.506804 -316.493473)
			(xy 112.431182 -316.452909) (xy 112.35969 -316.405442) (xy 112.292957 -316.351489) (xy 112.23157 -316.291525)
			(xy 112.176067 -316.226075) (xy 112.126938 -316.155716) (xy 112.084612 -316.081065) (xy 112.049463 -316.002779)
			(xy 112.0218 -315.921545) (xy 112.001864 -315.838078) (xy 111.989833 -315.75311) (xy 111.985811 -315.66739)
			(xy 111.790734 -315.66739) (xy 111.79023 -315.709738) (xy 111.782179 -315.794052) (xy 111.76615 -315.877218)
			(xy 111.742289 -315.958485) (xy 111.71081 -316.037115) (xy 111.671999 -316.112396) (xy 111.626209 -316.183648)
			(xy 111.573853 -316.250224) (xy 111.515405 -316.311522) (xy 111.451395 -316.366987) (xy 111.382403 -316.416116)
			(xy 111.309053 -316.458465) (xy 111.23201 -316.493649) (xy 111.151971 -316.521351) (xy 111.069662 -316.541319)
			(xy 110.985827 -316.553372) (xy 110.901226 -316.557403) (xy 110.816625 -316.553372) (xy 110.73279 -316.541319)
			(xy 110.650481 -316.521351) (xy 110.570442 -316.493649) (xy 110.493399 -316.458465) (xy 110.420049 -316.416116)
			(xy 110.351057 -316.366987) (xy 110.287047 -316.311522) (xy 110.228599 -316.250224) (xy 110.176243 -316.183648)
			(xy 110.130453 -316.112396) (xy 110.091642 -316.037115) (xy 110.060163 -315.958485) (xy 110.036302 -315.877218)
			(xy 110.020273 -315.794052) (xy 110.012222 -315.709738) (xy 107.637846 -315.709738) (xy 107.637839 -315.710297)
			(xy 107.629804 -315.795735) (xy 107.613803 -315.880045) (xy 107.589977 -315.962486) (xy 107.558536 -316.042334)
			(xy 107.519756 -316.118886) (xy 107.473978 -316.191471) (xy 107.421605 -316.259451) (xy 107.363096 -316.322227)
			(xy 107.298965 -316.379248) (xy 107.229777 -316.430014) (xy 107.156138 -316.474078) (xy 107.078698 -316.511052)
			(xy 106.998135 -316.540613) (xy 106.915158 -316.562499) (xy 106.830496 -316.576519) (xy 106.744894 -316.58255)
			(xy 106.659102 -316.580538) (xy 106.573876 -316.570502) (xy 106.489965 -316.552529) (xy 106.408105 -316.526777)
			(xy 106.329016 -316.493473) (xy 106.253394 -316.452909) (xy 106.181902 -316.405442) (xy 106.115169 -316.351489)
			(xy 106.053782 -316.291525) (xy 105.998279 -316.226075) (xy 105.94915 -316.155716) (xy 105.906824 -316.081065)
			(xy 105.871675 -316.002779) (xy 105.844012 -315.921545) (xy 105.824076 -315.838078) (xy 105.812045 -315.75311)
			(xy 105.808023 -315.66739) (xy 105.612946 -315.66739) (xy 105.612442 -315.709738) (xy 105.604391 -315.794052)
			(xy 105.588362 -315.877218) (xy 105.564501 -315.958485) (xy 105.533022 -316.037115) (xy 105.494211 -316.112396)
			(xy 105.448421 -316.183648) (xy 105.396065 -316.250224) (xy 105.337617 -316.311522) (xy 105.273607 -316.366987)
			(xy 105.204615 -316.416116) (xy 105.131265 -316.458465) (xy 105.054222 -316.493649) (xy 104.974183 -316.521351)
			(xy 104.891874 -316.541319) (xy 104.808039 -316.553372) (xy 104.723438 -316.557403) (xy 104.638837 -316.553372)
			(xy 104.555002 -316.541319) (xy 104.472693 -316.521351) (xy 104.392654 -316.493649) (xy 104.315611 -316.458465)
			(xy 104.242261 -316.416116) (xy 104.173269 -316.366987) (xy 104.109259 -316.311522) (xy 104.050811 -316.250224)
			(xy 103.998455 -316.183648) (xy 103.952665 -316.112396) (xy 103.913854 -316.037115) (xy 103.882375 -315.958485)
			(xy 103.858514 -315.877218) (xy 103.842485 -315.794052) (xy 103.834434 -315.709738) (xy 101.440246 -315.709738)
			(xy 101.440239 -315.710297) (xy 101.432204 -315.795735) (xy 101.416203 -315.880045) (xy 101.392377 -315.962486)
			(xy 101.360936 -316.042334) (xy 101.322156 -316.118886) (xy 101.276378 -316.191471) (xy 101.224005 -316.259451)
			(xy 101.165496 -316.322227) (xy 101.101365 -316.379248) (xy 101.032177 -316.430014) (xy 100.958538 -316.474078)
			(xy 100.881098 -316.511052) (xy 100.800535 -316.540613) (xy 100.717558 -316.562499) (xy 100.632896 -316.576519)
			(xy 100.547294 -316.58255) (xy 100.461502 -316.580538) (xy 100.376276 -316.570502) (xy 100.292365 -316.552529)
			(xy 100.210505 -316.526777) (xy 100.131416 -316.493473) (xy 100.055794 -316.452909) (xy 99.984302 -316.405442)
			(xy 99.917569 -316.351489) (xy 99.856182 -316.291525) (xy 99.800679 -316.226075) (xy 99.75155 -316.155716)
			(xy 99.709224 -316.081065) (xy 99.674075 -316.002779) (xy 99.646412 -315.921545) (xy 99.626476 -315.838078)
			(xy 99.614445 -315.75311) (xy 99.610423 -315.66739) (xy 99.415346 -315.66739) (xy 99.414842 -315.709738)
			(xy 99.406791 -315.794052) (xy 99.390762 -315.877218) (xy 99.366901 -315.958485) (xy 99.335422 -316.037115)
			(xy 99.296611 -316.112396) (xy 99.250821 -316.183648) (xy 99.198465 -316.250224) (xy 99.140017 -316.311522)
			(xy 99.076007 -316.366987) (xy 99.007015 -316.416116) (xy 98.933665 -316.458465) (xy 98.856622 -316.493649)
			(xy 98.776583 -316.521351) (xy 98.694274 -316.541319) (xy 98.610439 -316.553372) (xy 98.525838 -316.557403)
			(xy 98.441237 -316.553372) (xy 98.357402 -316.541319) (xy 98.275093 -316.521351) (xy 98.195054 -316.493649)
			(xy 98.118011 -316.458465) (xy 98.044661 -316.416116) (xy 97.975669 -316.366987) (xy 97.911659 -316.311522)
			(xy 97.853211 -316.250224) (xy 97.800855 -316.183648) (xy 97.755065 -316.112396) (xy 97.716254 -316.037115)
			(xy 97.684775 -315.958485) (xy 97.660914 -315.877218) (xy 97.644885 -315.794052) (xy 97.636834 -315.709738)
			(xy 91.523336 -315.709738) (xy 83.337146 -322.4276) (xy 80.748632 -325.016368) (xy 80.747108 -325.017892)
			(xy 80.736613 -325.030152) (xy 80.714762 -325.053909) (xy 80.70342 -325.06539) (xy 80.442562 -325.326248)
			(xy 80.431087 -325.337658) (xy 80.407331 -325.359636) (xy 80.395064 -325.37019) (xy 80.393286 -325.37146)
			(xy 79.811372 -325.953374) (xy 79.810102 -325.954898) (xy 79.799548 -325.967226) (xy 79.777569 -325.991109)
			(xy 79.76616 -326.00265) (xy 79.505302 -326.263508) (xy 79.493769 -326.274926) (xy 79.469886 -326.296905)
			(xy 79.45755 -326.30745) (xy 79.456026 -326.30872) (xy 78.395576 -327.36917) (xy 78.09484 -328.00544)
			(xy 77.584554 -329.084686) (xy 77.108304 -330.80071) (xy 76.921106 -332.704694) (xy 76.972414 -332.756002)
			(xy 83.831176 -332.756002)
		)
		(stroke
			(width 0)
			(type solid)
		)
		(fill yes)
		(layer "In6.Cu")
		(net "PVCCIN_CPU1")
	)
	(gr_poly
		(pts
			(xy 356.18801 -237.957106) (xy 356.201181 -237.95669) (xy 356.226644 -237.949944) (xy 356.249532 -237.936906)
			(xy 356.26832 -237.918443) (xy 356.281755 -237.895786) (xy 356.288944 -237.870445) (xy 356.28961 -237.857284)
			(xy 356.290549 -237.831618) (xy 356.299386 -237.781026) (xy 356.315945 -237.73241) (xy 356.339826 -237.686942)
			(xy 356.370453 -237.645716) (xy 356.407091 -237.609725) (xy 356.448855 -237.579835) (xy 356.494741 -237.556768)
			(xy 356.543644 -237.541077) (xy 356.594385 -237.533141) (xy 356.620064 -237.532672) (xy 356.646034 -237.533152)
			(xy 356.697336 -237.541273) (xy 356.746736 -237.55732) (xy 356.793017 -237.580898) (xy 356.835039 -237.611427)
			(xy 356.871767 -237.648154) (xy 356.902297 -237.690175) (xy 356.925876 -237.736455) (xy 356.941925 -237.785854)
			(xy 356.950047 -237.837156) (xy 356.950518 -237.863126) (xy 356.950474 -237.87248) (xy 356.949457 -237.89116)
			(xy 356.948486 -237.900464) (xy 356.947978 -237.903512) (xy 356.947978 -237.957106) (xy 357.037386 -237.957106)
			(xy 357.050086 -237.948724) (xy 357.070335 -237.936043) (xy 357.113707 -237.916006) (xy 357.15951 -237.902416)
			(xy 357.206792 -237.895556) (xy 357.23068 -237.89513) (xy 357.256419 -237.895624) (xy 357.307276 -237.903602)
			(xy 357.356286 -237.919354) (xy 357.402268 -237.942499) (xy 357.423466 -237.957106) (xy 357.977694 -237.957106)
			(xy 357.998888 -237.942488) (xy 358.044858 -237.919311) (xy 358.093872 -237.90356) (xy 358.144738 -237.895617)
			(xy 358.17048 -237.89513) (xy 358.196219 -237.895624) (xy 358.247076 -237.903602) (xy 358.296086 -237.919354)
			(xy 358.342068 -237.942499) (xy 358.363266 -237.957106) (xy 358.917494 -237.957106) (xy 358.938688 -237.942488)
			(xy 358.984658 -237.919311) (xy 359.033672 -237.90356) (xy 359.084538 -237.895617) (xy 359.11028 -237.89513)
			(xy 359.136019 -237.895624) (xy 359.186876 -237.903602) (xy 359.235886 -237.919354) (xy 359.281868 -237.942499)
			(xy 359.303066 -237.957106) (xy 359.857294 -237.957106) (xy 359.878488 -237.942488) (xy 359.924458 -237.919311)
			(xy 359.973472 -237.90356) (xy 360.024338 -237.895617) (xy 360.05008 -237.89513) (xy 360.075819 -237.895624)
			(xy 360.126676 -237.903602) (xy 360.175686 -237.919354) (xy 360.221668 -237.942499) (xy 360.242866 -237.957106)
			(xy 360.797094 -237.957106) (xy 360.818288 -237.942488) (xy 360.864258 -237.919311) (xy 360.913272 -237.90356)
			(xy 360.964138 -237.895617) (xy 360.98988 -237.89513) (xy 361.015619 -237.895624) (xy 361.066476 -237.903602)
			(xy 361.115486 -237.919354) (xy 361.161468 -237.942499) (xy 361.182666 -237.957106) (xy 361.736894 -237.957106)
			(xy 361.758088 -237.942488) (xy 361.804058 -237.919311) (xy 361.853072 -237.90356) (xy 361.903938 -237.895617)
			(xy 361.92968 -237.89513) (xy 361.955419 -237.895624) (xy 362.006276 -237.903602) (xy 362.055286 -237.919354)
			(xy 362.101268 -237.942499) (xy 362.122466 -237.957106) (xy 369.255294 -237.957106) (xy 369.276488 -237.942488)
			(xy 369.322458 -237.919311) (xy 369.371472 -237.90356) (xy 369.422338 -237.895617) (xy 369.44808 -237.89513)
			(xy 369.473819 -237.895624) (xy 369.524676 -237.903602) (xy 369.573686 -237.919354) (xy 369.619668 -237.942499)
			(xy 369.640866 -237.957106) (xy 370.195094 -237.957106) (xy 370.216288 -237.942488) (xy 370.262258 -237.919311)
			(xy 370.311272 -237.90356) (xy 370.362138 -237.895617) (xy 370.38788 -237.89513) (xy 370.413619 -237.895624)
			(xy 370.464476 -237.903602) (xy 370.513486 -237.919354) (xy 370.559468 -237.942499) (xy 370.580666 -237.957106)
			(xy 371.134894 -237.957106) (xy 371.156088 -237.942488) (xy 371.202058 -237.919311) (xy 371.251072 -237.90356)
			(xy 371.301938 -237.895617) (xy 371.32768 -237.89513) (xy 371.353419 -237.895624) (xy 371.404276 -237.903602)
			(xy 371.453286 -237.919354) (xy 371.499268 -237.942499) (xy 371.520466 -237.957106) (xy 372.074694 -237.957106)
			(xy 372.095888 -237.942488) (xy 372.141858 -237.919311) (xy 372.190872 -237.90356) (xy 372.241738 -237.895617)
			(xy 372.26748 -237.89513) (xy 372.293219 -237.895624) (xy 372.344076 -237.903602) (xy 372.393086 -237.919354)
			(xy 372.439068 -237.942499) (xy 372.460266 -237.957106) (xy 373.014494 -237.957106) (xy 373.035688 -237.942488)
			(xy 373.081658 -237.919311) (xy 373.130672 -237.90356) (xy 373.181538 -237.895617) (xy 373.20728 -237.89513)
			(xy 373.237159 -237.895771) (xy 373.295943 -237.906506) (xy 373.32412 -237.916466) (xy 373.3546 -237.92815)
			(xy 373.469916 -237.812834) (xy 373.479517 -237.802607) (xy 373.493206 -237.778134) (xy 373.499721 -237.750861)
			(xy 373.498571 -237.722843) (xy 373.489842 -237.696195) (xy 373.474193 -237.672927) (xy 373.46382 -237.663482)
			(xy 373.445855 -237.647715) (xy 373.414213 -237.61189) (xy 373.388064 -237.571879) (xy 373.367954 -237.528517)
			(xy 373.354304 -237.482709) (xy 373.347399 -237.435413) (xy 373.34698 -237.411514) (xy 373.347462 -237.385545)
			(xy 373.355585 -237.334246) (xy 373.371634 -237.28485) (xy 373.395214 -237.238573) (xy 373.425743 -237.196555)
			(xy 373.46247 -237.15983) (xy 373.50449 -237.129303) (xy 373.550768 -237.105727) (xy 373.600166 -237.089681)
			(xy 373.651465 -237.08156) (xy 373.677434 -237.08106) (xy 373.700808 -237.081483) (xy 373.747083 -237.088114)
			(xy 373.769636 -237.094268) (xy 373.782699 -237.097645) (xy 373.809665 -237.098156) (xy 373.835825 -237.091589)
			(xy 373.859352 -237.078402) (xy 373.878607 -237.059515) (xy 373.892245 -237.036246) (xy 373.899315 -237.010218)
			(xy 373.899684 -236.996732) (xy 373.899684 -236.817154) (xy 373.88243 -236.796853) (xy 373.853975 -236.751814)
			(xy 373.833109 -236.702796) (xy 373.820372 -236.651066) (xy 373.816093 -236.597964) (xy 373.820383 -236.544862)
			(xy 373.833132 -236.493136) (xy 373.854009 -236.444122) (xy 373.882474 -236.39909) (xy 373.899684 -236.37875)
			(xy 373.899684 -236.198664) (xy 373.899263 -236.185186) (xy 373.892196 -236.159172) (xy 373.878565 -236.135915)
			(xy 373.85932 -236.117038) (xy 373.835805 -236.103859) (xy 373.809659 -236.097295) (xy 373.782707 -236.097806)
			(xy 373.769636 -236.101128) (xy 373.747021 -236.107295) (xy 373.700617 -236.113921) (xy 373.67718 -236.114336)
			(xy 373.651215 -236.113825) (xy 373.599925 -236.105699) (xy 373.550538 -236.089649) (xy 373.50427 -236.066072)
			(xy 373.462259 -236.035547) (xy 373.42554 -235.998826) (xy 373.395018 -235.956813) (xy 373.371443 -235.910543)
			(xy 373.355396 -235.861155) (xy 373.347273 -235.809865) (xy 373.347273 -235.757935) (xy 373.355396 -235.706645)
			(xy 373.371443 -235.657257) (xy 373.395018 -235.610987) (xy 373.42554 -235.568974) (xy 373.462259 -235.532253)
			(xy 373.50427 -235.501728) (xy 373.550538 -235.478151) (xy 373.599925 -235.462101) (xy 373.651215 -235.453975)
			(xy 373.67718 -235.453428) (xy 373.700618 -235.453836) (xy 373.747023 -235.460461) (xy 373.769636 -235.466636)
			(xy 373.782697 -235.470013) (xy 373.809661 -235.470525) (xy 373.835818 -235.463958) (xy 373.859343 -235.45077)
			(xy 373.878593 -235.431882) (xy 373.892225 -235.408612) (xy 373.899287 -235.382584) (xy 373.899684 -235.3691)
			(xy 373.899684 -235.189268) (xy 373.882429 -235.168967) (xy 373.853972 -235.123928) (xy 373.833103 -235.074909)
			(xy 373.820364 -235.023178) (xy 373.816083 -234.970075) (xy 373.820372 -234.916971) (xy 373.83312 -234.865243)
			(xy 373.853995 -234.816227) (xy 373.88246 -234.771193) (xy 373.899684 -234.750864) (xy 373.899684 -234.571032)
			(xy 373.899271 -234.557547) (xy 373.892215 -234.531517) (xy 373.878588 -234.508244) (xy 373.85934 -234.489353)
			(xy 373.835816 -234.476163) (xy 373.809659 -234.469595) (xy 373.782694 -234.470108) (xy 373.769636 -234.473496)
			(xy 373.747082 -234.479646) (xy 373.700807 -234.486272) (xy 373.677434 -234.486704) (xy 373.651459 -234.486224)
			(xy 373.600148 -234.478102) (xy 373.550739 -234.462052) (xy 373.50445 -234.438471) (xy 373.46242 -234.407938)
			(xy 373.425684 -234.371206) (xy 373.395147 -234.329179) (xy 373.371561 -234.282892) (xy 373.355506 -234.233485)
			(xy 373.347379 -234.182175) (xy 373.347379 -234.130225) (xy 373.355506 -234.078915) (xy 373.371561 -234.029508)
			(xy 373.395147 -233.983221) (xy 373.425684 -233.941194) (xy 373.46242 -233.904462) (xy 373.50445 -233.873929)
			(xy 373.55074 -233.850348) (xy 373.600148 -233.834298) (xy 373.651459 -233.826176) (xy 373.677434 -233.825796)
			(xy 373.700808 -233.826219) (xy 373.747083 -233.832851) (xy 373.769636 -233.839004) (xy 373.782696 -233.842382)
			(xy 373.809658 -233.842895) (xy 373.835812 -233.836327) (xy 373.859334 -233.823139) (xy 373.87858 -233.80425)
			(xy 373.892206 -233.780979) (xy 373.899261 -233.754951) (xy 373.899684 -233.741468) (xy 373.899684 -233.560874)
			(xy 373.882486 -233.540611) (xy 373.854123 -233.495668) (xy 373.833325 -233.446763) (xy 373.820629 -233.395158)
			(xy 373.816362 -233.342185) (xy 373.820634 -233.289213) (xy 373.833335 -233.237609) (xy 373.854137 -233.188705)
			(xy 373.882504 -233.143765) (xy 373.899684 -233.123486) (xy 373.899684 -232.943146) (xy 373.899273 -232.92966)
			(xy 373.892219 -232.903627) (xy 373.878592 -232.88035) (xy 373.859344 -232.861456) (xy 373.835819 -232.848264)
			(xy 373.809659 -232.841695) (xy 373.782692 -232.842208) (xy 373.769636 -232.84561) (xy 373.747082 -232.851759)
			(xy 373.700807 -232.858385) (xy 373.677434 -232.858818) (xy 373.651466 -232.858338) (xy 373.600168 -232.850218)
			(xy 373.550772 -232.834173) (xy 373.504495 -232.810598) (xy 373.462476 -232.780073) (xy 373.425749 -232.74335)
			(xy 373.39522 -232.701334) (xy 373.37164 -232.655059) (xy 373.35559 -232.605665) (xy 373.347465 -232.554368)
			(xy 373.347465 -232.502432) (xy 373.35559 -232.451135) (xy 373.37164 -232.401741) (xy 373.39522 -232.355466)
			(xy 373.425749 -232.31345) (xy 373.462476 -232.276727) (xy 373.504495 -232.246202) (xy 373.550772 -232.222627)
			(xy 373.600168 -232.206582) (xy 373.651466 -232.198462) (xy 373.677434 -232.19791) (xy 373.700808 -232.198333)
			(xy 373.747083 -232.204965) (xy 373.769636 -232.211118) (xy 373.782697 -232.214496) (xy 373.809659 -232.215008)
			(xy 373.835815 -232.208441) (xy 373.859338 -232.195252) (xy 373.878585 -232.176364) (xy 373.892214 -232.153093)
			(xy 373.899272 -232.127066) (xy 373.899684 -232.113582) (xy 373.899684 -231.93375) (xy 373.882423 -231.913448)
			(xy 373.853952 -231.868407) (xy 373.833071 -231.819384) (xy 373.82032 -231.767648) (xy 373.816029 -231.714536)
			(xy 373.820309 -231.661423) (xy 373.833049 -231.609684) (xy 373.853919 -231.560656) (xy 373.88238 -231.515609)
			(xy 373.899684 -231.495346) (xy 373.899684 -231.31526) (xy 373.899262 -231.301782) (xy 373.892195 -231.275769)
			(xy 373.878563 -231.252513) (xy 373.859319 -231.233637) (xy 373.835804 -231.220458) (xy 373.809659 -231.213895)
			(xy 373.782708 -231.214406) (xy 373.769636 -231.217724) (xy 373.747082 -231.223873) (xy 373.700807 -231.230498)
			(xy 373.677434 -231.230932) (xy 373.651465 -231.230452) (xy 373.600165 -231.222332) (xy 373.550767 -231.206286)
			(xy 373.504488 -231.182709) (xy 373.462467 -231.152183) (xy 373.425739 -231.115459) (xy 373.395208 -231.073441)
			(xy 373.371627 -231.027164) (xy 373.355576 -230.977768) (xy 373.347451 -230.926469) (xy 373.347451 -230.874531)
			(xy 373.355576 -230.823232) (xy 373.371627 -230.773836) (xy 373.395208 -230.727559) (xy 373.425739 -230.685541)
			(xy 373.462467 -230.648817) (xy 373.504488 -230.618291) (xy 373.550767 -230.594714) (xy 373.600165 -230.578668)
			(xy 373.651465 -230.570548) (xy 373.677434 -230.570024) (xy 373.700808 -230.570447) (xy 373.747083 -230.577078)
			(xy 373.769636 -230.583232) (xy 373.782697 -230.586609) (xy 373.809661 -230.587121) (xy 373.835818 -230.580554)
			(xy 373.859342 -230.567366) (xy 373.878591 -230.548478) (xy 373.892223 -230.525208) (xy 373.899284 -230.49918)
			(xy 373.899684 -230.485696) (xy 373.899684 -230.305864) (xy 373.88243 -230.285563) (xy 373.853973 -230.240524)
			(xy 373.833105 -230.191505) (xy 373.820366 -230.139775) (xy 373.816086 -230.086672) (xy 373.820375 -230.033569)
			(xy 373.833123 -229.981841) (xy 373.853999 -229.932826) (xy 373.882464 -229.887792) (xy 373.899684 -229.86746)
			(xy 373.899684 -229.687628) (xy 373.899271 -229.674144) (xy 373.892214 -229.648115) (xy 373.878586 -229.624842)
			(xy 373.859339 -229.605952) (xy 373.835816 -229.592763) (xy 373.809659 -229.586195) (xy 373.782695 -229.586708)
			(xy 373.769636 -229.590092) (xy 373.747082 -229.596242) (xy 373.700807 -229.602868) (xy 373.677434 -229.6033)
			(xy 373.651459 -229.60282) (xy 373.600149 -229.594698) (xy 373.550741 -229.578649) (xy 373.504452 -229.555067)
			(xy 373.462423 -229.524535) (xy 373.425687 -229.487803) (xy 373.39515 -229.445777) (xy 373.371564 -229.39949)
			(xy 373.35551 -229.350084) (xy 373.347383 -229.298775) (xy 373.347383 -229.246825) (xy 373.35551 -229.195516)
			(xy 373.371564 -229.14611) (xy 373.39515 -229.099823) (xy 373.425687 -229.057797) (xy 373.462423 -229.021065)
			(xy 373.504452 -228.990533) (xy 373.550741 -228.966951) (xy 373.600149 -228.950902) (xy 373.651459 -228.94278)
			(xy 373.677434 -228.942392) (xy 373.706116 -228.943009) (xy 373.762619 -228.952918) (xy 373.816562 -228.972432)
			(xy 373.866326 -229.000966) (xy 373.888762 -229.018846) (xy 373.90069 -229.028011) (xy 373.928431 -229.039605)
			(xy 373.958344 -229.042638) (xy 373.987847 -229.036848) (xy 374.014395 -229.022735) (xy 374.025414 -229.012496)
			(xy 374.09374 -228.94417) (xy 374.103922 -228.933187) (xy 374.11798 -228.906757) (xy 374.123776 -228.877388)
			(xy 374.120813 -228.8476) (xy 374.109345 -228.819948) (xy 374.090356 -228.796806) (xy 374.065477 -228.780159)
			(xy 374.051322 -228.77526) (xy 374.026238 -228.767107) (xy 373.978846 -228.743964) (xy 373.935732 -228.713586)
			(xy 373.897991 -228.676745) (xy 373.866582 -228.634377) (xy 373.842303 -228.587556) (xy 373.825769 -228.537474)
			(xy 373.817402 -228.485401) (xy 373.81688 -228.45903) (xy 373.817361 -228.43306) (xy 373.825482 -228.381759)
			(xy 373.84153 -228.332361) (xy 373.865108 -228.286082) (xy 373.895637 -228.244061) (xy 373.932364 -228.207335)
			(xy 373.974385 -228.176806) (xy 374.020665 -228.153228) (xy 374.070063 -228.137181) (xy 374.121364 -228.12906)
			(xy 374.147334 -228.128576) (xy 374.173703 -228.129093) (xy 374.225771 -228.137473) (xy 374.275848 -228.154014)
			(xy 374.322662 -228.178298) (xy 374.365027 -228.209707) (xy 374.401867 -228.247446) (xy 374.432246 -228.290555)
			(xy 374.455394 -228.337941) (xy 374.463564 -228.363018) (xy 374.468404 -228.377209) (xy 374.485024 -228.402145)
			(xy 374.508172 -228.421178) (xy 374.535851 -228.432665) (xy 374.565673 -228.435616) (xy 374.595067 -228.429775)
			(xy 374.621495 -228.415648) (xy 374.632474 -228.405436) (xy 375.254774 -227.783136) (xy 375.24436 -227.75291)
			(xy 375.235914 -227.726727) (xy 375.226852 -227.672467) (xy 375.226326 -227.64496) (xy 375.226838 -227.618994)
			(xy 375.234967 -227.567703) (xy 375.251019 -227.518314) (xy 375.274599 -227.472045) (xy 375.305125 -227.430033)
			(xy 375.341848 -227.393312) (xy 375.383862 -227.362788) (xy 375.430133 -227.339212) (xy 375.479522 -227.323163)
			(xy 375.530814 -227.315037) (xy 375.55678 -227.314506) (xy 375.584286 -227.315034) (xy 375.638545 -227.324101)
			(xy 375.66473 -227.33254) (xy 375.694956 -227.342954) (xy 375.811796 -227.226114) (xy 375.821247 -227.216012)
			(xy 375.834844 -227.191933) (xy 375.841485 -227.16509) (xy 375.840685 -227.137449) (xy 375.832501 -227.111036)
			(xy 375.817534 -227.087784) (xy 375.807478 -227.078286) (xy 375.786994 -227.059292) (xy 375.752081 -227.015689)
			(xy 375.724987 -226.966841) (xy 375.706483 -226.914137) (xy 375.697094 -226.859073) (xy 375.69648 -226.831144)
			(xy 375.69696 -226.805173) (xy 375.705079 -226.753871) (xy 375.721126 -226.704471) (xy 375.744704 -226.658189)
			(xy 375.775232 -226.616167) (xy 375.811959 -226.579439) (xy 375.853981 -226.548909) (xy 375.900261 -226.52533)
			(xy 375.949661 -226.509282) (xy 376.000963 -226.50116) (xy 376.026934 -226.50069) (xy 376.054867 -226.501267)
			(xy 376.109941 -226.510646) (xy 376.162655 -226.529147) (xy 376.211509 -226.556246) (xy 376.255114 -226.59117)
			(xy 376.274076 -226.611688) (xy 376.283609 -226.621703) (xy 376.30685 -226.636664) (xy 376.33325 -226.644844)
			(xy 376.360878 -226.645646) (xy 376.387709 -226.639011) (xy 376.411778 -226.625424) (xy 376.421904 -226.616006)
			(xy 376.424444 -226.613466) (xy 376.717814 -226.613466) (xy 376.73504 -226.594518) (xy 376.774308 -226.561651)
			(xy 376.818176 -226.535235) (xy 376.865594 -226.515901) (xy 376.915426 -226.504112) (xy 376.96648 -226.500151)
			(xy 377.017534 -226.504112) (xy 377.067366 -226.515901) (xy 377.114784 -226.535235) (xy 377.158652 -226.561651)
			(xy 377.19792 -226.594518) (xy 377.215146 -226.613466) (xy 377.657614 -226.613466) (xy 377.67484 -226.594518)
			(xy 377.714108 -226.561651) (xy 377.757976 -226.535235) (xy 377.805394 -226.515901) (xy 377.855226 -226.504112)
			(xy 377.90628 -226.500151) (xy 377.957334 -226.504112) (xy 378.007166 -226.515901) (xy 378.054584 -226.535235)
			(xy 378.098452 -226.561651) (xy 378.13772 -226.594518) (xy 378.154946 -226.613466) (xy 378.597668 -226.613466)
			(xy 378.614894 -226.594518) (xy 378.654162 -226.561651) (xy 378.69803 -226.535235) (xy 378.745448 -226.515901)
			(xy 378.79528 -226.504112) (xy 378.846334 -226.500151) (xy 378.897388 -226.504112) (xy 378.94722 -226.515901)
			(xy 378.994638 -226.535235) (xy 379.038506 -226.561651) (xy 379.077774 -226.594518) (xy 379.095 -226.613466)
			(xy 379.537214 -226.613466) (xy 379.55444 -226.594518) (xy 379.593708 -226.561651) (xy 379.637576 -226.535235)
			(xy 379.684994 -226.515901) (xy 379.734826 -226.504112) (xy 379.78588 -226.500151) (xy 379.836934 -226.504112)
			(xy 379.886766 -226.515901) (xy 379.934184 -226.535235) (xy 379.978052 -226.561651) (xy 380.01732 -226.594518)
			(xy 380.034546 -226.613466) (xy 380.477014 -226.613466) (xy 380.49424 -226.594518) (xy 380.533508 -226.561651)
			(xy 380.577376 -226.535235) (xy 380.624794 -226.515901) (xy 380.674626 -226.504112) (xy 380.72568 -226.500151)
			(xy 380.776734 -226.504112) (xy 380.826566 -226.515901) (xy 380.873984 -226.535235) (xy 380.917852 -226.561651)
			(xy 380.95712 -226.594518) (xy 380.974346 -226.613466) (xy 381.417068 -226.613466) (xy 381.434294 -226.594518)
			(xy 381.473562 -226.561651) (xy 381.51743 -226.535235) (xy 381.564848 -226.515901) (xy 381.61468 -226.504112)
			(xy 381.665734 -226.500151) (xy 381.716788 -226.504112) (xy 381.76662 -226.515901) (xy 381.814038 -226.535235)
			(xy 381.857906 -226.561651) (xy 381.897174 -226.594518) (xy 381.9144 -226.613466) (xy 382.230884 -226.613466)
			(xy 382.566164 -226.278186) (xy 382.566164 -226.000564) (xy 382.468882 -226.000564) (xy 382.464818 -226.046792)
			(xy 382.462196 -226.071151) (xy 382.450682 -226.118769) (xy 382.432262 -226.164165) (xy 382.407341 -226.206344)
			(xy 382.376466 -226.244382) (xy 382.340313 -226.277443) (xy 382.299675 -226.304804) (xy 382.255442 -226.325865)
			(xy 382.208585 -226.340164) (xy 382.160129 -226.347388) (xy 382.135634 -226.347782) (xy 382.109661 -226.347302)
			(xy 382.058353 -226.33918) (xy 382.008948 -226.323132) (xy 381.962662 -226.299552) (xy 381.920634 -226.269021)
			(xy 381.883901 -226.232292) (xy 381.853366 -226.190267) (xy 381.829781 -226.143984) (xy 381.813728 -226.09458)
			(xy 381.805601 -226.043273) (xy 381.805601 -225.991327) (xy 381.813728 -225.94002) (xy 381.829781 -225.890616)
			(xy 381.853366 -225.844333) (xy 381.883901 -225.802308) (xy 381.920634 -225.765579) (xy 381.962662 -225.735048)
			(xy 382.008948 -225.711468) (xy 382.058353 -225.69542) (xy 382.109661 -225.687298) (xy 382.135634 -225.686874)
			(xy 382.15949 -225.687295) (xy 382.206707 -225.694161) (xy 382.252445 -225.707744) (xy 382.295755 -225.727762)
			(xy 382.335737 -225.7538) (xy 382.37156 -225.785316) (xy 382.387348 -225.803206) (xy 382.396637 -225.813377)
			(xy 382.419468 -225.82877) (xy 382.445582 -225.837501) (xy 382.473079 -225.838935) (xy 382.49996 -225.832969)
			(xy 382.524268 -225.820035) (xy 382.544236 -225.801076) (xy 382.55841 -225.777469) (xy 382.56576 -225.750934)
			(xy 382.566164 -225.737166) (xy 382.566164 -225.533712) (xy 382.527302 -225.524314) (xy 382.50364 -225.518095)
			(xy 382.458335 -225.499633) (xy 382.416247 -225.474693) (xy 382.378297 -225.44382) (xy 382.345314 -225.407687)
			(xy 382.318019 -225.367086) (xy 382.29701 -225.322905) (xy 382.282746 -225.276108) (xy 382.275538 -225.227719)
			(xy 382.27508 -225.203258) (xy 382.275688 -225.175277) (xy 382.28513 -225.120116) (xy 382.293876 -225.09353)
			(xy 382.301496 -225.071432) (xy 382.098042 -224.718626) (xy 382.074928 -224.714308) (xy 382.049985 -224.709171)
			(xy 382.001953 -224.69225) (xy 381.957085 -224.668161) (xy 381.916445 -224.637473) (xy 381.880995 -224.600913)
			(xy 381.851573 -224.559347) (xy 381.828877 -224.513759) (xy 381.813444 -224.465228) (xy 381.80564 -224.414905)
			(xy 381.80518 -224.389442) (xy 381.80566 -224.363472) (xy 381.81378 -224.312169) (xy 381.829826 -224.262769)
			(xy 381.853404 -224.216488) (xy 381.883933 -224.174466) (xy 381.92066 -224.137738) (xy 381.962682 -224.107208)
			(xy 382.008962 -224.083629) (xy 382.058362 -224.067582) (xy 382.109664 -224.05946) (xy 382.135634 -224.058988)
			(xy 382.15949 -224.059409) (xy 382.206706 -224.066275) (xy 382.252444 -224.079858) (xy 382.295754 -224.099877)
			(xy 382.335735 -224.125916) (xy 382.371557 -224.157433) (xy 382.387348 -224.17532) (xy 382.396638 -224.18549)
			(xy 382.41947 -224.200881) (xy 382.445584 -224.20961) (xy 382.473081 -224.211044) (xy 382.499961 -224.205078)
			(xy 382.52427 -224.192145) (xy 382.544238 -224.173187) (xy 382.558414 -224.149582) (xy 382.565767 -224.123047)
			(xy 382.566164 -224.10928) (xy 382.566164 -223.90608) (xy 382.527302 -223.896682) (xy 382.502253 -223.890062)
			(xy 382.454445 -223.870098) (xy 382.410339 -223.842918) (xy 382.371014 -223.809187) (xy 382.337435 -223.769734)
			(xy 382.310425 -223.725524) (xy 382.290644 -223.67764) (xy 382.278578 -223.627256) (xy 382.274522 -223.575606)
			(xy 382.278576 -223.523956) (xy 382.29064 -223.473572) (xy 382.310419 -223.425687) (xy 382.337428 -223.381476)
			(xy 382.371006 -223.342021) (xy 382.410329 -223.30829) (xy 382.454434 -223.281108) (xy 382.502241 -223.261141)
			(xy 382.527302 -223.25457) (xy 382.566164 -223.245172) (xy 382.566164 -223.041718) (xy 382.565712 -223.027958)
			(xy 382.558363 -223.001439) (xy 382.544194 -222.977847) (xy 382.524237 -222.9589) (xy 382.499942 -222.945974)
			(xy 382.473077 -222.940011) (xy 382.445595 -222.941444) (xy 382.419495 -222.950168) (xy 382.396676 -222.96555)
			(xy 382.387348 -222.975678) (xy 382.37157 -222.993577) (xy 382.335748 -223.025094) (xy 382.295764 -223.05113)
			(xy 382.252451 -223.071144) (xy 382.206709 -223.084719) (xy 382.159491 -223.091573) (xy 382.135634 -223.09201)
			(xy 382.109666 -223.09153) (xy 382.05837 -223.08341) (xy 382.008975 -223.067365) (xy 381.962699 -223.043791)
			(xy 381.920681 -223.013267) (xy 381.883955 -222.976545) (xy 381.853427 -222.93453) (xy 381.829848 -222.888256)
			(xy 381.813798 -222.838863) (xy 381.805673 -222.787568) (xy 381.805673 -222.735632) (xy 381.813798 -222.684337)
			(xy 381.829848 -222.634944) (xy 381.853427 -222.58867) (xy 381.883955 -222.546655) (xy 381.920681 -222.509933)
			(xy 381.962699 -222.479409) (xy 382.008975 -222.455835) (xy 382.05837 -222.43979) (xy 382.109666 -222.43167)
			(xy 382.135634 -222.431102) (xy 382.15949 -222.431523) (xy 382.206706 -222.438389) (xy 382.252444 -222.451973)
			(xy 382.295753 -222.471993) (xy 382.335733 -222.498032) (xy 382.371553 -222.52955) (xy 382.387348 -222.547434)
			(xy 382.396639 -222.557603) (xy 382.419472 -222.572992) (xy 382.445586 -222.58172) (xy 382.473083 -222.583153)
			(xy 382.499963 -222.577187) (xy 382.524272 -222.564255) (xy 382.544241 -222.545298) (xy 382.558419 -222.521695)
			(xy 382.565774 -222.495161) (xy 382.566164 -222.481394) (xy 382.566164 -222.278194) (xy 382.527302 -222.268796)
			(xy 382.502252 -222.262176) (xy 382.454442 -222.242212) (xy 382.410334 -222.215031) (xy 382.371007 -222.181299)
			(xy 382.337426 -222.141845) (xy 382.310414 -222.097633) (xy 382.290632 -222.049747) (xy 382.278565 -221.999361)
			(xy 382.274508 -221.947709) (xy 382.278562 -221.896058) (xy 382.290626 -221.845671) (xy 382.310405 -221.797784)
			(xy 382.337415 -221.753571) (xy 382.370994 -221.714114) (xy 382.410318 -221.680381) (xy 382.454425 -221.653197)
			(xy 382.502234 -221.63323) (xy 382.527302 -221.626684) (xy 382.566164 -221.617286) (xy 382.566164 -221.414086)
			(xy 382.565708 -221.40033) (xy 382.558354 -221.373818) (xy 382.544184 -221.350234) (xy 382.524229 -221.331294)
			(xy 382.499938 -221.318373) (xy 382.473079 -221.312411) (xy 382.445603 -221.313842) (xy 382.419509 -221.322562)
			(xy 382.396692 -221.337936) (xy 382.387348 -221.348046) (xy 382.371571 -221.365947) (xy 382.33575 -221.397467)
			(xy 382.295767 -221.423505) (xy 382.252453 -221.443521) (xy 382.206711 -221.457098) (xy 382.159491 -221.463952)
			(xy 382.135634 -221.464378) (xy 382.109662 -221.463898) (xy 382.058358 -221.455777) (xy 382.008955 -221.439731)
			(xy 381.962671 -221.416153) (xy 381.920645 -221.385625) (xy 381.883912 -221.348899) (xy 381.853377 -221.306879)
			(xy 381.829792 -221.260599) (xy 381.813736 -221.211199) (xy 381.805607 -221.159896) (xy 381.80518 -221.133924)
			(xy 381.805791 -221.105943) (xy 381.815239 -221.050784) (xy 381.823976 -221.024196) (xy 381.831596 -221.002098)
			(xy 381.627888 -220.649038) (xy 381.605028 -220.64472) (xy 381.580084 -220.639583) (xy 381.532051 -220.622663)
			(xy 381.487183 -220.598573) (xy 381.446542 -220.567886) (xy 381.41109 -220.531326) (xy 381.381667 -220.48976)
			(xy 381.358969 -220.444172) (xy 381.343535 -220.395641) (xy 381.335729 -220.345317) (xy 381.33528 -220.319854)
			(xy 381.335789 -220.293887) (xy 381.343914 -220.242592) (xy 381.359962 -220.193199) (xy 381.38354 -220.146925)
			(xy 381.414066 -220.104909) (xy 381.450789 -220.068186) (xy 381.492805 -220.03766) (xy 381.539079 -220.014082)
			(xy 381.588472 -219.998034) (xy 381.639767 -219.989909) (xy 381.691701 -219.989909) (xy 381.742996 -219.998034)
			(xy 381.792389 -220.014082) (xy 381.838663 -220.03766) (xy 381.880679 -220.068186) (xy 381.917402 -220.104909)
			(xy 381.947928 -220.146925) (xy 381.971506 -220.193199) (xy 381.987554 -220.242592) (xy 381.995679 -220.293887)
			(xy 381.996188 -220.319854) (xy 381.995579 -220.347835) (xy 381.986134 -220.402995) (xy 381.977392 -220.429582)
			(xy 381.969772 -220.451426) (xy 382.173734 -220.80474) (xy 382.196594 -220.809058) (xy 382.224142 -220.814794)
			(xy 382.276889 -220.834378) (xy 382.325551 -220.862625) (xy 382.368716 -220.898716) (xy 382.387348 -220.919802)
			(xy 382.396637 -220.929974) (xy 382.419467 -220.945367) (xy 382.445581 -220.954098) (xy 382.473079 -220.955533)
			(xy 382.499959 -220.949566) (xy 382.524268 -220.936632) (xy 382.544235 -220.917672) (xy 382.558409 -220.894066)
			(xy 382.565758 -220.86753) (xy 382.566164 -220.853762) (xy 382.566164 -220.650308) (xy 382.527302 -220.64091)
			(xy 382.503629 -220.634699) (xy 382.458297 -220.616251) (xy 382.416181 -220.591321) (xy 382.378201 -220.560454)
			(xy 382.345187 -220.524324) (xy 382.317861 -220.483722) (xy 382.29682 -220.439535) (xy 382.282524 -220.392728)
			(xy 382.275286 -220.344324) (xy 382.274826 -220.319854) (xy 382.27527 -220.295398) (xy 382.282482 -220.24702)
			(xy 382.296742 -220.200233) (xy 382.317738 -220.156056) (xy 382.345012 -220.115454) (xy 382.37797 -220.079313)
			(xy 382.415892 -220.048421) (xy 382.457951 -220.023452) (xy 382.503229 -220.004951) (xy 382.550739 -219.993322)
			(xy 382.575054 -219.99067) (xy 382.611884 -219.987368) (xy 382.805178 -219.134944) (xy 382.807969 -219.120427)
			(xy 382.806006 -219.090944) (xy 382.79569 -219.063254) (xy 382.777882 -219.039675) (xy 382.754072 -219.022176)
			(xy 382.72625 -219.012222) (xy 382.696744 -219.010645) (xy 382.682242 -219.013532) (xy 382.66335 -219.017786)
			(xy 382.624896 -219.022367) (xy 382.605534 -219.022676) (xy 382.579561 -219.022196) (xy 382.528255 -219.014074)
			(xy 382.47885 -218.998026) (xy 382.432565 -218.974447) (xy 382.390538 -218.943917) (xy 382.353805 -218.907188)
			(xy 382.323271 -218.865164) (xy 382.299687 -218.818881) (xy 382.283634 -218.769479) (xy 382.275507 -218.718173)
			(xy 382.275507 -218.666227) (xy 382.283634 -218.614921) (xy 382.299687 -218.565519) (xy 382.323271 -218.519236)
			(xy 382.353805 -218.477212) (xy 382.390538 -218.440483) (xy 382.432565 -218.409953) (xy 382.47885 -218.386374)
			(xy 382.528255 -218.370326) (xy 382.579561 -218.362204) (xy 382.605534 -218.361768) (xy 382.633679 -218.362337)
			(xy 382.689155 -218.37187) (xy 382.742218 -218.390656) (xy 382.791335 -218.418151) (xy 382.81356 -218.435428)
			(xy 382.825339 -218.444292) (xy 382.852604 -218.455471) (xy 382.881925 -218.458398) (xy 382.910861 -218.452829)
			(xy 382.937002 -218.439229) (xy 382.95817 -218.41873) (xy 382.972603 -218.393039) (xy 382.976374 -218.378786)
			(xy 383.01549 -218.206574) (xy 382.971548 -218.192096) (xy 382.947138 -218.183527) (xy 382.901129 -218.159876)
			(xy 382.859373 -218.129337) (xy 382.822893 -218.092657) (xy 382.792582 -218.050736) (xy 382.769182 -218.004598)
			(xy 382.753267 -217.955375) (xy 382.745226 -217.904272) (xy 382.744726 -217.878406) (xy 382.745235 -217.852438)
			(xy 382.753358 -217.801141) (xy 382.769406 -217.751746) (xy 382.792983 -217.70547) (xy 382.823509 -217.663452)
			(xy 382.860232 -217.626726) (xy 382.902248 -217.596197) (xy 382.948522 -217.572616) (xy 382.997916 -217.556564)
			(xy 383.049212 -217.548437) (xy 383.07518 -217.547952) (xy 383.085685 -217.548002) (xy 383.106656 -217.549273)
			(xy 383.11709 -217.550492) (xy 383.16281 -217.556588) (xy 383.243582 -217.199972) (xy 383.237994 -217.185494)
			(xy 383.227249 -217.156362) (xy 383.215621 -217.095377) (xy 383.21488 -217.064336) (xy 383.215457 -217.037189)
			(xy 383.224382 -216.983632) (xy 383.241932 -216.932252) (xy 383.267637 -216.884427) (xy 383.300806 -216.841441)
			(xy 383.32029 -216.822528) (xy 383.33172 -216.81186) (xy 383.36601 -216.660222) (xy 383.36868 -216.646147)
			(xy 383.366969 -216.617561) (xy 383.357396 -216.590572) (xy 383.340711 -216.567298) (xy 383.318226 -216.549566)
			(xy 383.291703 -216.538767) (xy 383.263226 -216.535749) (xy 383.235029 -216.54075) (xy 383.221992 -216.546684)
			(xy 383.199083 -216.557476) (xy 383.1508 -216.572743) (xy 383.100753 -216.580469) (xy 383.075434 -216.580974)
			(xy 383.049461 -216.580494) (xy 382.998155 -216.572372) (xy 382.948751 -216.556325) (xy 382.902466 -216.532745)
			(xy 382.860439 -216.502215) (xy 382.823707 -216.465486) (xy 382.793173 -216.423463) (xy 382.769589 -216.37718)
			(xy 382.753536 -216.327778) (xy 382.745409 -216.276473) (xy 382.745409 -216.224527) (xy 382.753536 -216.173222)
			(xy 382.769589 -216.12382) (xy 382.793173 -216.077537) (xy 382.823707 -216.035514) (xy 382.860439 -215.998785)
			(xy 382.902466 -215.968255) (xy 382.948751 -215.944675) (xy 382.998155 -215.928628) (xy 383.049461 -215.920506)
			(xy 383.075434 -215.920066) (xy 383.100361 -215.920522) (xy 383.14965 -215.928012) (xy 383.197255 -215.942817)
			(xy 383.242098 -215.964601) (xy 383.283162 -215.992871) (xy 383.319516 -216.026986) (xy 383.335276 -216.046304)
			(xy 383.344506 -216.057291) (xy 383.367773 -216.074062) (xy 383.394785 -216.083706) (xy 383.423413 -216.085464)
			(xy 383.451402 -216.079197) (xy 383.476547 -216.065398) (xy 383.496866 -216.045156) (xy 383.51076 -216.020063)
			(xy 383.514346 -216.006172) (xy 383.550922 -215.844374) (xy 384.278124 -215.117426) (xy 384.400044 -215.117426)
			(xy 384.405886 -215.115902) (xy 384.425449 -215.111377) (xy 384.465311 -215.106543) (xy 384.485388 -215.10625)
			(xy 384.505466 -215.106529) (xy 384.545329 -215.111366) (xy 384.56489 -215.115902) (xy 384.570732 -215.117426)
			(xy 385.281678 -215.117426) (xy 392.454638 -207.944466) (xy 392.454638 -205.084172) (xy 405.822404 -191.716406)
			(xy 406.976326 -191.716406) (xy 406.984454 -191.713612) (xy 407.014464 -191.703974) (xy 407.076638 -191.69364)
			(xy 407.108152 -191.693038) (xy 407.139661 -191.693691) (xy 407.201823 -191.704039) (xy 407.23185 -191.713612)
			(xy 407.239978 -191.716406) (xy 407.992326 -191.716406) (xy 408.000454 -191.713612) (xy 408.030464 -191.703974)
			(xy 408.092638 -191.69364) (xy 408.124152 -191.693038) (xy 408.155661 -191.693691) (xy 408.217823 -191.704039)
			(xy 408.24785 -191.713612) (xy 408.255978 -191.716406) (xy 409.008326 -191.716406) (xy 409.016454 -191.713612)
			(xy 409.046464 -191.703974) (xy 409.108638 -191.69364) (xy 409.140152 -191.693038) (xy 409.171661 -191.693691)
			(xy 409.233823 -191.704039) (xy 409.26385 -191.713612) (xy 409.271978 -191.716406) (xy 410.024326 -191.716406)
			(xy 410.032454 -191.713612) (xy 410.062464 -191.703974) (xy 410.124638 -191.69364) (xy 410.156152 -191.693038)
			(xy 410.187661 -191.693691) (xy 410.249823 -191.704039) (xy 410.27985 -191.713612) (xy 410.287978 -191.716406)
			(xy 411.040326 -191.716406) (xy 411.048454 -191.713612) (xy 411.078464 -191.703974) (xy 411.140638 -191.69364)
			(xy 411.172152 -191.693038) (xy 411.203661 -191.693691) (xy 411.265823 -191.704039) (xy 411.29585 -191.713612)
			(xy 411.303978 -191.716406) (xy 414.123886 -191.716406) (xy 414.132014 -191.713612) (xy 414.162024 -191.703971)
			(xy 414.224197 -191.69363) (xy 414.255712 -191.693038) (xy 414.287221 -191.693688) (xy 414.349386 -191.704029)
			(xy 414.37941 -191.713612) (xy 414.387538 -191.716406) (xy 415.139886 -191.716406) (xy 415.148014 -191.713612)
			(xy 415.178024 -191.703971) (xy 415.240197 -191.69363) (xy 415.271712 -191.693038) (xy 415.303221 -191.693688)
			(xy 415.365386 -191.704029) (xy 415.39541 -191.713612) (xy 415.403538 -191.716406) (xy 416.155886 -191.716406)
			(xy 416.164014 -191.713612) (xy 416.194024 -191.703971) (xy 416.256197 -191.69363) (xy 416.287712 -191.693038)
			(xy 416.319221 -191.693688) (xy 416.381386 -191.704029) (xy 416.41141 -191.713612) (xy 416.419538 -191.716406)
			(xy 424.378882 -191.716406) (xy 424.412918 -191.750696) (xy 424.746166 -191.750696) (xy 424.765724 -191.731138)
			(xy 426.88002 -191.731138) (xy 426.894029 -191.730734) (xy 426.921011 -191.723199) (xy 426.944932 -191.708617)
			(xy 426.963993 -191.688086) (xy 426.97676 -191.663149) (xy 426.982274 -191.635682) (xy 426.980119 -191.60775)
			(xy 426.970458 -191.581454) (xy 426.954017 -191.55877) (xy 426.943266 -191.549782) (xy 426.921074 -191.531598)
			(xy 426.881882 -191.489698) (xy 426.84941 -191.442401) (xy 426.824388 -191.390773) (xy 426.807384 -191.335979)
			(xy 426.798779 -191.279256) (xy 426.798232 -191.25057) (xy 426.798718 -191.223319) (xy 426.806474 -191.169371)
			(xy 426.821829 -191.117076) (xy 426.844471 -191.067499) (xy 426.873937 -191.021649) (xy 426.909628 -190.980458)
			(xy 426.950819 -190.944767) (xy 426.996669 -190.915301) (xy 427.046246 -190.892659) (xy 427.098541 -190.877304)
			(xy 427.152489 -190.869548) (xy 427.206991 -190.869548) (xy 427.260939 -190.877304) (xy 427.313234 -190.892659)
			(xy 427.362811 -190.915301) (xy 427.408661 -190.944767) (xy 427.449852 -190.980458) (xy 427.485543 -191.021649)
			(xy 427.515009 -191.067499) (xy 427.537651 -191.117076) (xy 427.553006 -191.169371) (xy 427.560762 -191.223319)
			(xy 427.561248 -191.25057) (xy 427.560731 -191.279258) (xy 427.552133 -191.335985) (xy 427.535128 -191.390783)
			(xy 427.510099 -191.442411) (xy 427.477613 -191.489704) (xy 427.438403 -191.531591) (xy 427.416214 -191.549782)
			(xy 427.405503 -191.558808) (xy 427.389073 -191.581481) (xy 427.379419 -191.607764) (xy 427.377267 -191.635681)
			(xy 427.382777 -191.663134) (xy 427.395536 -191.688058) (xy 427.414585 -191.70858) (xy 427.438492 -191.723156)
			(xy 427.465459 -191.730692) (xy 427.47946 -191.731138) (xy 432.744118 -191.731138) (xy 432.757802 -191.730705)
			(xy 432.784191 -191.72345) (xy 432.807702 -191.709441) (xy 432.826643 -191.689686) (xy 432.83965 -191.665607)
			(xy 432.845787 -191.638936) (xy 432.844614 -191.611593) (xy 432.836213 -191.585546) (xy 432.82119 -191.56267)
			(xy 432.811174 -191.553338) (xy 432.791196 -191.535142) (xy 432.756063 -191.494084) (xy 432.727078 -191.448477)
			(xy 432.704822 -191.399235) (xy 432.689741 -191.347345) (xy 432.682137 -191.293845) (xy 432.681634 -191.266826)
			(xy 432.68212 -191.239575) (xy 432.689876 -191.185627) (xy 432.705231 -191.133332) (xy 432.727873 -191.083755)
			(xy 432.757339 -191.037905) (xy 432.79303 -190.996714) (xy 432.834221 -190.961023) (xy 432.880071 -190.931557)
			(xy 432.929648 -190.908915) (xy 432.981943 -190.89356) (xy 433.035891 -190.885804) (xy 433.090393 -190.885804)
			(xy 433.144341 -190.89356) (xy 433.196636 -190.908915) (xy 433.246213 -190.931557) (xy 433.292063 -190.961023)
			(xy 433.333254 -190.996714) (xy 433.368945 -191.037905) (xy 433.398411 -191.083755) (xy 433.421053 -191.133332)
			(xy 433.436408 -191.185627) (xy 433.444164 -191.239575) (xy 433.44465 -191.266826) (xy 433.444179 -191.293846)
			(xy 433.436555 -191.347344) (xy 433.421463 -191.399233) (xy 433.399203 -191.448474) (xy 433.370222 -191.494085)
			(xy 433.335099 -191.535153) (xy 433.31511 -191.553338) (xy 433.30514 -191.562711) (xy 433.290153 -191.585592)
			(xy 433.281777 -191.611632) (xy 433.280613 -191.63896) (xy 433.286746 -191.665617) (xy 433.299735 -191.68969)
			(xy 433.318648 -191.709451) (xy 433.342128 -191.723483) (xy 433.36849 -191.730778) (xy 433.382166 -191.731138)
			(xy 443.04077 -191.731138) (xy 444.024258 -190.74765) (xy 444.024258 -188.39561) (xy 444.76289 -187.656978)
			(xy 445.941704 -187.656978) (xy 446.890902 -186.70778) (xy 446.890902 -175.511206) (xy 446.410842 -175.031146)
			(xy 441.804044 -175.031146) (xy 438.458864 -178.376326) (xy 438.458864 -182.359046) (xy 436.741824 -184.076086)
			(xy 435.837584 -184.076086) (xy 435.837584 -184.07634) (xy 425.484036 -184.07634) (xy 425.470424 -184.07677)
			(xy 425.444167 -184.083959) (xy 425.420745 -184.097834) (xy 425.401826 -184.117409) (xy 425.388756 -184.14129)
			(xy 425.382466 -184.167777) (xy 425.383403 -184.194984) (xy 425.3915 -184.220975) (xy 425.406182 -184.2439)
			(xy 425.415964 -184.253378) (xy 425.435422 -184.271538) (xy 425.469616 -184.312325) (xy 425.497803 -184.357472)
			(xy 425.519434 -184.406102) (xy 425.534088 -184.457268) (xy 425.541481 -184.509976) (xy 425.541948 -184.536588)
			(xy 425.541462 -184.563839) (xy 425.533706 -184.617787) (xy 425.518351 -184.670082) (xy 425.495709 -184.719659)
			(xy 425.466243 -184.765509) (xy 425.459919 -184.772808) (xy 431.191922 -184.772808) (xy 431.195993 -184.717186)
			(xy 431.208119 -184.662749) (xy 431.228042 -184.610658) (xy 431.255338 -184.562023) (xy 431.289424 -184.51788)
			(xy 431.329573 -184.479171) (xy 431.374931 -184.44672) (xy 431.424531 -184.421219) (xy 431.477315 -184.403212)
			(xy 431.532158 -184.393082) (xy 431.587892 -184.391045) (xy 431.643329 -184.397145) (xy 431.697286 -184.411251)
			(xy 431.748615 -184.433063) (xy 431.796221 -184.462117) (xy 431.839089 -184.497792) (xy 431.876306 -184.539329)
			(xy 431.907079 -184.585842) (xy 431.930751 -184.636339) (xy 431.946819 -184.689746) (xy 431.954939 -184.744922)
			(xy 431.955448 -184.772808) (xy 431.954939 -184.800694) (xy 431.946819 -184.85587) (xy 431.930751 -184.909277)
			(xy 431.907079 -184.959774) (xy 431.876306 -185.006287) (xy 431.839089 -185.047824) (xy 431.796221 -185.083499)
			(xy 431.748615 -185.112553) (xy 431.697286 -185.134365) (xy 431.643329 -185.148471) (xy 431.587892 -185.154571)
			(xy 431.532158 -185.152534) (xy 431.477315 -185.142404) (xy 431.424531 -185.124397) (xy 431.374931 -185.098896)
			(xy 431.329573 -185.066445) (xy 431.289424 -185.027736) (xy 431.255338 -184.983593) (xy 431.228042 -184.934958)
			(xy 431.208119 -184.882867) (xy 431.195993 -184.82843) (xy 431.191922 -184.772808) (xy 425.459919 -184.772808)
			(xy 425.430552 -184.8067) (xy 425.389361 -184.842391) (xy 425.343511 -184.871857) (xy 425.293934 -184.894499)
			(xy 425.241639 -184.909854) (xy 425.187691 -184.91761) (xy 425.133189 -184.91761) (xy 425.079241 -184.909854)
			(xy 425.026946 -184.894499) (xy 424.977369 -184.871857) (xy 424.931519 -184.842391) (xy 424.890328 -184.8067)
			(xy 424.854637 -184.765509) (xy 424.825171 -184.719659) (xy 424.802529 -184.670082) (xy 424.787174 -184.617787)
			(xy 424.779418 -184.563839) (xy 424.778932 -184.536588) (xy 424.779396 -184.509977) (xy 424.786798 -184.457271)
			(xy 424.801457 -184.406106) (xy 424.823088 -184.357477) (xy 424.851271 -184.312328) (xy 424.885458 -184.271537)
			(xy 424.904916 -184.253378) (xy 424.914742 -184.243938) (xy 424.929435 -184.221001) (xy 424.937538 -184.194996)
			(xy 424.938477 -184.167774) (xy 424.932183 -184.141272) (xy 424.919104 -184.117379) (xy 424.900173 -184.097794)
			(xy 424.876736 -184.083914) (xy 424.850464 -184.076725) (xy 424.836844 -184.07634) (xy 411.197298 -184.07634)
			(xy 411.197298 -184.076086) (xy 409.786328 -184.076086) (xy 409.786328 -184.123838) (xy 409.661106 -184.24906)
			(xy 409.641827 -184.267688) (xy 409.598696 -184.299524) (xy 409.551282 -184.324538) (xy 409.500655 -184.342165)
			(xy 409.447959 -184.352007) (xy 409.394382 -184.353841) (xy 409.341136 -184.347626) (xy 409.315158 -184.341008)
			(xy 409.303719 -184.36605) (xy 409.274701 -184.412836) (xy 409.239259 -184.454964) (xy 409.19813 -184.491561)
			(xy 409.152168 -184.521866) (xy 409.102328 -184.54525) (xy 409.049643 -184.561228) (xy 408.99521 -184.569467)
			(xy 408.967686 -184.570116) (xy 408.96377 -184.595345) (xy 408.949651 -184.644409) (xy 408.928664 -184.69095)
			(xy 408.90124 -184.734015) (xy 408.867943 -184.772717) (xy 408.829457 -184.806263) (xy 408.78657 -184.833964)
			(xy 408.740165 -184.855251) (xy 408.691193 -184.869686) (xy 408.640661 -184.876974) (xy 408.615134 -184.877456)
			(xy 403.233128 -184.877456) (xy 402.891284 -185.2193) (xy 432.315942 -185.2193) (xy 432.319856 -185.142113)
			(xy 432.33156 -185.065719) (xy 432.350931 -184.9909) (xy 432.377773 -184.918425) (xy 432.411809 -184.849038)
			(xy 432.45269 -184.78345) (xy 432.499996 -184.722334) (xy 432.553243 -184.666317) (xy 432.611884 -184.615975)
			(xy 432.675317 -184.571823) (xy 432.742891 -184.534316) (xy 432.813913 -184.503837) (xy 432.887655 -184.4807)
			(xy 432.963358 -184.465142) (xy 433.040247 -184.457322) (xy 433.07889 -184.456832) (xy 433.117654 -184.457295)
			(xy 433.194781 -184.465161) (xy 433.270712 -184.480814) (xy 433.344662 -184.504091) (xy 433.415869 -184.534752)
			(xy 433.483596 -184.572481) (xy 433.547146 -184.616888) (xy 433.60586 -184.667515) (xy 433.659134 -184.723839)
			(xy 433.683156 -184.754266) (xy 433.692409 -184.765626) (xy 433.716103 -184.782845) (xy 433.743705 -184.792647)
			(xy 433.772952 -184.794229) (xy 433.80145 -184.787462) (xy 433.826864 -184.772899) (xy 433.837334 -184.762648)
			(xy 433.855367 -184.744315) (xy 433.895538 -184.712208) (xy 433.939662 -184.685796) (xy 433.986938 -184.665557)
			(xy 434.036506 -184.651861) (xy 434.087465 -184.644955) (xy 434.113178 -184.644538) (xy 434.140435 -184.644907)
			(xy 434.194395 -184.652663) (xy 434.246702 -184.668019) (xy 434.296291 -184.690663) (xy 434.342152 -184.720134)
			(xy 434.383353 -184.755832) (xy 434.419053 -184.79703) (xy 434.448527 -184.84289) (xy 434.471173 -184.892477)
			(xy 434.486532 -184.944783) (xy 434.489926 -184.968388) (xy 434.834282 -184.968388) (xy 434.838353 -184.912766)
			(xy 434.850479 -184.858329) (xy 434.870402 -184.806238) (xy 434.897698 -184.757603) (xy 434.931784 -184.71346)
			(xy 434.971933 -184.674751) (xy 435.017291 -184.6423) (xy 435.066891 -184.616799) (xy 435.119675 -184.598792)
			(xy 435.174518 -184.588662) (xy 435.230252 -184.586625) (xy 435.285689 -184.592725) (xy 435.339646 -184.606831)
			(xy 435.390975 -184.628643) (xy 435.438581 -184.657697) (xy 435.481449 -184.693372) (xy 435.518666 -184.734909)
			(xy 435.549439 -184.781422) (xy 435.573111 -184.831919) (xy 435.589179 -184.885326) (xy 435.597299 -184.940502)
			(xy 435.597808 -184.968388) (xy 435.597299 -184.996274) (xy 435.589179 -185.05145) (xy 435.573111 -185.104857)
			(xy 435.549439 -185.155354) (xy 435.518666 -185.201867) (xy 435.481449 -185.243404) (xy 435.438581 -185.279079)
			(xy 435.390975 -185.308133) (xy 435.339646 -185.329945) (xy 435.285689 -185.344051) (xy 435.230252 -185.350151)
			(xy 435.174518 -185.348114) (xy 435.119675 -185.337984) (xy 435.066891 -185.319977) (xy 435.017291 -185.294476)
			(xy 434.971933 -185.262025) (xy 434.931784 -185.223316) (xy 434.897698 -185.179173) (xy 434.870402 -185.130538)
			(xy 434.850479 -185.078447) (xy 434.838353 -185.02401) (xy 434.834282 -184.968388) (xy 434.489926 -184.968388)
			(xy 434.494291 -184.998743) (xy 434.494291 -185.053257) (xy 434.486532 -185.107217) (xy 434.471173 -185.159523)
			(xy 434.448527 -185.20911) (xy 434.419053 -185.25497) (xy 434.383353 -185.296168) (xy 434.342152 -185.331866)
			(xy 434.296291 -185.361337) (xy 434.246702 -185.383981) (xy 434.194395 -185.399337) (xy 434.140435 -185.407093)
			(xy 434.113178 -185.407554) (xy 434.08527 -185.407085) (xy 434.030045 -185.398984) (xy 433.976597 -185.382902)
			(xy 433.951126 -185.371486) (xy 433.937674 -185.365703) (xy 433.908751 -185.361238) (xy 433.879749 -185.365164)
			(xy 433.853053 -185.377158) (xy 433.830859 -185.396235) (xy 433.814991 -185.420826) (xy 433.81041 -185.434732)
			(xy 433.799278 -185.47073) (xy 433.770959 -185.540559) (xy 433.735891 -185.607255) (xy 433.694417 -185.670168)
			(xy 433.64694 -185.728683) (xy 433.593924 -185.782231) (xy 433.535885 -185.830289) (xy 433.473389 -185.872389)
			(xy 433.407046 -185.90812) (xy 433.337503 -185.937134) (xy 433.265437 -185.959148) (xy 433.191551 -185.973947)
			(xy 433.116567 -185.981387) (xy 433.07889 -185.981848) (xy 433.040247 -185.981278) (xy 432.963358 -185.973458)
			(xy 432.887655 -185.9579) (xy 432.813913 -185.934763) (xy 432.742891 -185.904284) (xy 432.675317 -185.866777)
			(xy 432.611884 -185.822625) (xy 432.553243 -185.772283) (xy 432.499996 -185.716266) (xy 432.45269 -185.65515)
			(xy 432.411809 -185.589562) (xy 432.377773 -185.520175) (xy 432.350931 -185.4477) (xy 432.33156 -185.372881)
			(xy 432.319856 -185.296487) (xy 432.315942 -185.2193) (xy 402.891284 -185.2193) (xy 401.596606 -186.513978)
			(xy 399.82013 -186.513978) (xy 399.197254 -187.136854) (xy 404.179963 -187.136854) (xy 404.179963 -187.082346)
			(xy 404.187721 -187.028393) (xy 404.203079 -186.976093) (xy 404.225724 -186.926511) (xy 404.255195 -186.880657)
			(xy 404.290892 -186.839464) (xy 404.332089 -186.803771) (xy 404.377946 -186.774305) (xy 404.42753 -186.751665)
			(xy 404.479832 -186.736313) (xy 404.533786 -186.728561) (xy 404.56104 -186.7281) (xy 404.587846 -186.728539)
			(xy 404.640928 -186.736066) (xy 404.692433 -186.750952) (xy 404.741345 -186.772904) (xy 404.786702 -186.801489)
			(xy 404.827609 -186.836144) (xy 404.845774 -186.855862) (xy 404.855656 -186.866238) (xy 404.879884 -186.881512)
			(xy 404.9074 -186.889462) (xy 404.93604 -186.889462) (xy 404.963556 -186.881512) (xy 404.987784 -186.866238)
			(xy 404.997666 -186.855862) (xy 405.015841 -186.836153) (xy 405.05674 -186.801489) (xy 405.102093 -186.7729)
			(xy 405.151005 -186.750949) (xy 405.202511 -186.73607) (xy 405.255594 -186.728556) (xy 405.2824 -186.7281)
			(xy 405.309657 -186.728584) (xy 405.363614 -186.73635) (xy 405.415914 -186.751723) (xy 405.465492 -186.774389)
			(xy 405.511334 -186.803888) (xy 405.552507 -186.839615) (xy 405.57069 -186.859926) (xy 405.580403 -186.870454)
			(xy 405.604446 -186.886009) (xy 405.631856 -186.894298) (xy 405.660489 -186.894673) (xy 405.688107 -186.887104)
			(xy 405.712549 -186.872185) (xy 405.722582 -186.861958) (xy 405.740707 -186.842815) (xy 405.781339 -186.809227)
			(xy 405.826211 -186.781557) (xy 405.874466 -186.760331) (xy 405.925185 -186.745955) (xy 405.977401 -186.738701)
			(xy 406.00376 -186.73826) (xy 406.031012 -186.738785) (xy 406.084963 -186.746536) (xy 406.137261 -186.761888)
			(xy 406.186842 -186.784526) (xy 406.232697 -186.81399) (xy 406.273891 -186.849681) (xy 406.309586 -186.890871)
			(xy 406.339055 -186.936722) (xy 406.361698 -186.986301) (xy 406.377055 -187.038598) (xy 406.384813 -187.092548)
			(xy 406.384813 -187.147052) (xy 406.377055 -187.201002) (xy 406.361698 -187.253299) (xy 406.339055 -187.302878)
			(xy 406.309586 -187.348729) (xy 406.273891 -187.389919) (xy 406.232697 -187.42561) (xy 406.186842 -187.455074)
			(xy 406.137261 -187.477712) (xy 406.084963 -187.493064) (xy 406.031012 -187.500815) (xy 406.00376 -187.501276)
			(xy 405.976502 -187.500828) (xy 405.922543 -187.493056) (xy 405.870241 -187.477676) (xy 405.820664 -187.455003)
			(xy 405.774822 -187.425498) (xy 405.733652 -187.389764) (xy 405.71547 -187.36945) (xy 405.705697 -187.358983)
			(xy 405.68167 -187.34343) (xy 405.654276 -187.335136) (xy 405.625657 -187.33475) (xy 405.598049 -187.342302)
			(xy 405.573612 -187.357202) (xy 405.563578 -187.367418) (xy 405.545419 -187.386527) (xy 405.504795 -187.420119)
			(xy 405.45993 -187.447794) (xy 405.411682 -187.469026) (xy 405.360968 -187.48341) (xy 405.308757 -187.490671)
			(xy 405.2824 -187.491116) (xy 405.255595 -187.490644) (xy 405.202515 -187.483123) (xy 405.151011 -187.468243)
			(xy 405.102099 -187.446297) (xy 405.056741 -187.417718) (xy 405.015832 -187.38307) (xy 404.997666 -187.363354)
			(xy 404.987784 -187.352978) (xy 404.963556 -187.337704) (xy 404.93604 -187.329754) (xy 404.9074 -187.329754)
			(xy 404.879884 -187.337704) (xy 404.855656 -187.352978) (xy 404.845774 -187.363354) (xy 404.827633 -187.383096)
			(xy 404.786726 -187.417756) (xy 404.741366 -187.446341) (xy 404.692447 -187.468286) (xy 404.640936 -187.483158)
			(xy 404.587848 -187.490664) (xy 404.56104 -187.491116) (xy 404.533786 -187.490639) (xy 404.479832 -187.482887)
			(xy 404.42753 -187.467535) (xy 404.377946 -187.444895) (xy 404.332089 -187.415429) (xy 404.290892 -187.379736)
			(xy 404.255195 -187.338543) (xy 404.225724 -187.292689) (xy 404.203079 -187.243107) (xy 404.187721 -187.190807)
			(xy 404.179963 -187.136854) (xy 399.197254 -187.136854) (xy 397.17513 -189.158978) (xy 407.266581 -189.158978)
			(xy 407.266581 -189.074422) (xy 407.274383 -188.990228) (xy 407.289921 -188.907113) (xy 407.313061 -188.825786)
			(xy 407.343607 -188.746941) (xy 407.381298 -188.671251) (xy 407.425811 -188.599362) (xy 407.476769 -188.531886)
			(xy 407.533735 -188.469401) (xy 407.596223 -188.412438) (xy 407.663701 -188.361484) (xy 407.735593 -188.316974)
			(xy 407.811285 -188.279288) (xy 407.890131 -188.248746) (xy 407.97146 -188.22561) (xy 408.054576 -188.210077)
			(xy 408.13877 -188.202279) (xy 408.181048 -188.201808) (xy 409.425648 -188.201808) (xy 409.467923 -188.202266)
			(xy 409.552113 -188.210072) (xy 409.635224 -188.225612) (xy 409.716546 -188.248754) (xy 409.795387 -188.279301)
			(xy 409.871072 -188.316991) (xy 409.942957 -188.361504) (xy 410.010429 -188.412459) (xy 410.072911 -188.469423)
			(xy 410.129871 -188.531908) (xy 410.180823 -188.599382) (xy 410.225332 -188.67127) (xy 410.263019 -188.746957)
			(xy 410.293561 -188.825799) (xy 410.316699 -188.907123) (xy 410.332235 -188.990234) (xy 410.340036 -189.074424)
			(xy 410.340036 -189.158976) (xy 410.340036 -189.158978) (xy 414.810381 -189.158978) (xy 414.810381 -189.074422)
			(xy 414.818183 -188.990228) (xy 414.833721 -188.907113) (xy 414.856861 -188.825786) (xy 414.887407 -188.746941)
			(xy 414.925098 -188.671251) (xy 414.969611 -188.599362) (xy 415.020569 -188.531886) (xy 415.077535 -188.469401)
			(xy 415.140023 -188.412438) (xy 415.207501 -188.361484) (xy 415.279393 -188.316974) (xy 415.355085 -188.279288)
			(xy 415.433931 -188.248746) (xy 415.51526 -188.22561) (xy 415.598376 -188.210077) (xy 415.68257 -188.202279)
			(xy 415.724848 -188.201808) (xy 416.969448 -188.201808) (xy 417.011723 -188.202266) (xy 417.095913 -188.210072)
			(xy 417.179024 -188.225612) (xy 417.260346 -188.248754) (xy 417.339187 -188.279301) (xy 417.414872 -188.316991)
			(xy 417.486757 -188.361504) (xy 417.554229 -188.412459) (xy 417.616711 -188.469423) (xy 417.673671 -188.531908)
			(xy 417.724623 -188.599382) (xy 417.769132 -188.67127) (xy 417.806819 -188.746957) (xy 417.837361 -188.825799)
			(xy 417.860499 -188.907123) (xy 417.876035 -188.990234) (xy 417.883836 -189.074424) (xy 417.883836 -189.158976)
			(xy 417.883836 -189.158978) (xy 422.354181 -189.158978) (xy 422.354181 -189.074422) (xy 422.361983 -188.990228)
			(xy 422.377521 -188.907113) (xy 422.400661 -188.825786) (xy 422.431207 -188.746941) (xy 422.468898 -188.671251)
			(xy 422.513411 -188.599362) (xy 422.564369 -188.531886) (xy 422.621335 -188.469401) (xy 422.683823 -188.412438)
			(xy 422.751301 -188.361484) (xy 422.823193 -188.316974) (xy 422.898885 -188.279288) (xy 422.977731 -188.248746)
			(xy 423.05906 -188.22561) (xy 423.142176 -188.210077) (xy 423.22637 -188.202279) (xy 423.268648 -188.201808)
			(xy 424.513248 -188.201808) (xy 424.555523 -188.202266) (xy 424.639713 -188.210072) (xy 424.722824 -188.225612)
			(xy 424.804146 -188.248754) (xy 424.882987 -188.279301) (xy 424.958672 -188.316991) (xy 425.030557 -188.361504)
			(xy 425.098029 -188.412459) (xy 425.160511 -188.469423) (xy 425.217471 -188.531908) (xy 425.268423 -188.599382)
			(xy 425.312932 -188.67127) (xy 425.350619 -188.746957) (xy 425.381161 -188.825799) (xy 425.404299 -188.907123)
			(xy 425.419835 -188.990234) (xy 425.427636 -189.074424) (xy 425.427636 -189.158976) (xy 425.427636 -189.158978)
			(xy 429.897981 -189.158978) (xy 429.897981 -189.074422) (xy 429.905783 -188.990228) (xy 429.921321 -188.907113)
			(xy 429.944461 -188.825786) (xy 429.975007 -188.746941) (xy 430.012698 -188.671251) (xy 430.057211 -188.599362)
			(xy 430.108169 -188.531886) (xy 430.165135 -188.469401) (xy 430.227623 -188.412438) (xy 430.295101 -188.361484)
			(xy 430.366993 -188.316974) (xy 430.442685 -188.279288) (xy 430.521531 -188.248746) (xy 430.60286 -188.22561)
			(xy 430.685976 -188.210077) (xy 430.77017 -188.202279) (xy 430.812448 -188.201808) (xy 432.057048 -188.201808)
			(xy 432.099325 -188.202234) (xy 432.183519 -188.21004) (xy 432.266634 -188.225581) (xy 432.34796 -188.248725)
			(xy 432.426803 -188.279273) (xy 432.502492 -188.316966) (xy 432.574381 -188.361481) (xy 432.641855 -188.412439)
			(xy 432.70434 -188.469406) (xy 432.761302 -188.531894) (xy 432.812255 -188.599372) (xy 432.856766 -188.671264)
			(xy 432.894453 -188.746955) (xy 432.924996 -188.825801) (xy 432.948133 -188.907129) (xy 432.963668 -188.990244)
			(xy 432.971468 -189.074439) (xy 432.971956 -189.116716) (xy 432.971445 -189.158978) (xy 437.441781 -189.158978)
			(xy 437.441781 -189.074422) (xy 437.449583 -188.990228) (xy 437.465121 -188.907113) (xy 437.488261 -188.825786)
			(xy 437.518807 -188.746941) (xy 437.556498 -188.671251) (xy 437.601011 -188.599362) (xy 437.651969 -188.531886)
			(xy 437.708935 -188.469401) (xy 437.771423 -188.412438) (xy 437.838901 -188.361484) (xy 437.910793 -188.316974)
			(xy 437.986485 -188.279288) (xy 438.065331 -188.248746) (xy 438.14666 -188.22561) (xy 438.229776 -188.210077)
			(xy 438.31397 -188.202279) (xy 438.356248 -188.201808) (xy 439.600848 -188.201808) (xy 439.643123 -188.202266)
			(xy 439.727313 -188.210072) (xy 439.810424 -188.225612) (xy 439.891746 -188.248754) (xy 439.970587 -188.279301)
			(xy 440.046272 -188.316991) (xy 440.118157 -188.361504) (xy 440.185629 -188.412459) (xy 440.248111 -188.469423)
			(xy 440.305071 -188.531908) (xy 440.356023 -188.599382) (xy 440.400532 -188.67127) (xy 440.438219 -188.746957)
			(xy 440.468761 -188.825799) (xy 440.491899 -188.907123) (xy 440.507435 -188.990234) (xy 440.515236 -189.074424)
			(xy 440.515236 -189.158976) (xy 440.507435 -189.243166) (xy 440.491899 -189.326277) (xy 440.468761 -189.407601)
			(xy 440.438219 -189.486443) (xy 440.400532 -189.56213) (xy 440.356023 -189.634018) (xy 440.305071 -189.701492)
			(xy 440.248111 -189.763977) (xy 440.185629 -189.820941) (xy 440.118157 -189.871896) (xy 440.046272 -189.916409)
			(xy 439.970587 -189.954099) (xy 439.891746 -189.984646) (xy 439.810424 -190.007788) (xy 439.727313 -190.023328)
			(xy 439.643123 -190.031134) (xy 439.600848 -190.031624) (xy 438.356248 -190.031624) (xy 438.31397 -190.031121)
			(xy 438.229776 -190.023323) (xy 438.14666 -190.00779) (xy 438.065331 -189.984654) (xy 437.986485 -189.954112)
			(xy 437.910793 -189.916426) (xy 437.838901 -189.871916) (xy 437.771423 -189.820962) (xy 437.708935 -189.763999)
			(xy 437.651969 -189.701514) (xy 437.601011 -189.634038) (xy 437.556498 -189.562149) (xy 437.518807 -189.486459)
			(xy 437.488261 -189.407614) (xy 437.465121 -189.326287) (xy 437.449583 -189.243172) (xy 437.441781 -189.158978)
			(xy 432.971445 -189.158978) (xy 432.971429 -189.160318) (xy 432.96312 -189.247124) (xy 432.946588 -189.332746)
			(xy 432.921984 -189.416406) (xy 432.889531 -189.497346) (xy 432.849523 -189.57483) (xy 432.802323 -189.648155)
			(xy 432.74836 -189.716657) (xy 432.688124 -189.779712) (xy 432.655472 -189.808612) (xy 432.644945 -189.81839)
			(xy 432.629354 -189.842508) (xy 432.6211 -189.870015) (xy 432.620837 -189.898732) (xy 432.628585 -189.926386)
			(xy 432.643731 -189.950786) (xy 432.665075 -189.97) (xy 432.690928 -189.982506) (xy 432.705002 -189.985396)
			(xy 432.731293 -189.990361) (xy 432.782255 -190.006657) (xy 432.830441 -190.029914) (xy 432.874905 -190.059673)
			(xy 432.914775 -190.095353) (xy 432.949269 -190.136253) (xy 432.977712 -190.181572) (xy 432.999544 -190.230419)
			(xy 433.014337 -190.281837) (xy 433.021803 -190.334818) (xy 433.022248 -190.36157) (xy 433.021762 -190.388821)
			(xy 433.014006 -190.442769) (xy 432.998651 -190.495064) (xy 432.976009 -190.544641) (xy 432.946543 -190.590491)
			(xy 432.910852 -190.631682) (xy 432.869661 -190.667373) (xy 432.823811 -190.696839) (xy 432.774234 -190.719481)
			(xy 432.721939 -190.734836) (xy 432.667991 -190.742592) (xy 432.613489 -190.742592) (xy 432.559541 -190.734836)
			(xy 432.507246 -190.719481) (xy 432.457669 -190.696839) (xy 432.411819 -190.667373) (xy 432.370628 -190.631682)
			(xy 432.334937 -190.590491) (xy 432.305471 -190.544641) (xy 432.282829 -190.495064) (xy 432.267474 -190.442769)
			(xy 432.259718 -190.388821) (xy 432.259232 -190.36157) (xy 432.259603 -190.33652) (xy 432.266154 -190.286851)
			(xy 432.279141 -190.238464) (xy 432.29834 -190.192189) (xy 432.31054 -190.170308) (xy 432.317244 -190.15759)
			(xy 432.324171 -190.129708) (xy 432.323048 -190.101) (xy 432.313965 -190.073744) (xy 432.297642 -190.050102)
			(xy 432.275373 -190.031949) (xy 432.248927 -190.020726) (xy 432.220399 -190.017323) (xy 432.206146 -190.019178)
			(xy 432.169142 -190.024964) (xy 432.094499 -190.031196) (xy 432.057048 -190.031624) (xy 430.812448 -190.031624)
			(xy 430.77017 -190.031121) (xy 430.685976 -190.023323) (xy 430.60286 -190.00779) (xy 430.521531 -189.984654)
			(xy 430.442685 -189.954112) (xy 430.366993 -189.916426) (xy 430.295101 -189.871916) (xy 430.227623 -189.820962)
			(xy 430.165135 -189.763999) (xy 430.108169 -189.701514) (xy 430.057211 -189.634038) (xy 430.012698 -189.562149)
			(xy 429.975007 -189.486459) (xy 429.944461 -189.407614) (xy 429.921321 -189.326287) (xy 429.905783 -189.243172)
			(xy 429.897981 -189.158978) (xy 425.427636 -189.158978) (xy 425.419835 -189.243166) (xy 425.404299 -189.326277)
			(xy 425.381161 -189.407601) (xy 425.350619 -189.486443) (xy 425.312932 -189.56213) (xy 425.268423 -189.634018)
			(xy 425.217471 -189.701492) (xy 425.160511 -189.763977) (xy 425.098029 -189.820941) (xy 425.030557 -189.871896)
			(xy 424.958672 -189.916409) (xy 424.882987 -189.954099) (xy 424.804146 -189.984646) (xy 424.722824 -190.007788)
			(xy 424.639713 -190.023328) (xy 424.555523 -190.031134) (xy 424.513248 -190.031624) (xy 423.268648 -190.031624)
			(xy 423.22637 -190.031121) (xy 423.142176 -190.023323) (xy 423.05906 -190.00779) (xy 422.977731 -189.984654)
			(xy 422.898885 -189.954112) (xy 422.823193 -189.916426) (xy 422.751301 -189.871916) (xy 422.683823 -189.820962)
			(xy 422.621335 -189.763999) (xy 422.564369 -189.701514) (xy 422.513411 -189.634038) (xy 422.468898 -189.562149)
			(xy 422.431207 -189.486459) (xy 422.400661 -189.407614) (xy 422.377521 -189.326287) (xy 422.361983 -189.243172)
			(xy 422.354181 -189.158978) (xy 417.883836 -189.158978) (xy 417.876035 -189.243166) (xy 417.860499 -189.326277)
			(xy 417.837361 -189.407601) (xy 417.806819 -189.486443) (xy 417.769132 -189.56213) (xy 417.724623 -189.634018)
			(xy 417.673671 -189.701492) (xy 417.616711 -189.763977) (xy 417.554229 -189.820941) (xy 417.486757 -189.871896)
			(xy 417.414872 -189.916409) (xy 417.339187 -189.954099) (xy 417.260346 -189.984646) (xy 417.179024 -190.007788)
			(xy 417.095913 -190.023328) (xy 417.011723 -190.031134) (xy 416.969448 -190.031624) (xy 415.724848 -190.031624)
			(xy 415.68257 -190.031121) (xy 415.598376 -190.023323) (xy 415.51526 -190.00779) (xy 415.433931 -189.984654)
			(xy 415.355085 -189.954112) (xy 415.279393 -189.916426) (xy 415.207501 -189.871916) (xy 415.140023 -189.820962)
			(xy 415.077535 -189.763999) (xy 415.020569 -189.701514) (xy 414.969611 -189.634038) (xy 414.925098 -189.562149)
			(xy 414.887407 -189.486459) (xy 414.856861 -189.407614) (xy 414.833721 -189.326287) (xy 414.818183 -189.243172)
			(xy 414.810381 -189.158978) (xy 410.340036 -189.158978) (xy 410.332235 -189.243166) (xy 410.316699 -189.326277)
			(xy 410.293561 -189.407601) (xy 410.263019 -189.486443) (xy 410.225332 -189.56213) (xy 410.180823 -189.634018)
			(xy 410.129871 -189.701492) (xy 410.072911 -189.763977) (xy 410.010429 -189.820941) (xy 409.942957 -189.871896)
			(xy 409.871072 -189.916409) (xy 409.795387 -189.954099) (xy 409.716546 -189.984646) (xy 409.635224 -190.007788)
			(xy 409.552113 -190.023328) (xy 409.467923 -190.031134) (xy 409.425648 -190.031624) (xy 408.181048 -190.031624)
			(xy 408.13877 -190.031121) (xy 408.054576 -190.023323) (xy 407.97146 -190.00779) (xy 407.890131 -189.984654)
			(xy 407.811285 -189.954112) (xy 407.735593 -189.916426) (xy 407.663701 -189.871916) (xy 407.596223 -189.820962)
			(xy 407.533735 -189.763999) (xy 407.476769 -189.701514) (xy 407.425811 -189.634038) (xy 407.381298 -189.562149)
			(xy 407.343607 -189.486459) (xy 407.313061 -189.407614) (xy 407.289921 -189.326287) (xy 407.274383 -189.243172)
			(xy 407.266581 -189.158978) (xy 397.17513 -189.158978) (xy 396.711678 -189.62243) (xy 396.711678 -189.77483)
			(xy 398.79854 -189.77483) (xy 398.802611 -189.719208) (xy 398.814737 -189.664771) (xy 398.83466 -189.61268)
			(xy 398.861956 -189.564045) (xy 398.896042 -189.519902) (xy 398.936191 -189.481193) (xy 398.981549 -189.448742)
			(xy 399.031149 -189.423241) (xy 399.083933 -189.405234) (xy 399.138776 -189.395104) (xy 399.19451 -189.393067)
			(xy 399.249947 -189.399167) (xy 399.303904 -189.413273) (xy 399.355233 -189.435085) (xy 399.402839 -189.464139)
			(xy 399.445707 -189.499814) (xy 399.482924 -189.541351) (xy 399.513697 -189.587864) (xy 399.537369 -189.638361)
			(xy 399.553437 -189.691768) (xy 399.561557 -189.746944) (xy 399.562066 -189.77483) (xy 399.561557 -189.802716)
			(xy 399.553437 -189.857892) (xy 399.537369 -189.911299) (xy 399.513697 -189.961796) (xy 399.482924 -190.008309)
			(xy 399.445707 -190.049846) (xy 399.402839 -190.085521) (xy 399.355233 -190.114575) (xy 399.303904 -190.136387)
			(xy 399.249947 -190.150493) (xy 399.19451 -190.156593) (xy 399.138776 -190.154556) (xy 399.083933 -190.144426)
			(xy 399.031149 -190.126419) (xy 398.981549 -190.100918) (xy 398.936191 -190.068467) (xy 398.896042 -190.029758)
			(xy 398.861956 -189.985615) (xy 398.83466 -189.93698) (xy 398.814737 -189.884889) (xy 398.802611 -189.830452)
			(xy 398.79854 -189.77483) (xy 396.711678 -189.77483) (xy 396.711678 -190.887858) (xy 395.628114 -191.971422)
			(xy 403.710392 -191.971422) (xy 403.714463 -191.9158) (xy 403.726589 -191.861363) (xy 403.746512 -191.809272)
			(xy 403.773808 -191.760637) (xy 403.807894 -191.716494) (xy 403.848043 -191.677785) (xy 403.893401 -191.645334)
			(xy 403.943001 -191.619833) (xy 403.995785 -191.601826) (xy 404.050628 -191.591696) (xy 404.106362 -191.589659)
			(xy 404.161799 -191.595759) (xy 404.215756 -191.609865) (xy 404.267085 -191.631677) (xy 404.314691 -191.660731)
			(xy 404.357559 -191.696406) (xy 404.394776 -191.737943) (xy 404.425549 -191.784456) (xy 404.449221 -191.834953)
			(xy 404.465289 -191.88836) (xy 404.473409 -191.943536) (xy 404.473918 -191.971422) (xy 404.473409 -191.999308)
			(xy 404.465289 -192.054484) (xy 404.449221 -192.107891) (xy 404.425549 -192.158388) (xy 404.394776 -192.204901)
			(xy 404.357559 -192.246438) (xy 404.314691 -192.282113) (xy 404.267085 -192.311167) (xy 404.215756 -192.332979)
			(xy 404.161799 -192.347085) (xy 404.106362 -192.353185) (xy 404.050628 -192.351148) (xy 403.995785 -192.341018)
			(xy 403.943001 -192.323011) (xy 403.893401 -192.29751) (xy 403.848043 -192.265059) (xy 403.807894 -192.22635)
			(xy 403.773808 -192.182207) (xy 403.746512 -192.133572) (xy 403.726589 -192.081481) (xy 403.714463 -192.027044)
			(xy 403.710392 -191.971422) (xy 395.628114 -191.971422) (xy 391.57402 -196.025516) (xy 387.775958 -197.26529)
			(xy 387.018022 -197.789292) (xy 385.877054 -199.418448) (xy 385.857231 -199.445938) (xy 385.812175 -199.496571)
			(xy 385.761542 -199.541627) (xy 385.734052 -199.56145) (xy 382.028192 -202.156314) (xy 382.017394 -202.164377)
			(xy 382.000134 -202.185063) (xy 381.988891 -202.209545) (xy 381.98445 -202.236117) (xy 381.98712 -202.262925)
			(xy 381.996715 -202.288099) (xy 382.012566 -202.309883) (xy 382.033566 -202.326758) (xy 382.045718 -202.33259)
			(xy 382.070813 -202.344139) (xy 382.117669 -202.3734) (xy 382.159821 -202.409107) (xy 382.196388 -202.450514)
			(xy 382.226609 -202.496757) (xy 382.249851 -202.546871) (xy 382.265632 -202.599812) (xy 382.27362 -202.654473)
			(xy 382.274064 -202.682094) (xy 382.273619 -202.708474) (xy 382.266357 -202.760731) (xy 382.25197 -202.811491)
			(xy 382.230731 -202.859787) (xy 382.203047 -202.9047) (xy 382.169443 -202.945373) (xy 382.130559 -202.981033)
			(xy 382.102193 -203.00061) (xy 384.667252 -203.00061) (xy 384.667676 -202.97423) (xy 384.674939 -202.921973)
			(xy 384.689329 -202.871214) (xy 384.710572 -202.822919) (xy 384.738263 -202.77801) (xy 384.771874 -202.737342)
			(xy 384.810764 -202.70169) (xy 384.854194 -202.671732) (xy 384.877564 -202.659488) (xy 384.889914 -202.652772)
			(xy 384.910642 -202.633799) (xy 384.925403 -202.609887) (xy 384.933076 -202.582855) (xy 384.933077 -202.554754)
			(xy 384.925407 -202.527721) (xy 384.910648 -202.503808) (xy 384.889921 -202.484833) (xy 384.877564 -202.478132)
			(xy 384.85419 -202.465898) (xy 384.810767 -202.435934) (xy 384.771883 -202.400276) (xy 384.738277 -202.359606)
			(xy 384.710591 -202.314696) (xy 384.689351 -202.266402) (xy 384.674962 -202.215644) (xy 384.667698 -202.163389)
			(xy 384.667252 -202.13701) (xy 384.667738 -202.109759) (xy 384.675494 -202.055811) (xy 384.690849 -202.003516)
			(xy 384.713491 -201.953939) (xy 384.742957 -201.908089) (xy 384.778648 -201.866898) (xy 384.819839 -201.831207)
			(xy 384.865689 -201.801741) (xy 384.915266 -201.779099) (xy 384.967561 -201.763744) (xy 385.021509 -201.755988)
			(xy 385.076011 -201.755988) (xy 385.129959 -201.763744) (xy 385.182254 -201.779099) (xy 385.231831 -201.801741)
			(xy 385.277681 -201.831207) (xy 385.318872 -201.866898) (xy 385.354563 -201.908089) (xy 385.384029 -201.953939)
			(xy 385.406671 -202.003516) (xy 385.422026 -202.055811) (xy 385.429782 -202.109759) (xy 385.430268 -202.13701)
			(xy 385.429822 -202.16339) (xy 385.422568 -202.215648) (xy 385.408184 -202.266409) (xy 385.386946 -202.314705)
			(xy 385.359259 -202.359615) (xy 385.325649 -202.400283) (xy 385.286758 -202.435935) (xy 385.243327 -202.46589)
			(xy 385.219956 -202.478132) (xy 385.207586 -202.484817) (xy 385.186852 -202.503794) (xy 385.172087 -202.527711)
			(xy 385.164414 -202.554751) (xy 385.164415 -202.582858) (xy 385.172091 -202.609897) (xy 385.186858 -202.633813)
			(xy 385.207594 -202.652788) (xy 385.219956 -202.659488) (xy 385.243343 -202.671698) (xy 385.286766 -202.701667)
			(xy 385.325649 -202.737328) (xy 385.359253 -202.778002) (xy 385.386937 -202.822915) (xy 385.408175 -202.871212)
			(xy 385.422562 -202.921972) (xy 385.429824 -202.97423) (xy 385.430268 -203.00061) (xy 385.429782 -203.027861)
			(xy 385.422026 -203.081809) (xy 385.406671 -203.134104) (xy 385.384029 -203.183681) (xy 385.354563 -203.229531)
			(xy 385.318872 -203.270722) (xy 385.277681 -203.306413) (xy 385.231831 -203.335879) (xy 385.182254 -203.358521)
			(xy 385.129959 -203.373876) (xy 385.076011 -203.381632) (xy 385.021509 -203.381632) (xy 384.967561 -203.373876)
			(xy 384.915266 -203.358521) (xy 384.865689 -203.335879) (xy 384.819839 -203.306413) (xy 384.778648 -203.270722)
			(xy 384.742957 -203.229531) (xy 384.713491 -203.183681) (xy 384.690849 -203.134104) (xy 384.675494 -203.081809)
			(xy 384.667738 -203.027861) (xy 384.667252 -203.00061) (xy 382.102193 -203.00061) (xy 382.087137 -203.011001)
			(xy 382.063752 -203.023216) (xy 382.051391 -203.029916) (xy 382.030657 -203.048891) (xy 382.015891 -203.072806)
			(xy 382.008217 -203.099844) (xy 382.008216 -203.12795) (xy 382.015889 -203.154989) (xy 382.030653 -203.178905)
			(xy 382.051386 -203.197881) (xy 382.063752 -203.204572) (xy 382.087123 -203.216814) (xy 382.130554 -203.246769)
			(xy 382.169445 -203.28242) (xy 382.203055 -203.323089) (xy 382.230742 -203.367999) (xy 382.25198 -203.416295)
			(xy 382.266363 -203.467056) (xy 382.273617 -203.519314) (xy 382.274064 -203.545694) (xy 382.273496 -203.575874)
			(xy 382.26399 -203.63548) (xy 382.245199 -203.69284) (xy 382.2319 -203.719938) (xy 382.225656 -203.733084)
			(xy 382.220174 -203.761654) (xy 382.222978 -203.79061) (xy 382.233838 -203.817598) (xy 382.251874 -203.840424)
			(xy 382.275617 -203.857233) (xy 382.303139 -203.866659) (xy 382.332203 -203.867935) (xy 382.346454 -203.864972)
			(xy 382.411347 -203.849631) (xy 382.542563 -203.825813) (xy 382.674971 -203.809899) (xy 382.808094 -203.801949)
			(xy 382.874774 -203.801472) (xy 382.941104 -203.801962) (xy 383.073527 -203.80987) (xy 383.205244 -203.825657)
			(xy 383.335785 -203.849269) (xy 383.464687 -203.880622) (xy 383.59149 -203.919603) (xy 383.715743 -203.966075)
			(xy 383.837005 -204.019872) (xy 383.954845 -204.080802) (xy 384.068842 -204.148648) (xy 384.178591 -204.223171)
			(xy 384.283703 -204.304103) (xy 384.383803 -204.391158) (xy 384.478535 -204.484026) (xy 384.567561 -204.582376)
			(xy 384.650567 -204.685859) (xy 384.727255 -204.794106) (xy 384.797354 -204.906733) (xy 384.860613 -205.023338)
			(xy 384.916809 -205.143507) (xy 384.96574 -205.266813) (xy 385.007233 -205.392816) (xy 385.041141 -205.521069)
			(xy 385.067342 -205.651115) (xy 385.085744 -205.782492) (xy 385.096281 -205.914733) (xy 385.098916 -206.047366)
			(xy 385.093638 -206.179921) (xy 385.080468 -206.311925) (xy 385.059451 -206.442909) (xy 385.030663 -206.572407)
			(xy 384.994206 -206.699959) (xy 384.95021 -206.82511) (xy 384.89883 -206.947416) (xy 384.840251 -207.066441)
			(xy 384.77468 -207.181763) (xy 384.702351 -207.29297) (xy 384.62352 -207.399667) (xy 384.538469 -207.501475)
			(xy 384.4475 -207.598031) (xy 384.350936 -207.688992) (xy 384.249121 -207.774035) (xy 384.142417 -207.852857)
			(xy 384.031204 -207.925177) (xy 383.915877 -207.990738) (xy 383.796847 -208.049307) (xy 383.674537 -208.100676)
			(xy 383.549382 -208.144662) (xy 383.421827 -208.181109) (xy 383.292326 -208.209886) (xy 383.16134 -208.230892)
			(xy 383.029335 -208.244051) (xy 382.89678 -208.249317) (xy 382.764147 -208.246672) (xy 382.631907 -208.236124)
			(xy 382.500532 -208.217711) (xy 382.370488 -208.191499) (xy 382.242238 -208.15758) (xy 382.116238 -208.116077)
			(xy 381.992936 -208.067135) (xy 381.872772 -208.010929) (xy 381.756172 -207.94766) (xy 381.643551 -207.877552)
			(xy 381.535311 -207.800855) (xy 381.431835 -207.717841) (xy 381.333492 -207.628806) (xy 381.240632 -207.534066)
			(xy 381.153586 -207.433959) (xy 381.072662 -207.328841) (xy 380.998149 -207.219085) (xy 380.930311 -207.105082)
			(xy 380.869391 -206.987238) (xy 380.815605 -206.865971) (xy 380.769143 -206.741714) (xy 380.730173 -206.614907)
			(xy 380.698831 -206.486003) (xy 380.67523 -206.35546) (xy 380.659453 -206.223742) (xy 380.651557 -206.091318)
			(xy 380.651004 -206.024988) (xy 380.651482 -205.959736) (xy 380.659138 -205.829458) (xy 380.674422 -205.699853)
			(xy 380.697283 -205.571368) (xy 380.72764 -205.444445) (xy 380.76539 -205.319521) (xy 380.810403 -205.197026)
			(xy 380.862524 -205.077383) (xy 380.921573 -204.961003) (xy 380.987347 -204.848287) (xy 381.059619 -204.739623)
			(xy 381.138141 -204.635386) (xy 381.222642 -204.535934) (xy 381.312831 -204.44161) (xy 381.408397 -204.352739)
			(xy 381.509012 -204.269626) (xy 381.614329 -204.192558) (xy 381.723985 -204.121801) (xy 381.780542 -204.089254)
			(xy 381.792973 -204.081685) (xy 381.813232 -204.060806) (xy 381.826787 -204.035065) (xy 381.832541 -204.006547)
			(xy 381.830026 -203.977564) (xy 381.819447 -203.950463) (xy 381.80166 -203.927441) (xy 381.778108 -203.910363)
			(xy 381.76454 -203.905104) (xy 381.737103 -203.894766) (xy 381.685527 -203.866882) (xy 381.638825 -203.831435)
			(xy 381.598096 -203.789261) (xy 381.564299 -203.741352) (xy 381.538229 -203.688836) (xy 381.520501 -203.63295)
			(xy 381.511532 -203.575009) (xy 381.511048 -203.545694) (xy 381.511494 -203.519315) (xy 381.518757 -203.467059)
			(xy 381.533146 -203.4163) (xy 381.554386 -203.368006) (xy 381.582071 -203.323096) (xy 381.615676 -203.282424)
			(xy 381.65456 -203.246767) (xy 381.697983 -203.216801) (xy 381.72136 -203.204572) (xy 381.733718 -203.197871)
			(xy 381.754447 -203.178896) (xy 381.769207 -203.154983) (xy 381.776879 -203.127948) (xy 381.776878 -203.099846)
			(xy 381.769205 -203.072812) (xy 381.754443 -203.0489) (xy 381.733714 -203.029926) (xy 381.72136 -203.023216)
			(xy 381.696212 -203.009996) (xy 381.649789 -202.977246) (xy 381.608735 -202.937976) (xy 381.573955 -202.893054)
			(xy 381.546219 -202.843472) (xy 381.52614 -202.790327) (xy 381.514161 -202.734792) (xy 381.51181 -202.706478)
			(xy 381.510521 -202.693079) (xy 381.501814 -202.667619) (xy 381.486758 -202.645317) (xy 381.466399 -202.627723)
			(xy 381.44215 -202.616058) (xy 381.415696 -202.611134) (xy 381.388874 -202.613291) (xy 381.363548 -202.622381)
			(xy 381.352298 -202.62977) (xy 380.121414 -203.491592) (xy 377.514358 -206.97317) (xy 377.171966 -207.92059)
			(xy 377.138438 -207.96377) (xy 375.471944 -211.975446) (xy 375.471944 -213.758585) (xy 376.636789 -213.758585)
			(xy 376.636789 -213.706651) (xy 376.644914 -213.655356) (xy 376.660962 -213.605963) (xy 376.68454 -213.559689)
			(xy 376.715066 -213.517673) (xy 376.751789 -213.48095) (xy 376.793805 -213.450424) (xy 376.840079 -213.426846)
			(xy 376.889472 -213.410798) (xy 376.940767 -213.402673) (xy 376.992701 -213.402673) (xy 377.043996 -213.410798)
			(xy 377.093389 -213.426846) (xy 377.139663 -213.450424) (xy 377.181679 -213.48095) (xy 377.218402 -213.517673)
			(xy 377.248928 -213.559689) (xy 377.272506 -213.605963) (xy 377.288554 -213.655356) (xy 377.296679 -213.706651)
			(xy 377.297188 -213.732618) (xy 377.296679 -213.758585) (xy 378.516389 -213.758585) (xy 378.516389 -213.706651)
			(xy 378.524514 -213.655356) (xy 378.540562 -213.605963) (xy 378.56414 -213.559689) (xy 378.594666 -213.517673)
			(xy 378.631389 -213.48095) (xy 378.673405 -213.450424) (xy 378.719679 -213.426846) (xy 378.769072 -213.410798)
			(xy 378.820367 -213.402673) (xy 378.872301 -213.402673) (xy 378.923596 -213.410798) (xy 378.972989 -213.426846)
			(xy 379.019263 -213.450424) (xy 379.061279 -213.48095) (xy 379.098002 -213.517673) (xy 379.128528 -213.559689)
			(xy 379.152106 -213.605963) (xy 379.168154 -213.655356) (xy 379.176279 -213.706651) (xy 379.176788 -213.732618)
			(xy 379.176279 -213.758585) (xy 380.395989 -213.758585) (xy 380.395989 -213.706651) (xy 380.404114 -213.655356)
			(xy 380.420162 -213.605963) (xy 380.44374 -213.559689) (xy 380.474266 -213.517673) (xy 380.510989 -213.48095)
			(xy 380.553005 -213.450424) (xy 380.599279 -213.426846) (xy 380.648672 -213.410798) (xy 380.699967 -213.402673)
			(xy 380.751901 -213.402673) (xy 380.803196 -213.410798) (xy 380.852589 -213.426846) (xy 380.898863 -213.450424)
			(xy 380.940879 -213.48095) (xy 380.977602 -213.517673) (xy 381.008128 -213.559689) (xy 381.031706 -213.605963)
			(xy 381.047754 -213.655356) (xy 381.055879 -213.706651) (xy 381.056388 -213.732618) (xy 381.055879 -213.758585)
			(xy 381.047754 -213.80988) (xy 381.031706 -213.859273) (xy 381.008128 -213.905547) (xy 380.977602 -213.947563)
			(xy 380.940879 -213.984286) (xy 380.898863 -214.014812) (xy 380.852589 -214.03839) (xy 380.803196 -214.054438)
			(xy 380.751901 -214.062563) (xy 380.699967 -214.062563) (xy 380.648672 -214.054438) (xy 380.599279 -214.03839)
			(xy 380.553005 -214.014812) (xy 380.510989 -213.984286) (xy 380.474266 -213.947563) (xy 380.44374 -213.905547)
			(xy 380.420162 -213.859273) (xy 380.404114 -213.80988) (xy 380.395989 -213.758585) (xy 379.176279 -213.758585)
			(xy 379.168154 -213.80988) (xy 379.152106 -213.859273) (xy 379.128528 -213.905547) (xy 379.098002 -213.947563)
			(xy 379.061279 -213.984286) (xy 379.019263 -214.014812) (xy 378.972989 -214.03839) (xy 378.923596 -214.054438)
			(xy 378.872301 -214.062563) (xy 378.820367 -214.062563) (xy 378.769072 -214.054438) (xy 378.719679 -214.03839)
			(xy 378.673405 -214.014812) (xy 378.631389 -213.984286) (xy 378.594666 -213.947563) (xy 378.56414 -213.905547)
			(xy 378.540562 -213.859273) (xy 378.524514 -213.80988) (xy 378.516389 -213.758585) (xy 377.296679 -213.758585)
			(xy 377.288554 -213.80988) (xy 377.272506 -213.859273) (xy 377.248928 -213.905547) (xy 377.218402 -213.947563)
			(xy 377.181679 -213.984286) (xy 377.139663 -214.014812) (xy 377.093389 -214.03839) (xy 377.043996 -214.054438)
			(xy 376.992701 -214.062563) (xy 376.940767 -214.062563) (xy 376.889472 -214.054438) (xy 376.840079 -214.03839)
			(xy 376.793805 -214.014812) (xy 376.751789 -213.984286) (xy 376.715066 -213.947563) (xy 376.68454 -213.905547)
			(xy 376.660962 -213.859273) (xy 376.644914 -213.80988) (xy 376.636789 -213.758585) (xy 375.471944 -213.758585)
			(xy 375.471944 -214.46617) (xy 375.430485 -214.572401) (xy 381.805689 -214.572401) (xy 381.805689 -214.520467)
			(xy 381.813814 -214.469172) (xy 381.829862 -214.419779) (xy 381.85344 -214.373505) (xy 381.883966 -214.331489)
			(xy 381.920689 -214.294766) (xy 381.962705 -214.26424) (xy 382.008979 -214.240662) (xy 382.058372 -214.224614)
			(xy 382.109667 -214.216489) (xy 382.161601 -214.216489) (xy 382.212896 -214.224614) (xy 382.262289 -214.240662)
			(xy 382.308563 -214.26424) (xy 382.350579 -214.294766) (xy 382.387302 -214.331489) (xy 382.417828 -214.373505)
			(xy 382.441406 -214.419779) (xy 382.457454 -214.469172) (xy 382.465579 -214.520467) (xy 382.466088 -214.546434)
			(xy 382.465579 -214.572401) (xy 383.685289 -214.572401) (xy 383.685289 -214.520467) (xy 383.693414 -214.469172)
			(xy 383.709462 -214.419779) (xy 383.73304 -214.373505) (xy 383.763566 -214.331489) (xy 383.800289 -214.294766)
			(xy 383.842305 -214.26424) (xy 383.888579 -214.240662) (xy 383.937972 -214.224614) (xy 383.989267 -214.216489)
			(xy 384.041201 -214.216489) (xy 384.092496 -214.224614) (xy 384.141889 -214.240662) (xy 384.188163 -214.26424)
			(xy 384.230179 -214.294766) (xy 384.266902 -214.331489) (xy 384.297428 -214.373505) (xy 384.321006 -214.419779)
			(xy 384.337054 -214.469172) (xy 384.345179 -214.520467) (xy 384.345688 -214.546434) (xy 384.345179 -214.572401)
			(xy 384.337054 -214.623696) (xy 384.321006 -214.673089) (xy 384.297428 -214.719363) (xy 384.266902 -214.761379)
			(xy 384.230179 -214.798102) (xy 384.188163 -214.828628) (xy 384.141889 -214.852206) (xy 384.092496 -214.868254)
			(xy 384.041201 -214.876379) (xy 383.989267 -214.876379) (xy 383.937972 -214.868254) (xy 383.888579 -214.852206)
			(xy 383.842305 -214.828628) (xy 383.800289 -214.798102) (xy 383.763566 -214.761379) (xy 383.73304 -214.719363)
			(xy 383.709462 -214.673089) (xy 383.693414 -214.623696) (xy 383.685289 -214.572401) (xy 382.465579 -214.572401)
			(xy 382.457454 -214.623696) (xy 382.441406 -214.673089) (xy 382.417828 -214.719363) (xy 382.387302 -214.761379)
			(xy 382.350579 -214.798102) (xy 382.308563 -214.828628) (xy 382.262289 -214.852206) (xy 382.212896 -214.868254)
			(xy 382.161601 -214.876379) (xy 382.109667 -214.876379) (xy 382.058372 -214.868254) (xy 382.008979 -214.852206)
			(xy 381.962705 -214.828628) (xy 381.920689 -214.798102) (xy 381.883966 -214.761379) (xy 381.85344 -214.719363)
			(xy 381.829862 -214.673089) (xy 381.813814 -214.623696) (xy 381.805689 -214.572401) (xy 375.430485 -214.572401)
			(xy 375.083038 -215.462671) (xy 375.696735 -215.462671) (xy 375.696735 -215.410737) (xy 375.70486 -215.359442)
			(xy 375.720908 -215.310049) (xy 375.744486 -215.263775) (xy 375.775012 -215.221759) (xy 375.811735 -215.185036)
			(xy 375.853751 -215.15451) (xy 375.900025 -215.130932) (xy 375.949418 -215.114884) (xy 376.000713 -215.106759)
			(xy 376.052647 -215.106759) (xy 376.103942 -215.114884) (xy 376.153335 -215.130932) (xy 376.199609 -215.15451)
			(xy 376.241625 -215.185036) (xy 376.278348 -215.221759) (xy 376.308874 -215.263775) (xy 376.332452 -215.310049)
			(xy 376.3485 -215.359442) (xy 376.356625 -215.410737) (xy 376.357134 -215.436704) (xy 376.356625 -215.462671)
			(xy 377.576335 -215.462671) (xy 377.576335 -215.410737) (xy 377.58446 -215.359442) (xy 377.600508 -215.310049)
			(xy 377.624086 -215.263775) (xy 377.654612 -215.221759) (xy 377.691335 -215.185036) (xy 377.733351 -215.15451)
			(xy 377.779625 -215.130932) (xy 377.829018 -215.114884) (xy 377.880313 -215.106759) (xy 377.932247 -215.106759)
			(xy 377.983542 -215.114884) (xy 378.032935 -215.130932) (xy 378.079209 -215.15451) (xy 378.121225 -215.185036)
			(xy 378.157948 -215.221759) (xy 378.188474 -215.263775) (xy 378.212052 -215.310049) (xy 378.2281 -215.359442)
			(xy 378.236225 -215.410737) (xy 378.236734 -215.436704) (xy 378.236225 -215.462671) (xy 379.455935 -215.462671)
			(xy 379.455935 -215.410737) (xy 379.46406 -215.359442) (xy 379.480108 -215.310049) (xy 379.503686 -215.263775)
			(xy 379.534212 -215.221759) (xy 379.570935 -215.185036) (xy 379.612951 -215.15451) (xy 379.659225 -215.130932)
			(xy 379.708618 -215.114884) (xy 379.759913 -215.106759) (xy 379.811847 -215.106759) (xy 379.863142 -215.114884)
			(xy 379.912535 -215.130932) (xy 379.958809 -215.15451) (xy 380.000825 -215.185036) (xy 380.037548 -215.221759)
			(xy 380.068074 -215.263775) (xy 380.091652 -215.310049) (xy 380.1077 -215.359442) (xy 380.115825 -215.410737)
			(xy 380.116334 -215.436704) (xy 380.115825 -215.462671) (xy 380.1077 -215.513966) (xy 380.091652 -215.563359)
			(xy 380.068074 -215.609633) (xy 380.037548 -215.651649) (xy 380.000825 -215.688372) (xy 379.958809 -215.718898)
			(xy 379.912535 -215.742476) (xy 379.863142 -215.758524) (xy 379.811847 -215.766649) (xy 379.759913 -215.766649)
			(xy 379.708618 -215.758524) (xy 379.659225 -215.742476) (xy 379.612951 -215.718898) (xy 379.570935 -215.688372)
			(xy 379.534212 -215.651649) (xy 379.503686 -215.609633) (xy 379.480108 -215.563359) (xy 379.46406 -215.513966)
			(xy 379.455935 -215.462671) (xy 378.236225 -215.462671) (xy 378.2281 -215.513966) (xy 378.212052 -215.563359)
			(xy 378.188474 -215.609633) (xy 378.157948 -215.651649) (xy 378.121225 -215.688372) (xy 378.079209 -215.718898)
			(xy 378.032935 -215.742476) (xy 377.983542 -215.758524) (xy 377.932247 -215.766649) (xy 377.880313 -215.766649)
			(xy 377.829018 -215.758524) (xy 377.779625 -215.742476) (xy 377.733351 -215.718898) (xy 377.691335 -215.688372)
			(xy 377.654612 -215.651649) (xy 377.624086 -215.609633) (xy 377.600508 -215.563359) (xy 377.58446 -215.513966)
			(xy 377.576335 -215.462671) (xy 376.356625 -215.462671) (xy 376.3485 -215.513966) (xy 376.332452 -215.563359)
			(xy 376.308874 -215.609633) (xy 376.278348 -215.651649) (xy 376.241625 -215.688372) (xy 376.199609 -215.718898)
			(xy 376.153335 -215.742476) (xy 376.103942 -215.758524) (xy 376.052647 -215.766649) (xy 376.000713 -215.766649)
			(xy 375.949418 -215.758524) (xy 375.900025 -215.742476) (xy 375.853751 -215.718898) (xy 375.811735 -215.688372)
			(xy 375.775012 -215.651649) (xy 375.744486 -215.609633) (xy 375.720908 -215.563359) (xy 375.70486 -215.513966)
			(xy 375.696735 -215.462671) (xy 375.083038 -215.462671) (xy 374.862598 -216.027508) (xy 374.87987 -216.050114)
			(xy 374.895808 -216.071838) (xy 374.921145 -216.119386) (xy 374.938418 -216.17042) (xy 374.947169 -216.223581)
			(xy 374.947688 -216.25052) (xy 374.947209 -216.276165) (xy 374.947159 -216.276487) (xy 375.227089 -216.276487)
			(xy 375.227089 -216.224553) (xy 375.235214 -216.173258) (xy 375.251262 -216.123865) (xy 375.27484 -216.077591)
			(xy 375.305366 -216.035575) (xy 375.342089 -215.998852) (xy 375.384105 -215.968326) (xy 375.430379 -215.944748)
			(xy 375.479772 -215.9287) (xy 375.531067 -215.920575) (xy 375.583001 -215.920575) (xy 375.634296 -215.9287)
			(xy 375.683689 -215.944748) (xy 375.729963 -215.968326) (xy 375.771979 -215.998852) (xy 375.808702 -216.035575)
			(xy 375.839228 -216.077591) (xy 375.862806 -216.123865) (xy 375.878854 -216.173258) (xy 375.886979 -216.224553)
			(xy 375.887488 -216.25052) (xy 375.886979 -216.276487) (xy 376.166889 -216.276487) (xy 376.166889 -216.224553)
			(xy 376.175014 -216.173258) (xy 376.191062 -216.123865) (xy 376.21464 -216.077591) (xy 376.245166 -216.035575)
			(xy 376.281889 -215.998852) (xy 376.323905 -215.968326) (xy 376.370179 -215.944748) (xy 376.419572 -215.9287)
			(xy 376.470867 -215.920575) (xy 376.522801 -215.920575) (xy 376.574096 -215.9287) (xy 376.623489 -215.944748)
			(xy 376.669763 -215.968326) (xy 376.711779 -215.998852) (xy 376.748502 -216.035575) (xy 376.779028 -216.077591)
			(xy 376.802606 -216.123865) (xy 376.818654 -216.173258) (xy 376.826779 -216.224553) (xy 376.827288 -216.25052)
			(xy 376.826779 -216.276487) (xy 377.106689 -216.276487) (xy 377.106689 -216.224553) (xy 377.114814 -216.173258)
			(xy 377.130862 -216.123865) (xy 377.15444 -216.077591) (xy 377.184966 -216.035575) (xy 377.221689 -215.998852)
			(xy 377.263705 -215.968326) (xy 377.309979 -215.944748) (xy 377.359372 -215.9287) (xy 377.410667 -215.920575)
			(xy 377.462601 -215.920575) (xy 377.513896 -215.9287) (xy 377.563289 -215.944748) (xy 377.609563 -215.968326)
			(xy 377.651579 -215.998852) (xy 377.688302 -216.035575) (xy 377.718828 -216.077591) (xy 377.742406 -216.123865)
			(xy 377.758454 -216.173258) (xy 377.766579 -216.224553) (xy 377.767088 -216.25052) (xy 377.766579 -216.276487)
			(xy 378.046489 -216.276487) (xy 378.046489 -216.224553) (xy 378.054614 -216.173258) (xy 378.070662 -216.123865)
			(xy 378.09424 -216.077591) (xy 378.124766 -216.035575) (xy 378.161489 -215.998852) (xy 378.203505 -215.968326)
			(xy 378.249779 -215.944748) (xy 378.299172 -215.9287) (xy 378.350467 -215.920575) (xy 378.402401 -215.920575)
			(xy 378.453696 -215.9287) (xy 378.503089 -215.944748) (xy 378.549363 -215.968326) (xy 378.591379 -215.998852)
			(xy 378.628102 -216.035575) (xy 378.658628 -216.077591) (xy 378.682206 -216.123865) (xy 378.698254 -216.173258)
			(xy 378.706379 -216.224553) (xy 378.706888 -216.25052) (xy 378.706379 -216.276487) (xy 378.986289 -216.276487)
			(xy 378.986289 -216.224553) (xy 378.994414 -216.173258) (xy 379.010462 -216.123865) (xy 379.03404 -216.077591)
			(xy 379.064566 -216.035575) (xy 379.101289 -215.998852) (xy 379.143305 -215.968326) (xy 379.189579 -215.944748)
			(xy 379.238972 -215.9287) (xy 379.290267 -215.920575) (xy 379.342201 -215.920575) (xy 379.393496 -215.9287)
			(xy 379.442889 -215.944748) (xy 379.489163 -215.968326) (xy 379.531179 -215.998852) (xy 379.567902 -216.035575)
			(xy 379.598428 -216.077591) (xy 379.622006 -216.123865) (xy 379.638054 -216.173258) (xy 379.646179 -216.224553)
			(xy 379.646688 -216.25052) (xy 379.646179 -216.276487) (xy 379.926089 -216.276487) (xy 379.926089 -216.224553)
			(xy 379.934214 -216.173258) (xy 379.950262 -216.123865) (xy 379.97384 -216.077591) (xy 380.004366 -216.035575)
			(xy 380.041089 -215.998852) (xy 380.083105 -215.968326) (xy 380.129379 -215.944748) (xy 380.178772 -215.9287)
			(xy 380.230067 -215.920575) (xy 380.282001 -215.920575) (xy 380.333296 -215.9287) (xy 380.382689 -215.944748)
			(xy 380.428963 -215.968326) (xy 380.470979 -215.998852) (xy 380.507702 -216.035575) (xy 380.538228 -216.077591)
			(xy 380.561806 -216.123865) (xy 380.577854 -216.173258) (xy 380.585979 -216.224553) (xy 380.586488 -216.25052)
			(xy 380.585979 -216.276487) (xy 380.865889 -216.276487) (xy 380.865889 -216.224553) (xy 380.874014 -216.173258)
			(xy 380.890062 -216.123865) (xy 380.91364 -216.077591) (xy 380.944166 -216.035575) (xy 380.980889 -215.998852)
			(xy 381.022905 -215.968326) (xy 381.069179 -215.944748) (xy 381.118572 -215.9287) (xy 381.169867 -215.920575)
			(xy 381.221801 -215.920575) (xy 381.273096 -215.9287) (xy 381.322489 -215.944748) (xy 381.368763 -215.968326)
			(xy 381.410779 -215.998852) (xy 381.447502 -216.035575) (xy 381.478028 -216.077591) (xy 381.501606 -216.123865)
			(xy 381.517654 -216.173258) (xy 381.525779 -216.224553) (xy 381.526288 -216.25052) (xy 381.525779 -216.276487)
			(xy 381.805689 -216.276487) (xy 381.805689 -216.224553) (xy 381.813814 -216.173258) (xy 381.829862 -216.123865)
			(xy 381.85344 -216.077591) (xy 381.883966 -216.035575) (xy 381.920689 -215.998852) (xy 381.962705 -215.968326)
			(xy 382.008979 -215.944748) (xy 382.058372 -215.9287) (xy 382.109667 -215.920575) (xy 382.161601 -215.920575)
			(xy 382.212896 -215.9287) (xy 382.262289 -215.944748) (xy 382.308563 -215.968326) (xy 382.350579 -215.998852)
			(xy 382.387302 -216.035575) (xy 382.417828 -216.077591) (xy 382.441406 -216.123865) (xy 382.457454 -216.173258)
			(xy 382.465579 -216.224553) (xy 382.466088 -216.25052) (xy 382.465579 -216.276487) (xy 382.457454 -216.327782)
			(xy 382.441406 -216.377175) (xy 382.417828 -216.423449) (xy 382.387302 -216.465465) (xy 382.350579 -216.502188)
			(xy 382.308563 -216.532714) (xy 382.262289 -216.556292) (xy 382.212896 -216.57234) (xy 382.161601 -216.580465)
			(xy 382.109667 -216.580465) (xy 382.058372 -216.57234) (xy 382.008979 -216.556292) (xy 381.962705 -216.532714)
			(xy 381.920689 -216.502188) (xy 381.883966 -216.465465) (xy 381.85344 -216.423449) (xy 381.829862 -216.377175)
			(xy 381.813814 -216.327782) (xy 381.805689 -216.276487) (xy 381.525779 -216.276487) (xy 381.517654 -216.327782)
			(xy 381.501606 -216.377175) (xy 381.478028 -216.423449) (xy 381.447502 -216.465465) (xy 381.410779 -216.502188)
			(xy 381.368763 -216.532714) (xy 381.322489 -216.556292) (xy 381.273096 -216.57234) (xy 381.221801 -216.580465)
			(xy 381.169867 -216.580465) (xy 381.118572 -216.57234) (xy 381.069179 -216.556292) (xy 381.022905 -216.532714)
			(xy 380.980889 -216.502188) (xy 380.944166 -216.465465) (xy 380.91364 -216.423449) (xy 380.890062 -216.377175)
			(xy 380.874014 -216.327782) (xy 380.865889 -216.276487) (xy 380.585979 -216.276487) (xy 380.577854 -216.327782)
			(xy 380.561806 -216.377175) (xy 380.538228 -216.423449) (xy 380.507702 -216.465465) (xy 380.470979 -216.502188)
			(xy 380.428963 -216.532714) (xy 380.382689 -216.556292) (xy 380.333296 -216.57234) (xy 380.282001 -216.580465)
			(xy 380.230067 -216.580465) (xy 380.178772 -216.57234) (xy 380.129379 -216.556292) (xy 380.083105 -216.532714)
			(xy 380.041089 -216.502188) (xy 380.004366 -216.465465) (xy 379.97384 -216.423449) (xy 379.950262 -216.377175)
			(xy 379.934214 -216.327782) (xy 379.926089 -216.276487) (xy 379.646179 -216.276487) (xy 379.638054 -216.327782)
			(xy 379.622006 -216.377175) (xy 379.598428 -216.423449) (xy 379.567902 -216.465465) (xy 379.531179 -216.502188)
			(xy 379.489163 -216.532714) (xy 379.442889 -216.556292) (xy 379.393496 -216.57234) (xy 379.342201 -216.580465)
			(xy 379.290267 -216.580465) (xy 379.238972 -216.57234) (xy 379.189579 -216.556292) (xy 379.143305 -216.532714)
			(xy 379.101289 -216.502188) (xy 379.064566 -216.465465) (xy 379.03404 -216.423449) (xy 379.010462 -216.377175)
			(xy 378.994414 -216.327782) (xy 378.986289 -216.276487) (xy 378.706379 -216.276487) (xy 378.698254 -216.327782)
			(xy 378.682206 -216.377175) (xy 378.658628 -216.423449) (xy 378.628102 -216.465465) (xy 378.591379 -216.502188)
			(xy 378.549363 -216.532714) (xy 378.503089 -216.556292) (xy 378.453696 -216.57234) (xy 378.402401 -216.580465)
			(xy 378.350467 -216.580465) (xy 378.299172 -216.57234) (xy 378.249779 -216.556292) (xy 378.203505 -216.532714)
			(xy 378.161489 -216.502188) (xy 378.124766 -216.465465) (xy 378.09424 -216.423449) (xy 378.070662 -216.377175)
			(xy 378.054614 -216.327782) (xy 378.046489 -216.276487) (xy 377.766579 -216.276487) (xy 377.758454 -216.327782)
			(xy 377.742406 -216.377175) (xy 377.718828 -216.423449) (xy 377.688302 -216.465465) (xy 377.651579 -216.502188)
			(xy 377.609563 -216.532714) (xy 377.563289 -216.556292) (xy 377.513896 -216.57234) (xy 377.462601 -216.580465)
			(xy 377.410667 -216.580465) (xy 377.359372 -216.57234) (xy 377.309979 -216.556292) (xy 377.263705 -216.532714)
			(xy 377.221689 -216.502188) (xy 377.184966 -216.465465) (xy 377.15444 -216.423449) (xy 377.130862 -216.377175)
			(xy 377.114814 -216.327782) (xy 377.106689 -216.276487) (xy 376.826779 -216.276487) (xy 376.818654 -216.327782)
			(xy 376.802606 -216.377175) (xy 376.779028 -216.423449) (xy 376.748502 -216.465465) (xy 376.711779 -216.502188)
			(xy 376.669763 -216.532714) (xy 376.623489 -216.556292) (xy 376.574096 -216.57234) (xy 376.522801 -216.580465)
			(xy 376.470867 -216.580465) (xy 376.419572 -216.57234) (xy 376.370179 -216.556292) (xy 376.323905 -216.532714)
			(xy 376.281889 -216.502188) (xy 376.245166 -216.465465) (xy 376.21464 -216.423449) (xy 376.191062 -216.377175)
			(xy 376.175014 -216.327782) (xy 376.166889 -216.276487) (xy 375.886979 -216.276487) (xy 375.878854 -216.327782)
			(xy 375.862806 -216.377175) (xy 375.839228 -216.423449) (xy 375.808702 -216.465465) (xy 375.771979 -216.502188)
			(xy 375.729963 -216.532714) (xy 375.683689 -216.556292) (xy 375.634296 -216.57234) (xy 375.583001 -216.580465)
			(xy 375.531067 -216.580465) (xy 375.479772 -216.57234) (xy 375.430379 -216.556292) (xy 375.384105 -216.532714)
			(xy 375.342089 -216.502188) (xy 375.305366 -216.465465) (xy 375.27484 -216.423449) (xy 375.251262 -216.377175)
			(xy 375.235214 -216.327782) (xy 375.227089 -216.276487) (xy 374.947159 -216.276487) (xy 374.939293 -216.326842)
			(xy 374.923638 -216.375685) (xy 374.90062 -216.421521) (xy 374.870794 -216.463248) (xy 374.834876 -216.499863)
			(xy 374.79373 -216.530485) (xy 374.748344 -216.554378) (xy 374.699811 -216.570969) (xy 374.674638 -216.575894)
			(xy 374.646698 -216.580974) (xy 374.474994 -217.020902) (xy 374.47601 -217.03284) (xy 374.477534 -217.064336)
			(xy 374.477011 -217.090303) (xy 374.757189 -217.090303) (xy 374.757189 -217.038369) (xy 374.765314 -216.987074)
			(xy 374.781362 -216.937681) (xy 374.80494 -216.891407) (xy 374.835466 -216.849391) (xy 374.872189 -216.812668)
			(xy 374.914205 -216.782142) (xy 374.960479 -216.758564) (xy 375.009872 -216.742516) (xy 375.061167 -216.734391)
			(xy 375.113101 -216.734391) (xy 375.164396 -216.742516) (xy 375.213789 -216.758564) (xy 375.260063 -216.782142)
			(xy 375.302079 -216.812668) (xy 375.338802 -216.849391) (xy 375.369328 -216.891407) (xy 375.392906 -216.937681)
			(xy 375.408954 -216.987074) (xy 375.417079 -217.038369) (xy 375.417588 -217.064336) (xy 375.696226 -217.064336)
			(xy 375.696735 -217.038369) (xy 375.70486 -216.987074) (xy 375.720908 -216.937681) (xy 375.744486 -216.891407)
			(xy 375.775012 -216.849391) (xy 375.811735 -216.812668) (xy 375.853751 -216.782142) (xy 375.900025 -216.758564)
			(xy 375.949418 -216.742516) (xy 376.000713 -216.734391) (xy 376.052647 -216.734391) (xy 376.103942 -216.742516)
			(xy 376.153335 -216.758564) (xy 376.199609 -216.782142) (xy 376.241625 -216.812668) (xy 376.278348 -216.849391)
			(xy 376.308874 -216.891407) (xy 376.332452 -216.937681) (xy 376.3485 -216.987074) (xy 376.356625 -217.038369)
			(xy 376.357134 -217.064336) (xy 376.356634 -217.090303) (xy 376.636789 -217.090303) (xy 376.636789 -217.038369)
			(xy 376.644914 -216.987074) (xy 376.660962 -216.937681) (xy 376.68454 -216.891407) (xy 376.715066 -216.849391)
			(xy 376.751789 -216.812668) (xy 376.793805 -216.782142) (xy 376.840079 -216.758564) (xy 376.889472 -216.742516)
			(xy 376.940767 -216.734391) (xy 376.992701 -216.734391) (xy 377.043996 -216.742516) (xy 377.093389 -216.758564)
			(xy 377.139663 -216.782142) (xy 377.181679 -216.812668) (xy 377.218402 -216.849391) (xy 377.248928 -216.891407)
			(xy 377.272506 -216.937681) (xy 377.288554 -216.987074) (xy 377.296679 -217.038369) (xy 377.297188 -217.064336)
			(xy 377.575826 -217.064336) (xy 377.576335 -217.038369) (xy 377.58446 -216.987074) (xy 377.600508 -216.937681)
			(xy 377.624086 -216.891407) (xy 377.654612 -216.849391) (xy 377.691335 -216.812668) (xy 377.733351 -216.782142)
			(xy 377.779625 -216.758564) (xy 377.829018 -216.742516) (xy 377.880313 -216.734391) (xy 377.932247 -216.734391)
			(xy 377.983542 -216.742516) (xy 378.032935 -216.758564) (xy 378.079209 -216.782142) (xy 378.121225 -216.812668)
			(xy 378.157948 -216.849391) (xy 378.188474 -216.891407) (xy 378.212052 -216.937681) (xy 378.2281 -216.987074)
			(xy 378.236225 -217.038369) (xy 378.236734 -217.064336) (xy 378.236234 -217.090303) (xy 378.516389 -217.090303)
			(xy 378.516389 -217.038369) (xy 378.524514 -216.987074) (xy 378.540562 -216.937681) (xy 378.56414 -216.891407)
			(xy 378.594666 -216.849391) (xy 378.631389 -216.812668) (xy 378.673405 -216.782142) (xy 378.719679 -216.758564)
			(xy 378.769072 -216.742516) (xy 378.820367 -216.734391) (xy 378.872301 -216.734391) (xy 378.923596 -216.742516)
			(xy 378.972989 -216.758564) (xy 379.019263 -216.782142) (xy 379.061279 -216.812668) (xy 379.098002 -216.849391)
			(xy 379.128528 -216.891407) (xy 379.152106 -216.937681) (xy 379.168154 -216.987074) (xy 379.176279 -217.038369)
			(xy 379.176788 -217.064336) (xy 379.455426 -217.064336) (xy 379.455935 -217.038369) (xy 379.46406 -216.987074)
			(xy 379.480108 -216.937681) (xy 379.503686 -216.891407) (xy 379.534212 -216.849391) (xy 379.570935 -216.812668)
			(xy 379.612951 -216.782142) (xy 379.659225 -216.758564) (xy 379.708618 -216.742516) (xy 379.759913 -216.734391)
			(xy 379.811847 -216.734391) (xy 379.863142 -216.742516) (xy 379.912535 -216.758564) (xy 379.958809 -216.782142)
			(xy 380.000825 -216.812668) (xy 380.037548 -216.849391) (xy 380.068074 -216.891407) (xy 380.091652 -216.937681)
			(xy 380.1077 -216.987074) (xy 380.115825 -217.038369) (xy 380.116334 -217.064336) (xy 380.115834 -217.090303)
			(xy 380.395989 -217.090303) (xy 380.395989 -217.038369) (xy 380.404114 -216.987074) (xy 380.420162 -216.937681)
			(xy 380.44374 -216.891407) (xy 380.474266 -216.849391) (xy 380.510989 -216.812668) (xy 380.553005 -216.782142)
			(xy 380.599279 -216.758564) (xy 380.648672 -216.742516) (xy 380.699967 -216.734391) (xy 380.751901 -216.734391)
			(xy 380.803196 -216.742516) (xy 380.852589 -216.758564) (xy 380.898863 -216.782142) (xy 380.940879 -216.812668)
			(xy 380.977602 -216.849391) (xy 381.008128 -216.891407) (xy 381.031706 -216.937681) (xy 381.047754 -216.987074)
			(xy 381.055879 -217.038369) (xy 381.056388 -217.064336) (xy 381.335026 -217.064336) (xy 381.335535 -217.038369)
			(xy 381.34366 -216.987074) (xy 381.359708 -216.937681) (xy 381.383286 -216.891407) (xy 381.413812 -216.849391)
			(xy 381.450535 -216.812668) (xy 381.492551 -216.782142) (xy 381.538825 -216.758564) (xy 381.588218 -216.742516)
			(xy 381.639513 -216.734391) (xy 381.691447 -216.734391) (xy 381.742742 -216.742516) (xy 381.792135 -216.758564)
			(xy 381.838409 -216.782142) (xy 381.880425 -216.812668) (xy 381.917148 -216.849391) (xy 381.947674 -216.891407)
			(xy 381.971252 -216.937681) (xy 381.9873 -216.987074) (xy 381.995425 -217.038369) (xy 381.995934 -217.064336)
			(xy 381.995434 -217.090303) (xy 382.275589 -217.090303) (xy 382.275589 -217.038369) (xy 382.283714 -216.987074)
			(xy 382.299762 -216.937681) (xy 382.32334 -216.891407) (xy 382.353866 -216.849391) (xy 382.390589 -216.812668)
			(xy 382.432605 -216.782142) (xy 382.478879 -216.758564) (xy 382.528272 -216.742516) (xy 382.579567 -216.734391)
			(xy 382.631501 -216.734391) (xy 382.682796 -216.742516) (xy 382.732189 -216.758564) (xy 382.778463 -216.782142)
			(xy 382.820479 -216.812668) (xy 382.857202 -216.849391) (xy 382.887728 -216.891407) (xy 382.911306 -216.937681)
			(xy 382.927354 -216.987074) (xy 382.935479 -217.038369) (xy 382.935988 -217.064336) (xy 382.935479 -217.090303)
			(xy 382.927354 -217.141598) (xy 382.911306 -217.190991) (xy 382.887728 -217.237265) (xy 382.857202 -217.279281)
			(xy 382.820479 -217.316004) (xy 382.778463 -217.34653) (xy 382.732189 -217.370108) (xy 382.682796 -217.386156)
			(xy 382.631501 -217.394281) (xy 382.579567 -217.394281) (xy 382.528272 -217.386156) (xy 382.478879 -217.370108)
			(xy 382.432605 -217.34653) (xy 382.390589 -217.316004) (xy 382.353866 -217.279281) (xy 382.32334 -217.237265)
			(xy 382.299762 -217.190991) (xy 382.283714 -217.141598) (xy 382.275589 -217.090303) (xy 381.995434 -217.090303)
			(xy 381.995397 -217.092246) (xy 381.986071 -217.147278) (xy 381.977392 -217.17381) (xy 381.969518 -217.195654)
			(xy 382.173734 -217.549222) (xy 382.196594 -217.55354) (xy 382.221503 -217.558766) (xy 382.269485 -217.575722)
			(xy 382.314302 -217.599831) (xy 382.354895 -217.630524) (xy 382.390305 -217.667074) (xy 382.419696 -217.70862)
			(xy 382.442372 -217.754178) (xy 382.4578 -217.802674) (xy 382.465613 -217.852961) (xy 382.466088 -217.878406)
			(xy 382.465579 -217.904373) (xy 382.457454 -217.955668) (xy 382.441406 -218.005061) (xy 382.417828 -218.051335)
			(xy 382.387302 -218.093351) (xy 382.350579 -218.130074) (xy 382.308563 -218.1606) (xy 382.262289 -218.184178)
			(xy 382.212896 -218.200226) (xy 382.161601 -218.208351) (xy 382.109667 -218.208351) (xy 382.058372 -218.200226)
			(xy 382.008979 -218.184178) (xy 381.962705 -218.1606) (xy 381.920689 -218.130074) (xy 381.883966 -218.093351)
			(xy 381.85344 -218.051335) (xy 381.829862 -218.005061) (xy 381.813814 -217.955668) (xy 381.805689 -217.904373)
			(xy 381.80518 -217.878406) (xy 381.805735 -217.85042) (xy 381.815184 -217.795252) (xy 381.823976 -217.768678)
			(xy 381.831596 -217.74658) (xy 381.627888 -217.39352) (xy 381.604774 -217.389202) (xy 381.579829 -217.384082)
			(xy 381.531805 -217.367147) (xy 381.486946 -217.343047) (xy 381.446313 -217.312353) (xy 381.410868 -217.275792)
			(xy 381.381449 -217.234227) (xy 381.358751 -217.188643) (xy 381.343313 -217.140117) (xy 381.335498 -217.089797)
			(xy 381.335026 -217.064336) (xy 381.056388 -217.064336) (xy 381.055879 -217.090303) (xy 381.047754 -217.141598)
			(xy 381.031706 -217.190991) (xy 381.008128 -217.237265) (xy 380.977602 -217.279281) (xy 380.940879 -217.316004)
			(xy 380.898863 -217.34653) (xy 380.852589 -217.370108) (xy 380.803196 -217.386156) (xy 380.751901 -217.394281)
			(xy 380.699967 -217.394281) (xy 380.648672 -217.386156) (xy 380.599279 -217.370108) (xy 380.553005 -217.34653)
			(xy 380.510989 -217.316004) (xy 380.474266 -217.279281) (xy 380.44374 -217.237265) (xy 380.420162 -217.190991)
			(xy 380.404114 -217.141598) (xy 380.395989 -217.090303) (xy 380.115834 -217.090303) (xy 380.115797 -217.092246)
			(xy 380.106471 -217.147278) (xy 380.097792 -217.17381) (xy 380.089918 -217.195654) (xy 380.294134 -217.549222)
			(xy 380.316994 -217.55354) (xy 380.341903 -217.558766) (xy 380.389885 -217.575722) (xy 380.434702 -217.599831)
			(xy 380.475295 -217.630524) (xy 380.510705 -217.667074) (xy 380.540096 -217.70862) (xy 380.562772 -217.754178)
			(xy 380.5782 -217.802674) (xy 380.586013 -217.852961) (xy 380.586488 -217.878406) (xy 380.585979 -217.904373)
			(xy 380.577854 -217.955668) (xy 380.561806 -218.005061) (xy 380.538228 -218.051335) (xy 380.507702 -218.093351)
			(xy 380.470979 -218.130074) (xy 380.428963 -218.1606) (xy 380.382689 -218.184178) (xy 380.333296 -218.200226)
			(xy 380.282001 -218.208351) (xy 380.230067 -218.208351) (xy 380.178772 -218.200226) (xy 380.129379 -218.184178)
			(xy 380.083105 -218.1606) (xy 380.041089 -218.130074) (xy 380.004366 -218.093351) (xy 379.97384 -218.051335)
			(xy 379.950262 -218.005061) (xy 379.934214 -217.955668) (xy 379.926089 -217.904373) (xy 379.92558 -217.878406)
			(xy 379.926135 -217.85042) (xy 379.935584 -217.795252) (xy 379.944376 -217.768678) (xy 379.951996 -217.74658)
			(xy 379.748288 -217.39352) (xy 379.725174 -217.389202) (xy 379.700229 -217.384082) (xy 379.652205 -217.367147)
			(xy 379.607346 -217.343047) (xy 379.566713 -217.312353) (xy 379.531268 -217.275792) (xy 379.501849 -217.234227)
			(xy 379.479151 -217.188643) (xy 379.463713 -217.140117) (xy 379.455898 -217.089797) (xy 379.455426 -217.064336)
			(xy 379.176788 -217.064336) (xy 379.176279 -217.090303) (xy 379.168154 -217.141598) (xy 379.152106 -217.190991)
			(xy 379.128528 -217.237265) (xy 379.098002 -217.279281) (xy 379.061279 -217.316004) (xy 379.019263 -217.34653)
			(xy 378.972989 -217.370108) (xy 378.923596 -217.386156) (xy 378.872301 -217.394281) (xy 378.820367 -217.394281)
			(xy 378.769072 -217.386156) (xy 378.719679 -217.370108) (xy 378.673405 -217.34653) (xy 378.631389 -217.316004)
			(xy 378.594666 -217.279281) (xy 378.56414 -217.237265) (xy 378.540562 -217.190991) (xy 378.524514 -217.141598)
			(xy 378.516389 -217.090303) (xy 378.236234 -217.090303) (xy 378.236197 -217.092246) (xy 378.226871 -217.147278)
			(xy 378.218192 -217.17381) (xy 378.210318 -217.195654) (xy 378.414534 -217.549222) (xy 378.437394 -217.55354)
			(xy 378.462303 -217.558766) (xy 378.510285 -217.575722) (xy 378.555102 -217.599831) (xy 378.595695 -217.630524)
			(xy 378.631105 -217.667074) (xy 378.660496 -217.70862) (xy 378.683172 -217.754178) (xy 378.6986 -217.802674)
			(xy 378.706413 -217.852961) (xy 378.706888 -217.878406) (xy 378.706379 -217.904373) (xy 378.698254 -217.955668)
			(xy 378.682206 -218.005061) (xy 378.658628 -218.051335) (xy 378.628102 -218.093351) (xy 378.591379 -218.130074)
			(xy 378.549363 -218.1606) (xy 378.503089 -218.184178) (xy 378.453696 -218.200226) (xy 378.402401 -218.208351)
			(xy 378.350467 -218.208351) (xy 378.299172 -218.200226) (xy 378.249779 -218.184178) (xy 378.203505 -218.1606)
			(xy 378.161489 -218.130074) (xy 378.124766 -218.093351) (xy 378.09424 -218.051335) (xy 378.070662 -218.005061)
			(xy 378.054614 -217.955668) (xy 378.046489 -217.904373) (xy 378.04598 -217.878406) (xy 378.046535 -217.85042)
			(xy 378.055984 -217.795252) (xy 378.064776 -217.768678) (xy 378.072396 -217.74658) (xy 377.868688 -217.39352)
			(xy 377.845574 -217.389202) (xy 377.820629 -217.384082) (xy 377.772605 -217.367147) (xy 377.727746 -217.343047)
			(xy 377.687113 -217.312353) (xy 377.651668 -217.275792) (xy 377.622249 -217.234227) (xy 377.599551 -217.188643)
			(xy 377.584113 -217.140117) (xy 377.576298 -217.089797) (xy 377.575826 -217.064336) (xy 377.297188 -217.064336)
			(xy 377.296679 -217.090303) (xy 377.288554 -217.141598) (xy 377.272506 -217.190991) (xy 377.248928 -217.237265)
			(xy 377.218402 -217.279281) (xy 377.181679 -217.316004) (xy 377.139663 -217.34653) (xy 377.093389 -217.370108)
			(xy 377.043996 -217.386156) (xy 376.992701 -217.394281) (xy 376.940767 -217.394281) (xy 376.889472 -217.386156)
			(xy 376.840079 -217.370108) (xy 376.793805 -217.34653) (xy 376.751789 -217.316004) (xy 376.715066 -217.279281)
			(xy 376.68454 -217.237265) (xy 376.660962 -217.190991) (xy 376.644914 -217.141598) (xy 376.636789 -217.090303)
			(xy 376.356634 -217.090303) (xy 376.356597 -217.092246) (xy 376.347271 -217.147278) (xy 376.338592 -217.17381)
			(xy 376.330718 -217.195654) (xy 376.534934 -217.549222) (xy 376.557794 -217.55354) (xy 376.582703 -217.558766)
			(xy 376.630685 -217.575722) (xy 376.675502 -217.599831) (xy 376.716095 -217.630524) (xy 376.751505 -217.667074)
			(xy 376.780896 -217.70862) (xy 376.803572 -217.754178) (xy 376.819 -217.802674) (xy 376.826813 -217.852961)
			(xy 376.827288 -217.878406) (xy 376.826779 -217.904373) (xy 376.818654 -217.955668) (xy 376.802606 -218.005061)
			(xy 376.779028 -218.051335) (xy 376.748502 -218.093351) (xy 376.711779 -218.130074) (xy 376.669763 -218.1606)
			(xy 376.623489 -218.184178) (xy 376.574096 -218.200226) (xy 376.522801 -218.208351) (xy 376.470867 -218.208351)
			(xy 376.419572 -218.200226) (xy 376.370179 -218.184178) (xy 376.323905 -218.1606) (xy 376.281889 -218.130074)
			(xy 376.245166 -218.093351) (xy 376.21464 -218.051335) (xy 376.191062 -218.005061) (xy 376.175014 -217.955668)
			(xy 376.166889 -217.904373) (xy 376.16638 -217.878406) (xy 376.166935 -217.85042) (xy 376.176384 -217.795252)
			(xy 376.185176 -217.768678) (xy 376.192796 -217.74658) (xy 375.989088 -217.39352) (xy 375.965974 -217.389202)
			(xy 375.941029 -217.384082) (xy 375.893005 -217.367147) (xy 375.848146 -217.343047) (xy 375.807513 -217.312353)
			(xy 375.772068 -217.275792) (xy 375.742649 -217.234227) (xy 375.719951 -217.188643) (xy 375.704513 -217.140117)
			(xy 375.696698 -217.089797) (xy 375.696226 -217.064336) (xy 375.417588 -217.064336) (xy 375.417079 -217.090303)
			(xy 375.408954 -217.141598) (xy 375.392906 -217.190991) (xy 375.369328 -217.237265) (xy 375.338802 -217.279281)
			(xy 375.302079 -217.316004) (xy 375.260063 -217.34653) (xy 375.213789 -217.370108) (xy 375.164396 -217.386156)
			(xy 375.113101 -217.394281) (xy 375.061167 -217.394281) (xy 375.009872 -217.386156) (xy 374.960479 -217.370108)
			(xy 374.914205 -217.34653) (xy 374.872189 -217.316004) (xy 374.835466 -217.279281) (xy 374.80494 -217.237265)
			(xy 374.781362 -217.190991) (xy 374.765314 -217.141598) (xy 374.757189 -217.090303) (xy 374.477011 -217.090303)
			(xy 374.476972 -217.092243) (xy 374.46765 -217.147274) (xy 374.458992 -217.17381) (xy 374.451118 -217.195654)
			(xy 374.655334 -217.549222) (xy 374.678194 -217.55354) (xy 374.70312 -217.558693) (xy 374.751115 -217.575639)
			(xy 374.795942 -217.599746) (xy 374.836541 -217.630444) (xy 374.87195 -217.667006) (xy 374.901332 -217.708567)
			(xy 374.923991 -217.754143) (xy 374.939391 -217.802656) (xy 374.947167 -217.852957) (xy 374.947688 -217.878406)
			(xy 374.947179 -217.904373) (xy 374.939054 -217.955668) (xy 374.923006 -218.005061) (xy 374.899428 -218.051335)
			(xy 374.868902 -218.093351) (xy 374.832179 -218.130074) (xy 374.790163 -218.1606) (xy 374.743889 -218.184178)
			(xy 374.694496 -218.200226) (xy 374.643201 -218.208351) (xy 374.591267 -218.208351) (xy 374.539972 -218.200226)
			(xy 374.490579 -218.184178) (xy 374.444305 -218.1606) (xy 374.402289 -218.130074) (xy 374.365566 -218.093351)
			(xy 374.33504 -218.051335) (xy 374.311462 -218.005061) (xy 374.295414 -217.955668) (xy 374.287289 -217.904373)
			(xy 374.28678 -217.878406) (xy 374.287393 -217.850426) (xy 374.296843 -217.795268) (xy 374.305576 -217.768678)
			(xy 374.313196 -217.74658) (xy 374.293638 -217.712544) (xy 374.288543 -217.70444) (xy 374.273623 -217.69247)
			(xy 374.255352 -217.68681) (xy 374.236278 -217.688249) (xy 374.219063 -217.696587) (xy 374.206107 -217.710659)
			(xy 374.202198 -217.719402) (xy 374.004586 -218.225878) (xy 373.999667 -218.239983) (xy 373.997356 -218.269751)
			(xy 374.003739 -218.298918) (xy 374.018273 -218.325) (xy 374.03972 -218.345773) (xy 374.066252 -218.359468)
			(xy 374.095608 -218.364917) (xy 374.110504 -218.3638) (xy 374.119618 -218.362846) (xy 374.137917 -218.361828)
			(xy 374.14708 -218.361768) (xy 374.173049 -218.362249) (xy 374.224347 -218.370371) (xy 374.273743 -218.386418)
			(xy 374.32002 -218.409995) (xy 374.362039 -218.440522) (xy 374.398765 -218.477246) (xy 374.429294 -218.519263)
			(xy 374.452874 -218.565539) (xy 374.468924 -218.614934) (xy 374.477049 -218.666231) (xy 374.477049 -218.692222)
			(xy 374.756426 -218.692222) (xy 374.756859 -218.66677) (xy 374.764647 -218.616464) (xy 374.78006 -218.567949)
			(xy 374.802731 -218.522372) (xy 374.832124 -218.480811) (xy 374.867544 -218.44425) (xy 374.908152 -218.413554)
			(xy 374.952988 -218.38945) (xy 375.00099 -218.372507) (xy 375.02592 -218.367356) (xy 375.04878 -218.363038)
			(xy 375.252742 -218.00947) (xy 375.245122 -217.987626) (xy 375.236484 -217.96115) (xy 375.227159 -217.906249)
			(xy 375.22658 -217.878406) (xy 375.227089 -217.852439) (xy 375.235214 -217.801144) (xy 375.251262 -217.751751)
			(xy 375.27484 -217.705477) (xy 375.305366 -217.663461) (xy 375.342089 -217.626738) (xy 375.384105 -217.596212)
			(xy 375.430379 -217.572634) (xy 375.479772 -217.556586) (xy 375.531067 -217.548461) (xy 375.583001 -217.548461)
			(xy 375.634296 -217.556586) (xy 375.683689 -217.572634) (xy 375.729963 -217.596212) (xy 375.771979 -217.626738)
			(xy 375.808702 -217.663461) (xy 375.839228 -217.705477) (xy 375.862806 -217.751751) (xy 375.878854 -217.801144)
			(xy 375.886979 -217.852439) (xy 375.887488 -217.878406) (xy 375.886984 -217.903878) (xy 375.879164 -217.954219)
			(xy 375.863712 -218.002763) (xy 375.840993 -218.04836) (xy 375.811545 -218.089931) (xy 375.776066 -218.12649)
			(xy 375.735397 -218.15717) (xy 375.690501 -218.181246) (xy 375.642442 -218.198147) (xy 375.617486 -218.203272)
			(xy 375.594372 -218.20759) (xy 375.390918 -218.560396) (xy 375.398538 -218.582494) (xy 375.407272 -218.609083)
			(xy 375.416722 -218.664242) (xy 375.417334 -218.692222) (xy 375.416825 -218.718189) (xy 375.696735 -218.718189)
			(xy 375.696735 -218.666255) (xy 375.70486 -218.61496) (xy 375.720908 -218.565567) (xy 375.744486 -218.519293)
			(xy 375.775012 -218.477277) (xy 375.811735 -218.440554) (xy 375.853751 -218.410028) (xy 375.900025 -218.38645)
			(xy 375.949418 -218.370402) (xy 376.000713 -218.362277) (xy 376.052647 -218.362277) (xy 376.103942 -218.370402)
			(xy 376.153335 -218.38645) (xy 376.199609 -218.410028) (xy 376.241625 -218.440554) (xy 376.278348 -218.477277)
			(xy 376.308874 -218.519293) (xy 376.332452 -218.565567) (xy 376.3485 -218.61496) (xy 376.356625 -218.666255)
			(xy 376.357134 -218.692222) (xy 376.636026 -218.692222) (xy 376.636459 -218.66677) (xy 376.644247 -218.616464)
			(xy 376.65966 -218.567949) (xy 376.682331 -218.522372) (xy 376.711724 -218.480811) (xy 376.747144 -218.44425)
			(xy 376.787752 -218.413554) (xy 376.832588 -218.38945) (xy 376.88059 -218.372507) (xy 376.90552 -218.367356)
			(xy 376.92838 -218.363038) (xy 377.132342 -218.00947) (xy 377.124722 -217.987626) (xy 377.116084 -217.96115)
			(xy 377.106759 -217.906249) (xy 377.10618 -217.878406) (xy 377.106689 -217.852439) (xy 377.114814 -217.801144)
			(xy 377.130862 -217.751751) (xy 377.15444 -217.705477) (xy 377.184966 -217.663461) (xy 377.221689 -217.626738)
			(xy 377.263705 -217.596212) (xy 377.309979 -217.572634) (xy 377.359372 -217.556586) (xy 377.410667 -217.548461)
			(xy 377.462601 -217.548461) (xy 377.513896 -217.556586) (xy 377.563289 -217.572634) (xy 377.609563 -217.596212)
			(xy 377.651579 -217.626738) (xy 377.688302 -217.663461) (xy 377.718828 -217.705477) (xy 377.742406 -217.751751)
			(xy 377.758454 -217.801144) (xy 377.766579 -217.852439) (xy 377.767088 -217.878406) (xy 377.766584 -217.903878)
			(xy 377.758764 -217.954219) (xy 377.743312 -218.002763) (xy 377.720593 -218.04836) (xy 377.691145 -218.089931)
			(xy 377.655666 -218.12649) (xy 377.614997 -218.15717) (xy 377.570101 -218.181246) (xy 377.522042 -218.198147)
			(xy 377.497086 -218.203272) (xy 377.473972 -218.20759) (xy 377.270518 -218.560396) (xy 377.278138 -218.582494)
			(xy 377.286872 -218.609083) (xy 377.296322 -218.664242) (xy 377.296934 -218.692222) (xy 377.296425 -218.718189)
			(xy 377.576335 -218.718189) (xy 377.576335 -218.666255) (xy 377.58446 -218.61496) (xy 377.600508 -218.565567)
			(xy 377.624086 -218.519293) (xy 377.654612 -218.477277) (xy 377.691335 -218.440554) (xy 377.733351 -218.410028)
			(xy 377.779625 -218.38645) (xy 377.829018 -218.370402) (xy 377.880313 -218.362277) (xy 377.932247 -218.362277)
			(xy 377.983542 -218.370402) (xy 378.032935 -218.38645) (xy 378.079209 -218.410028) (xy 378.121225 -218.440554)
			(xy 378.157948 -218.477277) (xy 378.188474 -218.519293) (xy 378.212052 -218.565567) (xy 378.2281 -218.61496)
			(xy 378.236225 -218.666255) (xy 378.236734 -218.692222) (xy 378.515626 -218.692222) (xy 378.516059 -218.66677)
			(xy 378.523847 -218.616464) (xy 378.53926 -218.567949) (xy 378.561931 -218.522372) (xy 378.591324 -218.480811)
			(xy 378.626744 -218.44425) (xy 378.667352 -218.413554) (xy 378.712188 -218.38945) (xy 378.76019 -218.372507)
			(xy 378.78512 -218.367356) (xy 378.80798 -218.363038) (xy 379.011942 -218.00947) (xy 379.004322 -217.987626)
			(xy 378.995684 -217.96115) (xy 378.986359 -217.906249) (xy 378.98578 -217.878406) (xy 378.986289 -217.852439)
			(xy 378.994414 -217.801144) (xy 379.010462 -217.751751) (xy 379.03404 -217.705477) (xy 379.064566 -217.663461)
			(xy 379.101289 -217.626738) (xy 379.143305 -217.596212) (xy 379.189579 -217.572634) (xy 379.238972 -217.556586)
			(xy 379.290267 -217.548461) (xy 379.342201 -217.548461) (xy 379.393496 -217.556586) (xy 379.442889 -217.572634)
			(xy 379.489163 -217.596212) (xy 379.531179 -217.626738) (xy 379.567902 -217.663461) (xy 379.598428 -217.705477)
			(xy 379.622006 -217.751751) (xy 379.638054 -217.801144) (xy 379.646179 -217.852439) (xy 379.646688 -217.878406)
			(xy 379.646184 -217.903878) (xy 379.638364 -217.954219) (xy 379.622912 -218.002763) (xy 379.600193 -218.04836)
			(xy 379.570745 -218.089931) (xy 379.535266 -218.12649) (xy 379.494597 -218.15717) (xy 379.449701 -218.181246)
			(xy 379.401642 -218.198147) (xy 379.376686 -218.203272) (xy 379.353572 -218.20759) (xy 379.150118 -218.560396)
			(xy 379.157738 -218.582494) (xy 379.166472 -218.609083) (xy 379.175922 -218.664242) (xy 379.176534 -218.692222)
			(xy 379.176025 -218.718189) (xy 379.455935 -218.718189) (xy 379.455935 -218.666255) (xy 379.46406 -218.61496)
			(xy 379.480108 -218.565567) (xy 379.503686 -218.519293) (xy 379.534212 -218.477277) (xy 379.570935 -218.440554)
			(xy 379.612951 -218.410028) (xy 379.659225 -218.38645) (xy 379.708618 -218.370402) (xy 379.759913 -218.362277)
			(xy 379.811847 -218.362277) (xy 379.863142 -218.370402) (xy 379.912535 -218.38645) (xy 379.958809 -218.410028)
			(xy 380.000825 -218.440554) (xy 380.037548 -218.477277) (xy 380.068074 -218.519293) (xy 380.091652 -218.565567)
			(xy 380.1077 -218.61496) (xy 380.115825 -218.666255) (xy 380.116334 -218.692222) (xy 380.395226 -218.692222)
			(xy 380.395659 -218.66677) (xy 380.403447 -218.616464) (xy 380.41886 -218.567949) (xy 380.441531 -218.522372)
			(xy 380.470924 -218.480811) (xy 380.506344 -218.44425) (xy 380.546952 -218.413554) (xy 380.591788 -218.38945)
			(xy 380.63979 -218.372507) (xy 380.66472 -218.367356) (xy 380.68758 -218.363038) (xy 380.891542 -218.00947)
			(xy 380.883922 -217.987626) (xy 380.875284 -217.96115) (xy 380.865959 -217.906249) (xy 380.86538 -217.878406)
			(xy 380.865889 -217.852439) (xy 380.874014 -217.801144) (xy 380.890062 -217.751751) (xy 380.91364 -217.705477)
			(xy 380.944166 -217.663461) (xy 380.980889 -217.626738) (xy 381.022905 -217.596212) (xy 381.069179 -217.572634)
			(xy 381.118572 -217.556586) (xy 381.169867 -217.548461) (xy 381.221801 -217.548461) (xy 381.273096 -217.556586)
			(xy 381.322489 -217.572634) (xy 381.368763 -217.596212) (xy 381.410779 -217.626738) (xy 381.447502 -217.663461)
			(xy 381.478028 -217.705477) (xy 381.501606 -217.751751) (xy 381.517654 -217.801144) (xy 381.525779 -217.852439)
			(xy 381.526288 -217.878406) (xy 381.525784 -217.903878) (xy 381.517964 -217.954219) (xy 381.502512 -218.002763)
			(xy 381.479793 -218.04836) (xy 381.450345 -218.089931) (xy 381.414866 -218.12649) (xy 381.374197 -218.15717)
			(xy 381.329301 -218.181246) (xy 381.281242 -218.198147) (xy 381.256286 -218.203272) (xy 381.233172 -218.20759)
			(xy 381.029718 -218.560396) (xy 381.037338 -218.582494) (xy 381.046072 -218.609083) (xy 381.055522 -218.664242)
			(xy 381.056134 -218.692222) (xy 381.055625 -218.718189) (xy 381.335789 -218.718189) (xy 381.335789 -218.666255)
			(xy 381.343914 -218.61496) (xy 381.359962 -218.565567) (xy 381.38354 -218.519293) (xy 381.414066 -218.477277)
			(xy 381.450789 -218.440554) (xy 381.492805 -218.410028) (xy 381.539079 -218.38645) (xy 381.588472 -218.370402)
			(xy 381.639767 -218.362277) (xy 381.691701 -218.362277) (xy 381.742996 -218.370402) (xy 381.792389 -218.38645)
			(xy 381.838663 -218.410028) (xy 381.880679 -218.440554) (xy 381.917402 -218.477277) (xy 381.947928 -218.519293)
			(xy 381.971506 -218.565567) (xy 381.987554 -218.61496) (xy 381.995679 -218.666255) (xy 381.996188 -218.692222)
			(xy 381.995679 -218.718189) (xy 381.987554 -218.769484) (xy 381.971506 -218.818877) (xy 381.947928 -218.865151)
			(xy 381.917402 -218.907167) (xy 381.880679 -218.94389) (xy 381.838663 -218.974416) (xy 381.792389 -218.997994)
			(xy 381.742996 -219.014042) (xy 381.691701 -219.022167) (xy 381.639767 -219.022167) (xy 381.588472 -219.014042)
			(xy 381.539079 -218.997994) (xy 381.492805 -218.974416) (xy 381.450789 -218.94389) (xy 381.414066 -218.907167)
			(xy 381.38354 -218.865151) (xy 381.359962 -218.818877) (xy 381.343914 -218.769484) (xy 381.335789 -218.718189)
			(xy 381.055625 -218.718189) (xy 381.0475 -218.769484) (xy 381.031452 -218.818877) (xy 381.007874 -218.865151)
			(xy 380.977348 -218.907167) (xy 380.940625 -218.94389) (xy 380.898609 -218.974416) (xy 380.852335 -218.997994)
			(xy 380.802942 -219.014042) (xy 380.751647 -219.022167) (xy 380.699713 -219.022167) (xy 380.648418 -219.014042)
			(xy 380.599025 -218.997994) (xy 380.552751 -218.974416) (xy 380.510735 -218.94389) (xy 380.474012 -218.907167)
			(xy 380.443486 -218.865151) (xy 380.419908 -218.818877) (xy 380.40386 -218.769484) (xy 380.395735 -218.718189)
			(xy 380.395226 -218.692222) (xy 380.116334 -218.692222) (xy 380.115825 -218.718189) (xy 380.1077 -218.769484)
			(xy 380.091652 -218.818877) (xy 380.068074 -218.865151) (xy 380.037548 -218.907167) (xy 380.000825 -218.94389)
			(xy 379.958809 -218.974416) (xy 379.912535 -218.997994) (xy 379.863142 -219.014042) (xy 379.811847 -219.022167)
			(xy 379.759913 -219.022167) (xy 379.708618 -219.014042) (xy 379.659225 -218.997994) (xy 379.612951 -218.974416)
			(xy 379.570935 -218.94389) (xy 379.534212 -218.907167) (xy 379.503686 -218.865151) (xy 379.480108 -218.818877)
			(xy 379.46406 -218.769484) (xy 379.455935 -218.718189) (xy 379.176025 -218.718189) (xy 379.1679 -218.769484)
			(xy 379.151852 -218.818877) (xy 379.128274 -218.865151) (xy 379.097748 -218.907167) (xy 379.061025 -218.94389)
			(xy 379.019009 -218.974416) (xy 378.972735 -218.997994) (xy 378.923342 -219.014042) (xy 378.872047 -219.022167)
			(xy 378.820113 -219.022167) (xy 378.768818 -219.014042) (xy 378.719425 -218.997994) (xy 378.673151 -218.974416)
			(xy 378.631135 -218.94389) (xy 378.594412 -218.907167) (xy 378.563886 -218.865151) (xy 378.540308 -218.818877)
			(xy 378.52426 -218.769484) (xy 378.516135 -218.718189) (xy 378.515626 -218.692222) (xy 378.236734 -218.692222)
			(xy 378.236225 -218.718189) (xy 378.2281 -218.769484) (xy 378.212052 -218.818877) (xy 378.188474 -218.865151)
			(xy 378.157948 -218.907167) (xy 378.121225 -218.94389) (xy 378.079209 -218.974416) (xy 378.032935 -218.997994)
			(xy 377.983542 -219.014042) (xy 377.932247 -219.022167) (xy 377.880313 -219.022167) (xy 377.829018 -219.014042)
			(xy 377.779625 -218.997994) (xy 377.733351 -218.974416) (xy 377.691335 -218.94389) (xy 377.654612 -218.907167)
			(xy 377.624086 -218.865151) (xy 377.600508 -218.818877) (xy 377.58446 -218.769484) (xy 377.576335 -218.718189)
			(xy 377.296425 -218.718189) (xy 377.2883 -218.769484) (xy 377.272252 -218.818877) (xy 377.248674 -218.865151)
			(xy 377.218148 -218.907167) (xy 377.181425 -218.94389) (xy 377.139409 -218.974416) (xy 377.093135 -218.997994)
			(xy 377.043742 -219.014042) (xy 376.992447 -219.022167) (xy 376.940513 -219.022167) (xy 376.889218 -219.014042)
			(xy 376.839825 -218.997994) (xy 376.793551 -218.974416) (xy 376.751535 -218.94389) (xy 376.714812 -218.907167)
			(xy 376.684286 -218.865151) (xy 376.660708 -218.818877) (xy 376.64466 -218.769484) (xy 376.636535 -218.718189)
			(xy 376.636026 -218.692222) (xy 376.357134 -218.692222) (xy 376.356625 -218.718189) (xy 376.3485 -218.769484)
			(xy 376.332452 -218.818877) (xy 376.308874 -218.865151) (xy 376.278348 -218.907167) (xy 376.241625 -218.94389)
			(xy 376.199609 -218.974416) (xy 376.153335 -218.997994) (xy 376.103942 -219.014042) (xy 376.052647 -219.022167)
			(xy 376.000713 -219.022167) (xy 375.949418 -219.014042) (xy 375.900025 -218.997994) (xy 375.853751 -218.974416)
			(xy 375.811735 -218.94389) (xy 375.775012 -218.907167) (xy 375.744486 -218.865151) (xy 375.720908 -218.818877)
			(xy 375.70486 -218.769484) (xy 375.696735 -218.718189) (xy 375.416825 -218.718189) (xy 375.4087 -218.769484)
			(xy 375.392652 -218.818877) (xy 375.369074 -218.865151) (xy 375.338548 -218.907167) (xy 375.301825 -218.94389)
			(xy 375.259809 -218.974416) (xy 375.213535 -218.997994) (xy 375.164142 -219.014042) (xy 375.112847 -219.022167)
			(xy 375.060913 -219.022167) (xy 375.009618 -219.014042) (xy 374.960225 -218.997994) (xy 374.913951 -218.974416)
			(xy 374.871935 -218.94389) (xy 374.835212 -218.907167) (xy 374.804686 -218.865151) (xy 374.781108 -218.818877)
			(xy 374.76506 -218.769484) (xy 374.756935 -218.718189) (xy 374.756426 -218.692222) (xy 374.477049 -218.692222)
			(xy 374.477049 -218.718169) (xy 374.468924 -218.769466) (xy 374.452874 -218.818861) (xy 374.429294 -218.865137)
			(xy 374.398765 -218.907154) (xy 374.362039 -218.943878) (xy 374.32002 -218.974405) (xy 374.273743 -218.997982)
			(xy 374.224347 -219.014029) (xy 374.173049 -219.022151) (xy 374.14708 -219.022676) (xy 374.118804 -219.022098)
			(xy 374.063076 -219.01248) (xy 374.009795 -218.993526) (xy 373.960511 -218.96579) (xy 373.916661 -218.930079)
			(xy 373.897652 -218.909138) (xy 373.887477 -218.898191) (xy 373.862218 -218.882243) (xy 373.833422 -218.874299)
			(xy 373.803559 -218.875043) (xy 373.775193 -218.884409) (xy 373.750759 -218.901594) (xy 373.732354 -218.925123)
			(xy 373.726456 -218.938856) (xy 373.68353 -219.048838) (xy 373.678722 -219.062519) (xy 373.676159 -219.09139)
			(xy 373.681805 -219.119819) (xy 373.695206 -219.14552) (xy 373.715284 -219.166424) (xy 373.740423 -219.18085)
			(xy 373.754396 -219.184728) (xy 373.77815 -219.190877) (xy 373.823653 -219.209233) (xy 373.865942 -219.234113)
			(xy 373.904089 -219.264971) (xy 373.937256 -219.301129) (xy 373.964714 -219.341793) (xy 373.98586 -219.386068)
			(xy 374.000229 -219.432982) (xy 374.007505 -219.481505) (xy 374.007888 -219.506038) (xy 374.007376 -219.532004)
			(xy 374.007376 -219.532005) (xy 374.287289 -219.532005) (xy 374.287289 -219.480071) (xy 374.295414 -219.428776)
			(xy 374.311462 -219.379383) (xy 374.33504 -219.333109) (xy 374.365566 -219.291093) (xy 374.402289 -219.25437)
			(xy 374.444305 -219.223844) (xy 374.490579 -219.200266) (xy 374.539972 -219.184218) (xy 374.591267 -219.176093)
			(xy 374.643201 -219.176093) (xy 374.694496 -219.184218) (xy 374.743889 -219.200266) (xy 374.790163 -219.223844)
			(xy 374.832179 -219.25437) (xy 374.868902 -219.291093) (xy 374.899428 -219.333109) (xy 374.923006 -219.379383)
			(xy 374.939054 -219.428776) (xy 374.947179 -219.480071) (xy 374.947688 -219.506038) (xy 374.947179 -219.532005)
			(xy 375.227089 -219.532005) (xy 375.227089 -219.480071) (xy 375.235214 -219.428776) (xy 375.251262 -219.379383)
			(xy 375.27484 -219.333109) (xy 375.305366 -219.291093) (xy 375.342089 -219.25437) (xy 375.384105 -219.223844)
			(xy 375.430379 -219.200266) (xy 375.479772 -219.184218) (xy 375.531067 -219.176093) (xy 375.583001 -219.176093)
			(xy 375.634296 -219.184218) (xy 375.683689 -219.200266) (xy 375.729963 -219.223844) (xy 375.771979 -219.25437)
			(xy 375.808702 -219.291093) (xy 375.839228 -219.333109) (xy 375.862806 -219.379383) (xy 375.878854 -219.428776)
			(xy 375.886979 -219.480071) (xy 375.887488 -219.506038) (xy 375.886979 -219.532005) (xy 376.166889 -219.532005)
			(xy 376.166889 -219.480071) (xy 376.175014 -219.428776) (xy 376.191062 -219.379383) (xy 376.21464 -219.333109)
			(xy 376.245166 -219.291093) (xy 376.281889 -219.25437) (xy 376.323905 -219.223844) (xy 376.370179 -219.200266)
			(xy 376.419572 -219.184218) (xy 376.470867 -219.176093) (xy 376.522801 -219.176093) (xy 376.574096 -219.184218)
			(xy 376.623489 -219.200266) (xy 376.669763 -219.223844) (xy 376.711779 -219.25437) (xy 376.748502 -219.291093)
			(xy 376.779028 -219.333109) (xy 376.802606 -219.379383) (xy 376.818654 -219.428776) (xy 376.826779 -219.480071)
			(xy 376.827288 -219.506038) (xy 376.826779 -219.532005) (xy 377.106689 -219.532005) (xy 377.106689 -219.480071)
			(xy 377.114814 -219.428776) (xy 377.130862 -219.379383) (xy 377.15444 -219.333109) (xy 377.184966 -219.291093)
			(xy 377.221689 -219.25437) (xy 377.263705 -219.223844) (xy 377.309979 -219.200266) (xy 377.359372 -219.184218)
			(xy 377.410667 -219.176093) (xy 377.462601 -219.176093) (xy 377.513896 -219.184218) (xy 377.563289 -219.200266)
			(xy 377.609563 -219.223844) (xy 377.651579 -219.25437) (xy 377.688302 -219.291093) (xy 377.718828 -219.333109)
			(xy 377.742406 -219.379383) (xy 377.758454 -219.428776) (xy 377.766579 -219.480071) (xy 377.767088 -219.506038)
			(xy 377.766579 -219.532005) (xy 378.046489 -219.532005) (xy 378.046489 -219.480071) (xy 378.054614 -219.428776)
			(xy 378.070662 -219.379383) (xy 378.09424 -219.333109) (xy 378.124766 -219.291093) (xy 378.161489 -219.25437)
			(xy 378.203505 -219.223844) (xy 378.249779 -219.200266) (xy 378.299172 -219.184218) (xy 378.350467 -219.176093)
			(xy 378.402401 -219.176093) (xy 378.453696 -219.184218) (xy 378.503089 -219.200266) (xy 378.549363 -219.223844)
			(xy 378.591379 -219.25437) (xy 378.628102 -219.291093) (xy 378.658628 -219.333109) (xy 378.682206 -219.379383)
			(xy 378.698254 -219.428776) (xy 378.706379 -219.480071) (xy 378.706888 -219.506038) (xy 378.706379 -219.532005)
			(xy 378.986289 -219.532005) (xy 378.986289 -219.480071) (xy 378.994414 -219.428776) (xy 379.010462 -219.379383)
			(xy 379.03404 -219.333109) (xy 379.064566 -219.291093) (xy 379.101289 -219.25437) (xy 379.143305 -219.223844)
			(xy 379.189579 -219.200266) (xy 379.238972 -219.184218) (xy 379.290267 -219.176093) (xy 379.342201 -219.176093)
			(xy 379.393496 -219.184218) (xy 379.442889 -219.200266) (xy 379.489163 -219.223844) (xy 379.531179 -219.25437)
			(xy 379.567902 -219.291093) (xy 379.598428 -219.333109) (xy 379.622006 -219.379383) (xy 379.638054 -219.428776)
			(xy 379.646179 -219.480071) (xy 379.646688 -219.506038) (xy 379.646179 -219.532005) (xy 379.926089 -219.532005)
			(xy 379.926089 -219.480071) (xy 379.934214 -219.428776) (xy 379.950262 -219.379383) (xy 379.97384 -219.333109)
			(xy 380.004366 -219.291093) (xy 380.041089 -219.25437) (xy 380.083105 -219.223844) (xy 380.129379 -219.200266)
			(xy 380.178772 -219.184218) (xy 380.230067 -219.176093) (xy 380.282001 -219.176093) (xy 380.333296 -219.184218)
			(xy 380.382689 -219.200266) (xy 380.428963 -219.223844) (xy 380.470979 -219.25437) (xy 380.507702 -219.291093)
			(xy 380.538228 -219.333109) (xy 380.561806 -219.379383) (xy 380.577854 -219.428776) (xy 380.585979 -219.480071)
			(xy 380.586488 -219.506038) (xy 380.585979 -219.532005) (xy 380.865889 -219.532005) (xy 380.865889 -219.480071)
			(xy 380.874014 -219.428776) (xy 380.890062 -219.379383) (xy 380.91364 -219.333109) (xy 380.944166 -219.291093)
			(xy 380.980889 -219.25437) (xy 381.022905 -219.223844) (xy 381.069179 -219.200266) (xy 381.118572 -219.184218)
			(xy 381.169867 -219.176093) (xy 381.221801 -219.176093) (xy 381.273096 -219.184218) (xy 381.322489 -219.200266)
			(xy 381.368763 -219.223844) (xy 381.410779 -219.25437) (xy 381.447502 -219.291093) (xy 381.478028 -219.333109)
			(xy 381.501606 -219.379383) (xy 381.517654 -219.428776) (xy 381.525779 -219.480071) (xy 381.526288 -219.506038)
			(xy 381.525779 -219.532005) (xy 381.805689 -219.532005) (xy 381.805689 -219.480071) (xy 381.813814 -219.428776)
			(xy 381.829862 -219.379383) (xy 381.85344 -219.333109) (xy 381.883966 -219.291093) (xy 381.920689 -219.25437)
			(xy 381.962705 -219.223844) (xy 382.008979 -219.200266) (xy 382.058372 -219.184218) (xy 382.109667 -219.176093)
			(xy 382.161601 -219.176093) (xy 382.212896 -219.184218) (xy 382.262289 -219.200266) (xy 382.308563 -219.223844)
			(xy 382.350579 -219.25437) (xy 382.387302 -219.291093) (xy 382.417828 -219.333109) (xy 382.441406 -219.379383)
			(xy 382.457454 -219.428776) (xy 382.465579 -219.480071) (xy 382.466088 -219.506038) (xy 382.465579 -219.532005)
			(xy 382.457454 -219.5833) (xy 382.441406 -219.632693) (xy 382.417828 -219.678967) (xy 382.387302 -219.720983)
			(xy 382.350579 -219.757706) (xy 382.308563 -219.788232) (xy 382.262289 -219.81181) (xy 382.212896 -219.827858)
			(xy 382.161601 -219.835983) (xy 382.109667 -219.835983) (xy 382.058372 -219.827858) (xy 382.008979 -219.81181)
			(xy 381.962705 -219.788232) (xy 381.920689 -219.757706) (xy 381.883966 -219.720983) (xy 381.85344 -219.678967)
			(xy 381.829862 -219.632693) (xy 381.813814 -219.5833) (xy 381.805689 -219.532005) (xy 381.525779 -219.532005)
			(xy 381.517654 -219.5833) (xy 381.501606 -219.632693) (xy 381.478028 -219.678967) (xy 381.447502 -219.720983)
			(xy 381.410779 -219.757706) (xy 381.368763 -219.788232) (xy 381.322489 -219.81181) (xy 381.273096 -219.827858)
			(xy 381.221801 -219.835983) (xy 381.169867 -219.835983) (xy 381.118572 -219.827858) (xy 381.069179 -219.81181)
			(xy 381.022905 -219.788232) (xy 380.980889 -219.757706) (xy 380.944166 -219.720983) (xy 380.91364 -219.678967)
			(xy 380.890062 -219.632693) (xy 380.874014 -219.5833) (xy 380.865889 -219.532005) (xy 380.585979 -219.532005)
			(xy 380.577854 -219.5833) (xy 380.561806 -219.632693) (xy 380.538228 -219.678967) (xy 380.507702 -219.720983)
			(xy 380.470979 -219.757706) (xy 380.428963 -219.788232) (xy 380.382689 -219.81181) (xy 380.333296 -219.827858)
			(xy 380.282001 -219.835983) (xy 380.230067 -219.835983) (xy 380.178772 -219.827858) (xy 380.129379 -219.81181)
			(xy 380.083105 -219.788232) (xy 380.041089 -219.757706) (xy 380.004366 -219.720983) (xy 379.97384 -219.678967)
			(xy 379.950262 -219.632693) (xy 379.934214 -219.5833) (xy 379.926089 -219.532005) (xy 379.646179 -219.532005)
			(xy 379.638054 -219.5833) (xy 379.622006 -219.632693) (xy 379.598428 -219.678967) (xy 379.567902 -219.720983)
			(xy 379.531179 -219.757706) (xy 379.489163 -219.788232) (xy 379.442889 -219.81181) (xy 379.393496 -219.827858)
			(xy 379.342201 -219.835983) (xy 379.290267 -219.835983) (xy 379.238972 -219.827858) (xy 379.189579 -219.81181)
			(xy 379.143305 -219.788232) (xy 379.101289 -219.757706) (xy 379.064566 -219.720983) (xy 379.03404 -219.678967)
			(xy 379.010462 -219.632693) (xy 378.994414 -219.5833) (xy 378.986289 -219.532005) (xy 378.706379 -219.532005)
			(xy 378.698254 -219.5833) (xy 378.682206 -219.632693) (xy 378.658628 -219.678967) (xy 378.628102 -219.720983)
			(xy 378.591379 -219.757706) (xy 378.549363 -219.788232) (xy 378.503089 -219.81181) (xy 378.453696 -219.827858)
			(xy 378.402401 -219.835983) (xy 378.350467 -219.835983) (xy 378.299172 -219.827858) (xy 378.249779 -219.81181)
			(xy 378.203505 -219.788232) (xy 378.161489 -219.757706) (xy 378.124766 -219.720983) (xy 378.09424 -219.678967)
			(xy 378.070662 -219.632693) (xy 378.054614 -219.5833) (xy 378.046489 -219.532005) (xy 377.766579 -219.532005)
			(xy 377.758454 -219.5833) (xy 377.742406 -219.632693) (xy 377.718828 -219.678967) (xy 377.688302 -219.720983)
			(xy 377.651579 -219.757706) (xy 377.609563 -219.788232) (xy 377.563289 -219.81181) (xy 377.513896 -219.827858)
			(xy 377.462601 -219.835983) (xy 377.410667 -219.835983) (xy 377.359372 -219.827858) (xy 377.309979 -219.81181)
			(xy 377.263705 -219.788232) (xy 377.221689 -219.757706) (xy 377.184966 -219.720983) (xy 377.15444 -219.678967)
			(xy 377.130862 -219.632693) (xy 377.114814 -219.5833) (xy 377.106689 -219.532005) (xy 376.826779 -219.532005)
			(xy 376.818654 -219.5833) (xy 376.802606 -219.632693) (xy 376.779028 -219.678967) (xy 376.748502 -219.720983)
			(xy 376.711779 -219.757706) (xy 376.669763 -219.788232) (xy 376.623489 -219.81181) (xy 376.574096 -219.827858)
			(xy 376.522801 -219.835983) (xy 376.470867 -219.835983) (xy 376.419572 -219.827858) (xy 376.370179 -219.81181)
			(xy 376.323905 -219.788232) (xy 376.281889 -219.757706) (xy 376.245166 -219.720983) (xy 376.21464 -219.678967)
			(xy 376.191062 -219.632693) (xy 376.175014 -219.5833) (xy 376.166889 -219.532005) (xy 375.886979 -219.532005)
			(xy 375.878854 -219.5833) (xy 375.862806 -219.632693) (xy 375.839228 -219.678967) (xy 375.808702 -219.720983)
			(xy 375.771979 -219.757706) (xy 375.729963 -219.788232) (xy 375.683689 -219.81181) (xy 375.634296 -219.827858)
			(xy 375.583001 -219.835983) (xy 375.531067 -219.835983) (xy 375.479772 -219.827858) (xy 375.430379 -219.81181)
			(xy 375.384105 -219.788232) (xy 375.342089 -219.757706) (xy 375.305366 -219.720983) (xy 375.27484 -219.678967)
			(xy 375.251262 -219.632693) (xy 375.235214 -219.5833) (xy 375.227089 -219.532005) (xy 374.947179 -219.532005)
			(xy 374.939054 -219.5833) (xy 374.923006 -219.632693) (xy 374.899428 -219.678967) (xy 374.868902 -219.720983)
			(xy 374.832179 -219.757706) (xy 374.790163 -219.788232) (xy 374.743889 -219.81181) (xy 374.694496 -219.827858)
			(xy 374.643201 -219.835983) (xy 374.591267 -219.835983) (xy 374.539972 -219.827858) (xy 374.490579 -219.81181)
			(xy 374.444305 -219.788232) (xy 374.402289 -219.757706) (xy 374.365566 -219.720983) (xy 374.33504 -219.678967)
			(xy 374.311462 -219.632693) (xy 374.295414 -219.5833) (xy 374.287289 -219.532005) (xy 374.007376 -219.532005)
			(xy 373.999247 -219.583297) (xy 373.983196 -219.632686) (xy 373.959616 -219.678957) (xy 373.92909 -219.720971)
			(xy 373.892368 -219.757693) (xy 373.850354 -219.788218) (xy 373.804083 -219.811797) (xy 373.754693 -219.827848)
			(xy 373.7034 -219.835976) (xy 373.677434 -219.836492) (xy 373.649382 -219.8359) (xy 373.594083 -219.826424)
			(xy 373.541181 -219.807739) (xy 373.516398 -219.794582) (xy 373.503494 -219.787973) (xy 373.475238 -219.781538)
			(xy 373.446313 -219.783293) (xy 373.419043 -219.793095) (xy 373.39562 -219.810158) (xy 373.377928 -219.833109)
			(xy 373.372126 -219.846398) (xy 373.311166 -220.002608) (xy 373.353076 -220.023182) (xy 373.376486 -220.035237)
			(xy 373.419482 -220.06563) (xy 373.457114 -220.102455) (xy 373.488432 -220.144782) (xy 373.512644 -220.191538)
			(xy 373.529136 -220.241542) (xy 373.537491 -220.293528) (xy 373.537988 -220.319854) (xy 373.816626 -220.319854)
			(xy 373.817135 -220.293887) (xy 373.82526 -220.242592) (xy 373.841308 -220.193199) (xy 373.864886 -220.146925)
			(xy 373.895412 -220.104909) (xy 373.932135 -220.068186) (xy 373.974151 -220.03766) (xy 374.020425 -220.014082)
			(xy 374.069818 -219.998034) (xy 374.121113 -219.989909) (xy 374.173047 -219.989909) (xy 374.224342 -219.998034)
			(xy 374.273735 -220.014082) (xy 374.320009 -220.03766) (xy 374.362025 -220.068186) (xy 374.398748 -220.104909)
			(xy 374.429274 -220.146925) (xy 374.452852 -220.193199) (xy 374.4689 -220.242592) (xy 374.477025 -220.293887)
			(xy 374.477534 -220.319854) (xy 374.477038 -220.345821) (xy 374.757189 -220.345821) (xy 374.757189 -220.293887)
			(xy 374.765314 -220.242592) (xy 374.781362 -220.193199) (xy 374.80494 -220.146925) (xy 374.835466 -220.104909)
			(xy 374.872189 -220.068186) (xy 374.914205 -220.03766) (xy 374.960479 -220.014082) (xy 375.009872 -219.998034)
			(xy 375.061167 -219.989909) (xy 375.113101 -219.989909) (xy 375.164396 -219.998034) (xy 375.213789 -220.014082)
			(xy 375.260063 -220.03766) (xy 375.302079 -220.068186) (xy 375.338802 -220.104909) (xy 375.369328 -220.146925)
			(xy 375.392906 -220.193199) (xy 375.408954 -220.242592) (xy 375.417079 -220.293887) (xy 375.417588 -220.319854)
			(xy 375.696226 -220.319854) (xy 375.696735 -220.293887) (xy 375.70486 -220.242592) (xy 375.720908 -220.193199)
			(xy 375.744486 -220.146925) (xy 375.775012 -220.104909) (xy 375.811735 -220.068186) (xy 375.853751 -220.03766)
			(xy 375.900025 -220.014082) (xy 375.949418 -219.998034) (xy 376.000713 -219.989909) (xy 376.052647 -219.989909)
			(xy 376.103942 -219.998034) (xy 376.153335 -220.014082) (xy 376.199609 -220.03766) (xy 376.241625 -220.068186)
			(xy 376.278348 -220.104909) (xy 376.308874 -220.146925) (xy 376.332452 -220.193199) (xy 376.3485 -220.242592)
			(xy 376.356625 -220.293887) (xy 376.357134 -220.319854) (xy 376.356638 -220.345821) (xy 376.636789 -220.345821)
			(xy 376.636789 -220.293887) (xy 376.644914 -220.242592) (xy 376.660962 -220.193199) (xy 376.68454 -220.146925)
			(xy 376.715066 -220.104909) (xy 376.751789 -220.068186) (xy 376.793805 -220.03766) (xy 376.840079 -220.014082)
			(xy 376.889472 -219.998034) (xy 376.940767 -219.989909) (xy 376.992701 -219.989909) (xy 377.043996 -219.998034)
			(xy 377.093389 -220.014082) (xy 377.139663 -220.03766) (xy 377.181679 -220.068186) (xy 377.218402 -220.104909)
			(xy 377.248928 -220.146925) (xy 377.272506 -220.193199) (xy 377.288554 -220.242592) (xy 377.296679 -220.293887)
			(xy 377.297188 -220.319854) (xy 377.575826 -220.319854) (xy 377.576335 -220.293887) (xy 377.58446 -220.242592)
			(xy 377.600508 -220.193199) (xy 377.624086 -220.146925) (xy 377.654612 -220.104909) (xy 377.691335 -220.068186)
			(xy 377.733351 -220.03766) (xy 377.779625 -220.014082) (xy 377.829018 -219.998034) (xy 377.880313 -219.989909)
			(xy 377.932247 -219.989909) (xy 377.983542 -219.998034) (xy 378.032935 -220.014082) (xy 378.079209 -220.03766)
			(xy 378.121225 -220.068186) (xy 378.157948 -220.104909) (xy 378.188474 -220.146925) (xy 378.212052 -220.193199)
			(xy 378.2281 -220.242592) (xy 378.236225 -220.293887) (xy 378.236734 -220.319854) (xy 378.236238 -220.345821)
			(xy 378.516389 -220.345821) (xy 378.516389 -220.293887) (xy 378.524514 -220.242592) (xy 378.540562 -220.193199)
			(xy 378.56414 -220.146925) (xy 378.594666 -220.104909) (xy 378.631389 -220.068186) (xy 378.673405 -220.03766)
			(xy 378.719679 -220.014082) (xy 378.769072 -219.998034) (xy 378.820367 -219.989909) (xy 378.872301 -219.989909)
			(xy 378.923596 -219.998034) (xy 378.972989 -220.014082) (xy 379.019263 -220.03766) (xy 379.061279 -220.068186)
			(xy 379.098002 -220.104909) (xy 379.128528 -220.146925) (xy 379.152106 -220.193199) (xy 379.168154 -220.242592)
			(xy 379.176279 -220.293887) (xy 379.176788 -220.319854) (xy 379.455426 -220.319854) (xy 379.455935 -220.293887)
			(xy 379.46406 -220.242592) (xy 379.480108 -220.193199) (xy 379.503686 -220.146925) (xy 379.534212 -220.104909)
			(xy 379.570935 -220.068186) (xy 379.612951 -220.03766) (xy 379.659225 -220.014082) (xy 379.708618 -219.998034)
			(xy 379.759913 -219.989909) (xy 379.811847 -219.989909) (xy 379.863142 -219.998034) (xy 379.912535 -220.014082)
			(xy 379.958809 -220.03766) (xy 380.000825 -220.068186) (xy 380.037548 -220.104909) (xy 380.068074 -220.146925)
			(xy 380.091652 -220.193199) (xy 380.1077 -220.242592) (xy 380.115825 -220.293887) (xy 380.116334 -220.319854)
			(xy 380.115838 -220.345821) (xy 380.395989 -220.345821) (xy 380.395989 -220.293887) (xy 380.404114 -220.242592)
			(xy 380.420162 -220.193199) (xy 380.44374 -220.146925) (xy 380.474266 -220.104909) (xy 380.510989 -220.068186)
			(xy 380.553005 -220.03766) (xy 380.599279 -220.014082) (xy 380.648672 -219.998034) (xy 380.699967 -219.989909)
			(xy 380.751901 -219.989909) (xy 380.803196 -219.998034) (xy 380.852589 -220.014082) (xy 380.898863 -220.03766)
			(xy 380.940879 -220.068186) (xy 380.977602 -220.104909) (xy 381.008128 -220.146925) (xy 381.031706 -220.193199)
			(xy 381.047754 -220.242592) (xy 381.055879 -220.293887) (xy 381.056388 -220.319854) (xy 381.055879 -220.345821)
			(xy 381.047754 -220.397116) (xy 381.031706 -220.446509) (xy 381.008128 -220.492783) (xy 380.977602 -220.534799)
			(xy 380.940879 -220.571522) (xy 380.898863 -220.602048) (xy 380.852589 -220.625626) (xy 380.803196 -220.641674)
			(xy 380.751901 -220.649799) (xy 380.699967 -220.649799) (xy 380.648672 -220.641674) (xy 380.599279 -220.625626)
			(xy 380.553005 -220.602048) (xy 380.510989 -220.571522) (xy 380.474266 -220.534799) (xy 380.44374 -220.492783)
			(xy 380.420162 -220.446509) (xy 380.404114 -220.397116) (xy 380.395989 -220.345821) (xy 380.115838 -220.345821)
			(xy 380.115801 -220.347764) (xy 380.106472 -220.402797) (xy 380.097792 -220.429328) (xy 380.089918 -220.451172)
			(xy 380.294134 -220.80474) (xy 380.316994 -220.809058) (xy 380.341907 -220.814267) (xy 380.38989 -220.831224)
			(xy 380.434708 -220.855335) (xy 380.475302 -220.886029) (xy 380.510712 -220.922582) (xy 380.540102 -220.96413)
			(xy 380.562778 -221.009691) (xy 380.578203 -221.058189) (xy 380.586014 -221.108478) (xy 380.586488 -221.133924)
			(xy 380.585979 -221.159891) (xy 380.577854 -221.211186) (xy 380.561806 -221.260579) (xy 380.538228 -221.306853)
			(xy 380.507702 -221.348869) (xy 380.470979 -221.385592) (xy 380.428963 -221.416118) (xy 380.382689 -221.439696)
			(xy 380.333296 -221.455744) (xy 380.282001 -221.463869) (xy 380.230067 -221.463869) (xy 380.178772 -221.455744)
			(xy 380.129379 -221.439696) (xy 380.083105 -221.416118) (xy 380.041089 -221.385592) (xy 380.004366 -221.348869)
			(xy 379.97384 -221.306853) (xy 379.950262 -221.260579) (xy 379.934214 -221.211186) (xy 379.926089 -221.159891)
			(xy 379.92558 -221.133924) (xy 379.92614 -221.105938) (xy 379.935585 -221.050771) (xy 379.944376 -221.024196)
			(xy 379.951996 -221.002098) (xy 379.748288 -220.649038) (xy 379.725174 -220.64472) (xy 379.700233 -220.639583)
			(xy 379.65221 -220.622649) (xy 379.607352 -220.598551) (xy 379.56672 -220.567859) (xy 379.531275 -220.5313)
			(xy 379.501855 -220.489738) (xy 379.479156 -220.444156) (xy 379.463716 -220.395632) (xy 379.4559 -220.345314)
			(xy 379.455426 -220.319854) (xy 379.176788 -220.319854) (xy 379.176279 -220.345821) (xy 379.168154 -220.397116)
			(xy 379.152106 -220.446509) (xy 379.128528 -220.492783) (xy 379.098002 -220.534799) (xy 379.061279 -220.571522)
			(xy 379.019263 -220.602048) (xy 378.972989 -220.625626) (xy 378.923596 -220.641674) (xy 378.872301 -220.649799)
			(xy 378.820367 -220.649799) (xy 378.769072 -220.641674) (xy 378.719679 -220.625626) (xy 378.673405 -220.602048)
			(xy 378.631389 -220.571522) (xy 378.594666 -220.534799) (xy 378.56414 -220.492783) (xy 378.540562 -220.446509)
			(xy 378.524514 -220.397116) (xy 378.516389 -220.345821) (xy 378.236238 -220.345821) (xy 378.236201 -220.347764)
			(xy 378.226872 -220.402797) (xy 378.218192 -220.429328) (xy 378.210318 -220.451172) (xy 378.414534 -220.80474)
			(xy 378.437394 -220.809058) (xy 378.462307 -220.814267) (xy 378.51029 -220.831224) (xy 378.555108 -220.855335)
			(xy 378.595702 -220.886029) (xy 378.631112 -220.922582) (xy 378.660502 -220.96413) (xy 378.683178 -221.009691)
			(xy 378.698603 -221.058189) (xy 378.706414 -221.108478) (xy 378.706888 -221.133924) (xy 378.706379 -221.159891)
			(xy 378.698254 -221.211186) (xy 378.682206 -221.260579) (xy 378.658628 -221.306853) (xy 378.628102 -221.348869)
			(xy 378.591379 -221.385592) (xy 378.549363 -221.416118) (xy 378.503089 -221.439696) (xy 378.453696 -221.455744)
			(xy 378.402401 -221.463869) (xy 378.350467 -221.463869) (xy 378.299172 -221.455744) (xy 378.249779 -221.439696)
			(xy 378.203505 -221.416118) (xy 378.161489 -221.385592) (xy 378.124766 -221.348869) (xy 378.09424 -221.306853)
			(xy 378.070662 -221.260579) (xy 378.054614 -221.211186) (xy 378.046489 -221.159891) (xy 378.04598 -221.133924)
			(xy 378.04654 -221.105938) (xy 378.055985 -221.050771) (xy 378.064776 -221.024196) (xy 378.072396 -221.002098)
			(xy 377.868688 -220.649038) (xy 377.845574 -220.64472) (xy 377.820633 -220.639583) (xy 377.77261 -220.622649)
			(xy 377.727752 -220.598551) (xy 377.68712 -220.567859) (xy 377.651675 -220.5313) (xy 377.622255 -220.489738)
			(xy 377.599556 -220.444156) (xy 377.584116 -220.395632) (xy 377.5763 -220.345314) (xy 377.575826 -220.319854)
			(xy 377.297188 -220.319854) (xy 377.296679 -220.345821) (xy 377.288554 -220.397116) (xy 377.272506 -220.446509)
			(xy 377.248928 -220.492783) (xy 377.218402 -220.534799) (xy 377.181679 -220.571522) (xy 377.139663 -220.602048)
			(xy 377.093389 -220.625626) (xy 377.043996 -220.641674) (xy 376.992701 -220.649799) (xy 376.940767 -220.649799)
			(xy 376.889472 -220.641674) (xy 376.840079 -220.625626) (xy 376.793805 -220.602048) (xy 376.751789 -220.571522)
			(xy 376.715066 -220.534799) (xy 376.68454 -220.492783) (xy 376.660962 -220.446509) (xy 376.644914 -220.397116)
			(xy 376.636789 -220.345821) (xy 376.356638 -220.345821) (xy 376.356601 -220.347764) (xy 376.347272 -220.402797)
			(xy 376.338592 -220.429328) (xy 376.330718 -220.451172) (xy 376.534934 -220.80474) (xy 376.557794 -220.809058)
			(xy 376.582707 -220.814267) (xy 376.63069 -220.831224) (xy 376.675508 -220.855335) (xy 376.716102 -220.886029)
			(xy 376.751512 -220.922582) (xy 376.780902 -220.96413) (xy 376.803578 -221.009691) (xy 376.819003 -221.058189)
			(xy 376.826814 -221.108478) (xy 376.827288 -221.133924) (xy 376.826779 -221.159891) (xy 376.818654 -221.211186)
			(xy 376.802606 -221.260579) (xy 376.779028 -221.306853) (xy 376.748502 -221.348869) (xy 376.711779 -221.385592)
			(xy 376.669763 -221.416118) (xy 376.623489 -221.439696) (xy 376.574096 -221.455744) (xy 376.522801 -221.463869)
			(xy 376.470867 -221.463869) (xy 376.419572 -221.455744) (xy 376.370179 -221.439696) (xy 376.323905 -221.416118)
			(xy 376.281889 -221.385592) (xy 376.245166 -221.348869) (xy 376.21464 -221.306853) (xy 376.191062 -221.260579)
			(xy 376.175014 -221.211186) (xy 376.166889 -221.159891) (xy 376.16638 -221.133924) (xy 376.16694 -221.105938)
			(xy 376.176385 -221.050771) (xy 376.185176 -221.024196) (xy 376.192796 -221.002098) (xy 375.989088 -220.649038)
			(xy 375.965974 -220.64472) (xy 375.941033 -220.639583) (xy 375.89301 -220.622649) (xy 375.848152 -220.598551)
			(xy 375.80752 -220.567859) (xy 375.772075 -220.5313) (xy 375.742655 -220.489738) (xy 375.719956 -220.444156)
			(xy 375.704516 -220.395632) (xy 375.6967 -220.345314) (xy 375.696226 -220.319854) (xy 375.417588 -220.319854)
			(xy 375.417079 -220.345821) (xy 375.408954 -220.397116) (xy 375.392906 -220.446509) (xy 375.369328 -220.492783)
			(xy 375.338802 -220.534799) (xy 375.302079 -220.571522) (xy 375.260063 -220.602048) (xy 375.213789 -220.625626)
			(xy 375.164396 -220.641674) (xy 375.113101 -220.649799) (xy 375.061167 -220.649799) (xy 375.009872 -220.641674)
			(xy 374.960479 -220.625626) (xy 374.914205 -220.602048) (xy 374.872189 -220.571522) (xy 374.835466 -220.534799)
			(xy 374.80494 -220.492783) (xy 374.781362 -220.446509) (xy 374.765314 -220.397116) (xy 374.757189 -220.345821)
			(xy 374.477038 -220.345821) (xy 374.477001 -220.347764) (xy 374.467672 -220.402797) (xy 374.458992 -220.429328)
			(xy 374.451118 -220.451172) (xy 374.655334 -220.80474) (xy 374.678194 -220.809058) (xy 374.703107 -220.814267)
			(xy 374.75109 -220.831224) (xy 374.795908 -220.855335) (xy 374.836502 -220.886029) (xy 374.871912 -220.922582)
			(xy 374.901302 -220.96413) (xy 374.923978 -221.009691) (xy 374.939403 -221.058189) (xy 374.947214 -221.108478)
			(xy 374.947688 -221.133924) (xy 374.947179 -221.159891) (xy 374.939054 -221.211186) (xy 374.923006 -221.260579)
			(xy 374.899428 -221.306853) (xy 374.868902 -221.348869) (xy 374.832179 -221.385592) (xy 374.790163 -221.416118)
			(xy 374.743889 -221.439696) (xy 374.694496 -221.455744) (xy 374.643201 -221.463869) (xy 374.591267 -221.463869)
			(xy 374.539972 -221.455744) (xy 374.490579 -221.439696) (xy 374.444305 -221.416118) (xy 374.402289 -221.385592)
			(xy 374.365566 -221.348869) (xy 374.33504 -221.306853) (xy 374.311462 -221.260579) (xy 374.295414 -221.211186)
			(xy 374.287289 -221.159891) (xy 374.28678 -221.133924) (xy 374.28734 -221.105938) (xy 374.296785 -221.050771)
			(xy 374.305576 -221.024196) (xy 374.313196 -221.002098) (xy 374.109488 -220.649038) (xy 374.086374 -220.64472)
			(xy 374.061433 -220.639583) (xy 374.01341 -220.622649) (xy 373.968552 -220.598551) (xy 373.92792 -220.567859)
			(xy 373.892475 -220.5313) (xy 373.863055 -220.489738) (xy 373.840356 -220.444156) (xy 373.824916 -220.395632)
			(xy 373.8171 -220.345314) (xy 373.816626 -220.319854) (xy 373.537988 -220.319854) (xy 373.537509 -220.345827)
			(xy 373.52939 -220.397133) (xy 373.513344 -220.446538) (xy 373.489768 -220.492825) (xy 373.45924 -220.534853)
			(xy 373.422514 -220.571588) (xy 373.380493 -220.602126) (xy 373.334212 -220.625714) (xy 373.284811 -220.641771)
			(xy 373.233507 -220.649902) (xy 373.207534 -220.650308) (xy 373.183761 -220.649855) (xy 373.136716 -220.642963)
			(xy 373.113808 -220.636592) (xy 373.06885 -220.623384) (xy 372.964202 -220.891354) (xy 372.98503 -220.914722)
			(xy 373.000598 -220.932956) (xy 373.026853 -220.973072) (xy 373.047038 -221.01656) (xy 373.060728 -221.062508)
			(xy 373.067636 -221.109952) (xy 373.068088 -221.133924) (xy 373.067548 -221.160931) (xy 373.058758 -221.214226)
			(xy 373.041416 -221.265381) (xy 373.015983 -221.313034) (xy 372.983138 -221.355915) (xy 372.943755 -221.392882)
			(xy 372.898884 -221.422951) (xy 372.87454 -221.43466) (xy 372.861478 -221.479648) (xy 372.828811 -221.567454)
			(xy 372.78891 -221.652218) (xy 372.742055 -221.733346) (xy 372.688575 -221.810267) (xy 372.628845 -221.882443)
			(xy 372.59641 -221.916244) (xy 372.597934 -221.94774) (xy 372.876826 -221.94774) (xy 372.877275 -221.922288)
			(xy 372.885061 -221.871984) (xy 372.900471 -221.823469) (xy 372.92314 -221.777892) (xy 372.952531 -221.73633)
			(xy 372.987949 -221.699769) (xy 373.028555 -221.669073) (xy 373.07339 -221.644968) (xy 373.121391 -221.628025)
			(xy 373.14632 -221.622874) (xy 373.16918 -221.618556) (xy 373.373142 -221.264988) (xy 373.365522 -221.243144)
			(xy 373.356888 -221.216667) (xy 373.347561 -221.161767) (xy 373.34698 -221.133924) (xy 373.347489 -221.107957)
			(xy 373.355614 -221.056662) (xy 373.371662 -221.007269) (xy 373.39524 -220.960995) (xy 373.425766 -220.918979)
			(xy 373.462489 -220.882256) (xy 373.504505 -220.85173) (xy 373.550779 -220.828152) (xy 373.600172 -220.812104)
			(xy 373.651467 -220.803979) (xy 373.703401 -220.803979) (xy 373.754696 -220.812104) (xy 373.804089 -220.828152)
			(xy 373.850363 -220.85173) (xy 373.892379 -220.882256) (xy 373.929102 -220.918979) (xy 373.959628 -220.960995)
			(xy 373.983206 -221.007269) (xy 373.999254 -221.056662) (xy 374.007379 -221.107957) (xy 374.007888 -221.133924)
			(xy 374.0074 -221.159397) (xy 373.999578 -221.209738) (xy 373.984123 -221.258282) (xy 373.961402 -221.30388)
			(xy 373.931952 -221.34545) (xy 373.896471 -221.382009) (xy 373.8558 -221.412689) (xy 373.810903 -221.436765)
			(xy 373.762842 -221.453665) (xy 373.737886 -221.45879) (xy 373.714772 -221.463108) (xy 373.511318 -221.815914)
			(xy 373.518938 -221.838012) (xy 373.527677 -221.8646) (xy 373.537124 -221.919759) (xy 373.537734 -221.94774)
			(xy 373.537225 -221.973707) (xy 373.817135 -221.973707) (xy 373.817135 -221.921773) (xy 373.82526 -221.870478)
			(xy 373.841308 -221.821085) (xy 373.864886 -221.774811) (xy 373.895412 -221.732795) (xy 373.932135 -221.696072)
			(xy 373.974151 -221.665546) (xy 374.020425 -221.641968) (xy 374.069818 -221.62592) (xy 374.121113 -221.617795)
			(xy 374.173047 -221.617795) (xy 374.224342 -221.62592) (xy 374.273735 -221.641968) (xy 374.320009 -221.665546)
			(xy 374.362025 -221.696072) (xy 374.398748 -221.732795) (xy 374.429274 -221.774811) (xy 374.452852 -221.821085)
			(xy 374.4689 -221.870478) (xy 374.477025 -221.921773) (xy 374.477534 -221.94774) (xy 374.756426 -221.94774)
			(xy 374.756875 -221.922288) (xy 374.764661 -221.871984) (xy 374.780071 -221.823469) (xy 374.80274 -221.777892)
			(xy 374.832131 -221.73633) (xy 374.867549 -221.699769) (xy 374.908155 -221.669073) (xy 374.95299 -221.644968)
			(xy 375.000991 -221.628025) (xy 375.02592 -221.622874) (xy 375.04878 -221.618556) (xy 375.252742 -221.264988)
			(xy 375.245122 -221.243144) (xy 375.236488 -221.216667) (xy 375.227161 -221.161767) (xy 375.22658 -221.133924)
			(xy 375.227089 -221.107957) (xy 375.235214 -221.056662) (xy 375.251262 -221.007269) (xy 375.27484 -220.960995)
			(xy 375.305366 -220.918979) (xy 375.342089 -220.882256) (xy 375.384105 -220.85173) (xy 375.430379 -220.828152)
			(xy 375.479772 -220.812104) (xy 375.531067 -220.803979) (xy 375.583001 -220.803979) (xy 375.634296 -220.812104)
			(xy 375.683689 -220.828152) (xy 375.729963 -220.85173) (xy 375.771979 -220.882256) (xy 375.808702 -220.918979)
			(xy 375.839228 -220.960995) (xy 375.862806 -221.007269) (xy 375.878854 -221.056662) (xy 375.886979 -221.107957)
			(xy 375.887488 -221.133924) (xy 375.887 -221.159397) (xy 375.879178 -221.209738) (xy 375.863723 -221.258282)
			(xy 375.841002 -221.30388) (xy 375.811552 -221.34545) (xy 375.776071 -221.382009) (xy 375.7354 -221.412689)
			(xy 375.690503 -221.436765) (xy 375.642442 -221.453665) (xy 375.617486 -221.45879) (xy 375.594372 -221.463108)
			(xy 375.390918 -221.815914) (xy 375.398538 -221.838012) (xy 375.407277 -221.8646) (xy 375.416724 -221.919759)
			(xy 375.417334 -221.94774) (xy 375.416825 -221.973707) (xy 375.696735 -221.973707) (xy 375.696735 -221.921773)
			(xy 375.70486 -221.870478) (xy 375.720908 -221.821085) (xy 375.744486 -221.774811) (xy 375.775012 -221.732795)
			(xy 375.811735 -221.696072) (xy 375.853751 -221.665546) (xy 375.900025 -221.641968) (xy 375.949418 -221.62592)
			(xy 376.000713 -221.617795) (xy 376.052647 -221.617795) (xy 376.103942 -221.62592) (xy 376.153335 -221.641968)
			(xy 376.199609 -221.665546) (xy 376.241625 -221.696072) (xy 376.278348 -221.732795) (xy 376.308874 -221.774811)
			(xy 376.332452 -221.821085) (xy 376.3485 -221.870478) (xy 376.356625 -221.921773) (xy 376.357134 -221.94774)
			(xy 376.636026 -221.94774) (xy 376.636475 -221.922288) (xy 376.644261 -221.871984) (xy 376.659671 -221.823469)
			(xy 376.68234 -221.777892) (xy 376.711731 -221.73633) (xy 376.747149 -221.699769) (xy 376.787755 -221.669073)
			(xy 376.83259 -221.644968) (xy 376.880591 -221.628025) (xy 376.90552 -221.622874) (xy 376.92838 -221.618556)
			(xy 377.132342 -221.264988) (xy 377.124722 -221.243144) (xy 377.116088 -221.216667) (xy 377.106761 -221.161767)
			(xy 377.10618 -221.133924) (xy 377.106689 -221.107957) (xy 377.114814 -221.056662) (xy 377.130862 -221.007269)
			(xy 377.15444 -220.960995) (xy 377.184966 -220.918979) (xy 377.221689 -220.882256) (xy 377.263705 -220.85173)
			(xy 377.309979 -220.828152) (xy 377.359372 -220.812104) (xy 377.410667 -220.803979) (xy 377.462601 -220.803979)
			(xy 377.513896 -220.812104) (xy 377.563289 -220.828152) (xy 377.609563 -220.85173) (xy 377.651579 -220.882256)
			(xy 377.688302 -220.918979) (xy 377.718828 -220.960995) (xy 377.742406 -221.007269) (xy 377.758454 -221.056662)
			(xy 377.766579 -221.107957) (xy 377.767088 -221.133924) (xy 377.7666 -221.159397) (xy 377.758778 -221.209738)
			(xy 377.743323 -221.258282) (xy 377.720602 -221.30388) (xy 377.691152 -221.34545) (xy 377.655671 -221.382009)
			(xy 377.615 -221.412689) (xy 377.570103 -221.436765) (xy 377.522042 -221.453665) (xy 377.497086 -221.45879)
			(xy 377.473972 -221.463108) (xy 377.270518 -221.815914) (xy 377.278138 -221.838012) (xy 377.286877 -221.8646)
			(xy 377.296324 -221.919759) (xy 377.296934 -221.94774) (xy 377.296425 -221.973707) (xy 377.576335 -221.973707)
			(xy 377.576335 -221.921773) (xy 377.58446 -221.870478) (xy 377.600508 -221.821085) (xy 377.624086 -221.774811)
			(xy 377.654612 -221.732795) (xy 377.691335 -221.696072) (xy 377.733351 -221.665546) (xy 377.779625 -221.641968)
			(xy 377.829018 -221.62592) (xy 377.880313 -221.617795) (xy 377.932247 -221.617795) (xy 377.983542 -221.62592)
			(xy 378.032935 -221.641968) (xy 378.079209 -221.665546) (xy 378.121225 -221.696072) (xy 378.157948 -221.732795)
			(xy 378.188474 -221.774811) (xy 378.212052 -221.821085) (xy 378.2281 -221.870478) (xy 378.236225 -221.921773)
			(xy 378.236734 -221.94774) (xy 378.515626 -221.94774) (xy 378.516075 -221.922288) (xy 378.523861 -221.871984)
			(xy 378.539271 -221.823469) (xy 378.56194 -221.777892) (xy 378.591331 -221.73633) (xy 378.626749 -221.699769)
			(xy 378.667355 -221.669073) (xy 378.71219 -221.644968) (xy 378.760191 -221.628025) (xy 378.78512 -221.622874)
			(xy 378.80798 -221.618556) (xy 379.011942 -221.264988) (xy 379.004322 -221.243144) (xy 378.995688 -221.216667)
			(xy 378.986361 -221.161767) (xy 378.98578 -221.133924) (xy 378.986289 -221.107957) (xy 378.994414 -221.056662)
			(xy 379.010462 -221.007269) (xy 379.03404 -220.960995) (xy 379.064566 -220.918979) (xy 379.101289 -220.882256)
			(xy 379.143305 -220.85173) (xy 379.189579 -220.828152) (xy 379.238972 -220.812104) (xy 379.290267 -220.803979)
			(xy 379.342201 -220.803979) (xy 379.393496 -220.812104) (xy 379.442889 -220.828152) (xy 379.489163 -220.85173)
			(xy 379.531179 -220.882256) (xy 379.567902 -220.918979) (xy 379.598428 -220.960995) (xy 379.622006 -221.007269)
			(xy 379.638054 -221.056662) (xy 379.646179 -221.107957) (xy 379.646688 -221.133924) (xy 379.6462 -221.159397)
			(xy 379.638378 -221.209738) (xy 379.622923 -221.258282) (xy 379.600202 -221.30388) (xy 379.570752 -221.34545)
			(xy 379.535271 -221.382009) (xy 379.4946 -221.412689) (xy 379.449703 -221.436765) (xy 379.401642 -221.453665)
			(xy 379.376686 -221.45879) (xy 379.353572 -221.463108) (xy 379.150118 -221.815914) (xy 379.157738 -221.838012)
			(xy 379.166477 -221.8646) (xy 379.175924 -221.919759) (xy 379.176534 -221.94774) (xy 379.176025 -221.973707)
			(xy 379.455935 -221.973707) (xy 379.455935 -221.921773) (xy 379.46406 -221.870478) (xy 379.480108 -221.821085)
			(xy 379.503686 -221.774811) (xy 379.534212 -221.732795) (xy 379.570935 -221.696072) (xy 379.612951 -221.665546)
			(xy 379.659225 -221.641968) (xy 379.708618 -221.62592) (xy 379.759913 -221.617795) (xy 379.811847 -221.617795)
			(xy 379.863142 -221.62592) (xy 379.912535 -221.641968) (xy 379.958809 -221.665546) (xy 380.000825 -221.696072)
			(xy 380.037548 -221.732795) (xy 380.068074 -221.774811) (xy 380.091652 -221.821085) (xy 380.1077 -221.870478)
			(xy 380.115825 -221.921773) (xy 380.116334 -221.94774) (xy 380.395226 -221.94774) (xy 380.395675 -221.922288)
			(xy 380.403461 -221.871984) (xy 380.418871 -221.823469) (xy 380.44154 -221.777892) (xy 380.470931 -221.73633)
			(xy 380.506349 -221.699769) (xy 380.546955 -221.669073) (xy 380.59179 -221.644968) (xy 380.639791 -221.628025)
			(xy 380.66472 -221.622874) (xy 380.687834 -221.618556) (xy 380.891542 -221.264988) (xy 380.883922 -221.24289)
			(xy 380.875291 -221.216478) (xy 380.865972 -221.161704) (xy 380.86538 -221.133924) (xy 380.865889 -221.107957)
			(xy 380.874014 -221.056662) (xy 380.890062 -221.007269) (xy 380.91364 -220.960995) (xy 380.944166 -220.918979)
			(xy 380.980889 -220.882256) (xy 381.022905 -220.85173) (xy 381.069179 -220.828152) (xy 381.118572 -220.812104)
			(xy 381.169867 -220.803979) (xy 381.221801 -220.803979) (xy 381.273096 -220.812104) (xy 381.322489 -220.828152)
			(xy 381.368763 -220.85173) (xy 381.410779 -220.882256) (xy 381.447502 -220.918979) (xy 381.478028 -220.960995)
			(xy 381.501606 -221.007269) (xy 381.517654 -221.056662) (xy 381.525779 -221.107957) (xy 381.526288 -221.133924)
			(xy 381.5258 -221.159397) (xy 381.517978 -221.209738) (xy 381.502523 -221.258282) (xy 381.479802 -221.30388)
			(xy 381.450352 -221.34545) (xy 381.414871 -221.382009) (xy 381.3742 -221.412689) (xy 381.329303 -221.436765)
			(xy 381.281242 -221.453665) (xy 381.256286 -221.45879) (xy 381.233172 -221.463108) (xy 381.029718 -221.815914)
			(xy 381.037338 -221.838012) (xy 381.046077 -221.8646) (xy 381.055524 -221.919759) (xy 381.056134 -221.94774)
			(xy 381.055625 -221.973707) (xy 381.335789 -221.973707) (xy 381.335789 -221.921773) (xy 381.343914 -221.870478)
			(xy 381.359962 -221.821085) (xy 381.38354 -221.774811) (xy 381.414066 -221.732795) (xy 381.450789 -221.696072)
			(xy 381.492805 -221.665546) (xy 381.539079 -221.641968) (xy 381.588472 -221.62592) (xy 381.639767 -221.617795)
			(xy 381.691701 -221.617795) (xy 381.742996 -221.62592) (xy 381.792389 -221.641968) (xy 381.838663 -221.665546)
			(xy 381.880679 -221.696072) (xy 381.917402 -221.732795) (xy 381.947928 -221.774811) (xy 381.971506 -221.821085)
			(xy 381.987554 -221.870478) (xy 381.995679 -221.921773) (xy 381.996188 -221.94774) (xy 381.995679 -221.973707)
			(xy 381.987554 -222.025002) (xy 381.971506 -222.074395) (xy 381.947928 -222.120669) (xy 381.917402 -222.162685)
			(xy 381.880679 -222.199408) (xy 381.838663 -222.229934) (xy 381.792389 -222.253512) (xy 381.742996 -222.26956)
			(xy 381.691701 -222.277685) (xy 381.639767 -222.277685) (xy 381.588472 -222.26956) (xy 381.539079 -222.253512)
			(xy 381.492805 -222.229934) (xy 381.450789 -222.199408) (xy 381.414066 -222.162685) (xy 381.38354 -222.120669)
			(xy 381.359962 -222.074395) (xy 381.343914 -222.025002) (xy 381.335789 -221.973707) (xy 381.055625 -221.973707)
			(xy 381.0475 -222.025002) (xy 381.031452 -222.074395) (xy 381.007874 -222.120669) (xy 380.977348 -222.162685)
			(xy 380.940625 -222.199408) (xy 380.898609 -222.229934) (xy 380.852335 -222.253512) (xy 380.802942 -222.26956)
			(xy 380.751647 -222.277685) (xy 380.699713 -222.277685) (xy 380.648418 -222.26956) (xy 380.599025 -222.253512)
			(xy 380.552751 -222.229934) (xy 380.510735 -222.199408) (xy 380.474012 -222.162685) (xy 380.443486 -222.120669)
			(xy 380.419908 -222.074395) (xy 380.40386 -222.025002) (xy 380.395735 -221.973707) (xy 380.395226 -221.94774)
			(xy 380.116334 -221.94774) (xy 380.115825 -221.973707) (xy 380.1077 -222.025002) (xy 380.091652 -222.074395)
			(xy 380.068074 -222.120669) (xy 380.037548 -222.162685) (xy 380.000825 -222.199408) (xy 379.958809 -222.229934)
			(xy 379.912535 -222.253512) (xy 379.863142 -222.26956) (xy 379.811847 -222.277685) (xy 379.759913 -222.277685)
			(xy 379.708618 -222.26956) (xy 379.659225 -222.253512) (xy 379.612951 -222.229934) (xy 379.570935 -222.199408)
			(xy 379.534212 -222.162685) (xy 379.503686 -222.120669) (xy 379.480108 -222.074395) (xy 379.46406 -222.025002)
			(xy 379.455935 -221.973707) (xy 379.176025 -221.973707) (xy 379.1679 -222.025002) (xy 379.151852 -222.074395)
			(xy 379.128274 -222.120669) (xy 379.097748 -222.162685) (xy 379.061025 -222.199408) (xy 379.019009 -222.229934)
			(xy 378.972735 -222.253512) (xy 378.923342 -222.26956) (xy 378.872047 -222.277685) (xy 378.820113 -222.277685)
			(xy 378.768818 -222.26956) (xy 378.719425 -222.253512) (xy 378.673151 -222.229934) (xy 378.631135 -222.199408)
			(xy 378.594412 -222.162685) (xy 378.563886 -222.120669) (xy 378.540308 -222.074395) (xy 378.52426 -222.025002)
			(xy 378.516135 -221.973707) (xy 378.515626 -221.94774) (xy 378.236734 -221.94774) (xy 378.236225 -221.973707)
			(xy 378.2281 -222.025002) (xy 378.212052 -222.074395) (xy 378.188474 -222.120669) (xy 378.157948 -222.162685)
			(xy 378.121225 -222.199408) (xy 378.079209 -222.229934) (xy 378.032935 -222.253512) (xy 377.983542 -222.26956)
			(xy 377.932247 -222.277685) (xy 377.880313 -222.277685) (xy 377.829018 -222.26956) (xy 377.779625 -222.253512)
			(xy 377.733351 -222.229934) (xy 377.691335 -222.199408) (xy 377.654612 -222.162685) (xy 377.624086 -222.120669)
			(xy 377.600508 -222.074395) (xy 377.58446 -222.025002) (xy 377.576335 -221.973707) (xy 377.296425 -221.973707)
			(xy 377.2883 -222.025002) (xy 377.272252 -222.074395) (xy 377.248674 -222.120669) (xy 377.218148 -222.162685)
			(xy 377.181425 -222.199408) (xy 377.139409 -222.229934) (xy 377.093135 -222.253512) (xy 377.043742 -222.26956)
			(xy 376.992447 -222.277685) (xy 376.940513 -222.277685) (xy 376.889218 -222.26956) (xy 376.839825 -222.253512)
			(xy 376.793551 -222.229934) (xy 376.751535 -222.199408) (xy 376.714812 -222.162685) (xy 376.684286 -222.120669)
			(xy 376.660708 -222.074395) (xy 376.64466 -222.025002) (xy 376.636535 -221.973707) (xy 376.636026 -221.94774)
			(xy 376.357134 -221.94774) (xy 376.356625 -221.973707) (xy 376.3485 -222.025002) (xy 376.332452 -222.074395)
			(xy 376.308874 -222.120669) (xy 376.278348 -222.162685) (xy 376.241625 -222.199408) (xy 376.199609 -222.229934)
			(xy 376.153335 -222.253512) (xy 376.103942 -222.26956) (xy 376.052647 -222.277685) (xy 376.000713 -222.277685)
			(xy 375.949418 -222.26956) (xy 375.900025 -222.253512) (xy 375.853751 -222.229934) (xy 375.811735 -222.199408)
			(xy 375.775012 -222.162685) (xy 375.744486 -222.120669) (xy 375.720908 -222.074395) (xy 375.70486 -222.025002)
			(xy 375.696735 -221.973707) (xy 375.416825 -221.973707) (xy 375.4087 -222.025002) (xy 375.392652 -222.074395)
			(xy 375.369074 -222.120669) (xy 375.338548 -222.162685) (xy 375.301825 -222.199408) (xy 375.259809 -222.229934)
			(xy 375.213535 -222.253512) (xy 375.164142 -222.26956) (xy 375.112847 -222.277685) (xy 375.060913 -222.277685)
			(xy 375.009618 -222.26956) (xy 374.960225 -222.253512) (xy 374.913951 -222.229934) (xy 374.871935 -222.199408)
			(xy 374.835212 -222.162685) (xy 374.804686 -222.120669) (xy 374.781108 -222.074395) (xy 374.76506 -222.025002)
			(xy 374.756935 -221.973707) (xy 374.756426 -221.94774) (xy 374.477534 -221.94774) (xy 374.477025 -221.973707)
			(xy 374.4689 -222.025002) (xy 374.452852 -222.074395) (xy 374.429274 -222.120669) (xy 374.398748 -222.162685)
			(xy 374.362025 -222.199408) (xy 374.320009 -222.229934) (xy 374.273735 -222.253512) (xy 374.224342 -222.26956)
			(xy 374.173047 -222.277685) (xy 374.121113 -222.277685) (xy 374.069818 -222.26956) (xy 374.020425 -222.253512)
			(xy 373.974151 -222.229934) (xy 373.932135 -222.199408) (xy 373.895412 -222.162685) (xy 373.864886 -222.120669)
			(xy 373.841308 -222.074395) (xy 373.82526 -222.025002) (xy 373.817135 -221.973707) (xy 373.537225 -221.973707)
			(xy 373.5291 -222.025002) (xy 373.513052 -222.074395) (xy 373.489474 -222.120669) (xy 373.458948 -222.162685)
			(xy 373.422225 -222.199408) (xy 373.380209 -222.229934) (xy 373.333935 -222.253512) (xy 373.284542 -222.26956)
			(xy 373.233247 -222.277685) (xy 373.181313 -222.277685) (xy 373.130018 -222.26956) (xy 373.080625 -222.253512)
			(xy 373.034351 -222.229934) (xy 372.992335 -222.199408) (xy 372.955612 -222.162685) (xy 372.925086 -222.120669)
			(xy 372.901508 -222.074395) (xy 372.88546 -222.025002) (xy 372.877335 -221.973707) (xy 372.876826 -221.94774)
			(xy 372.597934 -221.94774) (xy 372.59743 -221.974366) (xy 372.58889 -222.026928) (xy 372.572022 -222.077437)
			(xy 372.547264 -222.124582) (xy 372.515257 -222.167141) (xy 372.476833 -222.204009) (xy 372.455186 -222.21952)
			(xy 372.442486 -222.22841) (xy 372.313962 -222.557848) (xy 372.128542 -222.743268) (xy 372.128288 -222.764096)
			(xy 372.127656 -222.787523) (xy 372.407689 -222.787523) (xy 372.407689 -222.735589) (xy 372.415814 -222.684294)
			(xy 372.431862 -222.634901) (xy 372.45544 -222.588627) (xy 372.485966 -222.546611) (xy 372.522689 -222.509888)
			(xy 372.564705 -222.479362) (xy 372.610979 -222.455784) (xy 372.660372 -222.439736) (xy 372.711667 -222.431611)
			(xy 372.763601 -222.431611) (xy 372.814896 -222.439736) (xy 372.864289 -222.455784) (xy 372.910563 -222.479362)
			(xy 372.952579 -222.509888) (xy 372.989302 -222.546611) (xy 373.019828 -222.588627) (xy 373.043406 -222.634901)
			(xy 373.059454 -222.684294) (xy 373.067579 -222.735589) (xy 373.068088 -222.761556) (xy 373.067579 -222.787523)
			(xy 373.347489 -222.787523) (xy 373.347489 -222.735589) (xy 373.355614 -222.684294) (xy 373.371662 -222.634901)
			(xy 373.39524 -222.588627) (xy 373.425766 -222.546611) (xy 373.462489 -222.509888) (xy 373.504505 -222.479362)
			(xy 373.550779 -222.455784) (xy 373.600172 -222.439736) (xy 373.651467 -222.431611) (xy 373.703401 -222.431611)
			(xy 373.754696 -222.439736) (xy 373.804089 -222.455784) (xy 373.850363 -222.479362) (xy 373.892379 -222.509888)
			(xy 373.929102 -222.546611) (xy 373.959628 -222.588627) (xy 373.983206 -222.634901) (xy 373.999254 -222.684294)
			(xy 374.007379 -222.735589) (xy 374.007888 -222.761556) (xy 374.007379 -222.787523) (xy 374.287289 -222.787523)
			(xy 374.287289 -222.735589) (xy 374.295414 -222.684294) (xy 374.311462 -222.634901) (xy 374.33504 -222.588627)
			(xy 374.365566 -222.546611) (xy 374.402289 -222.509888) (xy 374.444305 -222.479362) (xy 374.490579 -222.455784)
			(xy 374.539972 -222.439736) (xy 374.591267 -222.431611) (xy 374.643201 -222.431611) (xy 374.694496 -222.439736)
			(xy 374.743889 -222.455784) (xy 374.790163 -222.479362) (xy 374.832179 -222.509888) (xy 374.868902 -222.546611)
			(xy 374.899428 -222.588627) (xy 374.923006 -222.634901) (xy 374.939054 -222.684294) (xy 374.947179 -222.735589)
			(xy 374.947688 -222.761556) (xy 374.947179 -222.787523) (xy 375.227089 -222.787523) (xy 375.227089 -222.735589)
			(xy 375.235214 -222.684294) (xy 375.251262 -222.634901) (xy 375.27484 -222.588627) (xy 375.305366 -222.546611)
			(xy 375.342089 -222.509888) (xy 375.384105 -222.479362) (xy 375.430379 -222.455784) (xy 375.479772 -222.439736)
			(xy 375.531067 -222.431611) (xy 375.583001 -222.431611) (xy 375.634296 -222.439736) (xy 375.683689 -222.455784)
			(xy 375.729963 -222.479362) (xy 375.771979 -222.509888) (xy 375.808702 -222.546611) (xy 375.839228 -222.588627)
			(xy 375.862806 -222.634901) (xy 375.878854 -222.684294) (xy 375.886979 -222.735589) (xy 375.887488 -222.761556)
			(xy 375.886979 -222.787523) (xy 376.166889 -222.787523) (xy 376.166889 -222.735589) (xy 376.175014 -222.684294)
			(xy 376.191062 -222.634901) (xy 376.21464 -222.588627) (xy 376.245166 -222.546611) (xy 376.281889 -222.509888)
			(xy 376.323905 -222.479362) (xy 376.370179 -222.455784) (xy 376.419572 -222.439736) (xy 376.470867 -222.431611)
			(xy 376.522801 -222.431611) (xy 376.574096 -222.439736) (xy 376.623489 -222.455784) (xy 376.669763 -222.479362)
			(xy 376.711779 -222.509888) (xy 376.748502 -222.546611) (xy 376.779028 -222.588627) (xy 376.802606 -222.634901)
			(xy 376.818654 -222.684294) (xy 376.826779 -222.735589) (xy 376.827288 -222.761556) (xy 376.826779 -222.787523)
			(xy 377.106689 -222.787523) (xy 377.106689 -222.735589) (xy 377.114814 -222.684294) (xy 377.130862 -222.634901)
			(xy 377.15444 -222.588627) (xy 377.184966 -222.546611) (xy 377.221689 -222.509888) (xy 377.263705 -222.479362)
			(xy 377.309979 -222.455784) (xy 377.359372 -222.439736) (xy 377.410667 -222.431611) (xy 377.462601 -222.431611)
			(xy 377.513896 -222.439736) (xy 377.563289 -222.455784) (xy 377.609563 -222.479362) (xy 377.651579 -222.509888)
			(xy 377.688302 -222.546611) (xy 377.718828 -222.588627) (xy 377.742406 -222.634901) (xy 377.758454 -222.684294)
			(xy 377.766579 -222.735589) (xy 377.767088 -222.761556) (xy 377.766579 -222.787523) (xy 378.046489 -222.787523)
			(xy 378.046489 -222.735589) (xy 378.054614 -222.684294) (xy 378.070662 -222.634901) (xy 378.09424 -222.588627)
			(xy 378.124766 -222.546611) (xy 378.161489 -222.509888) (xy 378.203505 -222.479362) (xy 378.249779 -222.455784)
			(xy 378.299172 -222.439736) (xy 378.350467 -222.431611) (xy 378.402401 -222.431611) (xy 378.453696 -222.439736)
			(xy 378.503089 -222.455784) (xy 378.549363 -222.479362) (xy 378.591379 -222.509888) (xy 378.628102 -222.546611)
			(xy 378.658628 -222.588627) (xy 378.682206 -222.634901) (xy 378.698254 -222.684294) (xy 378.706379 -222.735589)
			(xy 378.706888 -222.761556) (xy 378.706379 -222.787523) (xy 378.986289 -222.787523) (xy 378.986289 -222.735589)
			(xy 378.994414 -222.684294) (xy 379.010462 -222.634901) (xy 379.03404 -222.588627) (xy 379.064566 -222.546611)
			(xy 379.101289 -222.509888) (xy 379.143305 -222.479362) (xy 379.189579 -222.455784) (xy 379.238972 -222.439736)
			(xy 379.290267 -222.431611) (xy 379.342201 -222.431611) (xy 379.393496 -222.439736) (xy 379.442889 -222.455784)
			(xy 379.489163 -222.479362) (xy 379.531179 -222.509888) (xy 379.567902 -222.546611) (xy 379.598428 -222.588627)
			(xy 379.622006 -222.634901) (xy 379.638054 -222.684294) (xy 379.646179 -222.735589) (xy 379.646688 -222.761556)
			(xy 379.646179 -222.787523) (xy 379.926089 -222.787523) (xy 379.926089 -222.735589) (xy 379.934214 -222.684294)
			(xy 379.950262 -222.634901) (xy 379.97384 -222.588627) (xy 380.004366 -222.546611) (xy 380.041089 -222.509888)
			(xy 380.083105 -222.479362) (xy 380.129379 -222.455784) (xy 380.178772 -222.439736) (xy 380.230067 -222.431611)
			(xy 380.282001 -222.431611) (xy 380.333296 -222.439736) (xy 380.382689 -222.455784) (xy 380.428963 -222.479362)
			(xy 380.470979 -222.509888) (xy 380.507702 -222.546611) (xy 380.538228 -222.588627) (xy 380.561806 -222.634901)
			(xy 380.577854 -222.684294) (xy 380.585979 -222.735589) (xy 380.586488 -222.761556) (xy 380.585979 -222.787523)
			(xy 380.865889 -222.787523) (xy 380.865889 -222.735589) (xy 380.874014 -222.684294) (xy 380.890062 -222.634901)
			(xy 380.91364 -222.588627) (xy 380.944166 -222.546611) (xy 380.980889 -222.509888) (xy 381.022905 -222.479362)
			(xy 381.069179 -222.455784) (xy 381.118572 -222.439736) (xy 381.169867 -222.431611) (xy 381.221801 -222.431611)
			(xy 381.273096 -222.439736) (xy 381.322489 -222.455784) (xy 381.368763 -222.479362) (xy 381.410779 -222.509888)
			(xy 381.447502 -222.546611) (xy 381.478028 -222.588627) (xy 381.501606 -222.634901) (xy 381.517654 -222.684294)
			(xy 381.525779 -222.735589) (xy 381.526288 -222.761556) (xy 381.525779 -222.787523) (xy 381.517654 -222.838818)
			(xy 381.501606 -222.888211) (xy 381.478028 -222.934485) (xy 381.447502 -222.976501) (xy 381.410779 -223.013224)
			(xy 381.368763 -223.04375) (xy 381.322489 -223.067328) (xy 381.273096 -223.083376) (xy 381.221801 -223.091501)
			(xy 381.169867 -223.091501) (xy 381.118572 -223.083376) (xy 381.069179 -223.067328) (xy 381.022905 -223.04375)
			(xy 380.980889 -223.013224) (xy 380.944166 -222.976501) (xy 380.91364 -222.934485) (xy 380.890062 -222.888211)
			(xy 380.874014 -222.838818) (xy 380.865889 -222.787523) (xy 380.585979 -222.787523) (xy 380.577854 -222.838818)
			(xy 380.561806 -222.888211) (xy 380.538228 -222.934485) (xy 380.507702 -222.976501) (xy 380.470979 -223.013224)
			(xy 380.428963 -223.04375) (xy 380.382689 -223.067328) (xy 380.333296 -223.083376) (xy 380.282001 -223.091501)
			(xy 380.230067 -223.091501) (xy 380.178772 -223.083376) (xy 380.129379 -223.067328) (xy 380.083105 -223.04375)
			(xy 380.041089 -223.013224) (xy 380.004366 -222.976501) (xy 379.97384 -222.934485) (xy 379.950262 -222.888211)
			(xy 379.934214 -222.838818) (xy 379.926089 -222.787523) (xy 379.646179 -222.787523) (xy 379.638054 -222.838818)
			(xy 379.622006 -222.888211) (xy 379.598428 -222.934485) (xy 379.567902 -222.976501) (xy 379.531179 -223.013224)
			(xy 379.489163 -223.04375) (xy 379.442889 -223.067328) (xy 379.393496 -223.083376) (xy 379.342201 -223.091501)
			(xy 379.290267 -223.091501) (xy 379.238972 -223.083376) (xy 379.189579 -223.067328) (xy 379.143305 -223.04375)
			(xy 379.101289 -223.013224) (xy 379.064566 -222.976501) (xy 379.03404 -222.934485) (xy 379.010462 -222.888211)
			(xy 378.994414 -222.838818) (xy 378.986289 -222.787523) (xy 378.706379 -222.787523) (xy 378.698254 -222.838818)
			(xy 378.682206 -222.888211) (xy 378.658628 -222.934485) (xy 378.628102 -222.976501) (xy 378.591379 -223.013224)
			(xy 378.549363 -223.04375) (xy 378.503089 -223.067328) (xy 378.453696 -223.083376) (xy 378.402401 -223.091501)
			(xy 378.350467 -223.091501) (xy 378.299172 -223.083376) (xy 378.249779 -223.067328) (xy 378.203505 -223.04375)
			(xy 378.161489 -223.013224) (xy 378.124766 -222.976501) (xy 378.09424 -222.934485) (xy 378.070662 -222.888211)
			(xy 378.054614 -222.838818) (xy 378.046489 -222.787523) (xy 377.766579 -222.787523) (xy 377.758454 -222.838818)
			(xy 377.742406 -222.888211) (xy 377.718828 -222.934485) (xy 377.688302 -222.976501) (xy 377.651579 -223.013224)
			(xy 377.609563 -223.04375) (xy 377.563289 -223.067328) (xy 377.513896 -223.083376) (xy 377.462601 -223.091501)
			(xy 377.410667 -223.091501) (xy 377.359372 -223.083376) (xy 377.309979 -223.067328) (xy 377.263705 -223.04375)
			(xy 377.221689 -223.013224) (xy 377.184966 -222.976501) (xy 377.15444 -222.934485) (xy 377.130862 -222.888211)
			(xy 377.114814 -222.838818) (xy 377.106689 -222.787523) (xy 376.826779 -222.787523) (xy 376.818654 -222.838818)
			(xy 376.802606 -222.888211) (xy 376.779028 -222.934485) (xy 376.748502 -222.976501) (xy 376.711779 -223.013224)
			(xy 376.669763 -223.04375) (xy 376.623489 -223.067328) (xy 376.574096 -223.083376) (xy 376.522801 -223.091501)
			(xy 376.470867 -223.091501) (xy 376.419572 -223.083376) (xy 376.370179 -223.067328) (xy 376.323905 -223.04375)
			(xy 376.281889 -223.013224) (xy 376.245166 -222.976501) (xy 376.21464 -222.934485) (xy 376.191062 -222.888211)
			(xy 376.175014 -222.838818) (xy 376.166889 -222.787523) (xy 375.886979 -222.787523) (xy 375.878854 -222.838818)
			(xy 375.862806 -222.888211) (xy 375.839228 -222.934485) (xy 375.808702 -222.976501) (xy 375.771979 -223.013224)
			(xy 375.729963 -223.04375) (xy 375.683689 -223.067328) (xy 375.634296 -223.083376) (xy 375.583001 -223.091501)
			(xy 375.531067 -223.091501) (xy 375.479772 -223.083376) (xy 375.430379 -223.067328) (xy 375.384105 -223.04375)
			(xy 375.342089 -223.013224) (xy 375.305366 -222.976501) (xy 375.27484 -222.934485) (xy 375.251262 -222.888211)
			(xy 375.235214 -222.838818) (xy 375.227089 -222.787523) (xy 374.947179 -222.787523) (xy 374.939054 -222.838818)
			(xy 374.923006 -222.888211) (xy 374.899428 -222.934485) (xy 374.868902 -222.976501) (xy 374.832179 -223.013224)
			(xy 374.790163 -223.04375) (xy 374.743889 -223.067328) (xy 374.694496 -223.083376) (xy 374.643201 -223.091501)
			(xy 374.591267 -223.091501) (xy 374.539972 -223.083376) (xy 374.490579 -223.067328) (xy 374.444305 -223.04375)
			(xy 374.402289 -223.013224) (xy 374.365566 -222.976501) (xy 374.33504 -222.934485) (xy 374.311462 -222.888211)
			(xy 374.295414 -222.838818) (xy 374.287289 -222.787523) (xy 374.007379 -222.787523) (xy 373.999254 -222.838818)
			(xy 373.983206 -222.888211) (xy 373.959628 -222.934485) (xy 373.929102 -222.976501) (xy 373.892379 -223.013224)
			(xy 373.850363 -223.04375) (xy 373.804089 -223.067328) (xy 373.754696 -223.083376) (xy 373.703401 -223.091501)
			(xy 373.651467 -223.091501) (xy 373.600172 -223.083376) (xy 373.550779 -223.067328) (xy 373.504505 -223.04375)
			(xy 373.462489 -223.013224) (xy 373.425766 -222.976501) (xy 373.39524 -222.934485) (xy 373.371662 -222.888211)
			(xy 373.355614 -222.838818) (xy 373.347489 -222.787523) (xy 373.067579 -222.787523) (xy 373.059454 -222.838818)
			(xy 373.043406 -222.888211) (xy 373.019828 -222.934485) (xy 372.989302 -222.976501) (xy 372.952579 -223.013224)
			(xy 372.910563 -223.04375) (xy 372.864289 -223.067328) (xy 372.814896 -223.083376) (xy 372.763601 -223.091501)
			(xy 372.711667 -223.091501) (xy 372.660372 -223.083376) (xy 372.610979 -223.067328) (xy 372.564705 -223.04375)
			(xy 372.522689 -223.013224) (xy 372.485966 -222.976501) (xy 372.45544 -222.934485) (xy 372.431862 -222.888211)
			(xy 372.415814 -222.838818) (xy 372.407689 -222.787523) (xy 372.127656 -222.787523) (xy 372.127565 -222.790879)
			(xy 372.118519 -222.843685) (xy 372.101069 -222.894339) (xy 372.075673 -222.941512) (xy 372.042996 -222.983969)
			(xy 372.003895 -223.020594) (xy 371.959395 -223.050429) (xy 371.935248 -223.062038) (xy 371.92219 -223.107078)
			(xy 371.889517 -223.194987) (xy 371.849589 -223.279847) (xy 371.80269 -223.361063) (xy 371.749148 -223.438061)
			(xy 371.68934 -223.510301) (xy 371.656864 -223.54413) (xy 371.658388 -223.575626) (xy 371.657848 -223.602633)
			(xy 371.649058 -223.655928) (xy 371.631715 -223.707082) (xy 371.606283 -223.754735) (xy 371.573438 -223.797616)
			(xy 371.534055 -223.834583) (xy 371.489183 -223.864651) (xy 371.46484 -223.876362) (xy 371.451782 -223.921339)
			(xy 371.41915 -224.009133) (xy 371.379289 -224.09389) (xy 371.332478 -224.175016) (xy 371.279046 -224.251943)
			(xy 371.219366 -224.32413) (xy 371.186964 -224.357946) (xy 371.188488 -224.389442) (xy 371.46738 -224.389442)
			(xy 371.467787 -224.363988) (xy 371.475574 -224.31368) (xy 371.490987 -224.265161) (xy 371.51366 -224.219581)
			(xy 371.543056 -224.178019) (xy 371.57848 -224.141457) (xy 371.619093 -224.110763) (xy 371.663934 -224.086661)
			(xy 371.711942 -224.069724) (xy 371.736874 -224.064576) (xy 371.759734 -224.060258) (xy 371.963442 -223.707198)
			(xy 371.955822 -223.685354) (xy 371.947098 -223.658762) (xy 371.937641 -223.603606) (xy 371.937026 -223.575626)
			(xy 371.937535 -223.549659) (xy 371.94566 -223.498364) (xy 371.961708 -223.448971) (xy 371.985286 -223.402697)
			(xy 372.015812 -223.360681) (xy 372.052535 -223.323958) (xy 372.094551 -223.293432) (xy 372.140825 -223.269854)
			(xy 372.190218 -223.253806) (xy 372.241513 -223.245681) (xy 372.293447 -223.245681) (xy 372.344742 -223.253806)
			(xy 372.394135 -223.269854) (xy 372.440409 -223.293432) (xy 372.482425 -223.323958) (xy 372.519148 -223.360681)
			(xy 372.549674 -223.402697) (xy 372.573252 -223.448971) (xy 372.5893 -223.498364) (xy 372.597425 -223.549659)
			(xy 372.597934 -223.575626) (xy 372.597486 -223.601078) (xy 372.597406 -223.601593) (xy 372.877589 -223.601593)
			(xy 372.877589 -223.549659) (xy 372.885714 -223.498364) (xy 372.901762 -223.448971) (xy 372.92534 -223.402697)
			(xy 372.955866 -223.360681) (xy 372.992589 -223.323958) (xy 373.034605 -223.293432) (xy 373.080879 -223.269854)
			(xy 373.130272 -223.253806) (xy 373.181567 -223.245681) (xy 373.233501 -223.245681) (xy 373.284796 -223.253806)
			(xy 373.334189 -223.269854) (xy 373.380463 -223.293432) (xy 373.422479 -223.323958) (xy 373.459202 -223.360681)
			(xy 373.489728 -223.402697) (xy 373.513306 -223.448971) (xy 373.529354 -223.498364) (xy 373.537479 -223.549659)
			(xy 373.537988 -223.575626) (xy 373.537479 -223.601593) (xy 373.529354 -223.652888) (xy 373.513306 -223.702281)
			(xy 373.489728 -223.748555) (xy 373.459202 -223.790571) (xy 373.422479 -223.827294) (xy 373.380463 -223.85782)
			(xy 373.334189 -223.881398) (xy 373.284796 -223.897446) (xy 373.233501 -223.905571) (xy 373.181567 -223.905571)
			(xy 373.130272 -223.897446) (xy 373.080879 -223.881398) (xy 373.034605 -223.85782) (xy 372.992589 -223.827294)
			(xy 372.955866 -223.790571) (xy 372.92534 -223.748555) (xy 372.901762 -223.702281) (xy 372.885714 -223.652888)
			(xy 372.877589 -223.601593) (xy 372.597406 -223.601593) (xy 372.589704 -223.651385) (xy 372.574297 -223.699901)
			(xy 372.551629 -223.74548) (xy 372.522238 -223.787043) (xy 372.486819 -223.823605) (xy 372.44621 -223.8543)
			(xy 372.401374 -223.878403) (xy 372.35337 -223.895342) (xy 372.32844 -223.900492) (xy 372.305326 -223.90481)
			(xy 372.101872 -224.257616) (xy 372.109492 -224.279714) (xy 372.118233 -224.306301) (xy 372.127678 -224.361461)
			(xy 372.128288 -224.389442) (xy 372.40718 -224.389442) (xy 372.407689 -224.363475) (xy 372.415814 -224.31218)
			(xy 372.431862 -224.262787) (xy 372.45544 -224.216513) (xy 372.485966 -224.174497) (xy 372.522689 -224.137774)
			(xy 372.564705 -224.107248) (xy 372.610979 -224.08367) (xy 372.660372 -224.067622) (xy 372.711667 -224.059497)
			(xy 372.763601 -224.059497) (xy 372.814896 -224.067622) (xy 372.864289 -224.08367) (xy 372.910563 -224.107248)
			(xy 372.952579 -224.137774) (xy 372.989302 -224.174497) (xy 373.019828 -224.216513) (xy 373.043406 -224.262787)
			(xy 373.059454 -224.31218) (xy 373.067579 -224.363475) (xy 373.068088 -224.389442) (xy 373.34698 -224.389442)
			(xy 373.347387 -224.363988) (xy 373.355174 -224.31368) (xy 373.370587 -224.265161) (xy 373.39326 -224.219581)
			(xy 373.422656 -224.178019) (xy 373.45808 -224.141457) (xy 373.498693 -224.110763) (xy 373.543534 -224.086661)
			(xy 373.591542 -224.069724) (xy 373.616474 -224.064576) (xy 373.639334 -224.060258) (xy 373.843042 -223.707198)
			(xy 373.835422 -223.685354) (xy 373.826698 -223.658762) (xy 373.817241 -223.603606) (xy 373.816626 -223.575626)
			(xy 373.817135 -223.549659) (xy 373.82526 -223.498364) (xy 373.841308 -223.448971) (xy 373.864886 -223.402697)
			(xy 373.895412 -223.360681) (xy 373.932135 -223.323958) (xy 373.974151 -223.293432) (xy 374.020425 -223.269854)
			(xy 374.069818 -223.253806) (xy 374.121113 -223.245681) (xy 374.173047 -223.245681) (xy 374.224342 -223.253806)
			(xy 374.273735 -223.269854) (xy 374.320009 -223.293432) (xy 374.362025 -223.323958) (xy 374.398748 -223.360681)
			(xy 374.429274 -223.402697) (xy 374.452852 -223.448971) (xy 374.4689 -223.498364) (xy 374.477025 -223.549659)
			(xy 374.477534 -223.575626) (xy 374.477086 -223.601078) (xy 374.477006 -223.601593) (xy 374.757189 -223.601593)
			(xy 374.757189 -223.549659) (xy 374.765314 -223.498364) (xy 374.781362 -223.448971) (xy 374.80494 -223.402697)
			(xy 374.835466 -223.360681) (xy 374.872189 -223.323958) (xy 374.914205 -223.293432) (xy 374.960479 -223.269854)
			(xy 375.009872 -223.253806) (xy 375.061167 -223.245681) (xy 375.113101 -223.245681) (xy 375.164396 -223.253806)
			(xy 375.213789 -223.269854) (xy 375.260063 -223.293432) (xy 375.302079 -223.323958) (xy 375.338802 -223.360681)
			(xy 375.369328 -223.402697) (xy 375.392906 -223.448971) (xy 375.408954 -223.498364) (xy 375.417079 -223.549659)
			(xy 375.417588 -223.575626) (xy 375.417079 -223.601593) (xy 375.408954 -223.652888) (xy 375.392906 -223.702281)
			(xy 375.369328 -223.748555) (xy 375.338802 -223.790571) (xy 375.302079 -223.827294) (xy 375.260063 -223.85782)
			(xy 375.213789 -223.881398) (xy 375.164396 -223.897446) (xy 375.113101 -223.905571) (xy 375.061167 -223.905571)
			(xy 375.009872 -223.897446) (xy 374.960479 -223.881398) (xy 374.914205 -223.85782) (xy 374.872189 -223.827294)
			(xy 374.835466 -223.790571) (xy 374.80494 -223.748555) (xy 374.781362 -223.702281) (xy 374.765314 -223.652888)
			(xy 374.757189 -223.601593) (xy 374.477006 -223.601593) (xy 374.469304 -223.651385) (xy 374.453897 -223.699901)
			(xy 374.431229 -223.74548) (xy 374.401838 -223.787043) (xy 374.366419 -223.823605) (xy 374.32581 -223.8543)
			(xy 374.280974 -223.878403) (xy 374.23297 -223.895342) (xy 374.20804 -223.900492) (xy 374.184926 -223.90481)
			(xy 373.981472 -224.257616) (xy 373.989092 -224.279714) (xy 373.997833 -224.306301) (xy 374.007278 -224.361461)
			(xy 374.007888 -224.389442) (xy 374.28678 -224.389442) (xy 374.287289 -224.363475) (xy 374.295414 -224.31218)
			(xy 374.311462 -224.262787) (xy 374.33504 -224.216513) (xy 374.365566 -224.174497) (xy 374.402289 -224.137774)
			(xy 374.444305 -224.107248) (xy 374.490579 -224.08367) (xy 374.539972 -224.067622) (xy 374.591267 -224.059497)
			(xy 374.643201 -224.059497) (xy 374.694496 -224.067622) (xy 374.743889 -224.08367) (xy 374.790163 -224.107248)
			(xy 374.832179 -224.137774) (xy 374.868902 -224.174497) (xy 374.899428 -224.216513) (xy 374.923006 -224.262787)
			(xy 374.939054 -224.31218) (xy 374.947179 -224.363475) (xy 374.947688 -224.389442) (xy 375.22658 -224.389442)
			(xy 375.226987 -224.363988) (xy 375.234774 -224.31368) (xy 375.250187 -224.265161) (xy 375.27286 -224.219581)
			(xy 375.302256 -224.178019) (xy 375.33768 -224.141457) (xy 375.378293 -224.110763) (xy 375.423134 -224.086661)
			(xy 375.471142 -224.069724) (xy 375.496074 -224.064576) (xy 375.518934 -224.060258) (xy 375.722642 -223.707198)
			(xy 375.715022 -223.685354) (xy 375.706298 -223.658762) (xy 375.696841 -223.603606) (xy 375.696226 -223.575626)
			(xy 375.696735 -223.549659) (xy 375.70486 -223.498364) (xy 375.720908 -223.448971) (xy 375.744486 -223.402697)
			(xy 375.775012 -223.360681) (xy 375.811735 -223.323958) (xy 375.853751 -223.293432) (xy 375.900025 -223.269854)
			(xy 375.949418 -223.253806) (xy 376.000713 -223.245681) (xy 376.052647 -223.245681) (xy 376.103942 -223.253806)
			(xy 376.153335 -223.269854) (xy 376.199609 -223.293432) (xy 376.241625 -223.323958) (xy 376.278348 -223.360681)
			(xy 376.308874 -223.402697) (xy 376.332452 -223.448971) (xy 376.3485 -223.498364) (xy 376.356625 -223.549659)
			(xy 376.357134 -223.575626) (xy 376.356686 -223.601078) (xy 376.356606 -223.601593) (xy 376.636789 -223.601593)
			(xy 376.636789 -223.549659) (xy 376.644914 -223.498364) (xy 376.660962 -223.448971) (xy 376.68454 -223.402697)
			(xy 376.715066 -223.360681) (xy 376.751789 -223.323958) (xy 376.793805 -223.293432) (xy 376.840079 -223.269854)
			(xy 376.889472 -223.253806) (xy 376.940767 -223.245681) (xy 376.992701 -223.245681) (xy 377.043996 -223.253806)
			(xy 377.093389 -223.269854) (xy 377.139663 -223.293432) (xy 377.181679 -223.323958) (xy 377.218402 -223.360681)
			(xy 377.248928 -223.402697) (xy 377.272506 -223.448971) (xy 377.288554 -223.498364) (xy 377.296679 -223.549659)
			(xy 377.297188 -223.575626) (xy 377.296679 -223.601593) (xy 377.288554 -223.652888) (xy 377.272506 -223.702281)
			(xy 377.248928 -223.748555) (xy 377.218402 -223.790571) (xy 377.181679 -223.827294) (xy 377.139663 -223.85782)
			(xy 377.093389 -223.881398) (xy 377.043996 -223.897446) (xy 376.992701 -223.905571) (xy 376.940767 -223.905571)
			(xy 376.889472 -223.897446) (xy 376.840079 -223.881398) (xy 376.793805 -223.85782) (xy 376.751789 -223.827294)
			(xy 376.715066 -223.790571) (xy 376.68454 -223.748555) (xy 376.660962 -223.702281) (xy 376.644914 -223.652888)
			(xy 376.636789 -223.601593) (xy 376.356606 -223.601593) (xy 376.348904 -223.651385) (xy 376.333497 -223.699901)
			(xy 376.310829 -223.74548) (xy 376.281438 -223.787043) (xy 376.246019 -223.823605) (xy 376.20541 -223.8543)
			(xy 376.160574 -223.878403) (xy 376.11257 -223.895342) (xy 376.08764 -223.900492) (xy 376.064526 -223.90481)
			(xy 375.861072 -224.257616) (xy 375.868692 -224.279714) (xy 375.877433 -224.306301) (xy 375.886878 -224.361461)
			(xy 375.887488 -224.389442) (xy 376.16638 -224.389442) (xy 376.166889 -224.363475) (xy 376.175014 -224.31218)
			(xy 376.191062 -224.262787) (xy 376.21464 -224.216513) (xy 376.245166 -224.174497) (xy 376.281889 -224.137774)
			(xy 376.323905 -224.107248) (xy 376.370179 -224.08367) (xy 376.419572 -224.067622) (xy 376.470867 -224.059497)
			(xy 376.522801 -224.059497) (xy 376.574096 -224.067622) (xy 376.623489 -224.08367) (xy 376.669763 -224.107248)
			(xy 376.711779 -224.137774) (xy 376.748502 -224.174497) (xy 376.779028 -224.216513) (xy 376.802606 -224.262787)
			(xy 376.818654 -224.31218) (xy 376.826779 -224.363475) (xy 376.827288 -224.389442) (xy 377.10618 -224.389442)
			(xy 377.106587 -224.363988) (xy 377.114374 -224.31368) (xy 377.129787 -224.265161) (xy 377.15246 -224.219581)
			(xy 377.181856 -224.178019) (xy 377.21728 -224.141457) (xy 377.257893 -224.110763) (xy 377.302734 -224.086661)
			(xy 377.350742 -224.069724) (xy 377.375674 -224.064576) (xy 377.398534 -224.060258) (xy 377.602242 -223.707198)
			(xy 377.594622 -223.685354) (xy 377.585898 -223.658762) (xy 377.576441 -223.603606) (xy 377.575826 -223.575626)
			(xy 377.576335 -223.549659) (xy 377.58446 -223.498364) (xy 377.600508 -223.448971) (xy 377.624086 -223.402697)
			(xy 377.654612 -223.360681) (xy 377.691335 -223.323958) (xy 377.733351 -223.293432) (xy 377.779625 -223.269854)
			(xy 377.829018 -223.253806) (xy 377.880313 -223.245681) (xy 377.932247 -223.245681) (xy 377.983542 -223.253806)
			(xy 378.032935 -223.269854) (xy 378.079209 -223.293432) (xy 378.121225 -223.323958) (xy 378.157948 -223.360681)
			(xy 378.188474 -223.402697) (xy 378.212052 -223.448971) (xy 378.2281 -223.498364) (xy 378.236225 -223.549659)
			(xy 378.236734 -223.575626) (xy 378.236286 -223.601078) (xy 378.236206 -223.601593) (xy 378.516389 -223.601593)
			(xy 378.516389 -223.549659) (xy 378.524514 -223.498364) (xy 378.540562 -223.448971) (xy 378.56414 -223.402697)
			(xy 378.594666 -223.360681) (xy 378.631389 -223.323958) (xy 378.673405 -223.293432) (xy 378.719679 -223.269854)
			(xy 378.769072 -223.253806) (xy 378.820367 -223.245681) (xy 378.872301 -223.245681) (xy 378.923596 -223.253806)
			(xy 378.972989 -223.269854) (xy 379.019263 -223.293432) (xy 379.061279 -223.323958) (xy 379.098002 -223.360681)
			(xy 379.128528 -223.402697) (xy 379.152106 -223.448971) (xy 379.168154 -223.498364) (xy 379.176279 -223.549659)
			(xy 379.176788 -223.575626) (xy 379.176279 -223.601593) (xy 379.168154 -223.652888) (xy 379.152106 -223.702281)
			(xy 379.128528 -223.748555) (xy 379.098002 -223.790571) (xy 379.061279 -223.827294) (xy 379.019263 -223.85782)
			(xy 378.972989 -223.881398) (xy 378.923596 -223.897446) (xy 378.872301 -223.905571) (xy 378.820367 -223.905571)
			(xy 378.769072 -223.897446) (xy 378.719679 -223.881398) (xy 378.673405 -223.85782) (xy 378.631389 -223.827294)
			(xy 378.594666 -223.790571) (xy 378.56414 -223.748555) (xy 378.540562 -223.702281) (xy 378.524514 -223.652888)
			(xy 378.516389 -223.601593) (xy 378.236206 -223.601593) (xy 378.228504 -223.651385) (xy 378.213097 -223.699901)
			(xy 378.190429 -223.74548) (xy 378.161038 -223.787043) (xy 378.125619 -223.823605) (xy 378.08501 -223.8543)
			(xy 378.040174 -223.878403) (xy 377.99217 -223.895342) (xy 377.96724 -223.900492) (xy 377.944126 -223.90481)
			(xy 377.740672 -224.257616) (xy 377.748292 -224.279714) (xy 377.757033 -224.306301) (xy 377.766478 -224.361461)
			(xy 377.767088 -224.389442) (xy 378.04598 -224.389442) (xy 378.046489 -224.363475) (xy 378.054614 -224.31218)
			(xy 378.070662 -224.262787) (xy 378.09424 -224.216513) (xy 378.124766 -224.174497) (xy 378.161489 -224.137774)
			(xy 378.203505 -224.107248) (xy 378.249779 -224.08367) (xy 378.299172 -224.067622) (xy 378.350467 -224.059497)
			(xy 378.402401 -224.059497) (xy 378.453696 -224.067622) (xy 378.503089 -224.08367) (xy 378.549363 -224.107248)
			(xy 378.591379 -224.137774) (xy 378.628102 -224.174497) (xy 378.658628 -224.216513) (xy 378.682206 -224.262787)
			(xy 378.698254 -224.31218) (xy 378.706379 -224.363475) (xy 378.706888 -224.389442) (xy 378.98578 -224.389442)
			(xy 378.986187 -224.363988) (xy 378.993974 -224.31368) (xy 379.009387 -224.265161) (xy 379.03206 -224.219581)
			(xy 379.061456 -224.178019) (xy 379.09688 -224.141457) (xy 379.137493 -224.110763) (xy 379.182334 -224.086661)
			(xy 379.230342 -224.069724) (xy 379.255274 -224.064576) (xy 379.278388 -224.060258) (xy 379.481842 -223.707198)
			(xy 379.474222 -223.6851) (xy 379.465475 -223.658579) (xy 379.456027 -223.603545) (xy 379.455426 -223.575626)
			(xy 379.455935 -223.549659) (xy 379.46406 -223.498364) (xy 379.480108 -223.448971) (xy 379.503686 -223.402697)
			(xy 379.534212 -223.360681) (xy 379.570935 -223.323958) (xy 379.612951 -223.293432) (xy 379.659225 -223.269854)
			(xy 379.708618 -223.253806) (xy 379.759913 -223.245681) (xy 379.811847 -223.245681) (xy 379.863142 -223.253806)
			(xy 379.912535 -223.269854) (xy 379.958809 -223.293432) (xy 380.000825 -223.323958) (xy 380.037548 -223.360681)
			(xy 380.068074 -223.402697) (xy 380.091652 -223.448971) (xy 380.1077 -223.498364) (xy 380.115825 -223.549659)
			(xy 380.116334 -223.575626) (xy 380.115886 -223.601078) (xy 380.115806 -223.601593) (xy 380.395989 -223.601593)
			(xy 380.395989 -223.549659) (xy 380.404114 -223.498364) (xy 380.420162 -223.448971) (xy 380.44374 -223.402697)
			(xy 380.474266 -223.360681) (xy 380.510989 -223.323958) (xy 380.553005 -223.293432) (xy 380.599279 -223.269854)
			(xy 380.648672 -223.253806) (xy 380.699967 -223.245681) (xy 380.751901 -223.245681) (xy 380.803196 -223.253806)
			(xy 380.852589 -223.269854) (xy 380.898863 -223.293432) (xy 380.940879 -223.323958) (xy 380.977602 -223.360681)
			(xy 381.008128 -223.402697) (xy 381.031706 -223.448971) (xy 381.047754 -223.498364) (xy 381.055879 -223.549659)
			(xy 381.056388 -223.575626) (xy 381.055879 -223.601593) (xy 381.047754 -223.652888) (xy 381.031706 -223.702281)
			(xy 381.008128 -223.748555) (xy 380.977602 -223.790571) (xy 380.940879 -223.827294) (xy 380.898863 -223.85782)
			(xy 380.852589 -223.881398) (xy 380.803196 -223.897446) (xy 380.751901 -223.905571) (xy 380.699967 -223.905571)
			(xy 380.648672 -223.897446) (xy 380.599279 -223.881398) (xy 380.553005 -223.85782) (xy 380.510989 -223.827294)
			(xy 380.474266 -223.790571) (xy 380.44374 -223.748555) (xy 380.420162 -223.702281) (xy 380.404114 -223.652888)
			(xy 380.395989 -223.601593) (xy 380.115806 -223.601593) (xy 380.108104 -223.651385) (xy 380.092697 -223.699901)
			(xy 380.070029 -223.74548) (xy 380.040638 -223.787043) (xy 380.005219 -223.823605) (xy 379.96461 -223.8543)
			(xy 379.919774 -223.878403) (xy 379.87177 -223.895342) (xy 379.84684 -223.900492) (xy 379.823726 -223.90481)
			(xy 379.620272 -224.257616) (xy 379.627892 -224.279714) (xy 379.636633 -224.306301) (xy 379.646078 -224.361461)
			(xy 379.646688 -224.389442) (xy 379.92558 -224.389442) (xy 379.926089 -224.363475) (xy 379.934214 -224.31218)
			(xy 379.950262 -224.262787) (xy 379.97384 -224.216513) (xy 380.004366 -224.174497) (xy 380.041089 -224.137774)
			(xy 380.083105 -224.107248) (xy 380.129379 -224.08367) (xy 380.178772 -224.067622) (xy 380.230067 -224.059497)
			(xy 380.282001 -224.059497) (xy 380.333296 -224.067622) (xy 380.382689 -224.08367) (xy 380.428963 -224.107248)
			(xy 380.470979 -224.137774) (xy 380.507702 -224.174497) (xy 380.538228 -224.216513) (xy 380.561806 -224.262787)
			(xy 380.577854 -224.31218) (xy 380.585979 -224.363475) (xy 380.586488 -224.389442) (xy 380.86538 -224.389442)
			(xy 380.865787 -224.363988) (xy 380.873574 -224.31368) (xy 380.888987 -224.265161) (xy 380.91166 -224.219581)
			(xy 380.941056 -224.178019) (xy 380.97648 -224.141457) (xy 381.017093 -224.110763) (xy 381.061934 -224.086661)
			(xy 381.109942 -224.069724) (xy 381.134874 -224.064576) (xy 381.157988 -224.060258) (xy 381.361696 -223.706944)
			(xy 381.353822 -223.6851) (xy 381.345162 -223.658564) (xy 381.335841 -223.603534) (xy 381.33528 -223.575626)
			(xy 381.335789 -223.549659) (xy 381.343914 -223.498364) (xy 381.359962 -223.448971) (xy 381.38354 -223.402697)
			(xy 381.414066 -223.360681) (xy 381.450789 -223.323958) (xy 381.492805 -223.293432) (xy 381.539079 -223.269854)
			(xy 381.588472 -223.253806) (xy 381.639767 -223.245681) (xy 381.691701 -223.245681) (xy 381.742996 -223.253806)
			(xy 381.792389 -223.269854) (xy 381.838663 -223.293432) (xy 381.880679 -223.323958) (xy 381.917402 -223.360681)
			(xy 381.947928 -223.402697) (xy 381.971506 -223.448971) (xy 381.987554 -223.498364) (xy 381.995679 -223.549659)
			(xy 381.996188 -223.575626) (xy 381.99574 -223.60109) (xy 381.987937 -223.651415) (xy 381.972504 -223.699947)
			(xy 381.949808 -223.745537) (xy 381.920385 -223.787104) (xy 381.884932 -223.823664) (xy 381.844289 -223.854351)
			(xy 381.799419 -223.878439) (xy 381.751385 -223.895356) (xy 381.72644 -223.900492) (xy 381.703326 -223.90481)
			(xy 381.499872 -224.257616) (xy 381.507492 -224.279714) (xy 381.516233 -224.306301) (xy 381.525678 -224.361461)
			(xy 381.526288 -224.389442) (xy 381.525779 -224.415409) (xy 381.517654 -224.466704) (xy 381.501606 -224.516097)
			(xy 381.478028 -224.562371) (xy 381.447502 -224.604387) (xy 381.410779 -224.64111) (xy 381.368763 -224.671636)
			(xy 381.322489 -224.695214) (xy 381.273096 -224.711262) (xy 381.221801 -224.719387) (xy 381.169867 -224.719387)
			(xy 381.118572 -224.711262) (xy 381.069179 -224.695214) (xy 381.022905 -224.671636) (xy 380.980889 -224.64111)
			(xy 380.944166 -224.604387) (xy 380.91364 -224.562371) (xy 380.890062 -224.516097) (xy 380.874014 -224.466704)
			(xy 380.865889 -224.415409) (xy 380.86538 -224.389442) (xy 380.586488 -224.389442) (xy 380.585946 -224.417428)
			(xy 380.576489 -224.472596) (xy 380.567692 -224.49917) (xy 380.560072 -224.521268) (xy 380.76378 -224.874074)
			(xy 380.78664 -224.878392) (xy 380.811567 -224.883535) (xy 380.859553 -224.900502) (xy 380.904372 -224.924622)
			(xy 380.944966 -224.955325) (xy 380.980375 -224.991886) (xy 381.009762 -225.033442) (xy 381.032435 -225.07901)
			(xy 381.047856 -225.127515) (xy 381.055662 -225.17781) (xy 381.056134 -225.203258) (xy 381.055625 -225.229225)
			(xy 381.335789 -225.229225) (xy 381.335789 -225.177291) (xy 381.343914 -225.125996) (xy 381.359962 -225.076603)
			(xy 381.38354 -225.030329) (xy 381.414066 -224.988313) (xy 381.450789 -224.95159) (xy 381.492805 -224.921064)
			(xy 381.539079 -224.897486) (xy 381.588472 -224.881438) (xy 381.639767 -224.873313) (xy 381.691701 -224.873313)
			(xy 381.742996 -224.881438) (xy 381.792389 -224.897486) (xy 381.838663 -224.921064) (xy 381.880679 -224.95159)
			(xy 381.917402 -224.988313) (xy 381.947928 -225.030329) (xy 381.971506 -225.076603) (xy 381.987554 -225.125996)
			(xy 381.995679 -225.177291) (xy 381.996188 -225.203258) (xy 381.995679 -225.229225) (xy 381.987554 -225.28052)
			(xy 381.971506 -225.329913) (xy 381.947928 -225.376187) (xy 381.917402 -225.418203) (xy 381.880679 -225.454926)
			(xy 381.838663 -225.485452) (xy 381.792389 -225.50903) (xy 381.742996 -225.525078) (xy 381.691701 -225.533203)
			(xy 381.639767 -225.533203) (xy 381.588472 -225.525078) (xy 381.539079 -225.50903) (xy 381.492805 -225.485452)
			(xy 381.450789 -225.454926) (xy 381.414066 -225.418203) (xy 381.38354 -225.376187) (xy 381.359962 -225.329913)
			(xy 381.343914 -225.28052) (xy 381.335789 -225.229225) (xy 381.055625 -225.229225) (xy 381.0475 -225.28052)
			(xy 381.031452 -225.329913) (xy 381.007874 -225.376187) (xy 380.977348 -225.418203) (xy 380.940625 -225.454926)
			(xy 380.898609 -225.485452) (xy 380.852335 -225.50903) (xy 380.802942 -225.525078) (xy 380.751647 -225.533203)
			(xy 380.699713 -225.533203) (xy 380.648418 -225.525078) (xy 380.599025 -225.50903) (xy 380.552751 -225.485452)
			(xy 380.510735 -225.454926) (xy 380.474012 -225.418203) (xy 380.443486 -225.376187) (xy 380.419908 -225.329913)
			(xy 380.40386 -225.28052) (xy 380.395735 -225.229225) (xy 380.395226 -225.203258) (xy 380.395767 -225.175272)
			(xy 380.405225 -225.120104) (xy 380.414022 -225.09353) (xy 380.421642 -225.071432) (xy 380.217934 -224.718626)
			(xy 380.195074 -224.714308) (xy 380.170149 -224.709155) (xy 380.122163 -224.69219) (xy 380.077344 -224.668072)
			(xy 380.03675 -224.63737) (xy 380.00134 -224.60081) (xy 379.971952 -224.559256) (xy 379.94928 -224.513688)
			(xy 379.933858 -224.465184) (xy 379.926052 -224.41489) (xy 379.92558 -224.389442) (xy 379.646688 -224.389442)
			(xy 379.646179 -224.415409) (xy 379.638054 -224.466704) (xy 379.622006 -224.516097) (xy 379.598428 -224.562371)
			(xy 379.567902 -224.604387) (xy 379.531179 -224.64111) (xy 379.489163 -224.671636) (xy 379.442889 -224.695214)
			(xy 379.393496 -224.711262) (xy 379.342201 -224.719387) (xy 379.290267 -224.719387) (xy 379.238972 -224.711262)
			(xy 379.189579 -224.695214) (xy 379.143305 -224.671636) (xy 379.101289 -224.64111) (xy 379.064566 -224.604387)
			(xy 379.03404 -224.562371) (xy 379.010462 -224.516097) (xy 378.994414 -224.466704) (xy 378.986289 -224.415409)
			(xy 378.98578 -224.389442) (xy 378.706888 -224.389442) (xy 378.706346 -224.417428) (xy 378.696889 -224.472596)
			(xy 378.688092 -224.49917) (xy 378.680472 -224.521268) (xy 378.88418 -224.874074) (xy 378.90704 -224.878392)
			(xy 378.931967 -224.883535) (xy 378.979953 -224.900502) (xy 379.024772 -224.924622) (xy 379.065366 -224.955325)
			(xy 379.100775 -224.991886) (xy 379.130162 -225.033442) (xy 379.152835 -225.07901) (xy 379.168256 -225.127515)
			(xy 379.176062 -225.17781) (xy 379.176534 -225.203258) (xy 379.176025 -225.229225) (xy 379.455935 -225.229225)
			(xy 379.455935 -225.177291) (xy 379.46406 -225.125996) (xy 379.480108 -225.076603) (xy 379.503686 -225.030329)
			(xy 379.534212 -224.988313) (xy 379.570935 -224.95159) (xy 379.612951 -224.921064) (xy 379.659225 -224.897486)
			(xy 379.708618 -224.881438) (xy 379.759913 -224.873313) (xy 379.811847 -224.873313) (xy 379.863142 -224.881438)
			(xy 379.912535 -224.897486) (xy 379.958809 -224.921064) (xy 380.000825 -224.95159) (xy 380.037548 -224.988313)
			(xy 380.068074 -225.030329) (xy 380.091652 -225.076603) (xy 380.1077 -225.125996) (xy 380.115825 -225.177291)
			(xy 380.116334 -225.203258) (xy 380.115825 -225.229225) (xy 380.1077 -225.28052) (xy 380.091652 -225.329913)
			(xy 380.068074 -225.376187) (xy 380.037548 -225.418203) (xy 380.000825 -225.454926) (xy 379.958809 -225.485452)
			(xy 379.912535 -225.50903) (xy 379.863142 -225.525078) (xy 379.811847 -225.533203) (xy 379.759913 -225.533203)
			(xy 379.708618 -225.525078) (xy 379.659225 -225.50903) (xy 379.612951 -225.485452) (xy 379.570935 -225.454926)
			(xy 379.534212 -225.418203) (xy 379.503686 -225.376187) (xy 379.480108 -225.329913) (xy 379.46406 -225.28052)
			(xy 379.455935 -225.229225) (xy 379.176025 -225.229225) (xy 379.1679 -225.28052) (xy 379.151852 -225.329913)
			(xy 379.128274 -225.376187) (xy 379.097748 -225.418203) (xy 379.061025 -225.454926) (xy 379.019009 -225.485452)
			(xy 378.972735 -225.50903) (xy 378.923342 -225.525078) (xy 378.872047 -225.533203) (xy 378.820113 -225.533203)
			(xy 378.768818 -225.525078) (xy 378.719425 -225.50903) (xy 378.673151 -225.485452) (xy 378.631135 -225.454926)
			(xy 378.594412 -225.418203) (xy 378.563886 -225.376187) (xy 378.540308 -225.329913) (xy 378.52426 -225.28052)
			(xy 378.516135 -225.229225) (xy 378.515626 -225.203258) (xy 378.516167 -225.175272) (xy 378.525625 -225.120104)
			(xy 378.534422 -225.09353) (xy 378.542042 -225.071432) (xy 378.338334 -224.718626) (xy 378.315474 -224.714308)
			(xy 378.290549 -224.709155) (xy 378.242563 -224.69219) (xy 378.197744 -224.668072) (xy 378.15715 -224.63737)
			(xy 378.12174 -224.60081) (xy 378.092352 -224.559256) (xy 378.06968 -224.513688) (xy 378.054258 -224.465184)
			(xy 378.046452 -224.41489) (xy 378.04598 -224.389442) (xy 377.767088 -224.389442) (xy 377.766579 -224.415409)
			(xy 377.758454 -224.466704) (xy 377.742406 -224.516097) (xy 377.718828 -224.562371) (xy 377.688302 -224.604387)
			(xy 377.651579 -224.64111) (xy 377.609563 -224.671636) (xy 377.563289 -224.695214) (xy 377.513896 -224.711262)
			(xy 377.462601 -224.719387) (xy 377.410667 -224.719387) (xy 377.359372 -224.711262) (xy 377.309979 -224.695214)
			(xy 377.263705 -224.671636) (xy 377.221689 -224.64111) (xy 377.184966 -224.604387) (xy 377.15444 -224.562371)
			(xy 377.130862 -224.516097) (xy 377.114814 -224.466704) (xy 377.106689 -224.415409) (xy 377.10618 -224.389442)
			(xy 376.827288 -224.389442) (xy 376.826746 -224.417428) (xy 376.817289 -224.472596) (xy 376.808492 -224.49917)
			(xy 376.800872 -224.521268) (xy 377.00458 -224.874074) (xy 377.02744 -224.878392) (xy 377.052367 -224.883535)
			(xy 377.100353 -224.900502) (xy 377.145172 -224.924622) (xy 377.185766 -224.955325) (xy 377.221175 -224.991886)
			(xy 377.250562 -225.033442) (xy 377.273235 -225.07901) (xy 377.288656 -225.127515) (xy 377.296462 -225.17781)
			(xy 377.296934 -225.203258) (xy 377.296425 -225.229225) (xy 377.576335 -225.229225) (xy 377.576335 -225.177291)
			(xy 377.58446 -225.125996) (xy 377.600508 -225.076603) (xy 377.624086 -225.030329) (xy 377.654612 -224.988313)
			(xy 377.691335 -224.95159) (xy 377.733351 -224.921064) (xy 377.779625 -224.897486) (xy 377.829018 -224.881438)
			(xy 377.880313 -224.873313) (xy 377.932247 -224.873313) (xy 377.983542 -224.881438) (xy 378.032935 -224.897486)
			(xy 378.079209 -224.921064) (xy 378.121225 -224.95159) (xy 378.157948 -224.988313) (xy 378.188474 -225.030329)
			(xy 378.212052 -225.076603) (xy 378.2281 -225.125996) (xy 378.236225 -225.177291) (xy 378.236734 -225.203258)
			(xy 378.236225 -225.229225) (xy 378.2281 -225.28052) (xy 378.212052 -225.329913) (xy 378.188474 -225.376187)
			(xy 378.157948 -225.418203) (xy 378.121225 -225.454926) (xy 378.079209 -225.485452) (xy 378.032935 -225.50903)
			(xy 377.983542 -225.525078) (xy 377.932247 -225.533203) (xy 377.880313 -225.533203) (xy 377.829018 -225.525078)
			(xy 377.779625 -225.50903) (xy 377.733351 -225.485452) (xy 377.691335 -225.454926) (xy 377.654612 -225.418203)
			(xy 377.624086 -225.376187) (xy 377.600508 -225.329913) (xy 377.58446 -225.28052) (xy 377.576335 -225.229225)
			(xy 377.296425 -225.229225) (xy 377.2883 -225.28052) (xy 377.272252 -225.329913) (xy 377.248674 -225.376187)
			(xy 377.218148 -225.418203) (xy 377.181425 -225.454926) (xy 377.139409 -225.485452) (xy 377.093135 -225.50903)
			(xy 377.043742 -225.525078) (xy 376.992447 -225.533203) (xy 376.940513 -225.533203) (xy 376.889218 -225.525078)
			(xy 376.839825 -225.50903) (xy 376.793551 -225.485452) (xy 376.751535 -225.454926) (xy 376.714812 -225.418203)
			(xy 376.684286 -225.376187) (xy 376.660708 -225.329913) (xy 376.64466 -225.28052) (xy 376.636535 -225.229225)
			(xy 376.636026 -225.203258) (xy 376.636567 -225.175272) (xy 376.646025 -225.120104) (xy 376.654822 -225.09353)
			(xy 376.662442 -225.071432) (xy 376.458734 -224.718626) (xy 376.435874 -224.714308) (xy 376.410949 -224.709155)
			(xy 376.362963 -224.69219) (xy 376.318144 -224.668072) (xy 376.27755 -224.63737) (xy 376.24214 -224.60081)
			(xy 376.212752 -224.559256) (xy 376.19008 -224.513688) (xy 376.174658 -224.465184) (xy 376.166852 -224.41489)
			(xy 376.16638 -224.389442) (xy 375.887488 -224.389442) (xy 375.886979 -224.415409) (xy 375.878854 -224.466704)
			(xy 375.862806 -224.516097) (xy 375.839228 -224.562371) (xy 375.808702 -224.604387) (xy 375.771979 -224.64111)
			(xy 375.729963 -224.671636) (xy 375.683689 -224.695214) (xy 375.634296 -224.711262) (xy 375.583001 -224.719387)
			(xy 375.531067 -224.719387) (xy 375.479772 -224.711262) (xy 375.430379 -224.695214) (xy 375.384105 -224.671636)
			(xy 375.342089 -224.64111) (xy 375.305366 -224.604387) (xy 375.27484 -224.562371) (xy 375.251262 -224.516097)
			(xy 375.235214 -224.466704) (xy 375.227089 -224.415409) (xy 375.22658 -224.389442) (xy 374.947688 -224.389442)
			(xy 374.947146 -224.417428) (xy 374.937689 -224.472596) (xy 374.928892 -224.49917) (xy 374.921272 -224.521268)
			(xy 375.12498 -224.874074) (xy 375.14784 -224.878392) (xy 375.172767 -224.883535) (xy 375.220753 -224.900502)
			(xy 375.265572 -224.924622) (xy 375.306166 -224.955325) (xy 375.341575 -224.991886) (xy 375.370962 -225.033442)
			(xy 375.393635 -225.07901) (xy 375.409056 -225.127515) (xy 375.416862 -225.17781) (xy 375.417334 -225.203258)
			(xy 375.416825 -225.229225) (xy 375.696735 -225.229225) (xy 375.696735 -225.177291) (xy 375.70486 -225.125996)
			(xy 375.720908 -225.076603) (xy 375.744486 -225.030329) (xy 375.775012 -224.988313) (xy 375.811735 -224.95159)
			(xy 375.853751 -224.921064) (xy 375.900025 -224.897486) (xy 375.949418 -224.881438) (xy 376.000713 -224.873313)
			(xy 376.052647 -224.873313) (xy 376.103942 -224.881438) (xy 376.153335 -224.897486) (xy 376.199609 -224.921064)
			(xy 376.241625 -224.95159) (xy 376.278348 -224.988313) (xy 376.308874 -225.030329) (xy 376.332452 -225.076603)
			(xy 376.3485 -225.125996) (xy 376.356625 -225.177291) (xy 376.357134 -225.203258) (xy 376.356625 -225.229225)
			(xy 376.3485 -225.28052) (xy 376.332452 -225.329913) (xy 376.308874 -225.376187) (xy 376.278348 -225.418203)
			(xy 376.241625 -225.454926) (xy 376.199609 -225.485452) (xy 376.153335 -225.50903) (xy 376.103942 -225.525078)
			(xy 376.052647 -225.533203) (xy 376.000713 -225.533203) (xy 375.949418 -225.525078) (xy 375.900025 -225.50903)
			(xy 375.853751 -225.485452) (xy 375.811735 -225.454926) (xy 375.775012 -225.418203) (xy 375.744486 -225.376187)
			(xy 375.720908 -225.329913) (xy 375.70486 -225.28052) (xy 375.696735 -225.229225) (xy 375.416825 -225.229225)
			(xy 375.4087 -225.28052) (xy 375.392652 -225.329913) (xy 375.369074 -225.376187) (xy 375.338548 -225.418203)
			(xy 375.301825 -225.454926) (xy 375.259809 -225.485452) (xy 375.213535 -225.50903) (xy 375.164142 -225.525078)
			(xy 375.112847 -225.533203) (xy 375.060913 -225.533203) (xy 375.009618 -225.525078) (xy 374.960225 -225.50903)
			(xy 374.913951 -225.485452) (xy 374.871935 -225.454926) (xy 374.835212 -225.418203) (xy 374.804686 -225.376187)
			(xy 374.781108 -225.329913) (xy 374.76506 -225.28052) (xy 374.756935 -225.229225) (xy 374.756426 -225.203258)
			(xy 374.756967 -225.175272) (xy 374.766425 -225.120104) (xy 374.775222 -225.09353) (xy 374.782842 -225.071432)
			(xy 374.579134 -224.718626) (xy 374.556274 -224.714308) (xy 374.531349 -224.709155) (xy 374.483363 -224.69219)
			(xy 374.438544 -224.668072) (xy 374.39795 -224.63737) (xy 374.36254 -224.60081) (xy 374.333152 -224.559256)
			(xy 374.31048 -224.513688) (xy 374.295058 -224.465184) (xy 374.287252 -224.41489) (xy 374.28678 -224.389442)
			(xy 374.007888 -224.389442) (xy 374.007379 -224.415409) (xy 373.999254 -224.466704) (xy 373.983206 -224.516097)
			(xy 373.959628 -224.562371) (xy 373.929102 -224.604387) (xy 373.892379 -224.64111) (xy 373.850363 -224.671636)
			(xy 373.804089 -224.695214) (xy 373.754696 -224.711262) (xy 373.703401 -224.719387) (xy 373.651467 -224.719387)
			(xy 373.600172 -224.711262) (xy 373.550779 -224.695214) (xy 373.504505 -224.671636) (xy 373.462489 -224.64111)
			(xy 373.425766 -224.604387) (xy 373.39524 -224.562371) (xy 373.371662 -224.516097) (xy 373.355614 -224.466704)
			(xy 373.347489 -224.415409) (xy 373.34698 -224.389442) (xy 373.068088 -224.389442) (xy 373.067546 -224.417428)
			(xy 373.058089 -224.472596) (xy 373.049292 -224.49917) (xy 373.041672 -224.521268) (xy 373.24538 -224.874074)
			(xy 373.26824 -224.878392) (xy 373.293167 -224.883535) (xy 373.341153 -224.900502) (xy 373.385972 -224.924622)
			(xy 373.426566 -224.955325) (xy 373.461975 -224.991886) (xy 373.491362 -225.033442) (xy 373.514035 -225.07901)
			(xy 373.529456 -225.127515) (xy 373.537262 -225.17781) (xy 373.537734 -225.203258) (xy 373.537225 -225.229225)
			(xy 373.817135 -225.229225) (xy 373.817135 -225.177291) (xy 373.82526 -225.125996) (xy 373.841308 -225.076603)
			(xy 373.864886 -225.030329) (xy 373.895412 -224.988313) (xy 373.932135 -224.95159) (xy 373.974151 -224.921064)
			(xy 374.020425 -224.897486) (xy 374.069818 -224.881438) (xy 374.121113 -224.873313) (xy 374.173047 -224.873313)
			(xy 374.224342 -224.881438) (xy 374.273735 -224.897486) (xy 374.320009 -224.921064) (xy 374.362025 -224.95159)
			(xy 374.398748 -224.988313) (xy 374.429274 -225.030329) (xy 374.452852 -225.076603) (xy 374.4689 -225.125996)
			(xy 374.477025 -225.177291) (xy 374.477534 -225.203258) (xy 374.477025 -225.229225) (xy 374.4689 -225.28052)
			(xy 374.452852 -225.329913) (xy 374.429274 -225.376187) (xy 374.398748 -225.418203) (xy 374.362025 -225.454926)
			(xy 374.320009 -225.485452) (xy 374.273735 -225.50903) (xy 374.224342 -225.525078) (xy 374.173047 -225.533203)
			(xy 374.121113 -225.533203) (xy 374.069818 -225.525078) (xy 374.020425 -225.50903) (xy 373.974151 -225.485452)
			(xy 373.932135 -225.454926) (xy 373.895412 -225.418203) (xy 373.864886 -225.376187) (xy 373.841308 -225.329913)
			(xy 373.82526 -225.28052) (xy 373.817135 -225.229225) (xy 373.537225 -225.229225) (xy 373.5291 -225.28052)
			(xy 373.513052 -225.329913) (xy 373.489474 -225.376187) (xy 373.458948 -225.418203) (xy 373.422225 -225.454926)
			(xy 373.380209 -225.485452) (xy 373.333935 -225.50903) (xy 373.284542 -225.525078) (xy 373.233247 -225.533203)
			(xy 373.181313 -225.533203) (xy 373.130018 -225.525078) (xy 373.080625 -225.50903) (xy 373.034351 -225.485452)
			(xy 372.992335 -225.454926) (xy 372.955612 -225.418203) (xy 372.925086 -225.376187) (xy 372.901508 -225.329913)
			(xy 372.88546 -225.28052) (xy 372.877335 -225.229225) (xy 372.876826 -225.203258) (xy 372.877367 -225.175272)
			(xy 372.886825 -225.120104) (xy 372.895622 -225.09353) (xy 372.903242 -225.071432) (xy 372.699534 -224.718626)
			(xy 372.676674 -224.714308) (xy 372.651749 -224.709155) (xy 372.603763 -224.69219) (xy 372.558944 -224.668072)
			(xy 372.51835 -224.63737) (xy 372.48294 -224.60081) (xy 372.453552 -224.559256) (xy 372.43088 -224.513688)
			(xy 372.415458 -224.465184) (xy 372.407652 -224.41489) (xy 372.40718 -224.389442) (xy 372.128288 -224.389442)
			(xy 372.127779 -224.415409) (xy 372.119654 -224.466704) (xy 372.103606 -224.516097) (xy 372.080028 -224.562371)
			(xy 372.049502 -224.604387) (xy 372.012779 -224.64111) (xy 371.970763 -224.671636) (xy 371.924489 -224.695214)
			(xy 371.875096 -224.711262) (xy 371.823801 -224.719387) (xy 371.771867 -224.719387) (xy 371.720572 -224.711262)
			(xy 371.671179 -224.695214) (xy 371.624905 -224.671636) (xy 371.582889 -224.64111) (xy 371.546166 -224.604387)
			(xy 371.51564 -224.562371) (xy 371.492062 -224.516097) (xy 371.476014 -224.466704) (xy 371.467889 -224.415409)
			(xy 371.46738 -224.389442) (xy 371.188488 -224.389442) (xy 371.186964 -224.421192) (xy 371.219355 -224.454991)
			(xy 371.279016 -224.527145) (xy 371.332438 -224.604032) (xy 371.379249 -224.685113) (xy 371.419121 -224.769823)
			(xy 371.451775 -224.857568) (xy 371.46484 -224.902522) (xy 371.489167 -224.91423) (xy 371.53397 -224.944348)
			(xy 371.573288 -224.981341) (xy 371.606079 -225.024228) (xy 371.631471 -225.071869) (xy 371.648791 -225.123)
			(xy 371.657579 -225.176266) (xy 371.658134 -225.203258) (xy 371.657623 -225.229225) (xy 371.937535 -225.229225)
			(xy 371.937535 -225.177291) (xy 371.94566 -225.125996) (xy 371.961708 -225.076603) (xy 371.985286 -225.030329)
			(xy 372.015812 -224.988313) (xy 372.052535 -224.95159) (xy 372.094551 -224.921064) (xy 372.140825 -224.897486)
			(xy 372.190218 -224.881438) (xy 372.241513 -224.873313) (xy 372.293447 -224.873313) (xy 372.344742 -224.881438)
			(xy 372.394135 -224.897486) (xy 372.440409 -224.921064) (xy 372.482425 -224.95159) (xy 372.519148 -224.988313)
			(xy 372.549674 -225.030329) (xy 372.573252 -225.076603) (xy 372.5893 -225.125996) (xy 372.597425 -225.177291)
			(xy 372.597934 -225.203258) (xy 372.597425 -225.229225) (xy 372.5893 -225.28052) (xy 372.573252 -225.329913)
			(xy 372.549674 -225.376187) (xy 372.519148 -225.418203) (xy 372.482425 -225.454926) (xy 372.440409 -225.485452)
			(xy 372.394135 -225.50903) (xy 372.344742 -225.525078) (xy 372.293447 -225.533203) (xy 372.241513 -225.533203)
			(xy 372.190218 -225.525078) (xy 372.140825 -225.50903) (xy 372.094551 -225.485452) (xy 372.052535 -225.454926)
			(xy 372.015812 -225.418203) (xy 371.985286 -225.376187) (xy 371.961708 -225.329913) (xy 371.94566 -225.28052)
			(xy 371.937535 -225.229225) (xy 371.657623 -225.229225) (xy 371.657603 -225.230227) (xy 371.648847 -225.283449)
			(xy 371.631561 -225.334541) (xy 371.606204 -225.382147) (xy 371.57345 -225.425) (xy 371.534169 -225.461963)
			(xy 371.489405 -225.492054) (xy 371.465094 -225.50374) (xy 371.452053 -225.548773) (xy 371.419415 -225.636672)
			(xy 371.379529 -225.721528) (xy 371.332674 -225.802744) (xy 371.279181 -225.87975) (xy 371.219425 -225.952003)
			(xy 371.186964 -225.985832) (xy 371.188488 -226.017328) (xy 371.187969 -226.043295) (xy 371.467889 -226.043295)
			(xy 371.467889 -225.991361) (xy 371.476014 -225.940066) (xy 371.492062 -225.890673) (xy 371.51564 -225.844399)
			(xy 371.546166 -225.802383) (xy 371.582889 -225.76566) (xy 371.624905 -225.735134) (xy 371.671179 -225.711556)
			(xy 371.720572 -225.695508) (xy 371.771867 -225.687383) (xy 371.823801 -225.687383) (xy 371.875096 -225.695508)
			(xy 371.924489 -225.711556) (xy 371.970763 -225.735134) (xy 372.012779 -225.76566) (xy 372.049502 -225.802383)
			(xy 372.080028 -225.844399) (xy 372.103606 -225.890673) (xy 372.119654 -225.940066) (xy 372.127779 -225.991361)
			(xy 372.128288 -226.017328) (xy 372.127779 -226.043295) (xy 372.407689 -226.043295) (xy 372.407689 -225.991361)
			(xy 372.415814 -225.940066) (xy 372.431862 -225.890673) (xy 372.45544 -225.844399) (xy 372.485966 -225.802383)
			(xy 372.522689 -225.76566) (xy 372.564705 -225.735134) (xy 372.610979 -225.711556) (xy 372.660372 -225.695508)
			(xy 372.711667 -225.687383) (xy 372.763601 -225.687383) (xy 372.814896 -225.695508) (xy 372.864289 -225.711556)
			(xy 372.910563 -225.735134) (xy 372.952579 -225.76566) (xy 372.989302 -225.802383) (xy 373.019828 -225.844399)
			(xy 373.043406 -225.890673) (xy 373.059454 -225.940066) (xy 373.067579 -225.991361) (xy 373.068088 -226.017328)
			(xy 373.067579 -226.043295) (xy 373.347489 -226.043295) (xy 373.347489 -225.991361) (xy 373.355614 -225.940066)
			(xy 373.371662 -225.890673) (xy 373.39524 -225.844399) (xy 373.425766 -225.802383) (xy 373.462489 -225.76566)
			(xy 373.504505 -225.735134) (xy 373.550779 -225.711556) (xy 373.600172 -225.695508) (xy 373.651467 -225.687383)
			(xy 373.703401 -225.687383) (xy 373.754696 -225.695508) (xy 373.804089 -225.711556) (xy 373.850363 -225.735134)
			(xy 373.892379 -225.76566) (xy 373.929102 -225.802383) (xy 373.959628 -225.844399) (xy 373.983206 -225.890673)
			(xy 373.999254 -225.940066) (xy 374.007379 -225.991361) (xy 374.007888 -226.017328) (xy 374.007379 -226.043295)
			(xy 374.287289 -226.043295) (xy 374.287289 -225.991361) (xy 374.295414 -225.940066) (xy 374.311462 -225.890673)
			(xy 374.33504 -225.844399) (xy 374.365566 -225.802383) (xy 374.402289 -225.76566) (xy 374.444305 -225.735134)
			(xy 374.490579 -225.711556) (xy 374.539972 -225.695508) (xy 374.591267 -225.687383) (xy 374.643201 -225.687383)
			(xy 374.694496 -225.695508) (xy 374.743889 -225.711556) (xy 374.790163 -225.735134) (xy 374.832179 -225.76566)
			(xy 374.868902 -225.802383) (xy 374.899428 -225.844399) (xy 374.923006 -225.890673) (xy 374.939054 -225.940066)
			(xy 374.947179 -225.991361) (xy 374.947688 -226.017328) (xy 374.947179 -226.043295) (xy 375.227089 -226.043295)
			(xy 375.227089 -225.991361) (xy 375.235214 -225.940066) (xy 375.251262 -225.890673) (xy 375.27484 -225.844399)
			(xy 375.305366 -225.802383) (xy 375.342089 -225.76566) (xy 375.384105 -225.735134) (xy 375.430379 -225.711556)
			(xy 375.479772 -225.695508) (xy 375.531067 -225.687383) (xy 375.583001 -225.687383) (xy 375.634296 -225.695508)
			(xy 375.683689 -225.711556) (xy 375.729963 -225.735134) (xy 375.771979 -225.76566) (xy 375.808702 -225.802383)
			(xy 375.839228 -225.844399) (xy 375.862806 -225.890673) (xy 375.878854 -225.940066) (xy 375.886979 -225.991361)
			(xy 375.887488 -226.017328) (xy 375.886979 -226.043295) (xy 376.166889 -226.043295) (xy 376.166889 -225.991361)
			(xy 376.175014 -225.940066) (xy 376.191062 -225.890673) (xy 376.21464 -225.844399) (xy 376.245166 -225.802383)
			(xy 376.281889 -225.76566) (xy 376.323905 -225.735134) (xy 376.370179 -225.711556) (xy 376.419572 -225.695508)
			(xy 376.470867 -225.687383) (xy 376.522801 -225.687383) (xy 376.574096 -225.695508) (xy 376.623489 -225.711556)
			(xy 376.669763 -225.735134) (xy 376.711779 -225.76566) (xy 376.748502 -225.802383) (xy 376.779028 -225.844399)
			(xy 376.802606 -225.890673) (xy 376.818654 -225.940066) (xy 376.826779 -225.991361) (xy 376.827288 -226.017328)
			(xy 376.826779 -226.043295) (xy 377.106689 -226.043295) (xy 377.106689 -225.991361) (xy 377.114814 -225.940066)
			(xy 377.130862 -225.890673) (xy 377.15444 -225.844399) (xy 377.184966 -225.802383) (xy 377.221689 -225.76566)
			(xy 377.263705 -225.735134) (xy 377.309979 -225.711556) (xy 377.359372 -225.695508) (xy 377.410667 -225.687383)
			(xy 377.462601 -225.687383) (xy 377.513896 -225.695508) (xy 377.563289 -225.711556) (xy 377.609563 -225.735134)
			(xy 377.651579 -225.76566) (xy 377.688302 -225.802383) (xy 377.718828 -225.844399) (xy 377.742406 -225.890673)
			(xy 377.758454 -225.940066) (xy 377.766579 -225.991361) (xy 377.767088 -226.017328) (xy 377.766579 -226.043295)
			(xy 378.046489 -226.043295) (xy 378.046489 -225.991361) (xy 378.054614 -225.940066) (xy 378.070662 -225.890673)
			(xy 378.09424 -225.844399) (xy 378.124766 -225.802383) (xy 378.161489 -225.76566) (xy 378.203505 -225.735134)
			(xy 378.249779 -225.711556) (xy 378.299172 -225.695508) (xy 378.350467 -225.687383) (xy 378.402401 -225.687383)
			(xy 378.453696 -225.695508) (xy 378.503089 -225.711556) (xy 378.549363 -225.735134) (xy 378.591379 -225.76566)
			(xy 378.628102 -225.802383) (xy 378.658628 -225.844399) (xy 378.682206 -225.890673) (xy 378.698254 -225.940066)
			(xy 378.706379 -225.991361) (xy 378.706888 -226.017328) (xy 378.706379 -226.043295) (xy 378.986289 -226.043295)
			(xy 378.986289 -225.991361) (xy 378.994414 -225.940066) (xy 379.010462 -225.890673) (xy 379.03404 -225.844399)
			(xy 379.064566 -225.802383) (xy 379.101289 -225.76566) (xy 379.143305 -225.735134) (xy 379.189579 -225.711556)
			(xy 379.238972 -225.695508) (xy 379.290267 -225.687383) (xy 379.342201 -225.687383) (xy 379.393496 -225.695508)
			(xy 379.442889 -225.711556) (xy 379.489163 -225.735134) (xy 379.531179 -225.76566) (xy 379.567902 -225.802383)
			(xy 379.598428 -225.844399) (xy 379.622006 -225.890673) (xy 379.638054 -225.940066) (xy 379.646179 -225.991361)
			(xy 379.646688 -226.017328) (xy 379.646179 -226.043295) (xy 379.926089 -226.043295) (xy 379.926089 -225.991361)
			(xy 379.934214 -225.940066) (xy 379.950262 -225.890673) (xy 379.97384 -225.844399) (xy 380.004366 -225.802383)
			(xy 380.041089 -225.76566) (xy 380.083105 -225.735134) (xy 380.129379 -225.711556) (xy 380.178772 -225.695508)
			(xy 380.230067 -225.687383) (xy 380.282001 -225.687383) (xy 380.333296 -225.695508) (xy 380.382689 -225.711556)
			(xy 380.428963 -225.735134) (xy 380.470979 -225.76566) (xy 380.507702 -225.802383) (xy 380.538228 -225.844399)
			(xy 380.561806 -225.890673) (xy 380.577854 -225.940066) (xy 380.585979 -225.991361) (xy 380.586488 -226.017328)
			(xy 380.585979 -226.043295) (xy 380.865889 -226.043295) (xy 380.865889 -225.991361) (xy 380.874014 -225.940066)
			(xy 380.890062 -225.890673) (xy 380.91364 -225.844399) (xy 380.944166 -225.802383) (xy 380.980889 -225.76566)
			(xy 381.022905 -225.735134) (xy 381.069179 -225.711556) (xy 381.118572 -225.695508) (xy 381.169867 -225.687383)
			(xy 381.221801 -225.687383) (xy 381.273096 -225.695508) (xy 381.322489 -225.711556) (xy 381.368763 -225.735134)
			(xy 381.410779 -225.76566) (xy 381.447502 -225.802383) (xy 381.478028 -225.844399) (xy 381.501606 -225.890673)
			(xy 381.517654 -225.940066) (xy 381.525779 -225.991361) (xy 381.526288 -226.017328) (xy 381.525779 -226.043295)
			(xy 381.517654 -226.09459) (xy 381.501606 -226.143983) (xy 381.478028 -226.190257) (xy 381.447502 -226.232273)
			(xy 381.410779 -226.268996) (xy 381.368763 -226.299522) (xy 381.322489 -226.3231) (xy 381.273096 -226.339148)
			(xy 381.221801 -226.347273) (xy 381.169867 -226.347273) (xy 381.118572 -226.339148) (xy 381.069179 -226.3231)
			(xy 381.022905 -226.299522) (xy 380.980889 -226.268996) (xy 380.944166 -226.232273) (xy 380.91364 -226.190257)
			(xy 380.890062 -226.143983) (xy 380.874014 -226.09459) (xy 380.865889 -226.043295) (xy 380.585979 -226.043295)
			(xy 380.577854 -226.09459) (xy 380.561806 -226.143983) (xy 380.538228 -226.190257) (xy 380.507702 -226.232273)
			(xy 380.470979 -226.268996) (xy 380.428963 -226.299522) (xy 380.382689 -226.3231) (xy 380.333296 -226.339148)
			(xy 380.282001 -226.347273) (xy 380.230067 -226.347273) (xy 380.178772 -226.339148) (xy 380.129379 -226.3231)
			(xy 380.083105 -226.299522) (xy 380.041089 -226.268996) (xy 380.004366 -226.232273) (xy 379.97384 -226.190257)
			(xy 379.950262 -226.143983) (xy 379.934214 -226.09459) (xy 379.926089 -226.043295) (xy 379.646179 -226.043295)
			(xy 379.638054 -226.09459) (xy 379.622006 -226.143983) (xy 379.598428 -226.190257) (xy 379.567902 -226.232273)
			(xy 379.531179 -226.268996) (xy 379.489163 -226.299522) (xy 379.442889 -226.3231) (xy 379.393496 -226.339148)
			(xy 379.342201 -226.347273) (xy 379.290267 -226.347273) (xy 379.238972 -226.339148) (xy 379.189579 -226.3231)
			(xy 379.143305 -226.299522) (xy 379.101289 -226.268996) (xy 379.064566 -226.232273) (xy 379.03404 -226.190257)
			(xy 379.010462 -226.143983) (xy 378.994414 -226.09459) (xy 378.986289 -226.043295) (xy 378.706379 -226.043295)
			(xy 378.698254 -226.09459) (xy 378.682206 -226.143983) (xy 378.658628 -226.190257) (xy 378.628102 -226.232273)
			(xy 378.591379 -226.268996) (xy 378.549363 -226.299522) (xy 378.503089 -226.3231) (xy 378.453696 -226.339148)
			(xy 378.402401 -226.347273) (xy 378.350467 -226.347273) (xy 378.299172 -226.339148) (xy 378.249779 -226.3231)
			(xy 378.203505 -226.299522) (xy 378.161489 -226.268996) (xy 378.124766 -226.232273) (xy 378.09424 -226.190257)
			(xy 378.070662 -226.143983) (xy 378.054614 -226.09459) (xy 378.046489 -226.043295) (xy 377.766579 -226.043295)
			(xy 377.758454 -226.09459) (xy 377.742406 -226.143983) (xy 377.718828 -226.190257) (xy 377.688302 -226.232273)
			(xy 377.651579 -226.268996) (xy 377.609563 -226.299522) (xy 377.563289 -226.3231) (xy 377.513896 -226.339148)
			(xy 377.462601 -226.347273) (xy 377.410667 -226.347273) (xy 377.359372 -226.339148) (xy 377.309979 -226.3231)
			(xy 377.263705 -226.299522) (xy 377.221689 -226.268996) (xy 377.184966 -226.232273) (xy 377.15444 -226.190257)
			(xy 377.130862 -226.143983) (xy 377.114814 -226.09459) (xy 377.106689 -226.043295) (xy 376.826779 -226.043295)
			(xy 376.818654 -226.09459) (xy 376.802606 -226.143983) (xy 376.779028 -226.190257) (xy 376.748502 -226.232273)
			(xy 376.711779 -226.268996) (xy 376.669763 -226.299522) (xy 376.623489 -226.3231) (xy 376.574096 -226.339148)
			(xy 376.522801 -226.347273) (xy 376.470867 -226.347273) (xy 376.419572 -226.339148) (xy 376.370179 -226.3231)
			(xy 376.323905 -226.299522) (xy 376.281889 -226.268996) (xy 376.245166 -226.232273) (xy 376.21464 -226.190257)
			(xy 376.191062 -226.143983) (xy 376.175014 -226.09459) (xy 376.166889 -226.043295) (xy 375.886979 -226.043295)
			(xy 375.878854 -226.09459) (xy 375.862806 -226.143983) (xy 375.839228 -226.190257) (xy 375.808702 -226.232273)
			(xy 375.771979 -226.268996) (xy 375.729963 -226.299522) (xy 375.683689 -226.3231) (xy 375.634296 -226.339148)
			(xy 375.583001 -226.347273) (xy 375.531067 -226.347273) (xy 375.479772 -226.339148) (xy 375.430379 -226.3231)
			(xy 375.384105 -226.299522) (xy 375.342089 -226.268996) (xy 375.305366 -226.232273) (xy 375.27484 -226.190257)
			(xy 375.251262 -226.143983) (xy 375.235214 -226.09459) (xy 375.227089 -226.043295) (xy 374.947179 -226.043295)
			(xy 374.939054 -226.09459) (xy 374.923006 -226.143983) (xy 374.899428 -226.190257) (xy 374.868902 -226.232273)
			(xy 374.832179 -226.268996) (xy 374.790163 -226.299522) (xy 374.743889 -226.3231) (xy 374.694496 -226.339148)
			(xy 374.643201 -226.347273) (xy 374.591267 -226.347273) (xy 374.539972 -226.339148) (xy 374.490579 -226.3231)
			(xy 374.444305 -226.299522) (xy 374.402289 -226.268996) (xy 374.365566 -226.232273) (xy 374.33504 -226.190257)
			(xy 374.311462 -226.143983) (xy 374.295414 -226.09459) (xy 374.287289 -226.043295) (xy 374.007379 -226.043295)
			(xy 373.999254 -226.09459) (xy 373.983206 -226.143983) (xy 373.959628 -226.190257) (xy 373.929102 -226.232273)
			(xy 373.892379 -226.268996) (xy 373.850363 -226.299522) (xy 373.804089 -226.3231) (xy 373.754696 -226.339148)
			(xy 373.703401 -226.347273) (xy 373.651467 -226.347273) (xy 373.600172 -226.339148) (xy 373.550779 -226.3231)
			(xy 373.504505 -226.299522) (xy 373.462489 -226.268996) (xy 373.425766 -226.232273) (xy 373.39524 -226.190257)
			(xy 373.371662 -226.143983) (xy 373.355614 -226.09459) (xy 373.347489 -226.043295) (xy 373.067579 -226.043295)
			(xy 373.059454 -226.09459) (xy 373.043406 -226.143983) (xy 373.019828 -226.190257) (xy 372.989302 -226.232273)
			(xy 372.952579 -226.268996) (xy 372.910563 -226.299522) (xy 372.864289 -226.3231) (xy 372.814896 -226.339148)
			(xy 372.763601 -226.347273) (xy 372.711667 -226.347273) (xy 372.660372 -226.339148) (xy 372.610979 -226.3231)
			(xy 372.564705 -226.299522) (xy 372.522689 -226.268996) (xy 372.485966 -226.232273) (xy 372.45544 -226.190257)
			(xy 372.431862 -226.143983) (xy 372.415814 -226.09459) (xy 372.407689 -226.043295) (xy 372.127779 -226.043295)
			(xy 372.119654 -226.09459) (xy 372.103606 -226.143983) (xy 372.080028 -226.190257) (xy 372.049502 -226.232273)
			(xy 372.012779 -226.268996) (xy 371.970763 -226.299522) (xy 371.924489 -226.3231) (xy 371.875096 -226.339148)
			(xy 371.823801 -226.347273) (xy 371.771867 -226.347273) (xy 371.720572 -226.339148) (xy 371.671179 -226.3231)
			(xy 371.624905 -226.299522) (xy 371.582889 -226.268996) (xy 371.546166 -226.232273) (xy 371.51564 -226.190257)
			(xy 371.492062 -226.143983) (xy 371.476014 -226.09459) (xy 371.467889 -226.043295) (xy 371.187969 -226.043295)
			(xy 371.187948 -226.044335) (xy 371.179157 -226.097629) (xy 371.161815 -226.148784) (xy 371.136382 -226.196436)
			(xy 371.103537 -226.239317) (xy 371.064154 -226.276283) (xy 371.019282 -226.306352) (xy 370.99494 -226.318064)
			(xy 370.981878 -226.363052) (xy 370.949211 -226.450858) (xy 370.909309 -226.535622) (xy 370.862454 -226.616749)
			(xy 370.808974 -226.69367) (xy 370.749244 -226.765846) (xy 370.71681 -226.799648) (xy 370.718334 -226.831144)
			(xy 370.717814 -226.857111) (xy 370.997735 -226.857111) (xy 370.997735 -226.805177) (xy 371.00586 -226.753882)
			(xy 371.021908 -226.704489) (xy 371.045486 -226.658215) (xy 371.076012 -226.616199) (xy 371.112735 -226.579476)
			(xy 371.154751 -226.54895) (xy 371.201025 -226.525372) (xy 371.250418 -226.509324) (xy 371.301713 -226.501199)
			(xy 371.353647 -226.501199) (xy 371.404942 -226.509324) (xy 371.454335 -226.525372) (xy 371.500609 -226.54895)
			(xy 371.542625 -226.579476) (xy 371.579348 -226.616199) (xy 371.609874 -226.658215) (xy 371.633452 -226.704489)
			(xy 371.6495 -226.753882) (xy 371.657625 -226.805177) (xy 371.658134 -226.831144) (xy 371.657625 -226.857111)
			(xy 371.937789 -226.857111) (xy 371.937789 -226.805177) (xy 371.945914 -226.753882) (xy 371.961962 -226.704489)
			(xy 371.98554 -226.658215) (xy 372.016066 -226.616199) (xy 372.052789 -226.579476) (xy 372.094805 -226.54895)
			(xy 372.141079 -226.525372) (xy 372.190472 -226.509324) (xy 372.241767 -226.501199) (xy 372.293701 -226.501199)
			(xy 372.344996 -226.509324) (xy 372.394389 -226.525372) (xy 372.440663 -226.54895) (xy 372.482679 -226.579476)
			(xy 372.519402 -226.616199) (xy 372.549928 -226.658215) (xy 372.573506 -226.704489) (xy 372.589554 -226.753882)
			(xy 372.597679 -226.805177) (xy 372.598188 -226.831144) (xy 372.597679 -226.857111) (xy 372.877335 -226.857111)
			(xy 372.877335 -226.805177) (xy 372.88546 -226.753882) (xy 372.901508 -226.704489) (xy 372.925086 -226.658215)
			(xy 372.955612 -226.616199) (xy 372.992335 -226.579476) (xy 373.034351 -226.54895) (xy 373.080625 -226.525372)
			(xy 373.130018 -226.509324) (xy 373.181313 -226.501199) (xy 373.233247 -226.501199) (xy 373.284542 -226.509324)
			(xy 373.333935 -226.525372) (xy 373.380209 -226.54895) (xy 373.422225 -226.579476) (xy 373.458948 -226.616199)
			(xy 373.489474 -226.658215) (xy 373.513052 -226.704489) (xy 373.5291 -226.753882) (xy 373.537225 -226.805177)
			(xy 373.537734 -226.831144) (xy 373.537225 -226.857111) (xy 373.817135 -226.857111) (xy 373.817135 -226.805177)
			(xy 373.82526 -226.753882) (xy 373.841308 -226.704489) (xy 373.864886 -226.658215) (xy 373.895412 -226.616199)
			(xy 373.932135 -226.579476) (xy 373.974151 -226.54895) (xy 374.020425 -226.525372) (xy 374.069818 -226.509324)
			(xy 374.121113 -226.501199) (xy 374.173047 -226.501199) (xy 374.224342 -226.509324) (xy 374.273735 -226.525372)
			(xy 374.320009 -226.54895) (xy 374.362025 -226.579476) (xy 374.398748 -226.616199) (xy 374.429274 -226.658215)
			(xy 374.452852 -226.704489) (xy 374.4689 -226.753882) (xy 374.477025 -226.805177) (xy 374.477534 -226.831144)
			(xy 374.477025 -226.857111) (xy 374.757189 -226.857111) (xy 374.757189 -226.805177) (xy 374.765314 -226.753882)
			(xy 374.781362 -226.704489) (xy 374.80494 -226.658215) (xy 374.835466 -226.616199) (xy 374.872189 -226.579476)
			(xy 374.914205 -226.54895) (xy 374.960479 -226.525372) (xy 375.009872 -226.509324) (xy 375.061167 -226.501199)
			(xy 375.113101 -226.501199) (xy 375.164396 -226.509324) (xy 375.213789 -226.525372) (xy 375.260063 -226.54895)
			(xy 375.302079 -226.579476) (xy 375.338802 -226.616199) (xy 375.369328 -226.658215) (xy 375.392906 -226.704489)
			(xy 375.408954 -226.753882) (xy 375.417079 -226.805177) (xy 375.417588 -226.831144) (xy 375.417079 -226.857111)
			(xy 375.408954 -226.908406) (xy 375.392906 -226.957799) (xy 375.369328 -227.004073) (xy 375.338802 -227.046089)
			(xy 375.302079 -227.082812) (xy 375.260063 -227.113338) (xy 375.213789 -227.136916) (xy 375.164396 -227.152964)
			(xy 375.113101 -227.161089) (xy 375.061167 -227.161089) (xy 375.009872 -227.152964) (xy 374.960479 -227.136916)
			(xy 374.914205 -227.113338) (xy 374.872189 -227.082812) (xy 374.835466 -227.046089) (xy 374.80494 -227.004073)
			(xy 374.781362 -226.957799) (xy 374.765314 -226.908406) (xy 374.757189 -226.857111) (xy 374.477025 -226.857111)
			(xy 374.4689 -226.908406) (xy 374.452852 -226.957799) (xy 374.429274 -227.004073) (xy 374.398748 -227.046089)
			(xy 374.362025 -227.082812) (xy 374.320009 -227.113338) (xy 374.273735 -227.136916) (xy 374.224342 -227.152964)
			(xy 374.173047 -227.161089) (xy 374.121113 -227.161089) (xy 374.069818 -227.152964) (xy 374.020425 -227.136916)
			(xy 373.974151 -227.113338) (xy 373.932135 -227.082812) (xy 373.895412 -227.046089) (xy 373.864886 -227.004073)
			(xy 373.841308 -226.957799) (xy 373.82526 -226.908406) (xy 373.817135 -226.857111) (xy 373.537225 -226.857111)
			(xy 373.5291 -226.908406) (xy 373.513052 -226.957799) (xy 373.489474 -227.004073) (xy 373.458948 -227.046089)
			(xy 373.422225 -227.082812) (xy 373.380209 -227.113338) (xy 373.333935 -227.136916) (xy 373.284542 -227.152964)
			(xy 373.233247 -227.161089) (xy 373.181313 -227.161089) (xy 373.130018 -227.152964) (xy 373.080625 -227.136916)
			(xy 373.034351 -227.113338) (xy 372.992335 -227.082812) (xy 372.955612 -227.046089) (xy 372.925086 -227.004073)
			(xy 372.901508 -226.957799) (xy 372.88546 -226.908406) (xy 372.877335 -226.857111) (xy 372.597679 -226.857111)
			(xy 372.589554 -226.908406) (xy 372.573506 -226.957799) (xy 372.549928 -227.004073) (xy 372.519402 -227.046089)
			(xy 372.482679 -227.082812) (xy 372.440663 -227.113338) (xy 372.394389 -227.136916) (xy 372.344996 -227.152964)
			(xy 372.293701 -227.161089) (xy 372.241767 -227.161089) (xy 372.190472 -227.152964) (xy 372.141079 -227.136916)
			(xy 372.094805 -227.113338) (xy 372.052789 -227.082812) (xy 372.016066 -227.046089) (xy 371.98554 -227.004073)
			(xy 371.961962 -226.957799) (xy 371.945914 -226.908406) (xy 371.937789 -226.857111) (xy 371.657625 -226.857111)
			(xy 371.6495 -226.908406) (xy 371.633452 -226.957799) (xy 371.609874 -227.004073) (xy 371.579348 -227.046089)
			(xy 371.542625 -227.082812) (xy 371.500609 -227.113338) (xy 371.454335 -227.136916) (xy 371.404942 -227.152964)
			(xy 371.353647 -227.161089) (xy 371.301713 -227.161089) (xy 371.250418 -227.152964) (xy 371.201025 -227.136916)
			(xy 371.154751 -227.113338) (xy 371.112735 -227.082812) (xy 371.076012 -227.046089) (xy 371.045486 -227.004073)
			(xy 371.021908 -226.957799) (xy 371.00586 -226.908406) (xy 370.997735 -226.857111) (xy 370.717814 -226.857111)
			(xy 370.717794 -226.858124) (xy 370.709015 -226.911365) (xy 370.691696 -226.96247) (xy 370.666299 -227.01008)
			(xy 370.6335 -227.052927) (xy 370.594172 -227.089872) (xy 370.54936 -227.119932) (xy 370.52504 -227.131626)
			(xy 370.511994 -227.176638) (xy 370.479348 -227.264494) (xy 370.439456 -227.349305) (xy 370.392598 -227.430476)
			(xy 370.339105 -227.507436) (xy 370.279352 -227.579643) (xy 370.24691 -227.613464) (xy 370.248434 -227.64496)
			(xy 370.247922 -227.670927) (xy 370.528089 -227.670927) (xy 370.528089 -227.618993) (xy 370.536214 -227.567698)
			(xy 370.552262 -227.518305) (xy 370.57584 -227.472031) (xy 370.606366 -227.430015) (xy 370.643089 -227.393292)
			(xy 370.685105 -227.362766) (xy 370.731379 -227.339188) (xy 370.780772 -227.32314) (xy 370.832067 -227.315015)
			(xy 370.884001 -227.315015) (xy 370.935296 -227.32314) (xy 370.984689 -227.339188) (xy 371.030963 -227.362766)
			(xy 371.072979 -227.393292) (xy 371.109702 -227.430015) (xy 371.140228 -227.472031) (xy 371.163806 -227.518305)
			(xy 371.179854 -227.567698) (xy 371.187979 -227.618993) (xy 371.188488 -227.64496) (xy 371.187979 -227.670927)
			(xy 371.467889 -227.670927) (xy 371.467889 -227.618993) (xy 371.476014 -227.567698) (xy 371.492062 -227.518305)
			(xy 371.51564 -227.472031) (xy 371.546166 -227.430015) (xy 371.582889 -227.393292) (xy 371.624905 -227.362766)
			(xy 371.671179 -227.339188) (xy 371.720572 -227.32314) (xy 371.771867 -227.315015) (xy 371.823801 -227.315015)
			(xy 371.875096 -227.32314) (xy 371.924489 -227.339188) (xy 371.970763 -227.362766) (xy 372.012779 -227.393292)
			(xy 372.049502 -227.430015) (xy 372.080028 -227.472031) (xy 372.103606 -227.518305) (xy 372.119654 -227.567698)
			(xy 372.127779 -227.618993) (xy 372.128288 -227.64496) (xy 372.127779 -227.670927) (xy 372.407689 -227.670927)
			(xy 372.407689 -227.618993) (xy 372.415814 -227.567698) (xy 372.431862 -227.518305) (xy 372.45544 -227.472031)
			(xy 372.485966 -227.430015) (xy 372.522689 -227.393292) (xy 372.564705 -227.362766) (xy 372.610979 -227.339188)
			(xy 372.660372 -227.32314) (xy 372.711667 -227.315015) (xy 372.763601 -227.315015) (xy 372.814896 -227.32314)
			(xy 372.864289 -227.339188) (xy 372.910563 -227.362766) (xy 372.952579 -227.393292) (xy 372.989302 -227.430015)
			(xy 373.019828 -227.472031) (xy 373.043406 -227.518305) (xy 373.059454 -227.567698) (xy 373.067579 -227.618993)
			(xy 373.068088 -227.64496) (xy 373.067579 -227.670927) (xy 373.347489 -227.670927) (xy 373.347489 -227.618993)
			(xy 373.355614 -227.567698) (xy 373.371662 -227.518305) (xy 373.39524 -227.472031) (xy 373.425766 -227.430015)
			(xy 373.462489 -227.393292) (xy 373.504505 -227.362766) (xy 373.550779 -227.339188) (xy 373.600172 -227.32314)
			(xy 373.651467 -227.315015) (xy 373.703401 -227.315015) (xy 373.754696 -227.32314) (xy 373.804089 -227.339188)
			(xy 373.850363 -227.362766) (xy 373.892379 -227.393292) (xy 373.929102 -227.430015) (xy 373.959628 -227.472031)
			(xy 373.983206 -227.518305) (xy 373.999254 -227.567698) (xy 374.007379 -227.618993) (xy 374.007888 -227.64496)
			(xy 374.007379 -227.670927) (xy 374.287289 -227.670927) (xy 374.287289 -227.618993) (xy 374.295414 -227.567698)
			(xy 374.311462 -227.518305) (xy 374.33504 -227.472031) (xy 374.365566 -227.430015) (xy 374.402289 -227.393292)
			(xy 374.444305 -227.362766) (xy 374.490579 -227.339188) (xy 374.539972 -227.32314) (xy 374.591267 -227.315015)
			(xy 374.643201 -227.315015) (xy 374.694496 -227.32314) (xy 374.743889 -227.339188) (xy 374.790163 -227.362766)
			(xy 374.832179 -227.393292) (xy 374.868902 -227.430015) (xy 374.899428 -227.472031) (xy 374.923006 -227.518305)
			(xy 374.939054 -227.567698) (xy 374.947179 -227.618993) (xy 374.947688 -227.64496) (xy 374.947179 -227.670927)
			(xy 374.939054 -227.722222) (xy 374.923006 -227.771615) (xy 374.899428 -227.817889) (xy 374.868902 -227.859905)
			(xy 374.832179 -227.896628) (xy 374.790163 -227.927154) (xy 374.743889 -227.950732) (xy 374.694496 -227.96678)
			(xy 374.643201 -227.974905) (xy 374.591267 -227.974905) (xy 374.539972 -227.96678) (xy 374.490579 -227.950732)
			(xy 374.444305 -227.927154) (xy 374.402289 -227.896628) (xy 374.365566 -227.859905) (xy 374.33504 -227.817889)
			(xy 374.311462 -227.771615) (xy 374.295414 -227.722222) (xy 374.287289 -227.670927) (xy 374.007379 -227.670927)
			(xy 373.999254 -227.722222) (xy 373.983206 -227.771615) (xy 373.959628 -227.817889) (xy 373.929102 -227.859905)
			(xy 373.892379 -227.896628) (xy 373.850363 -227.927154) (xy 373.804089 -227.950732) (xy 373.754696 -227.96678)
			(xy 373.703401 -227.974905) (xy 373.651467 -227.974905) (xy 373.600172 -227.96678) (xy 373.550779 -227.950732)
			(xy 373.504505 -227.927154) (xy 373.462489 -227.896628) (xy 373.425766 -227.859905) (xy 373.39524 -227.817889)
			(xy 373.371662 -227.771615) (xy 373.355614 -227.722222) (xy 373.347489 -227.670927) (xy 373.067579 -227.670927)
			(xy 373.059454 -227.722222) (xy 373.043406 -227.771615) (xy 373.019828 -227.817889) (xy 372.989302 -227.859905)
			(xy 372.952579 -227.896628) (xy 372.910563 -227.927154) (xy 372.864289 -227.950732) (xy 372.814896 -227.96678)
			(xy 372.763601 -227.974905) (xy 372.711667 -227.974905) (xy 372.660372 -227.96678) (xy 372.610979 -227.950732)
			(xy 372.564705 -227.927154) (xy 372.522689 -227.896628) (xy 372.485966 -227.859905) (xy 372.45544 -227.817889)
			(xy 372.431862 -227.771615) (xy 372.415814 -227.722222) (xy 372.407689 -227.670927) (xy 372.127779 -227.670927)
			(xy 372.119654 -227.722222) (xy 372.103606 -227.771615) (xy 372.080028 -227.817889) (xy 372.049502 -227.859905)
			(xy 372.012779 -227.896628) (xy 371.970763 -227.927154) (xy 371.924489 -227.950732) (xy 371.875096 -227.96678)
			(xy 371.823801 -227.974905) (xy 371.771867 -227.974905) (xy 371.720572 -227.96678) (xy 371.671179 -227.950732)
			(xy 371.624905 -227.927154) (xy 371.582889 -227.896628) (xy 371.546166 -227.859905) (xy 371.51564 -227.817889)
			(xy 371.492062 -227.771615) (xy 371.476014 -227.722222) (xy 371.467889 -227.670927) (xy 371.187979 -227.670927)
			(xy 371.179854 -227.722222) (xy 371.163806 -227.771615) (xy 371.140228 -227.817889) (xy 371.109702 -227.859905)
			(xy 371.072979 -227.896628) (xy 371.030963 -227.927154) (xy 370.984689 -227.950732) (xy 370.935296 -227.96678)
			(xy 370.884001 -227.974905) (xy 370.832067 -227.974905) (xy 370.780772 -227.96678) (xy 370.731379 -227.950732)
			(xy 370.685105 -227.927154) (xy 370.643089 -227.896628) (xy 370.606366 -227.859905) (xy 370.57584 -227.817889)
			(xy 370.552262 -227.771615) (xy 370.536214 -227.722222) (xy 370.528089 -227.670927) (xy 370.247922 -227.670927)
			(xy 370.247902 -227.671929) (xy 370.239146 -227.725151) (xy 370.22186 -227.776243) (xy 370.196503 -227.823848)
			(xy 370.163749 -227.866701) (xy 370.124468 -227.903664) (xy 370.079704 -227.933754) (xy 370.055394 -227.945442)
			(xy 370.04233 -227.99048) (xy 370.009647 -228.078384) (xy 369.969716 -228.163242) (xy 369.922819 -228.244457)
			(xy 369.869284 -228.321459) (xy 369.809487 -228.393707) (xy 369.77701 -228.427534) (xy 369.778534 -228.45903)
			(xy 369.778024 -228.484997) (xy 370.057935 -228.484997) (xy 370.057935 -228.433063) (xy 370.06606 -228.381768)
			(xy 370.082108 -228.332375) (xy 370.105686 -228.286101) (xy 370.136212 -228.244085) (xy 370.172935 -228.207362)
			(xy 370.214951 -228.176836) (xy 370.261225 -228.153258) (xy 370.310618 -228.13721) (xy 370.361913 -228.129085)
			(xy 370.413847 -228.129085) (xy 370.465142 -228.13721) (xy 370.514535 -228.153258) (xy 370.560809 -228.176836)
			(xy 370.602825 -228.207362) (xy 370.639548 -228.244085) (xy 370.670074 -228.286101) (xy 370.693652 -228.332375)
			(xy 370.7097 -228.381768) (xy 370.717825 -228.433063) (xy 370.718334 -228.45903) (xy 370.717825 -228.484997)
			(xy 370.997735 -228.484997) (xy 370.997735 -228.433063) (xy 371.00586 -228.381768) (xy 371.021908 -228.332375)
			(xy 371.045486 -228.286101) (xy 371.076012 -228.244085) (xy 371.112735 -228.207362) (xy 371.154751 -228.176836)
			(xy 371.201025 -228.153258) (xy 371.250418 -228.13721) (xy 371.301713 -228.129085) (xy 371.353647 -228.129085)
			(xy 371.404942 -228.13721) (xy 371.454335 -228.153258) (xy 371.500609 -228.176836) (xy 371.542625 -228.207362)
			(xy 371.579348 -228.244085) (xy 371.609874 -228.286101) (xy 371.633452 -228.332375) (xy 371.6495 -228.381768)
			(xy 371.657625 -228.433063) (xy 371.658134 -228.45903) (xy 371.657625 -228.484997) (xy 371.937535 -228.484997)
			(xy 371.937535 -228.433063) (xy 371.94566 -228.381768) (xy 371.961708 -228.332375) (xy 371.985286 -228.286101)
			(xy 372.015812 -228.244085) (xy 372.052535 -228.207362) (xy 372.094551 -228.176836) (xy 372.140825 -228.153258)
			(xy 372.190218 -228.13721) (xy 372.241513 -228.129085) (xy 372.293447 -228.129085) (xy 372.344742 -228.13721)
			(xy 372.394135 -228.153258) (xy 372.440409 -228.176836) (xy 372.482425 -228.207362) (xy 372.519148 -228.244085)
			(xy 372.549674 -228.286101) (xy 372.573252 -228.332375) (xy 372.5893 -228.381768) (xy 372.597425 -228.433063)
			(xy 372.597934 -228.45903) (xy 372.597425 -228.484997) (xy 372.877335 -228.484997) (xy 372.877335 -228.433063)
			(xy 372.88546 -228.381768) (xy 372.901508 -228.332375) (xy 372.925086 -228.286101) (xy 372.955612 -228.244085)
			(xy 372.992335 -228.207362) (xy 373.034351 -228.176836) (xy 373.080625 -228.153258) (xy 373.130018 -228.13721)
			(xy 373.181313 -228.129085) (xy 373.233247 -228.129085) (xy 373.284542 -228.13721) (xy 373.333935 -228.153258)
			(xy 373.380209 -228.176836) (xy 373.422225 -228.207362) (xy 373.458948 -228.244085) (xy 373.489474 -228.286101)
			(xy 373.513052 -228.332375) (xy 373.5291 -228.381768) (xy 373.537225 -228.433063) (xy 373.537734 -228.45903)
			(xy 373.537225 -228.484997) (xy 373.5291 -228.536292) (xy 373.513052 -228.585685) (xy 373.489474 -228.631959)
			(xy 373.458948 -228.673975) (xy 373.422225 -228.710698) (xy 373.380209 -228.741224) (xy 373.333935 -228.764802)
			(xy 373.284542 -228.78085) (xy 373.233247 -228.788975) (xy 373.181313 -228.788975) (xy 373.130018 -228.78085)
			(xy 373.080625 -228.764802) (xy 373.034351 -228.741224) (xy 372.992335 -228.710698) (xy 372.955612 -228.673975)
			(xy 372.925086 -228.631959) (xy 372.901508 -228.585685) (xy 372.88546 -228.536292) (xy 372.877335 -228.484997)
			(xy 372.597425 -228.484997) (xy 372.5893 -228.536292) (xy 372.573252 -228.585685) (xy 372.549674 -228.631959)
			(xy 372.519148 -228.673975) (xy 372.482425 -228.710698) (xy 372.440409 -228.741224) (xy 372.394135 -228.764802)
			(xy 372.344742 -228.78085) (xy 372.293447 -228.788975) (xy 372.241513 -228.788975) (xy 372.190218 -228.78085)
			(xy 372.140825 -228.764802) (xy 372.094551 -228.741224) (xy 372.052535 -228.710698) (xy 372.015812 -228.673975)
			(xy 371.985286 -228.631959) (xy 371.961708 -228.585685) (xy 371.94566 -228.536292) (xy 371.937535 -228.484997)
			(xy 371.657625 -228.484997) (xy 371.6495 -228.536292) (xy 371.633452 -228.585685) (xy 371.609874 -228.631959)
			(xy 371.579348 -228.673975) (xy 371.542625 -228.710698) (xy 371.500609 -228.741224) (xy 371.454335 -228.764802)
			(xy 371.404942 -228.78085) (xy 371.353647 -228.788975) (xy 371.301713 -228.788975) (xy 371.250418 -228.78085)
			(xy 371.201025 -228.764802) (xy 371.154751 -228.741224) (xy 371.112735 -228.710698) (xy 371.076012 -228.673975)
			(xy 371.045486 -228.631959) (xy 371.021908 -228.585685) (xy 371.00586 -228.536292) (xy 370.997735 -228.484997)
			(xy 370.717825 -228.484997) (xy 370.7097 -228.536292) (xy 370.693652 -228.585685) (xy 370.670074 -228.631959)
			(xy 370.639548 -228.673975) (xy 370.602825 -228.710698) (xy 370.560809 -228.741224) (xy 370.514535 -228.764802)
			(xy 370.465142 -228.78085) (xy 370.413847 -228.788975) (xy 370.361913 -228.788975) (xy 370.310618 -228.78085)
			(xy 370.261225 -228.764802) (xy 370.214951 -228.741224) (xy 370.172935 -228.710698) (xy 370.136212 -228.673975)
			(xy 370.105686 -228.631959) (xy 370.082108 -228.585685) (xy 370.06606 -228.536292) (xy 370.057935 -228.484997)
			(xy 369.778024 -228.484997) (xy 369.778004 -228.486027) (xy 369.769239 -228.539306) (xy 369.751932 -228.590451)
			(xy 369.726541 -228.638104) (xy 369.693744 -228.680996) (xy 369.654411 -228.717986) (xy 369.609588 -228.748093)
			(xy 369.58524 -228.759766) (xy 369.572195 -228.804729) (xy 369.539566 -228.892487) (xy 369.499706 -228.977207)
			(xy 369.452896 -229.058294) (xy 369.399463 -229.135178) (xy 369.339784 -229.207322) (xy 369.307364 -229.241096)
			(xy 369.308888 -229.272846) (xy 369.308375 -229.298813) (xy 369.588289 -229.298813) (xy 369.588289 -229.246879)
			(xy 369.596414 -229.195584) (xy 369.612462 -229.146191) (xy 369.63604 -229.099917) (xy 369.666566 -229.057901)
			(xy 369.703289 -229.021178) (xy 369.745305 -228.990652) (xy 369.791579 -228.967074) (xy 369.840972 -228.951026)
			(xy 369.892267 -228.942901) (xy 369.944201 -228.942901) (xy 369.995496 -228.951026) (xy 370.044889 -228.967074)
			(xy 370.091163 -228.990652) (xy 370.133179 -229.021178) (xy 370.169902 -229.057901) (xy 370.200428 -229.099917)
			(xy 370.224006 -229.146191) (xy 370.240054 -229.195584) (xy 370.248179 -229.246879) (xy 370.248688 -229.272846)
			(xy 370.248179 -229.298813) (xy 370.527835 -229.298813) (xy 370.527835 -229.246879) (xy 370.53596 -229.195584)
			(xy 370.552008 -229.146191) (xy 370.575586 -229.099917) (xy 370.606112 -229.057901) (xy 370.642835 -229.021178)
			(xy 370.684851 -228.990652) (xy 370.731125 -228.967074) (xy 370.780518 -228.951026) (xy 370.831813 -228.942901)
			(xy 370.883747 -228.942901) (xy 370.935042 -228.951026) (xy 370.984435 -228.967074) (xy 371.030709 -228.990652)
			(xy 371.072725 -229.021178) (xy 371.109448 -229.057901) (xy 371.139974 -229.099917) (xy 371.163552 -229.146191)
			(xy 371.1796 -229.195584) (xy 371.187725 -229.246879) (xy 371.188234 -229.272846) (xy 371.187725 -229.298813)
			(xy 371.467889 -229.298813) (xy 371.467889 -229.246879) (xy 371.476014 -229.195584) (xy 371.492062 -229.146191)
			(xy 371.51564 -229.099917) (xy 371.546166 -229.057901) (xy 371.582889 -229.021178) (xy 371.624905 -228.990652)
			(xy 371.671179 -228.967074) (xy 371.720572 -228.951026) (xy 371.771867 -228.942901) (xy 371.823801 -228.942901)
			(xy 371.875096 -228.951026) (xy 371.924489 -228.967074) (xy 371.970763 -228.990652) (xy 372.012779 -229.021178)
			(xy 372.049502 -229.057901) (xy 372.080028 -229.099917) (xy 372.103606 -229.146191) (xy 372.119654 -229.195584)
			(xy 372.127779 -229.246879) (xy 372.128288 -229.272846) (xy 372.127779 -229.298813) (xy 372.407689 -229.298813)
			(xy 372.407689 -229.246879) (xy 372.415814 -229.195584) (xy 372.431862 -229.146191) (xy 372.45544 -229.099917)
			(xy 372.485966 -229.057901) (xy 372.522689 -229.021178) (xy 372.564705 -228.990652) (xy 372.610979 -228.967074)
			(xy 372.660372 -228.951026) (xy 372.711667 -228.942901) (xy 372.763601 -228.942901) (xy 372.814896 -228.951026)
			(xy 372.864289 -228.967074) (xy 372.910563 -228.990652) (xy 372.952579 -229.021178) (xy 372.989302 -229.057901)
			(xy 373.019828 -229.099917) (xy 373.043406 -229.146191) (xy 373.059454 -229.195584) (xy 373.067579 -229.246879)
			(xy 373.068088 -229.272846) (xy 373.067579 -229.298813) (xy 373.059454 -229.350108) (xy 373.043406 -229.399501)
			(xy 373.019828 -229.445775) (xy 372.989302 -229.487791) (xy 372.952579 -229.524514) (xy 372.910563 -229.55504)
			(xy 372.864289 -229.578618) (xy 372.814896 -229.594666) (xy 372.763601 -229.602791) (xy 372.711667 -229.602791)
			(xy 372.660372 -229.594666) (xy 372.610979 -229.578618) (xy 372.564705 -229.55504) (xy 372.522689 -229.524514)
			(xy 372.485966 -229.487791) (xy 372.45544 -229.445775) (xy 372.431862 -229.399501) (xy 372.415814 -229.350108)
			(xy 372.407689 -229.298813) (xy 372.127779 -229.298813) (xy 372.119654 -229.350108) (xy 372.103606 -229.399501)
			(xy 372.080028 -229.445775) (xy 372.049502 -229.487791) (xy 372.012779 -229.524514) (xy 371.970763 -229.55504)
			(xy 371.924489 -229.578618) (xy 371.875096 -229.594666) (xy 371.823801 -229.602791) (xy 371.771867 -229.602791)
			(xy 371.720572 -229.594666) (xy 371.671179 -229.578618) (xy 371.624905 -229.55504) (xy 371.582889 -229.524514)
			(xy 371.546166 -229.487791) (xy 371.51564 -229.445775) (xy 371.492062 -229.399501) (xy 371.476014 -229.350108)
			(xy 371.467889 -229.298813) (xy 371.187725 -229.298813) (xy 371.1796 -229.350108) (xy 371.163552 -229.399501)
			(xy 371.139974 -229.445775) (xy 371.109448 -229.487791) (xy 371.072725 -229.524514) (xy 371.030709 -229.55504)
			(xy 370.984435 -229.578618) (xy 370.935042 -229.594666) (xy 370.883747 -229.602791) (xy 370.831813 -229.602791)
			(xy 370.780518 -229.594666) (xy 370.731125 -229.578618) (xy 370.684851 -229.55504) (xy 370.642835 -229.524514)
			(xy 370.606112 -229.487791) (xy 370.575586 -229.445775) (xy 370.552008 -229.399501) (xy 370.53596 -229.350108)
			(xy 370.527835 -229.298813) (xy 370.248179 -229.298813) (xy 370.240054 -229.350108) (xy 370.224006 -229.399501)
			(xy 370.200428 -229.445775) (xy 370.169902 -229.487791) (xy 370.133179 -229.524514) (xy 370.091163 -229.55504)
			(xy 370.044889 -229.578618) (xy 369.995496 -229.594666) (xy 369.944201 -229.602791) (xy 369.892267 -229.602791)
			(xy 369.840972 -229.594666) (xy 369.791579 -229.578618) (xy 369.745305 -229.55504) (xy 369.703289 -229.524514)
			(xy 369.666566 -229.487791) (xy 369.63604 -229.445775) (xy 369.612462 -229.399501) (xy 369.596414 -229.350108)
			(xy 369.588289 -229.298813) (xy 369.308375 -229.298813) (xy 369.308354 -229.299857) (xy 369.299575 -229.35316)
			(xy 369.28224 -229.404324) (xy 369.256813 -229.451987) (xy 369.223971 -229.494879) (xy 369.184588 -229.531856)
			(xy 369.139715 -229.561933) (xy 369.11534 -229.573582) (xy 369.102277 -229.618569) (xy 369.069609 -229.706374)
			(xy 369.029707 -229.791138) (xy 368.98285 -229.872264) (xy 368.929369 -229.949185) (xy 368.869638 -230.021359)
			(xy 368.83721 -230.055166) (xy 368.838734 -230.086662) (xy 368.838254 -230.112629) (xy 369.118135 -230.112629)
			(xy 369.118135 -230.060695) (xy 369.12626 -230.0094) (xy 369.142308 -229.960007) (xy 369.165886 -229.913733)
			(xy 369.196412 -229.871717) (xy 369.233135 -229.834994) (xy 369.275151 -229.804468) (xy 369.321425 -229.78089)
			(xy 369.370818 -229.764842) (xy 369.422113 -229.756717) (xy 369.474047 -229.756717) (xy 369.525342 -229.764842)
			(xy 369.574735 -229.78089) (xy 369.621009 -229.804468) (xy 369.663025 -229.834994) (xy 369.699748 -229.871717)
			(xy 369.730274 -229.913733) (xy 369.753852 -229.960007) (xy 369.7699 -230.0094) (xy 369.778025 -230.060695)
			(xy 369.778534 -230.086662) (xy 369.778025 -230.112629) (xy 370.057935 -230.112629) (xy 370.057935 -230.060695)
			(xy 370.06606 -230.0094) (xy 370.082108 -229.960007) (xy 370.105686 -229.913733) (xy 370.136212 -229.871717)
			(xy 370.172935 -229.834994) (xy 370.214951 -229.804468) (xy 370.261225 -229.78089) (xy 370.310618 -229.764842)
			(xy 370.361913 -229.756717) (xy 370.413847 -229.756717) (xy 370.465142 -229.764842) (xy 370.514535 -229.78089)
			(xy 370.560809 -229.804468) (xy 370.602825 -229.834994) (xy 370.639548 -229.871717) (xy 370.670074 -229.913733)
			(xy 370.693652 -229.960007) (xy 370.7097 -230.0094) (xy 370.717825 -230.060695) (xy 370.718334 -230.086662)
			(xy 370.717825 -230.112629) (xy 370.997735 -230.112629) (xy 370.997735 -230.060695) (xy 371.00586 -230.0094)
			(xy 371.021908 -229.960007) (xy 371.045486 -229.913733) (xy 371.076012 -229.871717) (xy 371.112735 -229.834994)
			(xy 371.154751 -229.804468) (xy 371.201025 -229.78089) (xy 371.250418 -229.764842) (xy 371.301713 -229.756717)
			(xy 371.353647 -229.756717) (xy 371.404942 -229.764842) (xy 371.454335 -229.78089) (xy 371.500609 -229.804468)
			(xy 371.542625 -229.834994) (xy 371.579348 -229.871717) (xy 371.609874 -229.913733) (xy 371.633452 -229.960007)
			(xy 371.6495 -230.0094) (xy 371.657625 -230.060695) (xy 371.658134 -230.086662) (xy 371.657625 -230.112629)
			(xy 371.937535 -230.112629) (xy 371.937535 -230.060695) (xy 371.94566 -230.0094) (xy 371.961708 -229.960007)
			(xy 371.985286 -229.913733) (xy 372.015812 -229.871717) (xy 372.052535 -229.834994) (xy 372.094551 -229.804468)
			(xy 372.140825 -229.78089) (xy 372.190218 -229.764842) (xy 372.241513 -229.756717) (xy 372.293447 -229.756717)
			(xy 372.344742 -229.764842) (xy 372.394135 -229.78089) (xy 372.440409 -229.804468) (xy 372.482425 -229.834994)
			(xy 372.519148 -229.871717) (xy 372.549674 -229.913733) (xy 372.573252 -229.960007) (xy 372.5893 -230.0094)
			(xy 372.597425 -230.060695) (xy 372.597934 -230.086662) (xy 372.597425 -230.112629) (xy 372.877589 -230.112629)
			(xy 372.877589 -230.060695) (xy 372.885714 -230.0094) (xy 372.901762 -229.960007) (xy 372.92534 -229.913733)
			(xy 372.955866 -229.871717) (xy 372.992589 -229.834994) (xy 373.034605 -229.804468) (xy 373.080879 -229.78089)
			(xy 373.130272 -229.764842) (xy 373.181567 -229.756717) (xy 373.233501 -229.756717) (xy 373.284796 -229.764842)
			(xy 373.334189 -229.78089) (xy 373.380463 -229.804468) (xy 373.422479 -229.834994) (xy 373.459202 -229.871717)
			(xy 373.489728 -229.913733) (xy 373.513306 -229.960007) (xy 373.529354 -230.0094) (xy 373.537479 -230.060695)
			(xy 373.537988 -230.086662) (xy 373.537479 -230.112629) (xy 373.529354 -230.163924) (xy 373.513306 -230.213317)
			(xy 373.489728 -230.259591) (xy 373.459202 -230.301607) (xy 373.422479 -230.33833) (xy 373.380463 -230.368856)
			(xy 373.334189 -230.392434) (xy 373.284796 -230.408482) (xy 373.233501 -230.416607) (xy 373.181567 -230.416607)
			(xy 373.130272 -230.408482) (xy 373.080879 -230.392434) (xy 373.034605 -230.368856) (xy 372.992589 -230.33833)
			(xy 372.955866 -230.301607) (xy 372.92534 -230.259591) (xy 372.901762 -230.213317) (xy 372.885714 -230.163924)
			(xy 372.877589 -230.112629) (xy 372.597425 -230.112629) (xy 372.5893 -230.163924) (xy 372.573252 -230.213317)
			(xy 372.549674 -230.259591) (xy 372.519148 -230.301607) (xy 372.482425 -230.33833) (xy 372.440409 -230.368856)
			(xy 372.394135 -230.392434) (xy 372.344742 -230.408482) (xy 372.293447 -230.416607) (xy 372.241513 -230.416607)
			(xy 372.190218 -230.408482) (xy 372.140825 -230.392434) (xy 372.094551 -230.368856) (xy 372.052535 -230.33833)
			(xy 372.015812 -230.301607) (xy 371.985286 -230.259591) (xy 371.961708 -230.213317) (xy 371.94566 -230.163924)
			(xy 371.937535 -230.112629) (xy 371.657625 -230.112629) (xy 371.6495 -230.163924) (xy 371.633452 -230.213317)
			(xy 371.609874 -230.259591) (xy 371.579348 -230.301607) (xy 371.542625 -230.33833) (xy 371.500609 -230.368856)
			(xy 371.454335 -230.392434) (xy 371.404942 -230.408482) (xy 371.353647 -230.416607) (xy 371.301713 -230.416607)
			(xy 371.250418 -230.408482) (xy 371.201025 -230.392434) (xy 371.154751 -230.368856) (xy 371.112735 -230.33833)
			(xy 371.076012 -230.301607) (xy 371.045486 -230.259591) (xy 371.021908 -230.213317) (xy 371.00586 -230.163924)
			(xy 370.997735 -230.112629) (xy 370.717825 -230.112629) (xy 370.7097 -230.163924) (xy 370.693652 -230.213317)
			(xy 370.670074 -230.259591) (xy 370.639548 -230.301607) (xy 370.602825 -230.33833) (xy 370.560809 -230.368856)
			(xy 370.514535 -230.392434) (xy 370.465142 -230.408482) (xy 370.413847 -230.416607) (xy 370.361913 -230.416607)
			(xy 370.310618 -230.408482) (xy 370.261225 -230.392434) (xy 370.214951 -230.368856) (xy 370.172935 -230.33833)
			(xy 370.136212 -230.301607) (xy 370.105686 -230.259591) (xy 370.082108 -230.213317) (xy 370.06606 -230.163924)
			(xy 370.057935 -230.112629) (xy 369.778025 -230.112629) (xy 369.7699 -230.163924) (xy 369.753852 -230.213317)
			(xy 369.730274 -230.259591) (xy 369.699748 -230.301607) (xy 369.663025 -230.33833) (xy 369.621009 -230.368856)
			(xy 369.574735 -230.392434) (xy 369.525342 -230.408482) (xy 369.474047 -230.416607) (xy 369.422113 -230.416607)
			(xy 369.370818 -230.408482) (xy 369.321425 -230.392434) (xy 369.275151 -230.368856) (xy 369.233135 -230.33833)
			(xy 369.196412 -230.301607) (xy 369.165886 -230.259591) (xy 369.142308 -230.213317) (xy 369.12626 -230.163924)
			(xy 369.118135 -230.112629) (xy 368.838254 -230.112629) (xy 368.838254 -230.112633) (xy 368.830134 -230.163935)
			(xy 368.814087 -230.213336) (xy 368.790509 -230.259617) (xy 368.75998 -230.30164) (xy 368.723253 -230.338369)
			(xy 368.681232 -230.368899) (xy 368.634952 -230.39248) (xy 368.585553 -230.408529) (xy 368.534251 -230.416653)
			(xy 368.50828 -230.417116) (xy 368.482728 -230.416636) (xy 368.432236 -230.408761) (xy 368.383559 -230.3932)
			(xy 368.337861 -230.370326) (xy 368.316764 -230.355902) (xy 368.264694 -230.368094) (xy 368.249708 -230.371142)
			(xy 368.172238 -230.448612) (xy 368.162955 -230.458479) (xy 368.149495 -230.481981) (xy 368.142691 -230.508195)
			(xy 368.143022 -230.535275) (xy 368.150464 -230.561315) (xy 368.164493 -230.584481) (xy 368.184121 -230.60314)
			(xy 368.19586 -230.609902) (xy 368.217977 -230.622371) (xy 368.258434 -230.653047) (xy 368.293715 -230.689557)
			(xy 368.322988 -230.73104) (xy 368.345563 -230.776517) (xy 368.360905 -230.824915) (xy 368.368654 -230.875092)
			(xy 368.369088 -230.900478) (xy 368.36858 -230.926445) (xy 368.648489 -230.926445) (xy 368.648489 -230.874511)
			(xy 368.656614 -230.823216) (xy 368.672662 -230.773823) (xy 368.69624 -230.727549) (xy 368.726766 -230.685533)
			(xy 368.763489 -230.64881) (xy 368.805505 -230.618284) (xy 368.851779 -230.594706) (xy 368.901172 -230.578658)
			(xy 368.952467 -230.570533) (xy 369.004401 -230.570533) (xy 369.055696 -230.578658) (xy 369.105089 -230.594706)
			(xy 369.151363 -230.618284) (xy 369.193379 -230.64881) (xy 369.230102 -230.685533) (xy 369.260628 -230.727549)
			(xy 369.284206 -230.773823) (xy 369.300254 -230.823216) (xy 369.308379 -230.874511) (xy 369.308888 -230.900478)
			(xy 369.308379 -230.926445) (xy 369.588035 -230.926445) (xy 369.588035 -230.874511) (xy 369.59616 -230.823216)
			(xy 369.612208 -230.773823) (xy 369.635786 -230.727549) (xy 369.666312 -230.685533) (xy 369.703035 -230.64881)
			(xy 369.745051 -230.618284) (xy 369.791325 -230.594706) (xy 369.840718 -230.578658) (xy 369.892013 -230.570533)
			(xy 369.943947 -230.570533) (xy 369.995242 -230.578658) (xy 370.044635 -230.594706) (xy 370.090909 -230.618284)
			(xy 370.132925 -230.64881) (xy 370.169648 -230.685533) (xy 370.200174 -230.727549) (xy 370.223752 -230.773823)
			(xy 370.2398 -230.823216) (xy 370.247925 -230.874511) (xy 370.248434 -230.900478) (xy 370.247925 -230.926445)
			(xy 370.528089 -230.926445) (xy 370.528089 -230.874511) (xy 370.536214 -230.823216) (xy 370.552262 -230.773823)
			(xy 370.57584 -230.727549) (xy 370.606366 -230.685533) (xy 370.643089 -230.64881) (xy 370.685105 -230.618284)
			(xy 370.731379 -230.594706) (xy 370.780772 -230.578658) (xy 370.832067 -230.570533) (xy 370.884001 -230.570533)
			(xy 370.935296 -230.578658) (xy 370.984689 -230.594706) (xy 371.030963 -230.618284) (xy 371.072979 -230.64881)
			(xy 371.109702 -230.685533) (xy 371.140228 -230.727549) (xy 371.163806 -230.773823) (xy 371.179854 -230.823216)
			(xy 371.187979 -230.874511) (xy 371.188488 -230.900478) (xy 371.187979 -230.926445) (xy 371.467889 -230.926445)
			(xy 371.467889 -230.874511) (xy 371.476014 -230.823216) (xy 371.492062 -230.773823) (xy 371.51564 -230.727549)
			(xy 371.546166 -230.685533) (xy 371.582889 -230.64881) (xy 371.624905 -230.618284) (xy 371.671179 -230.594706)
			(xy 371.720572 -230.578658) (xy 371.771867 -230.570533) (xy 371.823801 -230.570533) (xy 371.875096 -230.578658)
			(xy 371.924489 -230.594706) (xy 371.970763 -230.618284) (xy 372.012779 -230.64881) (xy 372.049502 -230.685533)
			(xy 372.080028 -230.727549) (xy 372.103606 -230.773823) (xy 372.119654 -230.823216) (xy 372.127779 -230.874511)
			(xy 372.128288 -230.900478) (xy 372.127779 -230.926445) (xy 372.407689 -230.926445) (xy 372.407689 -230.874511)
			(xy 372.415814 -230.823216) (xy 372.431862 -230.773823) (xy 372.45544 -230.727549) (xy 372.485966 -230.685533)
			(xy 372.522689 -230.64881) (xy 372.564705 -230.618284) (xy 372.610979 -230.594706) (xy 372.660372 -230.578658)
			(xy 372.711667 -230.570533) (xy 372.763601 -230.570533) (xy 372.814896 -230.578658) (xy 372.864289 -230.594706)
			(xy 372.910563 -230.618284) (xy 372.952579 -230.64881) (xy 372.989302 -230.685533) (xy 373.019828 -230.727549)
			(xy 373.043406 -230.773823) (xy 373.059454 -230.823216) (xy 373.067579 -230.874511) (xy 373.068088 -230.900478)
			(xy 373.067579 -230.926445) (xy 373.059454 -230.97774) (xy 373.043406 -231.027133) (xy 373.019828 -231.073407)
			(xy 372.989302 -231.115423) (xy 372.952579 -231.152146) (xy 372.910563 -231.182672) (xy 372.864289 -231.20625)
			(xy 372.814896 -231.222298) (xy 372.763601 -231.230423) (xy 372.711667 -231.230423) (xy 372.660372 -231.222298)
			(xy 372.610979 -231.20625) (xy 372.564705 -231.182672) (xy 372.522689 -231.152146) (xy 372.485966 -231.115423)
			(xy 372.45544 -231.073407) (xy 372.431862 -231.027133) (xy 372.415814 -230.97774) (xy 372.407689 -230.926445)
			(xy 372.127779 -230.926445) (xy 372.119654 -230.97774) (xy 372.103606 -231.027133) (xy 372.080028 -231.073407)
			(xy 372.049502 -231.115423) (xy 372.012779 -231.152146) (xy 371.970763 -231.182672) (xy 371.924489 -231.20625)
			(xy 371.875096 -231.222298) (xy 371.823801 -231.230423) (xy 371.771867 -231.230423) (xy 371.720572 -231.222298)
			(xy 371.671179 -231.20625) (xy 371.624905 -231.182672) (xy 371.582889 -231.152146) (xy 371.546166 -231.115423)
			(xy 371.51564 -231.073407) (xy 371.492062 -231.027133) (xy 371.476014 -230.97774) (xy 371.467889 -230.926445)
			(xy 371.187979 -230.926445) (xy 371.179854 -230.97774) (xy 371.163806 -231.027133) (xy 371.140228 -231.073407)
			(xy 371.109702 -231.115423) (xy 371.072979 -231.152146) (xy 371.030963 -231.182672) (xy 370.984689 -231.20625)
			(xy 370.935296 -231.222298) (xy 370.884001 -231.230423) (xy 370.832067 -231.230423) (xy 370.780772 -231.222298)
			(xy 370.731379 -231.20625) (xy 370.685105 -231.182672) (xy 370.643089 -231.152146) (xy 370.606366 -231.115423)
			(xy 370.57584 -231.073407) (xy 370.552262 -231.027133) (xy 370.536214 -230.97774) (xy 370.528089 -230.926445)
			(xy 370.247925 -230.926445) (xy 370.2398 -230.97774) (xy 370.223752 -231.027133) (xy 370.200174 -231.073407)
			(xy 370.169648 -231.115423) (xy 370.132925 -231.152146) (xy 370.090909 -231.182672) (xy 370.044635 -231.20625)
			(xy 369.995242 -231.222298) (xy 369.943947 -231.230423) (xy 369.892013 -231.230423) (xy 369.840718 -231.222298)
			(xy 369.791325 -231.20625) (xy 369.745051 -231.182672) (xy 369.703035 -231.152146) (xy 369.666312 -231.115423)
			(xy 369.635786 -231.073407) (xy 369.612208 -231.027133) (xy 369.59616 -230.97774) (xy 369.588035 -230.926445)
			(xy 369.308379 -230.926445) (xy 369.300254 -230.97774) (xy 369.284206 -231.027133) (xy 369.260628 -231.073407)
			(xy 369.230102 -231.115423) (xy 369.193379 -231.152146) (xy 369.151363 -231.182672) (xy 369.105089 -231.20625)
			(xy 369.055696 -231.222298) (xy 369.004401 -231.230423) (xy 368.952467 -231.230423) (xy 368.901172 -231.222298)
			(xy 368.851779 -231.20625) (xy 368.805505 -231.182672) (xy 368.763489 -231.152146) (xy 368.726766 -231.115423)
			(xy 368.69624 -231.073407) (xy 368.672662 -231.027133) (xy 368.656614 -230.97774) (xy 368.648489 -230.926445)
			(xy 368.36858 -230.926445) (xy 368.36858 -230.926447) (xy 368.360459 -230.977747) (xy 368.344413 -231.027145)
			(xy 368.320837 -231.073424) (xy 368.290311 -231.115446) (xy 368.253588 -231.152175) (xy 368.211572 -231.182707)
			(xy 368.165297 -231.206291) (xy 368.115902 -231.222346) (xy 368.064603 -231.230476) (xy 368.038634 -231.230932)
			(xy 368.013253 -231.230463) (xy 367.963088 -231.22269) (xy 367.914703 -231.207336) (xy 367.869235 -231.184762)
			(xy 367.827755 -231.155501) (xy 367.791237 -231.120239) (xy 367.760542 -231.079808) (xy 367.748058 -231.057704)
			(xy 367.741256 -231.045995) (xy 367.722592 -231.026391) (xy 367.699434 -231.012377) (xy 367.673407 -231.004939)
			(xy 367.646341 -231.004598) (xy 367.620135 -231.011379) (xy 367.596631 -231.024805) (xy 367.586768 -231.034082)
			(xy 367.496344 -231.124506) (xy 367.341658 -231.124506) (xy 367.322746 -231.144198) (xy 367.279648 -231.177711)
			(xy 367.231624 -231.203676) (xy 367.179983 -231.221386) (xy 367.126131 -231.230357) (xy 367.098834 -231.230932)
			(xy 367.073281 -231.230457) (xy 367.022784 -231.222589) (xy 366.974103 -231.207035) (xy 366.928398 -231.184167)
			(xy 366.907318 -231.169718) (xy 366.35055 -231.169718) (xy 366.329458 -231.18415) (xy 366.283758 -231.207025)
			(xy 366.23508 -231.222587) (xy 366.184586 -231.230465) (xy 366.159034 -231.230932) (xy 366.133449 -231.230476)
			(xy 366.082886 -231.222628) (xy 366.034141 -231.207067) (xy 365.988383 -231.184168) (xy 365.967264 -231.169718)
			(xy 365.921739 -231.180897) (xy 365.829302 -231.196527) (xy 365.735882 -231.20437) (xy 365.642132 -231.20437)
			(xy 365.548712 -231.196527) (xy 365.456275 -231.180897) (xy 365.41075 -231.169718) (xy 365.389658 -231.18415)
			(xy 365.343958 -231.207025) (xy 365.29528 -231.222587) (xy 365.244786 -231.230465) (xy 365.219234 -231.230932)
			(xy 365.193649 -231.230476) (xy 365.143086 -231.222628) (xy 365.094341 -231.207067) (xy 365.048583 -231.184168)
			(xy 365.027464 -231.169718) (xy 364.981964 -231.180909) (xy 364.889568 -231.19654) (xy 364.796188 -231.204382)
			(xy 364.70248 -231.204382) (xy 364.6091 -231.19654) (xy 364.516704 -231.180909) (xy 364.471204 -231.169718)
			(xy 364.450077 -231.184149) (xy 364.40431 -231.207017) (xy 364.355569 -231.222569) (xy 364.305015 -231.230433)
			(xy 364.279434 -231.230932) (xy 364.253464 -231.230452) (xy 364.202162 -231.222331) (xy 364.152762 -231.206284)
			(xy 364.106481 -231.182705) (xy 364.064459 -231.152177) (xy 364.027731 -231.11545) (xy 363.997201 -231.073429)
			(xy 363.973621 -231.027149) (xy 363.957572 -230.97775) (xy 363.949449 -230.926448) (xy 363.94898 -230.900478)
			(xy 363.950504 -230.869236) (xy 363.935081 -230.853308) (xy 363.905356 -230.820404) (xy 363.891068 -230.80345)
			(xy 363.544104 -230.456486) (xy 363.544104 -230.283766) (xy 363.528754 -230.262261) (xy 363.504372 -230.215392)
			(xy 363.487765 -230.165237) (xy 363.479358 -230.113078) (xy 363.478826 -230.086662) (xy 363.48035 -230.054912)
			(xy 363.446552 -230.019642) (xy 363.38457 -229.944131) (xy 363.329419 -229.863495) (xy 363.281518 -229.778352)
			(xy 363.241236 -229.689351) (xy 363.224572 -229.643432) (xy 363.220762 -229.632764) (xy 362.891324 -229.303326)
			(xy 362.881519 -229.29409) (xy 362.858172 -229.280674) (xy 362.832127 -229.27384) (xy 362.805201 -229.274062)
			(xy 362.779272 -229.281327) (xy 362.75615 -229.295127) (xy 362.737448 -229.314499) (xy 362.72447 -229.338092)
			(xy 362.72089 -229.351078) (xy 362.714667 -229.374738) (xy 362.6962 -229.42004) (xy 362.671257 -229.462125)
			(xy 362.640383 -229.500073) (xy 362.604251 -229.533055) (xy 362.563653 -229.56035) (xy 362.519474 -229.581363)
			(xy 362.472681 -229.595633) (xy 362.424295 -229.60285) (xy 362.399834 -229.6033) (xy 362.373864 -229.602793)
			(xy 362.322562 -229.594674) (xy 362.273162 -229.578628) (xy 362.22688 -229.555053) (xy 362.184856 -229.524528)
			(xy 362.148124 -229.487805) (xy 362.117589 -229.445788) (xy 362.094002 -229.399512) (xy 362.077945 -229.350116)
			(xy 362.069813 -229.298816) (xy 362.06938 -229.272846) (xy 362.070134 -229.240853) (xy 362.082416 -229.178055)
			(xy 362.093764 -229.148132) (xy 362.09893 -229.134026) (xy 362.101684 -229.104127) (xy 362.095633 -229.074717)
			(xy 362.081301 -229.048333) (xy 362.059922 -229.02725) (xy 362.03334 -229.013287) (xy 362.003849 -229.007647)
			(xy 361.988862 -229.008686) (xy 361.974114 -229.010211) (xy 361.944506 -229.011864) (xy 361.92968 -229.011988)
			(xy 361.914981 -229.011842) (xy 361.885629 -229.010188) (xy 361.871006 -229.008686) (xy 361.856005 -229.007592)
			(xy 361.826467 -229.013179) (xy 361.799837 -229.027126) (xy 361.778424 -229.048225) (xy 361.764084 -229.074647)
			(xy 361.758062 -229.104099) (xy 361.76088 -229.134029) (xy 361.766104 -229.148132) (xy 361.77749 -229.178044)
			(xy 361.789775 -229.240848) (xy 361.790488 -229.272846) (xy 361.789979 -229.298813) (xy 361.781854 -229.350108)
			(xy 361.765806 -229.399501) (xy 361.742228 -229.445775) (xy 361.711702 -229.487791) (xy 361.674979 -229.524514)
			(xy 361.632963 -229.55504) (xy 361.586689 -229.578618) (xy 361.537296 -229.594666) (xy 361.486001 -229.602791)
			(xy 361.434067 -229.602791) (xy 361.382772 -229.594666) (xy 361.333379 -229.578618) (xy 361.287105 -229.55504)
			(xy 361.245089 -229.524514) (xy 361.208366 -229.487791) (xy 361.17784 -229.445775) (xy 361.154262 -229.399501)
			(xy 361.138214 -229.350108) (xy 361.130089 -229.298813) (xy 361.12958 -229.272846) (xy 361.130334 -229.240853)
			(xy 361.142616 -229.178055) (xy 361.153964 -229.148132) (xy 361.15913 -229.134026) (xy 361.161884 -229.104127)
			(xy 361.155833 -229.074717) (xy 361.141501 -229.048333) (xy 361.120122 -229.02725) (xy 361.09354 -229.013287)
			(xy 361.064049 -229.007647) (xy 361.049062 -229.008686) (xy 361.034314 -229.010211) (xy 361.004706 -229.011864)
			(xy 360.98988 -229.011988) (xy 360.921808 -229.011988) (xy 360.907649 -229.012451) (xy 360.880418 -229.020224)
			(xy 360.856369 -229.035176) (xy 360.83735 -229.056157) (xy 360.824823 -229.081554) (xy 360.819751 -229.109414)
			(xy 360.822525 -229.137596) (xy 360.82732 -229.150926) (xy 360.838203 -229.180225) (xy 360.849974 -229.241599)
			(xy 360.850688 -229.272846) (xy 360.850179 -229.298813) (xy 360.842054 -229.350108) (xy 360.826006 -229.399501)
			(xy 360.802428 -229.445775) (xy 360.771902 -229.487791) (xy 360.735179 -229.524514) (xy 360.693163 -229.55504)
			(xy 360.646889 -229.578618) (xy 360.597496 -229.594666) (xy 360.546201 -229.602791) (xy 360.494267 -229.602791)
			(xy 360.442972 -229.594666) (xy 360.393579 -229.578618) (xy 360.347305 -229.55504) (xy 360.305289 -229.524514)
			(xy 360.268566 -229.487791) (xy 360.23804 -229.445775) (xy 360.214462 -229.399501) (xy 360.198414 -229.350108)
			(xy 360.190289 -229.298813) (xy 360.18978 -229.272846) (xy 360.19053 -229.241603) (xy 360.202288 -229.180231)
			(xy 360.213148 -229.150926) (xy 360.217919 -229.137592) (xy 360.220693 -229.109419) (xy 360.215622 -229.081568)
			(xy 360.203098 -229.05618) (xy 360.184082 -229.035209) (xy 360.160038 -229.020267) (xy 360.132815 -229.012502)
			(xy 360.11866 -229.011988) (xy 360.05008 -229.011988) (xy 360.035317 -229.011848) (xy 360.005838 -229.010195)
			(xy 359.991152 -229.008686) (xy 359.976147 -229.007586) (xy 359.946596 -229.013163) (xy 359.919953 -229.027108)
			(xy 359.898528 -229.048211) (xy 359.884181 -229.07464) (xy 359.878157 -229.104103) (xy 359.880978 -229.134042)
			(xy 359.88625 -229.148132) (xy 359.897634 -229.178045) (xy 359.909918 -229.240848) (xy 359.910634 -229.272846)
			(xy 359.910125 -229.298813) (xy 359.902 -229.350108) (xy 359.885952 -229.399501) (xy 359.862374 -229.445775)
			(xy 359.831848 -229.487791) (xy 359.795125 -229.524514) (xy 359.753109 -229.55504) (xy 359.706835 -229.578618)
			(xy 359.657442 -229.594666) (xy 359.606147 -229.602791) (xy 359.554213 -229.602791) (xy 359.502918 -229.594666)
			(xy 359.453525 -229.578618) (xy 359.407251 -229.55504) (xy 359.365235 -229.524514) (xy 359.328512 -229.487791)
			(xy 359.297986 -229.445775) (xy 359.274408 -229.399501) (xy 359.25836 -229.350108) (xy 359.250235 -229.298813)
			(xy 359.249726 -229.272846) (xy 359.250328 -229.244357) (xy 359.260106 -229.188223) (xy 359.279363 -229.134597)
			(xy 359.292906 -229.109524) (xy 359.299887 -229.096054) (xy 359.306415 -229.066442) (xy 359.303963 -229.036219)
			(xy 359.292747 -229.008047) (xy 359.273755 -228.984409) (xy 359.248661 -228.967388) (xy 359.219675 -228.958482)
			(xy 359.204514 -228.957886) (xy 359.0163 -228.957886) (xy 359.001132 -228.958444) (xy 358.972132 -228.96735)
			(xy 358.947025 -228.984378) (xy 358.928023 -229.008026) (xy 358.916801 -229.03621) (xy 358.914348 -229.066447)
			(xy 358.920881 -229.096072) (xy 358.927908 -229.109524) (xy 358.941465 -229.134588) (xy 358.960707 -229.18822)
			(xy 358.970469 -229.244356) (xy 358.971088 -229.272846) (xy 358.970579 -229.298813) (xy 358.962454 -229.350108)
			(xy 358.946406 -229.399501) (xy 358.922828 -229.445775) (xy 358.892302 -229.487791) (xy 358.855579 -229.524514)
			(xy 358.813563 -229.55504) (xy 358.767289 -229.578618) (xy 358.717896 -229.594666) (xy 358.666601 -229.602791)
			(xy 358.614667 -229.602791) (xy 358.563372 -229.594666) (xy 358.513979 -229.578618) (xy 358.467705 -229.55504)
			(xy 358.425689 -229.524514) (xy 358.388966 -229.487791) (xy 358.35844 -229.445775) (xy 358.334862 -229.399501)
			(xy 358.318814 -229.350108) (xy 358.310689 -229.298813) (xy 358.31018 -229.272846) (xy 358.310934 -229.240853)
			(xy 358.323216 -229.178055) (xy 358.334564 -229.148132) (xy 358.33973 -229.134026) (xy 358.342484 -229.104127)
			(xy 358.336433 -229.074717) (xy 358.322101 -229.048333) (xy 358.300722 -229.02725) (xy 358.27414 -229.013287)
			(xy 358.244649 -229.007647) (xy 358.229662 -229.008686) (xy 358.214914 -229.010211) (xy 358.185306 -229.011864)
			(xy 358.17048 -229.011988) (xy 358.155781 -229.011842) (xy 358.126429 -229.010188) (xy 358.111806 -229.008686)
			(xy 358.096805 -229.007592) (xy 358.067267 -229.013179) (xy 358.040637 -229.027126) (xy 358.019224 -229.048225)
			(xy 358.004884 -229.074647) (xy 357.998862 -229.104099) (xy 358.00168 -229.134029) (xy 358.006904 -229.148132)
			(xy 358.01829 -229.178044) (xy 358.030575 -229.240848) (xy 358.031288 -229.272846) (xy 358.030779 -229.298813)
			(xy 358.022654 -229.350108) (xy 358.006606 -229.399501) (xy 357.983028 -229.445775) (xy 357.952502 -229.487791)
			(xy 357.915779 -229.524514) (xy 357.873763 -229.55504) (xy 357.827489 -229.578618) (xy 357.778096 -229.594666)
			(xy 357.726801 -229.602791) (xy 357.674867 -229.602791) (xy 357.623572 -229.594666) (xy 357.574179 -229.578618)
			(xy 357.527905 -229.55504) (xy 357.485889 -229.524514) (xy 357.449166 -229.487791) (xy 357.41864 -229.445775)
			(xy 357.395062 -229.399501) (xy 357.379014 -229.350108) (xy 357.370889 -229.298813) (xy 357.37038 -229.272846)
			(xy 357.370895 -229.246511) (xy 357.379254 -229.194509) (xy 357.395752 -229.14449) (xy 357.419971 -229.097719)
			(xy 357.451299 -229.05538) (xy 357.488944 -229.018542) (xy 357.531952 -228.98814) (xy 357.579237 -228.96494)
			(xy 357.629602 -228.94953) (xy 357.655622 -228.94544) (xy 357.670418 -228.942868) (xy 357.697685 -228.930317)
			(xy 357.720127 -228.910383) (xy 357.735807 -228.884788) (xy 357.743371 -228.85574) (xy 357.742166 -228.825747)
			(xy 357.732296 -228.797399) (xy 357.723948 -228.784912) (xy 357.715307 -228.772914) (xy 357.699171 -228.748135)
			(xy 357.69169 -228.735382) (xy 357.535226 -228.464364) (xy 357.51585 -228.429428) (xy 357.486262 -228.355223)
			(xy 357.476298 -228.316536) (xy 357.448023 -228.288695) (xy 357.398937 -228.226348) (xy 357.378508 -228.19233)
			(xy 357.326184 -228.101906) (xy 357.079804 -228.101906) (xy 356.848664 -228.333046) (xy 356.848664 -228.764846)
			(xy 356.823264 -228.790246) (xy 356.813118 -228.801099) (xy 356.799028 -228.827239) (xy 356.793056 -228.856328)
			(xy 356.795707 -228.885905) (xy 356.806756 -228.913469) (xy 356.825268 -228.936688) (xy 356.849679 -228.953598)
			(xy 356.86365 -228.958648) (xy 356.888156 -228.967177) (xy 356.934362 -228.990783) (xy 356.976308 -229.021323)
			(xy 357.012964 -229.058045) (xy 357.043428 -229.100046) (xy 357.066951 -229.146294) (xy 357.082954 -229.195651)
			(xy 357.091043 -229.246903) (xy 357.091488 -229.272846) (xy 357.090979 -229.298813) (xy 357.082854 -229.350108)
			(xy 357.066806 -229.399501) (xy 357.043228 -229.445775) (xy 357.012702 -229.487791) (xy 356.975979 -229.524514)
			(xy 356.933963 -229.55504) (xy 356.887689 -229.578618) (xy 356.838296 -229.594666) (xy 356.787001 -229.602791)
			(xy 356.735067 -229.602791) (xy 356.683772 -229.594666) (xy 356.634379 -229.578618) (xy 356.588105 -229.55504)
			(xy 356.546089 -229.524514) (xy 356.509366 -229.487791) (xy 356.47884 -229.445775) (xy 356.455262 -229.399501)
			(xy 356.439214 -229.350108) (xy 356.431089 -229.298813) (xy 356.43058 -229.272846) (xy 356.431334 -229.240853)
			(xy 356.443616 -229.178055) (xy 356.454964 -229.148132) (xy 356.46013 -229.134026) (xy 356.462884 -229.104127)
			(xy 356.456833 -229.074717) (xy 356.442501 -229.048333) (xy 356.421122 -229.02725) (xy 356.39454 -229.013287)
			(xy 356.365049 -229.007647) (xy 356.350062 -229.008686) (xy 356.335314 -229.010211) (xy 356.305706 -229.011864)
			(xy 356.29088 -229.011988) (xy 356.276181 -229.011842) (xy 356.246829 -229.010188) (xy 356.232206 -229.008686)
			(xy 356.217205 -229.007592) (xy 356.187667 -229.013179) (xy 356.161037 -229.027126) (xy 356.139624 -229.048225)
			(xy 356.125284 -229.074647) (xy 356.119262 -229.104099) (xy 356.12208 -229.134029) (xy 356.127304 -229.148132)
			(xy 356.13869 -229.178044) (xy 356.150975 -229.240848) (xy 356.151688 -229.272846) (xy 356.151175 -229.298816)
			(xy 356.143043 -229.350114) (xy 356.126986 -229.399509) (xy 356.1034 -229.445785) (xy 356.072865 -229.4878)
			(xy 356.036133 -229.524522) (xy 355.994109 -229.555046) (xy 355.947828 -229.57862) (xy 355.898429 -229.594663)
			(xy 355.847128 -229.602782) (xy 355.795188 -229.602775) (xy 355.743889 -229.594644) (xy 355.694494 -229.578587)
			(xy 355.648219 -229.555002) (xy 355.606203 -229.524467) (xy 355.56948 -229.487736) (xy 355.538956 -229.445713)
			(xy 355.515382 -229.399432) (xy 355.499338 -229.350033) (xy 355.491218 -229.298732) (xy 355.491224 -229.246792)
			(xy 355.499355 -229.195493) (xy 355.515411 -229.146098) (xy 355.538996 -229.099822) (xy 355.56953 -229.057806)
			(xy 355.606261 -229.021083) (xy 355.648284 -228.990558) (xy 355.694565 -228.966983) (xy 355.743964 -228.950938)
			(xy 355.795264 -228.942819) (xy 355.821234 -228.942392) (xy 355.82606 -228.942392) (xy 355.847396 -228.942646)
			(xy 355.89845 -228.891592) (xy 355.822504 -228.815646) (xy 355.822504 -228.753162) (xy 355.815392 -228.74097)
			(xy 355.81209 -228.735382) (xy 355.655626 -228.464364) (xy 355.63625 -228.429428) (xy 355.606662 -228.355223)
			(xy 355.596698 -228.316536) (xy 355.568423 -228.288695) (xy 355.519337 -228.226348) (xy 355.498908 -228.19233)
			(xy 355.426264 -228.066346) (xy 355.239828 -228.066346) (xy 355.225858 -228.077522) (xy 355.200802 -228.096897)
			(xy 355.147055 -228.130412) (xy 355.089831 -228.157568) (xy 355.059996 -228.1682) (xy 355.04882 -228.17201)
			(xy 354.963984 -228.256846) (xy 354.963984 -228.4476) (xy 354.963984 -228.45903) (xy 354.963984 -228.637846)
			(xy 354.914962 -228.686868) (xy 354.902928 -228.712626) (xy 354.874298 -228.761749) (xy 354.857812 -228.784912)
			(xy 354.849381 -228.797352) (xy 354.839479 -228.825708) (xy 354.838262 -228.855719) (xy 354.845838 -228.884783)
			(xy 354.861548 -228.910382) (xy 354.884031 -228.930298) (xy 354.91134 -228.942803) (xy 354.926138 -228.94544)
			(xy 354.952186 -228.949517) (xy 355.002627 -228.964856) (xy 355.049993 -228.988008) (xy 355.093082 -229.018385)
			(xy 355.130803 -229.055218) (xy 355.162198 -229.097572) (xy 355.186471 -229.144373) (xy 355.203006 -229.194434)
			(xy 355.211384 -229.246486) (xy 355.211888 -229.272846) (xy 355.211379 -229.298813) (xy 355.203254 -229.350108)
			(xy 355.187206 -229.399501) (xy 355.163628 -229.445775) (xy 355.133102 -229.487791) (xy 355.096379 -229.524514)
			(xy 355.054363 -229.55504) (xy 355.008089 -229.578618) (xy 354.958696 -229.594666) (xy 354.907401 -229.602791)
			(xy 354.855467 -229.602791) (xy 354.804172 -229.594666) (xy 354.754779 -229.578618) (xy 354.708505 -229.55504)
			(xy 354.666489 -229.524514) (xy 354.629766 -229.487791) (xy 354.59924 -229.445775) (xy 354.575662 -229.399501)
			(xy 354.559614 -229.350108) (xy 354.551489 -229.298813) (xy 354.55098 -229.272846) (xy 354.551734 -229.240853)
			(xy 354.564016 -229.178055) (xy 354.575364 -229.148132) (xy 354.58053 -229.134026) (xy 354.583284 -229.104127)
			(xy 354.577233 -229.074717) (xy 354.562901 -229.048333) (xy 354.541522 -229.02725) (xy 354.51494 -229.013287)
			(xy 354.485449 -229.007647) (xy 354.470462 -229.008686) (xy 354.455714 -229.010211) (xy 354.426106 -229.011864)
			(xy 354.41128 -229.011988) (xy 354.396581 -229.011842) (xy 354.367229 -229.010188) (xy 354.352606 -229.008686)
			(xy 354.337605 -229.007592) (xy 354.308067 -229.013179) (xy 354.281437 -229.027126) (xy 354.260024 -229.048225)
			(xy 354.245684 -229.074647) (xy 354.239662 -229.104099) (xy 354.24248 -229.134029) (xy 354.247704 -229.148132)
			(xy 354.25909 -229.178044) (xy 354.271375 -229.240848) (xy 354.272088 -229.272846) (xy 354.271579 -229.298813)
			(xy 354.263454 -229.350108) (xy 354.247406 -229.399501) (xy 354.223828 -229.445775) (xy 354.193302 -229.487791)
			(xy 354.156579 -229.524514) (xy 354.114563 -229.55504) (xy 354.068289 -229.578618) (xy 354.018896 -229.594666)
			(xy 353.967601 -229.602791) (xy 353.915667 -229.602791) (xy 353.864372 -229.594666) (xy 353.814979 -229.578618)
			(xy 353.768705 -229.55504) (xy 353.726689 -229.524514) (xy 353.689966 -229.487791) (xy 353.65944 -229.445775)
			(xy 353.635862 -229.399501) (xy 353.619814 -229.350108) (xy 353.611689 -229.298813) (xy 353.61118 -229.272846)
			(xy 353.611695 -229.246511) (xy 353.620054 -229.194509) (xy 353.636552 -229.14449) (xy 353.660771 -229.097719)
			(xy 353.692099 -229.05538) (xy 353.729744 -229.018542) (xy 353.772752 -228.98814) (xy 353.820037 -228.96494)
			(xy 353.870402 -228.94953) (xy 353.896422 -228.94544) (xy 353.911218 -228.942868) (xy 353.938485 -228.930317)
			(xy 353.960927 -228.910383) (xy 353.976607 -228.884788) (xy 353.984171 -228.85574) (xy 353.982966 -228.825747)
			(xy 353.973096 -228.797399) (xy 353.964748 -228.784912) (xy 353.95749 -228.774897) (xy 353.943769 -228.754316)
			(xy 353.937316 -228.743764) (xy 353.934014 -228.738176) (xy 353.833684 -228.637846) (xy 353.860608 -228.610922)
			(xy 353.776026 -228.464364) (xy 353.75665 -228.429428) (xy 353.727062 -228.355223) (xy 353.717098 -228.316536)
			(xy 353.688823 -228.288695) (xy 353.639737 -228.226348) (xy 353.619308 -228.19233) (xy 353.57435 -228.114606)
			(xy 353.333304 -228.114606) (xy 353.132644 -228.315266) (xy 353.132644 -228.566726) (xy 353.051364 -228.648006)
			(xy 353.0473 -228.658166) (xy 353.042061 -228.67157) (xy 353.030368 -228.697871) (xy 353.023932 -228.710744)
			(xy 353.018344 -228.721666) (xy 353.018344 -228.940106) (xy 353.060254 -228.947472) (xy 353.08535 -228.952483)
			(xy 353.13371 -228.969215) (xy 353.178914 -228.9932) (xy 353.219882 -229.023863) (xy 353.255636 -229.060474)
			(xy 353.285321 -229.102157) (xy 353.308228 -229.147917) (xy 353.32381 -229.19666) (xy 353.331695 -229.247222)
			(xy 353.331693 -229.298395) (xy 353.323806 -229.348956) (xy 353.308222 -229.397698) (xy 353.285313 -229.443457)
			(xy 353.255626 -229.485138) (xy 353.21987 -229.521747) (xy 353.1789 -229.552409) (xy 353.133695 -229.576391)
			(xy 353.085334 -229.593121) (xy 353.060254 -229.59822) (xy 353.018344 -229.605586) (xy 353.018344 -230.112629)
			(xy 353.141535 -230.112629) (xy 353.141535 -230.060695) (xy 353.14966 -230.0094) (xy 353.165708 -229.960007)
			(xy 353.189286 -229.913733) (xy 353.219812 -229.871717) (xy 353.256535 -229.834994) (xy 353.298551 -229.804468)
			(xy 353.344825 -229.78089) (xy 353.394218 -229.764842) (xy 353.445513 -229.756717) (xy 353.497447 -229.756717)
			(xy 353.548742 -229.764842) (xy 353.598135 -229.78089) (xy 353.644409 -229.804468) (xy 353.686425 -229.834994)
			(xy 353.723148 -229.871717) (xy 353.753674 -229.913733) (xy 353.777252 -229.960007) (xy 353.7933 -230.0094)
			(xy 353.801425 -230.060695) (xy 353.801934 -230.086662) (xy 353.801425 -230.112629) (xy 354.081589 -230.112629)
			(xy 354.081589 -230.060695) (xy 354.089714 -230.0094) (xy 354.105762 -229.960007) (xy 354.12934 -229.913733)
			(xy 354.159866 -229.871717) (xy 354.196589 -229.834994) (xy 354.238605 -229.804468) (xy 354.284879 -229.78089)
			(xy 354.334272 -229.764842) (xy 354.385567 -229.756717) (xy 354.437501 -229.756717) (xy 354.488796 -229.764842)
			(xy 354.538189 -229.78089) (xy 354.584463 -229.804468) (xy 354.626479 -229.834994) (xy 354.663202 -229.871717)
			(xy 354.693728 -229.913733) (xy 354.717306 -229.960007) (xy 354.733354 -230.0094) (xy 354.741479 -230.060695)
			(xy 354.741988 -230.086662) (xy 354.741479 -230.112629) (xy 355.021135 -230.112629) (xy 355.021135 -230.060695)
			(xy 355.02926 -230.0094) (xy 355.045308 -229.960007) (xy 355.068886 -229.913733) (xy 355.099412 -229.871717)
			(xy 355.136135 -229.834994) (xy 355.178151 -229.804468) (xy 355.224425 -229.78089) (xy 355.273818 -229.764842)
			(xy 355.325113 -229.756717) (xy 355.377047 -229.756717) (xy 355.428342 -229.764842) (xy 355.477735 -229.78089)
			(xy 355.524009 -229.804468) (xy 355.566025 -229.834994) (xy 355.602748 -229.871717) (xy 355.633274 -229.913733)
			(xy 355.656852 -229.960007) (xy 355.6729 -230.0094) (xy 355.681025 -230.060695) (xy 355.681534 -230.086662)
			(xy 355.681025 -230.112629) (xy 355.960935 -230.112629) (xy 355.960935 -230.060695) (xy 355.96906 -230.0094)
			(xy 355.985108 -229.960007) (xy 356.008686 -229.913733) (xy 356.039212 -229.871717) (xy 356.075935 -229.834994)
			(xy 356.117951 -229.804468) (xy 356.164225 -229.78089) (xy 356.213618 -229.764842) (xy 356.264913 -229.756717)
			(xy 356.316847 -229.756717) (xy 356.368142 -229.764842) (xy 356.417535 -229.78089) (xy 356.463809 -229.804468)
			(xy 356.505825 -229.834994) (xy 356.542548 -229.871717) (xy 356.573074 -229.913733) (xy 356.596652 -229.960007)
			(xy 356.6127 -230.0094) (xy 356.620825 -230.060695) (xy 356.621334 -230.086662) (xy 356.620825 -230.112629)
			(xy 356.900735 -230.112629) (xy 356.900735 -230.060695) (xy 356.90886 -230.0094) (xy 356.924908 -229.960007)
			(xy 356.948486 -229.913733) (xy 356.979012 -229.871717) (xy 357.015735 -229.834994) (xy 357.057751 -229.804468)
			(xy 357.104025 -229.78089) (xy 357.153418 -229.764842) (xy 357.204713 -229.756717) (xy 357.256647 -229.756717)
			(xy 357.307942 -229.764842) (xy 357.357335 -229.78089) (xy 357.403609 -229.804468) (xy 357.445625 -229.834994)
			(xy 357.482348 -229.871717) (xy 357.512874 -229.913733) (xy 357.536452 -229.960007) (xy 357.5525 -230.0094)
			(xy 357.560625 -230.060695) (xy 357.561134 -230.086662) (xy 357.560625 -230.112629) (xy 357.840535 -230.112629)
			(xy 357.840535 -230.060695) (xy 357.84866 -230.0094) (xy 357.864708 -229.960007) (xy 357.888286 -229.913733)
			(xy 357.918812 -229.871717) (xy 357.955535 -229.834994) (xy 357.997551 -229.804468) (xy 358.043825 -229.78089)
			(xy 358.093218 -229.764842) (xy 358.144513 -229.756717) (xy 358.196447 -229.756717) (xy 358.247742 -229.764842)
			(xy 358.297135 -229.78089) (xy 358.343409 -229.804468) (xy 358.385425 -229.834994) (xy 358.422148 -229.871717)
			(xy 358.452674 -229.913733) (xy 358.476252 -229.960007) (xy 358.4923 -230.0094) (xy 358.500425 -230.060695)
			(xy 358.500934 -230.086662) (xy 358.500425 -230.112629) (xy 358.780589 -230.112629) (xy 358.780589 -230.060695)
			(xy 358.788714 -230.0094) (xy 358.804762 -229.960007) (xy 358.82834 -229.913733) (xy 358.858866 -229.871717)
			(xy 358.895589 -229.834994) (xy 358.937605 -229.804468) (xy 358.983879 -229.78089) (xy 359.033272 -229.764842)
			(xy 359.084567 -229.756717) (xy 359.136501 -229.756717) (xy 359.187796 -229.764842) (xy 359.237189 -229.78089)
			(xy 359.283463 -229.804468) (xy 359.325479 -229.834994) (xy 359.362202 -229.871717) (xy 359.392728 -229.913733)
			(xy 359.416306 -229.960007) (xy 359.432354 -230.0094) (xy 359.440479 -230.060695) (xy 359.440988 -230.086662)
			(xy 359.440479 -230.112629) (xy 359.720389 -230.112629) (xy 359.720389 -230.060695) (xy 359.728514 -230.0094)
			(xy 359.744562 -229.960007) (xy 359.76814 -229.913733) (xy 359.798666 -229.871717) (xy 359.835389 -229.834994)
			(xy 359.877405 -229.804468) (xy 359.923679 -229.78089) (xy 359.973072 -229.764842) (xy 360.024367 -229.756717)
			(xy 360.076301 -229.756717) (xy 360.127596 -229.764842) (xy 360.176989 -229.78089) (xy 360.223263 -229.804468)
			(xy 360.265279 -229.834994) (xy 360.302002 -229.871717) (xy 360.332528 -229.913733) (xy 360.356106 -229.960007)
			(xy 360.372154 -230.0094) (xy 360.380279 -230.060695) (xy 360.380788 -230.086662) (xy 360.380279 -230.112629)
			(xy 360.660189 -230.112629) (xy 360.660189 -230.060695) (xy 360.668314 -230.0094) (xy 360.684362 -229.960007)
			(xy 360.70794 -229.913733) (xy 360.738466 -229.871717) (xy 360.775189 -229.834994) (xy 360.817205 -229.804468)
			(xy 360.863479 -229.78089) (xy 360.912872 -229.764842) (xy 360.964167 -229.756717) (xy 361.016101 -229.756717)
			(xy 361.067396 -229.764842) (xy 361.116789 -229.78089) (xy 361.163063 -229.804468) (xy 361.205079 -229.834994)
			(xy 361.241802 -229.871717) (xy 361.272328 -229.913733) (xy 361.295906 -229.960007) (xy 361.311954 -230.0094)
			(xy 361.320079 -230.060695) (xy 361.320588 -230.086662) (xy 361.320079 -230.112629) (xy 361.599989 -230.112629)
			(xy 361.599989 -230.060695) (xy 361.608114 -230.0094) (xy 361.624162 -229.960007) (xy 361.64774 -229.913733)
			(xy 361.678266 -229.871717) (xy 361.714989 -229.834994) (xy 361.757005 -229.804468) (xy 361.803279 -229.78089)
			(xy 361.852672 -229.764842) (xy 361.903967 -229.756717) (xy 361.955901 -229.756717) (xy 362.007196 -229.764842)
			(xy 362.056589 -229.78089) (xy 362.102863 -229.804468) (xy 362.144879 -229.834994) (xy 362.181602 -229.871717)
			(xy 362.212128 -229.913733) (xy 362.235706 -229.960007) (xy 362.251754 -230.0094) (xy 362.259879 -230.060695)
			(xy 362.260388 -230.086662) (xy 362.259879 -230.112629) (xy 362.539789 -230.112629) (xy 362.539789 -230.060695)
			(xy 362.547914 -230.0094) (xy 362.563962 -229.960007) (xy 362.58754 -229.913733) (xy 362.618066 -229.871717)
			(xy 362.654789 -229.834994) (xy 362.696805 -229.804468) (xy 362.743079 -229.78089) (xy 362.792472 -229.764842)
			(xy 362.843767 -229.756717) (xy 362.895701 -229.756717) (xy 362.946996 -229.764842) (xy 362.996389 -229.78089)
			(xy 363.042663 -229.804468) (xy 363.084679 -229.834994) (xy 363.121402 -229.871717) (xy 363.151928 -229.913733)
			(xy 363.175506 -229.960007) (xy 363.191554 -230.0094) (xy 363.199679 -230.060695) (xy 363.200188 -230.086662)
			(xy 363.199679 -230.112629) (xy 363.191554 -230.163924) (xy 363.175506 -230.213317) (xy 363.151928 -230.259591)
			(xy 363.121402 -230.301607) (xy 363.084679 -230.33833) (xy 363.042663 -230.368856) (xy 362.996389 -230.392434)
			(xy 362.946996 -230.408482) (xy 362.895701 -230.416607) (xy 362.843767 -230.416607) (xy 362.792472 -230.408482)
			(xy 362.743079 -230.392434) (xy 362.696805 -230.368856) (xy 362.654789 -230.33833) (xy 362.618066 -230.301607)
			(xy 362.58754 -230.259591) (xy 362.563962 -230.213317) (xy 362.547914 -230.163924) (xy 362.539789 -230.112629)
			(xy 362.259879 -230.112629) (xy 362.251754 -230.163924) (xy 362.235706 -230.213317) (xy 362.212128 -230.259591)
			(xy 362.181602 -230.301607) (xy 362.144879 -230.33833) (xy 362.102863 -230.368856) (xy 362.056589 -230.392434)
			(xy 362.007196 -230.408482) (xy 361.955901 -230.416607) (xy 361.903967 -230.416607) (xy 361.852672 -230.408482)
			(xy 361.803279 -230.392434) (xy 361.757005 -230.368856) (xy 361.714989 -230.33833) (xy 361.678266 -230.301607)
			(xy 361.64774 -230.259591) (xy 361.624162 -230.213317) (xy 361.608114 -230.163924) (xy 361.599989 -230.112629)
			(xy 361.320079 -230.112629) (xy 361.311954 -230.163924) (xy 361.295906 -230.213317) (xy 361.272328 -230.259591)
			(xy 361.241802 -230.301607) (xy 361.205079 -230.33833) (xy 361.163063 -230.368856) (xy 361.116789 -230.392434)
			(xy 361.067396 -230.408482) (xy 361.016101 -230.416607) (xy 360.964167 -230.416607) (xy 360.912872 -230.408482)
			(xy 360.863479 -230.392434) (xy 360.817205 -230.368856) (xy 360.775189 -230.33833) (xy 360.738466 -230.301607)
			(xy 360.70794 -230.259591) (xy 360.684362 -230.213317) (xy 360.668314 -230.163924) (xy 360.660189 -230.112629)
			(xy 360.380279 -230.112629) (xy 360.372154 -230.163924) (xy 360.356106 -230.213317) (xy 360.332528 -230.259591)
			(xy 360.302002 -230.301607) (xy 360.265279 -230.33833) (xy 360.223263 -230.368856) (xy 360.176989 -230.392434)
			(xy 360.127596 -230.408482) (xy 360.076301 -230.416607) (xy 360.024367 -230.416607) (xy 359.973072 -230.408482)
			(xy 359.923679 -230.392434) (xy 359.877405 -230.368856) (xy 359.835389 -230.33833) (xy 359.798666 -230.301607)
			(xy 359.76814 -230.259591) (xy 359.744562 -230.213317) (xy 359.728514 -230.163924) (xy 359.720389 -230.112629)
			(xy 359.440479 -230.112629) (xy 359.432354 -230.163924) (xy 359.416306 -230.213317) (xy 359.392728 -230.259591)
			(xy 359.362202 -230.301607) (xy 359.325479 -230.33833) (xy 359.283463 -230.368856) (xy 359.237189 -230.392434)
			(xy 359.187796 -230.408482) (xy 359.136501 -230.416607) (xy 359.084567 -230.416607) (xy 359.033272 -230.408482)
			(xy 358.983879 -230.392434) (xy 358.937605 -230.368856) (xy 358.895589 -230.33833) (xy 358.858866 -230.301607)
			(xy 358.82834 -230.259591) (xy 358.804762 -230.213317) (xy 358.788714 -230.163924) (xy 358.780589 -230.112629)
			(xy 358.500425 -230.112629) (xy 358.4923 -230.163924) (xy 358.476252 -230.213317) (xy 358.452674 -230.259591)
			(xy 358.422148 -230.301607) (xy 358.385425 -230.33833) (xy 358.343409 -230.368856) (xy 358.297135 -230.392434)
			(xy 358.247742 -230.408482) (xy 358.196447 -230.416607) (xy 358.144513 -230.416607) (xy 358.093218 -230.408482)
			(xy 358.043825 -230.392434) (xy 357.997551 -230.368856) (xy 357.955535 -230.33833) (xy 357.918812 -230.301607)
			(xy 357.888286 -230.259591) (xy 357.864708 -230.213317) (xy 357.84866 -230.163924) (xy 357.840535 -230.112629)
			(xy 357.560625 -230.112629) (xy 357.5525 -230.163924) (xy 357.536452 -230.213317) (xy 357.512874 -230.259591)
			(xy 357.482348 -230.301607) (xy 357.445625 -230.33833) (xy 357.403609 -230.368856) (xy 357.357335 -230.392434)
			(xy 357.307942 -230.408482) (xy 357.256647 -230.416607) (xy 357.204713 -230.416607) (xy 357.153418 -230.408482)
			(xy 357.104025 -230.392434) (xy 357.057751 -230.368856) (xy 357.015735 -230.33833) (xy 356.979012 -230.301607)
			(xy 356.948486 -230.259591) (xy 356.924908 -230.213317) (xy 356.90886 -230.163924) (xy 356.900735 -230.112629)
			(xy 356.620825 -230.112629) (xy 356.6127 -230.163924) (xy 356.596652 -230.213317) (xy 356.573074 -230.259591)
			(xy 356.542548 -230.301607) (xy 356.505825 -230.33833) (xy 356.463809 -230.368856) (xy 356.417535 -230.392434)
			(xy 356.368142 -230.408482) (xy 356.316847 -230.416607) (xy 356.264913 -230.416607) (xy 356.213618 -230.408482)
			(xy 356.164225 -230.392434) (xy 356.117951 -230.368856) (xy 356.075935 -230.33833) (xy 356.039212 -230.301607)
			(xy 356.008686 -230.259591) (xy 355.985108 -230.213317) (xy 355.96906 -230.163924) (xy 355.960935 -230.112629)
			(xy 355.681025 -230.112629) (xy 355.6729 -230.163924) (xy 355.656852 -230.213317) (xy 355.633274 -230.259591)
			(xy 355.602748 -230.301607) (xy 355.566025 -230.33833) (xy 355.524009 -230.368856) (xy 355.477735 -230.392434)
			(xy 355.428342 -230.408482) (xy 355.377047 -230.416607) (xy 355.325113 -230.416607) (xy 355.273818 -230.408482)
			(xy 355.224425 -230.392434) (xy 355.178151 -230.368856) (xy 355.136135 -230.33833) (xy 355.099412 -230.301607)
			(xy 355.068886 -230.259591) (xy 355.045308 -230.213317) (xy 355.02926 -230.163924) (xy 355.021135 -230.112629)
			(xy 354.741479 -230.112629) (xy 354.733354 -230.163924) (xy 354.717306 -230.213317) (xy 354.693728 -230.259591)
			(xy 354.663202 -230.301607) (xy 354.626479 -230.33833) (xy 354.584463 -230.368856) (xy 354.538189 -230.392434)
			(xy 354.488796 -230.408482) (xy 354.437501 -230.416607) (xy 354.385567 -230.416607) (xy 354.334272 -230.408482)
			(xy 354.284879 -230.392434) (xy 354.238605 -230.368856) (xy 354.196589 -230.33833) (xy 354.159866 -230.301607)
			(xy 354.12934 -230.259591) (xy 354.105762 -230.213317) (xy 354.089714 -230.163924) (xy 354.081589 -230.112629)
			(xy 353.801425 -230.112629) (xy 353.7933 -230.163924) (xy 353.777252 -230.213317) (xy 353.753674 -230.259591)
			(xy 353.723148 -230.301607) (xy 353.686425 -230.33833) (xy 353.644409 -230.368856) (xy 353.598135 -230.392434)
			(xy 353.548742 -230.408482) (xy 353.497447 -230.416607) (xy 353.445513 -230.416607) (xy 353.394218 -230.408482)
			(xy 353.344825 -230.392434) (xy 353.298551 -230.368856) (xy 353.256535 -230.33833) (xy 353.219812 -230.301607)
			(xy 353.189286 -230.259591) (xy 353.165708 -230.213317) (xy 353.14966 -230.163924) (xy 353.141535 -230.112629)
			(xy 353.018344 -230.112629) (xy 353.018344 -230.567738) (xy 353.060254 -230.575104) (xy 353.085355 -230.580116)
			(xy 353.133725 -230.596849) (xy 353.17894 -230.620837) (xy 353.219918 -230.651505) (xy 353.25568 -230.688122)
			(xy 353.285372 -230.729812) (xy 353.308286 -230.77558) (xy 353.323872 -230.824333) (xy 353.33176 -230.874904)
			(xy 353.331761 -230.926088) (xy 353.331705 -230.926445) (xy 353.611689 -230.926445) (xy 353.611689 -230.874511)
			(xy 353.619814 -230.823216) (xy 353.635862 -230.773823) (xy 353.65944 -230.727549) (xy 353.689966 -230.685533)
			(xy 353.726689 -230.64881) (xy 353.768705 -230.618284) (xy 353.814979 -230.594706) (xy 353.864372 -230.578658)
			(xy 353.915667 -230.570533) (xy 353.967601 -230.570533) (xy 354.018896 -230.578658) (xy 354.068289 -230.594706)
			(xy 354.114563 -230.618284) (xy 354.156579 -230.64881) (xy 354.193302 -230.685533) (xy 354.223828 -230.727549)
			(xy 354.247406 -230.773823) (xy 354.263454 -230.823216) (xy 354.271579 -230.874511) (xy 354.272088 -230.900478)
			(xy 354.271579 -230.926445) (xy 354.551489 -230.926445) (xy 354.551489 -230.874511) (xy 354.559614 -230.823216)
			(xy 354.575662 -230.773823) (xy 354.59924 -230.727549) (xy 354.629766 -230.685533) (xy 354.666489 -230.64881)
			(xy 354.708505 -230.618284) (xy 354.754779 -230.594706) (xy 354.804172 -230.578658) (xy 354.855467 -230.570533)
			(xy 354.907401 -230.570533) (xy 354.958696 -230.578658) (xy 355.008089 -230.594706) (xy 355.054363 -230.618284)
			(xy 355.096379 -230.64881) (xy 355.133102 -230.685533) (xy 355.163628 -230.727549) (xy 355.187206 -230.773823)
			(xy 355.203254 -230.823216) (xy 355.211379 -230.874511) (xy 355.211888 -230.900478) (xy 355.211379 -230.926445)
			(xy 355.491035 -230.926445) (xy 355.491035 -230.874511) (xy 355.49916 -230.823216) (xy 355.515208 -230.773823)
			(xy 355.538786 -230.727549) (xy 355.569312 -230.685533) (xy 355.606035 -230.64881) (xy 355.648051 -230.618284)
			(xy 355.694325 -230.594706) (xy 355.743718 -230.578658) (xy 355.795013 -230.570533) (xy 355.846947 -230.570533)
			(xy 355.898242 -230.578658) (xy 355.947635 -230.594706) (xy 355.993909 -230.618284) (xy 356.035925 -230.64881)
			(xy 356.072648 -230.685533) (xy 356.103174 -230.727549) (xy 356.126752 -230.773823) (xy 356.1428 -230.823216)
			(xy 356.150925 -230.874511) (xy 356.151434 -230.900478) (xy 356.150925 -230.926445) (xy 356.431089 -230.926445)
			(xy 356.431089 -230.874511) (xy 356.439214 -230.823216) (xy 356.455262 -230.773823) (xy 356.47884 -230.727549)
			(xy 356.509366 -230.685533) (xy 356.546089 -230.64881) (xy 356.588105 -230.618284) (xy 356.634379 -230.594706)
			(xy 356.683772 -230.578658) (xy 356.735067 -230.570533) (xy 356.787001 -230.570533) (xy 356.838296 -230.578658)
			(xy 356.887689 -230.594706) (xy 356.933963 -230.618284) (xy 356.975979 -230.64881) (xy 357.012702 -230.685533)
			(xy 357.043228 -230.727549) (xy 357.066806 -230.773823) (xy 357.082854 -230.823216) (xy 357.090979 -230.874511)
			(xy 357.091488 -230.900478) (xy 357.090979 -230.926445) (xy 357.370635 -230.926445) (xy 357.370635 -230.874511)
			(xy 357.37876 -230.823216) (xy 357.394808 -230.773823) (xy 357.418386 -230.727549) (xy 357.448912 -230.685533)
			(xy 357.485635 -230.64881) (xy 357.527651 -230.618284) (xy 357.573925 -230.594706) (xy 357.623318 -230.578658)
			(xy 357.674613 -230.570533) (xy 357.726547 -230.570533) (xy 357.777842 -230.578658) (xy 357.827235 -230.594706)
			(xy 357.873509 -230.618284) (xy 357.915525 -230.64881) (xy 357.952248 -230.685533) (xy 357.982774 -230.727549)
			(xy 358.006352 -230.773823) (xy 358.0224 -230.823216) (xy 358.030525 -230.874511) (xy 358.031034 -230.900478)
			(xy 358.030525 -230.926445) (xy 358.310689 -230.926445) (xy 358.310689 -230.874511) (xy 358.318814 -230.823216)
			(xy 358.334862 -230.773823) (xy 358.35844 -230.727549) (xy 358.388966 -230.685533) (xy 358.425689 -230.64881)
			(xy 358.467705 -230.618284) (xy 358.513979 -230.594706) (xy 358.563372 -230.578658) (xy 358.614667 -230.570533)
			(xy 358.666601 -230.570533) (xy 358.717896 -230.578658) (xy 358.767289 -230.594706) (xy 358.813563 -230.618284)
			(xy 358.855579 -230.64881) (xy 358.892302 -230.685533) (xy 358.922828 -230.727549) (xy 358.946406 -230.773823)
			(xy 358.962454 -230.823216) (xy 358.970579 -230.874511) (xy 358.971088 -230.900478) (xy 358.970579 -230.926445)
			(xy 359.250489 -230.926445) (xy 359.250489 -230.874511) (xy 359.258614 -230.823216) (xy 359.274662 -230.773823)
			(xy 359.29824 -230.727549) (xy 359.328766 -230.685533) (xy 359.365489 -230.64881) (xy 359.407505 -230.618284)
			(xy 359.453779 -230.594706) (xy 359.503172 -230.578658) (xy 359.554467 -230.570533) (xy 359.606401 -230.570533)
			(xy 359.657696 -230.578658) (xy 359.707089 -230.594706) (xy 359.753363 -230.618284) (xy 359.795379 -230.64881)
			(xy 359.832102 -230.685533) (xy 359.862628 -230.727549) (xy 359.886206 -230.773823) (xy 359.902254 -230.823216)
			(xy 359.910379 -230.874511) (xy 359.910888 -230.900478) (xy 359.910379 -230.926445) (xy 360.190289 -230.926445)
			(xy 360.190289 -230.874511) (xy 360.198414 -230.823216) (xy 360.214462 -230.773823) (xy 360.23804 -230.727549)
			(xy 360.268566 -230.685533) (xy 360.305289 -230.64881) (xy 360.347305 -230.618284) (xy 360.393579 -230.594706)
			(xy 360.442972 -230.578658) (xy 360.494267 -230.570533) (xy 360.546201 -230.570533) (xy 360.597496 -230.578658)
			(xy 360.646889 -230.594706) (xy 360.693163 -230.618284) (xy 360.735179 -230.64881) (xy 360.771902 -230.685533)
			(xy 360.802428 -230.727549) (xy 360.826006 -230.773823) (xy 360.842054 -230.823216) (xy 360.850179 -230.874511)
			(xy 360.850688 -230.900478) (xy 360.850179 -230.926445) (xy 361.130089 -230.926445) (xy 361.130089 -230.874511)
			(xy 361.138214 -230.823216) (xy 361.154262 -230.773823) (xy 361.17784 -230.727549) (xy 361.208366 -230.685533)
			(xy 361.245089 -230.64881) (xy 361.287105 -230.618284) (xy 361.333379 -230.594706) (xy 361.382772 -230.578658)
			(xy 361.434067 -230.570533) (xy 361.486001 -230.570533) (xy 361.537296 -230.578658) (xy 361.586689 -230.594706)
			(xy 361.632963 -230.618284) (xy 361.674979 -230.64881) (xy 361.711702 -230.685533) (xy 361.742228 -230.727549)
			(xy 361.765806 -230.773823) (xy 361.781854 -230.823216) (xy 361.789979 -230.874511) (xy 361.790488 -230.900478)
			(xy 361.789979 -230.926445) (xy 362.070143 -230.926445) (xy 362.070143 -230.874511) (xy 362.078268 -230.823216)
			(xy 362.094316 -230.773823) (xy 362.117894 -230.727549) (xy 362.14842 -230.685533) (xy 362.185143 -230.64881)
			(xy 362.227159 -230.618284) (xy 362.273433 -230.594706) (xy 362.322826 -230.578658) (xy 362.374121 -230.570533)
			(xy 362.426055 -230.570533) (xy 362.47735 -230.578658) (xy 362.526743 -230.594706) (xy 362.573017 -230.618284)
			(xy 362.615033 -230.64881) (xy 362.651756 -230.685533) (xy 362.682282 -230.727549) (xy 362.70586 -230.773823)
			(xy 362.721908 -230.823216) (xy 362.730033 -230.874511) (xy 362.730542 -230.900478) (xy 362.730033 -230.926445)
			(xy 363.009689 -230.926445) (xy 363.009689 -230.874511) (xy 363.017814 -230.823216) (xy 363.033862 -230.773823)
			(xy 363.05744 -230.727549) (xy 363.087966 -230.685533) (xy 363.124689 -230.64881) (xy 363.166705 -230.618284)
			(xy 363.212979 -230.594706) (xy 363.262372 -230.578658) (xy 363.313667 -230.570533) (xy 363.365601 -230.570533)
			(xy 363.416896 -230.578658) (xy 363.466289 -230.594706) (xy 363.512563 -230.618284) (xy 363.554579 -230.64881)
			(xy 363.591302 -230.685533) (xy 363.621828 -230.727549) (xy 363.645406 -230.773823) (xy 363.661454 -230.823216)
			(xy 363.669579 -230.874511) (xy 363.670088 -230.900478) (xy 363.669579 -230.926445) (xy 363.661454 -230.97774)
			(xy 363.645406 -231.027133) (xy 363.621828 -231.073407) (xy 363.591302 -231.115423) (xy 363.554579 -231.152146)
			(xy 363.512563 -231.182672) (xy 363.466289 -231.20625) (xy 363.416896 -231.222298) (xy 363.365601 -231.230423)
			(xy 363.313667 -231.230423) (xy 363.262372 -231.222298) (xy 363.212979 -231.20625) (xy 363.166705 -231.182672)
			(xy 363.124689 -231.152146) (xy 363.087966 -231.115423) (xy 363.05744 -231.073407) (xy 363.033862 -231.027133)
			(xy 363.017814 -230.97774) (xy 363.009689 -230.926445) (xy 362.730033 -230.926445) (xy 362.721908 -230.97774)
			(xy 362.70586 -231.027133) (xy 362.682282 -231.073407) (xy 362.651756 -231.115423) (xy 362.615033 -231.152146)
			(xy 362.573017 -231.182672) (xy 362.526743 -231.20625) (xy 362.47735 -231.222298) (xy 362.426055 -231.230423)
			(xy 362.374121 -231.230423) (xy 362.322826 -231.222298) (xy 362.273433 -231.20625) (xy 362.227159 -231.182672)
			(xy 362.185143 -231.152146) (xy 362.14842 -231.115423) (xy 362.117894 -231.073407) (xy 362.094316 -231.027133)
			(xy 362.078268 -230.97774) (xy 362.070143 -230.926445) (xy 361.789979 -230.926445) (xy 361.781854 -230.97774)
			(xy 361.765806 -231.027133) (xy 361.742228 -231.073407) (xy 361.711702 -231.115423) (xy 361.674979 -231.152146)
			(xy 361.632963 -231.182672) (xy 361.586689 -231.20625) (xy 361.537296 -231.222298) (xy 361.486001 -231.230423)
			(xy 361.434067 -231.230423) (xy 361.382772 -231.222298) (xy 361.333379 -231.20625) (xy 361.287105 -231.182672)
			(xy 361.245089 -231.152146) (xy 361.208366 -231.115423) (xy 361.17784 -231.073407) (xy 361.154262 -231.027133)
			(xy 361.138214 -230.97774) (xy 361.130089 -230.926445) (xy 360.850179 -230.926445) (xy 360.842054 -230.97774)
			(xy 360.826006 -231.027133) (xy 360.802428 -231.073407) (xy 360.771902 -231.115423) (xy 360.735179 -231.152146)
			(xy 360.693163 -231.182672) (xy 360.646889 -231.20625) (xy 360.597496 -231.222298) (xy 360.546201 -231.230423)
			(xy 360.494267 -231.230423) (xy 360.442972 -231.222298) (xy 360.393579 -231.20625) (xy 360.347305 -231.182672)
			(xy 360.305289 -231.152146) (xy 360.268566 -231.115423) (xy 360.23804 -231.073407) (xy 360.214462 -231.027133)
			(xy 360.198414 -230.97774) (xy 360.190289 -230.926445) (xy 359.910379 -230.926445) (xy 359.902254 -230.97774)
			(xy 359.886206 -231.027133) (xy 359.862628 -231.073407) (xy 359.832102 -231.115423) (xy 359.795379 -231.152146)
			(xy 359.753363 -231.182672) (xy 359.707089 -231.20625) (xy 359.657696 -231.222298) (xy 359.606401 -231.230423)
			(xy 359.554467 -231.230423) (xy 359.503172 -231.222298) (xy 359.453779 -231.20625) (xy 359.407505 -231.182672)
			(xy 359.365489 -231.152146) (xy 359.328766 -231.115423) (xy 359.29824 -231.073407) (xy 359.274662 -231.027133)
			(xy 359.258614 -230.97774) (xy 359.250489 -230.926445) (xy 358.970579 -230.926445) (xy 358.962454 -230.97774)
			(xy 358.946406 -231.027133) (xy 358.922828 -231.073407) (xy 358.892302 -231.115423) (xy 358.855579 -231.152146)
			(xy 358.813563 -231.182672) (xy 358.767289 -231.20625) (xy 358.717896 -231.222298) (xy 358.666601 -231.230423)
			(xy 358.614667 -231.230423) (xy 358.563372 -231.222298) (xy 358.513979 -231.20625) (xy 358.467705 -231.182672)
			(xy 358.425689 -231.152146) (xy 358.388966 -231.115423) (xy 358.35844 -231.073407) (xy 358.334862 -231.027133)
			(xy 358.318814 -230.97774) (xy 358.310689 -230.926445) (xy 358.030525 -230.926445) (xy 358.0224 -230.97774)
			(xy 358.006352 -231.027133) (xy 357.982774 -231.073407) (xy 357.952248 -231.115423) (xy 357.915525 -231.152146)
			(xy 357.873509 -231.182672) (xy 357.827235 -231.20625) (xy 357.777842 -231.222298) (xy 357.726547 -231.230423)
			(xy 357.674613 -231.230423) (xy 357.623318 -231.222298) (xy 357.573925 -231.20625) (xy 357.527651 -231.182672)
			(xy 357.485635 -231.152146) (xy 357.448912 -231.115423) (xy 357.418386 -231.073407) (xy 357.394808 -231.027133)
			(xy 357.37876 -230.97774) (xy 357.370635 -230.926445) (xy 357.090979 -230.926445) (xy 357.082854 -230.97774)
			(xy 357.066806 -231.027133) (xy 357.043228 -231.073407) (xy 357.012702 -231.115423) (xy 356.975979 -231.152146)
			(xy 356.933963 -231.182672) (xy 356.887689 -231.20625) (xy 356.838296 -231.222298) (xy 356.787001 -231.230423)
			(xy 356.735067 -231.230423) (xy 356.683772 -231.222298) (xy 356.634379 -231.20625) (xy 356.588105 -231.182672)
			(xy 356.546089 -231.152146) (xy 356.509366 -231.115423) (xy 356.47884 -231.073407) (xy 356.455262 -231.027133)
			(xy 356.439214 -230.97774) (xy 356.431089 -230.926445) (xy 356.150925 -230.926445) (xy 356.1428 -230.97774)
			(xy 356.126752 -231.027133) (xy 356.103174 -231.073407) (xy 356.072648 -231.115423) (xy 356.035925 -231.152146)
			(xy 355.993909 -231.182672) (xy 355.947635 -231.20625) (xy 355.898242 -231.222298) (xy 355.846947 -231.230423)
			(xy 355.795013 -231.230423) (xy 355.743718 -231.222298) (xy 355.694325 -231.20625) (xy 355.648051 -231.182672)
			(xy 355.606035 -231.152146) (xy 355.569312 -231.115423) (xy 355.538786 -231.073407) (xy 355.515208 -231.027133)
			(xy 355.49916 -230.97774) (xy 355.491035 -230.926445) (xy 355.211379 -230.926445) (xy 355.203254 -230.97774)
			(xy 355.187206 -231.027133) (xy 355.163628 -231.073407) (xy 355.133102 -231.115423) (xy 355.096379 -231.152146)
			(xy 355.054363 -231.182672) (xy 355.008089 -231.20625) (xy 354.958696 -231.222298) (xy 354.907401 -231.230423)
			(xy 354.855467 -231.230423) (xy 354.804172 -231.222298) (xy 354.754779 -231.20625) (xy 354.708505 -231.182672)
			(xy 354.666489 -231.152146) (xy 354.629766 -231.115423) (xy 354.59924 -231.073407) (xy 354.575662 -231.027133)
			(xy 354.559614 -230.97774) (xy 354.551489 -230.926445) (xy 354.271579 -230.926445) (xy 354.263454 -230.97774)
			(xy 354.247406 -231.027133) (xy 354.223828 -231.073407) (xy 354.193302 -231.115423) (xy 354.156579 -231.152146)
			(xy 354.114563 -231.182672) (xy 354.068289 -231.20625) (xy 354.018896 -231.222298) (xy 353.967601 -231.230423)
			(xy 353.915667 -231.230423) (xy 353.864372 -231.222298) (xy 353.814979 -231.20625) (xy 353.768705 -231.182672)
			(xy 353.726689 -231.152146) (xy 353.689966 -231.115423) (xy 353.65944 -231.073407) (xy 353.635862 -231.027133)
			(xy 353.619814 -230.97774) (xy 353.611689 -230.926445) (xy 353.331705 -230.926445) (xy 353.323874 -230.97666)
			(xy 353.308289 -231.025412) (xy 353.285376 -231.071181) (xy 353.255685 -231.112872) (xy 353.219923 -231.14949)
			(xy 353.178946 -231.180159) (xy 353.133733 -231.204148) (xy 353.085362 -231.220882) (xy 353.060254 -231.225852)
			(xy 353.018344 -231.233218) (xy 353.018344 -231.740515) (xy 353.141535 -231.740515) (xy 353.141535 -231.688581)
			(xy 353.14966 -231.637286) (xy 353.165708 -231.587893) (xy 353.189286 -231.541619) (xy 353.219812 -231.499603)
			(xy 353.256535 -231.46288) (xy 353.298551 -231.432354) (xy 353.344825 -231.408776) (xy 353.394218 -231.392728)
			(xy 353.445513 -231.384603) (xy 353.497447 -231.384603) (xy 353.548742 -231.392728) (xy 353.598135 -231.408776)
			(xy 353.644409 -231.432354) (xy 353.686425 -231.46288) (xy 353.723148 -231.499603) (xy 353.753674 -231.541619)
			(xy 353.777252 -231.587893) (xy 353.7933 -231.637286) (xy 353.801425 -231.688581) (xy 353.801934 -231.714548)
			(xy 353.801425 -231.740515) (xy 354.081335 -231.740515) (xy 354.081335 -231.688581) (xy 354.08946 -231.637286)
			(xy 354.105508 -231.587893) (xy 354.129086 -231.541619) (xy 354.159612 -231.499603) (xy 354.196335 -231.46288)
			(xy 354.238351 -231.432354) (xy 354.284625 -231.408776) (xy 354.334018 -231.392728) (xy 354.385313 -231.384603)
			(xy 354.437247 -231.384603) (xy 354.488542 -231.392728) (xy 354.537935 -231.408776) (xy 354.584209 -231.432354)
			(xy 354.626225 -231.46288) (xy 354.662948 -231.499603) (xy 354.693474 -231.541619) (xy 354.717052 -231.587893)
			(xy 354.7331 -231.637286) (xy 354.741225 -231.688581) (xy 354.741734 -231.714548) (xy 354.741225 -231.740515)
			(xy 355.021135 -231.740515) (xy 355.021135 -231.688581) (xy 355.02926 -231.637286) (xy 355.045308 -231.587893)
			(xy 355.068886 -231.541619) (xy 355.099412 -231.499603) (xy 355.136135 -231.46288) (xy 355.178151 -231.432354)
			(xy 355.224425 -231.408776) (xy 355.273818 -231.392728) (xy 355.325113 -231.384603) (xy 355.377047 -231.384603)
			(xy 355.428342 -231.392728) (xy 355.477735 -231.408776) (xy 355.524009 -231.432354) (xy 355.566025 -231.46288)
			(xy 355.602748 -231.499603) (xy 355.633274 -231.541619) (xy 355.656852 -231.587893) (xy 355.6729 -231.637286)
			(xy 355.681025 -231.688581) (xy 355.681534 -231.714548) (xy 355.681025 -231.740515) (xy 355.960935 -231.740515)
			(xy 355.960935 -231.688581) (xy 355.96906 -231.637286) (xy 355.985108 -231.587893) (xy 356.008686 -231.541619)
			(xy 356.039212 -231.499603) (xy 356.075935 -231.46288) (xy 356.117951 -231.432354) (xy 356.164225 -231.408776)
			(xy 356.213618 -231.392728) (xy 356.264913 -231.384603) (xy 356.316847 -231.384603) (xy 356.368142 -231.392728)
			(xy 356.417535 -231.408776) (xy 356.463809 -231.432354) (xy 356.505825 -231.46288) (xy 356.542548 -231.499603)
			(xy 356.573074 -231.541619) (xy 356.596652 -231.587893) (xy 356.6127 -231.637286) (xy 356.620825 -231.688581)
			(xy 356.621334 -231.714548) (xy 356.620825 -231.740515) (xy 356.900735 -231.740515) (xy 356.900735 -231.688581)
			(xy 356.90886 -231.637286) (xy 356.924908 -231.587893) (xy 356.948486 -231.541619) (xy 356.979012 -231.499603)
			(xy 357.015735 -231.46288) (xy 357.057751 -231.432354) (xy 357.104025 -231.408776) (xy 357.153418 -231.392728)
			(xy 357.204713 -231.384603) (xy 357.256647 -231.384603) (xy 357.307942 -231.392728) (xy 357.357335 -231.408776)
			(xy 357.403609 -231.432354) (xy 357.445625 -231.46288) (xy 357.482348 -231.499603) (xy 357.512874 -231.541619)
			(xy 357.536452 -231.587893) (xy 357.5525 -231.637286) (xy 357.560625 -231.688581) (xy 357.561134 -231.714548)
			(xy 357.560625 -231.740515) (xy 357.840789 -231.740515) (xy 357.840789 -231.688581) (xy 357.848914 -231.637286)
			(xy 357.864962 -231.587893) (xy 357.88854 -231.541619) (xy 357.919066 -231.499603) (xy 357.955789 -231.46288)
			(xy 357.997805 -231.432354) (xy 358.044079 -231.408776) (xy 358.093472 -231.392728) (xy 358.144767 -231.384603)
			(xy 358.196701 -231.384603) (xy 358.247996 -231.392728) (xy 358.297389 -231.408776) (xy 358.343663 -231.432354)
			(xy 358.385679 -231.46288) (xy 358.422402 -231.499603) (xy 358.452928 -231.541619) (xy 358.476506 -231.587893)
			(xy 358.492554 -231.637286) (xy 358.500679 -231.688581) (xy 358.501188 -231.714548) (xy 358.500679 -231.740515)
			(xy 358.780335 -231.740515) (xy 358.780335 -231.688581) (xy 358.78846 -231.637286) (xy 358.804508 -231.587893)
			(xy 358.828086 -231.541619) (xy 358.858612 -231.499603) (xy 358.895335 -231.46288) (xy 358.937351 -231.432354)
			(xy 358.983625 -231.408776) (xy 359.033018 -231.392728) (xy 359.084313 -231.384603) (xy 359.136247 -231.384603)
			(xy 359.187542 -231.392728) (xy 359.236935 -231.408776) (xy 359.283209 -231.432354) (xy 359.325225 -231.46288)
			(xy 359.361948 -231.499603) (xy 359.392474 -231.541619) (xy 359.416052 -231.587893) (xy 359.4321 -231.637286)
			(xy 359.440225 -231.688581) (xy 359.440734 -231.714548) (xy 359.440225 -231.740515) (xy 359.720643 -231.740515)
			(xy 359.720643 -231.688581) (xy 359.728768 -231.637286) (xy 359.744816 -231.587893) (xy 359.768394 -231.541619)
			(xy 359.79892 -231.499603) (xy 359.835643 -231.46288) (xy 359.877659 -231.432354) (xy 359.923933 -231.408776)
			(xy 359.973326 -231.392728) (xy 360.024621 -231.384603) (xy 360.076555 -231.384603) (xy 360.12785 -231.392728)
			(xy 360.177243 -231.408776) (xy 360.223517 -231.432354) (xy 360.265533 -231.46288) (xy 360.302256 -231.499603)
			(xy 360.332782 -231.541619) (xy 360.35636 -231.587893) (xy 360.372408 -231.637286) (xy 360.380533 -231.688581)
			(xy 360.381042 -231.714548) (xy 360.380533 -231.740515) (xy 360.660443 -231.740515) (xy 360.660443 -231.688581)
			(xy 360.668568 -231.637286) (xy 360.684616 -231.587893) (xy 360.708194 -231.541619) (xy 360.73872 -231.499603)
			(xy 360.775443 -231.46288) (xy 360.817459 -231.432354) (xy 360.863733 -231.408776) (xy 360.913126 -231.392728)
			(xy 360.964421 -231.384603) (xy 361.016355 -231.384603) (xy 361.06765 -231.392728) (xy 361.117043 -231.408776)
			(xy 361.163317 -231.432354) (xy 361.205333 -231.46288) (xy 361.242056 -231.499603) (xy 361.272582 -231.541619)
			(xy 361.29616 -231.587893) (xy 361.312208 -231.637286) (xy 361.320333 -231.688581) (xy 361.320842 -231.714548)
			(xy 361.320333 -231.740515) (xy 361.600243 -231.740515) (xy 361.600243 -231.688581) (xy 361.608368 -231.637286)
			(xy 361.624416 -231.587893) (xy 361.647994 -231.541619) (xy 361.67852 -231.499603) (xy 361.715243 -231.46288)
			(xy 361.757259 -231.432354) (xy 361.803533 -231.408776) (xy 361.852926 -231.392728) (xy 361.904221 -231.384603)
			(xy 361.956155 -231.384603) (xy 362.00745 -231.392728) (xy 362.056843 -231.408776) (xy 362.103117 -231.432354)
			(xy 362.145133 -231.46288) (xy 362.181856 -231.499603) (xy 362.212382 -231.541619) (xy 362.23596 -231.587893)
			(xy 362.252008 -231.637286) (xy 362.260133 -231.688581) (xy 362.260642 -231.714548) (xy 362.260133 -231.740515)
			(xy 362.539535 -231.740515) (xy 362.539535 -231.688581) (xy 362.54766 -231.637286) (xy 362.563708 -231.587893)
			(xy 362.587286 -231.541619) (xy 362.617812 -231.499603) (xy 362.654535 -231.46288) (xy 362.696551 -231.432354)
			(xy 362.742825 -231.408776) (xy 362.792218 -231.392728) (xy 362.843513 -231.384603) (xy 362.895447 -231.384603)
			(xy 362.946742 -231.392728) (xy 362.996135 -231.408776) (xy 363.042409 -231.432354) (xy 363.084425 -231.46288)
			(xy 363.121148 -231.499603) (xy 363.151674 -231.541619) (xy 363.175252 -231.587893) (xy 363.1913 -231.637286)
			(xy 363.199425 -231.688581) (xy 363.199934 -231.714548) (xy 363.199425 -231.740515) (xy 363.479335 -231.740515)
			(xy 363.479335 -231.688581) (xy 363.48746 -231.637286) (xy 363.503508 -231.587893) (xy 363.527086 -231.541619)
			(xy 363.557612 -231.499603) (xy 363.594335 -231.46288) (xy 363.636351 -231.432354) (xy 363.682625 -231.408776)
			(xy 363.732018 -231.392728) (xy 363.783313 -231.384603) (xy 363.835247 -231.384603) (xy 363.886542 -231.392728)
			(xy 363.935935 -231.408776) (xy 363.982209 -231.432354) (xy 364.024225 -231.46288) (xy 364.060948 -231.499603)
			(xy 364.091474 -231.541619) (xy 364.115052 -231.587893) (xy 364.1311 -231.637286) (xy 364.139225 -231.688581)
			(xy 364.139734 -231.714548) (xy 364.139225 -231.740515) (xy 364.419135 -231.740515) (xy 364.419135 -231.688581)
			(xy 364.42726 -231.637286) (xy 364.443308 -231.587893) (xy 364.466886 -231.541619) (xy 364.497412 -231.499603)
			(xy 364.534135 -231.46288) (xy 364.576151 -231.432354) (xy 364.622425 -231.408776) (xy 364.671818 -231.392728)
			(xy 364.723113 -231.384603) (xy 364.775047 -231.384603) (xy 364.826342 -231.392728) (xy 364.875735 -231.408776)
			(xy 364.922009 -231.432354) (xy 364.964025 -231.46288) (xy 365.000748 -231.499603) (xy 365.031274 -231.541619)
			(xy 365.054852 -231.587893) (xy 365.0709 -231.637286) (xy 365.079025 -231.688581) (xy 365.079534 -231.714548)
			(xy 365.079025 -231.740515) (xy 365.358935 -231.740515) (xy 365.358935 -231.688581) (xy 365.36706 -231.637286)
			(xy 365.383108 -231.587893) (xy 365.406686 -231.541619) (xy 365.437212 -231.499603) (xy 365.473935 -231.46288)
			(xy 365.515951 -231.432354) (xy 365.562225 -231.408776) (xy 365.611618 -231.392728) (xy 365.662913 -231.384603)
			(xy 365.714847 -231.384603) (xy 365.766142 -231.392728) (xy 365.815535 -231.408776) (xy 365.861809 -231.432354)
			(xy 365.903825 -231.46288) (xy 365.940548 -231.499603) (xy 365.971074 -231.541619) (xy 365.994652 -231.587893)
			(xy 366.0107 -231.637286) (xy 366.018825 -231.688581) (xy 366.019334 -231.714548) (xy 366.018825 -231.740515)
			(xy 366.298735 -231.740515) (xy 366.298735 -231.688581) (xy 366.30686 -231.637286) (xy 366.322908 -231.587893)
			(xy 366.346486 -231.541619) (xy 366.377012 -231.499603) (xy 366.413735 -231.46288) (xy 366.455751 -231.432354)
			(xy 366.502025 -231.408776) (xy 366.551418 -231.392728) (xy 366.602713 -231.384603) (xy 366.654647 -231.384603)
			(xy 366.705942 -231.392728) (xy 366.755335 -231.408776) (xy 366.801609 -231.432354) (xy 366.843625 -231.46288)
			(xy 366.880348 -231.499603) (xy 366.910874 -231.541619) (xy 366.934452 -231.587893) (xy 366.9505 -231.637286)
			(xy 366.958625 -231.688581) (xy 366.959134 -231.714548) (xy 366.958625 -231.740515) (xy 367.239043 -231.740515)
			(xy 367.239043 -231.688581) (xy 367.247168 -231.637286) (xy 367.263216 -231.587893) (xy 367.286794 -231.541619)
			(xy 367.31732 -231.499603) (xy 367.354043 -231.46288) (xy 367.396059 -231.432354) (xy 367.442333 -231.408776)
			(xy 367.491726 -231.392728) (xy 367.543021 -231.384603) (xy 367.594955 -231.384603) (xy 367.64625 -231.392728)
			(xy 367.695643 -231.408776) (xy 367.741917 -231.432354) (xy 367.783933 -231.46288) (xy 367.820656 -231.499603)
			(xy 367.851182 -231.541619) (xy 367.87476 -231.587893) (xy 367.890808 -231.637286) (xy 367.898933 -231.688581)
			(xy 367.899442 -231.714548) (xy 367.898933 -231.740515) (xy 368.178335 -231.740515) (xy 368.178335 -231.688581)
			(xy 368.18646 -231.637286) (xy 368.202508 -231.587893) (xy 368.226086 -231.541619) (xy 368.256612 -231.499603)
			(xy 368.293335 -231.46288) (xy 368.335351 -231.432354) (xy 368.381625 -231.408776) (xy 368.431018 -231.392728)
			(xy 368.482313 -231.384603) (xy 368.534247 -231.384603) (xy 368.585542 -231.392728) (xy 368.634935 -231.408776)
			(xy 368.681209 -231.432354) (xy 368.723225 -231.46288) (xy 368.759948 -231.499603) (xy 368.790474 -231.541619)
			(xy 368.814052 -231.587893) (xy 368.8301 -231.637286) (xy 368.838225 -231.688581) (xy 368.838734 -231.714548)
			(xy 368.838225 -231.740515) (xy 369.118643 -231.740515) (xy 369.118643 -231.688581) (xy 369.126768 -231.637286)
			(xy 369.142816 -231.587893) (xy 369.166394 -231.541619) (xy 369.19692 -231.499603) (xy 369.233643 -231.46288)
			(xy 369.275659 -231.432354) (xy 369.321933 -231.408776) (xy 369.371326 -231.392728) (xy 369.422621 -231.384603)
			(xy 369.474555 -231.384603) (xy 369.52585 -231.392728) (xy 369.575243 -231.408776) (xy 369.621517 -231.432354)
			(xy 369.663533 -231.46288) (xy 369.700256 -231.499603) (xy 369.730782 -231.541619) (xy 369.75436 -231.587893)
			(xy 369.770408 -231.637286) (xy 369.778533 -231.688581) (xy 369.779042 -231.714548) (xy 369.778533 -231.740515)
			(xy 370.058189 -231.740515) (xy 370.058189 -231.688581) (xy 370.066314 -231.637286) (xy 370.082362 -231.587893)
			(xy 370.10594 -231.541619) (xy 370.136466 -231.499603) (xy 370.173189 -231.46288) (xy 370.215205 -231.432354)
			(xy 370.261479 -231.408776) (xy 370.310872 -231.392728) (xy 370.362167 -231.384603) (xy 370.414101 -231.384603)
			(xy 370.465396 -231.392728) (xy 370.514789 -231.408776) (xy 370.561063 -231.432354) (xy 370.603079 -231.46288)
			(xy 370.639802 -231.499603) (xy 370.670328 -231.541619) (xy 370.693906 -231.587893) (xy 370.709954 -231.637286)
			(xy 370.718079 -231.688581) (xy 370.718588 -231.714548) (xy 370.718079 -231.740515) (xy 370.997735 -231.740515)
			(xy 370.997735 -231.688581) (xy 371.00586 -231.637286) (xy 371.021908 -231.587893) (xy 371.045486 -231.541619)
			(xy 371.076012 -231.499603) (xy 371.112735 -231.46288) (xy 371.154751 -231.432354) (xy 371.201025 -231.408776)
			(xy 371.250418 -231.392728) (xy 371.301713 -231.384603) (xy 371.353647 -231.384603) (xy 371.404942 -231.392728)
			(xy 371.454335 -231.408776) (xy 371.500609 -231.432354) (xy 371.542625 -231.46288) (xy 371.579348 -231.499603)
			(xy 371.609874 -231.541619) (xy 371.633452 -231.587893) (xy 371.6495 -231.637286) (xy 371.657625 -231.688581)
			(xy 371.658134 -231.714548) (xy 371.657625 -231.740515) (xy 371.937535 -231.740515) (xy 371.937535 -231.688581)
			(xy 371.94566 -231.637286) (xy 371.961708 -231.587893) (xy 371.985286 -231.541619) (xy 372.015812 -231.499603)
			(xy 372.052535 -231.46288) (xy 372.094551 -231.432354) (xy 372.140825 -231.408776) (xy 372.190218 -231.392728)
			(xy 372.241513 -231.384603) (xy 372.293447 -231.384603) (xy 372.344742 -231.392728) (xy 372.394135 -231.408776)
			(xy 372.440409 -231.432354) (xy 372.482425 -231.46288) (xy 372.519148 -231.499603) (xy 372.549674 -231.541619)
			(xy 372.573252 -231.587893) (xy 372.5893 -231.637286) (xy 372.597425 -231.688581) (xy 372.597934 -231.714548)
			(xy 372.597425 -231.740515) (xy 372.877335 -231.740515) (xy 372.877335 -231.688581) (xy 372.88546 -231.637286)
			(xy 372.901508 -231.587893) (xy 372.925086 -231.541619) (xy 372.955612 -231.499603) (xy 372.992335 -231.46288)
			(xy 373.034351 -231.432354) (xy 373.080625 -231.408776) (xy 373.130018 -231.392728) (xy 373.181313 -231.384603)
			(xy 373.233247 -231.384603) (xy 373.284542 -231.392728) (xy 373.333935 -231.408776) (xy 373.380209 -231.432354)
			(xy 373.422225 -231.46288) (xy 373.458948 -231.499603) (xy 373.489474 -231.541619) (xy 373.513052 -231.587893)
			(xy 373.5291 -231.637286) (xy 373.537225 -231.688581) (xy 373.537734 -231.714548) (xy 373.537225 -231.740515)
			(xy 373.5291 -231.79181) (xy 373.513052 -231.841203) (xy 373.489474 -231.887477) (xy 373.458948 -231.929493)
			(xy 373.422225 -231.966216) (xy 373.380209 -231.996742) (xy 373.333935 -232.02032) (xy 373.284542 -232.036368)
			(xy 373.233247 -232.044493) (xy 373.181313 -232.044493) (xy 373.130018 -232.036368) (xy 373.080625 -232.02032)
			(xy 373.034351 -231.996742) (xy 372.992335 -231.966216) (xy 372.955612 -231.929493) (xy 372.925086 -231.887477)
			(xy 372.901508 -231.841203) (xy 372.88546 -231.79181) (xy 372.877335 -231.740515) (xy 372.597425 -231.740515)
			(xy 372.5893 -231.79181) (xy 372.573252 -231.841203) (xy 372.549674 -231.887477) (xy 372.519148 -231.929493)
			(xy 372.482425 -231.966216) (xy 372.440409 -231.996742) (xy 372.394135 -232.02032) (xy 372.344742 -232.036368)
			(xy 372.293447 -232.044493) (xy 372.241513 -232.044493) (xy 372.190218 -232.036368) (xy 372.140825 -232.02032)
			(xy 372.094551 -231.996742) (xy 372.052535 -231.966216) (xy 372.015812 -231.929493) (xy 371.985286 -231.887477)
			(xy 371.961708 -231.841203) (xy 371.94566 -231.79181) (xy 371.937535 -231.740515) (xy 371.657625 -231.740515)
			(xy 371.6495 -231.79181) (xy 371.633452 -231.841203) (xy 371.609874 -231.887477) (xy 371.579348 -231.929493)
			(xy 371.542625 -231.966216) (xy 371.500609 -231.996742) (xy 371.454335 -232.02032) (xy 371.404942 -232.036368)
			(xy 371.353647 -232.044493) (xy 371.301713 -232.044493) (xy 371.250418 -232.036368) (xy 371.201025 -232.02032)
			(xy 371.154751 -231.996742) (xy 371.112735 -231.966216) (xy 371.076012 -231.929493) (xy 371.045486 -231.887477)
			(xy 371.021908 -231.841203) (xy 371.00586 -231.79181) (xy 370.997735 -231.740515) (xy 370.718079 -231.740515)
			(xy 370.709954 -231.79181) (xy 370.693906 -231.841203) (xy 370.670328 -231.887477) (xy 370.639802 -231.929493)
			(xy 370.603079 -231.966216) (xy 370.561063 -231.996742) (xy 370.514789 -232.02032) (xy 370.465396 -232.036368)
			(xy 370.414101 -232.044493) (xy 370.362167 -232.044493) (xy 370.310872 -232.036368) (xy 370.261479 -232.02032)
			(xy 370.215205 -231.996742) (xy 370.173189 -231.966216) (xy 370.136466 -231.929493) (xy 370.10594 -231.887477)
			(xy 370.082362 -231.841203) (xy 370.066314 -231.79181) (xy 370.058189 -231.740515) (xy 369.778533 -231.740515)
			(xy 369.770408 -231.79181) (xy 369.75436 -231.841203) (xy 369.730782 -231.887477) (xy 369.700256 -231.929493)
			(xy 369.663533 -231.966216) (xy 369.621517 -231.996742) (xy 369.575243 -232.02032) (xy 369.52585 -232.036368)
			(xy 369.474555 -232.044493) (xy 369.422621 -232.044493) (xy 369.371326 -232.036368) (xy 369.321933 -232.02032)
			(xy 369.275659 -231.996742) (xy 369.233643 -231.966216) (xy 369.19692 -231.929493) (xy 369.166394 -231.887477)
			(xy 369.142816 -231.841203) (xy 369.126768 -231.79181) (xy 369.118643 -231.740515) (xy 368.838225 -231.740515)
			(xy 368.8301 -231.79181) (xy 368.814052 -231.841203) (xy 368.790474 -231.887477) (xy 368.759948 -231.929493)
			(xy 368.723225 -231.966216) (xy 368.681209 -231.996742) (xy 368.634935 -232.02032) (xy 368.585542 -232.036368)
			(xy 368.534247 -232.044493) (xy 368.482313 -232.044493) (xy 368.431018 -232.036368) (xy 368.381625 -232.02032)
			(xy 368.335351 -231.996742) (xy 368.293335 -231.966216) (xy 368.256612 -231.929493) (xy 368.226086 -231.887477)
			(xy 368.202508 -231.841203) (xy 368.18646 -231.79181) (xy 368.178335 -231.740515) (xy 367.898933 -231.740515)
			(xy 367.890808 -231.79181) (xy 367.87476 -231.841203) (xy 367.851182 -231.887477) (xy 367.820656 -231.929493)
			(xy 367.783933 -231.966216) (xy 367.741917 -231.996742) (xy 367.695643 -232.02032) (xy 367.64625 -232.036368)
			(xy 367.594955 -232.044493) (xy 367.543021 -232.044493) (xy 367.491726 -232.036368) (xy 367.442333 -232.02032)
			(xy 367.396059 -231.996742) (xy 367.354043 -231.966216) (xy 367.31732 -231.929493) (xy 367.286794 -231.887477)
			(xy 367.263216 -231.841203) (xy 367.247168 -231.79181) (xy 367.239043 -231.740515) (xy 366.958625 -231.740515)
			(xy 366.9505 -231.79181) (xy 366.934452 -231.841203) (xy 366.910874 -231.887477) (xy 366.880348 -231.929493)
			(xy 366.843625 -231.966216) (xy 366.801609 -231.996742) (xy 366.755335 -232.02032) (xy 366.705942 -232.036368)
			(xy 366.654647 -232.044493) (xy 366.602713 -232.044493) (xy 366.551418 -232.036368) (xy 366.502025 -232.02032)
			(xy 366.455751 -231.996742) (xy 366.413735 -231.966216) (xy 366.377012 -231.929493) (xy 366.346486 -231.887477)
			(xy 366.322908 -231.841203) (xy 366.30686 -231.79181) (xy 366.298735 -231.740515) (xy 366.018825 -231.740515)
			(xy 366.0107 -231.79181) (xy 365.994652 -231.841203) (xy 365.971074 -231.887477) (xy 365.940548 -231.929493)
			(xy 365.903825 -231.966216) (xy 365.861809 -231.996742) (xy 365.815535 -232.02032) (xy 365.766142 -232.036368)
			(xy 365.714847 -232.044493) (xy 365.662913 -232.044493) (xy 365.611618 -232.036368) (xy 365.562225 -232.02032)
			(xy 365.515951 -231.996742) (xy 365.473935 -231.966216) (xy 365.437212 -231.929493) (xy 365.406686 -231.887477)
			(xy 365.383108 -231.841203) (xy 365.36706 -231.79181) (xy 365.358935 -231.740515) (xy 365.079025 -231.740515)
			(xy 365.0709 -231.79181) (xy 365.054852 -231.841203) (xy 365.031274 -231.887477) (xy 365.000748 -231.929493)
			(xy 364.964025 -231.966216) (xy 364.922009 -231.996742) (xy 364.875735 -232.02032) (xy 364.826342 -232.036368)
			(xy 364.775047 -232.044493) (xy 364.723113 -232.044493) (xy 364.671818 -232.036368) (xy 364.622425 -232.02032)
			(xy 364.576151 -231.996742) (xy 364.534135 -231.966216) (xy 364.497412 -231.929493) (xy 364.466886 -231.887477)
			(xy 364.443308 -231.841203) (xy 364.42726 -231.79181) (xy 364.419135 -231.740515) (xy 364.139225 -231.740515)
			(xy 364.1311 -231.79181) (xy 364.115052 -231.841203) (xy 364.091474 -231.887477) (xy 364.060948 -231.929493)
			(xy 364.024225 -231.966216) (xy 363.982209 -231.996742) (xy 363.935935 -232.02032) (xy 363.886542 -232.036368)
			(xy 363.835247 -232.044493) (xy 363.783313 -232.044493) (xy 363.732018 -232.036368) (xy 363.682625 -232.02032)
			(xy 363.636351 -231.996742) (xy 363.594335 -231.966216) (xy 363.557612 -231.929493) (xy 363.527086 -231.887477)
			(xy 363.503508 -231.841203) (xy 363.48746 -231.79181) (xy 363.479335 -231.740515) (xy 363.199425 -231.740515)
			(xy 363.1913 -231.79181) (xy 363.175252 -231.841203) (xy 363.151674 -231.887477) (xy 363.121148 -231.929493)
			(xy 363.084425 -231.966216) (xy 363.042409 -231.996742) (xy 362.996135 -232.02032) (xy 362.946742 -232.036368)
			(xy 362.895447 -232.044493) (xy 362.843513 -232.044493) (xy 362.792218 -232.036368) (xy 362.742825 -232.02032)
			(xy 362.696551 -231.996742) (xy 362.654535 -231.966216) (xy 362.617812 -231.929493) (xy 362.587286 -231.887477)
			(xy 362.563708 -231.841203) (xy 362.54766 -231.79181) (xy 362.539535 -231.740515) (xy 362.260133 -231.740515)
			(xy 362.252008 -231.79181) (xy 362.23596 -231.841203) (xy 362.212382 -231.887477) (xy 362.181856 -231.929493)
			(xy 362.145133 -231.966216) (xy 362.103117 -231.996742) (xy 362.056843 -232.02032) (xy 362.00745 -232.036368)
			(xy 361.956155 -232.044493) (xy 361.904221 -232.044493) (xy 361.852926 -232.036368) (xy 361.803533 -232.02032)
			(xy 361.757259 -231.996742) (xy 361.715243 -231.966216) (xy 361.67852 -231.929493) (xy 361.647994 -231.887477)
			(xy 361.624416 -231.841203) (xy 361.608368 -231.79181) (xy 361.600243 -231.740515) (xy 361.320333 -231.740515)
			(xy 361.312208 -231.79181) (xy 361.29616 -231.841203) (xy 361.272582 -231.887477) (xy 361.242056 -231.929493)
			(xy 361.205333 -231.966216) (xy 361.163317 -231.996742) (xy 361.117043 -232.02032) (xy 361.06765 -232.036368)
			(xy 361.016355 -232.044493) (xy 360.964421 -232.044493) (xy 360.913126 -232.036368) (xy 360.863733 -232.02032)
			(xy 360.817459 -231.996742) (xy 360.775443 -231.966216) (xy 360.73872 -231.929493) (xy 360.708194 -231.887477)
			(xy 360.684616 -231.841203) (xy 360.668568 -231.79181) (xy 360.660443 -231.740515) (xy 360.380533 -231.740515)
			(xy 360.372408 -231.79181) (xy 360.35636 -231.841203) (xy 360.332782 -231.887477) (xy 360.302256 -231.929493)
			(xy 360.265533 -231.966216) (xy 360.223517 -231.996742) (xy 360.177243 -232.02032) (xy 360.12785 -232.036368)
			(xy 360.076555 -232.044493) (xy 360.024621 -232.044493) (xy 359.973326 -232.036368) (xy 359.923933 -232.02032)
			(xy 359.877659 -231.996742) (xy 359.835643 -231.966216) (xy 359.79892 -231.929493) (xy 359.768394 -231.887477)
			(xy 359.744816 -231.841203) (xy 359.728768 -231.79181) (xy 359.720643 -231.740515) (xy 359.440225 -231.740515)
			(xy 359.4321 -231.79181) (xy 359.416052 -231.841203) (xy 359.392474 -231.887477) (xy 359.361948 -231.929493)
			(xy 359.325225 -231.966216) (xy 359.283209 -231.996742) (xy 359.236935 -232.02032) (xy 359.187542 -232.036368)
			(xy 359.136247 -232.044493) (xy 359.084313 -232.044493) (xy 359.033018 -232.036368) (xy 358.983625 -232.02032)
			(xy 358.937351 -231.996742) (xy 358.895335 -231.966216) (xy 358.858612 -231.929493) (xy 358.828086 -231.887477)
			(xy 358.804508 -231.841203) (xy 358.78846 -231.79181) (xy 358.780335 -231.740515) (xy 358.500679 -231.740515)
			(xy 358.492554 -231.79181) (xy 358.476506 -231.841203) (xy 358.452928 -231.887477) (xy 358.422402 -231.929493)
			(xy 358.385679 -231.966216) (xy 358.343663 -231.996742) (xy 358.297389 -232.02032) (xy 358.247996 -232.036368)
			(xy 358.196701 -232.044493) (xy 358.144767 -232.044493) (xy 358.093472 -232.036368) (xy 358.044079 -232.02032)
			(xy 357.997805 -231.996742) (xy 357.955789 -231.966216) (xy 357.919066 -231.929493) (xy 357.88854 -231.887477)
			(xy 357.864962 -231.841203) (xy 357.848914 -231.79181) (xy 357.840789 -231.740515) (xy 357.560625 -231.740515)
			(xy 357.5525 -231.79181) (xy 357.536452 -231.841203) (xy 357.512874 -231.887477) (xy 357.482348 -231.929493)
			(xy 357.445625 -231.966216) (xy 357.403609 -231.996742) (xy 357.357335 -232.02032) (xy 357.307942 -232.036368)
			(xy 357.256647 -232.044493) (xy 357.204713 -232.044493) (xy 357.153418 -232.036368) (xy 357.104025 -232.02032)
			(xy 357.057751 -231.996742) (xy 357.015735 -231.966216) (xy 356.979012 -231.929493) (xy 356.948486 -231.887477)
			(xy 356.924908 -231.841203) (xy 356.90886 -231.79181) (xy 356.900735 -231.740515) (xy 356.620825 -231.740515)
			(xy 356.6127 -231.79181) (xy 356.596652 -231.841203) (xy 356.573074 -231.887477) (xy 356.542548 -231.929493)
			(xy 356.505825 -231.966216) (xy 356.463809 -231.996742) (xy 356.417535 -232.02032) (xy 356.368142 -232.036368)
			(xy 356.316847 -232.044493) (xy 356.264913 -232.044493) (xy 356.213618 -232.036368) (xy 356.164225 -232.02032)
			(xy 356.117951 -231.996742) (xy 356.075935 -231.966216) (xy 356.039212 -231.929493) (xy 356.008686 -231.887477)
			(xy 355.985108 -231.841203) (xy 355.96906 -231.79181) (xy 355.960935 -231.740515) (xy 355.681025 -231.740515)
			(xy 355.6729 -231.79181) (xy 355.656852 -231.841203) (xy 355.633274 -231.887477) (xy 355.602748 -231.929493)
			(xy 355.566025 -231.966216) (xy 355.524009 -231.996742) (xy 355.477735 -232.02032) (xy 355.428342 -232.036368)
			(xy 355.377047 -232.044493) (xy 355.325113 -232.044493) (xy 355.273818 -232.036368) (xy 355.224425 -232.02032)
			(xy 355.178151 -231.996742) (xy 355.136135 -231.966216) (xy 355.099412 -231.929493) (xy 355.068886 -231.887477)
			(xy 355.045308 -231.841203) (xy 355.02926 -231.79181) (xy 355.021135 -231.740515) (xy 354.741225 -231.740515)
			(xy 354.7331 -231.79181) (xy 354.717052 -231.841203) (xy 354.693474 -231.887477) (xy 354.662948 -231.929493)
			(xy 354.626225 -231.966216) (xy 354.584209 -231.996742) (xy 354.537935 -232.02032) (xy 354.488542 -232.036368)
			(xy 354.437247 -232.044493) (xy 354.385313 -232.044493) (xy 354.334018 -232.036368) (xy 354.284625 -232.02032)
			(xy 354.238351 -231.996742) (xy 354.196335 -231.966216) (xy 354.159612 -231.929493) (xy 354.129086 -231.887477)
			(xy 354.105508 -231.841203) (xy 354.08946 -231.79181) (xy 354.081335 -231.740515) (xy 353.801425 -231.740515)
			(xy 353.7933 -231.79181) (xy 353.777252 -231.841203) (xy 353.753674 -231.887477) (xy 353.723148 -231.929493)
			(xy 353.686425 -231.966216) (xy 353.644409 -231.996742) (xy 353.598135 -232.02032) (xy 353.548742 -232.036368)
			(xy 353.497447 -232.044493) (xy 353.445513 -232.044493) (xy 353.394218 -232.036368) (xy 353.344825 -232.02032)
			(xy 353.298551 -231.996742) (xy 353.256535 -231.966216) (xy 353.219812 -231.929493) (xy 353.189286 -231.887477)
			(xy 353.165708 -231.841203) (xy 353.14966 -231.79181) (xy 353.141535 -231.740515) (xy 353.018344 -231.740515)
			(xy 353.018344 -232.195624) (xy 353.060254 -232.20299) (xy 353.085356 -232.208002) (xy 353.133729 -232.224735)
			(xy 353.178945 -232.248724) (xy 353.219925 -232.279393) (xy 353.255689 -232.316011) (xy 353.285383 -232.357703)
			(xy 353.308297 -232.403473) (xy 353.323885 -232.452227) (xy 353.331774 -232.502801) (xy 353.331775 -232.553986)
			(xy 353.331721 -232.554331) (xy 353.611689 -232.554331) (xy 353.611689 -232.502397) (xy 353.619814 -232.451102)
			(xy 353.635862 -232.401709) (xy 353.65944 -232.355435) (xy 353.689966 -232.313419) (xy 353.726689 -232.276696)
			(xy 353.768705 -232.24617) (xy 353.814979 -232.222592) (xy 353.864372 -232.206544) (xy 353.915667 -232.198419)
			(xy 353.967601 -232.198419) (xy 354.018896 -232.206544) (xy 354.068289 -232.222592) (xy 354.114563 -232.24617)
			(xy 354.156579 -232.276696) (xy 354.193302 -232.313419) (xy 354.223828 -232.355435) (xy 354.247406 -232.401709)
			(xy 354.263454 -232.451102) (xy 354.271579 -232.502397) (xy 354.272088 -232.528364) (xy 354.271579 -232.554331)
			(xy 354.551489 -232.554331) (xy 354.551489 -232.502397) (xy 354.559614 -232.451102) (xy 354.575662 -232.401709)
			(xy 354.59924 -232.355435) (xy 354.629766 -232.313419) (xy 354.666489 -232.276696) (xy 354.708505 -232.24617)
			(xy 354.754779 -232.222592) (xy 354.804172 -232.206544) (xy 354.855467 -232.198419) (xy 354.907401 -232.198419)
			(xy 354.958696 -232.206544) (xy 355.008089 -232.222592) (xy 355.054363 -232.24617) (xy 355.096379 -232.276696)
			(xy 355.133102 -232.313419) (xy 355.163628 -232.355435) (xy 355.187206 -232.401709) (xy 355.203254 -232.451102)
			(xy 355.211379 -232.502397) (xy 355.211888 -232.528364) (xy 355.211379 -232.554331) (xy 355.491289 -232.554331)
			(xy 355.491289 -232.502397) (xy 355.499414 -232.451102) (xy 355.515462 -232.401709) (xy 355.53904 -232.355435)
			(xy 355.569566 -232.313419) (xy 355.606289 -232.276696) (xy 355.648305 -232.24617) (xy 355.694579 -232.222592)
			(xy 355.743972 -232.206544) (xy 355.795267 -232.198419) (xy 355.847201 -232.198419) (xy 355.898496 -232.206544)
			(xy 355.947889 -232.222592) (xy 355.994163 -232.24617) (xy 356.036179 -232.276696) (xy 356.072902 -232.313419)
			(xy 356.103428 -232.355435) (xy 356.127006 -232.401709) (xy 356.143054 -232.451102) (xy 356.151179 -232.502397)
			(xy 356.151688 -232.528364) (xy 356.151179 -232.554331) (xy 356.431089 -232.554331) (xy 356.431089 -232.502397)
			(xy 356.439214 -232.451102) (xy 356.455262 -232.401709) (xy 356.47884 -232.355435) (xy 356.509366 -232.313419)
			(xy 356.546089 -232.276696) (xy 356.588105 -232.24617) (xy 356.634379 -232.222592) (xy 356.683772 -232.206544)
			(xy 356.735067 -232.198419) (xy 356.787001 -232.198419) (xy 356.838296 -232.206544) (xy 356.887689 -232.222592)
			(xy 356.933963 -232.24617) (xy 356.975979 -232.276696) (xy 357.012702 -232.313419) (xy 357.043228 -232.355435)
			(xy 357.066806 -232.401709) (xy 357.082854 -232.451102) (xy 357.090979 -232.502397) (xy 357.091488 -232.528364)
			(xy 357.090979 -232.554331) (xy 357.370889 -232.554331) (xy 357.370889 -232.502397) (xy 357.379014 -232.451102)
			(xy 357.395062 -232.401709) (xy 357.41864 -232.355435) (xy 357.449166 -232.313419) (xy 357.485889 -232.276696)
			(xy 357.527905 -232.24617) (xy 357.574179 -232.222592) (xy 357.623572 -232.206544) (xy 357.674867 -232.198419)
			(xy 357.726801 -232.198419) (xy 357.778096 -232.206544) (xy 357.827489 -232.222592) (xy 357.873763 -232.24617)
			(xy 357.915779 -232.276696) (xy 357.952502 -232.313419) (xy 357.983028 -232.355435) (xy 358.006606 -232.401709)
			(xy 358.022654 -232.451102) (xy 358.030779 -232.502397) (xy 358.031288 -232.528364) (xy 358.030779 -232.554331)
			(xy 358.310689 -232.554331) (xy 358.310689 -232.502397) (xy 358.318814 -232.451102) (xy 358.334862 -232.401709)
			(xy 358.35844 -232.355435) (xy 358.388966 -232.313419) (xy 358.425689 -232.276696) (xy 358.467705 -232.24617)
			(xy 358.513979 -232.222592) (xy 358.563372 -232.206544) (xy 358.614667 -232.198419) (xy 358.666601 -232.198419)
			(xy 358.717896 -232.206544) (xy 358.767289 -232.222592) (xy 358.813563 -232.24617) (xy 358.855579 -232.276696)
			(xy 358.892302 -232.313419) (xy 358.922828 -232.355435) (xy 358.946406 -232.401709) (xy 358.962454 -232.451102)
			(xy 358.970579 -232.502397) (xy 358.971088 -232.528364) (xy 358.970579 -232.554331) (xy 359.250489 -232.554331)
			(xy 359.250489 -232.502397) (xy 359.258614 -232.451102) (xy 359.274662 -232.401709) (xy 359.29824 -232.355435)
			(xy 359.328766 -232.313419) (xy 359.365489 -232.276696) (xy 359.407505 -232.24617) (xy 359.453779 -232.222592)
			(xy 359.503172 -232.206544) (xy 359.554467 -232.198419) (xy 359.606401 -232.198419) (xy 359.657696 -232.206544)
			(xy 359.707089 -232.222592) (xy 359.753363 -232.24617) (xy 359.795379 -232.276696) (xy 359.832102 -232.313419)
			(xy 359.862628 -232.355435) (xy 359.886206 -232.401709) (xy 359.902254 -232.451102) (xy 359.910379 -232.502397)
			(xy 359.910888 -232.528364) (xy 359.910379 -232.554331) (xy 360.190289 -232.554331) (xy 360.190289 -232.502397)
			(xy 360.198414 -232.451102) (xy 360.214462 -232.401709) (xy 360.23804 -232.355435) (xy 360.268566 -232.313419)
			(xy 360.305289 -232.276696) (xy 360.347305 -232.24617) (xy 360.393579 -232.222592) (xy 360.442972 -232.206544)
			(xy 360.494267 -232.198419) (xy 360.546201 -232.198419) (xy 360.597496 -232.206544) (xy 360.646889 -232.222592)
			(xy 360.693163 -232.24617) (xy 360.735179 -232.276696) (xy 360.771902 -232.313419) (xy 360.802428 -232.355435)
			(xy 360.826006 -232.401709) (xy 360.842054 -232.451102) (xy 360.850179 -232.502397) (xy 360.850688 -232.528364)
			(xy 360.850179 -232.554331) (xy 361.130089 -232.554331) (xy 361.130089 -232.502397) (xy 361.138214 -232.451102)
			(xy 361.154262 -232.401709) (xy 361.17784 -232.355435) (xy 361.208366 -232.313419) (xy 361.245089 -232.276696)
			(xy 361.287105 -232.24617) (xy 361.333379 -232.222592) (xy 361.382772 -232.206544) (xy 361.434067 -232.198419)
			(xy 361.486001 -232.198419) (xy 361.537296 -232.206544) (xy 361.586689 -232.222592) (xy 361.632963 -232.24617)
			(xy 361.674979 -232.276696) (xy 361.711702 -232.313419) (xy 361.742228 -232.355435) (xy 361.765806 -232.401709)
			(xy 361.781854 -232.451102) (xy 361.789979 -232.502397) (xy 361.790488 -232.528364) (xy 361.789979 -232.554331)
			(xy 362.069889 -232.554331) (xy 362.069889 -232.502397) (xy 362.078014 -232.451102) (xy 362.094062 -232.401709)
			(xy 362.11764 -232.355435) (xy 362.148166 -232.313419) (xy 362.184889 -232.276696) (xy 362.226905 -232.24617)
			(xy 362.273179 -232.222592) (xy 362.322572 -232.206544) (xy 362.373867 -232.198419) (xy 362.425801 -232.198419)
			(xy 362.477096 -232.206544) (xy 362.526489 -232.222592) (xy 362.572763 -232.24617) (xy 362.614779 -232.276696)
			(xy 362.651502 -232.313419) (xy 362.682028 -232.355435) (xy 362.705606 -232.401709) (xy 362.721654 -232.451102)
			(xy 362.729779 -232.502397) (xy 362.730288 -232.528364) (xy 362.729779 -232.554331) (xy 363.009689 -232.554331)
			(xy 363.009689 -232.502397) (xy 363.017814 -232.451102) (xy 363.033862 -232.401709) (xy 363.05744 -232.355435)
			(xy 363.087966 -232.313419) (xy 363.124689 -232.276696) (xy 363.166705 -232.24617) (xy 363.212979 -232.222592)
			(xy 363.262372 -232.206544) (xy 363.313667 -232.198419) (xy 363.365601 -232.198419) (xy 363.416896 -232.206544)
			(xy 363.466289 -232.222592) (xy 363.512563 -232.24617) (xy 363.554579 -232.276696) (xy 363.591302 -232.313419)
			(xy 363.621828 -232.355435) (xy 363.645406 -232.401709) (xy 363.661454 -232.451102) (xy 363.669579 -232.502397)
			(xy 363.670088 -232.528364) (xy 363.669579 -232.554331) (xy 363.949489 -232.554331) (xy 363.949489 -232.502397)
			(xy 363.957614 -232.451102) (xy 363.973662 -232.401709) (xy 363.99724 -232.355435) (xy 364.027766 -232.313419)
			(xy 364.064489 -232.276696) (xy 364.106505 -232.24617) (xy 364.152779 -232.222592) (xy 364.202172 -232.206544)
			(xy 364.253467 -232.198419) (xy 364.305401 -232.198419) (xy 364.356696 -232.206544) (xy 364.406089 -232.222592)
			(xy 364.452363 -232.24617) (xy 364.494379 -232.276696) (xy 364.531102 -232.313419) (xy 364.561628 -232.355435)
			(xy 364.585206 -232.401709) (xy 364.601254 -232.451102) (xy 364.609379 -232.502397) (xy 364.609888 -232.528364)
			(xy 364.609379 -232.554331) (xy 364.889289 -232.554331) (xy 364.889289 -232.502397) (xy 364.897414 -232.451102)
			(xy 364.913462 -232.401709) (xy 364.93704 -232.355435) (xy 364.967566 -232.313419) (xy 365.004289 -232.276696)
			(xy 365.046305 -232.24617) (xy 365.092579 -232.222592) (xy 365.141972 -232.206544) (xy 365.193267 -232.198419)
			(xy 365.245201 -232.198419) (xy 365.296496 -232.206544) (xy 365.345889 -232.222592) (xy 365.392163 -232.24617)
			(xy 365.434179 -232.276696) (xy 365.470902 -232.313419) (xy 365.501428 -232.355435) (xy 365.525006 -232.401709)
			(xy 365.541054 -232.451102) (xy 365.549179 -232.502397) (xy 365.549688 -232.528364) (xy 365.549179 -232.554331)
			(xy 365.829089 -232.554331) (xy 365.829089 -232.502397) (xy 365.837214 -232.451102) (xy 365.853262 -232.401709)
			(xy 365.87684 -232.355435) (xy 365.907366 -232.313419) (xy 365.944089 -232.276696) (xy 365.986105 -232.24617)
			(xy 366.032379 -232.222592) (xy 366.081772 -232.206544) (xy 366.133067 -232.198419) (xy 366.185001 -232.198419)
			(xy 366.236296 -232.206544) (xy 366.285689 -232.222592) (xy 366.331963 -232.24617) (xy 366.373979 -232.276696)
			(xy 366.410702 -232.313419) (xy 366.441228 -232.355435) (xy 366.464806 -232.401709) (xy 366.480854 -232.451102)
			(xy 366.488979 -232.502397) (xy 366.489488 -232.528364) (xy 366.488979 -232.554331) (xy 366.768889 -232.554331)
			(xy 366.768889 -232.502397) (xy 366.777014 -232.451102) (xy 366.793062 -232.401709) (xy 366.81664 -232.355435)
			(xy 366.847166 -232.313419) (xy 366.883889 -232.276696) (xy 366.925905 -232.24617) (xy 366.972179 -232.222592)
			(xy 367.021572 -232.206544) (xy 367.072867 -232.198419) (xy 367.124801 -232.198419) (xy 367.176096 -232.206544)
			(xy 367.225489 -232.222592) (xy 367.271763 -232.24617) (xy 367.313779 -232.276696) (xy 367.350502 -232.313419)
			(xy 367.381028 -232.355435) (xy 367.404606 -232.401709) (xy 367.420654 -232.451102) (xy 367.428779 -232.502397)
			(xy 367.429288 -232.528364) (xy 367.428779 -232.554331) (xy 367.708435 -232.554331) (xy 367.708435 -232.502397)
			(xy 367.71656 -232.451102) (xy 367.732608 -232.401709) (xy 367.756186 -232.355435) (xy 367.786712 -232.313419)
			(xy 367.823435 -232.276696) (xy 367.865451 -232.24617) (xy 367.911725 -232.222592) (xy 367.961118 -232.206544)
			(xy 368.012413 -232.198419) (xy 368.064347 -232.198419) (xy 368.115642 -232.206544) (xy 368.165035 -232.222592)
			(xy 368.211309 -232.24617) (xy 368.253325 -232.276696) (xy 368.290048 -232.313419) (xy 368.320574 -232.355435)
			(xy 368.344152 -232.401709) (xy 368.3602 -232.451102) (xy 368.368325 -232.502397) (xy 368.368834 -232.528364)
			(xy 368.368325 -232.554331) (xy 368.648489 -232.554331) (xy 368.648489 -232.502397) (xy 368.656614 -232.451102)
			(xy 368.672662 -232.401709) (xy 368.69624 -232.355435) (xy 368.726766 -232.313419) (xy 368.763489 -232.276696)
			(xy 368.805505 -232.24617) (xy 368.851779 -232.222592) (xy 368.901172 -232.206544) (xy 368.952467 -232.198419)
			(xy 369.004401 -232.198419) (xy 369.055696 -232.206544) (xy 369.105089 -232.222592) (xy 369.151363 -232.24617)
			(xy 369.193379 -232.276696) (xy 369.230102 -232.313419) (xy 369.260628 -232.355435) (xy 369.284206 -232.401709)
			(xy 369.300254 -232.451102) (xy 369.308379 -232.502397) (xy 369.308888 -232.528364) (xy 369.308379 -232.554331)
			(xy 369.588289 -232.554331) (xy 369.588289 -232.502397) (xy 369.596414 -232.451102) (xy 369.612462 -232.401709)
			(xy 369.63604 -232.355435) (xy 369.666566 -232.313419) (xy 369.703289 -232.276696) (xy 369.745305 -232.24617)
			(xy 369.791579 -232.222592) (xy 369.840972 -232.206544) (xy 369.892267 -232.198419) (xy 369.944201 -232.198419)
			(xy 369.995496 -232.206544) (xy 370.044889 -232.222592) (xy 370.091163 -232.24617) (xy 370.133179 -232.276696)
			(xy 370.169902 -232.313419) (xy 370.200428 -232.355435) (xy 370.224006 -232.401709) (xy 370.240054 -232.451102)
			(xy 370.248179 -232.502397) (xy 370.248688 -232.528364) (xy 370.248179 -232.554331) (xy 370.528089 -232.554331)
			(xy 370.528089 -232.502397) (xy 370.536214 -232.451102) (xy 370.552262 -232.401709) (xy 370.57584 -232.355435)
			(xy 370.606366 -232.313419) (xy 370.643089 -232.276696) (xy 370.685105 -232.24617) (xy 370.731379 -232.222592)
			(xy 370.780772 -232.206544) (xy 370.832067 -232.198419) (xy 370.884001 -232.198419) (xy 370.935296 -232.206544)
			(xy 370.984689 -232.222592) (xy 371.030963 -232.24617) (xy 371.072979 -232.276696) (xy 371.109702 -232.313419)
			(xy 371.140228 -232.355435) (xy 371.163806 -232.401709) (xy 371.179854 -232.451102) (xy 371.187979 -232.502397)
			(xy 371.188488 -232.528364) (xy 371.187979 -232.554331) (xy 371.467889 -232.554331) (xy 371.467889 -232.502397)
			(xy 371.476014 -232.451102) (xy 371.492062 -232.401709) (xy 371.51564 -232.355435) (xy 371.546166 -232.313419)
			(xy 371.582889 -232.276696) (xy 371.624905 -232.24617) (xy 371.671179 -232.222592) (xy 371.720572 -232.206544)
			(xy 371.771867 -232.198419) (xy 371.823801 -232.198419) (xy 371.875096 -232.206544) (xy 371.924489 -232.222592)
			(xy 371.970763 -232.24617) (xy 372.012779 -232.276696) (xy 372.049502 -232.313419) (xy 372.080028 -232.355435)
			(xy 372.103606 -232.401709) (xy 372.119654 -232.451102) (xy 372.127779 -232.502397) (xy 372.128288 -232.528364)
			(xy 372.127779 -232.554331) (xy 372.407689 -232.554331) (xy 372.407689 -232.502397) (xy 372.415814 -232.451102)
			(xy 372.431862 -232.401709) (xy 372.45544 -232.355435) (xy 372.485966 -232.313419) (xy 372.522689 -232.276696)
			(xy 372.564705 -232.24617) (xy 372.610979 -232.222592) (xy 372.660372 -232.206544) (xy 372.711667 -232.198419)
			(xy 372.763601 -232.198419) (xy 372.814896 -232.206544) (xy 372.864289 -232.222592) (xy 372.910563 -232.24617)
			(xy 372.952579 -232.276696) (xy 372.989302 -232.313419) (xy 373.019828 -232.355435) (xy 373.043406 -232.401709)
			(xy 373.059454 -232.451102) (xy 373.067579 -232.502397) (xy 373.068088 -232.528364) (xy 373.067579 -232.554331)
			(xy 373.059454 -232.605626) (xy 373.043406 -232.655019) (xy 373.019828 -232.701293) (xy 372.989302 -232.743309)
			(xy 372.952579 -232.780032) (xy 372.910563 -232.810558) (xy 372.864289 -232.834136) (xy 372.814896 -232.850184)
			(xy 372.763601 -232.858309) (xy 372.711667 -232.858309) (xy 372.660372 -232.850184) (xy 372.610979 -232.834136)
			(xy 372.564705 -232.810558) (xy 372.522689 -232.780032) (xy 372.485966 -232.743309) (xy 372.45544 -232.701293)
			(xy 372.431862 -232.655019) (xy 372.415814 -232.605626) (xy 372.407689 -232.554331) (xy 372.127779 -232.554331)
			(xy 372.119654 -232.605626) (xy 372.103606 -232.655019) (xy 372.080028 -232.701293) (xy 372.049502 -232.743309)
			(xy 372.012779 -232.780032) (xy 371.970763 -232.810558) (xy 371.924489 -232.834136) (xy 371.875096 -232.850184)
			(xy 371.823801 -232.858309) (xy 371.771867 -232.858309) (xy 371.720572 -232.850184) (xy 371.671179 -232.834136)
			(xy 371.624905 -232.810558) (xy 371.582889 -232.780032) (xy 371.546166 -232.743309) (xy 371.51564 -232.701293)
			(xy 371.492062 -232.655019) (xy 371.476014 -232.605626) (xy 371.467889 -232.554331) (xy 371.187979 -232.554331)
			(xy 371.179854 -232.605626) (xy 371.163806 -232.655019) (xy 371.140228 -232.701293) (xy 371.109702 -232.743309)
			(xy 371.072979 -232.780032) (xy 371.030963 -232.810558) (xy 370.984689 -232.834136) (xy 370.935296 -232.850184)
			(xy 370.884001 -232.858309) (xy 370.832067 -232.858309) (xy 370.780772 -232.850184) (xy 370.731379 -232.834136)
			(xy 370.685105 -232.810558) (xy 370.643089 -232.780032) (xy 370.606366 -232.743309) (xy 370.57584 -232.701293)
			(xy 370.552262 -232.655019) (xy 370.536214 -232.605626) (xy 370.528089 -232.554331) (xy 370.248179 -232.554331)
			(xy 370.240054 -232.605626) (xy 370.224006 -232.655019) (xy 370.200428 -232.701293) (xy 370.169902 -232.743309)
			(xy 370.133179 -232.780032) (xy 370.091163 -232.810558) (xy 370.044889 -232.834136) (xy 369.995496 -232.850184)
			(xy 369.944201 -232.858309) (xy 369.892267 -232.858309) (xy 369.840972 -232.850184) (xy 369.791579 -232.834136)
			(xy 369.745305 -232.810558) (xy 369.703289 -232.780032) (xy 369.666566 -232.743309) (xy 369.63604 -232.701293)
			(xy 369.612462 -232.655019) (xy 369.596414 -232.605626) (xy 369.588289 -232.554331) (xy 369.308379 -232.554331)
			(xy 369.300254 -232.605626) (xy 369.284206 -232.655019) (xy 369.260628 -232.701293) (xy 369.230102 -232.743309)
			(xy 369.193379 -232.780032) (xy 369.151363 -232.810558) (xy 369.105089 -232.834136) (xy 369.055696 -232.850184)
			(xy 369.004401 -232.858309) (xy 368.952467 -232.858309) (xy 368.901172 -232.850184) (xy 368.851779 -232.834136)
			(xy 368.805505 -232.810558) (xy 368.763489 -232.780032) (xy 368.726766 -232.743309) (xy 368.69624 -232.701293)
			(xy 368.672662 -232.655019) (xy 368.656614 -232.605626) (xy 368.648489 -232.554331) (xy 368.368325 -232.554331)
			(xy 368.3602 -232.605626) (xy 368.344152 -232.655019) (xy 368.320574 -232.701293) (xy 368.290048 -232.743309)
			(xy 368.253325 -232.780032) (xy 368.211309 -232.810558) (xy 368.165035 -232.834136) (xy 368.115642 -232.850184)
			(xy 368.064347 -232.858309) (xy 368.012413 -232.858309) (xy 367.961118 -232.850184) (xy 367.911725 -232.834136)
			(xy 367.865451 -232.810558) (xy 367.823435 -232.780032) (xy 367.786712 -232.743309) (xy 367.756186 -232.701293)
			(xy 367.732608 -232.655019) (xy 367.71656 -232.605626) (xy 367.708435 -232.554331) (xy 367.428779 -232.554331)
			(xy 367.420654 -232.605626) (xy 367.404606 -232.655019) (xy 367.381028 -232.701293) (xy 367.350502 -232.743309)
			(xy 367.313779 -232.780032) (xy 367.271763 -232.810558) (xy 367.225489 -232.834136) (xy 367.176096 -232.850184)
			(xy 367.124801 -232.858309) (xy 367.072867 -232.858309) (xy 367.021572 -232.850184) (xy 366.972179 -232.834136)
			(xy 366.925905 -232.810558) (xy 366.883889 -232.780032) (xy 366.847166 -232.743309) (xy 366.81664 -232.701293)
			(xy 366.793062 -232.655019) (xy 366.777014 -232.605626) (xy 366.768889 -232.554331) (xy 366.488979 -232.554331)
			(xy 366.480854 -232.605626) (xy 366.464806 -232.655019) (xy 366.441228 -232.701293) (xy 366.410702 -232.743309)
			(xy 366.373979 -232.780032) (xy 366.331963 -232.810558) (xy 366.285689 -232.834136) (xy 366.236296 -232.850184)
			(xy 366.185001 -232.858309) (xy 366.133067 -232.858309) (xy 366.081772 -232.850184) (xy 366.032379 -232.834136)
			(xy 365.986105 -232.810558) (xy 365.944089 -232.780032) (xy 365.907366 -232.743309) (xy 365.87684 -232.701293)
			(xy 365.853262 -232.655019) (xy 365.837214 -232.605626) (xy 365.829089 -232.554331) (xy 365.549179 -232.554331)
			(xy 365.541054 -232.605626) (xy 365.525006 -232.655019) (xy 365.501428 -232.701293) (xy 365.470902 -232.743309)
			(xy 365.434179 -232.780032) (xy 365.392163 -232.810558) (xy 365.345889 -232.834136) (xy 365.296496 -232.850184)
			(xy 365.245201 -232.858309) (xy 365.193267 -232.858309) (xy 365.141972 -232.850184) (xy 365.092579 -232.834136)
			(xy 365.046305 -232.810558) (xy 365.004289 -232.780032) (xy 364.967566 -232.743309) (xy 364.93704 -232.701293)
			(xy 364.913462 -232.655019) (xy 364.897414 -232.605626) (xy 364.889289 -232.554331) (xy 364.609379 -232.554331)
			(xy 364.601254 -232.605626) (xy 364.585206 -232.655019) (xy 364.561628 -232.701293) (xy 364.531102 -232.743309)
			(xy 364.494379 -232.780032) (xy 364.452363 -232.810558) (xy 364.406089 -232.834136) (xy 364.356696 -232.850184)
			(xy 364.305401 -232.858309) (xy 364.253467 -232.858309) (xy 364.202172 -232.850184) (xy 364.152779 -232.834136)
			(xy 364.106505 -232.810558) (xy 364.064489 -232.780032) (xy 364.027766 -232.743309) (xy 363.99724 -232.701293)
			(xy 363.973662 -232.655019) (xy 363.957614 -232.605626) (xy 363.949489 -232.554331) (xy 363.669579 -232.554331)
			(xy 363.661454 -232.605626) (xy 363.645406 -232.655019) (xy 363.621828 -232.701293) (xy 363.591302 -232.743309)
			(xy 363.554579 -232.780032) (xy 363.512563 -232.810558) (xy 363.466289 -232.834136) (xy 363.416896 -232.850184)
			(xy 363.365601 -232.858309) (xy 363.313667 -232.858309) (xy 363.262372 -232.850184) (xy 363.212979 -232.834136)
			(xy 363.166705 -232.810558) (xy 363.124689 -232.780032) (xy 363.087966 -232.743309) (xy 363.05744 -232.701293)
			(xy 363.033862 -232.655019) (xy 363.017814 -232.605626) (xy 363.009689 -232.554331) (xy 362.729779 -232.554331)
			(xy 362.721654 -232.605626) (xy 362.705606 -232.655019) (xy 362.682028 -232.701293) (xy 362.651502 -232.743309)
			(xy 362.614779 -232.780032) (xy 362.572763 -232.810558) (xy 362.526489 -232.834136) (xy 362.477096 -232.850184)
			(xy 362.425801 -232.858309) (xy 362.373867 -232.858309) (xy 362.322572 -232.850184) (xy 362.273179 -232.834136)
			(xy 362.226905 -232.810558) (xy 362.184889 -232.780032) (xy 362.148166 -232.743309) (xy 362.11764 -232.701293)
			(xy 362.094062 -232.655019) (xy 362.078014 -232.605626) (xy 362.069889 -232.554331) (xy 361.789979 -232.554331)
			(xy 361.781854 -232.605626) (xy 361.765806 -232.655019) (xy 361.742228 -232.701293) (xy 361.711702 -232.743309)
			(xy 361.674979 -232.780032) (xy 361.632963 -232.810558) (xy 361.586689 -232.834136) (xy 361.537296 -232.850184)
			(xy 361.486001 -232.858309) (xy 361.434067 -232.858309) (xy 361.382772 -232.850184) (xy 361.333379 -232.834136)
			(xy 361.287105 -232.810558) (xy 361.245089 -232.780032) (xy 361.208366 -232.743309) (xy 361.17784 -232.701293)
			(xy 361.154262 -232.655019) (xy 361.138214 -232.605626) (xy 361.130089 -232.554331) (xy 360.850179 -232.554331)
			(xy 360.842054 -232.605626) (xy 360.826006 -232.655019) (xy 360.802428 -232.701293) (xy 360.771902 -232.743309)
			(xy 360.735179 -232.780032) (xy 360.693163 -232.810558) (xy 360.646889 -232.834136) (xy 360.597496 -232.850184)
			(xy 360.546201 -232.858309) (xy 360.494267 -232.858309) (xy 360.442972 -232.850184) (xy 360.393579 -232.834136)
			(xy 360.347305 -232.810558) (xy 360.305289 -232.780032) (xy 360.268566 -232.743309) (xy 360.23804 -232.701293)
			(xy 360.214462 -232.655019) (xy 360.198414 -232.605626) (xy 360.190289 -232.554331) (xy 359.910379 -232.554331)
			(xy 359.902254 -232.605626) (xy 359.886206 -232.655019) (xy 359.862628 -232.701293) (xy 359.832102 -232.743309)
			(xy 359.795379 -232.780032) (xy 359.753363 -232.810558) (xy 359.707089 -232.834136) (xy 359.657696 -232.850184)
			(xy 359.606401 -232.858309) (xy 359.554467 -232.858309) (xy 359.503172 -232.850184) (xy 359.453779 -232.834136)
			(xy 359.407505 -232.810558) (xy 359.365489 -232.780032) (xy 359.328766 -232.743309) (xy 359.29824 -232.701293)
			(xy 359.274662 -232.655019) (xy 359.258614 -232.605626) (xy 359.250489 -232.554331) (xy 358.970579 -232.554331)
			(xy 358.962454 -232.605626) (xy 358.946406 -232.655019) (xy 358.922828 -232.701293) (xy 358.892302 -232.743309)
			(xy 358.855579 -232.780032) (xy 358.813563 -232.810558) (xy 358.767289 -232.834136) (xy 358.717896 -232.850184)
			(xy 358.666601 -232.858309) (xy 358.614667 -232.858309) (xy 358.563372 -232.850184) (xy 358.513979 -232.834136)
			(xy 358.467705 -232.810558) (xy 358.425689 -232.780032) (xy 358.388966 -232.743309) (xy 358.35844 -232.701293)
			(xy 358.334862 -232.655019) (xy 358.318814 -232.605626) (xy 358.310689 -232.554331) (xy 358.030779 -232.554331)
			(xy 358.022654 -232.605626) (xy 358.006606 -232.655019) (xy 357.983028 -232.701293) (xy 357.952502 -232.743309)
			(xy 357.915779 -232.780032) (xy 357.873763 -232.810558) (xy 357.827489 -232.834136) (xy 357.778096 -232.850184)
			(xy 357.726801 -232.858309) (xy 357.674867 -232.858309) (xy 357.623572 -232.850184) (xy 357.574179 -232.834136)
			(xy 357.527905 -232.810558) (xy 357.485889 -232.780032) (xy 357.449166 -232.743309) (xy 357.41864 -232.701293)
			(xy 357.395062 -232.655019) (xy 357.379014 -232.605626) (xy 357.370889 -232.554331) (xy 357.090979 -232.554331)
			(xy 357.082854 -232.605626) (xy 357.066806 -232.655019) (xy 357.043228 -232.701293) (xy 357.012702 -232.743309)
			(xy 356.975979 -232.780032) (xy 356.933963 -232.810558) (xy 356.887689 -232.834136) (xy 356.838296 -232.850184)
			(xy 356.787001 -232.858309) (xy 356.735067 -232.858309) (xy 356.683772 -232.850184) (xy 356.634379 -232.834136)
			(xy 356.588105 -232.810558) (xy 356.546089 -232.780032) (xy 356.509366 -232.743309) (xy 356.47884 -232.701293)
			(xy 356.455262 -232.655019) (xy 356.439214 -232.605626) (xy 356.431089 -232.554331) (xy 356.151179 -232.554331)
			(xy 356.143054 -232.605626) (xy 356.127006 -232.655019) (xy 356.103428 -232.701293) (xy 356.072902 -232.743309)
			(xy 356.036179 -232.780032) (xy 355.994163 -232.810558) (xy 355.947889 -232.834136) (xy 355.898496 -232.850184)
			(xy 355.847201 -232.858309) (xy 355.795267 -232.858309) (xy 355.743972 -232.850184) (xy 355.694579 -232.834136)
			(xy 355.648305 -232.810558) (xy 355.606289 -232.780032) (xy 355.569566 -232.743309) (xy 355.53904 -232.701293)
			(xy 355.515462 -232.655019) (xy 355.499414 -232.605626) (xy 355.491289 -232.554331) (xy 355.211379 -232.554331)
			(xy 355.203254 -232.605626) (xy 355.187206 -232.655019) (xy 355.163628 -232.701293) (xy 355.133102 -232.743309)
			(xy 355.096379 -232.780032) (xy 355.054363 -232.810558) (xy 355.008089 -232.834136) (xy 354.958696 -232.850184)
			(xy 354.907401 -232.858309) (xy 354.855467 -232.858309) (xy 354.804172 -232.850184) (xy 354.754779 -232.834136)
			(xy 354.708505 -232.810558) (xy 354.666489 -232.780032) (xy 354.629766 -232.743309) (xy 354.59924 -232.701293)
			(xy 354.575662 -232.655019) (xy 354.559614 -232.605626) (xy 354.551489 -232.554331) (xy 354.271579 -232.554331)
			(xy 354.263454 -232.605626) (xy 354.247406 -232.655019) (xy 354.223828 -232.701293) (xy 354.193302 -232.743309)
			(xy 354.156579 -232.780032) (xy 354.114563 -232.810558) (xy 354.068289 -232.834136) (xy 354.018896 -232.850184)
			(xy 353.967601 -232.858309) (xy 353.915667 -232.858309) (xy 353.864372 -232.850184) (xy 353.814979 -232.834136)
			(xy 353.768705 -232.810558) (xy 353.726689 -232.780032) (xy 353.689966 -232.743309) (xy 353.65944 -232.701293)
			(xy 353.635862 -232.655019) (xy 353.619814 -232.605626) (xy 353.611689 -232.554331) (xy 353.331721 -232.554331)
			(xy 353.323888 -232.604561) (xy 353.308302 -232.653315) (xy 353.285389 -232.699086) (xy 353.255697 -232.740779)
			(xy 353.219934 -232.777399) (xy 353.178956 -232.80807) (xy 353.13374 -232.832059) (xy 353.085368 -232.848795)
			(xy 353.060254 -232.853738) (xy 353.018344 -232.861104) (xy 353.018344 -233.368147) (xy 353.141789 -233.368147)
			(xy 353.141789 -233.316213) (xy 353.149914 -233.264918) (xy 353.165962 -233.215525) (xy 353.18954 -233.169251)
			(xy 353.220066 -233.127235) (xy 353.256789 -233.090512) (xy 353.298805 -233.059986) (xy 353.345079 -233.036408)
			(xy 353.394472 -233.02036) (xy 353.445767 -233.012235) (xy 353.497701 -233.012235) (xy 353.548996 -233.02036)
			(xy 353.598389 -233.036408) (xy 353.644663 -233.059986) (xy 353.686679 -233.090512) (xy 353.723402 -233.127235)
			(xy 353.753928 -233.169251) (xy 353.777506 -233.215525) (xy 353.793554 -233.264918) (xy 353.801679 -233.316213)
			(xy 353.802188 -233.34218) (xy 353.801679 -233.368147) (xy 354.081335 -233.368147) (xy 354.081335 -233.316213)
			(xy 354.08946 -233.264918) (xy 354.105508 -233.215525) (xy 354.129086 -233.169251) (xy 354.159612 -233.127235)
			(xy 354.196335 -233.090512) (xy 354.238351 -233.059986) (xy 354.284625 -233.036408) (xy 354.334018 -233.02036)
			(xy 354.385313 -233.012235) (xy 354.437247 -233.012235) (xy 354.488542 -233.02036) (xy 354.537935 -233.036408)
			(xy 354.584209 -233.059986) (xy 354.626225 -233.090512) (xy 354.662948 -233.127235) (xy 354.693474 -233.169251)
			(xy 354.717052 -233.215525) (xy 354.7331 -233.264918) (xy 354.741225 -233.316213) (xy 354.741734 -233.34218)
			(xy 354.741225 -233.368147) (xy 355.021135 -233.368147) (xy 355.021135 -233.316213) (xy 355.02926 -233.264918)
			(xy 355.045308 -233.215525) (xy 355.068886 -233.169251) (xy 355.099412 -233.127235) (xy 355.136135 -233.090512)
			(xy 355.178151 -233.059986) (xy 355.224425 -233.036408) (xy 355.273818 -233.02036) (xy 355.325113 -233.012235)
			(xy 355.377047 -233.012235) (xy 355.428342 -233.02036) (xy 355.477735 -233.036408) (xy 355.524009 -233.059986)
			(xy 355.566025 -233.090512) (xy 355.602748 -233.127235) (xy 355.633274 -233.169251) (xy 355.656852 -233.215525)
			(xy 355.6729 -233.264918) (xy 355.681025 -233.316213) (xy 355.681534 -233.34218) (xy 355.681025 -233.368147)
			(xy 355.960935 -233.368147) (xy 355.960935 -233.316213) (xy 355.96906 -233.264918) (xy 355.985108 -233.215525)
			(xy 356.008686 -233.169251) (xy 356.039212 -233.127235) (xy 356.075935 -233.090512) (xy 356.117951 -233.059986)
			(xy 356.164225 -233.036408) (xy 356.213618 -233.02036) (xy 356.264913 -233.012235) (xy 356.316847 -233.012235)
			(xy 356.368142 -233.02036) (xy 356.417535 -233.036408) (xy 356.463809 -233.059986) (xy 356.505825 -233.090512)
			(xy 356.542548 -233.127235) (xy 356.573074 -233.169251) (xy 356.596652 -233.215525) (xy 356.6127 -233.264918)
			(xy 356.620825 -233.316213) (xy 356.621334 -233.34218) (xy 356.620825 -233.368147) (xy 356.900735 -233.368147)
			(xy 356.900735 -233.316213) (xy 356.90886 -233.264918) (xy 356.924908 -233.215525) (xy 356.948486 -233.169251)
			(xy 356.979012 -233.127235) (xy 357.015735 -233.090512) (xy 357.057751 -233.059986) (xy 357.104025 -233.036408)
			(xy 357.153418 -233.02036) (xy 357.204713 -233.012235) (xy 357.256647 -233.012235) (xy 357.307942 -233.02036)
			(xy 357.357335 -233.036408) (xy 357.403609 -233.059986) (xy 357.445625 -233.090512) (xy 357.482348 -233.127235)
			(xy 357.512874 -233.169251) (xy 357.536452 -233.215525) (xy 357.5525 -233.264918) (xy 357.560625 -233.316213)
			(xy 357.561134 -233.34218) (xy 357.560625 -233.368147) (xy 357.840789 -233.368147) (xy 357.840789 -233.316213)
			(xy 357.848914 -233.264918) (xy 357.864962 -233.215525) (xy 357.88854 -233.169251) (xy 357.919066 -233.127235)
			(xy 357.955789 -233.090512) (xy 357.997805 -233.059986) (xy 358.044079 -233.036408) (xy 358.093472 -233.02036)
			(xy 358.144767 -233.012235) (xy 358.196701 -233.012235) (xy 358.247996 -233.02036) (xy 358.297389 -233.036408)
			(xy 358.343663 -233.059986) (xy 358.385679 -233.090512) (xy 358.422402 -233.127235) (xy 358.452928 -233.169251)
			(xy 358.476506 -233.215525) (xy 358.492554 -233.264918) (xy 358.500679 -233.316213) (xy 358.501188 -233.34218)
			(xy 358.500679 -233.368147) (xy 358.780335 -233.368147) (xy 358.780335 -233.316213) (xy 358.78846 -233.264918)
			(xy 358.804508 -233.215525) (xy 358.828086 -233.169251) (xy 358.858612 -233.127235) (xy 358.895335 -233.090512)
			(xy 358.937351 -233.059986) (xy 358.983625 -233.036408) (xy 359.033018 -233.02036) (xy 359.084313 -233.012235)
			(xy 359.136247 -233.012235) (xy 359.187542 -233.02036) (xy 359.236935 -233.036408) (xy 359.283209 -233.059986)
			(xy 359.325225 -233.090512) (xy 359.361948 -233.127235) (xy 359.392474 -233.169251) (xy 359.416052 -233.215525)
			(xy 359.4321 -233.264918) (xy 359.440225 -233.316213) (xy 359.440734 -233.34218) (xy 359.440225 -233.368147)
			(xy 359.720135 -233.368147) (xy 359.720135 -233.316213) (xy 359.72826 -233.264918) (xy 359.744308 -233.215525)
			(xy 359.767886 -233.169251) (xy 359.798412 -233.127235) (xy 359.835135 -233.090512) (xy 359.877151 -233.059986)
			(xy 359.923425 -233.036408) (xy 359.972818 -233.02036) (xy 360.024113 -233.012235) (xy 360.076047 -233.012235)
			(xy 360.127342 -233.02036) (xy 360.176735 -233.036408) (xy 360.223009 -233.059986) (xy 360.265025 -233.090512)
			(xy 360.301748 -233.127235) (xy 360.332274 -233.169251) (xy 360.355852 -233.215525) (xy 360.3719 -233.264918)
			(xy 360.380025 -233.316213) (xy 360.380534 -233.34218) (xy 360.380025 -233.368147) (xy 360.659935 -233.368147)
			(xy 360.659935 -233.316213) (xy 360.66806 -233.264918) (xy 360.684108 -233.215525) (xy 360.707686 -233.169251)
			(xy 360.738212 -233.127235) (xy 360.774935 -233.090512) (xy 360.816951 -233.059986) (xy 360.863225 -233.036408)
			(xy 360.912618 -233.02036) (xy 360.963913 -233.012235) (xy 361.015847 -233.012235) (xy 361.067142 -233.02036)
			(xy 361.116535 -233.036408) (xy 361.162809 -233.059986) (xy 361.204825 -233.090512) (xy 361.241548 -233.127235)
			(xy 361.272074 -233.169251) (xy 361.295652 -233.215525) (xy 361.3117 -233.264918) (xy 361.319825 -233.316213)
			(xy 361.320334 -233.34218) (xy 361.319825 -233.368147) (xy 361.599989 -233.368147) (xy 361.599989 -233.316213)
			(xy 361.608114 -233.264918) (xy 361.624162 -233.215525) (xy 361.64774 -233.169251) (xy 361.678266 -233.127235)
			(xy 361.714989 -233.090512) (xy 361.757005 -233.059986) (xy 361.803279 -233.036408) (xy 361.852672 -233.02036)
			(xy 361.903967 -233.012235) (xy 361.955901 -233.012235) (xy 362.007196 -233.02036) (xy 362.056589 -233.036408)
			(xy 362.102863 -233.059986) (xy 362.144879 -233.090512) (xy 362.181602 -233.127235) (xy 362.212128 -233.169251)
			(xy 362.235706 -233.215525) (xy 362.251754 -233.264918) (xy 362.259879 -233.316213) (xy 362.260388 -233.34218)
			(xy 362.259879 -233.368147) (xy 362.539535 -233.368147) (xy 362.539535 -233.316213) (xy 362.54766 -233.264918)
			(xy 362.563708 -233.215525) (xy 362.587286 -233.169251) (xy 362.617812 -233.127235) (xy 362.654535 -233.090512)
			(xy 362.696551 -233.059986) (xy 362.742825 -233.036408) (xy 362.792218 -233.02036) (xy 362.843513 -233.012235)
			(xy 362.895447 -233.012235) (xy 362.946742 -233.02036) (xy 362.996135 -233.036408) (xy 363.042409 -233.059986)
			(xy 363.084425 -233.090512) (xy 363.121148 -233.127235) (xy 363.151674 -233.169251) (xy 363.175252 -233.215525)
			(xy 363.1913 -233.264918) (xy 363.199425 -233.316213) (xy 363.199934 -233.34218) (xy 363.199425 -233.368147)
			(xy 363.479335 -233.368147) (xy 363.479335 -233.316213) (xy 363.48746 -233.264918) (xy 363.503508 -233.215525)
			(xy 363.527086 -233.169251) (xy 363.557612 -233.127235) (xy 363.594335 -233.090512) (xy 363.636351 -233.059986)
			(xy 363.682625 -233.036408) (xy 363.732018 -233.02036) (xy 363.783313 -233.012235) (xy 363.835247 -233.012235)
			(xy 363.886542 -233.02036) (xy 363.935935 -233.036408) (xy 363.982209 -233.059986) (xy 364.024225 -233.090512)
			(xy 364.060948 -233.127235) (xy 364.091474 -233.169251) (xy 364.115052 -233.215525) (xy 364.1311 -233.264918)
			(xy 364.139225 -233.316213) (xy 364.139734 -233.34218) (xy 364.139225 -233.368147) (xy 364.419135 -233.368147)
			(xy 364.419135 -233.316213) (xy 364.42726 -233.264918) (xy 364.443308 -233.215525) (xy 364.466886 -233.169251)
			(xy 364.497412 -233.127235) (xy 364.534135 -233.090512) (xy 364.576151 -233.059986) (xy 364.622425 -233.036408)
			(xy 364.671818 -233.02036) (xy 364.723113 -233.012235) (xy 364.775047 -233.012235) (xy 364.826342 -233.02036)
			(xy 364.875735 -233.036408) (xy 364.922009 -233.059986) (xy 364.964025 -233.090512) (xy 365.000748 -233.127235)
			(xy 365.031274 -233.169251) (xy 365.054852 -233.215525) (xy 365.0709 -233.264918) (xy 365.079025 -233.316213)
			(xy 365.079534 -233.34218) (xy 365.079025 -233.368147) (xy 365.358935 -233.368147) (xy 365.358935 -233.316213)
			(xy 365.36706 -233.264918) (xy 365.383108 -233.215525) (xy 365.406686 -233.169251) (xy 365.437212 -233.127235)
			(xy 365.473935 -233.090512) (xy 365.515951 -233.059986) (xy 365.562225 -233.036408) (xy 365.611618 -233.02036)
			(xy 365.662913 -233.012235) (xy 365.714847 -233.012235) (xy 365.766142 -233.02036) (xy 365.815535 -233.036408)
			(xy 365.861809 -233.059986) (xy 365.903825 -233.090512) (xy 365.940548 -233.127235) (xy 365.971074 -233.169251)
			(xy 365.994652 -233.215525) (xy 366.0107 -233.264918) (xy 366.018825 -233.316213) (xy 366.019334 -233.34218)
			(xy 366.018825 -233.368147) (xy 366.298735 -233.368147) (xy 366.298735 -233.316213) (xy 366.30686 -233.264918)
			(xy 366.322908 -233.215525) (xy 366.346486 -233.169251) (xy 366.377012 -233.127235) (xy 366.413735 -233.090512)
			(xy 366.455751 -233.059986) (xy 366.502025 -233.036408) (xy 366.551418 -233.02036) (xy 366.602713 -233.012235)
			(xy 366.654647 -233.012235) (xy 366.705942 -233.02036) (xy 366.755335 -233.036408) (xy 366.801609 -233.059986)
			(xy 366.843625 -233.090512) (xy 366.880348 -233.127235) (xy 366.910874 -233.169251) (xy 366.934452 -233.215525)
			(xy 366.9505 -233.264918) (xy 366.958625 -233.316213) (xy 366.959134 -233.34218) (xy 366.958625 -233.368147)
			(xy 367.238535 -233.368147) (xy 367.238535 -233.316213) (xy 367.24666 -233.264918) (xy 367.262708 -233.215525)
			(xy 367.286286 -233.169251) (xy 367.316812 -233.127235) (xy 367.353535 -233.090512) (xy 367.395551 -233.059986)
			(xy 367.441825 -233.036408) (xy 367.491218 -233.02036) (xy 367.542513 -233.012235) (xy 367.594447 -233.012235)
			(xy 367.645742 -233.02036) (xy 367.695135 -233.036408) (xy 367.741409 -233.059986) (xy 367.783425 -233.090512)
			(xy 367.820148 -233.127235) (xy 367.850674 -233.169251) (xy 367.874252 -233.215525) (xy 367.8903 -233.264918)
			(xy 367.898425 -233.316213) (xy 367.898934 -233.34218) (xy 367.898425 -233.368147) (xy 368.178335 -233.368147)
			(xy 368.178335 -233.316213) (xy 368.18646 -233.264918) (xy 368.202508 -233.215525) (xy 368.226086 -233.169251)
			(xy 368.256612 -233.127235) (xy 368.293335 -233.090512) (xy 368.335351 -233.059986) (xy 368.381625 -233.036408)
			(xy 368.431018 -233.02036) (xy 368.482313 -233.012235) (xy 368.534247 -233.012235) (xy 368.585542 -233.02036)
			(xy 368.634935 -233.036408) (xy 368.681209 -233.059986) (xy 368.723225 -233.090512) (xy 368.759948 -233.127235)
			(xy 368.790474 -233.169251) (xy 368.814052 -233.215525) (xy 368.8301 -233.264918) (xy 368.838225 -233.316213)
			(xy 368.838734 -233.34218) (xy 368.838225 -233.368147) (xy 369.118389 -233.368147) (xy 369.118389 -233.316213)
			(xy 369.126514 -233.264918) (xy 369.142562 -233.215525) (xy 369.16614 -233.169251) (xy 369.196666 -233.127235)
			(xy 369.233389 -233.090512) (xy 369.275405 -233.059986) (xy 369.321679 -233.036408) (xy 369.371072 -233.02036)
			(xy 369.422367 -233.012235) (xy 369.474301 -233.012235) (xy 369.525596 -233.02036) (xy 369.574989 -233.036408)
			(xy 369.621263 -233.059986) (xy 369.663279 -233.090512) (xy 369.700002 -233.127235) (xy 369.730528 -233.169251)
			(xy 369.754106 -233.215525) (xy 369.770154 -233.264918) (xy 369.778279 -233.316213) (xy 369.778788 -233.34218)
			(xy 369.778279 -233.368147) (xy 370.057935 -233.368147) (xy 370.057935 -233.316213) (xy 370.06606 -233.264918)
			(xy 370.082108 -233.215525) (xy 370.105686 -233.169251) (xy 370.136212 -233.127235) (xy 370.172935 -233.090512)
			(xy 370.214951 -233.059986) (xy 370.261225 -233.036408) (xy 370.310618 -233.02036) (xy 370.361913 -233.012235)
			(xy 370.413847 -233.012235) (xy 370.465142 -233.02036) (xy 370.514535 -233.036408) (xy 370.560809 -233.059986)
			(xy 370.602825 -233.090512) (xy 370.639548 -233.127235) (xy 370.670074 -233.169251) (xy 370.693652 -233.215525)
			(xy 370.7097 -233.264918) (xy 370.717825 -233.316213) (xy 370.718334 -233.34218) (xy 370.717825 -233.368147)
			(xy 370.997735 -233.368147) (xy 370.997735 -233.316213) (xy 371.00586 -233.264918) (xy 371.021908 -233.215525)
			(xy 371.045486 -233.169251) (xy 371.076012 -233.127235) (xy 371.112735 -233.090512) (xy 371.154751 -233.059986)
			(xy 371.201025 -233.036408) (xy 371.250418 -233.02036) (xy 371.301713 -233.012235) (xy 371.353647 -233.012235)
			(xy 371.404942 -233.02036) (xy 371.454335 -233.036408) (xy 371.500609 -233.059986) (xy 371.542625 -233.090512)
			(xy 371.579348 -233.127235) (xy 371.609874 -233.169251) (xy 371.633452 -233.215525) (xy 371.6495 -233.264918)
			(xy 371.657625 -233.316213) (xy 371.658134 -233.34218) (xy 371.657625 -233.368147) (xy 371.937535 -233.368147)
			(xy 371.937535 -233.316213) (xy 371.94566 -233.264918) (xy 371.961708 -233.215525) (xy 371.985286 -233.169251)
			(xy 372.015812 -233.127235) (xy 372.052535 -233.090512) (xy 372.094551 -233.059986) (xy 372.140825 -233.036408)
			(xy 372.190218 -233.02036) (xy 372.241513 -233.012235) (xy 372.293447 -233.012235) (xy 372.344742 -233.02036)
			(xy 372.394135 -233.036408) (xy 372.440409 -233.059986) (xy 372.482425 -233.090512) (xy 372.519148 -233.127235)
			(xy 372.549674 -233.169251) (xy 372.573252 -233.215525) (xy 372.5893 -233.264918) (xy 372.597425 -233.316213)
			(xy 372.597934 -233.34218) (xy 372.597425 -233.368147) (xy 372.877335 -233.368147) (xy 372.877335 -233.316213)
			(xy 372.88546 -233.264918) (xy 372.901508 -233.215525) (xy 372.925086 -233.169251) (xy 372.955612 -233.127235)
			(xy 372.992335 -233.090512) (xy 373.034351 -233.059986) (xy 373.080625 -233.036408) (xy 373.130018 -233.02036)
			(xy 373.181313 -233.012235) (xy 373.233247 -233.012235) (xy 373.284542 -233.02036) (xy 373.333935 -233.036408)
			(xy 373.380209 -233.059986) (xy 373.422225 -233.090512) (xy 373.458948 -233.127235) (xy 373.489474 -233.169251)
			(xy 373.513052 -233.215525) (xy 373.5291 -233.264918) (xy 373.537225 -233.316213) (xy 373.537734 -233.34218)
			(xy 373.537225 -233.368147) (xy 373.5291 -233.419442) (xy 373.513052 -233.468835) (xy 373.489474 -233.515109)
			(xy 373.458948 -233.557125) (xy 373.422225 -233.593848) (xy 373.380209 -233.624374) (xy 373.333935 -233.647952)
			(xy 373.284542 -233.664) (xy 373.233247 -233.672125) (xy 373.181313 -233.672125) (xy 373.130018 -233.664)
			(xy 373.080625 -233.647952) (xy 373.034351 -233.624374) (xy 372.992335 -233.593848) (xy 372.955612 -233.557125)
			(xy 372.925086 -233.515109) (xy 372.901508 -233.468835) (xy 372.88546 -233.419442) (xy 372.877335 -233.368147)
			(xy 372.597425 -233.368147) (xy 372.5893 -233.419442) (xy 372.573252 -233.468835) (xy 372.549674 -233.515109)
			(xy 372.519148 -233.557125) (xy 372.482425 -233.593848) (xy 372.440409 -233.624374) (xy 372.394135 -233.647952)
			(xy 372.344742 -233.664) (xy 372.293447 -233.672125) (xy 372.241513 -233.672125) (xy 372.190218 -233.664)
			(xy 372.140825 -233.647952) (xy 372.094551 -233.624374) (xy 372.052535 -233.593848) (xy 372.015812 -233.557125)
			(xy 371.985286 -233.515109) (xy 371.961708 -233.468835) (xy 371.94566 -233.419442) (xy 371.937535 -233.368147)
			(xy 371.657625 -233.368147) (xy 371.6495 -233.419442) (xy 371.633452 -233.468835) (xy 371.609874 -233.515109)
			(xy 371.579348 -233.557125) (xy 371.542625 -233.593848) (xy 371.500609 -233.624374) (xy 371.454335 -233.647952)
			(xy 371.404942 -233.664) (xy 371.353647 -233.672125) (xy 371.301713 -233.672125) (xy 371.250418 -233.664)
			(xy 371.201025 -233.647952) (xy 371.154751 -233.624374) (xy 371.112735 -233.593848) (xy 371.076012 -233.557125)
			(xy 371.045486 -233.515109) (xy 371.021908 -233.468835) (xy 371.00586 -233.419442) (xy 370.997735 -233.368147)
			(xy 370.717825 -233.368147) (xy 370.7097 -233.419442) (xy 370.693652 -233.468835) (xy 370.670074 -233.515109)
			(xy 370.639548 -233.557125) (xy 370.602825 -233.593848) (xy 370.560809 -233.624374) (xy 370.514535 -233.647952)
			(xy 370.465142 -233.664) (xy 370.413847 -233.672125) (xy 370.361913 -233.672125) (xy 370.310618 -233.664)
			(xy 370.261225 -233.647952) (xy 370.214951 -233.624374) (xy 370.172935 -233.593848) (xy 370.136212 -233.557125)
			(xy 370.105686 -233.515109) (xy 370.082108 -233.468835) (xy 370.06606 -233.419442) (xy 370.057935 -233.368147)
			(xy 369.778279 -233.368147) (xy 369.770154 -233.419442) (xy 369.754106 -233.468835) (xy 369.730528 -233.515109)
			(xy 369.700002 -233.557125) (xy 369.663279 -233.593848) (xy 369.621263 -233.624374) (xy 369.574989 -233.647952)
			(xy 369.525596 -233.664) (xy 369.474301 -233.672125) (xy 369.422367 -233.672125) (xy 369.371072 -233.664)
			(xy 369.321679 -233.647952) (xy 369.275405 -233.624374) (xy 369.233389 -233.593848) (xy 369.196666 -233.557125)
			(xy 369.16614 -233.515109) (xy 369.142562 -233.468835) (xy 369.126514 -233.419442) (xy 369.118389 -233.368147)
			(xy 368.838225 -233.368147) (xy 368.8301 -233.419442) (xy 368.814052 -233.468835) (xy 368.790474 -233.515109)
			(xy 368.759948 -233.557125) (xy 368.723225 -233.593848) (xy 368.681209 -233.624374) (xy 368.634935 -233.647952)
			(xy 368.585542 -233.664) (xy 368.534247 -233.672125) (xy 368.482313 -233.672125) (xy 368.431018 -233.664)
			(xy 368.381625 -233.647952) (xy 368.335351 -233.624374) (xy 368.293335 -233.593848) (xy 368.256612 -233.557125)
			(xy 368.226086 -233.515109) (xy 368.202508 -233.468835) (xy 368.18646 -233.419442) (xy 368.178335 -233.368147)
			(xy 367.898425 -233.368147) (xy 367.8903 -233.419442) (xy 367.874252 -233.468835) (xy 367.850674 -233.515109)
			(xy 367.820148 -233.557125) (xy 367.783425 -233.593848) (xy 367.741409 -233.624374) (xy 367.695135 -233.647952)
			(xy 367.645742 -233.664) (xy 367.594447 -233.672125) (xy 367.542513 -233.672125) (xy 367.491218 -233.664)
			(xy 367.441825 -233.647952) (xy 367.395551 -233.624374) (xy 367.353535 -233.593848) (xy 367.316812 -233.557125)
			(xy 367.286286 -233.515109) (xy 367.262708 -233.468835) (xy 367.24666 -233.419442) (xy 367.238535 -233.368147)
			(xy 366.958625 -233.368147) (xy 366.9505 -233.419442) (xy 366.934452 -233.468835) (xy 366.910874 -233.515109)
			(xy 366.880348 -233.557125) (xy 366.843625 -233.593848) (xy 366.801609 -233.624374) (xy 366.755335 -233.647952)
			(xy 366.705942 -233.664) (xy 366.654647 -233.672125) (xy 366.602713 -233.672125) (xy 366.551418 -233.664)
			(xy 366.502025 -233.647952) (xy 366.455751 -233.624374) (xy 366.413735 -233.593848) (xy 366.377012 -233.557125)
			(xy 366.346486 -233.515109) (xy 366.322908 -233.468835) (xy 366.30686 -233.419442) (xy 366.298735 -233.368147)
			(xy 366.018825 -233.368147) (xy 366.0107 -233.419442) (xy 365.994652 -233.468835) (xy 365.971074 -233.515109)
			(xy 365.940548 -233.557125) (xy 365.903825 -233.593848) (xy 365.861809 -233.624374) (xy 365.815535 -233.647952)
			(xy 365.766142 -233.664) (xy 365.714847 -233.672125) (xy 365.662913 -233.672125) (xy 365.611618 -233.664)
			(xy 365.562225 -233.647952) (xy 365.515951 -233.624374) (xy 365.473935 -233.593848) (xy 365.437212 -233.557125)
			(xy 365.406686 -233.515109) (xy 365.383108 -233.468835) (xy 365.36706 -233.419442) (xy 365.358935 -233.368147)
			(xy 365.079025 -233.368147) (xy 365.0709 -233.419442) (xy 365.054852 -233.468835) (xy 365.031274 -233.515109)
			(xy 365.000748 -233.557125) (xy 364.964025 -233.593848) (xy 364.922009 -233.624374) (xy 364.875735 -233.647952)
			(xy 364.826342 -233.664) (xy 364.775047 -233.672125) (xy 364.723113 -233.672125) (xy 364.671818 -233.664)
			(xy 364.622425 -233.647952) (xy 364.576151 -233.624374) (xy 364.534135 -233.593848) (xy 364.497412 -233.557125)
			(xy 364.466886 -233.515109) (xy 364.443308 -233.468835) (xy 364.42726 -233.419442) (xy 364.419135 -233.368147)
			(xy 364.139225 -233.368147) (xy 364.1311 -233.419442) (xy 364.115052 -233.468835) (xy 364.091474 -233.515109)
			(xy 364.060948 -233.557125) (xy 364.024225 -233.593848) (xy 363.982209 -233.624374) (xy 363.935935 -233.647952)
			(xy 363.886542 -233.664) (xy 363.835247 -233.672125) (xy 363.783313 -233.672125) (xy 363.732018 -233.664)
			(xy 363.682625 -233.647952) (xy 363.636351 -233.624374) (xy 363.594335 -233.593848) (xy 363.557612 -233.557125)
			(xy 363.527086 -233.515109) (xy 363.503508 -233.468835) (xy 363.48746 -233.419442) (xy 363.479335 -233.368147)
			(xy 363.199425 -233.368147) (xy 363.1913 -233.419442) (xy 363.175252 -233.468835) (xy 363.151674 -233.515109)
			(xy 363.121148 -233.557125) (xy 363.084425 -233.593848) (xy 363.042409 -233.624374) (xy 362.996135 -233.647952)
			(xy 362.946742 -233.664) (xy 362.895447 -233.672125) (xy 362.843513 -233.672125) (xy 362.792218 -233.664)
			(xy 362.742825 -233.647952) (xy 362.696551 -233.624374) (xy 362.654535 -233.593848) (xy 362.617812 -233.557125)
			(xy 362.587286 -233.515109) (xy 362.563708 -233.468835) (xy 362.54766 -233.419442) (xy 362.539535 -233.368147)
			(xy 362.259879 -233.368147) (xy 362.251754 -233.419442) (xy 362.235706 -233.468835) (xy 362.212128 -233.515109)
			(xy 362.181602 -233.557125) (xy 362.144879 -233.593848) (xy 362.102863 -233.624374) (xy 362.056589 -233.647952)
			(xy 362.007196 -233.664) (xy 361.955901 -233.672125) (xy 361.903967 -233.672125) (xy 361.852672 -233.664)
			(xy 361.803279 -233.647952) (xy 361.757005 -233.624374) (xy 361.714989 -233.593848) (xy 361.678266 -233.557125)
			(xy 361.64774 -233.515109) (xy 361.624162 -233.468835) (xy 361.608114 -233.419442) (xy 361.599989 -233.368147)
			(xy 361.319825 -233.368147) (xy 361.3117 -233.419442) (xy 361.295652 -233.468835) (xy 361.272074 -233.515109)
			(xy 361.241548 -233.557125) (xy 361.204825 -233.593848) (xy 361.162809 -233.624374) (xy 361.116535 -233.647952)
			(xy 361.067142 -233.664) (xy 361.015847 -233.672125) (xy 360.963913 -233.672125) (xy 360.912618 -233.664)
			(xy 360.863225 -233.647952) (xy 360.816951 -233.624374) (xy 360.774935 -233.593848) (xy 360.738212 -233.557125)
			(xy 360.707686 -233.515109) (xy 360.684108 -233.468835) (xy 360.66806 -233.419442) (xy 360.659935 -233.368147)
			(xy 360.380025 -233.368147) (xy 360.3719 -233.419442) (xy 360.355852 -233.468835) (xy 360.332274 -233.515109)
			(xy 360.301748 -233.557125) (xy 360.265025 -233.593848) (xy 360.223009 -233.624374) (xy 360.176735 -233.647952)
			(xy 360.127342 -233.664) (xy 360.076047 -233.672125) (xy 360.024113 -233.672125) (xy 359.972818 -233.664)
			(xy 359.923425 -233.647952) (xy 359.877151 -233.624374) (xy 359.835135 -233.593848) (xy 359.798412 -233.557125)
			(xy 359.767886 -233.515109) (xy 359.744308 -233.468835) (xy 359.72826 -233.419442) (xy 359.720135 -233.368147)
			(xy 359.440225 -233.368147) (xy 359.4321 -233.419442) (xy 359.416052 -233.468835) (xy 359.392474 -233.515109)
			(xy 359.361948 -233.557125) (xy 359.325225 -233.593848) (xy 359.283209 -233.624374) (xy 359.236935 -233.647952)
			(xy 359.187542 -233.664) (xy 359.136247 -233.672125) (xy 359.084313 -233.672125) (xy 359.033018 -233.664)
			(xy 358.983625 -233.647952) (xy 358.937351 -233.624374) (xy 358.895335 -233.593848) (xy 358.858612 -233.557125)
			(xy 358.828086 -233.515109) (xy 358.804508 -233.468835) (xy 358.78846 -233.419442) (xy 358.780335 -233.368147)
			(xy 358.500679 -233.368147) (xy 358.492554 -233.419442) (xy 358.476506 -233.468835) (xy 358.452928 -233.515109)
			(xy 358.422402 -233.557125) (xy 358.385679 -233.593848) (xy 358.343663 -233.624374) (xy 358.297389 -233.647952)
			(xy 358.247996 -233.664) (xy 358.196701 -233.672125) (xy 358.144767 -233.672125) (xy 358.093472 -233.664)
			(xy 358.044079 -233.647952) (xy 357.997805 -233.624374) (xy 357.955789 -233.593848) (xy 357.919066 -233.557125)
			(xy 357.88854 -233.515109) (xy 357.864962 -233.468835) (xy 357.848914 -233.419442) (xy 357.840789 -233.368147)
			(xy 357.560625 -233.368147) (xy 357.5525 -233.419442) (xy 357.536452 -233.468835) (xy 357.512874 -233.515109)
			(xy 357.482348 -233.557125) (xy 357.445625 -233.593848) (xy 357.403609 -233.624374) (xy 357.357335 -233.647952)
			(xy 357.307942 -233.664) (xy 357.256647 -233.672125) (xy 357.204713 -233.672125) (xy 357.153418 -233.664)
			(xy 357.104025 -233.647952) (xy 357.057751 -233.624374) (xy 357.015735 -233.593848) (xy 356.979012 -233.557125)
			(xy 356.948486 -233.515109) (xy 356.924908 -233.468835) (xy 356.90886 -233.419442) (xy 356.900735 -233.368147)
			(xy 356.620825 -233.368147) (xy 356.6127 -233.419442) (xy 356.596652 -233.468835) (xy 356.573074 -233.515109)
			(xy 356.542548 -233.557125) (xy 356.505825 -233.593848) (xy 356.463809 -233.624374) (xy 356.417535 -233.647952)
			(xy 356.368142 -233.664) (xy 356.316847 -233.672125) (xy 356.264913 -233.672125) (xy 356.213618 -233.664)
			(xy 356.164225 -233.647952) (xy 356.117951 -233.624374) (xy 356.075935 -233.593848) (xy 356.039212 -233.557125)
			(xy 356.008686 -233.515109) (xy 355.985108 -233.468835) (xy 355.96906 -233.419442) (xy 355.960935 -233.368147)
			(xy 355.681025 -233.368147) (xy 355.6729 -233.419442) (xy 355.656852 -233.468835) (xy 355.633274 -233.515109)
			(xy 355.602748 -233.557125) (xy 355.566025 -233.593848) (xy 355.524009 -233.624374) (xy 355.477735 -233.647952)
			(xy 355.428342 -233.664) (xy 355.377047 -233.672125) (xy 355.325113 -233.672125) (xy 355.273818 -233.664)
			(xy 355.224425 -233.647952) (xy 355.178151 -233.624374) (xy 355.136135 -233.593848) (xy 355.099412 -233.557125)
			(xy 355.068886 -233.515109) (xy 355.045308 -233.468835) (xy 355.02926 -233.419442) (xy 355.021135 -233.368147)
			(xy 354.741225 -233.368147) (xy 354.7331 -233.419442) (xy 354.717052 -233.468835) (xy 354.693474 -233.515109)
			(xy 354.662948 -233.557125) (xy 354.626225 -233.593848) (xy 354.584209 -233.624374) (xy 354.537935 -233.647952)
			(xy 354.488542 -233.664) (xy 354.437247 -233.672125) (xy 354.385313 -233.672125) (xy 354.334018 -233.664)
			(xy 354.284625 -233.647952) (xy 354.238351 -233.624374) (xy 354.196335 -233.593848) (xy 354.159612 -233.557125)
			(xy 354.129086 -233.515109) (xy 354.105508 -233.468835) (xy 354.08946 -233.419442) (xy 354.081335 -233.368147)
			(xy 353.801679 -233.368147) (xy 353.793554 -233.419442) (xy 353.777506 -233.468835) (xy 353.753928 -233.515109)
			(xy 353.723402 -233.557125) (xy 353.686679 -233.593848) (xy 353.644663 -233.624374) (xy 353.598389 -233.647952)
			(xy 353.548996 -233.664) (xy 353.497701 -233.672125) (xy 353.445767 -233.672125) (xy 353.394472 -233.664)
			(xy 353.345079 -233.647952) (xy 353.298805 -233.624374) (xy 353.256789 -233.593848) (xy 353.220066 -233.557125)
			(xy 353.18954 -233.515109) (xy 353.165962 -233.468835) (xy 353.149914 -233.419442) (xy 353.141789 -233.368147)
			(xy 353.018344 -233.368147) (xy 353.018344 -234.182217) (xy 353.611689 -234.182217) (xy 353.611689 -234.130283)
			(xy 353.619814 -234.078988) (xy 353.635862 -234.029595) (xy 353.65944 -233.983321) (xy 353.689966 -233.941305)
			(xy 353.726689 -233.904582) (xy 353.768705 -233.874056) (xy 353.814979 -233.850478) (xy 353.864372 -233.83443)
			(xy 353.915667 -233.826305) (xy 353.967601 -233.826305) (xy 354.018896 -233.83443) (xy 354.068289 -233.850478)
			(xy 354.114563 -233.874056) (xy 354.156579 -233.904582) (xy 354.193302 -233.941305) (xy 354.223828 -233.983321)
			(xy 354.247406 -234.029595) (xy 354.263454 -234.078988) (xy 354.271579 -234.130283) (xy 354.272088 -234.15625)
			(xy 354.271579 -234.182217) (xy 354.551489 -234.182217) (xy 354.551489 -234.130283) (xy 354.559614 -234.078988)
			(xy 354.575662 -234.029595) (xy 354.59924 -233.983321) (xy 354.629766 -233.941305) (xy 354.666489 -233.904582)
			(xy 354.708505 -233.874056) (xy 354.754779 -233.850478) (xy 354.804172 -233.83443) (xy 354.855467 -233.826305)
			(xy 354.907401 -233.826305) (xy 354.958696 -233.83443) (xy 355.008089 -233.850478) (xy 355.054363 -233.874056)
			(xy 355.096379 -233.904582) (xy 355.133102 -233.941305) (xy 355.163628 -233.983321) (xy 355.187206 -234.029595)
			(xy 355.203254 -234.078988) (xy 355.211379 -234.130283) (xy 355.211888 -234.15625) (xy 355.211379 -234.182217)
			(xy 355.491289 -234.182217) (xy 355.491289 -234.130283) (xy 355.499414 -234.078988) (xy 355.515462 -234.029595)
			(xy 355.53904 -233.983321) (xy 355.569566 -233.941305) (xy 355.606289 -233.904582) (xy 355.648305 -233.874056)
			(xy 355.694579 -233.850478) (xy 355.743972 -233.83443) (xy 355.795267 -233.826305) (xy 355.847201 -233.826305)
			(xy 355.898496 -233.83443) (xy 355.947889 -233.850478) (xy 355.994163 -233.874056) (xy 356.036179 -233.904582)
			(xy 356.072902 -233.941305) (xy 356.103428 -233.983321) (xy 356.127006 -234.029595) (xy 356.143054 -234.078988)
			(xy 356.151179 -234.130283) (xy 356.151688 -234.15625) (xy 356.151179 -234.182217) (xy 356.431089 -234.182217)
			(xy 356.431089 -234.130283) (xy 356.439214 -234.078988) (xy 356.455262 -234.029595) (xy 356.47884 -233.983321)
			(xy 356.509366 -233.941305) (xy 356.546089 -233.904582) (xy 356.588105 -233.874056) (xy 356.634379 -233.850478)
			(xy 356.683772 -233.83443) (xy 356.735067 -233.826305) (xy 356.787001 -233.826305) (xy 356.838296 -233.83443)
			(xy 356.887689 -233.850478) (xy 356.933963 -233.874056) (xy 356.975979 -233.904582) (xy 357.012702 -233.941305)
			(xy 357.043228 -233.983321) (xy 357.066806 -234.029595) (xy 357.082854 -234.078988) (xy 357.090979 -234.130283)
			(xy 357.091488 -234.15625) (xy 357.090979 -234.182217) (xy 357.370889 -234.182217) (xy 357.370889 -234.130283)
			(xy 357.379014 -234.078988) (xy 357.395062 -234.029595) (xy 357.41864 -233.983321) (xy 357.449166 -233.941305)
			(xy 357.485889 -233.904582) (xy 357.527905 -233.874056) (xy 357.574179 -233.850478) (xy 357.623572 -233.83443)
			(xy 357.674867 -233.826305) (xy 357.726801 -233.826305) (xy 357.778096 -233.83443) (xy 357.827489 -233.850478)
			(xy 357.873763 -233.874056) (xy 357.915779 -233.904582) (xy 357.952502 -233.941305) (xy 357.983028 -233.983321)
			(xy 358.006606 -234.029595) (xy 358.022654 -234.078988) (xy 358.030779 -234.130283) (xy 358.031288 -234.15625)
			(xy 358.030779 -234.182217) (xy 358.310689 -234.182217) (xy 358.310689 -234.130283) (xy 358.318814 -234.078988)
			(xy 358.334862 -234.029595) (xy 358.35844 -233.983321) (xy 358.388966 -233.941305) (xy 358.425689 -233.904582)
			(xy 358.467705 -233.874056) (xy 358.513979 -233.850478) (xy 358.563372 -233.83443) (xy 358.614667 -233.826305)
			(xy 358.666601 -233.826305) (xy 358.717896 -233.83443) (xy 358.767289 -233.850478) (xy 358.813563 -233.874056)
			(xy 358.855579 -233.904582) (xy 358.892302 -233.941305) (xy 358.922828 -233.983321) (xy 358.946406 -234.029595)
			(xy 358.962454 -234.078988) (xy 358.970579 -234.130283) (xy 358.971088 -234.15625) (xy 358.970579 -234.182217)
			(xy 359.250489 -234.182217) (xy 359.250489 -234.130283) (xy 359.258614 -234.078988) (xy 359.274662 -234.029595)
			(xy 359.29824 -233.983321) (xy 359.328766 -233.941305) (xy 359.365489 -233.904582) (xy 359.407505 -233.874056)
			(xy 359.453779 -233.850478) (xy 359.503172 -233.83443) (xy 359.554467 -233.826305) (xy 359.606401 -233.826305)
			(xy 359.657696 -233.83443) (xy 359.707089 -233.850478) (xy 359.753363 -233.874056) (xy 359.795379 -233.904582)
			(xy 359.832102 -233.941305) (xy 359.862628 -233.983321) (xy 359.886206 -234.029595) (xy 359.902254 -234.078988)
			(xy 359.910379 -234.130283) (xy 359.910888 -234.15625) (xy 359.910379 -234.182217) (xy 360.190289 -234.182217)
			(xy 360.190289 -234.130283) (xy 360.198414 -234.078988) (xy 360.214462 -234.029595) (xy 360.23804 -233.983321)
			(xy 360.268566 -233.941305) (xy 360.305289 -233.904582) (xy 360.347305 -233.874056) (xy 360.393579 -233.850478)
			(xy 360.442972 -233.83443) (xy 360.494267 -233.826305) (xy 360.546201 -233.826305) (xy 360.597496 -233.83443)
			(xy 360.646889 -233.850478) (xy 360.693163 -233.874056) (xy 360.735179 -233.904582) (xy 360.771902 -233.941305)
			(xy 360.802428 -233.983321) (xy 360.826006 -234.029595) (xy 360.842054 -234.078988) (xy 360.850179 -234.130283)
			(xy 360.850688 -234.15625) (xy 360.850179 -234.182217) (xy 361.130089 -234.182217) (xy 361.130089 -234.130283)
			(xy 361.138214 -234.078988) (xy 361.154262 -234.029595) (xy 361.17784 -233.983321) (xy 361.208366 -233.941305)
			(xy 361.245089 -233.904582) (xy 361.287105 -233.874056) (xy 361.333379 -233.850478) (xy 361.382772 -233.83443)
			(xy 361.434067 -233.826305) (xy 361.486001 -233.826305) (xy 361.537296 -233.83443) (xy 361.586689 -233.850478)
			(xy 361.632963 -233.874056) (xy 361.674979 -233.904582) (xy 361.711702 -233.941305) (xy 361.742228 -233.983321)
			(xy 361.765806 -234.029595) (xy 361.781854 -234.078988) (xy 361.789979 -234.130283) (xy 361.790488 -234.15625)
			(xy 361.789979 -234.182217) (xy 362.069889 -234.182217) (xy 362.069889 -234.130283) (xy 362.078014 -234.078988)
			(xy 362.094062 -234.029595) (xy 362.11764 -233.983321) (xy 362.148166 -233.941305) (xy 362.184889 -233.904582)
			(xy 362.226905 -233.874056) (xy 362.273179 -233.850478) (xy 362.322572 -233.83443) (xy 362.373867 -233.826305)
			(xy 362.425801 -233.826305) (xy 362.477096 -233.83443) (xy 362.526489 -233.850478) (xy 362.572763 -233.874056)
			(xy 362.614779 -233.904582) (xy 362.651502 -233.941305) (xy 362.682028 -233.983321) (xy 362.705606 -234.029595)
			(xy 362.721654 -234.078988) (xy 362.729779 -234.130283) (xy 362.730288 -234.15625) (xy 362.729779 -234.182217)
			(xy 363.009689 -234.182217) (xy 363.009689 -234.130283) (xy 363.017814 -234.078988) (xy 363.033862 -234.029595)
			(xy 363.05744 -233.983321) (xy 363.087966 -233.941305) (xy 363.124689 -233.904582) (xy 363.166705 -233.874056)
			(xy 363.212979 -233.850478) (xy 363.262372 -233.83443) (xy 363.313667 -233.826305) (xy 363.365601 -233.826305)
			(xy 363.416896 -233.83443) (xy 363.466289 -233.850478) (xy 363.512563 -233.874056) (xy 363.554579 -233.904582)
			(xy 363.591302 -233.941305) (xy 363.621828 -233.983321) (xy 363.645406 -234.029595) (xy 363.661454 -234.078988)
			(xy 363.669579 -234.130283) (xy 363.670088 -234.15625) (xy 363.669579 -234.182217) (xy 363.949489 -234.182217)
			(xy 363.949489 -234.130283) (xy 363.957614 -234.078988) (xy 363.973662 -234.029595) (xy 363.99724 -233.983321)
			(xy 364.027766 -233.941305) (xy 364.064489 -233.904582) (xy 364.106505 -233.874056) (xy 364.152779 -233.850478)
			(xy 364.202172 -233.83443) (xy 364.253467 -233.826305) (xy 364.305401 -233.826305) (xy 364.356696 -233.83443)
			(xy 364.406089 -233.850478) (xy 364.452363 -233.874056) (xy 364.494379 -233.904582) (xy 364.531102 -233.941305)
			(xy 364.561628 -233.983321) (xy 364.585206 -234.029595) (xy 364.601254 -234.078988) (xy 364.609379 -234.130283)
			(xy 364.609888 -234.15625) (xy 364.609379 -234.182217) (xy 364.889289 -234.182217) (xy 364.889289 -234.130283)
			(xy 364.897414 -234.078988) (xy 364.913462 -234.029595) (xy 364.93704 -233.983321) (xy 364.967566 -233.941305)
			(xy 365.004289 -233.904582) (xy 365.046305 -233.874056) (xy 365.092579 -233.850478) (xy 365.141972 -233.83443)
			(xy 365.193267 -233.826305) (xy 365.245201 -233.826305) (xy 365.296496 -233.83443) (xy 365.345889 -233.850478)
			(xy 365.392163 -233.874056) (xy 365.434179 -233.904582) (xy 365.470902 -233.941305) (xy 365.501428 -233.983321)
			(xy 365.525006 -234.029595) (xy 365.541054 -234.078988) (xy 365.549179 -234.130283) (xy 365.549688 -234.15625)
			(xy 365.549179 -234.182217) (xy 365.829089 -234.182217) (xy 365.829089 -234.130283) (xy 365.837214 -234.078988)
			(xy 365.853262 -234.029595) (xy 365.87684 -233.983321) (xy 365.907366 -233.941305) (xy 365.944089 -233.904582)
			(xy 365.986105 -233.874056) (xy 366.032379 -233.850478) (xy 366.081772 -233.83443) (xy 366.133067 -233.826305)
			(xy 366.185001 -233.826305) (xy 366.236296 -233.83443) (xy 366.285689 -233.850478) (xy 366.331963 -233.874056)
			(xy 366.373979 -233.904582) (xy 366.410702 -233.941305) (xy 366.441228 -233.983321) (xy 366.464806 -234.029595)
			(xy 366.480854 -234.078988) (xy 366.488979 -234.130283) (xy 366.489488 -234.15625) (xy 366.488979 -234.182217)
			(xy 366.768889 -234.182217) (xy 366.768889 -234.130283) (xy 366.777014 -234.078988) (xy 366.793062 -234.029595)
			(xy 366.81664 -233.983321) (xy 366.847166 -233.941305) (xy 366.883889 -233.904582) (xy 366.925905 -233.874056)
			(xy 366.972179 -233.850478) (xy 367.021572 -233.83443) (xy 367.072867 -233.826305) (xy 367.124801 -233.826305)
			(xy 367.176096 -233.83443) (xy 367.225489 -233.850478) (xy 367.271763 -233.874056) (xy 367.313779 -233.904582)
			(xy 367.350502 -233.941305) (xy 367.381028 -233.983321) (xy 367.404606 -234.029595) (xy 367.420654 -234.078988)
			(xy 367.428779 -234.130283) (xy 367.429288 -234.15625) (xy 367.428779 -234.182217) (xy 367.708689 -234.182217)
			(xy 367.708689 -234.130283) (xy 367.716814 -234.078988) (xy 367.732862 -234.029595) (xy 367.75644 -233.983321)
			(xy 367.786966 -233.941305) (xy 367.823689 -233.904582) (xy 367.865705 -233.874056) (xy 367.911979 -233.850478)
			(xy 367.961372 -233.83443) (xy 368.012667 -233.826305) (xy 368.064601 -233.826305) (xy 368.115896 -233.83443)
			(xy 368.165289 -233.850478) (xy 368.211563 -233.874056) (xy 368.253579 -233.904582) (xy 368.290302 -233.941305)
			(xy 368.320828 -233.983321) (xy 368.344406 -234.029595) (xy 368.360454 -234.078988) (xy 368.368579 -234.130283)
			(xy 368.369088 -234.15625) (xy 368.368579 -234.182217) (xy 368.648235 -234.182217) (xy 368.648235 -234.130283)
			(xy 368.65636 -234.078988) (xy 368.672408 -234.029595) (xy 368.695986 -233.983321) (xy 368.726512 -233.941305)
			(xy 368.763235 -233.904582) (xy 368.805251 -233.874056) (xy 368.851525 -233.850478) (xy 368.900918 -233.83443)
			(xy 368.952213 -233.826305) (xy 369.004147 -233.826305) (xy 369.055442 -233.83443) (xy 369.104835 -233.850478)
			(xy 369.151109 -233.874056) (xy 369.193125 -233.904582) (xy 369.229848 -233.941305) (xy 369.260374 -233.983321)
			(xy 369.283952 -234.029595) (xy 369.3 -234.078988) (xy 369.308125 -234.130283) (xy 369.308634 -234.15625)
			(xy 369.308125 -234.182217) (xy 369.588289 -234.182217) (xy 369.588289 -234.130283) (xy 369.596414 -234.078988)
			(xy 369.612462 -234.029595) (xy 369.63604 -233.983321) (xy 369.666566 -233.941305) (xy 369.703289 -233.904582)
			(xy 369.745305 -233.874056) (xy 369.791579 -233.850478) (xy 369.840972 -233.83443) (xy 369.892267 -233.826305)
			(xy 369.944201 -233.826305) (xy 369.995496 -233.83443) (xy 370.044889 -233.850478) (xy 370.091163 -233.874056)
			(xy 370.133179 -233.904582) (xy 370.169902 -233.941305) (xy 370.200428 -233.983321) (xy 370.224006 -234.029595)
			(xy 370.240054 -234.078988) (xy 370.248179 -234.130283) (xy 370.248688 -234.15625) (xy 370.248179 -234.182217)
			(xy 370.527835 -234.182217) (xy 370.527835 -234.130283) (xy 370.53596 -234.078988) (xy 370.552008 -234.029595)
			(xy 370.575586 -233.983321) (xy 370.606112 -233.941305) (xy 370.642835 -233.904582) (xy 370.684851 -233.874056)
			(xy 370.731125 -233.850478) (xy 370.780518 -233.83443) (xy 370.831813 -233.826305) (xy 370.883747 -233.826305)
			(xy 370.935042 -233.83443) (xy 370.984435 -233.850478) (xy 371.030709 -233.874056) (xy 371.072725 -233.904582)
			(xy 371.109448 -233.941305) (xy 371.139974 -233.983321) (xy 371.163552 -234.029595) (xy 371.1796 -234.078988)
			(xy 371.187725 -234.130283) (xy 371.188234 -234.15625) (xy 371.187725 -234.182217) (xy 371.467889 -234.182217)
			(xy 371.467889 -234.130283) (xy 371.476014 -234.078988) (xy 371.492062 -234.029595) (xy 371.51564 -233.983321)
			(xy 371.546166 -233.941305) (xy 371.582889 -233.904582) (xy 371.624905 -233.874056) (xy 371.671179 -233.850478)
			(xy 371.720572 -233.83443) (xy 371.771867 -233.826305) (xy 371.823801 -233.826305) (xy 371.875096 -233.83443)
			(xy 371.924489 -233.850478) (xy 371.970763 -233.874056) (xy 372.012779 -233.904582) (xy 372.049502 -233.941305)
			(xy 372.080028 -233.983321) (xy 372.103606 -234.029595) (xy 372.119654 -234.078988) (xy 372.127779 -234.130283)
			(xy 372.128288 -234.15625) (xy 372.127779 -234.182217) (xy 372.407689 -234.182217) (xy 372.407689 -234.130283)
			(xy 372.415814 -234.078988) (xy 372.431862 -234.029595) (xy 372.45544 -233.983321) (xy 372.485966 -233.941305)
			(xy 372.522689 -233.904582) (xy 372.564705 -233.874056) (xy 372.610979 -233.850478) (xy 372.660372 -233.83443)
			(xy 372.711667 -233.826305) (xy 372.763601 -233.826305) (xy 372.814896 -233.83443) (xy 372.864289 -233.850478)
			(xy 372.910563 -233.874056) (xy 372.952579 -233.904582) (xy 372.989302 -233.941305) (xy 373.019828 -233.983321)
			(xy 373.043406 -234.029595) (xy 373.059454 -234.078988) (xy 373.067579 -234.130283) (xy 373.068088 -234.15625)
			(xy 373.067579 -234.182217) (xy 373.059454 -234.233512) (xy 373.043406 -234.282905) (xy 373.019828 -234.329179)
			(xy 372.989302 -234.371195) (xy 372.952579 -234.407918) (xy 372.910563 -234.438444) (xy 372.864289 -234.462022)
			(xy 372.814896 -234.47807) (xy 372.763601 -234.486195) (xy 372.711667 -234.486195) (xy 372.660372 -234.47807)
			(xy 372.610979 -234.462022) (xy 372.564705 -234.438444) (xy 372.522689 -234.407918) (xy 372.485966 -234.371195)
			(xy 372.45544 -234.329179) (xy 372.431862 -234.282905) (xy 372.415814 -234.233512) (xy 372.407689 -234.182217)
			(xy 372.127779 -234.182217) (xy 372.119654 -234.233512) (xy 372.103606 -234.282905) (xy 372.080028 -234.329179)
			(xy 372.049502 -234.371195) (xy 372.012779 -234.407918) (xy 371.970763 -234.438444) (xy 371.924489 -234.462022)
			(xy 371.875096 -234.47807) (xy 371.823801 -234.486195) (xy 371.771867 -234.486195) (xy 371.720572 -234.47807)
			(xy 371.671179 -234.462022) (xy 371.624905 -234.438444) (xy 371.582889 -234.407918) (xy 371.546166 -234.371195)
			(xy 371.51564 -234.329179) (xy 371.492062 -234.282905) (xy 371.476014 -234.233512) (xy 371.467889 -234.182217)
			(xy 371.187725 -234.182217) (xy 371.1796 -234.233512) (xy 371.163552 -234.282905) (xy 371.139974 -234.329179)
			(xy 371.109448 -234.371195) (xy 371.072725 -234.407918) (xy 371.030709 -234.438444) (xy 370.984435 -234.462022)
			(xy 370.935042 -234.47807) (xy 370.883747 -234.486195) (xy 370.831813 -234.486195) (xy 370.780518 -234.47807)
			(xy 370.731125 -234.462022) (xy 370.684851 -234.438444) (xy 370.642835 -234.407918) (xy 370.606112 -234.371195)
			(xy 370.575586 -234.329179) (xy 370.552008 -234.282905) (xy 370.53596 -234.233512) (xy 370.527835 -234.182217)
			(xy 370.248179 -234.182217) (xy 370.240054 -234.233512) (xy 370.224006 -234.282905) (xy 370.200428 -234.329179)
			(xy 370.169902 -234.371195) (xy 370.133179 -234.407918) (xy 370.091163 -234.438444) (xy 370.044889 -234.462022)
			(xy 369.995496 -234.47807) (xy 369.944201 -234.486195) (xy 369.892267 -234.486195) (xy 369.840972 -234.47807)
			(xy 369.791579 -234.462022) (xy 369.745305 -234.438444) (xy 369.703289 -234.407918) (xy 369.666566 -234.371195)
			(xy 369.63604 -234.329179) (xy 369.612462 -234.282905) (xy 369.596414 -234.233512) (xy 369.588289 -234.182217)
			(xy 369.308125 -234.182217) (xy 369.3 -234.233512) (xy 369.283952 -234.282905) (xy 369.260374 -234.329179)
			(xy 369.229848 -234.371195) (xy 369.193125 -234.407918) (xy 369.151109 -234.438444) (xy 369.104835 -234.462022)
			(xy 369.055442 -234.47807) (xy 369.004147 -234.486195) (xy 368.952213 -234.486195) (xy 368.900918 -234.47807)
			(xy 368.851525 -234.462022) (xy 368.805251 -234.438444) (xy 368.763235 -234.407918) (xy 368.726512 -234.371195)
			(xy 368.695986 -234.329179) (xy 368.672408 -234.282905) (xy 368.65636 -234.233512) (xy 368.648235 -234.182217)
			(xy 368.368579 -234.182217) (xy 368.360454 -234.233512) (xy 368.344406 -234.282905) (xy 368.320828 -234.329179)
			(xy 368.290302 -234.371195) (xy 368.253579 -234.407918) (xy 368.211563 -234.438444) (xy 368.165289 -234.462022)
			(xy 368.115896 -234.47807) (xy 368.064601 -234.486195) (xy 368.012667 -234.486195) (xy 367.961372 -234.47807)
			(xy 367.911979 -234.462022) (xy 367.865705 -234.438444) (xy 367.823689 -234.407918) (xy 367.786966 -234.371195)
			(xy 367.75644 -234.329179) (xy 367.732862 -234.282905) (xy 367.716814 -234.233512) (xy 367.708689 -234.182217)
			(xy 367.428779 -234.182217) (xy 367.420654 -234.233512) (xy 367.404606 -234.282905) (xy 367.381028 -234.329179)
			(xy 367.350502 -234.371195) (xy 367.313779 -234.407918) (xy 367.271763 -234.438444) (xy 367.225489 -234.462022)
			(xy 367.176096 -234.47807) (xy 367.124801 -234.486195) (xy 367.072867 -234.486195) (xy 367.021572 -234.47807)
			(xy 366.972179 -234.462022) (xy 366.925905 -234.438444) (xy 366.883889 -234.407918) (xy 366.847166 -234.371195)
			(xy 366.81664 -234.329179) (xy 366.793062 -234.282905) (xy 366.777014 -234.233512) (xy 366.768889 -234.182217)
			(xy 366.488979 -234.182217) (xy 366.480854 -234.233512) (xy 366.464806 -234.282905) (xy 366.441228 -234.329179)
			(xy 366.410702 -234.371195) (xy 366.373979 -234.407918) (xy 366.331963 -234.438444) (xy 366.285689 -234.462022)
			(xy 366.236296 -234.47807) (xy 366.185001 -234.486195) (xy 366.133067 -234.486195) (xy 366.081772 -234.47807)
			(xy 366.032379 -234.462022) (xy 365.986105 -234.438444) (xy 365.944089 -234.407918) (xy 365.907366 -234.371195)
			(xy 365.87684 -234.329179) (xy 365.853262 -234.282905) (xy 365.837214 -234.233512) (xy 365.829089 -234.182217)
			(xy 365.549179 -234.182217) (xy 365.541054 -234.233512) (xy 365.525006 -234.282905) (xy 365.501428 -234.329179)
			(xy 365.470902 -234.371195) (xy 365.434179 -234.407918) (xy 365.392163 -234.438444) (xy 365.345889 -234.462022)
			(xy 365.296496 -234.47807) (xy 365.245201 -234.486195) (xy 365.193267 -234.486195) (xy 365.141972 -234.47807)
			(xy 365.092579 -234.462022) (xy 365.046305 -234.438444) (xy 365.004289 -234.407918) (xy 364.967566 -234.371195)
			(xy 364.93704 -234.329179) (xy 364.913462 -234.282905) (xy 364.897414 -234.233512) (xy 364.889289 -234.182217)
			(xy 364.609379 -234.182217) (xy 364.601254 -234.233512) (xy 364.585206 -234.282905) (xy 364.561628 -234.329179)
			(xy 364.531102 -234.371195) (xy 364.494379 -234.407918) (xy 364.452363 -234.438444) (xy 364.406089 -234.462022)
			(xy 364.356696 -234.47807) (xy 364.305401 -234.486195) (xy 364.253467 -234.486195) (xy 364.202172 -234.47807)
			(xy 364.152779 -234.462022) (xy 364.106505 -234.438444) (xy 364.064489 -234.407918) (xy 364.027766 -234.371195)
			(xy 363.99724 -234.329179) (xy 363.973662 -234.282905) (xy 363.957614 -234.233512) (xy 363.949489 -234.182217)
			(xy 363.669579 -234.182217) (xy 363.661454 -234.233512) (xy 363.645406 -234.282905) (xy 363.621828 -234.329179)
			(xy 363.591302 -234.371195) (xy 363.554579 -234.407918) (xy 363.512563 -234.438444) (xy 363.466289 -234.462022)
			(xy 363.416896 -234.47807) (xy 363.365601 -234.486195) (xy 363.313667 -234.486195) (xy 363.262372 -234.47807)
			(xy 363.212979 -234.462022) (xy 363.166705 -234.438444) (xy 363.124689 -234.407918) (xy 363.087966 -234.371195)
			(xy 363.05744 -234.329179) (xy 363.033862 -234.282905) (xy 363.017814 -234.233512) (xy 363.009689 -234.182217)
			(xy 362.729779 -234.182217) (xy 362.721654 -234.233512) (xy 362.705606 -234.282905) (xy 362.682028 -234.329179)
			(xy 362.651502 -234.371195) (xy 362.614779 -234.407918) (xy 362.572763 -234.438444) (xy 362.526489 -234.462022)
			(xy 362.477096 -234.47807) (xy 362.425801 -234.486195) (xy 362.373867 -234.486195) (xy 362.322572 -234.47807)
			(xy 362.273179 -234.462022) (xy 362.226905 -234.438444) (xy 362.184889 -234.407918) (xy 362.148166 -234.371195)
			(xy 362.11764 -234.329179) (xy 362.094062 -234.282905) (xy 362.078014 -234.233512) (xy 362.069889 -234.182217)
			(xy 361.789979 -234.182217) (xy 361.781854 -234.233512) (xy 361.765806 -234.282905) (xy 361.742228 -234.329179)
			(xy 361.711702 -234.371195) (xy 361.674979 -234.407918) (xy 361.632963 -234.438444) (xy 361.586689 -234.462022)
			(xy 361.537296 -234.47807) (xy 361.486001 -234.486195) (xy 361.434067 -234.486195) (xy 361.382772 -234.47807)
			(xy 361.333379 -234.462022) (xy 361.287105 -234.438444) (xy 361.245089 -234.407918) (xy 361.208366 -234.371195)
			(xy 361.17784 -234.329179) (xy 361.154262 -234.282905) (xy 361.138214 -234.233512) (xy 361.130089 -234.182217)
			(xy 360.850179 -234.182217) (xy 360.842054 -234.233512) (xy 360.826006 -234.282905) (xy 360.802428 -234.329179)
			(xy 360.771902 -234.371195) (xy 360.735179 -234.407918) (xy 360.693163 -234.438444) (xy 360.646889 -234.462022)
			(xy 360.597496 -234.47807) (xy 360.546201 -234.486195) (xy 360.494267 -234.486195) (xy 360.442972 -234.47807)
			(xy 360.393579 -234.462022) (xy 360.347305 -234.438444) (xy 360.305289 -234.407918) (xy 360.268566 -234.371195)
			(xy 360.23804 -234.329179) (xy 360.214462 -234.282905) (xy 360.198414 -234.233512) (xy 360.190289 -234.182217)
			(xy 359.910379 -234.182217) (xy 359.902254 -234.233512) (xy 359.886206 -234.282905) (xy 359.862628 -234.329179)
			(xy 359.832102 -234.371195) (xy 359.795379 -234.407918) (xy 359.753363 -234.438444) (xy 359.707089 -234.462022)
			(xy 359.657696 -234.47807) (xy 359.606401 -234.486195) (xy 359.554467 -234.486195) (xy 359.503172 -234.47807)
			(xy 359.453779 -234.462022) (xy 359.407505 -234.438444) (xy 359.365489 -234.407918) (xy 359.328766 -234.371195)
			(xy 359.29824 -234.329179) (xy 359.274662 -234.282905) (xy 359.258614 -234.233512) (xy 359.250489 -234.182217)
			(xy 358.970579 -234.182217) (xy 358.962454 -234.233512) (xy 358.946406 -234.282905) (xy 358.922828 -234.329179)
			(xy 358.892302 -234.371195) (xy 358.855579 -234.407918) (xy 358.813563 -234.438444) (xy 358.767289 -234.462022)
			(xy 358.717896 -234.47807) (xy 358.666601 -234.486195) (xy 358.614667 -234.486195) (xy 358.563372 -234.47807)
			(xy 358.513979 -234.462022) (xy 358.467705 -234.438444) (xy 358.425689 -234.407918) (xy 358.388966 -234.371195)
			(xy 358.35844 -234.329179) (xy 358.334862 -234.282905) (xy 358.318814 -234.233512) (xy 358.310689 -234.182217)
			(xy 358.030779 -234.182217) (xy 358.022654 -234.233512) (xy 358.006606 -234.282905) (xy 357.983028 -234.329179)
			(xy 357.952502 -234.371195) (xy 357.915779 -234.407918) (xy 357.873763 -234.438444) (xy 357.827489 -234.462022)
			(xy 357.778096 -234.47807) (xy 357.726801 -234.486195) (xy 357.674867 -234.486195) (xy 357.623572 -234.47807)
			(xy 357.574179 -234.462022) (xy 357.527905 -234.438444) (xy 357.485889 -234.407918) (xy 357.449166 -234.371195)
			(xy 357.41864 -234.329179) (xy 357.395062 -234.282905) (xy 357.379014 -234.233512) (xy 357.370889 -234.182217)
			(xy 357.090979 -234.182217) (xy 357.082854 -234.233512) (xy 357.066806 -234.282905) (xy 357.043228 -234.329179)
			(xy 357.012702 -234.371195) (xy 356.975979 -234.407918) (xy 356.933963 -234.438444) (xy 356.887689 -234.462022)
			(xy 356.838296 -234.47807) (xy 356.787001 -234.486195) (xy 356.735067 -234.486195) (xy 356.683772 -234.47807)
			(xy 356.634379 -234.462022) (xy 356.588105 -234.438444) (xy 356.546089 -234.407918) (xy 356.509366 -234.371195)
			(xy 356.47884 -234.329179) (xy 356.455262 -234.282905) (xy 356.439214 -234.233512) (xy 356.431089 -234.182217)
			(xy 356.151179 -234.182217) (xy 356.143054 -234.233512) (xy 356.127006 -234.282905) (xy 356.103428 -234.329179)
			(xy 356.072902 -234.371195) (xy 356.036179 -234.407918) (xy 355.994163 -234.438444) (xy 355.947889 -234.462022)
			(xy 355.898496 -234.47807) (xy 355.847201 -234.486195) (xy 355.795267 -234.486195) (xy 355.743972 -234.47807)
			(xy 355.694579 -234.462022) (xy 355.648305 -234.438444) (xy 355.606289 -234.407918) (xy 355.569566 -234.371195)
			(xy 355.53904 -234.329179) (xy 355.515462 -234.282905) (xy 355.499414 -234.233512) (xy 355.491289 -234.182217)
			(xy 355.211379 -234.182217) (xy 355.203254 -234.233512) (xy 355.187206 -234.282905) (xy 355.163628 -234.329179)
			(xy 355.133102 -234.371195) (xy 355.096379 -234.407918) (xy 355.054363 -234.438444) (xy 355.008089 -234.462022)
			(xy 354.958696 -234.47807) (xy 354.907401 -234.486195) (xy 354.855467 -234.486195) (xy 354.804172 -234.47807)
			(xy 354.754779 -234.462022) (xy 354.708505 -234.438444) (xy 354.666489 -234.407918) (xy 354.629766 -234.371195)
			(xy 354.59924 -234.329179) (xy 354.575662 -234.282905) (xy 354.559614 -234.233512) (xy 354.551489 -234.182217)
			(xy 354.271579 -234.182217) (xy 354.263454 -234.233512) (xy 354.247406 -234.282905) (xy 354.223828 -234.329179)
			(xy 354.193302 -234.371195) (xy 354.156579 -234.407918) (xy 354.114563 -234.438444) (xy 354.068289 -234.462022)
			(xy 354.018896 -234.47807) (xy 353.967601 -234.486195) (xy 353.915667 -234.486195) (xy 353.864372 -234.47807)
			(xy 353.814979 -234.462022) (xy 353.768705 -234.438444) (xy 353.726689 -234.407918) (xy 353.689966 -234.371195)
			(xy 353.65944 -234.329179) (xy 353.635862 -234.282905) (xy 353.619814 -234.233512) (xy 353.611689 -234.182217)
			(xy 353.018344 -234.182217) (xy 353.018344 -235.031593) (xy 353.123755 -235.031593) (xy 353.123755 -234.979659)
			(xy 353.13188 -234.928364) (xy 353.147928 -234.878971) (xy 353.171506 -234.832697) (xy 353.202032 -234.790681)
			(xy 353.238755 -234.753958) (xy 353.280771 -234.723432) (xy 353.327045 -234.699854) (xy 353.376438 -234.683806)
			(xy 353.427733 -234.675681) (xy 353.479667 -234.675681) (xy 353.530962 -234.683806) (xy 353.580355 -234.699854)
			(xy 353.626629 -234.723432) (xy 353.668645 -234.753958) (xy 353.705368 -234.790681) (xy 353.735894 -234.832697)
			(xy 353.759472 -234.878971) (xy 353.77552 -234.928364) (xy 353.783645 -234.979659) (xy 353.784154 -235.005626)
			(xy 353.783645 -235.031593) (xy 353.77552 -235.082888) (xy 353.759472 -235.132281) (xy 353.735894 -235.178555)
			(xy 353.705368 -235.220571) (xy 353.668645 -235.257294) (xy 353.626629 -235.28782) (xy 353.608069 -235.297277)
			(xy 354.047553 -235.297277) (xy 354.047553 -235.245343) (xy 354.055678 -235.194048) (xy 354.071726 -235.144655)
			(xy 354.095304 -235.098381) (xy 354.12583 -235.056365) (xy 354.162553 -235.019642) (xy 354.204569 -234.989116)
			(xy 354.250843 -234.965538) (xy 354.300236 -234.94949) (xy 354.351531 -234.941365) (xy 354.403465 -234.941365)
			(xy 354.45476 -234.94949) (xy 354.504153 -234.965538) (xy 354.550427 -234.989116) (xy 354.559948 -234.996033)
			(xy 356.900735 -234.996033) (xy 356.900735 -234.944099) (xy 356.90886 -234.892804) (xy 356.924908 -234.843411)
			(xy 356.948486 -234.797137) (xy 356.979012 -234.755121) (xy 357.015735 -234.718398) (xy 357.057751 -234.687872)
			(xy 357.104025 -234.664294) (xy 357.153418 -234.648246) (xy 357.204713 -234.640121) (xy 357.256647 -234.640121)
			(xy 357.307942 -234.648246) (xy 357.357335 -234.664294) (xy 357.403609 -234.687872) (xy 357.445625 -234.718398)
			(xy 357.482348 -234.755121) (xy 357.512874 -234.797137) (xy 357.536452 -234.843411) (xy 357.5525 -234.892804)
			(xy 357.560625 -234.944099) (xy 357.561134 -234.970066) (xy 357.560625 -234.996033) (xy 357.840789 -234.996033)
			(xy 357.840789 -234.944099) (xy 357.848914 -234.892804) (xy 357.864962 -234.843411) (xy 357.88854 -234.797137)
			(xy 357.919066 -234.755121) (xy 357.955789 -234.718398) (xy 357.997805 -234.687872) (xy 358.044079 -234.664294)
			(xy 358.093472 -234.648246) (xy 358.144767 -234.640121) (xy 358.196701 -234.640121) (xy 358.247996 -234.648246)
			(xy 358.297389 -234.664294) (xy 358.343663 -234.687872) (xy 358.385679 -234.718398) (xy 358.422402 -234.755121)
			(xy 358.452928 -234.797137) (xy 358.476506 -234.843411) (xy 358.492554 -234.892804) (xy 358.500679 -234.944099)
			(xy 358.501188 -234.970066) (xy 358.500679 -234.996033) (xy 358.780335 -234.996033) (xy 358.780335 -234.944099)
			(xy 358.78846 -234.892804) (xy 358.804508 -234.843411) (xy 358.828086 -234.797137) (xy 358.858612 -234.755121)
			(xy 358.895335 -234.718398) (xy 358.937351 -234.687872) (xy 358.983625 -234.664294) (xy 359.033018 -234.648246)
			(xy 359.084313 -234.640121) (xy 359.136247 -234.640121) (xy 359.187542 -234.648246) (xy 359.236935 -234.664294)
			(xy 359.283209 -234.687872) (xy 359.325225 -234.718398) (xy 359.361948 -234.755121) (xy 359.392474 -234.797137)
			(xy 359.416052 -234.843411) (xy 359.4321 -234.892804) (xy 359.440225 -234.944099) (xy 359.440734 -234.970066)
			(xy 359.440225 -234.996033) (xy 359.720135 -234.996033) (xy 359.720135 -234.944099) (xy 359.72826 -234.892804)
			(xy 359.744308 -234.843411) (xy 359.767886 -234.797137) (xy 359.798412 -234.755121) (xy 359.835135 -234.718398)
			(xy 359.877151 -234.687872) (xy 359.923425 -234.664294) (xy 359.972818 -234.648246) (xy 360.024113 -234.640121)
			(xy 360.076047 -234.640121) (xy 360.127342 -234.648246) (xy 360.176735 -234.664294) (xy 360.223009 -234.687872)
			(xy 360.265025 -234.718398) (xy 360.301748 -234.755121) (xy 360.332274 -234.797137) (xy 360.355852 -234.843411)
			(xy 360.3719 -234.892804) (xy 360.380025 -234.944099) (xy 360.380534 -234.970066) (xy 360.380025 -234.996033)
			(xy 360.659935 -234.996033) (xy 360.659935 -234.944099) (xy 360.66806 -234.892804) (xy 360.684108 -234.843411)
			(xy 360.707686 -234.797137) (xy 360.738212 -234.755121) (xy 360.774935 -234.718398) (xy 360.816951 -234.687872)
			(xy 360.863225 -234.664294) (xy 360.912618 -234.648246) (xy 360.963913 -234.640121) (xy 361.015847 -234.640121)
			(xy 361.067142 -234.648246) (xy 361.116535 -234.664294) (xy 361.162809 -234.687872) (xy 361.204825 -234.718398)
			(xy 361.241548 -234.755121) (xy 361.272074 -234.797137) (xy 361.295652 -234.843411) (xy 361.3117 -234.892804)
			(xy 361.319825 -234.944099) (xy 361.320334 -234.970066) (xy 361.319825 -234.996033) (xy 361.599989 -234.996033)
			(xy 361.599989 -234.944099) (xy 361.608114 -234.892804) (xy 361.624162 -234.843411) (xy 361.64774 -234.797137)
			(xy 361.678266 -234.755121) (xy 361.714989 -234.718398) (xy 361.757005 -234.687872) (xy 361.803279 -234.664294)
			(xy 361.852672 -234.648246) (xy 361.903967 -234.640121) (xy 361.955901 -234.640121) (xy 362.007196 -234.648246)
			(xy 362.056589 -234.664294) (xy 362.102863 -234.687872) (xy 362.144879 -234.718398) (xy 362.181602 -234.755121)
			(xy 362.212128 -234.797137) (xy 362.235706 -234.843411) (xy 362.251754 -234.892804) (xy 362.259879 -234.944099)
			(xy 362.260388 -234.970066) (xy 362.259879 -234.996033) (xy 369.118135 -234.996033) (xy 369.118135 -234.944099)
			(xy 369.12626 -234.892804) (xy 369.142308 -234.843411) (xy 369.165886 -234.797137) (xy 369.196412 -234.755121)
			(xy 369.233135 -234.718398) (xy 369.275151 -234.687872) (xy 369.321425 -234.664294) (xy 369.370818 -234.648246)
			(xy 369.422113 -234.640121) (xy 369.474047 -234.640121) (xy 369.525342 -234.648246) (xy 369.574735 -234.664294)
			(xy 369.621009 -234.687872) (xy 369.663025 -234.718398) (xy 369.699748 -234.755121) (xy 369.730274 -234.797137)
			(xy 369.753852 -234.843411) (xy 369.7699 -234.892804) (xy 369.778025 -234.944099) (xy 369.778534 -234.970066)
			(xy 369.778025 -234.996033) (xy 370.057935 -234.996033) (xy 370.057935 -234.944099) (xy 370.06606 -234.892804)
			(xy 370.082108 -234.843411) (xy 370.105686 -234.797137) (xy 370.136212 -234.755121) (xy 370.172935 -234.718398)
			(xy 370.214951 -234.687872) (xy 370.261225 -234.664294) (xy 370.310618 -234.648246) (xy 370.361913 -234.640121)
			(xy 370.413847 -234.640121) (xy 370.465142 -234.648246) (xy 370.514535 -234.664294) (xy 370.560809 -234.687872)
			(xy 370.602825 -234.718398) (xy 370.639548 -234.755121) (xy 370.670074 -234.797137) (xy 370.693652 -234.843411)
			(xy 370.7097 -234.892804) (xy 370.717825 -234.944099) (xy 370.718334 -234.970066) (xy 370.717825 -234.996033)
			(xy 370.997735 -234.996033) (xy 370.997735 -234.944099) (xy 371.00586 -234.892804) (xy 371.021908 -234.843411)
			(xy 371.045486 -234.797137) (xy 371.076012 -234.755121) (xy 371.112735 -234.718398) (xy 371.154751 -234.687872)
			(xy 371.201025 -234.664294) (xy 371.250418 -234.648246) (xy 371.301713 -234.640121) (xy 371.353647 -234.640121)
			(xy 371.404942 -234.648246) (xy 371.454335 -234.664294) (xy 371.500609 -234.687872) (xy 371.542625 -234.718398)
			(xy 371.579348 -234.755121) (xy 371.609874 -234.797137) (xy 371.633452 -234.843411) (xy 371.6495 -234.892804)
			(xy 371.657625 -234.944099) (xy 371.658134 -234.970066) (xy 371.657625 -234.996033) (xy 371.937535 -234.996033)
			(xy 371.937535 -234.944099) (xy 371.94566 -234.892804) (xy 371.961708 -234.843411) (xy 371.985286 -234.797137)
			(xy 372.015812 -234.755121) (xy 372.052535 -234.718398) (xy 372.094551 -234.687872) (xy 372.140825 -234.664294)
			(xy 372.190218 -234.648246) (xy 372.241513 -234.640121) (xy 372.293447 -234.640121) (xy 372.344742 -234.648246)
			(xy 372.394135 -234.664294) (xy 372.440409 -234.687872) (xy 372.482425 -234.718398) (xy 372.519148 -234.755121)
			(xy 372.549674 -234.797137) (xy 372.573252 -234.843411) (xy 372.5893 -234.892804) (xy 372.597425 -234.944099)
			(xy 372.597934 -234.970066) (xy 372.597425 -234.996033) (xy 372.877589 -234.996033) (xy 372.877589 -234.944099)
			(xy 372.885714 -234.892804) (xy 372.901762 -234.843411) (xy 372.92534 -234.797137) (xy 372.955866 -234.755121)
			(xy 372.992589 -234.718398) (xy 373.034605 -234.687872) (xy 373.080879 -234.664294) (xy 373.130272 -234.648246)
			(xy 373.181567 -234.640121) (xy 373.233501 -234.640121) (xy 373.284796 -234.648246) (xy 373.334189 -234.664294)
			(xy 373.380463 -234.687872) (xy 373.422479 -234.718398) (xy 373.459202 -234.755121) (xy 373.489728 -234.797137)
			(xy 373.513306 -234.843411) (xy 373.529354 -234.892804) (xy 373.537479 -234.944099) (xy 373.537988 -234.970066)
			(xy 373.537479 -234.996033) (xy 373.529354 -235.047328) (xy 373.513306 -235.096721) (xy 373.489728 -235.142995)
			(xy 373.459202 -235.185011) (xy 373.422479 -235.221734) (xy 373.380463 -235.25226) (xy 373.334189 -235.275838)
			(xy 373.284796 -235.291886) (xy 373.233501 -235.300011) (xy 373.181567 -235.300011) (xy 373.130272 -235.291886)
			(xy 373.080879 -235.275838) (xy 373.034605 -235.25226) (xy 372.992589 -235.221734) (xy 372.955866 -235.185011)
			(xy 372.92534 -235.142995) (xy 372.901762 -235.096721) (xy 372.885714 -235.047328) (xy 372.877589 -234.996033)
			(xy 372.597425 -234.996033) (xy 372.5893 -235.047328) (xy 372.573252 -235.096721) (xy 372.549674 -235.142995)
			(xy 372.519148 -235.185011) (xy 372.482425 -235.221734) (xy 372.440409 -235.25226) (xy 372.394135 -235.275838)
			(xy 372.344742 -235.291886) (xy 372.293447 -235.300011) (xy 372.241513 -235.300011) (xy 372.190218 -235.291886)
			(xy 372.140825 -235.275838) (xy 372.094551 -235.25226) (xy 372.052535 -235.221734) (xy 372.015812 -235.185011)
			(xy 371.985286 -235.142995) (xy 371.961708 -235.096721) (xy 371.94566 -235.047328) (xy 371.937535 -234.996033)
			(xy 371.657625 -234.996033) (xy 371.6495 -235.047328) (xy 371.633452 -235.096721) (xy 371.609874 -235.142995)
			(xy 371.579348 -235.185011) (xy 371.542625 -235.221734) (xy 371.500609 -235.25226) (xy 371.454335 -235.275838)
			(xy 371.404942 -235.291886) (xy 371.353647 -235.300011) (xy 371.301713 -235.300011) (xy 371.250418 -235.291886)
			(xy 371.201025 -235.275838) (xy 371.154751 -235.25226) (xy 371.112735 -235.221734) (xy 371.076012 -235.185011)
			(xy 371.045486 -235.142995) (xy 371.021908 -235.096721) (xy 371.00586 -235.047328) (xy 370.997735 -234.996033)
			(xy 370.717825 -234.996033) (xy 370.7097 -235.047328) (xy 370.693652 -235.096721) (xy 370.670074 -235.142995)
			(xy 370.639548 -235.185011) (xy 370.602825 -235.221734) (xy 370.560809 -235.25226) (xy 370.514535 -235.275838)
			(xy 370.465142 -235.291886) (xy 370.413847 -235.300011) (xy 370.361913 -235.300011) (xy 370.310618 -235.291886)
			(xy 370.261225 -235.275838) (xy 370.214951 -235.25226) (xy 370.172935 -235.221734) (xy 370.136212 -235.185011)
			(xy 370.105686 -235.142995) (xy 370.082108 -235.096721) (xy 370.06606 -235.047328) (xy 370.057935 -234.996033)
			(xy 369.778025 -234.996033) (xy 369.7699 -235.047328) (xy 369.753852 -235.096721) (xy 369.730274 -235.142995)
			(xy 369.699748 -235.185011) (xy 369.663025 -235.221734) (xy 369.621009 -235.25226) (xy 369.574735 -235.275838)
			(xy 369.525342 -235.291886) (xy 369.474047 -235.300011) (xy 369.422113 -235.300011) (xy 369.370818 -235.291886)
			(xy 369.321425 -235.275838) (xy 369.275151 -235.25226) (xy 369.233135 -235.221734) (xy 369.196412 -235.185011)
			(xy 369.165886 -235.142995) (xy 369.142308 -235.096721) (xy 369.12626 -235.047328) (xy 369.118135 -234.996033)
			(xy 362.259879 -234.996033) (xy 362.251754 -235.047328) (xy 362.235706 -235.096721) (xy 362.212128 -235.142995)
			(xy 362.181602 -235.185011) (xy 362.144879 -235.221734) (xy 362.102863 -235.25226) (xy 362.056589 -235.275838)
			(xy 362.007196 -235.291886) (xy 361.955901 -235.300011) (xy 361.903967 -235.300011) (xy 361.852672 -235.291886)
			(xy 361.803279 -235.275838) (xy 361.757005 -235.25226) (xy 361.714989 -235.221734) (xy 361.678266 -235.185011)
			(xy 361.64774 -235.142995) (xy 361.624162 -235.096721) (xy 361.608114 -235.047328) (xy 361.599989 -234.996033)
			(xy 361.319825 -234.996033) (xy 361.3117 -235.047328) (xy 361.295652 -235.096721) (xy 361.272074 -235.142995)
			(xy 361.241548 -235.185011) (xy 361.204825 -235.221734) (xy 361.162809 -235.25226) (xy 361.116535 -235.275838)
			(xy 361.067142 -235.291886) (xy 361.015847 -235.300011) (xy 360.963913 -235.300011) (xy 360.912618 -235.291886)
			(xy 360.863225 -235.275838) (xy 360.816951 -235.25226) (xy 360.774935 -235.221734) (xy 360.738212 -235.185011)
			(xy 360.707686 -235.142995) (xy 360.684108 -235.096721) (xy 360.66806 -235.047328) (xy 360.659935 -234.996033)
			(xy 360.380025 -234.996033) (xy 360.3719 -235.047328) (xy 360.355852 -235.096721) (xy 360.332274 -235.142995)
			(xy 360.301748 -235.185011) (xy 360.265025 -235.221734) (xy 360.223009 -235.25226) (xy 360.176735 -235.275838)
			(xy 360.127342 -235.291886) (xy 360.076047 -235.300011) (xy 360.024113 -235.300011) (xy 359.972818 -235.291886)
			(xy 359.923425 -235.275838) (xy 359.877151 -235.25226) (xy 359.835135 -235.221734) (xy 359.798412 -235.185011)
			(xy 359.767886 -235.142995) (xy 359.744308 -235.096721) (xy 359.72826 -235.047328) (xy 359.720135 -234.996033)
			(xy 359.440225 -234.996033) (xy 359.4321 -235.047328) (xy 359.416052 -235.096721) (xy 359.392474 -235.142995)
			(xy 359.361948 -235.185011) (xy 359.325225 -235.221734) (xy 359.283209 -235.25226) (xy 359.236935 -235.275838)
			(xy 359.187542 -235.291886) (xy 359.136247 -235.300011) (xy 359.084313 -235.300011) (xy 359.033018 -235.291886)
			(xy 358.983625 -235.275838) (xy 358.937351 -235.25226) (xy 358.895335 -235.221734) (xy 358.858612 -235.185011)
			(xy 358.828086 -235.142995) (xy 358.804508 -235.096721) (xy 358.78846 -235.047328) (xy 358.780335 -234.996033)
			(xy 358.500679 -234.996033) (xy 358.492554 -235.047328) (xy 358.476506 -235.096721) (xy 358.452928 -235.142995)
			(xy 358.422402 -235.185011) (xy 358.385679 -235.221734) (xy 358.343663 -235.25226) (xy 358.297389 -235.275838)
			(xy 358.247996 -235.291886) (xy 358.196701 -235.300011) (xy 358.144767 -235.300011) (xy 358.093472 -235.291886)
			(xy 358.044079 -235.275838) (xy 357.997805 -235.25226) (xy 357.955789 -235.221734) (xy 357.919066 -235.185011)
			(xy 357.88854 -235.142995) (xy 357.864962 -235.096721) (xy 357.848914 -235.047328) (xy 357.840789 -234.996033)
			(xy 357.560625 -234.996033) (xy 357.5525 -235.047328) (xy 357.536452 -235.096721) (xy 357.512874 -235.142995)
			(xy 357.482348 -235.185011) (xy 357.445625 -235.221734) (xy 357.403609 -235.25226) (xy 357.357335 -235.275838)
			(xy 357.307942 -235.291886) (xy 357.256647 -235.300011) (xy 357.204713 -235.300011) (xy 357.153418 -235.291886)
			(xy 357.104025 -235.275838) (xy 357.057751 -235.25226) (xy 357.015735 -235.221734) (xy 356.979012 -235.185011)
			(xy 356.948486 -235.142995) (xy 356.924908 -235.096721) (xy 356.90886 -235.047328) (xy 356.900735 -234.996033)
			(xy 354.559948 -234.996033) (xy 354.592443 -235.019642) (xy 354.629166 -235.056365) (xy 354.659692 -235.098381)
			(xy 354.68327 -235.144655) (xy 354.699318 -235.194048) (xy 354.707443 -235.245343) (xy 354.707952 -235.27131)
			(xy 354.707443 -235.297277) (xy 354.699318 -235.348572) (xy 354.68327 -235.397965) (xy 354.659692 -235.444239)
			(xy 354.629166 -235.486255) (xy 354.592443 -235.522978) (xy 354.550427 -235.553504) (xy 354.504153 -235.577082)
			(xy 354.45476 -235.59313) (xy 354.403465 -235.601255) (xy 354.351531 -235.601255) (xy 354.300236 -235.59313)
			(xy 354.250843 -235.577082) (xy 354.204569 -235.553504) (xy 354.162553 -235.522978) (xy 354.12583 -235.486255)
			(xy 354.095304 -235.444239) (xy 354.071726 -235.397965) (xy 354.055678 -235.348572) (xy 354.047553 -235.297277)
			(xy 353.608069 -235.297277) (xy 353.580355 -235.311398) (xy 353.530962 -235.327446) (xy 353.479667 -235.335571)
			(xy 353.427733 -235.335571) (xy 353.376438 -235.327446) (xy 353.327045 -235.311398) (xy 353.280771 -235.28782)
			(xy 353.238755 -235.257294) (xy 353.202032 -235.220571) (xy 353.171506 -235.178555) (xy 353.147928 -235.132281)
			(xy 353.13188 -235.082888) (xy 353.123755 -235.031593) (xy 353.018344 -235.031593) (xy 353.018344 -235.809849)
			(xy 357.370889 -235.809849) (xy 357.370889 -235.757915) (xy 357.379014 -235.70662) (xy 357.395062 -235.657227)
			(xy 357.41864 -235.610953) (xy 357.449166 -235.568937) (xy 357.485889 -235.532214) (xy 357.527905 -235.501688)
			(xy 357.574179 -235.47811) (xy 357.623572 -235.462062) (xy 357.674867 -235.453937) (xy 357.726801 -235.453937)
			(xy 357.778096 -235.462062) (xy 357.827489 -235.47811) (xy 357.873763 -235.501688) (xy 357.915779 -235.532214)
			(xy 357.952502 -235.568937) (xy 357.983028 -235.610953) (xy 358.006606 -235.657227) (xy 358.022654 -235.70662)
			(xy 358.030779 -235.757915) (xy 358.031288 -235.783882) (xy 358.030779 -235.809849) (xy 358.310689 -235.809849)
			(xy 358.310689 -235.757915) (xy 358.318814 -235.70662) (xy 358.334862 -235.657227) (xy 358.35844 -235.610953)
			(xy 358.388966 -235.568937) (xy 358.425689 -235.532214) (xy 358.467705 -235.501688) (xy 358.513979 -235.47811)
			(xy 358.563372 -235.462062) (xy 358.614667 -235.453937) (xy 358.666601 -235.453937) (xy 358.717896 -235.462062)
			(xy 358.767289 -235.47811) (xy 358.813563 -235.501688) (xy 358.855579 -235.532214) (xy 358.892302 -235.568937)
			(xy 358.922828 -235.610953) (xy 358.946406 -235.657227) (xy 358.962454 -235.70662) (xy 358.970579 -235.757915)
			(xy 358.971088 -235.783882) (xy 358.970579 -235.809849) (xy 359.250489 -235.809849) (xy 359.250489 -235.757915)
			(xy 359.258614 -235.70662) (xy 359.274662 -235.657227) (xy 359.29824 -235.610953) (xy 359.328766 -235.568937)
			(xy 359.365489 -235.532214) (xy 359.407505 -235.501688) (xy 359.453779 -235.47811) (xy 359.503172 -235.462062)
			(xy 359.554467 -235.453937) (xy 359.606401 -235.453937) (xy 359.657696 -235.462062) (xy 359.707089 -235.47811)
			(xy 359.753363 -235.501688) (xy 359.795379 -235.532214) (xy 359.832102 -235.568937) (xy 359.862628 -235.610953)
			(xy 359.886206 -235.657227) (xy 359.902254 -235.70662) (xy 359.910379 -235.757915) (xy 359.910888 -235.783882)
			(xy 359.910379 -235.809849) (xy 360.190289 -235.809849) (xy 360.190289 -235.757915) (xy 360.198414 -235.70662)
			(xy 360.214462 -235.657227) (xy 360.23804 -235.610953) (xy 360.268566 -235.568937) (xy 360.305289 -235.532214)
			(xy 360.347305 -235.501688) (xy 360.393579 -235.47811) (xy 360.442972 -235.462062) (xy 360.494267 -235.453937)
			(xy 360.546201 -235.453937) (xy 360.597496 -235.462062) (xy 360.646889 -235.47811) (xy 360.693163 -235.501688)
			(xy 360.735179 -235.532214) (xy 360.771902 -235.568937) (xy 360.802428 -235.610953) (xy 360.826006 -235.657227)
			(xy 360.842054 -235.70662) (xy 360.850179 -235.757915) (xy 360.850688 -235.783882) (xy 360.850179 -235.809849)
			(xy 361.130089 -235.809849) (xy 361.130089 -235.757915) (xy 361.138214 -235.70662) (xy 361.154262 -235.657227)
			(xy 361.17784 -235.610953) (xy 361.208366 -235.568937) (xy 361.245089 -235.532214) (xy 361.287105 -235.501688)
			(xy 361.333379 -235.47811) (xy 361.382772 -235.462062) (xy 361.434067 -235.453937) (xy 361.486001 -235.453937)
			(xy 361.537296 -235.462062) (xy 361.586689 -235.47811) (xy 361.632963 -235.501688) (xy 361.674979 -235.532214)
			(xy 361.711702 -235.568937) (xy 361.742228 -235.610953) (xy 361.765806 -235.657227) (xy 361.781854 -235.70662)
			(xy 361.789979 -235.757915) (xy 361.790488 -235.783882) (xy 361.789979 -235.809849) (xy 362.069889 -235.809849)
			(xy 362.069889 -235.757915) (xy 362.078014 -235.70662) (xy 362.094062 -235.657227) (xy 362.11764 -235.610953)
			(xy 362.148166 -235.568937) (xy 362.184889 -235.532214) (xy 362.226905 -235.501688) (xy 362.273179 -235.47811)
			(xy 362.322572 -235.462062) (xy 362.373867 -235.453937) (xy 362.425801 -235.453937) (xy 362.477096 -235.462062)
			(xy 362.526489 -235.47811) (xy 362.572763 -235.501688) (xy 362.614779 -235.532214) (xy 362.651502 -235.568937)
			(xy 362.682028 -235.610953) (xy 362.705606 -235.657227) (xy 362.721654 -235.70662) (xy 362.729779 -235.757915)
			(xy 362.730288 -235.783882) (xy 362.729779 -235.809849) (xy 362.727163 -235.826366) (xy 364.205047 -235.826366)
			(xy 364.205047 -235.774434) (xy 364.21317 -235.723142) (xy 364.229217 -235.673752) (xy 364.252791 -235.62748)
			(xy 364.283314 -235.585465) (xy 364.320033 -235.548741) (xy 364.362044 -235.518213) (xy 364.408313 -235.494633)
			(xy 364.457701 -235.47858) (xy 364.508992 -235.47045) (xy 364.534958 -235.469938) (xy 364.55951 -235.470382)
			(xy 364.608076 -235.477623) (xy 364.655038 -235.491966) (xy 364.699362 -235.513097) (xy 364.740073 -235.54055)
			(xy 364.758478 -235.556806) (xy 364.769967 -235.566609) (xy 364.797204 -235.579623) (xy 364.827058 -235.584091)
			(xy 364.856912 -235.579623) (xy 364.884149 -235.566609) (xy 364.895638 -235.556806) (xy 364.914049 -235.540556)
			(xy 364.954752 -235.513086) (xy 364.999073 -235.491946) (xy 365.046036 -235.477601) (xy 365.094605 -235.470368)
			(xy 365.119158 -235.469938) (xy 365.14371 -235.470382) (xy 365.192276 -235.477623) (xy 365.239238 -235.491966)
			(xy 365.283562 -235.513097) (xy 365.324273 -235.54055) (xy 365.342678 -235.556806) (xy 365.354167 -235.566609)
			(xy 365.381404 -235.579623) (xy 365.411258 -235.584091) (xy 365.441112 -235.579623) (xy 365.468349 -235.566609)
			(xy 365.479838 -235.556806) (xy 365.498249 -235.540556) (xy 365.538952 -235.513086) (xy 365.583273 -235.491946)
			(xy 365.630236 -235.477601) (xy 365.678805 -235.470368) (xy 365.703358 -235.469938) (xy 365.72791 -235.470382)
			(xy 365.776476 -235.477623) (xy 365.823438 -235.491966) (xy 365.867762 -235.513097) (xy 365.908473 -235.54055)
			(xy 365.926878 -235.556806) (xy 365.938367 -235.566609) (xy 365.965604 -235.579623) (xy 365.995458 -235.584091)
			(xy 366.025312 -235.579623) (xy 366.052549 -235.566609) (xy 366.064038 -235.556806) (xy 366.082449 -235.540556)
			(xy 366.123152 -235.513086) (xy 366.167473 -235.491946) (xy 366.214436 -235.477601) (xy 366.263005 -235.470368)
			(xy 366.287558 -235.469938) (xy 366.31211 -235.470382) (xy 366.360676 -235.477623) (xy 366.407638 -235.491966)
			(xy 366.451962 -235.513097) (xy 366.492673 -235.54055) (xy 366.511078 -235.556806) (xy 366.522567 -235.566609)
			(xy 366.549804 -235.579623) (xy 366.579658 -235.584091) (xy 366.609512 -235.579623) (xy 366.636749 -235.566609)
			(xy 366.648238 -235.556806) (xy 366.666649 -235.540556) (xy 366.707352 -235.513086) (xy 366.751673 -235.491946)
			(xy 366.798636 -235.477601) (xy 366.847205 -235.470368) (xy 366.871758 -235.469938) (xy 366.89631 -235.470382)
			(xy 366.944876 -235.477623) (xy 366.991838 -235.491966) (xy 367.036162 -235.513097) (xy 367.076873 -235.54055)
			(xy 367.095278 -235.556806) (xy 367.106767 -235.566609) (xy 367.134004 -235.579623) (xy 367.163858 -235.584091)
			(xy 367.193712 -235.579623) (xy 367.220949 -235.566609) (xy 367.232438 -235.556806) (xy 367.250849 -235.540556)
			(xy 367.291552 -235.513086) (xy 367.335873 -235.491946) (xy 367.382836 -235.477601) (xy 367.431405 -235.470368)
			(xy 367.455958 -235.469938) (xy 367.481929 -235.470434) (xy 367.533232 -235.478553) (xy 367.582633 -235.494599)
			(xy 367.628915 -235.518176) (xy 367.670939 -235.548703) (xy 367.70767 -235.585429) (xy 367.738202 -235.627449)
			(xy 367.761785 -235.673728) (xy 367.777837 -235.723127) (xy 367.785963 -235.774429) (xy 367.785963 -235.809849)
			(xy 369.588289 -235.809849) (xy 369.588289 -235.757915) (xy 369.596414 -235.70662) (xy 369.612462 -235.657227)
			(xy 369.63604 -235.610953) (xy 369.666566 -235.568937) (xy 369.703289 -235.532214) (xy 369.745305 -235.501688)
			(xy 369.791579 -235.47811) (xy 369.840972 -235.462062) (xy 369.892267 -235.453937) (xy 369.944201 -235.453937)
			(xy 369.995496 -235.462062) (xy 370.044889 -235.47811) (xy 370.091163 -235.501688) (xy 370.133179 -235.532214)
			(xy 370.169902 -235.568937) (xy 370.200428 -235.610953) (xy 370.224006 -235.657227) (xy 370.240054 -235.70662)
			(xy 370.248179 -235.757915) (xy 370.248688 -235.783882) (xy 370.248179 -235.809849) (xy 370.528089 -235.809849)
			(xy 370.528089 -235.757915) (xy 370.536214 -235.70662) (xy 370.552262 -235.657227) (xy 370.57584 -235.610953)
			(xy 370.606366 -235.568937) (xy 370.643089 -235.532214) (xy 370.685105 -235.501688) (xy 370.731379 -235.47811)
			(xy 370.780772 -235.462062) (xy 370.832067 -235.453937) (xy 370.884001 -235.453937) (xy 370.935296 -235.462062)
			(xy 370.984689 -235.47811) (xy 371.030963 -235.501688) (xy 371.072979 -235.532214) (xy 371.109702 -235.568937)
			(xy 371.140228 -235.610953) (xy 371.163806 -235.657227) (xy 371.179854 -235.70662) (xy 371.187979 -235.757915)
			(xy 371.188488 -235.783882) (xy 371.187979 -235.809849) (xy 371.467889 -235.809849) (xy 371.467889 -235.757915)
			(xy 371.476014 -235.70662) (xy 371.492062 -235.657227) (xy 371.51564 -235.610953) (xy 371.546166 -235.568937)
			(xy 371.582889 -235.532214) (xy 371.624905 -235.501688) (xy 371.671179 -235.47811) (xy 371.720572 -235.462062)
			(xy 371.771867 -235.453937) (xy 371.823801 -235.453937) (xy 371.875096 -235.462062) (xy 371.924489 -235.47811)
			(xy 371.970763 -235.501688) (xy 372.012779 -235.532214) (xy 372.049502 -235.568937) (xy 372.080028 -235.610953)
			(xy 372.103606 -235.657227) (xy 372.119654 -235.70662) (xy 372.127779 -235.757915) (xy 372.128288 -235.783882)
			(xy 372.127779 -235.809849) (xy 372.407689 -235.809849) (xy 372.407689 -235.757915) (xy 372.415814 -235.70662)
			(xy 372.431862 -235.657227) (xy 372.45544 -235.610953) (xy 372.485966 -235.568937) (xy 372.522689 -235.532214)
			(xy 372.564705 -235.501688) (xy 372.610979 -235.47811) (xy 372.660372 -235.462062) (xy 372.711667 -235.453937)
			(xy 372.763601 -235.453937) (xy 372.814896 -235.462062) (xy 372.864289 -235.47811) (xy 372.910563 -235.501688)
			(xy 372.952579 -235.532214) (xy 372.989302 -235.568937) (xy 373.019828 -235.610953) (xy 373.043406 -235.657227)
			(xy 373.059454 -235.70662) (xy 373.067579 -235.757915) (xy 373.068088 -235.783882) (xy 373.067579 -235.809849)
			(xy 373.059454 -235.861144) (xy 373.043406 -235.910537) (xy 373.019828 -235.956811) (xy 372.989302 -235.998827)
			(xy 372.952579 -236.03555) (xy 372.910563 -236.066076) (xy 372.864289 -236.089654) (xy 372.814896 -236.105702)
			(xy 372.763601 -236.113827) (xy 372.711667 -236.113827) (xy 372.660372 -236.105702) (xy 372.610979 -236.089654)
			(xy 372.564705 -236.066076) (xy 372.522689 -236.03555) (xy 372.485966 -235.998827) (xy 372.45544 -235.956811)
			(xy 372.431862 -235.910537) (xy 372.415814 -235.861144) (xy 372.407689 -235.809849) (xy 372.127779 -235.809849)
			(xy 372.119654 -235.861144) (xy 372.103606 -235.910537) (xy 372.080028 -235.956811) (xy 372.049502 -235.998827)
			(xy 372.012779 -236.03555) (xy 371.970763 -236.066076) (xy 371.924489 -236.089654) (xy 371.875096 -236.105702)
			(xy 371.823801 -236.113827) (xy 371.771867 -236.113827) (xy 371.720572 -236.105702) (xy 371.671179 -236.089654)
			(xy 371.624905 -236.066076) (xy 371.582889 -236.03555) (xy 371.546166 -235.998827) (xy 371.51564 -235.956811)
			(xy 371.492062 -235.910537) (xy 371.476014 -235.861144) (xy 371.467889 -235.809849) (xy 371.187979 -235.809849)
			(xy 371.179854 -235.861144) (xy 371.163806 -235.910537) (xy 371.140228 -235.956811) (xy 371.109702 -235.998827)
			(xy 371.072979 -236.03555) (xy 371.030963 -236.066076) (xy 370.984689 -236.089654) (xy 370.935296 -236.105702)
			(xy 370.884001 -236.113827) (xy 370.832067 -236.113827) (xy 370.780772 -236.105702) (xy 370.731379 -236.089654)
			(xy 370.685105 -236.066076) (xy 370.643089 -236.03555) (xy 370.606366 -235.998827) (xy 370.57584 -235.956811)
			(xy 370.552262 -235.910537) (xy 370.536214 -235.861144) (xy 370.528089 -235.809849) (xy 370.248179 -235.809849)
			(xy 370.240054 -235.861144) (xy 370.224006 -235.910537) (xy 370.200428 -235.956811) (xy 370.169902 -235.998827)
			(xy 370.133179 -236.03555) (xy 370.091163 -236.066076) (xy 370.044889 -236.089654) (xy 369.995496 -236.105702)
			(xy 369.944201 -236.113827) (xy 369.892267 -236.113827) (xy 369.840972 -236.105702) (xy 369.791579 -236.089654)
			(xy 369.745305 -236.066076) (xy 369.703289 -236.03555) (xy 369.666566 -235.998827) (xy 369.63604 -235.956811)
			(xy 369.612462 -235.910537) (xy 369.596414 -235.861144) (xy 369.588289 -235.809849) (xy 367.785963 -235.809849)
			(xy 367.785963 -235.826371) (xy 367.777837 -235.877673) (xy 367.761785 -235.927072) (xy 367.738202 -235.973351)
			(xy 367.70767 -236.015371) (xy 367.670939 -236.052097) (xy 367.628915 -236.082624) (xy 367.582633 -236.106201)
			(xy 367.533232 -236.122247) (xy 367.481929 -236.130366) (xy 367.455958 -236.130846) (xy 367.431406 -236.130397)
			(xy 367.38284 -236.123158) (xy 367.335878 -236.108816) (xy 367.291554 -236.087686) (xy 367.250843 -236.060234)
			(xy 367.232438 -236.043978) (xy 367.220949 -236.034175) (xy 367.193712 -236.021161) (xy 367.163858 -236.016693)
			(xy 367.134004 -236.021161) (xy 367.106767 -236.034175) (xy 367.095278 -236.043978) (xy 367.076898 -236.060266)
			(xy 367.036187 -236.08773) (xy 366.991858 -236.108864) (xy 366.944888 -236.1232) (xy 366.896313 -236.130422)
			(xy 366.871758 -236.130846) (xy 366.847206 -236.130397) (xy 366.79864 -236.123158) (xy 366.751678 -236.108816)
			(xy 366.707354 -236.087686) (xy 366.666643 -236.060234) (xy 366.648238 -236.043978) (xy 366.636749 -236.034175)
			(xy 366.609512 -236.021161) (xy 366.579658 -236.016693) (xy 366.549804 -236.021161) (xy 366.522567 -236.034175)
			(xy 366.511078 -236.043978) (xy 366.492698 -236.060266) (xy 366.451987 -236.08773) (xy 366.407658 -236.108864)
			(xy 366.360688 -236.1232) (xy 366.312113 -236.130422) (xy 366.287558 -236.130846) (xy 366.263006 -236.130397)
			(xy 366.21444 -236.123158) (xy 366.167478 -236.108816) (xy 366.123154 -236.087686) (xy 366.082443 -236.060234)
			(xy 366.064038 -236.043978) (xy 366.052549 -236.034175) (xy 366.025312 -236.021161) (xy 365.995458 -236.016693)
			(xy 365.965604 -236.021161) (xy 365.938367 -236.034175) (xy 365.926878 -236.043978) (xy 365.908498 -236.060266)
			(xy 365.867787 -236.08773) (xy 365.823458 -236.108864) (xy 365.776488 -236.1232) (xy 365.727913 -236.130422)
			(xy 365.703358 -236.130846) (xy 365.678806 -236.130397) (xy 365.63024 -236.123158) (xy 365.583278 -236.108816)
			(xy 365.538954 -236.087686) (xy 365.498243 -236.060234) (xy 365.479838 -236.043978) (xy 365.468349 -236.034175)
			(xy 365.441112 -236.021161) (xy 365.411258 -236.016693) (xy 365.381404 -236.021161) (xy 365.354167 -236.034175)
			(xy 365.342678 -236.043978) (xy 365.324298 -236.060266) (xy 365.283587 -236.08773) (xy 365.239258 -236.108864)
			(xy 365.192288 -236.1232) (xy 365.143713 -236.130422) (xy 365.119158 -236.130846) (xy 365.094606 -236.130397)
			(xy 365.04604 -236.123158) (xy 364.999078 -236.108816) (xy 364.954754 -236.087686) (xy 364.914043 -236.060234)
			(xy 364.895638 -236.043978) (xy 364.884149 -236.034175) (xy 364.856912 -236.021161) (xy 364.827058 -236.016693)
			(xy 364.797204 -236.021161) (xy 364.769967 -236.034175) (xy 364.758478 -236.043978) (xy 364.740098 -236.060266)
			(xy 364.699387 -236.08773) (xy 364.655058 -236.108864) (xy 364.608088 -236.1232) (xy 364.559513 -236.130422)
			(xy 364.534958 -236.130846) (xy 364.508992 -236.13035) (xy 364.457701 -236.12222) (xy 364.408313 -236.106167)
			(xy 364.362044 -236.082587) (xy 364.320033 -236.052059) (xy 364.283314 -236.015335) (xy 364.252791 -235.97332)
			(xy 364.229217 -235.927048) (xy 364.21317 -235.877658) (xy 364.205047 -235.826366) (xy 362.727163 -235.826366)
			(xy 362.721654 -235.861144) (xy 362.705606 -235.910537) (xy 362.682028 -235.956811) (xy 362.651502 -235.998827)
			(xy 362.614779 -236.03555) (xy 362.572763 -236.066076) (xy 362.526489 -236.089654) (xy 362.477096 -236.105702)
			(xy 362.425801 -236.113827) (xy 362.373867 -236.113827) (xy 362.322572 -236.105702) (xy 362.273179 -236.089654)
			(xy 362.226905 -236.066076) (xy 362.184889 -236.03555) (xy 362.148166 -235.998827) (xy 362.11764 -235.956811)
			(xy 362.094062 -235.910537) (xy 362.078014 -235.861144) (xy 362.069889 -235.809849) (xy 361.789979 -235.809849)
			(xy 361.781854 -235.861144) (xy 361.765806 -235.910537) (xy 361.742228 -235.956811) (xy 361.711702 -235.998827)
			(xy 361.674979 -236.03555) (xy 361.632963 -236.066076) (xy 361.586689 -236.089654) (xy 361.537296 -236.105702)
			(xy 361.486001 -236.113827) (xy 361.434067 -236.113827) (xy 361.382772 -236.105702) (xy 361.333379 -236.089654)
			(xy 361.287105 -236.066076) (xy 361.245089 -236.03555) (xy 361.208366 -235.998827) (xy 361.17784 -235.956811)
			(xy 361.154262 -235.910537) (xy 361.138214 -235.861144) (xy 361.130089 -235.809849) (xy 360.850179 -235.809849)
			(xy 360.842054 -235.861144) (xy 360.826006 -235.910537) (xy 360.802428 -235.956811) (xy 360.771902 -235.998827)
			(xy 360.735179 -236.03555) (xy 360.693163 -236.066076) (xy 360.646889 -236.089654) (xy 360.597496 -236.105702)
			(xy 360.546201 -236.113827) (xy 360.494267 -236.113827) (xy 360.442972 -236.105702) (xy 360.393579 -236.089654)
			(xy 360.347305 -236.066076) (xy 360.305289 -236.03555) (xy 360.268566 -235.998827) (xy 360.23804 -235.956811)
			(xy 360.214462 -235.910537) (xy 360.198414 -235.861144) (xy 360.190289 -235.809849) (xy 359.910379 -235.809849)
			(xy 359.902254 -235.861144) (xy 359.886206 -235.910537) (xy 359.862628 -235.956811) (xy 359.832102 -235.998827)
			(xy 359.795379 -236.03555) (xy 359.753363 -236.066076) (xy 359.707089 -236.089654) (xy 359.657696 -236.105702)
			(xy 359.606401 -236.113827) (xy 359.554467 -236.113827) (xy 359.503172 -236.105702) (xy 359.453779 -236.089654)
			(xy 359.407505 -236.066076) (xy 359.365489 -236.03555) (xy 359.328766 -235.998827) (xy 359.29824 -235.956811)
			(xy 359.274662 -235.910537) (xy 359.258614 -235.861144) (xy 359.250489 -235.809849) (xy 358.970579 -235.809849)
			(xy 358.962454 -235.861144) (xy 358.946406 -235.910537) (xy 358.922828 -235.956811) (xy 358.892302 -235.998827)
			(xy 358.855579 -236.03555) (xy 358.813563 -236.066076) (xy 358.767289 -236.089654) (xy 358.717896 -236.105702)
			(xy 358.666601 -236.113827) (xy 358.614667 -236.113827) (xy 358.563372 -236.105702) (xy 358.513979 -236.089654)
			(xy 358.467705 -236.066076) (xy 358.425689 -236.03555) (xy 358.388966 -235.998827) (xy 358.35844 -235.956811)
			(xy 358.334862 -235.910537) (xy 358.318814 -235.861144) (xy 358.310689 -235.809849) (xy 358.030779 -235.809849)
			(xy 358.022654 -235.861144) (xy 358.006606 -235.910537) (xy 357.983028 -235.956811) (xy 357.952502 -235.998827)
			(xy 357.915779 -236.03555) (xy 357.873763 -236.066076) (xy 357.827489 -236.089654) (xy 357.778096 -236.105702)
			(xy 357.726801 -236.113827) (xy 357.674867 -236.113827) (xy 357.623572 -236.105702) (xy 357.574179 -236.089654)
			(xy 357.527905 -236.066076) (xy 357.485889 -236.03555) (xy 357.449166 -235.998827) (xy 357.41864 -235.956811)
			(xy 357.395062 -235.910537) (xy 357.379014 -235.861144) (xy 357.370889 -235.809849) (xy 353.018344 -235.809849)
			(xy 353.018344 -236.623919) (xy 356.900735 -236.623919) (xy 356.900735 -236.571985) (xy 356.90886 -236.52069)
			(xy 356.924908 -236.471297) (xy 356.948486 -236.425023) (xy 356.979012 -236.383007) (xy 357.015735 -236.346284)
			(xy 357.057751 -236.315758) (xy 357.104025 -236.29218) (xy 357.153418 -236.276132) (xy 357.204713 -236.268007)
			(xy 357.256647 -236.268007) (xy 357.307942 -236.276132) (xy 357.357335 -236.29218) (xy 357.403609 -236.315758)
			(xy 357.445625 -236.346284) (xy 357.482348 -236.383007) (xy 357.512874 -236.425023) (xy 357.536452 -236.471297)
			(xy 357.5525 -236.52069) (xy 357.560625 -236.571985) (xy 357.561134 -236.597952) (xy 357.560625 -236.623919)
			(xy 357.840789 -236.623919) (xy 357.840789 -236.571985) (xy 357.848914 -236.52069) (xy 357.864962 -236.471297)
			(xy 357.88854 -236.425023) (xy 357.919066 -236.383007) (xy 357.955789 -236.346284) (xy 357.997805 -236.315758)
			(xy 358.044079 -236.29218) (xy 358.093472 -236.276132) (xy 358.144767 -236.268007) (xy 358.196701 -236.268007)
			(xy 358.247996 -236.276132) (xy 358.297389 -236.29218) (xy 358.343663 -236.315758) (xy 358.385679 -236.346284)
			(xy 358.422402 -236.383007) (xy 358.452928 -236.425023) (xy 358.476506 -236.471297) (xy 358.492554 -236.52069)
			(xy 358.500679 -236.571985) (xy 358.501188 -236.597952) (xy 358.500679 -236.623919) (xy 358.780335 -236.623919)
			(xy 358.780335 -236.571985) (xy 358.78846 -236.52069) (xy 358.804508 -236.471297) (xy 358.828086 -236.425023)
			(xy 358.858612 -236.383007) (xy 358.895335 -236.346284) (xy 358.937351 -236.315758) (xy 358.983625 -236.29218)
			(xy 359.033018 -236.276132) (xy 359.084313 -236.268007) (xy 359.136247 -236.268007) (xy 359.187542 -236.276132)
			(xy 359.236935 -236.29218) (xy 359.283209 -236.315758) (xy 359.325225 -236.346284) (xy 359.361948 -236.383007)
			(xy 359.392474 -236.425023) (xy 359.416052 -236.471297) (xy 359.4321 -236.52069) (xy 359.440225 -236.571985)
			(xy 359.440734 -236.597952) (xy 359.440225 -236.623919) (xy 359.720135 -236.623919) (xy 359.720135 -236.571985)
			(xy 359.72826 -236.52069) (xy 359.744308 -236.471297) (xy 359.767886 -236.425023) (xy 359.798412 -236.383007)
			(xy 359.835135 -236.346284) (xy 359.877151 -236.315758) (xy 359.923425 -236.29218) (xy 359.972818 -236.276132)
			(xy 360.024113 -236.268007) (xy 360.076047 -236.268007) (xy 360.127342 -236.276132) (xy 360.176735 -236.29218)
			(xy 360.223009 -236.315758) (xy 360.265025 -236.346284) (xy 360.301748 -236.383007) (xy 360.332274 -236.425023)
			(xy 360.355852 -236.471297) (xy 360.3719 -236.52069) (xy 360.380025 -236.571985) (xy 360.380534 -236.597952)
			(xy 360.380025 -236.623919) (xy 360.659935 -236.623919) (xy 360.659935 -236.571985) (xy 360.66806 -236.52069)
			(xy 360.684108 -236.471297) (xy 360.707686 -236.425023) (xy 360.738212 -236.383007) (xy 360.774935 -236.346284)
			(xy 360.816951 -236.315758) (xy 360.863225 -236.29218) (xy 360.912618 -236.276132) (xy 360.963913 -236.268007)
			(xy 361.015847 -236.268007) (xy 361.067142 -236.276132) (xy 361.116535 -236.29218) (xy 361.162809 -236.315758)
			(xy 361.204825 -236.346284) (xy 361.241548 -236.383007) (xy 361.272074 -236.425023) (xy 361.295652 -236.471297)
			(xy 361.3117 -236.52069) (xy 361.319825 -236.571985) (xy 361.320334 -236.597952) (xy 361.319825 -236.623919)
			(xy 361.599989 -236.623919) (xy 361.599989 -236.571985) (xy 361.608114 -236.52069) (xy 361.624162 -236.471297)
			(xy 361.64774 -236.425023) (xy 361.678266 -236.383007) (xy 361.714989 -236.346284) (xy 361.757005 -236.315758)
			(xy 361.803279 -236.29218) (xy 361.852672 -236.276132) (xy 361.903967 -236.268007) (xy 361.955901 -236.268007)
			(xy 362.007196 -236.276132) (xy 362.056589 -236.29218) (xy 362.102863 -236.315758) (xy 362.144879 -236.346284)
			(xy 362.181602 -236.383007) (xy 362.212128 -236.425023) (xy 362.235706 -236.471297) (xy 362.251754 -236.52069)
			(xy 362.259879 -236.571985) (xy 362.260388 -236.597952) (xy 362.259879 -236.623919) (xy 362.251754 -236.675214)
			(xy 362.235706 -236.724607) (xy 362.212128 -236.770881) (xy 362.181602 -236.812897) (xy 362.144879 -236.84962)
			(xy 362.102863 -236.880146) (xy 362.056589 -236.903724) (xy 362.007196 -236.919772) (xy 361.955901 -236.927897)
			(xy 361.903967 -236.927897) (xy 361.852672 -236.919772) (xy 361.803279 -236.903724) (xy 361.757005 -236.880146)
			(xy 361.714989 -236.84962) (xy 361.678266 -236.812897) (xy 361.64774 -236.770881) (xy 361.624162 -236.724607)
			(xy 361.608114 -236.675214) (xy 361.599989 -236.623919) (xy 361.319825 -236.623919) (xy 361.3117 -236.675214)
			(xy 361.295652 -236.724607) (xy 361.272074 -236.770881) (xy 361.241548 -236.812897) (xy 361.204825 -236.84962)
			(xy 361.162809 -236.880146) (xy 361.116535 -236.903724) (xy 361.067142 -236.919772) (xy 361.015847 -236.927897)
			(xy 360.963913 -236.927897) (xy 360.912618 -236.919772) (xy 360.863225 -236.903724) (xy 360.816951 -236.880146)
			(xy 360.774935 -236.84962) (xy 360.738212 -236.812897) (xy 360.707686 -236.770881) (xy 360.684108 -236.724607)
			(xy 360.66806 -236.675214) (xy 360.659935 -236.623919) (xy 360.380025 -236.623919) (xy 360.3719 -236.675214)
			(xy 360.355852 -236.724607) (xy 360.332274 -236.770881) (xy 360.301748 -236.812897) (xy 360.265025 -236.84962)
			(xy 360.223009 -236.880146) (xy 360.176735 -236.903724) (xy 360.127342 -236.919772) (xy 360.076047 -236.927897)
			(xy 360.024113 -236.927897) (xy 359.972818 -236.919772) (xy 359.923425 -236.903724) (xy 359.877151 -236.880146)
			(xy 359.835135 -236.84962) (xy 359.798412 -236.812897) (xy 359.767886 -236.770881) (xy 359.744308 -236.724607)
			(xy 359.72826 -236.675214) (xy 359.720135 -236.623919) (xy 359.440225 -236.623919) (xy 359.4321 -236.675214)
			(xy 359.416052 -236.724607) (xy 359.392474 -236.770881) (xy 359.361948 -236.812897) (xy 359.325225 -236.84962)
			(xy 359.283209 -236.880146) (xy 359.236935 -236.903724) (xy 359.187542 -236.919772) (xy 359.136247 -236.927897)
			(xy 359.084313 -236.927897) (xy 359.033018 -236.919772) (xy 358.983625 -236.903724) (xy 358.937351 -236.880146)
			(xy 358.895335 -236.84962) (xy 358.858612 -236.812897) (xy 358.828086 -236.770881) (xy 358.804508 -236.724607)
			(xy 358.78846 -236.675214) (xy 358.780335 -236.623919) (xy 358.500679 -236.623919) (xy 358.492554 -236.675214)
			(xy 358.476506 -236.724607) (xy 358.452928 -236.770881) (xy 358.422402 -236.812897) (xy 358.385679 -236.84962)
			(xy 358.343663 -236.880146) (xy 358.297389 -236.903724) (xy 358.247996 -236.919772) (xy 358.196701 -236.927897)
			(xy 358.144767 -236.927897) (xy 358.093472 -236.919772) (xy 358.044079 -236.903724) (xy 357.997805 -236.880146)
			(xy 357.955789 -236.84962) (xy 357.919066 -236.812897) (xy 357.88854 -236.770881) (xy 357.864962 -236.724607)
			(xy 357.848914 -236.675214) (xy 357.840789 -236.623919) (xy 357.560625 -236.623919) (xy 357.5525 -236.675214)
			(xy 357.536452 -236.724607) (xy 357.512874 -236.770881) (xy 357.482348 -236.812897) (xy 357.445625 -236.84962)
			(xy 357.403609 -236.880146) (xy 357.357335 -236.903724) (xy 357.307942 -236.919772) (xy 357.256647 -236.927897)
			(xy 357.204713 -236.927897) (xy 357.153418 -236.919772) (xy 357.104025 -236.903724) (xy 357.057751 -236.880146)
			(xy 357.015735 -236.84962) (xy 356.979012 -236.812897) (xy 356.948486 -236.770881) (xy 356.924908 -236.724607)
			(xy 356.90886 -236.675214) (xy 356.900735 -236.623919) (xy 353.018344 -236.623919) (xy 353.018344 -237.437481)
			(xy 357.370889 -237.437481) (xy 357.370889 -237.385547) (xy 357.379014 -237.334252) (xy 357.395062 -237.284859)
			(xy 357.41864 -237.238585) (xy 357.449166 -237.196569) (xy 357.485889 -237.159846) (xy 357.527905 -237.12932)
			(xy 357.574179 -237.105742) (xy 357.623572 -237.089694) (xy 357.674867 -237.081569) (xy 357.726801 -237.081569)
			(xy 357.778096 -237.089694) (xy 357.827489 -237.105742) (xy 357.873763 -237.12932) (xy 357.915779 -237.159846)
			(xy 357.952502 -237.196569) (xy 357.983028 -237.238585) (xy 358.006606 -237.284859) (xy 358.022654 -237.334252)
			(xy 358.030779 -237.385547) (xy 358.031288 -237.411514) (xy 358.030779 -237.437481) (xy 358.310689 -237.437481)
			(xy 358.310689 -237.385547) (xy 358.318814 -237.334252) (xy 358.334862 -237.284859) (xy 358.35844 -237.238585)
			(xy 358.388966 -237.196569) (xy 358.425689 -237.159846) (xy 358.467705 -237.12932) (xy 358.513979 -237.105742)
			(xy 358.563372 -237.089694) (xy 358.614667 -237.081569) (xy 358.666601 -237.081569) (xy 358.717896 -237.089694)
			(xy 358.767289 -237.105742) (xy 358.813563 -237.12932) (xy 358.855579 -237.159846) (xy 358.892302 -237.196569)
			(xy 358.922828 -237.238585) (xy 358.946406 -237.284859) (xy 358.962454 -237.334252) (xy 358.970579 -237.385547)
			(xy 358.971088 -237.411514) (xy 358.970579 -237.437481) (xy 359.250489 -237.437481) (xy 359.250489 -237.385547)
			(xy 359.258614 -237.334252) (xy 359.274662 -237.284859) (xy 359.29824 -237.238585) (xy 359.328766 -237.196569)
			(xy 359.365489 -237.159846) (xy 359.407505 -237.12932) (xy 359.453779 -237.105742) (xy 359.503172 -237.089694)
			(xy 359.554467 -237.081569) (xy 359.606401 -237.081569) (xy 359.657696 -237.089694) (xy 359.707089 -237.105742)
			(xy 359.753363 -237.12932) (xy 359.795379 -237.159846) (xy 359.832102 -237.196569) (xy 359.862628 -237.238585)
			(xy 359.886206 -237.284859) (xy 359.902254 -237.334252) (xy 359.910379 -237.385547) (xy 359.910888 -237.411514)
			(xy 359.910379 -237.437481) (xy 360.190289 -237.437481) (xy 360.190289 -237.385547) (xy 360.198414 -237.334252)
			(xy 360.214462 -237.284859) (xy 360.23804 -237.238585) (xy 360.268566 -237.196569) (xy 360.305289 -237.159846)
			(xy 360.347305 -237.12932) (xy 360.393579 -237.105742) (xy 360.442972 -237.089694) (xy 360.494267 -237.081569)
			(xy 360.546201 -237.081569) (xy 360.597496 -237.089694) (xy 360.646889 -237.105742) (xy 360.693163 -237.12932)
			(xy 360.735179 -237.159846) (xy 360.771902 -237.196569) (xy 360.802428 -237.238585) (xy 360.826006 -237.284859)
			(xy 360.842054 -237.334252) (xy 360.850179 -237.385547) (xy 360.850688 -237.411514) (xy 360.850179 -237.437481)
			(xy 361.130089 -237.437481) (xy 361.130089 -237.385547) (xy 361.138214 -237.334252) (xy 361.154262 -237.284859)
			(xy 361.17784 -237.238585) (xy 361.208366 -237.196569) (xy 361.245089 -237.159846) (xy 361.287105 -237.12932)
			(xy 361.333379 -237.105742) (xy 361.382772 -237.089694) (xy 361.434067 -237.081569) (xy 361.486001 -237.081569)
			(xy 361.537296 -237.089694) (xy 361.586689 -237.105742) (xy 361.632963 -237.12932) (xy 361.660232 -237.149132)
			(xy 362.951522 -237.149132) (xy 362.951964 -237.12458) (xy 362.959206 -237.076014) (xy 362.97355 -237.029052)
			(xy 362.994681 -236.984729) (xy 363.022134 -236.944017) (xy 363.03839 -236.925612) (xy 363.048161 -236.914098)
			(xy 363.061176 -236.886869) (xy 363.06565 -236.857024) (xy 363.06119 -236.827176) (xy 363.048188 -236.799941)
			(xy 363.03839 -236.788452) (xy 363.022132 -236.770047) (xy 362.994664 -236.729343) (xy 362.973526 -236.68502)
			(xy 362.959183 -236.638055) (xy 362.951952 -236.589485) (xy 362.951522 -236.564932) (xy 362.952031 -236.538965)
			(xy 362.960156 -236.48767) (xy 362.976204 -236.438277) (xy 362.999782 -236.392003) (xy 363.030308 -236.349987)
			(xy 363.067031 -236.313264) (xy 363.109047 -236.282738) (xy 363.155321 -236.25916) (xy 363.204714 -236.243112)
			(xy 363.256009 -236.234987) (xy 363.307943 -236.234987) (xy 363.359238 -236.243112) (xy 363.408631 -236.25916)
			(xy 363.444951 -236.277666) (xy 368.586279 -236.277666) (xy 368.586279 -236.225734) (xy 368.594403 -236.174443)
			(xy 368.61045 -236.125053) (xy 368.634027 -236.078782) (xy 368.664551 -236.036769) (xy 368.701272 -236.000049)
			(xy 368.743286 -235.969525) (xy 368.789557 -235.945949) (xy 368.838947 -235.929902) (xy 368.890238 -235.921778)
			(xy 368.916204 -235.921296) (xy 368.941974 -235.921745) (xy 368.992892 -235.929719) (xy 369.041953 -235.945504)
			(xy 369.087968 -235.968717) (xy 369.12982 -235.998795) (xy 369.166492 -236.035008) (xy 369.197096 -236.076477)
			(xy 369.220888 -236.122195) (xy 369.23729 -236.171054) (xy 369.242086 -236.196378) (xy 369.244862 -236.210088)
			(xy 369.256877 -236.235337) (xy 369.275298 -236.256375) (xy 369.29874 -236.27162) (xy 369.325441 -236.279926)
			(xy 369.353393 -236.280668) (xy 369.367054 -236.277658) (xy 369.387099 -236.272893) (xy 369.427986 -236.267797)
			(xy 369.448588 -236.267498) (xy 369.474554 -236.268076) (xy 369.525847 -236.276198) (xy 369.575238 -236.292245)
			(xy 369.621511 -236.31582) (xy 369.663526 -236.346344) (xy 369.700248 -236.383065) (xy 369.730774 -236.425079)
			(xy 369.754351 -236.471351) (xy 369.770399 -236.520741) (xy 369.778523 -236.572034) (xy 369.778523 -236.623919)
			(xy 370.057935 -236.623919) (xy 370.057935 -236.571985) (xy 370.06606 -236.52069) (xy 370.082108 -236.471297)
			(xy 370.105686 -236.425023) (xy 370.136212 -236.383007) (xy 370.172935 -236.346284) (xy 370.214951 -236.315758)
			(xy 370.261225 -236.29218) (xy 370.310618 -236.276132) (xy 370.361913 -236.268007) (xy 370.413847 -236.268007)
			(xy 370.465142 -236.276132) (xy 370.514535 -236.29218) (xy 370.560809 -236.315758) (xy 370.602825 -236.346284)
			(xy 370.639548 -236.383007) (xy 370.670074 -236.425023) (xy 370.693652 -236.471297) (xy 370.7097 -236.52069)
			(xy 370.717825 -236.571985) (xy 370.718334 -236.597952) (xy 370.717825 -236.623919) (xy 370.997735 -236.623919)
			(xy 370.997735 -236.571985) (xy 371.00586 -236.52069) (xy 371.021908 -236.471297) (xy 371.045486 -236.425023)
			(xy 371.076012 -236.383007) (xy 371.112735 -236.346284) (xy 371.154751 -236.315758) (xy 371.201025 -236.29218)
			(xy 371.250418 -236.276132) (xy 371.301713 -236.268007) (xy 371.353647 -236.268007) (xy 371.404942 -236.276132)
			(xy 371.454335 -236.29218) (xy 371.500609 -236.315758) (xy 371.542625 -236.346284) (xy 371.579348 -236.383007)
			(xy 371.609874 -236.425023) (xy 371.633452 -236.471297) (xy 371.6495 -236.52069) (xy 371.657625 -236.571985)
			(xy 371.658134 -236.597952) (xy 371.657625 -236.623919) (xy 371.937535 -236.623919) (xy 371.937535 -236.571985)
			(xy 371.94566 -236.52069) (xy 371.961708 -236.471297) (xy 371.985286 -236.425023) (xy 372.015812 -236.383007)
			(xy 372.052535 -236.346284) (xy 372.094551 -236.315758) (xy 372.140825 -236.29218) (xy 372.190218 -236.276132)
			(xy 372.241513 -236.268007) (xy 372.293447 -236.268007) (xy 372.344742 -236.276132) (xy 372.394135 -236.29218)
			(xy 372.440409 -236.315758) (xy 372.482425 -236.346284) (xy 372.519148 -236.383007) (xy 372.549674 -236.425023)
			(xy 372.573252 -236.471297) (xy 372.5893 -236.52069) (xy 372.597425 -236.571985) (xy 372.597934 -236.597952)
			(xy 372.597425 -236.623919) (xy 372.877335 -236.623919) (xy 372.877335 -236.571985) (xy 372.88546 -236.52069)
			(xy 372.901508 -236.471297) (xy 372.925086 -236.425023) (xy 372.955612 -236.383007) (xy 372.992335 -236.346284)
			(xy 373.034351 -236.315758) (xy 373.080625 -236.29218) (xy 373.130018 -236.276132) (xy 373.181313 -236.268007)
			(xy 373.233247 -236.268007) (xy 373.284542 -236.276132) (xy 373.333935 -236.29218) (xy 373.380209 -236.315758)
			(xy 373.422225 -236.346284) (xy 373.458948 -236.383007) (xy 373.489474 -236.425023) (xy 373.513052 -236.471297)
			(xy 373.5291 -236.52069) (xy 373.537225 -236.571985) (xy 373.537734 -236.597952) (xy 373.537225 -236.623919)
			(xy 373.5291 -236.675214) (xy 373.513052 -236.724607) (xy 373.489474 -236.770881) (xy 373.458948 -236.812897)
			(xy 373.422225 -236.84962) (xy 373.380209 -236.880146) (xy 373.333935 -236.903724) (xy 373.284542 -236.919772)
			(xy 373.233247 -236.927897) (xy 373.181313 -236.927897) (xy 373.130018 -236.919772) (xy 373.080625 -236.903724)
			(xy 373.034351 -236.880146) (xy 372.992335 -236.84962) (xy 372.955612 -236.812897) (xy 372.925086 -236.770881)
			(xy 372.901508 -236.724607) (xy 372.88546 -236.675214) (xy 372.877335 -236.623919) (xy 372.597425 -236.623919)
			(xy 372.5893 -236.675214) (xy 372.573252 -236.724607) (xy 372.549674 -236.770881) (xy 372.519148 -236.812897)
			(xy 372.482425 -236.84962) (xy 372.440409 -236.880146) (xy 372.394135 -236.903724) (xy 372.344742 -236.919772)
			(xy 372.293447 -236.927897) (xy 372.241513 -236.927897) (xy 372.190218 -236.919772) (xy 372.140825 -236.903724)
			(xy 372.094551 -236.880146) (xy 372.052535 -236.84962) (xy 372.015812 -236.812897) (xy 371.985286 -236.770881)
			(xy 371.961708 -236.724607) (xy 371.94566 -236.675214) (xy 371.937535 -236.623919) (xy 371.657625 -236.623919)
			(xy 371.6495 -236.675214) (xy 371.633452 -236.724607) (xy 371.609874 -236.770881) (xy 371.579348 -236.812897)
			(xy 371.542625 -236.84962) (xy 371.500609 -236.880146) (xy 371.454335 -236.903724) (xy 371.404942 -236.919772)
			(xy 371.353647 -236.927897) (xy 371.301713 -236.927897) (xy 371.250418 -236.919772) (xy 371.201025 -236.903724)
			(xy 371.154751 -236.880146) (xy 371.112735 -236.84962) (xy 371.076012 -236.812897) (xy 371.045486 -236.770881)
			(xy 371.021908 -236.724607) (xy 371.00586 -236.675214) (xy 370.997735 -236.623919) (xy 370.717825 -236.623919)
			(xy 370.7097 -236.675214) (xy 370.693652 -236.724607) (xy 370.670074 -236.770881) (xy 370.639548 -236.812897)
			(xy 370.602825 -236.84962) (xy 370.560809 -236.880146) (xy 370.514535 -236.903724) (xy 370.465142 -236.919772)
			(xy 370.413847 -236.927897) (xy 370.361913 -236.927897) (xy 370.310618 -236.919772) (xy 370.261225 -236.903724)
			(xy 370.214951 -236.880146) (xy 370.172935 -236.84962) (xy 370.136212 -236.812897) (xy 370.105686 -236.770881)
			(xy 370.082108 -236.724607) (xy 370.06606 -236.675214) (xy 370.057935 -236.623919) (xy 369.778523 -236.623919)
			(xy 369.778523 -236.623966) (xy 369.770399 -236.675259) (xy 369.754351 -236.724649) (xy 369.730774 -236.770921)
			(xy 369.700248 -236.812935) (xy 369.663526 -236.849656) (xy 369.621511 -236.88018) (xy 369.575238 -236.903755)
			(xy 369.525847 -236.919802) (xy 369.474554 -236.927924) (xy 369.448588 -236.928406) (xy 369.422818 -236.927963)
			(xy 369.3719 -236.919988) (xy 369.322838 -236.904201) (xy 369.276823 -236.880987) (xy 369.234972 -236.850909)
			(xy 369.1983 -236.814695) (xy 369.167696 -236.773226) (xy 369.143904 -236.727507) (xy 369.127502 -236.678648)
			(xy 369.122706 -236.653324) (xy 369.119938 -236.639612) (xy 369.107922 -236.614361) (xy 369.0895 -236.593323)
			(xy 369.066056 -236.578078) (xy 369.039353 -236.569773) (xy 369.011399 -236.569032) (xy 368.997738 -236.572044)
			(xy 368.977693 -236.576811) (xy 368.936806 -236.581905) (xy 368.916204 -236.582204) (xy 368.890238 -236.581622)
			(xy 368.838947 -236.573498) (xy 368.789557 -236.557451) (xy 368.743286 -236.533875) (xy 368.701272 -236.503351)
			(xy 368.664551 -236.466631) (xy 368.634027 -236.424618) (xy 368.61045 -236.378347) (xy 368.594403 -236.328957)
			(xy 368.586279 -236.277666) (xy 363.444951 -236.277666) (xy 363.454905 -236.282738) (xy 363.496921 -236.313264)
			(xy 363.533644 -236.349987) (xy 363.56417 -236.392003) (xy 363.587748 -236.438277) (xy 363.603796 -236.48767)
			(xy 363.611921 -236.538965) (xy 363.61243 -236.564932) (xy 363.611979 -236.589484) (xy 363.604741 -236.63805)
			(xy 363.5904 -236.685012) (xy 363.56927 -236.729336) (xy 363.541818 -236.770048) (xy 363.525562 -236.788452)
			(xy 363.515724 -236.799915) (xy 363.502709 -236.827161) (xy 363.498245 -236.857024) (xy 363.502723 -236.886884)
			(xy 363.515751 -236.914124) (xy 363.525562 -236.925612) (xy 363.541842 -236.943998) (xy 363.569309 -236.984707)
			(xy 363.590444 -237.029035) (xy 363.604781 -237.076003) (xy 363.612005 -237.124577) (xy 363.61243 -237.149132)
			(xy 363.611921 -237.175099) (xy 363.603796 -237.226394) (xy 363.587748 -237.275787) (xy 363.56417 -237.322061)
			(xy 363.533644 -237.364077) (xy 363.496921 -237.4008) (xy 363.454905 -237.431326) (xy 363.425876 -237.446117)
			(xy 368.586259 -237.446117) (xy 368.586259 -237.394183) (xy 368.594384 -237.342888) (xy 368.610432 -237.293495)
			(xy 368.63401 -237.247221) (xy 368.664536 -237.205205) (xy 368.701259 -237.168482) (xy 368.743275 -237.137956)
			(xy 368.789549 -237.114378) (xy 368.838942 -237.09833) (xy 368.890237 -237.090205) (xy 368.942171 -237.090205)
			(xy 368.993466 -237.09833) (xy 369.042859 -237.114378) (xy 369.089133 -237.137956) (xy 369.131149 -237.168482)
			(xy 369.167872 -237.205205) (xy 369.198398 -237.247221) (xy 369.221976 -237.293495) (xy 369.238024 -237.342888)
			(xy 369.246149 -237.394183) (xy 369.246658 -237.42015) (xy 369.246318 -237.437481) (xy 369.588289 -237.437481)
			(xy 369.588289 -237.385547) (xy 369.596414 -237.334252) (xy 369.612462 -237.284859) (xy 369.63604 -237.238585)
			(xy 369.666566 -237.196569) (xy 369.703289 -237.159846) (xy 369.745305 -237.12932) (xy 369.791579 -237.105742)
			(xy 369.840972 -237.089694) (xy 369.892267 -237.081569) (xy 369.944201 -237.081569) (xy 369.995496 -237.089694)
			(xy 370.044889 -237.105742) (xy 370.091163 -237.12932) (xy 370.133179 -237.159846) (xy 370.169902 -237.196569)
			(xy 370.200428 -237.238585) (xy 370.224006 -237.284859) (xy 370.240054 -237.334252) (xy 370.248179 -237.385547)
			(xy 370.248688 -237.411514) (xy 370.248179 -237.437481) (xy 370.528089 -237.437481) (xy 370.528089 -237.385547)
			(xy 370.536214 -237.334252) (xy 370.552262 -237.284859) (xy 370.57584 -237.238585) (xy 370.606366 -237.196569)
			(xy 370.643089 -237.159846) (xy 370.685105 -237.12932) (xy 370.731379 -237.105742) (xy 370.780772 -237.089694)
			(xy 370.832067 -237.081569) (xy 370.884001 -237.081569) (xy 370.935296 -237.089694) (xy 370.984689 -237.105742)
			(xy 371.030963 -237.12932) (xy 371.072979 -237.159846) (xy 371.109702 -237.196569) (xy 371.140228 -237.238585)
			(xy 371.163806 -237.284859) (xy 371.179854 -237.334252) (xy 371.187979 -237.385547) (xy 371.188488 -237.411514)
			(xy 371.187979 -237.437481) (xy 371.467889 -237.437481) (xy 371.467889 -237.385547) (xy 371.476014 -237.334252)
			(xy 371.492062 -237.284859) (xy 371.51564 -237.238585) (xy 371.546166 -237.196569) (xy 371.582889 -237.159846)
			(xy 371.624905 -237.12932) (xy 371.671179 -237.105742) (xy 371.720572 -237.089694) (xy 371.771867 -237.081569)
			(xy 371.823801 -237.081569) (xy 371.875096 -237.089694) (xy 371.924489 -237.105742) (xy 371.970763 -237.12932)
			(xy 372.012779 -237.159846) (xy 372.049502 -237.196569) (xy 372.080028 -237.238585) (xy 372.103606 -237.284859)
			(xy 372.119654 -237.334252) (xy 372.127779 -237.385547) (xy 372.128288 -237.411514) (xy 372.127779 -237.437481)
			(xy 372.407689 -237.437481) (xy 372.407689 -237.385547) (xy 372.415814 -237.334252) (xy 372.431862 -237.284859)
			(xy 372.45544 -237.238585) (xy 372.485966 -237.196569) (xy 372.522689 -237.159846) (xy 372.564705 -237.12932)
			(xy 372.610979 -237.105742) (xy 372.660372 -237.089694) (xy 372.711667 -237.081569) (xy 372.763601 -237.081569)
			(xy 372.814896 -237.089694) (xy 372.864289 -237.105742) (xy 372.910563 -237.12932) (xy 372.952579 -237.159846)
			(xy 372.989302 -237.196569) (xy 373.019828 -237.238585) (xy 373.043406 -237.284859) (xy 373.059454 -237.334252)
			(xy 373.067579 -237.385547) (xy 373.068088 -237.411514) (xy 373.067579 -237.437481) (xy 373.059454 -237.488776)
			(xy 373.043406 -237.538169) (xy 373.019828 -237.584443) (xy 372.989302 -237.626459) (xy 372.952579 -237.663182)
			(xy 372.910563 -237.693708) (xy 372.864289 -237.717286) (xy 372.814896 -237.733334) (xy 372.763601 -237.741459)
			(xy 372.711667 -237.741459) (xy 372.660372 -237.733334) (xy 372.610979 -237.717286) (xy 372.564705 -237.693708)
			(xy 372.522689 -237.663182) (xy 372.485966 -237.626459) (xy 372.45544 -237.584443) (xy 372.431862 -237.538169)
			(xy 372.415814 -237.488776) (xy 372.407689 -237.437481) (xy 372.127779 -237.437481) (xy 372.119654 -237.488776)
			(xy 372.103606 -237.538169) (xy 372.080028 -237.584443) (xy 372.049502 -237.626459) (xy 372.012779 -237.663182)
			(xy 371.970763 -237.693708) (xy 371.924489 -237.717286) (xy 371.875096 -237.733334) (xy 371.823801 -237.741459)
			(xy 371.771867 -237.741459) (xy 371.720572 -237.733334) (xy 371.671179 -237.717286) (xy 371.624905 -237.693708)
			(xy 371.582889 -237.663182) (xy 371.546166 -237.626459) (xy 371.51564 -237.584443) (xy 371.492062 -237.538169)
			(xy 371.476014 -237.488776) (xy 371.467889 -237.437481) (xy 371.187979 -237.437481) (xy 371.179854 -237.488776)
			(xy 371.163806 -237.538169) (xy 371.140228 -237.584443) (xy 371.109702 -237.626459) (xy 371.072979 -237.663182)
			(xy 371.030963 -237.693708) (xy 370.984689 -237.717286) (xy 370.935296 -237.733334) (xy 370.884001 -237.741459)
			(xy 370.832067 -237.741459) (xy 370.780772 -237.733334) (xy 370.731379 -237.717286) (xy 370.685105 -237.693708)
			(xy 370.643089 -237.663182) (xy 370.606366 -237.626459) (xy 370.57584 -237.584443) (xy 370.552262 -237.538169)
			(xy 370.536214 -237.488776) (xy 370.528089 -237.437481) (xy 370.248179 -237.437481) (xy 370.240054 -237.488776)
			(xy 370.224006 -237.538169) (xy 370.200428 -237.584443) (xy 370.169902 -237.626459) (xy 370.133179 -237.663182)
			(xy 370.091163 -237.693708) (xy 370.044889 -237.717286) (xy 369.995496 -237.733334) (xy 369.944201 -237.741459)
			(xy 369.892267 -237.741459) (xy 369.840972 -237.733334) (xy 369.791579 -237.717286) (xy 369.745305 -237.693708)
			(xy 369.703289 -237.663182) (xy 369.666566 -237.626459) (xy 369.63604 -237.584443) (xy 369.612462 -237.538169)
			(xy 369.596414 -237.488776) (xy 369.588289 -237.437481) (xy 369.246318 -237.437481) (xy 369.246149 -237.446117)
			(xy 369.238024 -237.497412) (xy 369.221976 -237.546805) (xy 369.198398 -237.593079) (xy 369.167872 -237.635095)
			(xy 369.131149 -237.671818) (xy 369.089133 -237.702344) (xy 369.042859 -237.725922) (xy 368.993466 -237.74197)
			(xy 368.942171 -237.750095) (xy 368.890237 -237.750095) (xy 368.838942 -237.74197) (xy 368.789549 -237.725922)
			(xy 368.743275 -237.702344) (xy 368.701259 -237.671818) (xy 368.664536 -237.635095) (xy 368.63401 -237.593079)
			(xy 368.610432 -237.546805) (xy 368.594384 -237.497412) (xy 368.586259 -237.446117) (xy 363.425876 -237.446117)
			(xy 363.408631 -237.454904) (xy 363.359238 -237.470952) (xy 363.307943 -237.479077) (xy 363.256009 -237.479077)
			(xy 363.204714 -237.470952) (xy 363.155321 -237.454904) (xy 363.109047 -237.431326) (xy 363.067031 -237.4008)
			(xy 363.030308 -237.364077) (xy 362.999782 -237.322061) (xy 362.976204 -237.275787) (xy 362.960156 -237.226394)
			(xy 362.952031 -237.175099) (xy 362.951522 -237.149132) (xy 361.660232 -237.149132) (xy 361.674979 -237.159846)
			(xy 361.711702 -237.196569) (xy 361.742228 -237.238585) (xy 361.765806 -237.284859) (xy 361.781854 -237.334252)
			(xy 361.789979 -237.385547) (xy 361.790488 -237.411514) (xy 361.789979 -237.437481) (xy 361.781854 -237.488776)
			(xy 361.765806 -237.538169) (xy 361.742228 -237.584443) (xy 361.711702 -237.626459) (xy 361.674979 -237.663182)
			(xy 361.632963 -237.693708) (xy 361.586689 -237.717286) (xy 361.537296 -237.733334) (xy 361.486001 -237.741459)
			(xy 361.434067 -237.741459) (xy 361.382772 -237.733334) (xy 361.333379 -237.717286) (xy 361.287105 -237.693708)
			(xy 361.245089 -237.663182) (xy 361.208366 -237.626459) (xy 361.17784 -237.584443) (xy 361.154262 -237.538169)
			(xy 361.138214 -237.488776) (xy 361.130089 -237.437481) (xy 360.850179 -237.437481) (xy 360.842054 -237.488776)
			(xy 360.826006 -237.538169) (xy 360.802428 -237.584443) (xy 360.771902 -237.626459) (xy 360.735179 -237.663182)
			(xy 360.693163 -237.693708) (xy 360.646889 -237.717286) (xy 360.597496 -237.733334) (xy 360.546201 -237.741459)
			(xy 360.494267 -237.741459) (xy 360.442972 -237.733334) (xy 360.393579 -237.717286) (xy 360.347305 -237.693708)
			(xy 360.305289 -237.663182) (xy 360.268566 -237.626459) (xy 360.23804 -237.584443) (xy 360.214462 -237.538169)
			(xy 360.198414 -237.488776) (xy 360.190289 -237.437481) (xy 359.910379 -237.437481) (xy 359.902254 -237.488776)
			(xy 359.886206 -237.538169) (xy 359.862628 -237.584443) (xy 359.832102 -237.626459) (xy 359.795379 -237.663182)
			(xy 359.753363 -237.693708) (xy 359.707089 -237.717286) (xy 359.657696 -237.733334) (xy 359.606401 -237.741459)
			(xy 359.554467 -237.741459) (xy 359.503172 -237.733334) (xy 359.453779 -237.717286) (xy 359.407505 -237.693708)
			(xy 359.365489 -237.663182) (xy 359.328766 -237.626459) (xy 359.29824 -237.584443) (xy 359.274662 -237.538169)
			(xy 359.258614 -237.488776) (xy 359.250489 -237.437481) (xy 358.970579 -237.437481) (xy 358.962454 -237.488776)
			(xy 358.946406 -237.538169) (xy 358.922828 -237.584443) (xy 358.892302 -237.626459) (xy 358.855579 -237.663182)
			(xy 358.813563 -237.693708) (xy 358.767289 -237.717286) (xy 358.717896 -237.733334) (xy 358.666601 -237.741459)
			(xy 358.614667 -237.741459) (xy 358.563372 -237.733334) (xy 358.513979 -237.717286) (xy 358.467705 -237.693708)
			(xy 358.425689 -237.663182) (xy 358.388966 -237.626459) (xy 358.35844 -237.584443) (xy 358.334862 -237.538169)
			(xy 358.318814 -237.488776) (xy 358.310689 -237.437481) (xy 358.030779 -237.437481) (xy 358.022654 -237.488776)
			(xy 358.006606 -237.538169) (xy 357.983028 -237.584443) (xy 357.952502 -237.626459) (xy 357.915779 -237.663182)
			(xy 357.873763 -237.693708) (xy 357.827489 -237.717286) (xy 357.778096 -237.733334) (xy 357.726801 -237.741459)
			(xy 357.674867 -237.741459) (xy 357.623572 -237.733334) (xy 357.574179 -237.717286) (xy 357.527905 -237.693708)
			(xy 357.485889 -237.663182) (xy 357.449166 -237.626459) (xy 357.41864 -237.584443) (xy 357.395062 -237.538169)
			(xy 357.379014 -237.488776) (xy 357.370889 -237.437481) (xy 353.018344 -237.437481) (xy 353.018344 -237.483396)
			(xy 353.492054 -237.957106)
		)
		(stroke
			(width 0)
			(type solid)
		)
		(fill yes)
		(layer "In6.Cu")
		(net "PVNN_MAIN_CPU0")
	)
	(gr_poly
		(pts
			(xy 188.85535 -366.394238) (xy 188.868812 -366.385856) (xy 190.69812 -364.556548) (xy 190.69812 -359.233978)
			(xy 190.697544 -359.219009) (xy 190.688775 -359.190379) (xy 190.672085 -359.16552) (xy 190.648906 -359.146565)
			(xy 190.621228 -359.135142) (xy 190.591427 -359.132231) (xy 190.562062 -359.138083) (xy 190.535654 -359.152194)
			(xy 190.524638 -359.16235) (xy 184.320688 -365.366046) (xy 184.314846 -365.371888) (xy 184.259474 -365.42726)
			(xy 184.187592 -365.457232) (xy 184.187084 -365.457486) (xy 184.184036 -365.458756) (xy 184.180734 -365.460026)
			(xy 184.177686 -365.461296) (xy 180.179472 -367.117376) (xy 180.17109 -367.120678) (xy 180.16855 -367.121948)
			(xy 180.168042 -367.121948) (xy 180.098446 -367.150904) (xy 161.507932 -367.150904) (xy 161.385504 -367.028476)
			(xy 161.3789 -367.021872) (xy 157.958282 -363.601508) (xy 133.302756 -363.601508) (xy 131.312412 -365.591852)
			(xy 131.312412 -365.747808) (xy 132.860799 -365.747808) (xy 132.864835 -365.664361) (xy 132.876907 -365.581693)
			(xy 132.8969 -365.500576) (xy 132.924629 -365.421767) (xy 132.959835 -365.346002) (xy 133.002189 -365.273989)
			(xy 133.051295 -365.2064) (xy 133.106696 -365.143866) (xy 133.167873 -365.086971) (xy 133.234256 -365.036245)
			(xy 133.305224 -364.992164) (xy 133.380116 -364.955138) (xy 133.458232 -364.925512) (xy 133.538842 -364.903564)
			(xy 133.621194 -364.889499) (xy 133.70452 -364.883447) (xy 133.78804 -364.885466) (xy 133.870976 -364.895536)
			(xy 133.952552 -364.913564) (xy 134.032008 -364.939381) (xy 134.108601 -364.972746) (xy 134.181617 -365.013347)
			(xy 134.250373 -365.060806) (xy 134.314227 -365.114679) (xy 134.372584 -365.174464) (xy 134.424899 -365.239601)
			(xy 134.470682 -365.309484) (xy 134.509507 -365.383459) (xy 134.541012 -365.460836) (xy 134.564901 -365.540893)
			(xy 134.580952 -365.622881) (xy 134.589015 -365.706036) (xy 134.58952 -365.747808) (xy 134.589015 -365.78958)
			(xy 134.580952 -365.872735) (xy 134.564901 -365.954723) (xy 134.541012 -366.03478) (xy 134.528065 -366.066578)
			(xy 138.60324 -366.066578) (xy 138.607206 -365.982047) (xy 138.619071 -365.89826) (xy 138.638729 -365.815951)
			(xy 138.666009 -365.735845) (xy 138.70067 -365.658646) (xy 138.742408 -365.585031) (xy 138.790855 -365.515648)
			(xy 138.845587 -365.451107) (xy 138.906123 -365.391975) (xy 138.971929 -365.338771) (xy 139.042429 -365.291963)
			(xy 139.117001 -365.251962) (xy 139.194992 -365.21912) (xy 139.275716 -365.193726) (xy 139.358463 -365.176003)
			(xy 139.442505 -365.166105) (xy 139.527106 -365.164122) (xy 139.61152 -365.170069) (xy 139.695007 -365.183894)
			(xy 139.776832 -365.205477) (xy 139.856276 -365.234627) (xy 139.932642 -365.271088) (xy 140.005258 -365.31454)
			(xy 140.073486 -365.364601) (xy 140.136726 -365.420831) (xy 140.194423 -365.482736) (xy 140.24607 -365.549772)
			(xy 140.291212 -365.621349) (xy 140.329454 -365.696839) (xy 140.360458 -365.775578) (xy 140.383953 -365.856875)
			(xy 140.399732 -365.940014) (xy 140.407656 -366.024266) (xy 140.408152 -366.066578) (xy 143.68324 -366.066578)
			(xy 143.687206 -365.982047) (xy 143.699071 -365.89826) (xy 143.718729 -365.815951) (xy 143.746009 -365.735845)
			(xy 143.78067 -365.658646) (xy 143.822408 -365.585031) (xy 143.870855 -365.515648) (xy 143.925587 -365.451107)
			(xy 143.986123 -365.391975) (xy 144.051929 -365.338771) (xy 144.122429 -365.291963) (xy 144.197001 -365.251962)
			(xy 144.274992 -365.21912) (xy 144.355716 -365.193726) (xy 144.438463 -365.176003) (xy 144.522505 -365.166105)
			(xy 144.607106 -365.164122) (xy 144.69152 -365.170069) (xy 144.775007 -365.183894) (xy 144.856832 -365.205477)
			(xy 144.936276 -365.234627) (xy 145.012642 -365.271088) (xy 145.085258 -365.31454) (xy 145.153486 -365.364601)
			(xy 145.216726 -365.420831) (xy 145.274423 -365.482736) (xy 145.32607 -365.549772) (xy 145.371212 -365.621349)
			(xy 145.409454 -365.696839) (xy 145.440458 -365.775578) (xy 145.463953 -365.856875) (xy 145.479732 -365.940014)
			(xy 145.487656 -366.024266) (xy 145.488152 -366.066578) (xy 145.487656 -366.10889) (xy 145.479732 -366.193142)
			(xy 145.463953 -366.276281) (xy 145.440458 -366.357578) (xy 145.409454 -366.436317) (xy 145.371212 -366.511807)
			(xy 145.32607 -366.583384) (xy 145.274423 -366.65042) (xy 145.216726 -366.712325) (xy 145.153486 -366.768555)
			(xy 145.085258 -366.818616) (xy 145.012642 -366.862068) (xy 144.936276 -366.898529) (xy 144.856832 -366.927679)
			(xy 144.775007 -366.949262) (xy 144.69152 -366.963087) (xy 144.607106 -366.969034) (xy 144.522505 -366.967051)
			(xy 144.438463 -366.957153) (xy 144.355716 -366.93943) (xy 144.274992 -366.914036) (xy 144.197001 -366.881194)
			(xy 144.122429 -366.841193) (xy 144.051929 -366.794385) (xy 143.986123 -366.741181) (xy 143.925587 -366.682049)
			(xy 143.870855 -366.617508) (xy 143.822408 -366.548125) (xy 143.78067 -366.47451) (xy 143.746009 -366.397311)
			(xy 143.718729 -366.317205) (xy 143.699071 -366.234896) (xy 143.687206 -366.151109) (xy 143.68324 -366.066578)
			(xy 140.408152 -366.066578) (xy 140.407656 -366.10889) (xy 140.399732 -366.193142) (xy 140.383953 -366.276281)
			(xy 140.360458 -366.357578) (xy 140.329454 -366.436317) (xy 140.291212 -366.511807) (xy 140.24607 -366.583384)
			(xy 140.194423 -366.65042) (xy 140.136726 -366.712325) (xy 140.073486 -366.768555) (xy 140.005258 -366.818616)
			(xy 139.932642 -366.862068) (xy 139.856276 -366.898529) (xy 139.776832 -366.927679) (xy 139.695007 -366.949262)
			(xy 139.61152 -366.963087) (xy 139.527106 -366.969034) (xy 139.442505 -366.967051) (xy 139.358463 -366.957153)
			(xy 139.275716 -366.93943) (xy 139.194992 -366.914036) (xy 139.117001 -366.881194) (xy 139.042429 -366.841193)
			(xy 138.971929 -366.794385) (xy 138.906123 -366.741181) (xy 138.845587 -366.682049) (xy 138.790855 -366.617508)
			(xy 138.742408 -366.548125) (xy 138.70067 -366.47451) (xy 138.666009 -366.397311) (xy 138.638729 -366.317205)
			(xy 138.619071 -366.234896) (xy 138.607206 -366.151109) (xy 138.60324 -366.066578) (xy 134.528065 -366.066578)
			(xy 134.509507 -366.112157) (xy 134.470682 -366.186132) (xy 134.424899 -366.256015) (xy 134.372584 -366.321152)
			(xy 134.314227 -366.380937) (xy 134.250373 -366.43481) (xy 134.181617 -366.482269) (xy 134.108601 -366.52287)
			(xy 134.032008 -366.556235) (xy 133.952552 -366.582052) (xy 133.870976 -366.60008) (xy 133.78804 -366.61015)
			(xy 133.70452 -366.612169) (xy 133.621194 -366.606117) (xy 133.538842 -366.592052) (xy 133.458232 -366.570104)
			(xy 133.380116 -366.540478) (xy 133.305224 -366.503452) (xy 133.234256 -366.459371) (xy 133.167873 -366.408645)
			(xy 133.106696 -366.35175) (xy 133.051295 -366.289216) (xy 133.002189 -366.221627) (xy 132.959835 -366.149614)
			(xy 132.924629 -366.073849) (xy 132.8969 -365.99504) (xy 132.876907 -365.913923) (xy 132.864835 -365.831255)
			(xy 132.860799 -365.747808) (xy 131.312412 -365.747808) (xy 131.312412 -368.20983) (xy 131.312158 -368.219228)
			(xy 131.312158 -368.290278) (xy 132.836408 -368.290278) (xy 132.836408 -368.205582) (xy 132.844459 -368.121268)
			(xy 132.860488 -368.038102) (xy 132.884349 -367.956835) (xy 132.915828 -367.878205) (xy 132.954639 -367.802924)
			(xy 133.000429 -367.731672) (xy 133.052785 -367.665096) (xy 133.111233 -367.603798) (xy 133.175243 -367.548333)
			(xy 133.244235 -367.499204) (xy 133.317585 -367.456855) (xy 133.394628 -367.421671) (xy 133.474667 -367.393969)
			(xy 133.556976 -367.374001) (xy 133.640811 -367.361948) (xy 133.725412 -367.357918) (xy 133.810013 -367.361948)
			(xy 133.893848 -367.374001) (xy 133.976157 -367.393969) (xy 134.056196 -367.421671) (xy 134.133239 -367.456855)
			(xy 134.206589 -367.499204) (xy 134.275581 -367.548333) (xy 134.339591 -367.603798) (xy 134.398039 -367.665096)
			(xy 134.450395 -367.731672) (xy 134.496185 -367.802924) (xy 134.534996 -367.878205) (xy 134.566475 -367.956835)
			(xy 134.590336 -368.038102) (xy 134.606365 -368.121268) (xy 134.608758 -368.14633) (xy 140.60246 -368.14633)
			(xy 140.606531 -368.090708) (xy 140.618657 -368.036271) (xy 140.63858 -367.98418) (xy 140.665876 -367.935545)
			(xy 140.699962 -367.891402) (xy 140.740111 -367.852693) (xy 140.785469 -367.820242) (xy 140.835069 -367.794741)
			(xy 140.887853 -367.776734) (xy 140.942696 -367.766604) (xy 140.99843 -367.764567) (xy 141.053867 -367.770667)
			(xy 141.107824 -367.784773) (xy 141.159153 -367.806585) (xy 141.206759 -367.835639) (xy 141.249627 -367.871314)
			(xy 141.286844 -367.912851) (xy 141.317617 -367.959364) (xy 141.341289 -368.009861) (xy 141.357357 -368.063268)
			(xy 141.365477 -368.118444) (xy 141.365986 -368.14633) (xy 141.365477 -368.174216) (xy 141.357357 -368.229392)
			(xy 141.341289 -368.282799) (xy 141.317617 -368.333296) (xy 141.286844 -368.379809) (xy 141.249627 -368.421346)
			(xy 141.206759 -368.457021) (xy 141.159153 -368.486075) (xy 141.107824 -368.507887) (xy 141.053867 -368.521993)
			(xy 140.99843 -368.528093) (xy 140.942696 -368.526056) (xy 140.887853 -368.515926) (xy 140.835069 -368.497919)
			(xy 140.785469 -368.472418) (xy 140.740111 -368.439967) (xy 140.699962 -368.401258) (xy 140.665876 -368.357115)
			(xy 140.63858 -368.30848) (xy 140.618657 -368.256389) (xy 140.606531 -368.201952) (xy 140.60246 -368.14633)
			(xy 134.608758 -368.14633) (xy 134.614416 -368.205582) (xy 134.61492 -368.24793) (xy 134.614416 -368.290278)
			(xy 134.606365 -368.374592) (xy 134.590336 -368.457758) (xy 134.566475 -368.539025) (xy 134.55926 -368.557048)
			(xy 167.537382 -368.557048) (xy 167.541453 -368.501426) (xy 167.553579 -368.446989) (xy 167.573502 -368.394898)
			(xy 167.600798 -368.346263) (xy 167.634884 -368.30212) (xy 167.675033 -368.263411) (xy 167.720391 -368.23096)
			(xy 167.769991 -368.205459) (xy 167.822775 -368.187452) (xy 167.877618 -368.177322) (xy 167.933352 -368.175285)
			(xy 167.988789 -368.181385) (xy 168.042746 -368.195491) (xy 168.094075 -368.217303) (xy 168.141681 -368.246357)
			(xy 168.184549 -368.282032) (xy 168.221766 -368.323569) (xy 168.252539 -368.370082) (xy 168.276211 -368.420579)
			(xy 168.292279 -368.473986) (xy 168.300399 -368.529162) (xy 168.300908 -368.557048) (xy 168.300399 -368.584934)
			(xy 168.292279 -368.64011) (xy 168.276211 -368.693517) (xy 168.252539 -368.744014) (xy 168.221766 -368.790527)
			(xy 168.184549 -368.832064) (xy 168.141681 -368.867739) (xy 168.094075 -368.896793) (xy 168.042746 -368.918605)
			(xy 167.988789 -368.932711) (xy 167.933352 -368.938811) (xy 167.877618 -368.936774) (xy 167.822775 -368.926644)
			(xy 167.769991 -368.908637) (xy 167.720391 -368.883136) (xy 167.675033 -368.850685) (xy 167.634884 -368.811976)
			(xy 167.600798 -368.767833) (xy 167.573502 -368.719198) (xy 167.553579 -368.667107) (xy 167.541453 -368.61267)
			(xy 167.537382 -368.557048) (xy 134.55926 -368.557048) (xy 134.534996 -368.617655) (xy 134.496185 -368.692936)
			(xy 134.450395 -368.764188) (xy 134.398039 -368.830764) (xy 134.339591 -368.892062) (xy 134.275581 -368.947527)
			(xy 134.206589 -368.996656) (xy 134.133239 -369.039005) (xy 134.056196 -369.074189) (xy 133.976157 -369.101891)
			(xy 133.893848 -369.121859) (xy 133.810013 -369.133912) (xy 133.725412 -369.137943) (xy 133.640811 -369.133912)
			(xy 133.556976 -369.121859) (xy 133.474667 -369.101891) (xy 133.394628 -369.074189) (xy 133.317585 -369.039005)
			(xy 133.244235 -368.996656) (xy 133.175243 -368.947527) (xy 133.111233 -368.892062) (xy 133.052785 -368.830764)
			(xy 133.000429 -368.764188) (xy 132.954639 -368.692936) (xy 132.915828 -368.617655) (xy 132.884349 -368.539025)
			(xy 132.860488 -368.457758) (xy 132.844459 -368.374592) (xy 132.836408 -368.290278) (xy 131.312158 -368.290278)
			(xy 131.312158 -368.39398) (xy 131.18973 -368.516408) (xy 131.182364 -368.523774) (xy 130.408934 -369.297204)
			(xy 130.401568 -369.30457) (xy 130.27914 -369.426998) (xy 130.104388 -369.426998) (xy 130.09499 -369.427252)
			(xy 120.619012 -369.427252) (xy 120.040908 -370.005102) (xy 120.034304 -370.011706) (xy 119.911876 -370.134134)
			(xy 119.731536 -370.134134) (xy 119.727726 -370.134388) (xy 113.049304 -370.134388) (xy 113.045494 -370.134134)
			(xy 112.865154 -370.134134) (xy 112.742726 -370.011706) (xy 112.735614 -370.004594) (xy 108.706666 -365.975646)
			(xy 108.700316 -365.969296) (xy 108.577126 -365.846106) (xy 108.577126 -365.671354) (xy 108.576872 -365.661956)
			(xy 108.576872 -363.484668) (xy 107.557316 -362.465112) (xy 106.94289 -362.465112) (xy 106.933492 -362.464858)
			(xy 106.75874 -362.464858) (xy 106.636312 -362.34243) (xy 106.6292 -362.335318) (xy 105.296716 -361.002834)
			(xy 105.290366 -360.996484) (xy 105.167176 -360.873294) (xy 105.167176 -356.963472) (xy 104.422448 -356.218998)
			(xy 104.418638 -356.215188) (xy 104.407936 -356.205154) (xy 104.382173 -356.191146) (xy 104.353491 -356.185041)
			(xy 104.324257 -356.187342) (xy 104.296883 -356.197859) (xy 104.273628 -356.215724) (xy 104.256413 -356.239464)
			(xy 104.246656 -356.267118) (xy 104.24541 -356.281736) (xy 104.243364 -356.310656) (xy 104.231625 -356.367429)
			(xy 104.211433 -356.421773) (xy 104.18325 -356.472436) (xy 104.147728 -356.518252) (xy 104.105682 -356.558166)
			(xy 104.058082 -356.59126) (xy 104.006023 -356.616772) (xy 103.950703 -356.634113) (xy 103.893397 -356.642886)
			(xy 103.86441 -356.643432) (xy 103.837158 -356.642947) (xy 103.783208 -356.635192) (xy 103.73091 -356.619838)
			(xy 103.68133 -356.597197) (xy 103.635477 -356.567732) (xy 103.594283 -356.532041) (xy 103.558589 -356.49085)
			(xy 103.529119 -356.445) (xy 103.506474 -356.395422) (xy 103.491116 -356.343126) (xy 103.483356 -356.289176)
			(xy 103.482902 -356.261924) (xy 103.48344 -356.232936) (xy 103.492209 -356.175626) (xy 103.509548 -356.120304)
			(xy 103.535058 -356.068241) (xy 103.568153 -356.020639) (xy 103.608069 -355.978591) (xy 103.653887 -355.943068)
			(xy 103.704553 -355.914886) (xy 103.7589 -355.894695) (xy 103.815677 -355.88296) (xy 103.844598 -355.880924)
			(xy 103.859207 -355.879665) (xy 103.886832 -355.869868) (xy 103.910543 -355.852636) (xy 103.92839 -355.829385)
			(xy 103.938906 -355.802026) (xy 103.941229 -355.772807) (xy 103.935165 -355.74413) (xy 103.921215 -355.718352)
			(xy 103.911146 -355.707696) (xy 102.10673 -353.90328) (xy 100.345494 -353.90328) (xy 100.279454 -353.96932)
			(xy 100.253292 -353.995228) (xy 100.253292 -354.459032) (xy 101.443534 -354.459032) (xy 101.447605 -354.40341)
			(xy 101.459731 -354.348973) (xy 101.479654 -354.296882) (xy 101.50695 -354.248247) (xy 101.541036 -354.204104)
			(xy 101.581185 -354.165395) (xy 101.626543 -354.132944) (xy 101.676143 -354.107443) (xy 101.728927 -354.089436)
			(xy 101.78377 -354.079306) (xy 101.839504 -354.077269) (xy 101.894941 -354.083369) (xy 101.948898 -354.097475)
			(xy 102.000227 -354.119287) (xy 102.047833 -354.148341) (xy 102.090701 -354.184016) (xy 102.127918 -354.225553)
			(xy 102.158691 -354.272066) (xy 102.182363 -354.322563) (xy 102.198431 -354.37597) (xy 102.206551 -354.431146)
			(xy 102.20706 -354.459032) (xy 102.206551 -354.486918) (xy 102.198431 -354.542094) (xy 102.182363 -354.595501)
			(xy 102.158691 -354.645998) (xy 102.127918 -354.692511) (xy 102.090701 -354.734048) (xy 102.047833 -354.769723)
			(xy 102.000227 -354.798777) (xy 101.948898 -354.820589) (xy 101.894941 -354.834695) (xy 101.839504 -354.840795)
			(xy 101.78377 -354.838758) (xy 101.728927 -354.828628) (xy 101.676143 -354.810621) (xy 101.626543 -354.78512)
			(xy 101.581185 -354.752669) (xy 101.541036 -354.71396) (xy 101.50695 -354.669817) (xy 101.479654 -354.621182)
			(xy 101.459731 -354.569091) (xy 101.447605 -354.514654) (xy 101.443534 -354.459032) (xy 100.253292 -354.459032)
			(xy 100.253292 -355.232208) (xy 100.131372 -355.354128) (xy 100.114608 -355.370892) (xy 100.086668 -355.398832)
			(xy 101.492048 -355.398832) (xy 101.496119 -355.34321) (xy 101.508245 -355.288773) (xy 101.528168 -355.236682)
			(xy 101.555464 -355.188047) (xy 101.58955 -355.143904) (xy 101.629699 -355.105195) (xy 101.675057 -355.072744)
			(xy 101.724657 -355.047243) (xy 101.777441 -355.029236) (xy 101.832284 -355.019106) (xy 101.888018 -355.017069)
			(xy 101.943455 -355.023169) (xy 101.997412 -355.037275) (xy 102.048741 -355.059087) (xy 102.096347 -355.088141)
			(xy 102.139215 -355.123816) (xy 102.176432 -355.165353) (xy 102.207205 -355.211866) (xy 102.230877 -355.262363)
			(xy 102.246945 -355.31577) (xy 102.255065 -355.370946) (xy 102.255574 -355.398832) (xy 102.255065 -355.426718)
			(xy 102.246945 -355.481894) (xy 102.230877 -355.535301) (xy 102.207205 -355.585798) (xy 102.176432 -355.632311)
			(xy 102.139215 -355.673848) (xy 102.096347 -355.709523) (xy 102.048741 -355.738577) (xy 101.997412 -355.760389)
			(xy 101.943455 -355.774495) (xy 101.888018 -355.780595) (xy 101.832284 -355.778558) (xy 101.777441 -355.768428)
			(xy 101.724657 -355.750421) (xy 101.675057 -355.72492) (xy 101.629699 -355.692469) (xy 101.58955 -355.65376)
			(xy 101.555464 -355.609617) (xy 101.528168 -355.560982) (xy 101.508245 -355.508891) (xy 101.496119 -355.454454)
			(xy 101.492048 -355.398832) (xy 100.086668 -355.398832) (xy 99.992688 -355.492812) (xy 99.271328 -355.492812)
			(xy 99.150932 -355.613208) (xy 99.150932 -355.862382) (xy 99.437444 -356.14864) (xy 99.449382 -356.15245)
			(xy 99.479973 -356.162571) (xy 99.538522 -356.189475) (xy 99.593204 -356.223559) (xy 99.643143 -356.264277)
			(xy 99.687539 -356.310977) (xy 99.72568 -356.362911) (xy 99.756956 -356.419246) (xy 99.780866 -356.47908)
			(xy 99.797027 -356.541456) (xy 99.80518 -356.605373) (xy 99.805744 -356.63759) (xy 99.805744 -356.795578)
			(xy 101.453186 -356.795578) (xy 101.457257 -356.739956) (xy 101.469383 -356.685519) (xy 101.489306 -356.633428)
			(xy 101.516602 -356.584793) (xy 101.550688 -356.54065) (xy 101.590837 -356.501941) (xy 101.636195 -356.46949)
			(xy 101.685795 -356.443989) (xy 101.738579 -356.425982) (xy 101.793422 -356.415852) (xy 101.849156 -356.413815)
			(xy 101.904593 -356.419915) (xy 101.95855 -356.434021) (xy 102.009879 -356.455833) (xy 102.057485 -356.484887)
			(xy 102.100353 -356.520562) (xy 102.13757 -356.562099) (xy 102.168343 -356.608612) (xy 102.192015 -356.659109)
			(xy 102.208083 -356.712516) (xy 102.216203 -356.767692) (xy 102.216712 -356.795578) (xy 102.216203 -356.823464)
			(xy 102.208083 -356.87864) (xy 102.192015 -356.932047) (xy 102.168343 -356.982544) (xy 102.13757 -357.029057)
			(xy 102.100353 -357.070594) (xy 102.057485 -357.106269) (xy 102.009879 -357.135323) (xy 101.95855 -357.157135)
			(xy 101.904593 -357.171241) (xy 101.849156 -357.177341) (xy 101.793422 -357.175304) (xy 101.738579 -357.165174)
			(xy 101.685795 -357.147167) (xy 101.636195 -357.121666) (xy 101.590837 -357.089215) (xy 101.550688 -357.050506)
			(xy 101.516602 -357.006363) (xy 101.489306 -356.957728) (xy 101.469383 -356.905637) (xy 101.457257 -356.8512)
			(xy 101.453186 -356.795578) (xy 99.805744 -356.795578) (xy 99.805744 -357.53167) (xy 99.805242 -357.563631)
			(xy 99.797231 -357.627049) (xy 99.781334 -357.688963) (xy 99.781059 -357.689658) (xy 101.452678 -357.689658)
			(xy 101.456749 -357.634036) (xy 101.468875 -357.579599) (xy 101.488798 -357.527508) (xy 101.516094 -357.478873)
			(xy 101.55018 -357.43473) (xy 101.590329 -357.396021) (xy 101.635687 -357.36357) (xy 101.685287 -357.338069)
			(xy 101.738071 -357.320062) (xy 101.792914 -357.309932) (xy 101.848648 -357.307895) (xy 101.904085 -357.313995)
			(xy 101.958042 -357.328101) (xy 102.009371 -357.349913) (xy 102.056977 -357.378967) (xy 102.099845 -357.414642)
			(xy 102.137062 -357.456179) (xy 102.167835 -357.502692) (xy 102.191507 -357.553189) (xy 102.207575 -357.606596)
			(xy 102.215695 -357.661772) (xy 102.216204 -357.689658) (xy 102.215695 -357.717544) (xy 102.207575 -357.77272)
			(xy 102.191507 -357.826127) (xy 102.167835 -357.876624) (xy 102.137062 -357.923137) (xy 102.099845 -357.964674)
			(xy 102.056977 -358.000349) (xy 102.009371 -358.029403) (xy 101.958042 -358.051215) (xy 101.904085 -358.065321)
			(xy 101.848648 -358.071421) (xy 101.792914 -358.069384) (xy 101.738071 -358.059254) (xy 101.685287 -358.041247)
			(xy 101.635687 -358.015746) (xy 101.590329 -357.983295) (xy 101.55018 -357.944586) (xy 101.516094 -357.900443)
			(xy 101.488798 -357.851808) (xy 101.468875 -357.799717) (xy 101.456749 -357.74528) (xy 101.452678 -357.689658)
			(xy 99.781059 -357.689658) (xy 99.757802 -357.748396) (xy 99.727008 -357.804411) (xy 99.689435 -357.856126)
			(xy 99.645678 -357.902723) (xy 99.596425 -357.943468) (xy 99.542454 -357.977719) (xy 99.484615 -358.004936)
			(xy 99.423822 -358.024689) (xy 99.361032 -358.036667) (xy 99.297236 -358.040681) (xy 99.23344 -358.036667)
			(xy 99.17065 -358.024689) (xy 99.109857 -358.004936) (xy 99.052018 -357.977719) (xy 98.998047 -357.943468)
			(xy 98.948794 -357.902723) (xy 98.905037 -357.856126) (xy 98.867464 -357.804411) (xy 98.83667 -357.748396)
			(xy 98.813138 -357.688963) (xy 98.797241 -357.627049) (xy 98.78923 -357.563631) (xy 98.788728 -357.53167)
			(xy 98.788728 -356.75824) (xy 98.391726 -356.360984) (xy 98.371447 -356.34008) (xy 98.335974 -356.293887)
			(xy 98.306839 -356.243457) (xy 98.284542 -356.189652) (xy 98.269465 -356.133396) (xy 98.261865 -356.075653)
			(xy 98.261424 -356.046532) (xy 98.261424 -355.429058) (xy 98.261883 -355.399939) (xy 98.269491 -355.342199)
			(xy 98.284571 -355.285947) (xy 98.306866 -355.232145) (xy 98.335993 -355.181713) (xy 98.371454 -355.135516)
			(xy 98.391726 -355.114606) (xy 98.772726 -354.733606) (xy 98.793631 -354.713328) (xy 98.839824 -354.677858)
			(xy 98.890255 -354.648726) (xy 98.944059 -354.626431) (xy 99.000315 -354.611355) (xy 99.058058 -354.603757)
			(xy 99.087178 -354.603304) (xy 99.363784 -354.603304) (xy 99.363784 -353.626928) (xy 99.486212 -353.5045)
			(xy 99.493578 -353.497134) (xy 99.8474 -353.143312) (xy 99.854766 -353.135946) (xy 99.977194 -353.013518)
			(xy 100.151946 -353.013518) (xy 100.161344 -353.013264) (xy 102.29088 -353.013264) (xy 102.300278 -353.013518)
			(xy 102.47503 -353.013518) (xy 102.597458 -353.135946) (xy 102.60457 -353.143058) (xy 102.95001 -353.488498)
			(xy 110.4806 -353.488498) (xy 110.484671 -353.432876) (xy 110.496797 -353.378439) (xy 110.51672 -353.326348)
			(xy 110.544016 -353.277713) (xy 110.578102 -353.23357) (xy 110.618251 -353.194861) (xy 110.663609 -353.16241)
			(xy 110.713209 -353.136909) (xy 110.765993 -353.118902) (xy 110.820836 -353.108772) (xy 110.87657 -353.106735)
			(xy 110.932007 -353.112835) (xy 110.985964 -353.126941) (xy 111.037293 -353.148753) (xy 111.084899 -353.177807)
			(xy 111.127767 -353.213482) (xy 111.164984 -353.255019) (xy 111.195757 -353.301532) (xy 111.219429 -353.352029)
			(xy 111.235497 -353.405436) (xy 111.243617 -353.460612) (xy 111.244126 -353.488498) (xy 111.243617 -353.516384)
			(xy 111.241179 -353.532948) (xy 113.415062 -353.532948) (xy 113.419133 -353.477326) (xy 113.431259 -353.422889)
			(xy 113.451182 -353.370798) (xy 113.478478 -353.322163) (xy 113.512564 -353.27802) (xy 113.552713 -353.239311)
			(xy 113.598071 -353.20686) (xy 113.647671 -353.181359) (xy 113.700455 -353.163352) (xy 113.755298 -353.153222)
			(xy 113.811032 -353.151185) (xy 113.866469 -353.157285) (xy 113.920426 -353.171391) (xy 113.971755 -353.193203)
			(xy 114.019361 -353.222257) (xy 114.062229 -353.257932) (xy 114.099446 -353.299469) (xy 114.130219 -353.345982)
			(xy 114.153891 -353.396479) (xy 114.169959 -353.449886) (xy 114.178079 -353.505062) (xy 114.178588 -353.532948)
			(xy 114.178079 -353.560834) (xy 114.169959 -353.61601) (xy 114.153891 -353.669417) (xy 114.130219 -353.719914)
			(xy 114.099446 -353.766427) (xy 114.062229 -353.807964) (xy 114.019361 -353.843639) (xy 113.971755 -353.872693)
			(xy 113.920426 -353.894505) (xy 113.866469 -353.908611) (xy 113.811032 -353.914711) (xy 113.755298 -353.912674)
			(xy 113.700455 -353.902544) (xy 113.647671 -353.884537) (xy 113.598071 -353.859036) (xy 113.552713 -353.826585)
			(xy 113.512564 -353.787876) (xy 113.478478 -353.743733) (xy 113.451182 -353.695098) (xy 113.431259 -353.643007)
			(xy 113.419133 -353.58857) (xy 113.415062 -353.532948) (xy 111.241179 -353.532948) (xy 111.235497 -353.57156)
			(xy 111.219429 -353.624967) (xy 111.195757 -353.675464) (xy 111.164984 -353.721977) (xy 111.127767 -353.763514)
			(xy 111.084899 -353.799189) (xy 111.037293 -353.828243) (xy 110.985964 -353.850055) (xy 110.932007 -353.864161)
			(xy 110.87657 -353.870261) (xy 110.820836 -353.868224) (xy 110.765993 -353.858094) (xy 110.713209 -353.840087)
			(xy 110.663609 -353.814586) (xy 110.618251 -353.782135) (xy 110.578102 -353.743426) (xy 110.544016 -353.699283)
			(xy 110.51672 -353.650648) (xy 110.496797 -353.598557) (xy 110.484671 -353.54412) (xy 110.4806 -353.488498)
			(xy 102.95001 -353.488498) (xy 103.958644 -354.497132) (xy 105.004868 -354.497132) (xy 105.008939 -354.44151)
			(xy 105.021065 -354.387073) (xy 105.040988 -354.334982) (xy 105.068284 -354.286347) (xy 105.10237 -354.242204)
			(xy 105.142519 -354.203495) (xy 105.187877 -354.171044) (xy 105.237477 -354.145543) (xy 105.290261 -354.127536)
			(xy 105.345104 -354.117406) (xy 105.400838 -354.115369) (xy 105.456275 -354.121469) (xy 105.510232 -354.135575)
			(xy 105.525446 -354.14204) (xy 111.725708 -354.14204) (xy 111.729779 -354.086418) (xy 111.741905 -354.031981)
			(xy 111.761828 -353.97989) (xy 111.789124 -353.931255) (xy 111.82321 -353.887112) (xy 111.863359 -353.848403)
			(xy 111.908717 -353.815952) (xy 111.958317 -353.790451) (xy 112.011101 -353.772444) (xy 112.065944 -353.762314)
			(xy 112.121678 -353.760277) (xy 112.177115 -353.766377) (xy 112.231072 -353.780483) (xy 112.282401 -353.802295)
			(xy 112.330007 -353.831349) (xy 112.372875 -353.867024) (xy 112.410092 -353.908561) (xy 112.440865 -353.955074)
			(xy 112.464537 -354.005571) (xy 112.480605 -354.058978) (xy 112.488725 -354.114154) (xy 112.489234 -354.14204)
			(xy 112.488725 -354.169926) (xy 112.480605 -354.225102) (xy 112.464537 -354.278509) (xy 112.440865 -354.329006)
			(xy 112.410092 -354.375519) (xy 112.372875 -354.417056) (xy 112.330007 -354.452731) (xy 112.282401 -354.481785)
			(xy 112.231072 -354.503597) (xy 112.177115 -354.517703) (xy 112.121678 -354.523803) (xy 112.065944 -354.521766)
			(xy 112.011101 -354.511636) (xy 111.958317 -354.493629) (xy 111.908717 -354.468128) (xy 111.863359 -354.435677)
			(xy 111.82321 -354.396968) (xy 111.789124 -354.352825) (xy 111.761828 -354.30419) (xy 111.741905 -354.252099)
			(xy 111.729779 -354.197662) (xy 111.725708 -354.14204) (xy 105.525446 -354.14204) (xy 105.561561 -354.157387)
			(xy 105.609167 -354.186441) (xy 105.652035 -354.222116) (xy 105.689252 -354.263653) (xy 105.720025 -354.310166)
			(xy 105.743697 -354.360663) (xy 105.759765 -354.41407) (xy 105.767885 -354.469246) (xy 105.768394 -354.497132)
			(xy 105.767885 -354.525018) (xy 105.759765 -354.580194) (xy 105.743697 -354.633601) (xy 105.720025 -354.684098)
			(xy 105.689252 -354.730611) (xy 105.652035 -354.772148) (xy 105.609167 -354.807823) (xy 105.561561 -354.836877)
			(xy 105.510232 -354.858689) (xy 105.456275 -354.872795) (xy 105.400838 -354.878895) (xy 105.345104 -354.876858)
			(xy 105.290261 -354.866728) (xy 105.237477 -354.848721) (xy 105.187877 -354.82322) (xy 105.142519 -354.790769)
			(xy 105.10237 -354.75206) (xy 105.068284 -354.707917) (xy 105.040988 -354.659282) (xy 105.021065 -354.607191)
			(xy 105.008939 -354.552754) (xy 105.004868 -354.497132) (xy 103.958644 -354.497132) (xy 104.621076 -355.159564)
			(xy 111.223296 -355.159564) (xy 111.227367 -355.103942) (xy 111.239493 -355.049505) (xy 111.259416 -354.997414)
			(xy 111.286712 -354.948779) (xy 111.320798 -354.904636) (xy 111.360947 -354.865927) (xy 111.406305 -354.833476)
			(xy 111.455905 -354.807975) (xy 111.508689 -354.789968) (xy 111.563532 -354.779838) (xy 111.619266 -354.777801)
			(xy 111.674703 -354.783901) (xy 111.72866 -354.798007) (xy 111.779989 -354.819819) (xy 111.827595 -354.848873)
			(xy 111.870463 -354.884548) (xy 111.90768 -354.926085) (xy 111.938453 -354.972598) (xy 111.962125 -355.023095)
			(xy 111.972845 -355.058726) (xy 112.247678 -355.058726) (xy 112.251749 -355.003104) (xy 112.263875 -354.948667)
			(xy 112.283798 -354.896576) (xy 112.311094 -354.847941) (xy 112.34518 -354.803798) (xy 112.385329 -354.765089)
			(xy 112.430687 -354.732638) (xy 112.480287 -354.707137) (xy 112.533071 -354.68913) (xy 112.587914 -354.679)
			(xy 112.643648 -354.676963) (xy 112.699085 -354.683063) (xy 112.753042 -354.697169) (xy 112.804371 -354.718981)
			(xy 112.851977 -354.748035) (xy 112.894845 -354.78371) (xy 112.900703 -354.790248) (xy 113.438938 -354.790248)
			(xy 113.443009 -354.734626) (xy 113.455135 -354.680189) (xy 113.475058 -354.628098) (xy 113.502354 -354.579463)
			(xy 113.53644 -354.53532) (xy 113.576589 -354.496611) (xy 113.621947 -354.46416) (xy 113.671547 -354.438659)
			(xy 113.724331 -354.420652) (xy 113.779174 -354.410522) (xy 113.834908 -354.408485) (xy 113.890345 -354.414585)
			(xy 113.944302 -354.428691) (xy 113.995631 -354.450503) (xy 114.043237 -354.479557) (xy 114.086105 -354.515232)
			(xy 114.123322 -354.556769) (xy 114.154095 -354.603282) (xy 114.177767 -354.653779) (xy 114.193835 -354.707186)
			(xy 114.201955 -354.762362) (xy 114.202464 -354.790248) (xy 114.201955 -354.818134) (xy 114.193835 -354.87331)
			(xy 114.177767 -354.926717) (xy 114.154095 -354.977214) (xy 114.123322 -355.023727) (xy 114.086105 -355.065264)
			(xy 114.043237 -355.100939) (xy 113.995631 -355.129993) (xy 113.944302 -355.151805) (xy 113.890345 -355.165911)
			(xy 113.834908 -355.172011) (xy 113.779174 -355.169974) (xy 113.724331 -355.159844) (xy 113.671547 -355.141837)
			(xy 113.621947 -355.116336) (xy 113.576589 -355.083885) (xy 113.53644 -355.045176) (xy 113.502354 -355.001033)
			(xy 113.475058 -354.952398) (xy 113.455135 -354.900307) (xy 113.443009 -354.84587) (xy 113.438938 -354.790248)
			(xy 112.900703 -354.790248) (xy 112.932062 -354.825247) (xy 112.962835 -354.87176) (xy 112.986507 -354.922257)
			(xy 113.002575 -354.975664) (xy 113.010695 -355.03084) (xy 113.011204 -355.058726) (xy 113.010695 -355.086612)
			(xy 113.002575 -355.141788) (xy 112.990426 -355.18217) (xy 117.96852 -355.18217) (xy 117.972591 -355.126548)
			(xy 117.984717 -355.072111) (xy 118.00464 -355.02002) (xy 118.031936 -354.971385) (xy 118.066022 -354.927242)
			(xy 118.106171 -354.888533) (xy 118.151529 -354.856082) (xy 118.201129 -354.830581) (xy 118.253913 -354.812574)
			(xy 118.308756 -354.802444) (xy 118.36449 -354.800407) (xy 118.419927 -354.806507) (xy 118.473884 -354.820613)
			(xy 118.525213 -354.842425) (xy 118.572819 -354.871479) (xy 118.615687 -354.907154) (xy 118.652904 -354.948691)
			(xy 118.683677 -354.995204) (xy 118.707349 -355.045701) (xy 118.723417 -355.099108) (xy 118.731537 -355.154284)
			(xy 118.732046 -355.18217) (xy 118.731537 -355.210056) (xy 118.723417 -355.265232) (xy 118.707349 -355.318639)
			(xy 118.683677 -355.369136) (xy 118.652904 -355.415649) (xy 118.615687 -355.457186) (xy 118.572819 -355.492861)
			(xy 118.525213 -355.521915) (xy 118.473884 -355.543727) (xy 118.419927 -355.557833) (xy 118.36449 -355.563933)
			(xy 118.308756 -355.561896) (xy 118.253913 -355.551766) (xy 118.201129 -355.533759) (xy 118.151529 -355.508258)
			(xy 118.106171 -355.475807) (xy 118.066022 -355.437098) (xy 118.031936 -355.392955) (xy 118.00464 -355.34432)
			(xy 117.984717 -355.292229) (xy 117.972591 -355.237792) (xy 117.96852 -355.18217) (xy 112.990426 -355.18217)
			(xy 112.986507 -355.195195) (xy 112.962835 -355.245692) (xy 112.932062 -355.292205) (xy 112.894845 -355.333742)
			(xy 112.851977 -355.369417) (xy 112.804371 -355.398471) (xy 112.753042 -355.420283) (xy 112.699085 -355.434389)
			(xy 112.643648 -355.440489) (xy 112.587914 -355.438452) (xy 112.533071 -355.428322) (xy 112.480287 -355.410315)
			(xy 112.430687 -355.384814) (xy 112.385329 -355.352363) (xy 112.34518 -355.313654) (xy 112.311094 -355.269511)
			(xy 112.283798 -355.220876) (xy 112.263875 -355.168785) (xy 112.251749 -355.114348) (xy 112.247678 -355.058726)
			(xy 111.972845 -355.058726) (xy 111.978193 -355.076502) (xy 111.986313 -355.131678) (xy 111.986822 -355.159564)
			(xy 111.986313 -355.18745) (xy 111.978193 -355.242626) (xy 111.962125 -355.296033) (xy 111.938453 -355.34653)
			(xy 111.90768 -355.393043) (xy 111.870463 -355.43458) (xy 111.827595 -355.470255) (xy 111.779989 -355.499309)
			(xy 111.72866 -355.521121) (xy 111.674703 -355.535227) (xy 111.619266 -355.541327) (xy 111.563532 -355.53929)
			(xy 111.508689 -355.52916) (xy 111.455905 -355.511153) (xy 111.406305 -355.485652) (xy 111.360947 -355.453201)
			(xy 111.320798 -355.414492) (xy 111.286712 -355.370349) (xy 111.259416 -355.321714) (xy 111.239493 -355.269623)
			(xy 111.227367 -355.215186) (xy 111.223296 -355.159564) (xy 104.621076 -355.159564) (xy 105.612438 -356.150926)
			(xy 110.986314 -356.150926) (xy 110.990385 -356.095304) (xy 111.002511 -356.040867) (xy 111.022434 -355.988776)
			(xy 111.04973 -355.940141) (xy 111.083816 -355.895998) (xy 111.123965 -355.857289) (xy 111.169323 -355.824838)
			(xy 111.218923 -355.799337) (xy 111.271707 -355.78133) (xy 111.32655 -355.7712) (xy 111.382284 -355.769163)
			(xy 111.437721 -355.775263) (xy 111.491678 -355.789369) (xy 111.543007 -355.811181) (xy 111.590613 -355.840235)
			(xy 111.633481 -355.87591) (xy 111.670698 -355.917447) (xy 111.687202 -355.942392) (xy 116.343682 -355.942392)
			(xy 116.347753 -355.88677) (xy 116.359879 -355.832333) (xy 116.379802 -355.780242) (xy 116.407098 -355.731607)
			(xy 116.441184 -355.687464) (xy 116.481333 -355.648755) (xy 116.526691 -355.616304) (xy 116.576291 -355.590803)
			(xy 116.629075 -355.572796) (xy 116.683918 -355.562666) (xy 116.739652 -355.560629) (xy 116.795089 -355.566729)
			(xy 116.849046 -355.580835) (xy 116.900375 -355.602647) (xy 116.947981 -355.631701) (xy 116.990849 -355.667376)
			(xy 117.0181 -355.69779) (xy 120.263664 -355.69779) (xy 120.267735 -355.642168) (xy 120.279861 -355.587731)
			(xy 120.299784 -355.53564) (xy 120.32708 -355.487005) (xy 120.361166 -355.442862) (xy 120.401315 -355.404153)
			(xy 120.446673 -355.371702) (xy 120.496273 -355.346201) (xy 120.549057 -355.328194) (xy 120.6039 -355.318064)
			(xy 120.659634 -355.316027) (xy 120.715071 -355.322127) (xy 120.769028 -355.336233) (xy 120.820357 -355.358045)
			(xy 120.867963 -355.387099) (xy 120.910831 -355.422774) (xy 120.948048 -355.464311) (xy 120.978821 -355.510824)
			(xy 121.002493 -355.561321) (xy 121.018561 -355.614728) (xy 121.026681 -355.669904) (xy 121.02719 -355.69779)
			(xy 121.026681 -355.725676) (xy 121.018561 -355.780852) (xy 121.002493 -355.834259) (xy 120.978821 -355.884756)
			(xy 120.948048 -355.931269) (xy 120.910831 -355.972806) (xy 120.867963 -356.008481) (xy 120.820357 -356.037535)
			(xy 120.769028 -356.059347) (xy 120.715071 -356.073453) (xy 120.659634 -356.079553) (xy 120.6039 -356.077516)
			(xy 120.549057 -356.067386) (xy 120.496273 -356.049379) (xy 120.446673 -356.023878) (xy 120.401315 -355.991427)
			(xy 120.361166 -355.952718) (xy 120.32708 -355.908575) (xy 120.299784 -355.85994) (xy 120.279861 -355.807849)
			(xy 120.267735 -355.753412) (xy 120.263664 -355.69779) (xy 117.0181 -355.69779) (xy 117.028066 -355.708913)
			(xy 117.058839 -355.755426) (xy 117.082511 -355.805923) (xy 117.098579 -355.85933) (xy 117.106699 -355.914506)
			(xy 117.107208 -355.942392) (xy 117.106699 -355.970278) (xy 117.098579 -356.025454) (xy 117.082511 -356.078861)
			(xy 117.058839 -356.129358) (xy 117.028066 -356.175871) (xy 116.990849 -356.217408) (xy 116.947981 -356.253083)
			(xy 116.900375 -356.282137) (xy 116.849046 -356.303949) (xy 116.795089 -356.318055) (xy 116.739652 -356.324155)
			(xy 116.683918 -356.322118) (xy 116.629075 -356.311988) (xy 116.576291 -356.293981) (xy 116.526691 -356.26848)
			(xy 116.481333 -356.236029) (xy 116.441184 -356.19732) (xy 116.407098 -356.153177) (xy 116.379802 -356.104542)
			(xy 116.359879 -356.052451) (xy 116.347753 -355.998014) (xy 116.343682 -355.942392) (xy 111.687202 -355.942392)
			(xy 111.701471 -355.96396) (xy 111.725143 -356.014457) (xy 111.741211 -356.067864) (xy 111.749331 -356.12304)
			(xy 111.74984 -356.150926) (xy 111.749331 -356.178812) (xy 111.741211 -356.233988) (xy 111.725143 -356.287395)
			(xy 111.701471 -356.337892) (xy 111.670698 -356.384405) (xy 111.633481 -356.425942) (xy 111.590613 -356.461617)
			(xy 111.543007 -356.490671) (xy 111.491678 -356.512483) (xy 111.437721 -356.526589) (xy 111.382284 -356.532689)
			(xy 111.32655 -356.530652) (xy 111.271707 -356.520522) (xy 111.218923 -356.502515) (xy 111.169323 -356.477014)
			(xy 111.123965 -356.444563) (xy 111.083816 -356.405854) (xy 111.04973 -356.361711) (xy 111.022434 -356.313076)
			(xy 111.002511 -356.260985) (xy 110.990385 -356.206548) (xy 110.986314 -356.150926) (xy 105.612438 -356.150926)
			(xy 105.927144 -356.465632) (xy 105.933494 -356.471982) (xy 106.02976 -356.568248) (xy 113.183922 -356.568248)
			(xy 113.187993 -356.512626) (xy 113.200119 -356.458189) (xy 113.220042 -356.406098) (xy 113.247338 -356.357463)
			(xy 113.281424 -356.31332) (xy 113.321573 -356.274611) (xy 113.366931 -356.24216) (xy 113.416531 -356.216659)
			(xy 113.469315 -356.198652) (xy 113.524158 -356.188522) (xy 113.579892 -356.186485) (xy 113.635329 -356.192585)
			(xy 113.689286 -356.206691) (xy 113.740615 -356.228503) (xy 113.788221 -356.257557) (xy 113.831089 -356.293232)
			(xy 113.868306 -356.334769) (xy 113.899079 -356.381282) (xy 113.922751 -356.431779) (xy 113.938819 -356.485186)
			(xy 113.946939 -356.540362) (xy 113.947448 -356.568248) (xy 113.946939 -356.596134) (xy 113.938819 -356.65131)
			(xy 113.922751 -356.704717) (xy 113.899079 -356.755214) (xy 113.868306 -356.801727) (xy 113.831089 -356.843264)
			(xy 113.825211 -356.848156) (xy 114.184174 -356.848156) (xy 114.188245 -356.792534) (xy 114.200371 -356.738097)
			(xy 114.220294 -356.686006) (xy 114.24759 -356.637371) (xy 114.281676 -356.593228) (xy 114.321825 -356.554519)
			(xy 114.367183 -356.522068) (xy 114.416783 -356.496567) (xy 114.469567 -356.47856) (xy 114.52441 -356.46843)
			(xy 114.580144 -356.466393) (xy 114.635581 -356.472493) (xy 114.689538 -356.486599) (xy 114.740867 -356.508411)
			(xy 114.788473 -356.537465) (xy 114.831341 -356.57314) (xy 114.868558 -356.614677) (xy 114.899331 -356.66119)
			(xy 114.923003 -356.711687) (xy 114.939071 -356.765094) (xy 114.947191 -356.82027) (xy 114.9477 -356.848156)
			(xy 114.947191 -356.876042) (xy 114.939071 -356.931218) (xy 114.923003 -356.984625) (xy 114.899331 -357.035122)
			(xy 114.868558 -357.081635) (xy 114.831341 -357.123172) (xy 114.788473 -357.158847) (xy 114.740867 -357.187901)
			(xy 114.689538 -357.209713) (xy 114.635581 -357.223819) (xy 114.580144 -357.229919) (xy 114.52441 -357.227882)
			(xy 114.469567 -357.217752) (xy 114.416783 -357.199745) (xy 114.367183 -357.174244) (xy 114.321825 -357.141793)
			(xy 114.281676 -357.103084) (xy 114.24759 -357.058941) (xy 114.220294 -357.010306) (xy 114.200371 -356.958215)
			(xy 114.188245 -356.903778) (xy 114.184174 -356.848156) (xy 113.825211 -356.848156) (xy 113.788221 -356.878939)
			(xy 113.740615 -356.907993) (xy 113.689286 -356.929805) (xy 113.635329 -356.943911) (xy 113.579892 -356.950011)
			(xy 113.524158 -356.947974) (xy 113.469315 -356.937844) (xy 113.416531 -356.919837) (xy 113.366931 -356.894336)
			(xy 113.321573 -356.861885) (xy 113.281424 -356.823176) (xy 113.247338 -356.779033) (xy 113.220042 -356.730398)
			(xy 113.200119 -356.678307) (xy 113.187993 -356.62387) (xy 113.183922 -356.568248) (xy 106.02976 -356.568248)
			(xy 106.056684 -356.595172) (xy 106.056684 -357.561388) (xy 112.960402 -357.561388) (xy 112.964473 -357.505766)
			(xy 112.976599 -357.451329) (xy 112.996522 -357.399238) (xy 113.023818 -357.350603) (xy 113.057904 -357.30646)
			(xy 113.098053 -357.267751) (xy 113.143411 -357.2353) (xy 113.193011 -357.209799) (xy 113.245795 -357.191792)
			(xy 113.300638 -357.181662) (xy 113.356372 -357.179625) (xy 113.411809 -357.185725) (xy 113.465766 -357.199831)
			(xy 113.517095 -357.221643) (xy 113.564701 -357.250697) (xy 113.607569 -357.286372) (xy 113.644786 -357.327909)
			(xy 113.675559 -357.374422) (xy 113.699231 -357.424919) (xy 113.715299 -357.478326) (xy 113.723419 -357.533502)
			(xy 113.723928 -357.561388) (xy 113.723419 -357.589274) (xy 113.715299 -357.64445) (xy 113.699231 -357.697857)
			(xy 113.675559 -357.748354) (xy 113.644786 -357.794867) (xy 113.607569 -357.836404) (xy 113.564701 -357.872079)
			(xy 113.517095 -357.901133) (xy 113.465766 -357.922945) (xy 113.411809 -357.937051) (xy 113.356372 -357.943151)
			(xy 113.300638 -357.941114) (xy 113.245795 -357.930984) (xy 113.193011 -357.912977) (xy 113.143411 -357.887476)
			(xy 113.098053 -357.855025) (xy 113.057904 -357.816316) (xy 113.023818 -357.772173) (xy 112.996522 -357.723538)
			(xy 112.976599 -357.671447) (xy 112.964473 -357.61701) (xy 112.960402 -357.561388) (xy 106.056684 -357.561388)
			(xy 106.056684 -358.576626) (xy 112.706402 -358.576626) (xy 112.710473 -358.521004) (xy 112.722599 -358.466567)
			(xy 112.742522 -358.414476) (xy 112.769818 -358.365841) (xy 112.803904 -358.321698) (xy 112.844053 -358.282989)
			(xy 112.889411 -358.250538) (xy 112.939011 -358.225037) (xy 112.991795 -358.20703) (xy 113.046638 -358.1969)
			(xy 113.102372 -358.194863) (xy 113.157809 -358.200963) (xy 113.211766 -358.215069) (xy 113.263095 -358.236881)
			(xy 113.310701 -358.265935) (xy 113.353569 -358.30161) (xy 113.390786 -358.343147) (xy 113.421559 -358.38966)
			(xy 113.445231 -358.440157) (xy 113.461299 -358.493564) (xy 113.469419 -358.54874) (xy 113.469928 -358.576626)
			(xy 113.469419 -358.604512) (xy 113.461299 -358.659688) (xy 113.445231 -358.713095) (xy 113.421559 -358.763592)
			(xy 113.390786 -358.810105) (xy 113.353569 -358.851642) (xy 113.310701 -358.887317) (xy 113.263095 -358.916371)
			(xy 113.211766 -358.938183) (xy 113.157809 -358.952289) (xy 113.102372 -358.958389) (xy 113.046638 -358.956352)
			(xy 112.991795 -358.946222) (xy 112.939011 -358.928215) (xy 112.889411 -358.902714) (xy 112.844053 -358.870263)
			(xy 112.803904 -358.831554) (xy 112.769818 -358.787411) (xy 112.742522 -358.738776) (xy 112.722599 -358.686685)
			(xy 112.710473 -358.632248) (xy 112.706402 -358.576626) (xy 106.056684 -358.576626) (xy 106.056684 -359.622955)
			(xy 112.735029 -359.622955) (xy 112.735029 -359.568445) (xy 112.742787 -359.51449) (xy 112.758144 -359.462188)
			(xy 112.780788 -359.412604) (xy 112.810259 -359.366747) (xy 112.845956 -359.325552) (xy 112.887152 -359.289855)
			(xy 112.933009 -359.260386) (xy 112.982593 -359.237742) (xy 113.034896 -359.222385) (xy 113.088851 -359.214628)
			(xy 113.116106 -359.214166) (xy 113.14219 -359.214548) (xy 113.19387 -359.221669) (xy 113.244099 -359.235765)
			(xy 113.291938 -359.256571) (xy 113.336498 -359.283701) (xy 113.376946 -359.316648) (xy 113.412528 -359.354798)
			(xy 113.442582 -359.39744) (xy 113.454942 -359.420414) (xy 113.469166 -359.4481) (xy 113.931192 -359.4481)
			(xy 114.944652 -358.434386) (xy 114.944652 -357.688388) (xy 114.945272 -357.663391) (xy 114.95508 -357.614367)
			(xy 114.974258 -357.568197) (xy 115.002071 -357.526651) (xy 115.019328 -357.508556) (xy 115.382548 -357.145336)
			(xy 115.400635 -357.12807) (xy 115.442182 -357.10026) (xy 115.488356 -357.081089) (xy 115.537383 -357.071294)
			(xy 115.56238 -357.07066) (xy 115.95862 -357.07066) (xy 115.983617 -357.071273) (xy 116.032642 -357.081083)
			(xy 116.078812 -357.100263) (xy 116.120357 -357.128078) (xy 116.138452 -357.145336) (xy 116.55679 -357.56342)
			(xy 117.70487 -357.56342) (xy 118.850156 -356.418388) (xy 118.868232 -356.40111) (xy 118.909784 -356.373305)
			(xy 118.955961 -356.354138) (xy 119.00499 -356.344345) (xy 119.029988 -356.343712) (xy 120.897904 -356.343712)
			(xy 122.487944 -354.753926) (xy 122.506061 -354.736712) (xy 122.547618 -354.70897) (xy 122.593786 -354.689861)
			(xy 122.642793 -354.680117) (xy 122.667776 -354.679504) (xy 125.18644 -354.679504) (xy 125.211423 -354.680123)
			(xy 125.26043 -354.689866) (xy 125.306599 -354.708972) (xy 125.348161 -354.736707) (xy 125.366272 -354.753926)
			(xy 126.029608 -355.4171) (xy 172.316679 -355.4171) (xy 172.320847 -355.361492) (xy 172.333255 -355.307126)
			(xy 172.353627 -355.255216) (xy 172.381508 -355.206922) (xy 172.416275 -355.163323) (xy 172.457152 -355.125392)
			(xy 172.503225 -355.093977) (xy 172.553465 -355.069779) (xy 172.606751 -355.053339) (xy 172.661892 -355.045025)
			(xy 172.689774 -355.044502) (xy 172.717106 -355.044977) (xy 172.771185 -355.052948) (xy 172.823518 -355.068736)
			(xy 172.872982 -355.092004) (xy 172.918514 -355.122251) (xy 172.959137 -355.158828) (xy 172.993977 -355.200949)
			(xy 173.008544 -355.22408) (xy 173.016453 -355.236315) (xy 173.037926 -355.255989) (xy 173.064084 -355.268794)
			(xy 173.092794 -355.273686) (xy 173.121716 -355.270266) (xy 173.13529 -355.264974) (xy 173.158503 -355.255494)
			(xy 173.206835 -355.24214) (xy 173.256523 -355.235408) (xy 173.281594 -355.235002) (xy 173.306663 -355.235442)
			(xy 173.356345 -355.242185) (xy 173.40468 -355.255511) (xy 173.427898 -355.264974) (xy 173.441482 -355.270214)
			(xy 173.470388 -355.273597) (xy 173.499075 -355.268699) (xy 173.52522 -355.255916) (xy 173.546704 -355.236283)
			(xy 173.554644 -355.22408) (xy 173.569213 -355.200949) (xy 173.604056 -355.158828) (xy 173.644679 -355.122249)
			(xy 173.69021 -355.091998) (xy 173.739672 -355.068722) (xy 173.792003 -355.052922) (xy 173.846082 -355.044936)
			(xy 173.900746 -355.044936) (xy 173.954825 -355.052922) (xy 174.007156 -355.068722) (xy 174.056618 -355.091998)
			(xy 174.102149 -355.122249) (xy 174.142772 -355.158828) (xy 174.177615 -355.200949) (xy 174.192184 -355.22408)
			(xy 174.20015 -355.236274) (xy 174.221608 -355.255948) (xy 174.24775 -355.268758) (xy 174.276446 -355.273661)
			(xy 174.305358 -355.270257) (xy 174.31893 -355.264974) (xy 174.342139 -355.255482) (xy 174.390472 -355.242132)
			(xy 174.440162 -355.235405) (xy 174.465234 -355.235002) (xy 174.492078 -355.23542) (xy 174.545211 -355.24313)
			(xy 174.596686 -355.258385) (xy 174.64544 -355.280868) (xy 174.690463 -355.310116) (xy 174.730823 -355.345522)
			(xy 174.765683 -355.386354) (xy 174.794323 -355.431765) (xy 174.81615 -355.480817) (xy 174.823882 -355.506528)
			(xy 174.828594 -355.521008) (xy 174.845101 -355.546571) (xy 174.868405 -355.566137) (xy 174.896439 -355.577971)
			(xy 174.926716 -355.58102) (xy 174.956547 -355.575016) (xy 174.970186 -355.56825) (xy 174.998325 -355.553603)
			(xy 175.05828 -355.532881) (xy 175.120841 -355.522389) (xy 175.152558 -355.521768) (xy 175.170577 -355.521985)
			(xy 175.206452 -355.525422) (xy 175.224186 -355.528626) (xy 175.239394 -355.530974) (xy 175.269951 -355.527449)
			(xy 175.298072 -355.514987) (xy 175.321208 -355.494718) (xy 175.337261 -355.46848) (xy 175.341534 -355.453696)
			(xy 175.348943 -355.426655) (xy 175.370568 -355.374927) (xy 175.399529 -355.32692) (xy 175.435203 -355.283666)
			(xy 175.476821 -355.246098) (xy 175.523487 -355.215023) (xy 175.574199 -355.191111) (xy 175.627863 -355.174875)
			(xy 175.683325 -355.166666) (xy 175.711358 -355.166168) (xy 175.738609 -355.166694) (xy 175.792556 -355.174445)
			(xy 175.844851 -355.189794) (xy 175.89443 -355.21243) (xy 175.940282 -355.241892) (xy 175.981474 -355.277579)
			(xy 176.017169 -355.318765) (xy 176.046638 -355.364612) (xy 176.069282 -355.414187) (xy 176.070138 -355.4171)
			(xy 182.004979 -355.4171) (xy 182.009147 -355.36149) (xy 182.021556 -355.307122) (xy 182.04193 -355.25521)
			(xy 182.069813 -355.206915) (xy 182.104582 -355.163315) (xy 182.145461 -355.125384) (xy 182.191537 -355.09397)
			(xy 182.241781 -355.069773) (xy 182.29507 -355.053335) (xy 182.350213 -355.045023) (xy 182.378096 -355.044502)
			(xy 182.405428 -355.044959) (xy 182.459508 -355.052933) (xy 182.511842 -355.068725) (xy 182.561306 -355.091995)
			(xy 182.606838 -355.122245) (xy 182.64746 -355.158824) (xy 182.6823 -355.200947) (xy 182.696866 -355.22408)
			(xy 182.704754 -355.23633) (xy 182.726233 -355.256004) (xy 182.752397 -355.268807) (xy 182.781111 -355.273695)
			(xy 182.810037 -355.27027) (xy 182.823612 -355.264974) (xy 182.846823 -355.255487) (xy 182.895155 -355.242135)
			(xy 182.944844 -355.235406) (xy 182.969916 -355.235002) (xy 182.994985 -355.235435) (xy 183.044668 -355.242181)
			(xy 183.093002 -355.25551) (xy 183.11622 -355.264974) (xy 183.129796 -355.270237) (xy 183.158706 -355.273615)
			(xy 183.187396 -355.268712) (xy 183.213543 -355.255923) (xy 183.235026 -355.236286) (xy 183.242966 -355.22408)
			(xy 183.257535 -355.200949) (xy 183.292378 -355.158828) (xy 183.333001 -355.122249) (xy 183.378532 -355.091998)
			(xy 183.427994 -355.068722) (xy 183.480325 -355.052922) (xy 183.534404 -355.044936) (xy 183.589068 -355.044936)
			(xy 183.643147 -355.052922) (xy 183.695478 -355.068722) (xy 183.74494 -355.091998) (xy 183.790471 -355.122249)
			(xy 183.831094 -355.158828) (xy 183.865937 -355.200949) (xy 183.880506 -355.22408) (xy 183.888451 -355.236289)
			(xy 183.909915 -355.255963) (xy 183.936063 -355.268771) (xy 183.964764 -355.27367) (xy 183.99368 -355.270261)
			(xy 184.007252 -355.264974) (xy 184.030458 -355.255475) (xy 184.078793 -355.242128) (xy 184.128484 -355.235403)
			(xy 184.153556 -355.235002) (xy 184.180398 -355.23549) (xy 184.233527 -355.243189) (xy 184.285002 -355.258433)
			(xy 184.333755 -355.280907) (xy 184.378778 -355.310146) (xy 184.419139 -355.345544) (xy 184.454001 -355.386368)
			(xy 184.482643 -355.431774) (xy 184.504471 -355.48082) (xy 184.512204 -355.506528) (xy 184.516888 -355.521018)
			(xy 184.533399 -355.546585) (xy 184.55671 -355.566152) (xy 184.58475 -355.577984) (xy 184.615032 -355.58103)
			(xy 184.644867 -355.575019) (xy 184.658508 -355.56825) (xy 184.686661 -355.553631) (xy 184.746609 -355.5329)
			(xy 184.809164 -355.522395) (xy 184.84088 -355.521768) (xy 184.8589 -355.521982) (xy 184.894774 -355.525421)
			(xy 184.912508 -355.528626) (xy 184.927714 -355.530997) (xy 184.958273 -355.527466) (xy 184.986395 -355.514998)
			(xy 185.009532 -355.494724) (xy 185.025584 -355.468482) (xy 185.029856 -355.453696) (xy 185.037245 -355.426649)
			(xy 185.058872 -355.374919) (xy 185.087835 -355.326911) (xy 185.123511 -355.283658) (xy 185.165131 -355.24609)
			(xy 185.211801 -355.215015) (xy 185.262515 -355.191104) (xy 185.316182 -355.174871) (xy 185.371646 -355.166664)
			(xy 185.39968 -355.166168) (xy 185.42693 -355.166697) (xy 185.480875 -355.17445) (xy 185.533167 -355.189801)
			(xy 185.582742 -355.212438) (xy 185.628592 -355.2419) (xy 185.669782 -355.277587) (xy 185.705473 -355.318773)
			(xy 185.734941 -355.364619) (xy 185.757583 -355.414192) (xy 185.772941 -355.466482) (xy 185.7807 -355.520426)
			(xy 185.781188 -355.547676) (xy 185.78071 -355.57525) (xy 185.772761 -355.629823) (xy 185.757038 -355.682682)
			(xy 185.733871 -355.732729) (xy 185.70374 -355.778918) (xy 185.667274 -355.82029) (xy 185.646568 -355.838506)
			(xy 185.635698 -355.848431) (xy 185.61963 -355.873075) (xy 185.611247 -355.901275) (xy 185.611243 -355.930694)
			(xy 185.619617 -355.958897) (xy 185.635678 -355.983546) (xy 185.646568 -355.993446) (xy 185.667251 -356.011687)
			(xy 185.703717 -356.053054) (xy 185.733847 -356.09924) (xy 185.757012 -356.149284) (xy 185.77273 -356.202142)
			(xy 185.780673 -356.256712) (xy 185.780675 -356.311857) (xy 185.772737 -356.366428) (xy 185.757023 -356.419287)
			(xy 185.733862 -356.469333) (xy 185.703736 -356.515521) (xy 185.667273 -356.556891) (xy 185.646568 -356.575106)
			(xy 185.635698 -356.585031) (xy 185.61963 -356.609675) (xy 185.611247 -356.637875) (xy 185.611243 -356.667294)
			(xy 185.619617 -356.695497) (xy 185.635678 -356.720146) (xy 185.646568 -356.730046) (xy 185.66725 -356.748289)
			(xy 185.703724 -356.78965) (xy 185.73386 -356.835833) (xy 185.757032 -356.885875) (xy 185.772754 -356.938732)
			(xy 185.7807 -356.993303) (xy 185.781188 -357.020876) (xy 185.780722 -357.048129) (xy 185.772968 -357.102081)
			(xy 185.757614 -357.15438) (xy 185.734973 -357.203961) (xy 185.705506 -357.249816) (xy 185.669812 -357.291009)
			(xy 185.628619 -357.326703) (xy 185.582765 -357.356171) (xy 185.533184 -357.378813) (xy 185.480885 -357.394167)
			(xy 185.426933 -357.401922) (xy 185.39968 -357.402384) (xy 185.371824 -357.401891) (xy 185.316706 -357.393764)
			(xy 185.263355 -357.377715) (xy 185.212901 -357.354085) (xy 185.166416 -357.323374) (xy 185.124887 -357.286235)
			(xy 185.089195 -357.243456) (xy 185.060097 -357.195945) (xy 185.038211 -357.144711) (xy 185.030618 -357.117904)
			(xy 185.026394 -357.10377) (xy 185.010993 -357.078621) (xy 184.989063 -357.058905) (xy 184.962422 -357.046259)
			(xy 184.933281 -357.041732) (xy 184.918604 -357.043228) (xy 184.905587 -357.044895) (xy 184.879403 -357.046676)
			(xy 184.86628 -357.046784) (xy 184.852131 -357.046693) (xy 184.823908 -357.044657) (xy 184.809892 -357.04272)
			(xy 184.79654 -357.041169) (xy 184.769851 -357.044258) (xy 184.744897 -357.054218) (xy 184.723417 -357.070357)
			(xy 184.706905 -357.091552) (xy 184.696509 -357.116327) (xy 184.694322 -357.129588) (xy 184.690263 -357.156746)
			(xy 184.675284 -357.209576) (xy 184.652888 -357.259714) (xy 184.623536 -357.306124) (xy 184.587835 -357.347847)
			(xy 184.546523 -357.384023) (xy 184.500452 -357.413903) (xy 184.450573 -357.436871) (xy 184.397918 -357.452452)
			(xy 184.343572 -357.460326) (xy 184.316116 -357.460804) (xy 184.288863 -357.46033) (xy 184.234913 -357.452575)
			(xy 184.182615 -357.437221) (xy 184.133034 -357.41458) (xy 184.087181 -357.385113) (xy 184.045988 -357.34942)
			(xy 184.010294 -357.308229) (xy 183.980826 -357.262376) (xy 183.958184 -357.212797) (xy 183.942828 -357.160499)
			(xy 183.935071 -357.106549) (xy 183.934608 -357.079296) (xy 183.935068 -357.051721) (xy 183.943021 -356.997148)
			(xy 183.958747 -356.944288) (xy 183.981918 -356.894242) (xy 184.012052 -356.848052) (xy 184.04852 -356.806682)
			(xy 184.069228 -356.788466) (xy 184.080126 -356.77857) (xy 184.096194 -356.753918) (xy 184.104574 -356.72571)
			(xy 184.104573 -356.696284) (xy 184.096191 -356.668078) (xy 184.080123 -356.643426) (xy 184.069228 -356.633526)
			(xy 184.048532 -356.615298) (xy 184.012059 -356.573934) (xy 183.981924 -356.527748) (xy 183.958756 -356.477703)
			(xy 183.943037 -356.424843) (xy 183.935094 -356.37027) (xy 183.934608 -356.342696) (xy 183.935076 -356.316195)
			(xy 183.942417 -356.263705) (xy 183.956958 -356.212737) (xy 183.978418 -356.164275) (xy 184.006384 -356.119251)
			(xy 184.023 -356.098602) (xy 184.032398 -356.086423) (xy 184.0442 -356.058034) (xy 184.047035 -356.027421)
			(xy 184.040647 -355.997347) (xy 184.025613 -355.970529) (xy 184.003291 -355.949389) (xy 183.989726 -355.942138)
			(xy 183.96604 -355.93003) (xy 183.922058 -355.900108) (xy 183.882776 -355.864239) (xy 183.848991 -355.823151)
			(xy 183.834786 -355.80066) (xy 183.826864 -355.788436) (xy 183.80539 -355.76877) (xy 183.779237 -355.755968)
			(xy 183.750533 -355.751072) (xy 183.721614 -355.754481) (xy 183.70804 -355.759766) (xy 183.684836 -355.76927)
			(xy 183.6365 -355.782615) (xy 183.586808 -355.789337) (xy 183.561736 -355.789738) (xy 183.536666 -355.789326)
			(xy 183.486983 -355.782572) (xy 183.438649 -355.769235) (xy 183.415432 -355.759766) (xy 183.401852 -355.754528)
			(xy 183.372954 -355.751164) (xy 183.344277 -355.756074) (xy 183.318144 -355.76886) (xy 183.296668 -355.788488)
			(xy 183.288686 -355.80066) (xy 183.274117 -355.823791) (xy 183.239274 -355.865912) (xy 183.198651 -355.902491)
			(xy 183.15312 -355.932742) (xy 183.103658 -355.956018) (xy 183.051327 -355.971818) (xy 182.997248 -355.979804)
			(xy 182.942584 -355.979804) (xy 182.888505 -355.971818) (xy 182.836174 -355.956018) (xy 182.786712 -355.932742)
			(xy 182.741181 -355.902491) (xy 182.700558 -355.865912) (xy 182.665715 -355.823791) (xy 182.651146 -355.80066)
			(xy 182.643262 -355.788408) (xy 182.621778 -355.768742) (xy 182.595614 -355.755943) (xy 182.566901 -355.751055)
			(xy 182.537976 -355.754474) (xy 182.5244 -355.759766) (xy 182.501189 -355.769251) (xy 182.452856 -355.782603)
			(xy 182.403167 -355.789333) (xy 182.378096 -355.789738) (xy 182.350213 -355.789177) (xy 182.29507 -355.780865)
			(xy 182.241781 -355.764427) (xy 182.191537 -355.74023) (xy 182.145461 -355.708816) (xy 182.104582 -355.670885)
			(xy 182.069813 -355.627285) (xy 182.04193 -355.57899) (xy 182.021556 -355.527078) (xy 182.009147 -355.47271)
			(xy 182.004979 -355.4171) (xy 176.070138 -355.4171) (xy 176.084641 -355.466479) (xy 176.092401 -355.520425)
			(xy 176.092866 -355.547676) (xy 176.092396 -355.575251) (xy 176.084446 -355.629824) (xy 176.068722 -355.682684)
			(xy 176.045553 -355.73273) (xy 176.015421 -355.77892) (xy 175.978953 -355.820291) (xy 175.958246 -355.838506)
			(xy 175.947369 -355.848427) (xy 175.931289 -355.873069) (xy 175.922898 -355.901272) (xy 175.922894 -355.930697)
			(xy 175.931276 -355.958903) (xy 175.947348 -355.98355) (xy 175.958246 -355.993446) (xy 175.97893 -356.011686)
			(xy 176.015398 -356.053052) (xy 176.04553 -356.099239) (xy 176.068696 -356.149282) (xy 176.084415 -356.202141)
			(xy 176.092358 -356.256712) (xy 176.092361 -356.311857) (xy 176.084422 -356.366429) (xy 176.068707 -356.419288)
			(xy 176.045545 -356.469334) (xy 176.036694 -356.482904) (xy 178.547266 -356.482904) (xy 178.551337 -356.427282)
			(xy 178.563463 -356.372845) (xy 178.583386 -356.320754) (xy 178.610682 -356.272119) (xy 178.644768 -356.227976)
			(xy 178.684917 -356.189267) (xy 178.730275 -356.156816) (xy 178.779875 -356.131315) (xy 178.832659 -356.113308)
			(xy 178.887502 -356.103178) (xy 178.943236 -356.101141) (xy 178.998673 -356.107241) (xy 179.05263 -356.121347)
			(xy 179.103959 -356.143159) (xy 179.151565 -356.172213) (xy 179.194433 -356.207888) (xy 179.23165 -356.249425)
			(xy 179.262423 -356.295938) (xy 179.286095 -356.346435) (xy 179.302163 -356.399842) (xy 179.310283 -356.455018)
			(xy 179.310792 -356.482904) (xy 179.310283 -356.51079) (xy 179.302163 -356.565966) (xy 179.286095 -356.619373)
			(xy 179.262423 -356.66987) (xy 179.23165 -356.716383) (xy 179.194433 -356.75792) (xy 179.151565 -356.793595)
			(xy 179.103959 -356.822649) (xy 179.05263 -356.844461) (xy 178.998673 -356.858567) (xy 178.943236 -356.864667)
			(xy 178.887502 -356.86263) (xy 178.832659 -356.8525) (xy 178.779875 -356.834493) (xy 178.730275 -356.808992)
			(xy 178.684917 -356.776541) (xy 178.644768 -356.737832) (xy 178.610682 -356.693689) (xy 178.583386 -356.645054)
			(xy 178.563463 -356.592963) (xy 178.551337 -356.538526) (xy 178.547266 -356.482904) (xy 176.036694 -356.482904)
			(xy 176.015417 -356.515523) (xy 175.978952 -356.556892) (xy 175.958246 -356.575106) (xy 175.947369 -356.585027)
			(xy 175.931289 -356.609669) (xy 175.922898 -356.637872) (xy 175.922894 -356.667297) (xy 175.931276 -356.695503)
			(xy 175.947348 -356.72015) (xy 175.958246 -356.730046) (xy 175.978943 -356.748272) (xy 176.015413 -356.789639)
			(xy 176.045546 -356.835826) (xy 176.068713 -356.885871) (xy 176.084433 -356.93873) (xy 176.092378 -356.993302)
			(xy 176.092866 -357.020876) (xy 176.092422 -357.04813) (xy 176.084667 -357.102084) (xy 176.069312 -357.154385)
			(xy 176.04667 -357.203968) (xy 176.0172 -357.249823) (xy 175.981504 -357.291017) (xy 175.940308 -357.326711)
			(xy 175.894452 -357.356178) (xy 175.844868 -357.378819) (xy 175.792566 -357.394171) (xy 175.738612 -357.401924)
			(xy 175.711358 -357.402384) (xy 175.683501 -357.401911) (xy 175.628383 -357.393781) (xy 175.575031 -357.377729)
			(xy 175.524577 -357.354095) (xy 175.478092 -357.323382) (xy 175.436563 -357.286241) (xy 175.400871 -357.24346)
			(xy 175.371774 -357.195948) (xy 175.349889 -357.144711) (xy 175.342296 -357.117904) (xy 175.337994 -357.103798)
			(xy 175.322609 -357.078656) (xy 175.300697 -357.058941) (xy 175.274076 -357.046287) (xy 175.244953 -357.041743)
			(xy 175.230282 -357.043228) (xy 175.217265 -357.044897) (xy 175.191081 -357.046677) (xy 175.177958 -357.046784)
			(xy 175.163809 -357.046695) (xy 175.135586 -357.044658) (xy 175.12157 -357.04272) (xy 175.10822 -357.041147)
			(xy 175.081529 -357.044241) (xy 175.056574 -357.054206) (xy 175.035094 -357.070349) (xy 175.018582 -357.091547)
			(xy 175.008187 -357.116326) (xy 175.006 -357.129588) (xy 175.001962 -357.15675) (xy 174.986983 -357.209582)
			(xy 174.964584 -357.259721) (xy 174.935231 -357.306132) (xy 174.899527 -357.347855) (xy 174.858212 -357.384031)
			(xy 174.812138 -357.41391) (xy 174.762257 -357.436877) (xy 174.709599 -357.452457) (xy 174.655251 -357.460327)
			(xy 174.627794 -357.460804) (xy 177.882802 -357.460804) (xy 177.886873 -357.405182) (xy 177.898999 -357.350745)
			(xy 177.918922 -357.298654) (xy 177.946218 -357.250019) (xy 177.980304 -357.205876) (xy 178.020453 -357.167167)
			(xy 178.065811 -357.134716) (xy 178.115411 -357.109215) (xy 178.168195 -357.091208) (xy 178.223038 -357.081078)
			(xy 178.278772 -357.079041) (xy 178.334209 -357.085141) (xy 178.388166 -357.099247) (xy 178.439495 -357.121059)
			(xy 178.487101 -357.150113) (xy 178.529969 -357.185788) (xy 178.567186 -357.227325) (xy 178.597959 -357.273838)
			(xy 178.621631 -357.324335) (xy 178.637699 -357.377742) (xy 178.645819 -357.432918) (xy 178.646328 -357.460804)
			(xy 178.645819 -357.48869) (xy 178.637699 -357.543866) (xy 178.621631 -357.597273) (xy 178.597959 -357.64777)
			(xy 178.567186 -357.694283) (xy 178.529969 -357.73582) (xy 178.487101 -357.771495) (xy 178.439495 -357.800549)
			(xy 178.388166 -357.822361) (xy 178.334209 -357.836467) (xy 178.278772 -357.842567) (xy 178.223038 -357.84053)
			(xy 178.168195 -357.8304) (xy 178.115411 -357.812393) (xy 178.065811 -357.786892) (xy 178.020453 -357.754441)
			(xy 177.980304 -357.715732) (xy 177.946218 -357.671589) (xy 177.918922 -357.622954) (xy 177.898999 -357.570863)
			(xy 177.886873 -357.516426) (xy 177.882802 -357.460804) (xy 174.627794 -357.460804) (xy 174.600542 -357.460328)
			(xy 174.546594 -357.45257) (xy 174.494299 -357.437214) (xy 174.444721 -357.414572) (xy 174.398871 -357.385105)
			(xy 174.357681 -357.349412) (xy 174.321989 -357.308221) (xy 174.292523 -357.26237) (xy 174.269882 -357.212792)
			(xy 174.254528 -357.160496) (xy 174.246772 -357.106548) (xy 174.246286 -357.079296) (xy 174.246754 -357.051722)
			(xy 174.254707 -356.997149) (xy 174.270432 -356.944289) (xy 174.293601 -356.894244) (xy 174.323733 -356.848054)
			(xy 174.3602 -356.806682) (xy 174.380906 -356.788466) (xy 174.391806 -356.778571) (xy 174.407877 -356.753919)
			(xy 174.41626 -356.725711) (xy 174.416259 -356.696284) (xy 174.407875 -356.668076) (xy 174.391803 -356.643425)
			(xy 174.380906 -356.633526) (xy 174.360205 -356.615303) (xy 174.323734 -356.573937) (xy 174.2936 -356.52775)
			(xy 174.270433 -356.477704) (xy 174.254714 -356.424843) (xy 174.246772 -356.37027) (xy 174.246286 -356.342696)
			(xy 174.246759 -356.316196) (xy 174.2541 -356.263705) (xy 174.26864 -356.212738) (xy 174.290099 -356.164275)
			(xy 174.318063 -356.119252) (xy 174.334678 -356.098602) (xy 174.344049 -356.086407) (xy 174.355839 -356.058023)
			(xy 174.35867 -356.027419) (xy 174.352287 -355.997354) (xy 174.337266 -355.97054) (xy 174.31496 -355.949395)
			(xy 174.301404 -355.942138) (xy 174.277714 -355.930037) (xy 174.233734 -355.900113) (xy 174.194453 -355.864242)
			(xy 174.160669 -355.823152) (xy 174.146464 -355.80066) (xy 174.138563 -355.788421) (xy 174.117083 -355.768755)
			(xy 174.090924 -355.755954) (xy 174.062215 -355.751063) (xy 174.033293 -355.754477) (xy 174.019718 -355.759766)
			(xy 173.996504 -355.769246) (xy 173.948173 -355.7826) (xy 173.898485 -355.789332) (xy 173.873414 -355.789738)
			(xy 173.848345 -355.7893) (xy 173.798662 -355.782557) (xy 173.750328 -355.76923) (xy 173.72711 -355.759766)
			(xy 173.713502 -355.75461) (xy 173.684618 -355.751229) (xy 173.655952 -355.756121) (xy 173.629823 -355.768887)
			(xy 173.608347 -355.788496) (xy 173.600364 -355.80066) (xy 173.585795 -355.823791) (xy 173.550952 -355.865912)
			(xy 173.510329 -355.902491) (xy 173.464798 -355.932742) (xy 173.415336 -355.956018) (xy 173.363005 -355.971818)
			(xy 173.308926 -355.979804) (xy 173.254262 -355.979804) (xy 173.200183 -355.971818) (xy 173.147852 -355.956018)
			(xy 173.09839 -355.932742) (xy 173.052859 -355.902491) (xy 173.012236 -355.865912) (xy 172.977393 -355.823791)
			(xy 172.962824 -355.80066) (xy 172.954866 -355.788462) (xy 172.933402 -355.768796) (xy 172.907258 -355.75599)
			(xy 172.878563 -355.751087) (xy 172.849651 -355.754487) (xy 172.836078 -355.759766) (xy 172.812869 -355.769258)
			(xy 172.764536 -355.782607) (xy 172.714846 -355.789335) (xy 172.689774 -355.789738) (xy 172.661892 -355.789175)
			(xy 172.606751 -355.780861) (xy 172.553465 -355.764421) (xy 172.503225 -355.740223) (xy 172.457152 -355.708808)
			(xy 172.416275 -355.670877) (xy 172.381508 -355.627278) (xy 172.353627 -355.578984) (xy 172.333255 -355.527074)
			(xy 172.320847 -355.472708) (xy 172.316679 -355.4171) (xy 126.029608 -355.4171) (xy 126.404624 -355.792024)
			(xy 132.385562 -355.792024) (xy 132.410557 -355.792683) (xy 132.459578 -355.80248) (xy 132.505749 -355.821647)
			(xy 132.547297 -355.849448) (xy 132.565394 -355.8667) (xy 133.181598 -356.482904) (xy 168.858944 -356.482904)
			(xy 168.863015 -356.427282) (xy 168.875141 -356.372845) (xy 168.895064 -356.320754) (xy 168.92236 -356.272119)
			(xy 168.956446 -356.227976) (xy 168.996595 -356.189267) (xy 169.041953 -356.156816) (xy 169.091553 -356.131315)
			(xy 169.144337 -356.113308) (xy 169.19918 -356.103178) (xy 169.254914 -356.101141) (xy 169.310351 -356.107241)
			(xy 169.364308 -356.121347) (xy 169.415637 -356.143159) (xy 169.463243 -356.172213) (xy 169.506111 -356.207888)
			(xy 169.543328 -356.249425) (xy 169.574101 -356.295938) (xy 169.597773 -356.346435) (xy 169.613841 -356.399842)
			(xy 169.621961 -356.455018) (xy 169.62247 -356.482904) (xy 169.621961 -356.51079) (xy 169.613841 -356.565966)
			(xy 169.597773 -356.619373) (xy 169.574101 -356.66987) (xy 169.543328 -356.716383) (xy 169.506111 -356.75792)
			(xy 169.463243 -356.793595) (xy 169.415637 -356.822649) (xy 169.364308 -356.844461) (xy 169.310351 -356.858567)
			(xy 169.254914 -356.864667) (xy 169.19918 -356.86263) (xy 169.144337 -356.8525) (xy 169.091553 -356.834493)
			(xy 169.041953 -356.808992) (xy 168.996595 -356.776541) (xy 168.956446 -356.737832) (xy 168.92236 -356.693689)
			(xy 168.895064 -356.645054) (xy 168.875141 -356.592963) (xy 168.863015 -356.538526) (xy 168.858944 -356.482904)
			(xy 133.181598 -356.482904) (xy 134.14756 -357.448866) (xy 168.19448 -357.448866) (xy 168.198551 -357.393244)
			(xy 168.210677 -357.338807) (xy 168.2306 -357.286716) (xy 168.257896 -357.238081) (xy 168.291982 -357.193938)
			(xy 168.332131 -357.155229) (xy 168.377489 -357.122778) (xy 168.427089 -357.097277) (xy 168.479873 -357.07927)
			(xy 168.534716 -357.06914) (xy 168.59045 -357.067103) (xy 168.645887 -357.073203) (xy 168.699844 -357.087309)
			(xy 168.751173 -357.109121) (xy 168.798779 -357.138175) (xy 168.841647 -357.17385) (xy 168.878864 -357.215387)
			(xy 168.909637 -357.2619) (xy 168.933309 -357.312397) (xy 168.949377 -357.365804) (xy 168.957497 -357.42098)
			(xy 168.958006 -357.448866) (xy 168.957497 -357.476752) (xy 168.949377 -357.531928) (xy 168.933309 -357.585335)
			(xy 168.909637 -357.635832) (xy 168.878864 -357.682345) (xy 168.841647 -357.723882) (xy 168.798779 -357.759557)
			(xy 168.751173 -357.788611) (xy 168.699844 -357.810423) (xy 168.645887 -357.824529) (xy 168.59045 -357.830629)
			(xy 168.534716 -357.828592) (xy 168.479873 -357.818462) (xy 168.427089 -357.800455) (xy 168.377489 -357.774954)
			(xy 168.332131 -357.742503) (xy 168.291982 -357.703794) (xy 168.257896 -357.659651) (xy 168.2306 -357.611016)
			(xy 168.210677 -357.558925) (xy 168.198551 -357.504488) (xy 168.19448 -357.448866) (xy 134.14756 -357.448866)
			(xy 134.690104 -357.99141) (xy 169.66565 -357.99141) (xy 169.666086 -357.966072) (xy 169.672793 -357.915843)
			(xy 169.686091 -357.866943) (xy 169.705744 -357.820235) (xy 169.731409 -357.776539) (xy 169.762632 -357.736625)
			(xy 169.780458 -357.718614) (xy 169.789846 -357.708834) (xy 169.803642 -357.685512) (xy 169.810797 -357.659378)
			(xy 169.810805 -357.632282) (xy 169.803665 -357.606143) (xy 169.789883 -357.582814) (xy 169.780458 -357.573072)
			(xy 169.762627 -357.555065) (xy 169.731397 -357.515153) (xy 169.705728 -357.471458) (xy 169.68607 -357.424748)
			(xy 169.67277 -357.375847) (xy 169.666063 -357.325615) (xy 169.66565 -357.300276) (xy 169.666136 -357.273025)
			(xy 169.673892 -357.219077) (xy 169.689247 -357.166782) (xy 169.711889 -357.117205) (xy 169.741355 -357.071355)
			(xy 169.777046 -357.030164) (xy 169.818237 -356.994473) (xy 169.864087 -356.965007) (xy 169.913664 -356.942365)
			(xy 169.965959 -356.92701) (xy 170.019907 -356.919254) (xy 170.074409 -356.919254) (xy 170.128357 -356.92701)
			(xy 170.180652 -356.942365) (xy 170.230229 -356.965007) (xy 170.276079 -356.994473) (xy 170.31727 -357.030164)
			(xy 170.352961 -357.071355) (xy 170.382427 -357.117205) (xy 170.405069 -357.166782) (xy 170.420424 -357.219077)
			(xy 170.42818 -357.273025) (xy 170.428666 -357.300276) (xy 170.428216 -357.325613) (xy 170.421511 -357.375842)
			(xy 170.408216 -357.424741) (xy 170.388565 -357.47145) (xy 170.362903 -357.515146) (xy 170.331683 -357.555061)
			(xy 170.313858 -357.573072) (xy 170.30443 -357.582799) (xy 170.290719 -357.606154) (xy 170.283619 -357.632289)
			(xy 170.283627 -357.659371) (xy 170.290743 -357.685502) (xy 170.304467 -357.708849) (xy 170.313858 -357.718614)
			(xy 170.331685 -357.736625) (xy 170.362915 -357.776536) (xy 170.388585 -357.820231) (xy 170.408243 -357.86694)
			(xy 170.421543 -357.91584) (xy 170.428252 -357.966071) (xy 170.428666 -357.99141) (xy 170.42818 -358.018661)
			(xy 170.420424 -358.072609) (xy 170.405069 -358.124904) (xy 170.382427 -358.174481) (xy 170.352961 -358.220331)
			(xy 170.31727 -358.261522) (xy 170.276079 -358.297213) (xy 170.230229 -358.326679) (xy 170.180652 -358.349321)
			(xy 170.128357 -358.364676) (xy 170.074409 -358.372432) (xy 170.019907 -358.372432) (xy 169.965959 -358.364676)
			(xy 169.913664 -358.349321) (xy 169.864087 -358.326679) (xy 169.818237 -358.297213) (xy 169.777046 -358.261522)
			(xy 169.741355 -358.220331) (xy 169.711889 -358.174481) (xy 169.689247 -358.124904) (xy 169.673892 -358.072609)
			(xy 169.666136 -358.018661) (xy 169.66565 -357.99141) (xy 134.690104 -357.99141) (xy 135.18769 -358.488996)
			(xy 164.69868 -358.488996) (xy 164.723663 -358.489625) (xy 164.772671 -358.499361) (xy 164.818841 -358.518463)
			(xy 164.860402 -358.546198) (xy 164.878512 -358.563418) (xy 166.143686 -359.828592) (xy 170.395138 -359.828592)
			(xy 170.808904 -359.414826) (xy 170.808904 -358.26827) (xy 170.789283 -358.250094) (xy 170.754783 -358.209224)
			(xy 170.726325 -358.16394) (xy 170.704467 -358.115126) (xy 170.689636 -358.063739) (xy 170.682123 -358.010786)
			(xy 170.68165 -357.984044) (xy 170.682136 -357.956793) (xy 170.689892 -357.902845) (xy 170.705247 -357.85055)
			(xy 170.727889 -357.800973) (xy 170.757355 -357.755123) (xy 170.793046 -357.713932) (xy 170.834237 -357.678241)
			(xy 170.880087 -357.648775) (xy 170.929664 -357.626133) (xy 170.981959 -357.610778) (xy 171.035907 -357.603022)
			(xy 171.090409 -357.603022) (xy 171.144357 -357.610778) (xy 171.196652 -357.626133) (xy 171.246229 -357.648775)
			(xy 171.292079 -357.678241) (xy 171.33327 -357.713932) (xy 171.368961 -357.755123) (xy 171.398427 -357.800973)
			(xy 171.421069 -357.85055) (xy 171.436424 -357.902845) (xy 171.44418 -357.956793) (xy 171.444666 -357.984044)
			(xy 171.444204 -358.010788) (xy 171.43671 -358.063749) (xy 171.421889 -358.115144) (xy 171.400032 -358.163963)
			(xy 171.371567 -358.209249) (xy 171.337054 -358.250114) (xy 171.317412 -358.26827) (xy 171.317412 -359.520236)
			(xy 171.316815 -359.54522) (xy 171.307069 -359.59423) (xy 171.287958 -359.6404) (xy 171.260214 -359.681959)
			(xy 171.24299 -359.700068) (xy 170.68038 -360.262678) (xy 170.662296 -360.279928) (xy 170.620727 -360.307663)
			(xy 170.574549 -360.326763) (xy 170.525534 -360.336494) (xy 170.500548 -360.3371) (xy 166.038276 -360.3371)
			(xy 166.013294 -360.33647) (xy 165.964287 -360.32673) (xy 165.918118 -360.307628) (xy 165.876556 -360.279896)
			(xy 165.858444 -360.262678) (xy 164.59327 -358.997504) (xy 135.08228 -358.997504) (xy 135.057296 -358.996899)
			(xy 135.008287 -358.987156) (xy 134.962117 -358.968047) (xy 134.920557 -358.940305) (xy 134.902448 -358.923082)
			(xy 132.280152 -356.30104) (xy 126.299214 -356.30104) (xy 126.274218 -356.300406) (xy 126.225194 -356.290603)
			(xy 126.179024 -356.271429) (xy 126.137478 -356.24362) (xy 126.119382 -356.226364) (xy 125.08103 -355.188012)
			(xy 122.773186 -355.188012) (xy 121.92635 -356.034848) (xy 122.442222 -356.034848) (xy 122.446293 -355.979226)
			(xy 122.458419 -355.924789) (xy 122.478342 -355.872698) (xy 122.505638 -355.824063) (xy 122.539724 -355.77992)
			(xy 122.579873 -355.741211) (xy 122.625231 -355.70876) (xy 122.674831 -355.683259) (xy 122.727615 -355.665252)
			(xy 122.782458 -355.655122) (xy 122.838192 -355.653085) (xy 122.893629 -355.659185) (xy 122.947586 -355.673291)
			(xy 122.998915 -355.695103) (xy 123.046521 -355.724157) (xy 123.089389 -355.759832) (xy 123.126606 -355.801369)
			(xy 123.157379 -355.847882) (xy 123.181051 -355.898379) (xy 123.197119 -355.951786) (xy 123.205239 -356.006962)
			(xy 123.205748 -356.034848) (xy 123.205239 -356.062734) (xy 123.197119 -356.11791) (xy 123.181051 -356.171317)
			(xy 123.157379 -356.221814) (xy 123.126606 -356.268327) (xy 123.089389 -356.309864) (xy 123.046521 -356.345539)
			(xy 122.998915 -356.374593) (xy 122.947586 -356.396405) (xy 122.893629 -356.410511) (xy 122.838192 -356.416611)
			(xy 122.782458 -356.414574) (xy 122.727615 -356.404444) (xy 122.674831 -356.386437) (xy 122.625231 -356.360936)
			(xy 122.579873 -356.328485) (xy 122.539724 -356.289776) (xy 122.505638 -356.245633) (xy 122.478342 -356.196998)
			(xy 122.458419 -356.144907) (xy 122.446293 -356.09047) (xy 122.442222 -356.034848) (xy 121.92635 -356.034848)
			(xy 121.183146 -356.778052) (xy 121.16506 -356.795319) (xy 121.123512 -356.823129) (xy 121.077338 -356.8423)
			(xy 121.028311 -356.852094) (xy 121.003314 -356.852728) (xy 119.135398 -356.852728) (xy 119.008878 -356.97922)
			(xy 122.843796 -356.97922) (xy 122.847867 -356.923598) (xy 122.859993 -356.869161) (xy 122.879916 -356.81707)
			(xy 122.907212 -356.768435) (xy 122.941298 -356.724292) (xy 122.981447 -356.685583) (xy 123.026805 -356.653132)
			(xy 123.076405 -356.627631) (xy 123.129189 -356.609624) (xy 123.184032 -356.599494) (xy 123.239766 -356.597457)
			(xy 123.295203 -356.603557) (xy 123.34916 -356.617663) (xy 123.400489 -356.639475) (xy 123.448095 -356.668529)
			(xy 123.490963 -356.704204) (xy 123.52818 -356.745741) (xy 123.558953 -356.792254) (xy 123.582625 -356.842751)
			(xy 123.598693 -356.896158) (xy 123.606813 -356.951334) (xy 123.607322 -356.97922) (xy 123.606813 -357.007106)
			(xy 123.598693 -357.062282) (xy 123.582625 -357.115689) (xy 123.558953 -357.166186) (xy 123.52818 -357.212699)
			(xy 123.490963 -357.254236) (xy 123.448095 -357.289911) (xy 123.400489 -357.318965) (xy 123.34916 -357.340777)
			(xy 123.295203 -357.354883) (xy 123.239766 -357.360983) (xy 123.184032 -357.358946) (xy 123.129189 -357.348816)
			(xy 123.076405 -357.330809) (xy 123.026805 -357.305308) (xy 122.981447 -357.272857) (xy 122.941298 -357.234148)
			(xy 122.907212 -357.190005) (xy 122.879916 -357.14137) (xy 122.859993 -357.089279) (xy 122.847867 -357.034842)
			(xy 122.843796 -356.97922) (xy 119.008878 -356.97922) (xy 117.990112 -357.99776) (xy 117.971999 -358.014997)
			(xy 117.930461 -358.042812) (xy 117.884295 -358.061991) (xy 117.835275 -358.071796) (xy 117.81028 -358.072436)
			(xy 116.45138 -358.072436) (xy 116.426383 -358.071824) (xy 116.377358 -358.062014) (xy 116.331187 -358.042834)
			(xy 116.289643 -358.015019) (xy 116.271548 -357.99776) (xy 115.85321 -357.579676) (xy 115.66779 -357.579676)
			(xy 115.453668 -357.793798) (xy 115.453668 -358.13111) (xy 119.24868 -358.13111) (xy 119.252751 -358.075488)
			(xy 119.264877 -358.021051) (xy 119.2848 -357.96896) (xy 119.312096 -357.920325) (xy 119.346182 -357.876182)
			(xy 119.386331 -357.837473) (xy 119.431689 -357.805022) (xy 119.481289 -357.779521) (xy 119.534073 -357.761514)
			(xy 119.588916 -357.751384) (xy 119.64465 -357.749347) (xy 119.700087 -357.755447) (xy 119.754044 -357.769553)
			(xy 119.805373 -357.791365) (xy 119.852979 -357.820419) (xy 119.895847 -357.856094) (xy 119.933064 -357.897631)
			(xy 119.963837 -357.944144) (xy 119.987509 -357.994641) (xy 120.003577 -358.048048) (xy 120.011697 -358.103224)
			(xy 120.012206 -358.13111) (xy 120.011697 -358.158996) (xy 120.003577 -358.214172) (xy 119.987509 -358.267579)
			(xy 119.963837 -358.318076) (xy 119.933064 -358.364589) (xy 119.895847 -358.406126) (xy 119.852979 -358.441801)
			(xy 119.805373 -358.470855) (xy 119.754044 -358.492667) (xy 119.700087 -358.506773) (xy 119.64465 -358.512873)
			(xy 119.588916 -358.510836) (xy 119.534073 -358.500706) (xy 119.481289 -358.482699) (xy 119.431689 -358.457198)
			(xy 119.386331 -358.424747) (xy 119.346182 -358.386038) (xy 119.312096 -358.341895) (xy 119.2848 -358.29326)
			(xy 119.264877 -358.241169) (xy 119.252751 -358.186732) (xy 119.24868 -358.13111) (xy 115.453668 -358.13111)
			(xy 115.453668 -358.539796) (xy 115.453032 -358.564792) (xy 115.443228 -358.613815) (xy 115.424054 -358.659985)
			(xy 115.396247 -358.701532) (xy 115.378992 -358.719628) (xy 114.715798 -359.382822) (xy 116.061996 -359.382822)
			(xy 116.066067 -359.3272) (xy 116.078193 -359.272763) (xy 116.098116 -359.220672) (xy 116.125412 -359.172037)
			(xy 116.159498 -359.127894) (xy 116.199647 -359.089185) (xy 116.245005 -359.056734) (xy 116.294605 -359.031233)
			(xy 116.347389 -359.013226) (xy 116.402232 -359.003096) (xy 116.457966 -359.001059) (xy 116.513403 -359.007159)
			(xy 116.56736 -359.021265) (xy 116.618689 -359.043077) (xy 116.666295 -359.072131) (xy 116.709163 -359.107806)
			(xy 116.74638 -359.149343) (xy 116.777153 -359.195856) (xy 116.800825 -359.246353) (xy 116.816893 -359.29976)
			(xy 116.825013 -359.354936) (xy 116.825522 -359.382822) (xy 116.825013 -359.410708) (xy 116.816893 -359.465884)
			(xy 116.800825 -359.519291) (xy 116.777153 -359.569788) (xy 116.74638 -359.616301) (xy 116.709163 -359.657838)
			(xy 116.666295 -359.693513) (xy 116.618689 -359.722567) (xy 116.56736 -359.744379) (xy 116.513403 -359.758485)
			(xy 116.457966 -359.764585) (xy 116.402232 -359.762548) (xy 116.347389 -359.752418) (xy 116.294605 -359.734411)
			(xy 116.245005 -359.70891) (xy 116.199647 -359.676459) (xy 116.159498 -359.63775) (xy 116.125412 -359.593607)
			(xy 116.098116 -359.544972) (xy 116.078193 -359.492881) (xy 116.066067 -359.438444) (xy 116.061996 -359.382822)
			(xy 114.715798 -359.382822) (xy 114.216434 -359.882186) (xy 114.198328 -359.899412) (xy 114.156767 -359.927151)
			(xy 114.110596 -359.946257) (xy 114.061586 -359.955997) (xy 114.036602 -359.956608) (xy 113.23955 -359.956608)
			(xy 113.23193 -359.959148) (xy 113.20372 -359.967581) (xy 113.145544 -359.976638) (xy 113.116106 -359.977182)
			(xy 113.088851 -359.976772) (xy 113.034896 -359.969015) (xy 112.982593 -359.953658) (xy 112.933009 -359.931014)
			(xy 112.887152 -359.901545) (xy 112.845956 -359.865848) (xy 112.810259 -359.824653) (xy 112.780788 -359.778796)
			(xy 112.758144 -359.729212) (xy 112.742787 -359.67691) (xy 112.735029 -359.622955) (xy 106.056684 -359.622955)
			(xy 106.056684 -360.504994) (xy 106.163135 -360.61142) (xy 112.831624 -360.61142) (xy 112.835695 -360.555798)
			(xy 112.847821 -360.501361) (xy 112.867744 -360.44927) (xy 112.89504 -360.400635) (xy 112.929126 -360.356492)
			(xy 112.969275 -360.317783) (xy 113.014633 -360.285332) (xy 113.064233 -360.259831) (xy 113.117017 -360.241824)
			(xy 113.17186 -360.231694) (xy 113.227594 -360.229657) (xy 113.283031 -360.235757) (xy 113.336988 -360.249863)
			(xy 113.388317 -360.271675) (xy 113.391471 -360.2736) (xy 118.713758 -360.2736) (xy 118.714176 -360.246539)
			(xy 118.721807 -360.192957) (xy 118.736931 -360.14099) (xy 118.759244 -360.091681) (xy 118.788299 -360.046018)
			(xy 118.823513 -360.004918) (xy 118.86418 -359.969204) (xy 118.909484 -359.939593) (xy 118.958516 -359.916678)
			(xy 118.984268 -359.908348) (xy 119.662702 -359.229914) (xy 120.51665 -359.229914) (xy 121.872248 -357.874316)
			(xy 122.142504 -357.874316) (xy 122.160682 -357.854625) (xy 122.201609 -357.820028) (xy 122.246974 -357.791497)
			(xy 122.295884 -357.769595) (xy 122.347378 -357.754751) (xy 122.400443 -357.747259) (xy 122.427238 -357.746808)
			(xy 122.454503 -357.747357) (xy 122.508479 -357.755122) (xy 122.5608 -357.77049) (xy 122.610401 -357.793146)
			(xy 122.656274 -357.822631) (xy 122.697483 -357.858343) (xy 122.733192 -357.899557) (xy 122.762672 -357.945432)
			(xy 122.785323 -357.995036) (xy 122.800686 -358.047358) (xy 122.808446 -358.101334) (xy 122.808446 -358.155865)
			(xy 122.800686 -358.209842) (xy 122.785323 -358.262164) (xy 122.762672 -358.311768) (xy 122.733192 -358.357643)
			(xy 122.697483 -358.398857) (xy 122.656274 -358.434569) (xy 122.610401 -358.464054) (xy 122.5608 -358.48671)
			(xy 122.508479 -358.502078) (xy 122.454503 -358.509843) (xy 122.427238 -358.510332) (xy 122.400446 -358.509834)
			(xy 122.347388 -358.502335) (xy 122.2959 -358.487492) (xy 122.246993 -358.465598) (xy 122.201626 -358.437081)
			(xy 122.160691 -358.402503) (xy 122.142504 -358.382824) (xy 122.083068 -358.382824) (xy 121.501408 -358.964484)
			(xy 122.787916 -358.964484) (xy 122.791987 -358.908862) (xy 122.804113 -358.854425) (xy 122.824036 -358.802334)
			(xy 122.851332 -358.753699) (xy 122.885418 -358.709556) (xy 122.925567 -358.670847) (xy 122.970925 -358.638396)
			(xy 123.020525 -358.612895) (xy 123.073309 -358.594888) (xy 123.128152 -358.584758) (xy 123.183886 -358.582721)
			(xy 123.239323 -358.588821) (xy 123.29328 -358.602927) (xy 123.344609 -358.624739) (xy 123.392215 -358.653793)
			(xy 123.435083 -358.689468) (xy 123.4723 -358.731005) (xy 123.503073 -358.777518) (xy 123.526745 -358.828015)
			(xy 123.542813 -358.881422) (xy 123.550933 -358.936598) (xy 123.551442 -358.964484) (xy 123.550933 -358.99237)
			(xy 123.542813 -359.047546) (xy 123.526745 -359.100953) (xy 123.503073 -359.15145) (xy 123.4723 -359.197963)
			(xy 123.435083 -359.2395) (xy 123.392215 -359.275175) (xy 123.344609 -359.304229) (xy 123.29328 -359.326041)
			(xy 123.239323 -359.340147) (xy 123.183886 -359.346247) (xy 123.128152 -359.34421) (xy 123.073309 -359.33408)
			(xy 123.020525 -359.316073) (xy 122.970925 -359.290572) (xy 122.925567 -359.258121) (xy 122.885418 -359.219412)
			(xy 122.851332 -359.175269) (xy 122.824036 -359.126634) (xy 122.804113 -359.074543) (xy 122.791987 -359.020106)
			(xy 122.787916 -358.964484) (xy 121.501408 -358.964484) (xy 120.72747 -359.738422) (xy 119.873522 -359.738422)
			(xy 119.466614 -360.14533) (xy 119.466614 -360.183938) (xy 119.471606 -360.206016) (xy 119.476949 -360.250967)
			(xy 119.477282 -360.2736) (xy 119.476796 -360.300869) (xy 119.469034 -360.354853) (xy 119.453669 -360.407183)
			(xy 119.431012 -360.456793) (xy 119.401526 -360.502674) (xy 119.365811 -360.543891) (xy 119.324594 -360.579606)
			(xy 119.278713 -360.609092) (xy 119.229103 -360.631749) (xy 119.176773 -360.647114) (xy 119.122789 -360.654876)
			(xy 119.068251 -360.654876) (xy 119.014267 -360.647114) (xy 118.961937 -360.631749) (xy 118.912327 -360.609092)
			(xy 118.866446 -360.579606) (xy 118.825229 -360.543891) (xy 118.789514 -360.502674) (xy 118.760028 -360.456793)
			(xy 118.737371 -360.407183) (xy 118.722006 -360.354853) (xy 118.714244 -360.300869) (xy 118.713758 -360.2736)
			(xy 113.391471 -360.2736) (xy 113.435923 -360.300729) (xy 113.478791 -360.336404) (xy 113.516008 -360.377941)
			(xy 113.546781 -360.424454) (xy 113.570453 -360.474951) (xy 113.586521 -360.528358) (xy 113.594641 -360.583534)
			(xy 113.59515 -360.61142) (xy 113.594641 -360.639306) (xy 113.588577 -360.680508) (xy 128.966466 -360.680508)
			(xy 128.970537 -360.624886) (xy 128.982663 -360.570449) (xy 129.002586 -360.518358) (xy 129.029882 -360.469723)
			(xy 129.063968 -360.42558) (xy 129.104117 -360.386871) (xy 129.149475 -360.35442) (xy 129.199075 -360.328919)
			(xy 129.251859 -360.310912) (xy 129.306702 -360.300782) (xy 129.362436 -360.298745) (xy 129.417873 -360.304845)
			(xy 129.47183 -360.318951) (xy 129.523159 -360.340763) (xy 129.570765 -360.369817) (xy 129.613633 -360.405492)
			(xy 129.65085 -360.447029) (xy 129.681623 -360.493542) (xy 129.705295 -360.544039) (xy 129.721363 -360.597446)
			(xy 129.729483 -360.652622) (xy 129.729992 -360.680508) (xy 129.729483 -360.708394) (xy 129.721363 -360.76357)
			(xy 129.705295 -360.816977) (xy 129.681623 -360.867474) (xy 129.65085 -360.913987) (xy 129.613633 -360.955524)
			(xy 129.570765 -360.991199) (xy 129.523159 -361.020253) (xy 129.47183 -361.042065) (xy 129.417873 -361.056171)
			(xy 129.362436 -361.062271) (xy 129.306702 -361.060234) (xy 129.251859 -361.050104) (xy 129.199075 -361.032097)
			(xy 129.149475 -361.006596) (xy 129.104117 -360.974145) (xy 129.063968 -360.935436) (xy 129.029882 -360.891293)
			(xy 129.002586 -360.842658) (xy 128.982663 -360.790567) (xy 128.970537 -360.73613) (xy 128.966466 -360.680508)
			(xy 113.588577 -360.680508) (xy 113.586521 -360.694482) (xy 113.570453 -360.747889) (xy 113.546781 -360.798386)
			(xy 113.516008 -360.844899) (xy 113.478791 -360.886436) (xy 113.435923 -360.922111) (xy 113.388317 -360.951165)
			(xy 113.336988 -360.972977) (xy 113.283031 -360.987083) (xy 113.227594 -360.993183) (xy 113.17186 -360.991146)
			(xy 113.117017 -360.981016) (xy 113.064233 -360.963009) (xy 113.014633 -360.937508) (xy 112.969275 -360.905057)
			(xy 112.929126 -360.866348) (xy 112.89504 -360.822205) (xy 112.867744 -360.77357) (xy 112.847821 -360.721479)
			(xy 112.835695 -360.667042) (xy 112.831624 -360.61142) (xy 106.163135 -360.61142) (xy 106.684975 -361.133136)
			(xy 121.446286 -361.133136) (xy 121.450375 -361.077254) (xy 121.462558 -361.022564) (xy 121.482574 -360.97023)
			(xy 121.509997 -360.921368) (xy 121.544242 -360.87702) (xy 121.584578 -360.83813) (xy 121.630148 -360.805528)
			(xy 121.679979 -360.779909) (xy 121.733009 -360.761817) (xy 121.788107 -360.75164) (xy 121.844101 -360.749594)
			(xy 121.899796 -360.755722) (xy 121.954005 -360.769894) (xy 122.005573 -360.791808) (xy 122.053401 -360.820997)
			(xy 122.096469 -360.856838) (xy 122.133859 -360.898568) (xy 122.164775 -360.945298) (xy 122.188558 -360.996031)
			(xy 122.2047 -361.049687) (xy 122.212859 -361.105121) (xy 122.21337 -361.133136) (xy 122.212859 -361.161151)
			(xy 122.2047 -361.216585) (xy 122.188558 -361.270241) (xy 122.164775 -361.320974) (xy 122.133859 -361.367704)
			(xy 122.096469 -361.409434) (xy 122.053401 -361.445275) (xy 122.005573 -361.474464) (xy 121.954005 -361.496378)
			(xy 121.899796 -361.51055) (xy 121.844101 -361.516678) (xy 121.788107 -361.514632) (xy 121.733009 -361.504455)
			(xy 121.679979 -361.486363) (xy 121.630148 -361.460744) (xy 121.584578 -361.428142) (xy 121.544242 -361.389252)
			(xy 121.509997 -361.344904) (xy 121.482574 -361.296042) (xy 121.462558 -361.243708) (xy 121.450375 -361.189018)
			(xy 121.446286 -361.133136) (xy 106.684975 -361.133136) (xy 107.096553 -361.544616) (xy 112.355882 -361.544616)
			(xy 112.359953 -361.488994) (xy 112.372079 -361.434557) (xy 112.392002 -361.382466) (xy 112.419298 -361.333831)
			(xy 112.453384 -361.289688) (xy 112.493533 -361.250979) (xy 112.538891 -361.218528) (xy 112.588491 -361.193027)
			(xy 112.641275 -361.17502) (xy 112.696118 -361.16489) (xy 112.751852 -361.162853) (xy 112.807289 -361.168953)
			(xy 112.861246 -361.183059) (xy 112.912575 -361.204871) (xy 112.960181 -361.233925) (xy 113.003049 -361.2696)
			(xy 113.040266 -361.311137) (xy 113.071039 -361.35765) (xy 113.094711 -361.408147) (xy 113.110779 -361.461554)
			(xy 113.118899 -361.51673) (xy 113.119408 -361.544616) (xy 113.118899 -361.572502) (xy 113.110779 -361.627678)
			(xy 113.094711 -361.681085) (xy 113.071039 -361.731582) (xy 113.040266 -361.778095) (xy 113.003049 -361.819632)
			(xy 112.960181 -361.855307) (xy 112.912575 -361.884361) (xy 112.861246 -361.906173) (xy 112.807289 -361.920279)
			(xy 112.751852 -361.926379) (xy 112.696118 -361.924342) (xy 112.641275 -361.914212) (xy 112.588491 -361.896205)
			(xy 112.538891 -361.870704) (xy 112.493533 -361.838253) (xy 112.453384 -361.799544) (xy 112.419298 -361.755401)
			(xy 112.392002 -361.706766) (xy 112.372079 -361.654675) (xy 112.359953 -361.600238) (xy 112.355882 -361.544616)
			(xy 107.096553 -361.544616) (xy 107.12704 -361.575096) (xy 107.741466 -361.575096) (xy 107.750864 -361.57535)
			(xy 107.925616 -361.57535) (xy 108.048044 -361.697778) (xy 108.055156 -361.70489) (xy 108.780326 -362.43006)
			(xy 111.034322 -362.43006) (xy 111.034808 -362.402809) (xy 111.042564 -362.348861) (xy 111.057919 -362.296566)
			(xy 111.080561 -362.246989) (xy 111.110027 -362.201139) (xy 111.145718 -362.159948) (xy 111.186909 -362.124257)
			(xy 111.232759 -362.094791) (xy 111.282336 -362.072149) (xy 111.334631 -362.056794) (xy 111.388579 -362.049038)
			(xy 111.443081 -362.049038) (xy 111.497029 -362.056794) (xy 111.549324 -362.072149) (xy 111.598901 -362.094791)
			(xy 111.602441 -362.097066) (xy 128.08534 -362.097066) (xy 128.089411 -362.041444) (xy 128.101537 -361.987007)
			(xy 128.12146 -361.934916) (xy 128.148756 -361.886281) (xy 128.182842 -361.842138) (xy 128.222991 -361.803429)
			(xy 128.268349 -361.770978) (xy 128.317949 -361.745477) (xy 128.370733 -361.72747) (xy 128.425576 -361.71734)
			(xy 128.48131 -361.715303) (xy 128.536747 -361.721403) (xy 128.590704 -361.735509) (xy 128.642033 -361.757321)
			(xy 128.689639 -361.786375) (xy 128.732507 -361.82205) (xy 128.769724 -361.863587) (xy 128.800497 -361.9101)
			(xy 128.824169 -361.960597) (xy 128.840237 -362.014004) (xy 128.848357 -362.06918) (xy 128.848866 -362.097066)
			(xy 128.848357 -362.124952) (xy 128.840237 -362.180128) (xy 128.824169 -362.233535) (xy 128.800497 -362.284032)
			(xy 128.769724 -362.330545) (xy 128.732507 -362.372082) (xy 128.689639 -362.407757) (xy 128.642033 -362.436811)
			(xy 128.590704 -362.458623) (xy 128.536747 -362.472729) (xy 128.48131 -362.478829) (xy 128.425576 -362.476792)
			(xy 128.370733 -362.466662) (xy 128.317949 -362.448655) (xy 128.268349 -362.423154) (xy 128.222991 -362.390703)
			(xy 128.182842 -362.351994) (xy 128.148756 -362.307851) (xy 128.12146 -362.259216) (xy 128.101537 -362.207125)
			(xy 128.089411 -362.152688) (xy 128.08534 -362.097066) (xy 111.602441 -362.097066) (xy 111.644751 -362.124257)
			(xy 111.685942 -362.159948) (xy 111.721633 -362.201139) (xy 111.751099 -362.246989) (xy 111.773741 -362.296566)
			(xy 111.789096 -362.348861) (xy 111.796852 -362.402809) (xy 111.797338 -362.43006) (xy 111.796939 -362.454636)
			(xy 111.790622 -362.503382) (xy 111.7781 -362.550913) (xy 111.759581 -362.596444) (xy 111.747808 -362.61802)
			(xy 111.728758 -362.651548) (xy 112.823498 -363.746288) (xy 112.931702 -363.746288) (xy 112.931702 -363.666786)
			(xy 112.907318 -363.6518) (xy 112.883589 -363.636933) (xy 112.840417 -363.601273) (xy 112.802922 -363.559684)
			(xy 112.77191 -363.51306) (xy 112.748048 -363.462403) (xy 112.731849 -363.408802) (xy 112.723661 -363.353408)
			(xy 112.723168 -363.32541) (xy 112.723654 -363.298159) (xy 112.73141 -363.244211) (xy 112.746765 -363.191916)
			(xy 112.769407 -363.142339) (xy 112.798873 -363.096489) (xy 112.834564 -363.055298) (xy 112.875755 -363.019607)
			(xy 112.921605 -362.990141) (xy 112.971182 -362.967499) (xy 113.023477 -362.952144) (xy 113.077425 -362.944388)
			(xy 113.131927 -362.944388) (xy 113.185875 -362.952144) (xy 113.23817 -362.967499) (xy 113.287747 -362.990141)
			(xy 113.333597 -363.019607) (xy 113.374788 -363.055298) (xy 113.410479 -363.096489) (xy 113.439945 -363.142339)
			(xy 113.462587 -363.191916) (xy 113.477942 -363.244211) (xy 113.485698 -363.298159) (xy 113.486184 -363.32541)
			(xy 113.485632 -363.354524) (xy 113.476801 -363.412079) (xy 113.45933 -363.467625) (xy 113.433624 -363.519873)
			(xy 113.432134 -363.522006) (xy 115.599208 -363.522006) (xy 115.603279 -363.466384) (xy 115.615405 -363.411947)
			(xy 115.635328 -363.359856) (xy 115.662624 -363.311221) (xy 115.69671 -363.267078) (xy 115.736859 -363.228369)
			(xy 115.782217 -363.195918) (xy 115.831817 -363.170417) (xy 115.884601 -363.15241) (xy 115.939444 -363.14228)
			(xy 115.995178 -363.140243) (xy 116.050615 -363.146343) (xy 116.104572 -363.160449) (xy 116.155901 -363.182261)
			(xy 116.203507 -363.211315) (xy 116.246375 -363.24699) (xy 116.283592 -363.288527) (xy 116.314365 -363.33504)
			(xy 116.338037 -363.385537) (xy 116.354105 -363.438944) (xy 116.362225 -363.49412) (xy 116.362734 -363.522006)
			(xy 116.362225 -363.549892) (xy 116.354105 -363.605068) (xy 116.338037 -363.658475) (xy 116.314365 -363.708972)
			(xy 116.283592 -363.755485) (xy 116.246375 -363.797022) (xy 116.203507 -363.832697) (xy 116.155901 -363.861751)
			(xy 116.104572 -363.883563) (xy 116.050615 -363.897669) (xy 115.995178 -363.903769) (xy 115.939444 -363.901732)
			(xy 115.884601 -363.891602) (xy 115.831817 -363.873595) (xy 115.782217 -363.848094) (xy 115.736859 -363.815643)
			(xy 115.69671 -363.776934) (xy 115.662624 -363.732791) (xy 115.635328 -363.684156) (xy 115.615405 -363.632065)
			(xy 115.603279 -363.577628) (xy 115.599208 -363.522006) (xy 113.432134 -363.522006) (xy 113.400281 -363.56761)
			(xy 113.360074 -363.609728) (xy 113.33734 -363.627924) (xy 113.326754 -363.63654) (xy 113.310313 -363.65832)
			(xy 113.300227 -363.683677) (xy 113.297217 -363.710799) (xy 113.301498 -363.73775) (xy 113.312764 -363.762605)
			(xy 113.33021 -363.783588) (xy 113.34115 -363.791754) (xy 113.350338 -363.798309) (xy 113.367638 -363.812805)
			(xy 113.375694 -363.82071) (xy 113.725045 -364.16996) (xy 114.192302 -364.16996) (xy 114.196373 -364.114338)
			(xy 114.208499 -364.059901) (xy 114.228422 -364.00781) (xy 114.255718 -363.959175) (xy 114.289804 -363.915032)
			(xy 114.329953 -363.876323) (xy 114.375311 -363.843872) (xy 114.424911 -363.818371) (xy 114.477695 -363.800364)
			(xy 114.532538 -363.790234) (xy 114.588272 -363.788197) (xy 114.643709 -363.794297) (xy 114.697666 -363.808403)
			(xy 114.748995 -363.830215) (xy 114.796601 -363.859269) (xy 114.839469 -363.894944) (xy 114.876686 -363.936481)
			(xy 114.907459 -363.982994) (xy 114.931131 -364.033491) (xy 114.947199 -364.086898) (xy 114.955319 -364.142074)
			(xy 114.955828 -364.16996) (xy 114.955319 -364.197846) (xy 114.947199 -364.253022) (xy 114.931131 -364.306429)
			(xy 114.907459 -364.356926) (xy 114.876686 -364.403439) (xy 114.839469 -364.444976) (xy 114.796601 -364.480651)
			(xy 114.748995 -364.509705) (xy 114.697666 -364.531517) (xy 114.643709 -364.545623) (xy 114.588272 -364.551723)
			(xy 114.532538 -364.549686) (xy 114.477695 -364.539556) (xy 114.424911 -364.521549) (xy 114.375311 -364.496048)
			(xy 114.329953 -364.463597) (xy 114.289804 -364.424888) (xy 114.255718 -364.380745) (xy 114.228422 -364.33211)
			(xy 114.208499 -364.280019) (xy 114.196373 -364.225582) (xy 114.192302 -364.16996) (xy 113.725045 -364.16996)
			(xy 114.25047 -364.695232) (xy 117.883178 -364.695232) (xy 119.116348 -363.462316) (xy 119.134432 -363.445047)
			(xy 119.175981 -363.417238) (xy 119.222155 -363.398069) (xy 119.271183 -363.388274) (xy 119.29618 -363.38764)
			(xy 129.952496 -363.38764) (xy 134.014972 -359.325418) (xy 134.033076 -359.30819) (xy 134.074638 -359.280451)
			(xy 134.12081 -359.261346) (xy 134.16982 -359.251606) (xy 134.194804 -359.250996) (xy 157.52445 -359.250996)
			(xy 157.549435 -359.251582) (xy 157.598445 -359.261331) (xy 157.644615 -359.280446) (xy 157.686174 -359.308192)
			(xy 157.704282 -359.325418) (xy 158.969456 -360.590592) (xy 171.40428 -360.590592) (xy 172.49648 -359.498392)
			(xy 172.49648 -358.285796) (xy 172.360336 -358.149652) (xy 172.339621 -358.166392) (xy 172.294448 -358.194602)
			(xy 172.245791 -358.216255) (xy 172.194595 -358.23093) (xy 172.141855 -358.238341) (xy 172.115226 -358.238806)
			(xy 172.087974 -358.23832) (xy 172.034023 -358.230567) (xy 171.981726 -358.215214) (xy 171.932146 -358.192575)
			(xy 171.886292 -358.163109) (xy 171.845099 -358.127418) (xy 171.809405 -358.086227) (xy 171.779937 -358.040375)
			(xy 171.757294 -357.990797) (xy 171.741938 -357.9385) (xy 171.734181 -357.88455) (xy 171.733718 -357.857298)
			(xy 171.733956 -357.838631) (xy 171.737645 -357.801479) (xy 171.741084 -357.78313) (xy 171.743398 -357.76886)
			(xy 171.740872 -357.740075) (xy 171.730379 -357.713153) (xy 171.71276 -357.690251) (xy 171.689428 -357.673205)
			(xy 171.662253 -357.663383) (xy 171.647866 -357.661972) (xy 171.619211 -357.659618) (xy 171.563046 -357.647326)
			(xy 171.50936 -357.626748) (xy 171.459369 -357.598348) (xy 171.414205 -357.562771) (xy 171.374888 -357.520821)
			(xy 171.34231 -357.473447) (xy 171.317207 -357.421722) (xy 171.300148 -357.366816) (xy 171.291519 -357.309973)
			(xy 171.290996 -357.281226) (xy 171.291482 -357.253975) (xy 171.299238 -357.200027) (xy 171.314593 -357.147732)
			(xy 171.337235 -357.098155) (xy 171.366701 -357.052305) (xy 171.402392 -357.011114) (xy 171.443583 -356.975423)
			(xy 171.489433 -356.945957) (xy 171.53901 -356.923315) (xy 171.591305 -356.90796) (xy 171.645253 -356.900204)
			(xy 171.699755 -356.900204) (xy 171.753703 -356.90796) (xy 171.805998 -356.923315) (xy 171.855575 -356.945957)
			(xy 171.901425 -356.975423) (xy 171.942616 -357.011114) (xy 171.978307 -357.052305) (xy 172.007773 -357.098155)
			(xy 172.030415 -357.147732) (xy 172.04577 -357.200027) (xy 172.053526 -357.253975) (xy 172.054012 -357.281226)
			(xy 172.05377 -357.299893) (xy 172.050079 -357.337044) (xy 172.046646 -357.355394) (xy 172.044279 -357.369658)
			(xy 172.046811 -357.398451) (xy 172.057314 -357.425379) (xy 172.074943 -357.448283) (xy 172.098287 -357.465328)
			(xy 172.125472 -357.475145) (xy 172.139864 -357.476552) (xy 172.167353 -357.478863) (xy 172.221308 -357.490336)
			(xy 172.273052 -357.509451) (xy 172.321507 -357.535811) (xy 172.365666 -357.568867) (xy 172.385482 -357.588058)
			(xy 172.400214 -357.603044) (xy 172.427646 -357.603044) (xy 172.45263 -357.603648) (xy 172.501638 -357.613394)
			(xy 172.547808 -357.632503) (xy 172.589368 -357.660244) (xy 172.607478 -357.677466) (xy 172.930566 -358.000554)
			(xy 172.947783 -358.018668) (xy 172.971129 -358.05364) (xy 179.353972 -358.05364) (xy 179.35445 -358.025192)
			(xy 179.362913 -357.96893) (xy 179.379643 -357.91455) (xy 179.404268 -357.86326) (xy 179.436242 -357.816198)
			(xy 179.474853 -357.77441) (xy 179.49672 -357.756206) (xy 179.508238 -357.746308) (xy 179.525265 -357.721175)
			(xy 179.534167 -357.692153) (xy 179.534159 -357.661795) (xy 179.525242 -357.632777) (xy 179.508202 -357.607653)
			(xy 179.49672 -357.59771) (xy 179.474849 -357.579513) (xy 179.436246 -357.537721) (xy 179.404282 -357.490657)
			(xy 179.379667 -357.439365) (xy 179.362948 -357.384984) (xy 179.354497 -357.328722) (xy 179.353972 -357.300276)
			(xy 179.354458 -357.273025) (xy 179.362214 -357.219077) (xy 179.377569 -357.166782) (xy 179.400211 -357.117205)
			(xy 179.429677 -357.071355) (xy 179.465368 -357.030164) (xy 179.506559 -356.994473) (xy 179.552409 -356.965007)
			(xy 179.601986 -356.942365) (xy 179.654281 -356.92701) (xy 179.708229 -356.919254) (xy 179.762731 -356.919254)
			(xy 179.816679 -356.92701) (xy 179.868974 -356.942365) (xy 179.918551 -356.965007) (xy 179.964401 -356.994473)
			(xy 180.005592 -357.030164) (xy 180.041283 -357.071355) (xy 180.070749 -357.117205) (xy 180.093391 -357.166782)
			(xy 180.108746 -357.219077) (xy 180.116502 -357.273025) (xy 180.116988 -357.300276) (xy 180.116428 -357.32872)
			(xy 180.107979 -357.384978) (xy 180.091264 -357.439356) (xy 180.066654 -357.490646) (xy 180.034696 -357.53771)
			(xy 179.9961 -357.579502) (xy 179.97424 -357.59771) (xy 179.96281 -357.6077) (xy 179.945787 -357.632808)
			(xy 179.93688 -357.661806) (xy 179.936872 -357.692141) (xy 179.945764 -357.721144) (xy 179.962774 -357.746261)
			(xy 179.97424 -357.756206) (xy 179.99611 -357.774404) (xy 180.034716 -357.816194) (xy 180.066681 -357.863258)
			(xy 180.091296 -357.914551) (xy 180.108014 -357.968932) (xy 180.110284 -357.984044) (xy 180.369462 -357.984044)
			(xy 180.373533 -357.928422) (xy 180.385659 -357.873985) (xy 180.405582 -357.821894) (xy 180.432878 -357.773259)
			(xy 180.466964 -357.729116) (xy 180.507113 -357.690407) (xy 180.552471 -357.657956) (xy 180.602071 -357.632455)
			(xy 180.654855 -357.614448) (xy 180.709698 -357.604318) (xy 180.765432 -357.602281) (xy 180.820869 -357.608381)
			(xy 180.874826 -357.622487) (xy 180.926155 -357.644299) (xy 180.973761 -357.673353) (xy 181.016629 -357.709028)
			(xy 181.053846 -357.750565) (xy 181.084619 -357.797078) (xy 181.108291 -357.847575) (xy 181.124359 -357.900982)
			(xy 181.132479 -357.956158) (xy 181.132988 -357.984044) (xy 181.132479 -358.01193) (xy 181.124359 -358.067106)
			(xy 181.108291 -358.120513) (xy 181.084619 -358.17101) (xy 181.053846 -358.217523) (xy 181.016629 -358.25906)
			(xy 180.973761 -358.294735) (xy 180.926155 -358.323789) (xy 180.874826 -358.345601) (xy 180.820869 -358.359707)
			(xy 180.765432 -358.365807) (xy 180.709698 -358.36377) (xy 180.654855 -358.35364) (xy 180.602071 -358.335633)
			(xy 180.552471 -358.310132) (xy 180.507113 -358.277681) (xy 180.466964 -358.238972) (xy 180.432878 -358.194829)
			(xy 180.405582 -358.146194) (xy 180.385659 -358.094103) (xy 180.373533 -358.039666) (xy 180.369462 -357.984044)
			(xy 180.110284 -357.984044) (xy 180.116464 -358.025193) (xy 180.116988 -358.05364) (xy 180.116502 -358.080891)
			(xy 180.108746 -358.134839) (xy 180.093391 -358.187134) (xy 180.070749 -358.236711) (xy 180.041283 -358.282561)
			(xy 180.005592 -358.323752) (xy 179.964401 -358.359443) (xy 179.918551 -358.388909) (xy 179.868974 -358.411551)
			(xy 179.816679 -358.426906) (xy 179.762731 -358.434662) (xy 179.708229 -358.434662) (xy 179.654281 -358.426906)
			(xy 179.601986 -358.411551) (xy 179.552409 -358.388909) (xy 179.506559 -358.359443) (xy 179.465368 -358.323752)
			(xy 179.429677 -358.282561) (xy 179.400211 -358.236711) (xy 179.377569 -358.187134) (xy 179.362214 -358.134839)
			(xy 179.354458 -358.080891) (xy 179.353972 -358.05364) (xy 172.971129 -358.05364) (xy 172.975525 -358.060226)
			(xy 172.994633 -358.106395) (xy 173.004376 -358.155403) (xy 173.004988 -358.180386) (xy 173.004988 -359.603802)
			(xy 173.004349 -359.628784) (xy 172.994612 -359.67779) (xy 172.975513 -359.723959) (xy 172.947783 -359.765522)
			(xy 172.930566 -359.783634) (xy 171.689522 -361.024678) (xy 171.67142 -361.041908) (xy 171.629857 -361.069647)
			(xy 171.583685 -361.088752) (xy 171.534674 -361.09849) (xy 171.50969 -361.0991) (xy 158.864046 -361.0991)
			(xy 158.839063 -361.098489) (xy 158.790056 -361.088743) (xy 158.743886 -361.069635) (xy 158.702325 -361.041898)
			(xy 158.684214 -361.024678) (xy 157.41904 -359.759504) (xy 134.300214 -359.759504) (xy 130.237738 -363.82198)
			(xy 130.219659 -363.839255) (xy 130.178109 -363.867063) (xy 130.131932 -363.886231) (xy 130.082904 -363.896023)
			(xy 130.057906 -363.896656) (xy 119.40159 -363.896656) (xy 118.595228 -364.702852) (xy 119.224042 -364.702852)
			(xy 119.228113 -364.64723) (xy 119.240239 -364.592793) (xy 119.260162 -364.540702) (xy 119.287458 -364.492067)
			(xy 119.321544 -364.447924) (xy 119.361693 -364.409215) (xy 119.407051 -364.376764) (xy 119.456651 -364.351263)
			(xy 119.509435 -364.333256) (xy 119.564278 -364.323126) (xy 119.620012 -364.321089) (xy 119.675449 -364.327189)
			(xy 119.729406 -364.341295) (xy 119.780735 -364.363107) (xy 119.828341 -364.392161) (xy 119.871209 -364.427836)
			(xy 119.908426 -364.469373) (xy 119.939199 -364.515886) (xy 119.962871 -364.566383) (xy 119.978939 -364.61979)
			(xy 119.987059 -364.674966) (xy 119.987568 -364.702852) (xy 119.987059 -364.730738) (xy 119.978939 -364.785914)
			(xy 119.962871 -364.839321) (xy 119.939199 -364.889818) (xy 119.908426 -364.936331) (xy 119.871209 -364.977868)
			(xy 119.828341 -365.013543) (xy 119.780735 -365.042597) (xy 119.729406 -365.064409) (xy 119.675449 -365.078515)
			(xy 119.620012 -365.084615) (xy 119.564278 -365.082578) (xy 119.509435 -365.072448) (xy 119.456651 -365.054441)
			(xy 119.407051 -365.02894) (xy 119.361693 -364.996489) (xy 119.321544 -364.95778) (xy 119.287458 -364.913637)
			(xy 119.260162 -364.865002) (xy 119.240239 -364.812911) (xy 119.228113 -364.758474) (xy 119.224042 -364.702852)
			(xy 118.595228 -364.702852) (xy 118.16842 -365.129572) (xy 118.150305 -365.146807) (xy 118.108768 -365.174622)
			(xy 118.062602 -365.193801) (xy 118.013583 -365.203608) (xy 117.988588 -365.204248) (xy 114.14506 -365.204248)
			(xy 114.120065 -365.203584) (xy 114.071044 -365.19379) (xy 114.024873 -365.174625) (xy 113.983325 -365.146824)
			(xy 113.965228 -365.129572) (xy 113.090452 -364.254796) (xy 112.718088 -364.254796) (xy 112.693106 -364.25416)
			(xy 112.6441 -364.244422) (xy 112.597931 -364.225322) (xy 112.556368 -364.197591) (xy 112.538256 -364.180374)
			(xy 111.235998 -362.878116) (xy 111.220155 -362.86155) (xy 111.194087 -362.82385) (xy 111.175187 -362.782094)
			(xy 111.164063 -362.737631) (xy 111.162084 -362.714794) (xy 111.14236 -362.696634) (xy 111.107697 -362.655733)
			(xy 111.079109 -362.610377) (xy 111.05716 -362.561461) (xy 111.042285 -362.509952) (xy 111.034776 -362.456867)
			(xy 111.034322 -362.43006) (xy 108.780326 -362.43006) (xy 109.337094 -362.986828) (xy 109.343444 -362.993178)
			(xy 109.466634 -363.116368) (xy 109.466634 -363.29112) (xy 109.466888 -363.300518) (xy 109.466888 -363.375702)
			(xy 109.736888 -363.375702) (xy 109.740959 -363.32008) (xy 109.753085 -363.265643) (xy 109.773008 -363.213552)
			(xy 109.800304 -363.164917) (xy 109.83439 -363.120774) (xy 109.874539 -363.082065) (xy 109.919897 -363.049614)
			(xy 109.969497 -363.024113) (xy 110.022281 -363.006106) (xy 110.077124 -362.995976) (xy 110.132858 -362.993939)
			(xy 110.188295 -363.000039) (xy 110.242252 -363.014145) (xy 110.293581 -363.035957) (xy 110.341187 -363.065011)
			(xy 110.384055 -363.100686) (xy 110.421272 -363.142223) (xy 110.452045 -363.188736) (xy 110.475717 -363.239233)
			(xy 110.491785 -363.29264) (xy 110.499905 -363.347816) (xy 110.500414 -363.375702) (xy 110.499905 -363.403588)
			(xy 110.491785 -363.458764) (xy 110.475717 -363.512171) (xy 110.452045 -363.562668) (xy 110.421272 -363.609181)
			(xy 110.384055 -363.650718) (xy 110.341187 -363.686393) (xy 110.293581 -363.715447) (xy 110.242252 -363.737259)
			(xy 110.188295 -363.751365) (xy 110.132858 -363.757465) (xy 110.077124 -363.755428) (xy 110.022281 -363.745298)
			(xy 109.969497 -363.727291) (xy 109.919897 -363.70179) (xy 109.874539 -363.669339) (xy 109.83439 -363.63063)
			(xy 109.800304 -363.586487) (xy 109.773008 -363.537852) (xy 109.753085 -363.485761) (xy 109.740959 -363.431324)
			(xy 109.736888 -363.375702) (xy 109.466888 -363.375702) (xy 109.466888 -364.40618) (xy 109.82782 -364.40618)
			(xy 109.831891 -364.350558) (xy 109.844017 -364.296121) (xy 109.86394 -364.24403) (xy 109.891236 -364.195395)
			(xy 109.925322 -364.151252) (xy 109.965471 -364.112543) (xy 110.010829 -364.080092) (xy 110.060429 -364.054591)
			(xy 110.113213 -364.036584) (xy 110.168056 -364.026454) (xy 110.22379 -364.024417) (xy 110.279227 -364.030517)
			(xy 110.333184 -364.044623) (xy 110.384513 -364.066435) (xy 110.432119 -364.095489) (xy 110.474987 -364.131164)
			(xy 110.512204 -364.172701) (xy 110.542977 -364.219214) (xy 110.548703 -364.231428) (xy 111.419638 -364.231428)
			(xy 111.423709 -364.175806) (xy 111.435835 -364.121369) (xy 111.455758 -364.069278) (xy 111.483054 -364.020643)
			(xy 111.51714 -363.9765) (xy 111.557289 -363.937791) (xy 111.602647 -363.90534) (xy 111.652247 -363.879839)
			(xy 111.705031 -363.861832) (xy 111.759874 -363.851702) (xy 111.815608 -363.849665) (xy 111.871045 -363.855765)
			(xy 111.925002 -363.869871) (xy 111.976331 -363.891683) (xy 112.023937 -363.920737) (xy 112.066805 -363.956412)
			(xy 112.104022 -363.997949) (xy 112.134795 -364.044462) (xy 112.158467 -364.094959) (xy 112.174535 -364.148366)
			(xy 112.182655 -364.203542) (xy 112.183164 -364.231428) (xy 112.182655 -364.259314) (xy 112.174535 -364.31449)
			(xy 112.158467 -364.367897) (xy 112.134795 -364.418394) (xy 112.104022 -364.464907) (xy 112.066805 -364.506444)
			(xy 112.023937 -364.542119) (xy 111.976331 -364.571173) (xy 111.925002 -364.592985) (xy 111.871045 -364.607091)
			(xy 111.815608 -364.613191) (xy 111.759874 -364.611154) (xy 111.705031 -364.601024) (xy 111.652247 -364.583017)
			(xy 111.602647 -364.557516) (xy 111.557289 -364.525065) (xy 111.51714 -364.486356) (xy 111.483054 -364.442213)
			(xy 111.455758 -364.393578) (xy 111.435835 -364.341487) (xy 111.423709 -364.28705) (xy 111.419638 -364.231428)
			(xy 110.548703 -364.231428) (xy 110.566649 -364.269711) (xy 110.582717 -364.323118) (xy 110.590837 -364.378294)
			(xy 110.591346 -364.40618) (xy 110.590837 -364.434066) (xy 110.582717 -364.489242) (xy 110.566649 -364.542649)
			(xy 110.542977 -364.593146) (xy 110.512204 -364.639659) (xy 110.474987 -364.681196) (xy 110.432119 -364.716871)
			(xy 110.384513 -364.745925) (xy 110.333184 -364.767737) (xy 110.279227 -364.781843) (xy 110.22379 -364.787943)
			(xy 110.168056 -364.785906) (xy 110.113213 -364.775776) (xy 110.060429 -364.757769) (xy 110.010829 -364.732268)
			(xy 109.965471 -364.699817) (xy 109.925322 -364.661108) (xy 109.891236 -364.616965) (xy 109.86394 -364.56833)
			(xy 109.844017 -364.516239) (xy 109.831891 -364.461802) (xy 109.82782 -364.40618) (xy 109.466888 -364.40618)
			(xy 109.466888 -364.940596) (xy 110.692438 -364.940596) (xy 110.69281 -364.913328) (xy 110.700575 -364.859349)
			(xy 110.715946 -364.807025) (xy 110.73861 -364.757422) (xy 110.768105 -364.711552) (xy 110.803831 -364.670348)
			(xy 110.845059 -364.63465) (xy 110.890949 -364.605186) (xy 110.940567 -364.582556) (xy 110.992901 -364.56722)
			(xy 111.046886 -364.559491) (xy 111.101421 -364.559528) (xy 111.155396 -364.567328) (xy 111.20771 -364.582733)
			(xy 111.257297 -364.60543) (xy 111.303148 -364.634955) (xy 111.344329 -364.670708) (xy 111.38 -364.711959)
			(xy 111.40901 -364.757208) (xy 112.321592 -364.757208) (xy 112.325663 -364.701586) (xy 112.337789 -364.647149)
			(xy 112.357712 -364.595058) (xy 112.385008 -364.546423) (xy 112.419094 -364.50228) (xy 112.459243 -364.463571)
			(xy 112.504601 -364.43112) (xy 112.554201 -364.405619) (xy 112.606985 -364.387612) (xy 112.661828 -364.377482)
			(xy 112.717562 -364.375445) (xy 112.772999 -364.381545) (xy 112.826956 -364.395651) (xy 112.878285 -364.417463)
			(xy 112.925891 -364.446517) (xy 112.968759 -364.482192) (xy 113.005976 -364.523729) (xy 113.036749 -364.570242)
			(xy 113.060421 -364.620739) (xy 113.076489 -364.674146) (xy 113.084609 -364.729322) (xy 113.085118 -364.757208)
			(xy 113.084609 -364.785094) (xy 113.076489 -364.84027) (xy 113.060421 -364.893677) (xy 113.036749 -364.944174)
			(xy 113.005976 -364.990687) (xy 112.968759 -365.032224) (xy 112.925891 -365.067899) (xy 112.878285 -365.096953)
			(xy 112.826956 -365.118765) (xy 112.772999 -365.132871) (xy 112.717562 -365.138971) (xy 112.661828 -365.136934)
			(xy 112.606985 -365.126804) (xy 112.554201 -365.108797) (xy 112.504601 -365.083296) (xy 112.459243 -365.050845)
			(xy 112.419094 -365.012136) (xy 112.385008 -364.967993) (xy 112.357712 -364.919358) (xy 112.337789 -364.867267)
			(xy 112.325663 -364.81283) (xy 112.321592 -364.757208) (xy 111.40901 -364.757208) (xy 111.409434 -364.757869)
			(xy 111.432032 -364.807502) (xy 111.447333 -364.859846) (xy 111.455026 -364.913836) (xy 111.455454 -364.941104)
			(xy 111.455454 -364.96244) (xy 113.15954 -366.666272) (xy 118.919244 -366.666272) (xy 121.241058 -364.344712)
			(xy 121.259137 -364.327438) (xy 121.300687 -364.29963) (xy 121.346864 -364.280462) (xy 121.395892 -364.270669)
			(xy 121.42089 -364.270036) (xy 130.318002 -364.270036) (xy 134.380478 -360.207814) (xy 134.398579 -360.190582)
			(xy 134.440142 -360.162844) (xy 134.486315 -360.14374) (xy 134.535326 -360.134002) (xy 134.56031 -360.133392)
			(xy 156.807662 -360.133392) (xy 156.832647 -360.133972) (xy 156.881657 -360.143723) (xy 156.927827 -360.16284)
			(xy 156.969386 -360.190588) (xy 156.987494 -360.207814) (xy 159.39135 -362.61167) (xy 165.871652 -362.61167)
			(xy 165.872125 -362.585292) (xy 165.879381 -362.533037) (xy 165.893763 -362.482279) (xy 165.914999 -362.433985)
			(xy 165.942682 -362.389075) (xy 165.976287 -362.348406) (xy 166.015172 -362.312752) (xy 166.058596 -362.282793)
			(xy 166.081964 -362.270548) (xy 166.094349 -362.263891) (xy 166.115081 -362.244908) (xy 166.129843 -362.220985)
			(xy 166.137514 -362.193942) (xy 166.13751 -362.165831) (xy 166.129833 -362.13879) (xy 166.115064 -362.114872)
			(xy 166.094327 -362.095894) (xy 166.081964 -362.089192) (xy 166.058615 -362.076913) (xy 166.015193 -362.046954)
			(xy 165.976308 -362.011304) (xy 165.942702 -361.970639) (xy 165.915013 -361.925736) (xy 165.893768 -361.877449)
			(xy 165.879373 -361.826697) (xy 165.872102 -361.774447) (xy 165.871652 -361.74807) (xy 165.872138 -361.720819)
			(xy 165.879894 -361.666871) (xy 165.895249 -361.614576) (xy 165.917891 -361.564999) (xy 165.947357 -361.519149)
			(xy 165.983048 -361.477958) (xy 166.024239 -361.442267) (xy 166.070089 -361.412801) (xy 166.119666 -361.390159)
			(xy 166.171961 -361.374804) (xy 166.225909 -361.367048) (xy 166.280411 -361.367048) (xy 166.334359 -361.374804)
			(xy 166.386654 -361.390159) (xy 166.436231 -361.412801) (xy 166.482081 -361.442267) (xy 166.523272 -361.477958)
			(xy 166.558801 -361.518962) (xy 175.165258 -361.518962) (xy 175.165781 -361.489792) (xy 175.174688 -361.432135)
			(xy 175.192271 -361.376507) (xy 175.218122 -361.324205) (xy 175.251636 -361.276451) (xy 175.292033 -361.234359)
			(xy 175.314864 -361.216194) (xy 175.325211 -361.207738) (xy 175.341501 -361.186567) (xy 175.351744 -361.161896)
			(xy 175.355241 -361.135413) (xy 175.351751 -361.10893) (xy 175.341514 -361.084257) (xy 175.32523 -361.063081)
			(xy 175.314864 -361.05465) (xy 175.292028 -361.036491) (xy 175.251629 -360.994402) (xy 175.218116 -360.946647)
			(xy 175.192271 -360.894343) (xy 175.1747 -360.838712) (xy 175.165812 -360.781052) (xy 175.165258 -360.751882)
			(xy 175.165761 -360.724632) (xy 175.173519 -360.670687) (xy 175.188875 -360.618394) (xy 175.211515 -360.568819)
			(xy 175.24098 -360.52297) (xy 175.27667 -360.481781) (xy 175.317858 -360.44609) (xy 175.363705 -360.416623)
			(xy 175.413279 -360.39398) (xy 175.465571 -360.378622) (xy 175.519516 -360.370862) (xy 175.546766 -360.370374)
			(xy 175.575683 -360.370889) (xy 175.632856 -360.379614) (xy 175.688056 -360.396871) (xy 175.740019 -360.422263)
			(xy 175.787552 -360.455209) (xy 175.829567 -360.494953) (xy 175.847756 -360.51744) (xy 175.857653 -360.529245)
			(xy 175.882977 -360.546764) (xy 175.91237 -360.55594) (xy 175.943162 -360.55594) (xy 175.972555 -360.546764)
			(xy 175.997879 -360.529245) (xy 176.007776 -360.51744) (xy 176.025991 -360.494976) (xy 176.068004 -360.455238)
			(xy 176.115534 -360.422296) (xy 176.167491 -360.396903) (xy 176.222685 -360.379643) (xy 176.279851 -360.370911)
			(xy 176.308766 -360.370374) (xy 176.337312 -360.37093) (xy 176.393765 -360.379443) (xy 176.44832 -360.396269)
			(xy 176.499761 -360.421033) (xy 176.52365 -360.436668) (xy 176.534772 -360.443765) (xy 176.559632 -360.452568)
			(xy 176.585919 -360.45469) (xy 176.61187 -360.449989) (xy 176.635742 -360.438781) (xy 176.655935 -360.421817)
			(xy 176.663858 -360.411268) (xy 176.679265 -360.390252) (xy 176.714864 -360.352198) (xy 176.75531 -360.31934)
			(xy 176.799849 -360.29229) (xy 176.847654 -360.27155) (xy 176.897835 -360.257507) (xy 176.949461 -360.25042)
			(xy 176.975516 -360.249978) (xy 177.004432 -360.250527) (xy 177.061603 -360.259246) (xy 177.116803 -360.276496)
			(xy 177.168765 -360.301881) (xy 177.2163 -360.334821) (xy 177.258316 -360.37456) (xy 177.276506 -360.397044)
			(xy 177.286403 -360.408849) (xy 177.311727 -360.426368) (xy 177.34112 -360.435544) (xy 177.371912 -360.435544)
			(xy 177.401305 -360.426368) (xy 177.426629 -360.408849) (xy 177.436526 -360.397044) (xy 177.454713 -360.374557)
			(xy 177.496733 -360.33482) (xy 177.544268 -360.30188) (xy 177.59623 -360.276492) (xy 177.651429 -360.259237)
			(xy 177.7086 -360.250511) (xy 177.737516 -360.249978) (xy 177.764767 -360.250463) (xy 177.818714 -360.258221)
			(xy 177.871008 -360.273578) (xy 177.920584 -360.29622) (xy 177.966434 -360.325686) (xy 178.007624 -360.361378)
			(xy 178.043315 -360.402568) (xy 178.072781 -360.448417) (xy 178.095423 -360.497994) (xy 178.110779 -360.550288)
			(xy 178.118537 -360.604235) (xy 178.119024 -360.631486) (xy 178.118573 -360.657529) (xy 178.111489 -360.70913)
			(xy 178.097451 -360.759287) (xy 178.076719 -360.807069) (xy 178.04968 -360.851586) (xy 178.016836 -360.89201)
			(xy 177.99812 -360.910124) (xy 177.988141 -360.920052) (xy 177.973673 -360.94419) (xy 177.966332 -360.971357)
			(xy 177.966673 -360.999497) (xy 177.97467 -361.026479) (xy 177.989718 -361.050259) (xy 177.999898 -361.059984)
			(xy 178.019495 -361.07813) (xy 178.053888 -361.118993) (xy 178.082244 -361.164254) (xy 178.104009 -361.213028)
			(xy 178.118757 -361.264362) (xy 178.1262 -361.317251) (xy 178.126644 -361.343956) (xy 178.126102 -361.371724)
			(xy 178.118056 -361.426674) (xy 178.102127 -361.479877) (xy 178.078653 -361.530208) (xy 178.048129 -361.576604)
			(xy 178.011201 -361.618083) (xy 177.990246 -361.63631) (xy 177.979642 -361.645881) (xy 177.963652 -361.66953)
			(xy 177.954852 -361.696687) (xy 177.953933 -361.725219) (xy 177.960967 -361.752886) (xy 177.975402 -361.777515)
			(xy 177.98542 -361.787694) (xy 178.003747 -361.805801) (xy 178.035923 -361.846035) (xy 178.062396 -361.890231)
			(xy 178.082685 -361.937585) (xy 178.096422 -361.987238) (xy 178.103357 -362.038287) (xy 178.103784 -362.064046)
			(xy 178.10329 -362.091415) (xy 178.09548 -362.145593) (xy 178.079997 -362.198096) (xy 178.057162 -362.247844)
			(xy 178.027443 -362.293812) (xy 178.009804 -362.314744) (xy 178.000523 -362.326038) (xy 177.98835 -362.352608)
			(xy 177.984186 -362.381535) (xy 177.98837 -362.410459) (xy 178.00056 -362.437021) (xy 178.009804 -362.448348)
			(xy 178.027488 -362.469245) (xy 178.057209 -362.51522) (xy 178.08005 -362.564972) (xy 178.095541 -362.617479)
			(xy 178.103365 -362.671662) (xy 178.10336 -362.726407) (xy 178.095526 -362.780589) (xy 178.080025 -362.833093)
			(xy 178.057176 -362.882841) (xy 178.027447 -362.928811) (xy 178.009804 -362.949744) (xy 178.000523 -362.961038)
			(xy 177.98835 -362.987608) (xy 177.984186 -363.016535) (xy 177.98837 -363.045459) (xy 178.00056 -363.072021)
			(xy 178.009804 -363.083348) (xy 178.027433 -363.104288) (xy 178.057146 -363.150259) (xy 178.059513 -363.155414)
			(xy 179.144926 -363.155414) (xy 179.144926 -363.070718) (xy 179.152977 -362.986404) (xy 179.169006 -362.903238)
			(xy 179.192867 -362.821971) (xy 179.224346 -362.743341) (xy 179.263157 -362.66806) (xy 179.308947 -362.596808)
			(xy 179.361303 -362.530232) (xy 179.419751 -362.468934) (xy 179.483761 -362.413469) (xy 179.552753 -362.36434)
			(xy 179.626103 -362.321991) (xy 179.703146 -362.286807) (xy 179.783185 -362.259105) (xy 179.865494 -362.239137)
			(xy 179.949329 -362.227084) (xy 180.03393 -362.223054) (xy 180.118531 -362.227084) (xy 180.202366 -362.239137)
			(xy 180.284675 -362.259105) (xy 180.364714 -362.286807) (xy 180.441757 -362.321991) (xy 180.515107 -362.36434)
			(xy 180.584099 -362.413469) (xy 180.648109 -362.468934) (xy 180.706557 -362.530232) (xy 180.758913 -362.596808)
			(xy 180.804703 -362.66806) (xy 180.843514 -362.743341) (xy 180.874993 -362.821971) (xy 180.898854 -362.903238)
			(xy 180.914883 -362.986404) (xy 180.922934 -363.070718) (xy 180.923438 -363.113066) (xy 181.669439 -363.113066)
			(xy 181.673475 -363.029619) (xy 181.685547 -362.946951) (xy 181.70554 -362.865834) (xy 181.733269 -362.787025)
			(xy 181.768475 -362.71126) (xy 181.810829 -362.639247) (xy 181.859935 -362.571658) (xy 181.915336 -362.509124)
			(xy 181.976513 -362.452229) (xy 182.042896 -362.401503) (xy 182.113864 -362.357422) (xy 182.188756 -362.320396)
			(xy 182.266872 -362.29077) (xy 182.347482 -362.268822) (xy 182.429834 -362.254757) (xy 182.51316 -362.248705)
			(xy 182.59668 -362.250724) (xy 182.679616 -362.260794) (xy 182.761192 -362.278822) (xy 182.840648 -362.304639)
			(xy 182.917241 -362.338004) (xy 182.990257 -362.378605) (xy 183.059013 -362.426064) (xy 183.122867 -362.479937)
			(xy 183.181224 -362.539722) (xy 183.233539 -362.604859) (xy 183.279322 -362.674742) (xy 183.318147 -362.748717)
			(xy 183.349652 -362.826094) (xy 183.373541 -362.906151) (xy 183.389592 -362.988139) (xy 183.397655 -363.071294)
			(xy 183.39816 -363.113066) (xy 183.397655 -363.154838) (xy 183.389592 -363.237993) (xy 183.373541 -363.319981)
			(xy 183.349652 -363.400038) (xy 183.318147 -363.477415) (xy 183.279322 -363.55139) (xy 183.233539 -363.621273)
			(xy 183.181224 -363.68641) (xy 183.122867 -363.746195) (xy 183.059013 -363.800068) (xy 182.990257 -363.847527)
			(xy 182.917241 -363.888128) (xy 182.840648 -363.921493) (xy 182.761192 -363.94731) (xy 182.679616 -363.965338)
			(xy 182.59668 -363.975408) (xy 182.51316 -363.977427) (xy 182.429834 -363.971375) (xy 182.347482 -363.95731)
			(xy 182.266872 -363.935362) (xy 182.188756 -363.905736) (xy 182.113864 -363.86871) (xy 182.042896 -363.824629)
			(xy 181.976513 -363.773903) (xy 181.915336 -363.717008) (xy 181.859935 -363.654474) (xy 181.810829 -363.586885)
			(xy 181.768475 -363.514872) (xy 181.733269 -363.439107) (xy 181.70554 -363.360298) (xy 181.685547 -363.279181)
			(xy 181.673475 -363.196513) (xy 181.669439 -363.113066) (xy 180.923438 -363.113066) (xy 180.922934 -363.155414)
			(xy 180.914883 -363.239728) (xy 180.898854 -363.322894) (xy 180.874993 -363.404161) (xy 180.843514 -363.482791)
			(xy 180.804703 -363.558072) (xy 180.758913 -363.629324) (xy 180.706557 -363.6959) (xy 180.648109 -363.757198)
			(xy 180.584099 -363.812663) (xy 180.515107 -363.861792) (xy 180.441757 -363.904141) (xy 180.364714 -363.939325)
			(xy 180.284675 -363.967027) (xy 180.202366 -363.986995) (xy 180.118531 -363.999048) (xy 180.03393 -364.003079)
			(xy 179.949329 -363.999048) (xy 179.865494 -363.986995) (xy 179.783185 -363.967027) (xy 179.703146 -363.939325)
			(xy 179.626103 -363.904141) (xy 179.552753 -363.861792) (xy 179.483761 -363.812663) (xy 179.419751 -363.757198)
			(xy 179.361303 -363.6959) (xy 179.308947 -363.629324) (xy 179.263157 -363.558072) (xy 179.224346 -363.482791)
			(xy 179.192867 -363.404161) (xy 179.169006 -363.322894) (xy 179.152977 -363.239728) (xy 179.144926 -363.155414)
			(xy 178.059513 -363.155414) (xy 178.079984 -363.200004) (xy 178.095477 -363.252503) (xy 178.103308 -363.306677)
			(xy 178.103784 -363.334046) (xy 178.103365 -363.361299) (xy 178.095601 -363.415251) (xy 178.080239 -363.467548)
			(xy 178.057591 -363.517127) (xy 178.028118 -363.562979) (xy 177.992419 -363.604169) (xy 177.951222 -363.63986)
			(xy 177.905366 -363.669325) (xy 177.855783 -363.691964) (xy 177.803482 -363.707316) (xy 177.74953 -363.71507)
			(xy 177.722276 -363.715554) (xy 177.69336 -363.714998) (xy 177.63619 -363.706279) (xy 177.580991 -363.68903)
			(xy 177.529029 -363.663645) (xy 177.481494 -363.630708) (xy 177.439477 -363.590971) (xy 177.421286 -363.568488)
			(xy 177.411389 -363.556683) (xy 177.386065 -363.539164) (xy 177.356672 -363.529988) (xy 177.32588 -363.529988)
			(xy 177.296487 -363.539164) (xy 177.271163 -363.556683) (xy 177.261266 -363.568488) (xy 177.243091 -363.590985)
			(xy 177.201068 -363.63072) (xy 177.15353 -363.663658) (xy 177.101566 -363.689044) (xy 177.046365 -363.706297)
			(xy 176.989193 -363.715022) (xy 176.960276 -363.715554) (xy 176.933026 -363.715045) (xy 176.879082 -363.707286)
			(xy 176.82679 -363.69193) (xy 176.777216 -363.66929) (xy 176.731368 -363.639825) (xy 176.690179 -363.604136)
			(xy 176.654488 -363.56295) (xy 176.625021 -363.517103) (xy 176.602377 -363.46753) (xy 176.587019 -363.41524)
			(xy 176.579257 -363.361296) (xy 176.578768 -363.334046) (xy 176.579244 -363.306676) (xy 176.587057 -363.252497)
			(xy 176.602543 -363.199993) (xy 176.625383 -363.150246) (xy 176.655107 -363.104279) (xy 176.672748 -363.083348)
			(xy 176.681937 -363.071986) (xy 176.694114 -363.04544) (xy 176.698293 -363.016535) (xy 176.694133 -362.987627)
			(xy 176.681975 -362.961073) (xy 176.672748 -362.949744) (xy 176.655151 -362.928775) (xy 176.625423 -362.882814)
			(xy 176.602574 -362.833074) (xy 176.587073 -362.780577) (xy 176.57924 -362.726403) (xy 176.579235 -362.671666)
			(xy 176.587058 -362.617491) (xy 176.60255 -362.564991) (xy 176.62539 -362.515247) (xy 176.65511 -362.46928)
			(xy 176.672748 -362.448348) (xy 176.681937 -362.436986) (xy 176.694114 -362.41044) (xy 176.698293 -362.381535)
			(xy 176.694133 -362.352627) (xy 176.681975 -362.326073) (xy 176.672748 -362.314744) (xy 176.655124 -362.2938)
			(xy 176.625408 -362.247831) (xy 176.602568 -362.198087) (xy 176.587074 -362.145589) (xy 176.579243 -362.091414)
			(xy 176.578768 -362.064046) (xy 176.578999 -362.044991) (xy 176.582819 -362.007073) (xy 176.586388 -361.988354)
			(xy 176.588705 -361.97488) (xy 176.586854 -361.947611) (xy 176.577837 -361.92181) (xy 176.562301 -361.899324)
			(xy 176.541357 -361.881763) (xy 176.516507 -361.870386) (xy 176.489529 -361.866007) (xy 176.462355 -361.868939)
			(xy 176.449482 -361.873546) (xy 176.427016 -361.882082) (xy 176.380475 -361.894068) (xy 176.332796 -361.900107)
			(xy 176.308766 -361.90047) (xy 176.27985 -361.899916) (xy 176.22268 -361.891196) (xy 176.167482 -361.873946)
			(xy 176.115519 -361.848561) (xy 176.067985 -361.815623) (xy 176.025967 -361.775887) (xy 176.007776 -361.753404)
			(xy 175.997879 -361.741599) (xy 175.972555 -361.72408) (xy 175.943162 -361.714904) (xy 175.91237 -361.714904)
			(xy 175.882977 -361.72408) (xy 175.857653 -361.741599) (xy 175.847756 -361.753404) (xy 175.829591 -361.775909)
			(xy 175.787566 -361.815643) (xy 175.740025 -361.848579) (xy 175.688059 -361.873964) (xy 175.632857 -361.891215)
			(xy 175.575684 -361.899938) (xy 175.546766 -361.90047) (xy 175.519511 -361.900077) (xy 175.465555 -361.892314)
			(xy 175.413254 -361.876952) (xy 175.363671 -361.854303) (xy 175.317816 -361.824827) (xy 175.276623 -361.789126)
			(xy 175.240929 -361.747926) (xy 175.211463 -361.702066) (xy 175.188823 -361.652479) (xy 175.173471 -361.600174)
			(xy 175.165718 -361.546218) (xy 175.165258 -361.518962) (xy 166.558801 -361.518962) (xy 166.558963 -361.519149)
			(xy 166.588429 -361.564999) (xy 166.611071 -361.614576) (xy 166.626426 -361.666871) (xy 166.634182 -361.720819)
			(xy 166.634668 -361.74807) (xy 166.634272 -361.774451) (xy 166.627009 -361.826712) (xy 166.612618 -361.877474)
			(xy 166.591373 -361.92577) (xy 166.563678 -361.97068) (xy 166.530062 -362.011347) (xy 166.491166 -362.046998)
			(xy 166.44773 -362.076951) (xy 166.424356 -362.089192) (xy 166.412022 -362.095936) (xy 166.391291 -362.114903)
			(xy 166.376527 -362.138809) (xy 166.368852 -362.165838) (xy 166.368848 -362.193935) (xy 166.376517 -362.220966)
			(xy 166.391274 -362.244876) (xy 166.411999 -362.263848) (xy 166.424356 -362.270548) (xy 166.447727 -362.282788)
			(xy 166.491148 -362.312753) (xy 166.530032 -362.34841) (xy 166.563637 -362.38908) (xy 166.591323 -362.433988)
			(xy 166.612564 -362.482281) (xy 166.626954 -362.533037) (xy 166.634221 -362.585291) (xy 166.634668 -362.61167)
			(xy 166.634182 -362.638921) (xy 166.626426 -362.692869) (xy 166.611071 -362.745164) (xy 166.588429 -362.794741)
			(xy 166.558963 -362.840591) (xy 166.523272 -362.881782) (xy 166.482081 -362.917473) (xy 166.436231 -362.946939)
			(xy 166.386654 -362.969581) (xy 166.334359 -362.984936) (xy 166.280411 -362.992692) (xy 166.225909 -362.992692)
			(xy 166.171961 -362.984936) (xy 166.119666 -362.969581) (xy 166.070089 -362.946939) (xy 166.024239 -362.917473)
			(xy 165.983048 -362.881782) (xy 165.947357 -362.840591) (xy 165.917891 -362.794741) (xy 165.895249 -362.745164)
			(xy 165.879894 -362.692869) (xy 165.872138 -362.638921) (xy 165.871652 -362.61167) (xy 159.39135 -362.61167)
			(xy 161.053526 -364.273846) (xy 169.455338 -364.273846) (xy 169.455875 -364.24493) (xy 169.464598 -364.187759)
			(xy 169.481851 -364.13256) (xy 169.507239 -364.080597) (xy 169.54018 -364.033063) (xy 169.579919 -363.991046)
			(xy 169.602404 -363.972856) (xy 169.614161 -363.962907) (xy 169.631677 -363.937597) (xy 169.640856 -363.908218)
			(xy 169.640864 -363.877438) (xy 169.631702 -363.848054) (xy 169.614201 -363.822734) (xy 169.602404 -363.812836)
			(xy 169.579939 -363.794624) (xy 169.540202 -363.752608) (xy 169.507261 -363.705078) (xy 169.481869 -363.653121)
			(xy 169.464609 -363.597927) (xy 169.455876 -363.540761) (xy 169.455338 -363.511846) (xy 169.455822 -363.484476)
			(xy 169.463634 -363.430298) (xy 169.479118 -363.377794) (xy 169.501956 -363.328047) (xy 169.531678 -363.28208)
			(xy 169.549318 -363.261148) (xy 169.558509 -363.249787) (xy 169.57069 -363.223241) (xy 169.57487 -363.194335)
			(xy 169.570709 -363.165426) (xy 169.558547 -363.138872) (xy 169.549318 -363.127544) (xy 169.531723 -363.106575)
			(xy 169.501997 -363.060613) (xy 169.479149 -363.010873) (xy 169.46365 -362.958376) (xy 169.455817 -362.904203)
			(xy 169.455812 -362.849466) (xy 169.463635 -362.795292) (xy 169.479125 -362.742792) (xy 169.501963 -362.693048)
			(xy 169.531681 -362.647081) (xy 169.549318 -362.626148) (xy 169.558509 -362.614787) (xy 169.57069 -362.588241)
			(xy 169.57487 -362.559335) (xy 169.570709 -362.530426) (xy 169.558547 -362.503872) (xy 169.549318 -362.492544)
			(xy 169.531689 -362.471604) (xy 169.501975 -362.425634) (xy 169.479137 -362.375888) (xy 169.463643 -362.323389)
			(xy 169.455813 -362.269215) (xy 169.455338 -362.241846) (xy 169.455798 -362.214592) (xy 169.46355 -362.160639)
			(xy 169.478903 -362.108338) (xy 169.501543 -362.058755) (xy 169.531011 -362.012899) (xy 169.566705 -361.971705)
			(xy 169.607899 -361.936011) (xy 169.653755 -361.906543) (xy 169.703338 -361.883903) (xy 169.755639 -361.86855)
			(xy 169.809592 -361.860798) (xy 169.836846 -361.860338) (xy 169.864216 -361.860826) (xy 169.918394 -361.868637)
			(xy 169.970897 -361.884121) (xy 170.020645 -361.906958) (xy 170.066612 -361.936678) (xy 170.087544 -361.954318)
			(xy 170.098872 -361.963554) (xy 170.125429 -361.97573) (xy 170.154346 -361.979903) (xy 170.183263 -361.97573)
			(xy 170.20982 -361.963554) (xy 170.221148 -361.954318) (xy 170.242091 -361.936693) (xy 170.288061 -361.906978)
			(xy 170.337805 -361.884139) (xy 170.390304 -361.868645) (xy 170.444478 -361.860814) (xy 170.471846 -361.860338)
			(xy 170.500762 -361.860881) (xy 170.557933 -361.869602) (xy 170.613132 -361.886855) (xy 170.665094 -361.912242)
			(xy 170.712628 -361.945182) (xy 170.754646 -361.98492) (xy 170.772836 -362.007404) (xy 170.782733 -362.019209)
			(xy 170.808057 -362.036728) (xy 170.83745 -362.045904) (xy 170.868242 -362.045904) (xy 170.897635 -362.036728)
			(xy 170.922959 -362.019209) (xy 170.932856 -362.007404) (xy 170.951073 -361.984942) (xy 170.993087 -361.945206)
			(xy 171.040617 -361.912264) (xy 171.092573 -361.886872) (xy 171.147766 -361.869611) (xy 171.204932 -361.860876)
			(xy 171.233846 -361.860338) (xy 171.2611 -361.860735) (xy 171.315054 -361.868499) (xy 171.367353 -361.883862)
			(xy 171.416933 -361.906512) (xy 171.462786 -361.935988) (xy 171.503977 -361.971688) (xy 171.539668 -362.012888)
			(xy 171.569132 -362.058747) (xy 171.59177 -362.108333) (xy 171.60712 -362.160636) (xy 171.614871 -362.214591)
			(xy 171.615354 -362.241846) (xy 171.614867 -362.269216) (xy 171.607056 -362.323394) (xy 171.591573 -362.375898)
			(xy 171.568735 -362.425645) (xy 171.539014 -362.471612) (xy 171.521374 -362.492544) (xy 171.512095 -362.503839)
			(xy 171.499926 -362.530409) (xy 171.495763 -362.559335) (xy 171.499946 -362.588258) (xy 171.512133 -362.61482)
			(xy 171.521374 -362.626148) (xy 171.532804 -362.639864) (xy 171.542155 -362.650819) (xy 171.565655 -362.667446)
			(xy 171.592863 -362.676855) (xy 171.621615 -362.678296) (xy 171.649627 -362.671655) (xy 171.674673 -362.657461)
			(xy 171.694761 -362.63684) (xy 171.701968 -362.62437) (xy 171.716343 -362.59857) (xy 171.751735 -362.551293)
			(xy 171.793987 -362.510033) (xy 171.842091 -362.475774) (xy 171.894898 -362.449334) (xy 171.951148 -362.431345)
			(xy 172.009498 -362.422236) (xy 172.039026 -362.421678) (xy 172.066277 -362.422154) (xy 172.120225 -362.429913)
			(xy 172.172519 -362.445271) (xy 172.222095 -362.467914) (xy 172.267945 -362.497382) (xy 172.309134 -362.533074)
			(xy 172.344825 -362.574265) (xy 172.374292 -362.620115) (xy 172.396933 -362.669693) (xy 172.412289 -362.721987)
			(xy 172.420047 -362.775935) (xy 172.420534 -362.803186) (xy 172.420076 -362.830557) (xy 172.412259 -362.884737)
			(xy 172.396769 -362.937241) (xy 172.373925 -362.986987) (xy 172.344197 -363.032953) (xy 172.326554 -363.053884)
			(xy 172.317334 -363.065223) (xy 172.305161 -363.091777) (xy 172.300988 -363.120689) (xy 172.305155 -363.149602)
			(xy 172.317323 -363.176159) (xy 172.326554 -363.187488) (xy 172.344182 -363.208431) (xy 172.373909 -363.254397)
			(xy 172.396756 -363.304141) (xy 172.412254 -363.356642) (xy 172.420084 -363.410819) (xy 172.420086 -363.46556)
			(xy 172.412259 -363.519737) (xy 172.396763 -363.572239) (xy 172.373919 -363.621985) (xy 172.344194 -363.667952)
			(xy 172.326554 -363.688884) (xy 172.317334 -363.700223) (xy 172.305161 -363.726777) (xy 172.300988 -363.755689)
			(xy 172.305155 -363.784602) (xy 172.317323 -363.811159) (xy 172.326554 -363.822488) (xy 172.344194 -363.84342)
			(xy 172.373907 -363.889392) (xy 172.396744 -363.939139) (xy 172.412234 -363.99164) (xy 172.420061 -364.045817)
			(xy 172.420534 -364.073186) (xy 172.420009 -364.100436) (xy 172.412255 -364.154381) (xy 172.396903 -364.206673)
			(xy 172.377828 -364.248446) (xy 172.820838 -364.248446) (xy 172.821375 -364.21953) (xy 172.830098 -364.162359)
			(xy 172.847351 -364.10716) (xy 172.872739 -364.055197) (xy 172.90568 -364.007663) (xy 172.945419 -363.965646)
			(xy 172.967904 -363.947456) (xy 172.979661 -363.937507) (xy 172.997177 -363.912197) (xy 173.006356 -363.882818)
			(xy 173.006364 -363.852038) (xy 172.997202 -363.822654) (xy 172.979701 -363.797334) (xy 172.967904 -363.787436)
			(xy 172.945439 -363.769224) (xy 172.905702 -363.727208) (xy 172.872761 -363.679678) (xy 172.847369 -363.627721)
			(xy 172.830109 -363.572527) (xy 172.821376 -363.515361) (xy 172.820838 -363.486446) (xy 172.821322 -363.459076)
			(xy 172.829134 -363.404898) (xy 172.844618 -363.352394) (xy 172.867456 -363.302647) (xy 172.897178 -363.25668)
			(xy 172.914818 -363.235748) (xy 172.924009 -363.224387) (xy 172.93619 -363.197841) (xy 172.94037 -363.168935)
			(xy 172.936209 -363.140026) (xy 172.924047 -363.113472) (xy 172.914818 -363.102144) (xy 172.897223 -363.081175)
			(xy 172.867497 -363.035213) (xy 172.844649 -362.985473) (xy 172.82915 -362.932976) (xy 172.821317 -362.878803)
			(xy 172.821312 -362.824066) (xy 172.829135 -362.769892) (xy 172.844625 -362.717392) (xy 172.867463 -362.667648)
			(xy 172.897181 -362.621681) (xy 172.914818 -362.600748) (xy 172.924009 -362.589387) (xy 172.93619 -362.562841)
			(xy 172.94037 -362.533935) (xy 172.936209 -362.505026) (xy 172.924047 -362.478472) (xy 172.914818 -362.467144)
			(xy 172.897189 -362.446204) (xy 172.867475 -362.400234) (xy 172.844637 -362.350488) (xy 172.829143 -362.297989)
			(xy 172.821313 -362.243815) (xy 172.820838 -362.216446) (xy 172.821324 -362.189195) (xy 172.82908 -362.135247)
			(xy 172.844435 -362.082952) (xy 172.867077 -362.033375) (xy 172.896543 -361.987525) (xy 172.932234 -361.946334)
			(xy 172.973425 -361.910643) (xy 173.019275 -361.881177) (xy 173.068852 -361.858535) (xy 173.121147 -361.84318)
			(xy 173.175095 -361.835424) (xy 173.229597 -361.835424) (xy 173.283545 -361.84318) (xy 173.33584 -361.858535)
			(xy 173.385417 -361.881177) (xy 173.431267 -361.910643) (xy 173.472458 -361.946334) (xy 173.508149 -361.987525)
			(xy 173.537615 -362.033375) (xy 173.560257 -362.082952) (xy 173.575612 -362.135247) (xy 173.583368 -362.189195)
			(xy 173.583854 -362.216446) (xy 173.583367 -362.243816) (xy 173.575556 -362.297994) (xy 173.560073 -362.350498)
			(xy 173.537235 -362.400245) (xy 173.507514 -362.446212) (xy 173.489874 -362.467144) (xy 173.480595 -362.478439)
			(xy 173.468426 -362.505009) (xy 173.464263 -362.533935) (xy 173.468446 -362.562858) (xy 173.480633 -362.58942)
			(xy 173.489874 -362.600748) (xy 173.50756 -362.621644) (xy 173.537283 -362.667618) (xy 173.560125 -362.717371)
			(xy 173.575618 -362.769878) (xy 173.583442 -362.824062) (xy 173.583437 -362.878807) (xy 173.575603 -362.932989)
			(xy 173.560101 -362.985494) (xy 173.537249 -363.035242) (xy 173.507518 -363.081211) (xy 173.489874 -363.102144)
			(xy 173.480595 -363.113439) (xy 173.468426 -363.140009) (xy 173.464263 -363.168935) (xy 173.468446 -363.197858)
			(xy 173.480633 -363.22442) (xy 173.489874 -363.235748) (xy 173.507498 -363.256692) (xy 173.537213 -363.302661)
			(xy 173.560052 -363.352406) (xy 173.575547 -363.404904) (xy 173.583378 -363.459078) (xy 173.583854 -363.486446)
			(xy 173.583314 -363.515362) (xy 173.574592 -363.572533) (xy 173.55734 -363.627733) (xy 173.531952 -363.679695)
			(xy 173.499012 -363.727229) (xy 173.459273 -363.769246) (xy 173.436788 -363.787436) (xy 173.424939 -363.797285)
			(xy 173.407427 -363.822623) (xy 173.398258 -363.852028) (xy 173.398267 -363.882829) (xy 173.407452 -363.912229)
			(xy 173.424978 -363.937557) (xy 173.436788 -363.947456) (xy 173.459248 -363.965675) (xy 173.498985 -364.007688)
			(xy 173.531927 -364.055217) (xy 173.55732 -364.107173) (xy 173.574581 -364.162366) (xy 173.583316 -364.219532)
			(xy 173.583854 -364.248446) (xy 173.583368 -364.275697) (xy 173.575612 -364.329645) (xy 173.560257 -364.38194)
			(xy 173.537615 -364.431517) (xy 173.508149 -364.477367) (xy 173.472458 -364.518558) (xy 173.431267 -364.554249)
			(xy 173.385417 -364.583715) (xy 173.33584 -364.606357) (xy 173.283545 -364.621712) (xy 173.229597 -364.629468)
			(xy 173.175095 -364.629468) (xy 173.121147 -364.621712) (xy 173.068852 -364.606357) (xy 173.019275 -364.583715)
			(xy 172.973425 -364.554249) (xy 172.932234 -364.518558) (xy 172.896543 -364.477367) (xy 172.867077 -364.431517)
			(xy 172.844435 -364.38194) (xy 172.82908 -364.329645) (xy 172.821324 -364.275697) (xy 172.820838 -364.248446)
			(xy 172.377828 -364.248446) (xy 172.374265 -364.256248) (xy 172.344803 -364.302098) (xy 172.309116 -364.343287)
			(xy 172.26793 -364.378979) (xy 172.222084 -364.408446) (xy 172.172511 -364.431089) (xy 172.12022 -364.446446)
			(xy 172.066276 -364.454206) (xy 172.039026 -364.454694) (xy 172.008913 -364.454148) (xy 171.949431 -364.44471)
			(xy 171.892169 -364.426048) (xy 171.838548 -364.398626) (xy 171.789899 -364.363123) (xy 171.768262 -364.342172)
			(xy 171.757249 -364.331965) (xy 171.730832 -364.31774) (xy 171.701418 -364.311816) (xy 171.671553 -364.314704)
			(xy 171.64382 -364.326156) (xy 171.620618 -364.34518) (xy 171.603954 -364.370131) (xy 171.599098 -364.384336)
			(xy 171.590828 -364.410127) (xy 171.567947 -364.459219) (xy 171.538357 -364.504584) (xy 171.502652 -364.545312)
			(xy 171.461549 -364.580584) (xy 171.415873 -364.609692) (xy 171.366542 -364.632053) (xy 171.314545 -364.647216)
			(xy 171.260927 -364.654878) (xy 171.233846 -364.655354) (xy 171.204929 -364.65482) (xy 171.147758 -364.646097)
			(xy 171.092559 -364.628843) (xy 171.040597 -364.603455) (xy 170.993063 -364.570513) (xy 170.951046 -364.530773)
			(xy 170.932856 -364.508288) (xy 170.922959 -364.496483) (xy 170.897635 -364.478964) (xy 170.868242 -364.469788)
			(xy 170.83745 -364.469788) (xy 170.808057 -364.478964) (xy 170.782733 -364.496483) (xy 170.772836 -364.508288)
			(xy 170.754622 -364.530752) (xy 170.712607 -364.570489) (xy 170.665077 -364.60343) (xy 170.61312 -364.628822)
			(xy 170.557927 -364.646083) (xy 170.500761 -364.654816) (xy 170.471846 -364.655354) (xy 170.444476 -364.654872)
			(xy 170.390297 -364.64706) (xy 170.337794 -364.631575) (xy 170.288047 -364.608737) (xy 170.24208 -364.579014)
			(xy 170.221148 -364.561374) (xy 170.20982 -364.552138) (xy 170.183263 -364.539962) (xy 170.154346 -364.535789)
			(xy 170.125429 -364.539962) (xy 170.098872 -364.552138) (xy 170.087544 -364.561374) (xy 170.066603 -364.579002)
			(xy 170.020633 -364.608716) (xy 169.970888 -364.631555) (xy 169.918389 -364.647048) (xy 169.864215 -364.654879)
			(xy 169.836846 -364.655354) (xy 169.809598 -364.654779) (xy 169.755656 -364.64703) (xy 169.703366 -364.631683)
			(xy 169.653792 -364.609051) (xy 169.607943 -364.579594) (xy 169.566754 -364.543911) (xy 169.531062 -364.50273)
			(xy 169.501593 -364.456889) (xy 169.478949 -364.407321) (xy 169.46359 -364.355034) (xy 169.455827 -364.301094)
			(xy 169.455338 -364.273846) (xy 161.053526 -364.273846) (xy 162.406076 -365.626396) (xy 179.794408 -365.626396)
			(xy 183.39562 -364.134654) (xy 184.43448 -363.09554) (xy 184.43448 -359.245916) (xy 183.30037 -358.111552)
			(xy 182.087774 -358.111552) (xy 182.069637 -358.131211) (xy 182.02876 -358.165709) (xy 181.983468 -358.194163)
			(xy 181.934646 -358.216015) (xy 181.883252 -358.230837) (xy 181.830292 -358.238339) (xy 181.803548 -358.238806)
			(xy 181.776296 -358.2383) (xy 181.722347 -358.23055) (xy 181.67005 -358.2152) (xy 181.620469 -358.192562)
			(xy 181.574616 -358.163099) (xy 181.533423 -358.12741) (xy 181.497728 -358.086221) (xy 181.46826 -358.040371)
			(xy 181.445617 -357.990794) (xy 181.43026 -357.938498) (xy 181.422503 -357.88455) (xy 181.42204 -357.857298)
			(xy 181.422277 -357.838631) (xy 181.425967 -357.801479) (xy 181.429406 -357.78313) (xy 181.431793 -357.768867)
			(xy 181.429265 -357.740068) (xy 181.418763 -357.713134) (xy 181.401128 -357.690227) (xy 181.377777 -357.673184)
			(xy 181.350583 -357.663373) (xy 181.336188 -357.661972) (xy 181.307535 -357.659599) (xy 181.25137 -357.64731)
			(xy 181.197685 -357.626735) (xy 181.147693 -357.598338) (xy 181.102528 -357.562763) (xy 181.063211 -357.520815)
			(xy 181.030633 -357.473442) (xy 181.00553 -357.421719) (xy 180.98847 -357.366815) (xy 180.979841 -357.309973)
			(xy 180.979318 -357.281226) (xy 180.979804 -357.253975) (xy 180.98756 -357.200027) (xy 181.002915 -357.147732)
			(xy 181.025557 -357.098155) (xy 181.055023 -357.052305) (xy 181.090714 -357.011114) (xy 181.131905 -356.975423)
			(xy 181.177755 -356.945957) (xy 181.227332 -356.923315) (xy 181.279627 -356.90796) (xy 181.333575 -356.900204)
			(xy 181.388077 -356.900204) (xy 181.442025 -356.90796) (xy 181.49432 -356.923315) (xy 181.543897 -356.945957)
			(xy 181.589747 -356.975423) (xy 181.630938 -357.011114) (xy 181.666629 -357.052305) (xy 181.696095 -357.098155)
			(xy 181.718737 -357.147732) (xy 181.734092 -357.200027) (xy 181.741848 -357.253975) (xy 181.742334 -357.281226)
			(xy 181.742101 -357.299893) (xy 181.738409 -357.337045) (xy 181.734968 -357.355394) (xy 181.73258 -357.369656)
			(xy 181.735113 -357.398452) (xy 181.745618 -357.425384) (xy 181.763252 -357.44829) (xy 181.786601 -357.465334)
			(xy 181.813792 -357.475148) (xy 181.828186 -357.476552) (xy 181.857717 -357.479038) (xy 181.915541 -357.49201)
			(xy 181.970664 -357.513764) (xy 182.021764 -357.543776) (xy 182.06761 -357.581325) (xy 182.087774 -357.603044)
			(xy 183.40578 -357.603044) (xy 183.430762 -357.603688) (xy 183.479768 -357.613421) (xy 183.525938 -357.632519)
			(xy 183.5675 -357.660249) (xy 183.585612 -357.677466) (xy 184.86882 -358.960674) (xy 184.886107 -358.978741)
			(xy 184.913911 -359.020296) (xy 184.933075 -359.066476) (xy 184.942865 -359.115507) (xy 184.943496 -359.140506)
			(xy 184.943496 -363.20095) (xy 184.942824 -363.225944) (xy 184.93303 -363.274965) (xy 184.913867 -363.321135)
			(xy 184.88607 -363.362684) (xy 184.86882 -363.380782) (xy 183.71947 -364.530132) (xy 183.701349 -364.547358)
			(xy 183.659777 -364.575119) (xy 183.63692 -364.58525) (xy 179.942236 -366.1156) (xy 179.918976 -366.124536)
			(xy 179.870117 -366.134267) (xy 179.845208 -366.134904) (xy 162.300666 -366.134904) (xy 162.275681 -366.134308)
			(xy 162.226672 -366.124562) (xy 162.180502 -366.10545) (xy 162.138943 -366.077706) (xy 162.120834 -366.060482)
			(xy 156.702252 -360.6419) (xy 134.66572 -360.6419) (xy 133.486652 -361.820968) (xy 144.809462 -361.820968)
			(xy 144.813533 -361.765346) (xy 144.825659 -361.710909) (xy 144.845582 -361.658818) (xy 144.872878 -361.610183)
			(xy 144.906964 -361.56604) (xy 144.947113 -361.527331) (xy 144.992471 -361.49488) (xy 145.042071 -361.469379)
			(xy 145.094855 -361.451372) (xy 145.149698 -361.441242) (xy 145.205432 -361.439205) (xy 145.260869 -361.445305)
			(xy 145.314826 -361.459411) (xy 145.366155 -361.481223) (xy 145.413761 -361.510277) (xy 145.456629 -361.545952)
			(xy 145.493846 -361.587489) (xy 145.524619 -361.634002) (xy 145.537251 -361.660948) (xy 145.977862 -361.660948)
			(xy 145.981933 -361.605326) (xy 145.994059 -361.550889) (xy 146.013982 -361.498798) (xy 146.041278 -361.450163)
			(xy 146.075364 -361.40602) (xy 146.115513 -361.367311) (xy 146.160871 -361.33486) (xy 146.210471 -361.309359)
			(xy 146.263255 -361.291352) (xy 146.318098 -361.281222) (xy 146.373832 -361.279185) (xy 146.429269 -361.285285)
			(xy 146.483226 -361.299391) (xy 146.534555 -361.321203) (xy 146.582161 -361.350257) (xy 146.625029 -361.385932)
			(xy 146.662246 -361.427469) (xy 146.693019 -361.473982) (xy 146.716691 -361.524479) (xy 146.732759 -361.577886)
			(xy 146.740879 -361.633062) (xy 146.741388 -361.660948) (xy 146.740879 -361.688834) (xy 146.732759 -361.74401)
			(xy 146.716691 -361.797417) (xy 146.693019 -361.847914) (xy 146.662246 -361.894427) (xy 146.625029 -361.935964)
			(xy 146.582161 -361.971639) (xy 146.534555 -362.000693) (xy 146.483226 -362.022505) (xy 146.429269 -362.036611)
			(xy 146.373832 -362.042711) (xy 146.318098 -362.040674) (xy 146.263255 -362.030544) (xy 146.210471 -362.012537)
			(xy 146.160871 -361.987036) (xy 146.115513 -361.954585) (xy 146.075364 -361.915876) (xy 146.041278 -361.871733)
			(xy 146.013982 -361.823098) (xy 145.994059 -361.771007) (xy 145.981933 -361.71657) (xy 145.977862 -361.660948)
			(xy 145.537251 -361.660948) (xy 145.548291 -361.684499) (xy 145.564359 -361.737906) (xy 145.572479 -361.793082)
			(xy 145.572988 -361.820968) (xy 145.572479 -361.848854) (xy 145.564359 -361.90403) (xy 145.548291 -361.957437)
			(xy 145.524619 -362.007934) (xy 145.493846 -362.054447) (xy 145.456629 -362.095984) (xy 145.413761 -362.131659)
			(xy 145.366155 -362.160713) (xy 145.314826 -362.182525) (xy 145.260869 -362.196631) (xy 145.205432 -362.202731)
			(xy 145.149698 -362.200694) (xy 145.094855 -362.190564) (xy 145.042071 -362.172557) (xy 144.992471 -362.147056)
			(xy 144.947113 -362.114605) (xy 144.906964 -362.075896) (xy 144.872878 -362.031753) (xy 144.845582 -361.983118)
			(xy 144.825659 -361.931027) (xy 144.813533 -361.87659) (xy 144.809462 -361.820968) (xy 133.486652 -361.820968)
			(xy 130.603244 -364.704376) (xy 130.585162 -364.721648) (xy 130.543613 -364.749456) (xy 130.497437 -364.768625)
			(xy 130.44841 -364.778419) (xy 130.423412 -364.779052) (xy 121.5263 -364.779052) (xy 119.204486 -367.100612)
			(xy 119.186392 -367.11787) (xy 119.144846 -367.145679) (xy 119.098675 -367.164852) (xy 119.04965 -367.174651)
			(xy 119.024654 -367.175288) (xy 113.05413 -367.175288) (xy 113.029135 -367.174631) (xy 112.980114 -367.164832)
			(xy 112.933943 -367.145665) (xy 112.892396 -367.117864) (xy 112.874298 -367.100612) (xy 111.09579 -365.322104)
			(xy 111.074454 -365.322104) (xy 111.047178 -365.321636) (xy 110.993174 -365.313944) (xy 110.940815 -365.298638)
			(xy 110.891171 -365.276029) (xy 110.845254 -365.24658) (xy 110.804 -365.21089) (xy 110.76825 -365.169687)
			(xy 110.738735 -365.123812) (xy 110.716054 -365.074201) (xy 110.700673 -365.021865) (xy 110.692903 -364.967871)
			(xy 110.692438 -364.940596) (xy 109.466888 -364.940596) (xy 109.466888 -365.477806) (xy 109.502448 -365.513366)
			(xy 109.842298 -365.513366) (xy 109.846369 -365.457744) (xy 109.858495 -365.403307) (xy 109.878418 -365.351216)
			(xy 109.905714 -365.302581) (xy 109.9398 -365.258438) (xy 109.979949 -365.219729) (xy 110.025307 -365.187278)
			(xy 110.074907 -365.161777) (xy 110.127691 -365.14377) (xy 110.182534 -365.13364) (xy 110.238268 -365.131603)
			(xy 110.293705 -365.137703) (xy 110.347662 -365.151809) (xy 110.398991 -365.173621) (xy 110.446597 -365.202675)
			(xy 110.489465 -365.23835) (xy 110.526682 -365.279887) (xy 110.557455 -365.3264) (xy 110.581127 -365.376897)
			(xy 110.597195 -365.430304) (xy 110.605315 -365.48548) (xy 110.605824 -365.513366) (xy 110.605315 -365.541252)
			(xy 110.597195 -365.596428) (xy 110.581127 -365.649835) (xy 110.557455 -365.700332) (xy 110.526682 -365.746845)
			(xy 110.489465 -365.788382) (xy 110.446597 -365.824057) (xy 110.398991 -365.853111) (xy 110.347662 -365.874923)
			(xy 110.293705 -365.889029) (xy 110.238268 -365.895129) (xy 110.182534 -365.893092) (xy 110.127691 -365.882962)
			(xy 110.074907 -365.864955) (xy 110.025307 -365.839454) (xy 109.979949 -365.807003) (xy 109.9398 -365.768294)
			(xy 109.905714 -365.724151) (xy 109.878418 -365.675516) (xy 109.858495 -365.623425) (xy 109.846369 -365.568988)
			(xy 109.842298 -365.513366) (xy 109.502448 -365.513366) (xy 111.821214 -367.832132) (xy 121.144028 -367.832132)
			(xy 121.148099 -367.77651) (xy 121.160225 -367.722073) (xy 121.180148 -367.669982) (xy 121.207444 -367.621347)
			(xy 121.24153 -367.577204) (xy 121.281679 -367.538495) (xy 121.327037 -367.506044) (xy 121.376637 -367.480543)
			(xy 121.429421 -367.462536) (xy 121.484264 -367.452406) (xy 121.539998 -367.450369) (xy 121.595435 -367.456469)
			(xy 121.649392 -367.470575) (xy 121.700721 -367.492387) (xy 121.748327 -367.521441) (xy 121.791195 -367.557116)
			(xy 121.828412 -367.598653) (xy 121.859185 -367.645166) (xy 121.882857 -367.695663) (xy 121.898925 -367.74907)
			(xy 121.907045 -367.804246) (xy 121.907554 -367.832132) (xy 121.907045 -367.860018) (xy 121.898925 -367.915194)
			(xy 121.882857 -367.968601) (xy 121.859185 -368.019098) (xy 121.828412 -368.065611) (xy 121.791195 -368.107148)
			(xy 121.748327 -368.142823) (xy 121.700721 -368.171877) (xy 121.649392 -368.193689) (xy 121.595435 -368.207795)
			(xy 121.539998 -368.213895) (xy 121.484264 -368.211858) (xy 121.429421 -368.201728) (xy 121.376637 -368.183721)
			(xy 121.327037 -368.15822) (xy 121.281679 -368.125769) (xy 121.24153 -368.08706) (xy 121.207444 -368.042917)
			(xy 121.180148 -367.994282) (xy 121.160225 -367.942191) (xy 121.148099 -367.887754) (xy 121.144028 -367.832132)
			(xy 111.821214 -367.832132) (xy 112.68583 -368.696748) (xy 117.255542 -368.696748) (xy 117.259613 -368.641126)
			(xy 117.271739 -368.586689) (xy 117.291662 -368.534598) (xy 117.318958 -368.485963) (xy 117.353044 -368.44182)
			(xy 117.393193 -368.403111) (xy 117.438551 -368.37066) (xy 117.488151 -368.345159) (xy 117.540935 -368.327152)
			(xy 117.595778 -368.317022) (xy 117.651512 -368.314985) (xy 117.706949 -368.321085) (xy 117.760906 -368.335191)
			(xy 117.812235 -368.357003) (xy 117.859841 -368.386057) (xy 117.902709 -368.421732) (xy 117.939926 -368.463269)
			(xy 117.970699 -368.509782) (xy 117.994371 -368.560279) (xy 118.010439 -368.613686) (xy 118.018559 -368.668862)
			(xy 118.019068 -368.696748) (xy 118.018559 -368.724634) (xy 118.010439 -368.77981) (xy 117.994371 -368.833217)
			(xy 117.970699 -368.883714) (xy 117.939926 -368.930227) (xy 117.902709 -368.971764) (xy 117.859841 -369.007439)
			(xy 117.812235 -369.036493) (xy 117.760906 -369.058305) (xy 117.706949 -369.072411) (xy 117.651512 -369.078511)
			(xy 117.595778 -369.076474) (xy 117.540935 -369.066344) (xy 117.488151 -369.048337) (xy 117.438551 -369.022836)
			(xy 117.393193 -368.990385) (xy 117.353044 -368.951676) (xy 117.318958 -368.907533) (xy 117.291662 -368.858898)
			(xy 117.271739 -368.806807) (xy 117.259613 -368.75237) (xy 117.255542 -368.696748) (xy 112.68583 -368.696748)
			(xy 113.233454 -369.244372) (xy 119.543576 -369.244372) (xy 120.12168 -368.666522) (xy 120.128284 -368.659918)
			(xy 120.250712 -368.53749) (xy 120.431052 -368.53749) (xy 120.434862 -368.537236) (xy 122.27433 -368.537236)
			(xy 122.287504 -368.536791) (xy 122.31296 -368.529988) (xy 122.335827 -368.516896) (xy 122.354581 -368.498386)
			(xy 122.367971 -368.475693) (xy 122.375107 -368.450328) (xy 122.375676 -368.43716) (xy 122.351845 -368.422822)
			(xy 122.307773 -368.388899) (xy 122.268496 -368.349523) (xy 122.234683 -368.305366) (xy 122.206911 -368.25718)
			(xy 122.185653 -368.205787) (xy 122.171271 -368.152062) (xy 122.164011 -368.096922) (xy 122.163586 -368.069114)
			(xy 122.164081 -368.040053) (xy 122.171992 -367.982473) (xy 122.187668 -367.926506) (xy 122.210819 -367.873194)
			(xy 122.241012 -367.823531) (xy 122.277685 -367.77844) (xy 122.320156 -367.738762) (xy 122.367633 -367.705236)
			(xy 122.393202 -367.691416) (xy 122.393108 -367.675471) (xy 122.384304 -367.644843) (xy 122.36651 -367.618406)
			(xy 122.35434 -367.608104) (xy 122.331856 -367.589914) (xy 122.292118 -367.547897) (xy 122.259179 -367.500363)
			(xy 122.233794 -367.4484) (xy 122.216544 -367.393201) (xy 122.207826 -367.33603) (xy 122.207274 -367.307114)
			(xy 122.20776 -367.279863) (xy 122.215516 -367.225915) (xy 122.230871 -367.17362) (xy 122.253513 -367.124043)
			(xy 122.282979 -367.078193) (xy 122.31867 -367.037002) (xy 122.359861 -367.001311) (xy 122.405711 -366.971845)
			(xy 122.455288 -366.949203) (xy 122.507583 -366.933848) (xy 122.561531 -366.926092) (xy 122.616033 -366.926092)
			(xy 122.669981 -366.933848) (xy 122.722276 -366.949203) (xy 122.771853 -366.971845) (xy 122.817703 -367.001311)
			(xy 122.858894 -367.037002) (xy 122.894585 -367.078193) (xy 122.924051 -367.124043) (xy 122.946693 -367.17362)
			(xy 122.962048 -367.225915) (xy 122.969804 -367.279863) (xy 122.97029 -367.307114) (xy 122.969734 -367.336301)
			(xy 122.960842 -367.393993) (xy 122.943266 -367.449658) (xy 122.917418 -367.501996) (xy 122.883899 -367.549787)
			(xy 122.843493 -367.591916) (xy 122.820684 -367.610136) (xy 122.809216 -367.620424) (xy 122.792555 -367.646322)
			(xy 122.784371 -367.67601) (xy 122.784362 -367.691416) (xy 122.809931 -367.705234) (xy 122.857402 -367.738764)
			(xy 122.899867 -367.778445) (xy 122.936536 -367.823536) (xy 122.966724 -367.8732) (xy 122.989871 -367.926511)
			(xy 123.005545 -367.982476) (xy 123.013455 -368.040054) (xy 123.013978 -368.069114) (xy 123.013524 -368.096909)
			(xy 123.006274 -368.152024) (xy 122.9919 -368.205723) (xy 122.970646 -368.25709) (xy 122.942877 -368.305247)
			(xy 122.909066 -368.349372) (xy 122.869789 -368.388711) (xy 122.825719 -368.422594) (xy 122.801888 -368.436906)
			(xy 122.802475 -368.45009) (xy 122.809565 -368.475502) (xy 122.822931 -368.498247) (xy 122.841681 -368.516806)
			(xy 122.864562 -368.529939) (xy 122.890044 -368.536768) (xy 122.903234 -368.537236) (xy 124.422154 -368.537236)
			(xy 124.435326 -368.536788) (xy 124.460777 -368.529981) (xy 124.483638 -368.516887) (xy 124.502387 -368.498378)
			(xy 124.515774 -368.475687) (xy 124.522907 -368.450325) (xy 124.5235 -368.43716) (xy 124.499668 -368.422823)
			(xy 124.455593 -368.388901) (xy 124.416314 -368.349526) (xy 124.382499 -368.305369) (xy 124.354726 -368.257183)
			(xy 124.333466 -368.205789) (xy 124.319084 -368.152064) (xy 124.311823 -368.096922) (xy 124.31141 -368.069114)
			(xy 124.311905 -368.040052) (xy 124.319815 -367.98247) (xy 124.33549 -367.9265) (xy 124.358638 -367.873185)
			(xy 124.388828 -367.823518) (xy 124.425498 -367.778422) (xy 124.467965 -367.738738) (xy 124.515439 -367.705204)
			(xy 124.541026 -367.691416) (xy 124.540933 -367.67547) (xy 124.53213 -367.644841) (xy 124.514338 -367.618401)
			(xy 124.502164 -367.608104) (xy 124.479683 -367.589912) (xy 124.439953 -367.547892) (xy 124.40702 -367.500356)
			(xy 124.38164 -367.448394) (xy 124.364395 -367.393197) (xy 124.355679 -367.336029) (xy 124.355098 -367.307114)
			(xy 124.355584 -367.279863) (xy 124.36334 -367.225915) (xy 124.378695 -367.17362) (xy 124.401337 -367.124043)
			(xy 124.430803 -367.078193) (xy 124.466494 -367.037002) (xy 124.507685 -367.001311) (xy 124.553535 -366.971845)
			(xy 124.603112 -366.949203) (xy 124.655407 -366.933848) (xy 124.709355 -366.926092) (xy 124.763857 -366.926092)
			(xy 124.817805 -366.933848) (xy 124.8701 -366.949203) (xy 124.919677 -366.971845) (xy 124.965527 -367.001311)
			(xy 125.006718 -367.037002) (xy 125.042409 -367.078193) (xy 125.071875 -367.124043) (xy 125.094517 -367.17362)
			(xy 125.109872 -367.225915) (xy 125.117628 -367.279863) (xy 125.118114 -367.307114) (xy 125.117558 -367.336301)
			(xy 125.108666 -367.393994) (xy 125.091091 -367.449659) (xy 125.065244 -367.501999) (xy 125.031727 -367.549792)
			(xy 124.991322 -367.591922) (xy 124.968508 -367.610136) (xy 124.957037 -367.620423) (xy 124.940372 -367.646321)
			(xy 124.932186 -367.676009) (xy 124.932186 -367.691416) (xy 124.957754 -367.705235) (xy 125.005223 -367.738766)
			(xy 125.047685 -367.778448) (xy 125.084351 -367.82354) (xy 125.114538 -367.873203) (xy 125.137684 -367.926513)
			(xy 125.153357 -367.982478) (xy 125.161266 -368.040055) (xy 125.161802 -368.069114) (xy 125.161348 -368.096908)
			(xy 125.154097 -368.152021) (xy 125.139721 -368.205718) (xy 125.118465 -368.257082) (xy 125.090693 -368.305235)
			(xy 125.056879 -368.349356) (xy 125.017599 -368.38869) (xy 124.973526 -368.422565) (xy 124.949712 -368.436906)
			(xy 124.950299 -368.450089) (xy 124.957389 -368.475498) (xy 124.970756 -368.49824) (xy 124.989507 -368.516796)
			(xy 125.012388 -368.529924) (xy 125.037869 -368.536747) (xy 125.051058 -368.537236) (xy 126.555754 -368.537236)
			(xy 126.568926 -368.536788) (xy 126.594377 -368.529981) (xy 126.617238 -368.516887) (xy 126.635987 -368.498378)
			(xy 126.649374 -368.475687) (xy 126.656507 -368.450325) (xy 126.6571 -368.43716) (xy 126.633268 -368.422823)
			(xy 126.589193 -368.388901) (xy 126.549914 -368.349526) (xy 126.516099 -368.305369) (xy 126.488326 -368.257183)
			(xy 126.467066 -368.205789) (xy 126.452684 -368.152064) (xy 126.445423 -368.096922) (xy 126.44501 -368.069114)
			(xy 126.445505 -368.040052) (xy 126.453415 -367.98247) (xy 126.46909 -367.9265) (xy 126.492238 -367.873185)
			(xy 126.522428 -367.823518) (xy 126.559098 -367.778422) (xy 126.601565 -367.738738) (xy 126.649039 -367.705204)
			(xy 126.674626 -367.691416) (xy 126.674533 -367.67547) (xy 126.66573 -367.644841) (xy 126.647938 -367.618401)
			(xy 126.635764 -367.608104) (xy 126.613283 -367.589912) (xy 126.573553 -367.547892) (xy 126.54062 -367.500356)
			(xy 126.51524 -367.448394) (xy 126.497995 -367.393197) (xy 126.489279 -367.336029) (xy 126.488698 -367.307114)
			(xy 126.489184 -367.279863) (xy 126.49694 -367.225915) (xy 126.512295 -367.17362) (xy 126.534937 -367.124043)
			(xy 126.564403 -367.078193) (xy 126.600094 -367.037002) (xy 126.641285 -367.001311) (xy 126.687135 -366.971845)
			(xy 126.736712 -366.949203) (xy 126.789007 -366.933848) (xy 126.842955 -366.926092) (xy 126.897457 -366.926092)
			(xy 126.951405 -366.933848) (xy 127.0037 -366.949203) (xy 127.053277 -366.971845) (xy 127.099127 -367.001311)
			(xy 127.140318 -367.037002) (xy 127.176009 -367.078193) (xy 127.205475 -367.124043) (xy 127.228117 -367.17362)
			(xy 127.243472 -367.225915) (xy 127.251228 -367.279863) (xy 127.251714 -367.307114) (xy 127.251158 -367.336301)
			(xy 127.242266 -367.393994) (xy 127.224691 -367.449659) (xy 127.198844 -367.501999) (xy 127.165327 -367.549792)
			(xy 127.124922 -367.591922) (xy 127.102108 -367.610136) (xy 127.090637 -367.620423) (xy 127.073972 -367.646321)
			(xy 127.065786 -367.676009) (xy 127.065786 -367.691416) (xy 127.091354 -367.705235) (xy 127.138823 -367.738766)
			(xy 127.181285 -367.778448) (xy 127.217951 -367.82354) (xy 127.248138 -367.873203) (xy 127.271284 -367.926513)
			(xy 127.286957 -367.982478) (xy 127.294866 -368.040055) (xy 127.294877 -368.040666) (xy 128.641348 -368.040666)
			(xy 128.641896 -368.01175) (xy 128.650616 -367.954579) (xy 128.667867 -367.89938) (xy 128.693253 -367.847418)
			(xy 128.726193 -367.799884) (xy 128.76593 -367.757867) (xy 128.788414 -367.739676) (xy 128.800251 -367.729814)
			(xy 128.817763 -367.70448) (xy 128.826932 -367.675078) (xy 128.826926 -367.64428) (xy 128.817744 -367.614882)
			(xy 128.800222 -367.589555) (xy 128.788414 -367.579656) (xy 128.765912 -367.561486) (xy 128.726178 -367.519463)
			(xy 128.69324 -367.471923) (xy 128.667855 -367.419958) (xy 128.650603 -367.364756) (xy 128.64188 -367.307583)
			(xy 128.641348 -367.278666) (xy 128.641834 -367.251415) (xy 128.64959 -367.197467) (xy 128.664945 -367.145172)
			(xy 128.687587 -367.095595) (xy 128.717053 -367.049745) (xy 128.752744 -367.008554) (xy 128.793935 -366.972863)
			(xy 128.839785 -366.943397) (xy 128.889362 -366.920755) (xy 128.941657 -366.9054) (xy 128.995605 -366.897644)
			(xy 129.050107 -366.897644) (xy 129.104055 -366.9054) (xy 129.15635 -366.920755) (xy 129.205927 -366.943397)
			(xy 129.251777 -366.972863) (xy 129.292968 -367.008554) (xy 129.328659 -367.049745) (xy 129.358125 -367.095595)
			(xy 129.380767 -367.145172) (xy 129.396122 -367.197467) (xy 129.403878 -367.251415) (xy 129.404364 -367.278666)
			(xy 129.403835 -367.307583) (xy 129.39511 -367.364754) (xy 129.377855 -367.419953) (xy 129.352466 -367.471915)
			(xy 129.319523 -367.519449) (xy 129.279783 -367.561466) (xy 129.257298 -367.579656) (xy 129.245528 -367.589592)
			(xy 129.228013 -367.614905) (xy 129.218835 -367.644288) (xy 129.218829 -367.675071) (xy 129.227994 -367.704457)
			(xy 129.2455 -367.729778) (xy 129.257298 -367.739676) (xy 129.27977 -367.757881) (xy 129.319506 -367.799898)
			(xy 129.352446 -367.84743) (xy 129.377836 -367.899388) (xy 129.395095 -367.954583) (xy 129.403827 -368.011751)
			(xy 129.404364 -368.040666) (xy 129.403878 -368.067917) (xy 129.396122 -368.121865) (xy 129.380767 -368.17416)
			(xy 129.358125 -368.223737) (xy 129.328659 -368.269587) (xy 129.292968 -368.310778) (xy 129.251777 -368.346469)
			(xy 129.205927 -368.375935) (xy 129.15635 -368.398577) (xy 129.104055 -368.413932) (xy 129.050107 -368.421688)
			(xy 128.995605 -368.421688) (xy 128.941657 -368.413932) (xy 128.889362 -368.398577) (xy 128.839785 -368.375935)
			(xy 128.793935 -368.346469) (xy 128.752744 -368.310778) (xy 128.717053 -368.269587) (xy 128.687587 -368.223737)
			(xy 128.664945 -368.17416) (xy 128.64959 -368.121865) (xy 128.641834 -368.067917) (xy 128.641348 -368.040666)
			(xy 127.294877 -368.040666) (xy 127.295402 -368.069114) (xy 127.294948 -368.096908) (xy 127.287697 -368.152021)
			(xy 127.273321 -368.205718) (xy 127.252065 -368.257082) (xy 127.224293 -368.305235) (xy 127.190479 -368.349356)
			(xy 127.151199 -368.38869) (xy 127.107126 -368.422565) (xy 127.083312 -368.436906) (xy 127.083899 -368.450089)
			(xy 127.090989 -368.475498) (xy 127.104356 -368.49824) (xy 127.123107 -368.516796) (xy 127.145988 -368.529924)
			(xy 127.171469 -368.536747) (xy 127.184658 -368.537236) (xy 129.91084 -368.537236) (xy 130.422396 -368.02568)
			(xy 130.422396 -365.407702) (xy 130.42265 -365.398304) (xy 130.42265 -365.223552) (xy 130.545078 -365.101124)
			(xy 130.552444 -365.093758) (xy 132.804662 -362.84154) (xy 132.812028 -362.834174) (xy 132.934456 -362.711746)
			(xy 133.109208 -362.711746) (xy 133.118606 -362.711492) (xy 158.142432 -362.711492) (xy 158.15183 -362.711746)
			(xy 158.326582 -362.711746) (xy 158.44901 -362.834174) (xy 158.456376 -362.84154) (xy 161.876232 -366.261396)
			(xy 179.921662 -366.261396) (xy 183.755538 -364.673134) (xy 190.69812 -357.730552) (xy 190.69812 -333.944468)
			(xy 189.495938 -332.742286) (xy 133.781292 -332.742286) (xy 133.771223 -332.741861) (xy 133.752622 -332.734143)
			(xy 133.745224 -332.7273) (xy 133.417056 -332.399132) (xy 133.410214 -332.391733) (xy 133.402496 -332.373134)
			(xy 133.40207 -332.363064) (xy 133.40207 -331.30871) (xy 131.783582 -329.690476) (xy 127.370332 -329.690476)
			(xy 127.360268 -329.69004) (xy 127.341684 -329.682305) (xy 127.334264 -329.67549) (xy 123.933966 -326.275192)
			(xy 95.285306 -326.275192) (xy 92.013532 -329.546966) (xy 92.006131 -329.553805) (xy 91.987533 -329.56152)
			(xy 91.977464 -329.561952) (xy 86.458806 -329.561952) (xy 84.945728 -331.07503) (xy 84.945728 -332.384146)
			(xy 84.945297 -332.394213) (xy 84.937574 -332.412808) (xy 84.930742 -332.420214) (xy 84.289138 -333.061818)
			(xy 84.28174 -333.068663) (xy 84.263141 -333.076388) (xy 84.25307 -333.076804) (xy 76.985114 -333.076804)
			(xy 76.420472 -333.641446) (xy 76.418186 -333.664814) (xy 76.416916 -333.678276) (xy 76.411582 -333.732886)
			(xy 76.40701 -333.7814) (xy 76.40701 -334.541368) (xy 93.012768 -334.541368) (xy 93.013254 -334.514117)
			(xy 93.02101 -334.460169) (xy 93.036365 -334.407874) (xy 93.059007 -334.358297) (xy 93.088473 -334.312447)
			(xy 93.124164 -334.271256) (xy 93.165355 -334.235565) (xy 93.211205 -334.206099) (xy 93.260782 -334.183457)
			(xy 93.313077 -334.168102) (xy 93.367025 -334.160346) (xy 93.421527 -334.160346) (xy 93.475475 -334.168102)
			(xy 93.52777 -334.183457) (xy 93.577347 -334.206099) (xy 93.623197 -334.235565) (xy 93.664388 -334.271256)
			(xy 93.700079 -334.312447) (xy 93.729545 -334.358297) (xy 93.752187 -334.407874) (xy 93.767542 -334.460169)
			(xy 93.775298 -334.514117) (xy 93.775784 -334.541368) (xy 93.775371 -334.567043) (xy 93.768491 -334.61793)
			(xy 93.75485 -334.667435) (xy 93.734695 -334.714664) (xy 93.70839 -334.758764) (xy 93.692726 -334.779112)
			(xy 93.683994 -334.790855) (xy 93.672944 -334.817938) (xy 93.670019 -334.847042) (xy 93.675461 -334.875781)
			(xy 93.688821 -334.901802) (xy 93.698568 -334.912716) (xy 93.718314 -334.934136) (xy 93.751715 -334.981866)
			(xy 93.777482 -335.034113) (xy 93.795016 -335.089668) (xy 93.803912 -335.147241) (xy 93.804486 -335.176368)
			(xy 101.201982 -335.176368) (xy 101.202409 -335.148996) (xy 101.210233 -335.094815) (xy 101.22573 -335.04231)
			(xy 101.248581 -334.992564) (xy 101.278316 -334.9466) (xy 101.295962 -334.92567) (xy 101.305233 -334.914367)
			(xy 101.317411 -334.887801) (xy 101.321579 -334.858876) (xy 101.317397 -334.829952) (xy 101.305206 -334.803392)
			(xy 101.295962 -334.792066) (xy 101.278334 -334.771125) (xy 101.248622 -334.725154) (xy 101.225784 -334.675409)
			(xy 101.21029 -334.62291) (xy 101.202458 -334.568736) (xy 101.201982 -334.541368) (xy 101.202468 -334.514117)
			(xy 101.210224 -334.460169) (xy 101.225579 -334.407874) (xy 101.248221 -334.358297) (xy 101.277687 -334.312447)
			(xy 101.313378 -334.271256) (xy 101.354569 -334.235565) (xy 101.400419 -334.206099) (xy 101.449996 -334.183457)
			(xy 101.502291 -334.168102) (xy 101.556239 -334.160346) (xy 101.610741 -334.160346) (xy 101.664689 -334.168102)
			(xy 101.716984 -334.183457) (xy 101.766561 -334.206099) (xy 101.812411 -334.235565) (xy 101.853602 -334.271256)
			(xy 101.889293 -334.312447) (xy 101.918759 -334.358297) (xy 101.941401 -334.407874) (xy 101.956756 -334.460169)
			(xy 101.964512 -334.514117) (xy 101.964998 -334.541368) (xy 101.964514 -334.568738) (xy 101.9567 -334.622916)
			(xy 101.941216 -334.675419) (xy 101.918378 -334.725166) (xy 101.888657 -334.771134) (xy 101.871018 -334.792066)
			(xy 101.861811 -334.803416) (xy 101.849628 -334.829965) (xy 101.845448 -334.858876) (xy 101.849614 -334.887788)
			(xy 101.861785 -334.914343) (xy 101.871018 -334.92567) (xy 101.888659 -334.9466) (xy 101.91837 -334.992574)
			(xy 101.941205 -335.042322) (xy 101.956696 -335.094823) (xy 101.964524 -335.148999) (xy 101.964998 -335.176368)
			(xy 109.362494 -335.176368) (xy 109.362943 -335.148997) (xy 109.370765 -335.094817) (xy 109.386258 -335.042314)
			(xy 109.409104 -334.992568) (xy 109.438831 -334.946601) (xy 109.456474 -334.92567) (xy 109.465744 -334.914367)
			(xy 109.477921 -334.887801) (xy 109.482088 -334.858876) (xy 109.477907 -334.829953) (xy 109.465717 -334.803393)
			(xy 109.456474 -334.792066) (xy 109.438848 -334.771123) (xy 109.409135 -334.725153) (xy 109.386297 -334.675408)
			(xy 109.370803 -334.62291) (xy 109.362971 -334.568736) (xy 109.362494 -334.541368) (xy 109.36298 -334.514117)
			(xy 109.370736 -334.460169) (xy 109.386091 -334.407874) (xy 109.408733 -334.358297) (xy 109.438199 -334.312447)
			(xy 109.47389 -334.271256) (xy 109.515081 -334.235565) (xy 109.560931 -334.206099) (xy 109.610508 -334.183457)
			(xy 109.662803 -334.168102) (xy 109.716751 -334.160346) (xy 109.771253 -334.160346) (xy 109.825201 -334.168102)
			(xy 109.877496 -334.183457) (xy 109.927073 -334.206099) (xy 109.972923 -334.235565) (xy 110.014114 -334.271256)
			(xy 110.049805 -334.312447) (xy 110.079271 -334.358297) (xy 110.101913 -334.407874) (xy 110.117268 -334.460169)
			(xy 110.125024 -334.514117) (xy 110.12551 -334.541368) (xy 110.125023 -334.568737) (xy 110.11721 -334.622916)
			(xy 110.101725 -334.675418) (xy 110.078888 -334.725165) (xy 110.049169 -334.771133) (xy 110.03153 -334.792066)
			(xy 110.022322 -334.803415) (xy 110.010137 -334.829965) (xy 110.005957 -334.858876) (xy 110.010123 -334.887789)
			(xy 110.022296 -334.914344) (xy 110.03153 -334.92567) (xy 110.049173 -334.946599) (xy 110.078883 -334.992573)
			(xy 110.101718 -335.042321) (xy 110.117208 -335.094823) (xy 110.125036 -335.148999) (xy 110.12551 -335.176368)
			(xy 117.523006 -335.176368) (xy 117.523452 -335.148997) (xy 117.531274 -335.094817) (xy 117.546768 -335.042314)
			(xy 117.569614 -334.992567) (xy 117.599343 -334.946601) (xy 117.616986 -334.92567) (xy 117.626255 -334.914366)
			(xy 117.63843 -334.8878) (xy 117.642597 -334.858876) (xy 117.638416 -334.829953) (xy 117.626228 -334.803393)
			(xy 117.616986 -334.792066) (xy 117.599362 -334.771122) (xy 117.569649 -334.725152) (xy 117.54681 -334.675408)
			(xy 117.531315 -334.62291) (xy 117.523483 -334.568736) (xy 117.523006 -334.541368) (xy 117.523492 -334.514117)
			(xy 117.531248 -334.460169) (xy 117.546603 -334.407874) (xy 117.569245 -334.358297) (xy 117.598711 -334.312447)
			(xy 117.634402 -334.271256) (xy 117.675593 -334.235565) (xy 117.721443 -334.206099) (xy 117.77102 -334.183457)
			(xy 117.823315 -334.168102) (xy 117.877263 -334.160346) (xy 117.931765 -334.160346) (xy 117.985713 -334.168102)
			(xy 118.038008 -334.183457) (xy 118.087585 -334.206099) (xy 118.133435 -334.235565) (xy 118.174626 -334.271256)
			(xy 118.210317 -334.312447) (xy 118.239783 -334.358297) (xy 118.262425 -334.407874) (xy 118.27778 -334.460169)
			(xy 118.285536 -334.514117) (xy 118.286022 -334.541368) (xy 118.285556 -334.568738) (xy 118.277741 -334.622918)
			(xy 118.262253 -334.675422) (xy 118.239411 -334.725169) (xy 118.209684 -334.771135) (xy 118.192042 -334.792066)
			(xy 118.182841 -334.803418) (xy 118.170666 -334.829968) (xy 118.16649 -334.858876) (xy 118.170653 -334.887785)
			(xy 118.182814 -334.914341) (xy 118.192042 -334.92567) (xy 118.209687 -334.946597) (xy 118.239397 -334.992572)
			(xy 118.262231 -335.042321) (xy 118.277721 -335.094822) (xy 118.285549 -335.148999) (xy 118.286022 -335.176368)
			(xy 118.285536 -335.203619) (xy 118.27778 -335.257567) (xy 118.262425 -335.309862) (xy 118.239783 -335.359439)
			(xy 118.210317 -335.405289) (xy 118.174626 -335.44648) (xy 118.133435 -335.482171) (xy 118.087585 -335.511637)
			(xy 118.038008 -335.534279) (xy 117.985713 -335.549634) (xy 117.931765 -335.55739) (xy 117.877263 -335.55739)
			(xy 117.823315 -335.549634) (xy 117.77102 -335.534279) (xy 117.721443 -335.511637) (xy 117.675593 -335.482171)
			(xy 117.634402 -335.44648) (xy 117.598711 -335.405289) (xy 117.569245 -335.359439) (xy 117.546603 -335.309862)
			(xy 117.531248 -335.257567) (xy 117.523492 -335.203619) (xy 117.523006 -335.176368) (xy 110.12551 -335.176368)
			(xy 110.125024 -335.203619) (xy 110.117268 -335.257567) (xy 110.101913 -335.309862) (xy 110.079271 -335.359439)
			(xy 110.049805 -335.405289) (xy 110.014114 -335.44648) (xy 109.972923 -335.482171) (xy 109.927073 -335.511637)
			(xy 109.877496 -335.534279) (xy 109.825201 -335.549634) (xy 109.771253 -335.55739) (xy 109.716751 -335.55739)
			(xy 109.662803 -335.549634) (xy 109.610508 -335.534279) (xy 109.560931 -335.511637) (xy 109.515081 -335.482171)
			(xy 109.47389 -335.44648) (xy 109.438199 -335.405289) (xy 109.408733 -335.359439) (xy 109.386091 -335.309862)
			(xy 109.370736 -335.257567) (xy 109.36298 -335.203619) (xy 109.362494 -335.176368) (xy 101.964998 -335.176368)
			(xy 101.964512 -335.203619) (xy 101.956756 -335.257567) (xy 101.941401 -335.309862) (xy 101.918759 -335.359439)
			(xy 101.889293 -335.405289) (xy 101.853602 -335.44648) (xy 101.812411 -335.482171) (xy 101.766561 -335.511637)
			(xy 101.716984 -335.534279) (xy 101.664689 -335.549634) (xy 101.610741 -335.55739) (xy 101.556239 -335.55739)
			(xy 101.502291 -335.549634) (xy 101.449996 -335.534279) (xy 101.400419 -335.511637) (xy 101.354569 -335.482171)
			(xy 101.313378 -335.44648) (xy 101.277687 -335.405289) (xy 101.248221 -335.359439) (xy 101.225579 -335.309862)
			(xy 101.210224 -335.257567) (xy 101.202468 -335.203619) (xy 101.201982 -335.176368) (xy 93.804486 -335.176368)
			(xy 93.804 -335.203619) (xy 93.796244 -335.257567) (xy 93.780889 -335.309862) (xy 93.758247 -335.359439)
			(xy 93.728781 -335.405289) (xy 93.69309 -335.44648) (xy 93.651899 -335.482171) (xy 93.606049 -335.511637)
			(xy 93.556472 -335.534279) (xy 93.504177 -335.549634) (xy 93.450229 -335.55739) (xy 93.395727 -335.55739)
			(xy 93.341779 -335.549634) (xy 93.289484 -335.534279) (xy 93.239907 -335.511637) (xy 93.194057 -335.482171)
			(xy 93.152866 -335.44648) (xy 93.117175 -335.405289) (xy 93.087709 -335.359439) (xy 93.065067 -335.309862)
			(xy 93.049712 -335.257567) (xy 93.041956 -335.203619) (xy 93.04147 -335.176368) (xy 93.041913 -335.150694)
			(xy 93.048788 -335.099809) (xy 93.062422 -335.050305) (xy 93.08257 -335.003075) (xy 93.108868 -334.958973)
			(xy 93.124528 -334.938624) (xy 93.133329 -334.926927) (xy 93.144376 -334.899827) (xy 93.147289 -334.870708)
			(xy 93.14183 -334.841957) (xy 93.128445 -334.815933) (xy 93.118686 -334.80502) (xy 93.098966 -334.783577)
			(xy 93.065559 -334.735854) (xy 93.039787 -334.683613) (xy 93.022246 -334.628063) (xy 93.013345 -334.570494)
			(xy 93.012768 -334.541368) (xy 76.40701 -334.541368) (xy 76.40701 -335.579) (xy 97.290117 -335.579)
			(xy 97.294285 -335.523384) (xy 97.306694 -335.469011) (xy 97.327068 -335.417094) (xy 97.354952 -335.368793)
			(xy 97.389723 -335.325188) (xy 97.430604 -335.287251) (xy 97.476682 -335.25583) (xy 97.526928 -335.231627)
			(xy 97.580221 -335.215183) (xy 97.635368 -335.206864) (xy 97.663254 -335.20634) (xy 97.690586 -335.206812)
			(xy 97.744666 -335.214781) (xy 97.797 -335.230569) (xy 97.846465 -335.253837) (xy 97.891997 -335.284084)
			(xy 97.932619 -335.320663) (xy 97.967459 -335.362786) (xy 97.982024 -335.385918) (xy 97.989942 -335.398145)
			(xy 98.011416 -335.417814) (xy 98.03757 -335.430618) (xy 98.066276 -335.435512) (xy 98.095196 -335.4321)
			(xy 98.10877 -335.426812) (xy 98.131987 -335.41734) (xy 98.180316 -335.403982) (xy 98.230003 -335.397247)
			(xy 98.255074 -335.39684) (xy 98.280144 -335.397251) (xy 98.329827 -335.404006) (xy 98.378161 -335.417343)
			(xy 98.401378 -335.426812) (xy 98.414951 -335.43207) (xy 98.443854 -335.435432) (xy 98.472533 -335.430519)
			(xy 98.498669 -335.417728) (xy 98.520144 -335.398094) (xy 98.528124 -335.385918) (xy 98.542693 -335.362787)
			(xy 98.577536 -335.320666) (xy 98.618159 -335.284087) (xy 98.66369 -335.253836) (xy 98.713152 -335.23056)
			(xy 98.765483 -335.21476) (xy 98.819562 -335.206774) (xy 98.874226 -335.206774) (xy 98.928305 -335.21476)
			(xy 98.980636 -335.23056) (xy 99.030098 -335.253836) (xy 99.075629 -335.284087) (xy 99.116252 -335.320666)
			(xy 99.151095 -335.362787) (xy 99.165664 -335.385918) (xy 99.173544 -335.398173) (xy 99.195028 -335.417842)
			(xy 99.221193 -335.430641) (xy 99.249908 -335.435529) (xy 99.278834 -335.432106) (xy 99.29241 -335.426812)
			(xy 99.315622 -335.417328) (xy 99.363954 -335.403974) (xy 99.413643 -335.397244) (xy 99.438714 -335.39684)
			(xy 99.465556 -335.397321) (xy 99.518683 -335.405026) (xy 99.570155 -335.420275) (xy 99.618906 -335.442752)
			(xy 99.663928 -335.471992) (xy 99.704287 -335.50739) (xy 99.73915 -335.548213) (xy 99.767794 -335.593616)
			(xy 99.789627 -335.642659) (xy 99.797362 -335.668366) (xy 99.802083 -335.682841) (xy 99.818592 -335.708398)
			(xy 99.841895 -335.72796) (xy 99.869926 -335.739792) (xy 99.900198 -335.742845) (xy 99.930026 -335.736849)
			(xy 99.943666 -335.730088) (xy 99.97181 -335.715451) (xy 100.031762 -335.694725) (xy 100.094321 -335.684228)
			(xy 100.126038 -335.683606) (xy 100.144057 -335.683825) (xy 100.179932 -335.687261) (xy 100.197666 -335.690464)
			(xy 100.212879 -335.692764) (xy 100.243427 -335.689245) (xy 100.271544 -335.676793) (xy 100.294679 -335.656537)
			(xy 100.310737 -335.630312) (xy 100.315014 -335.615534) (xy 100.3224 -335.588487) (xy 100.344032 -335.536761)
			(xy 100.372998 -335.488756) (xy 100.408676 -335.445505) (xy 100.450296 -335.407938) (xy 100.496965 -335.376865)
			(xy 100.547677 -335.352952) (xy 100.601342 -335.336716) (xy 100.656805 -335.328505) (xy 100.684838 -335.328006)
			(xy 100.712091 -335.328443) (xy 100.766041 -335.336205) (xy 100.818338 -335.351565) (xy 100.867916 -335.374212)
			(xy 100.913767 -335.403683) (xy 100.954957 -335.43938) (xy 100.990648 -335.480575) (xy 101.020113 -335.52643)
			(xy 101.042753 -335.576011) (xy 101.043631 -335.579) (xy 105.450617 -335.579) (xy 105.454785 -335.523383)
			(xy 105.467195 -335.469009) (xy 105.48757 -335.417091) (xy 105.515455 -335.36879) (xy 105.550227 -335.325183)
			(xy 105.591109 -335.287246) (xy 105.637189 -335.255826) (xy 105.687437 -335.231624) (xy 105.740731 -335.21518)
			(xy 105.79588 -335.206863) (xy 105.823766 -335.20634) (xy 105.851098 -335.206803) (xy 105.905179 -335.214774)
			(xy 105.957513 -335.230563) (xy 106.006978 -335.253832) (xy 106.05251 -335.284081) (xy 106.093132 -335.320661)
			(xy 106.127971 -335.362785) (xy 106.142536 -335.385918) (xy 106.150443 -335.398154) (xy 106.17192 -335.417823)
			(xy 106.198077 -335.430625) (xy 106.226786 -335.435517) (xy 106.255707 -335.432101) (xy 106.269282 -335.426812)
			(xy 106.292497 -335.417336) (xy 106.340827 -335.40398) (xy 106.390515 -335.397246) (xy 106.415586 -335.39684)
			(xy 106.440655 -335.397279) (xy 106.490337 -335.404022) (xy 106.538672 -335.417349) (xy 106.56189 -335.426812)
			(xy 106.575495 -335.431977) (xy 106.604381 -335.435359) (xy 106.63305 -335.430467) (xy 106.65918 -335.417697)
			(xy 106.680654 -335.398084) (xy 106.688636 -335.385918) (xy 106.703205 -335.362787) (xy 106.738048 -335.320666)
			(xy 106.778671 -335.284087) (xy 106.824202 -335.253836) (xy 106.873664 -335.23056) (xy 106.925995 -335.21476)
			(xy 106.980074 -335.206774) (xy 107.034738 -335.206774) (xy 107.088817 -335.21476) (xy 107.141148 -335.23056)
			(xy 107.19061 -335.253836) (xy 107.236141 -335.284087) (xy 107.276764 -335.320666) (xy 107.311607 -335.362787)
			(xy 107.326176 -335.385918) (xy 107.33414 -335.398113) (xy 107.355601 -335.417782) (xy 107.381743 -335.430589)
			(xy 107.410438 -335.435492) (xy 107.43935 -335.432092) (xy 107.452922 -335.426812) (xy 107.476132 -335.417324)
			(xy 107.524465 -335.403972) (xy 107.574154 -335.397244) (xy 107.599226 -335.39684) (xy 107.626068 -335.39731)
			(xy 107.679196 -335.405017) (xy 107.730668 -335.420268) (xy 107.779419 -335.442746) (xy 107.824441 -335.471988)
			(xy 107.8648 -335.507387) (xy 107.899663 -335.548211) (xy 107.928307 -335.593614) (xy 107.950139 -335.642658)
			(xy 107.957874 -335.668366) (xy 107.962579 -335.682847) (xy 107.979091 -335.708406) (xy 108.002398 -335.727968)
			(xy 108.030432 -335.7398) (xy 108.060707 -335.742851) (xy 108.090538 -335.736851) (xy 108.104178 -335.730088)
			(xy 108.13232 -335.715447) (xy 108.192273 -335.694722) (xy 108.254833 -335.684227) (xy 108.28655 -335.683606)
			(xy 108.304569 -335.683824) (xy 108.340444 -335.68726) (xy 108.358178 -335.690464) (xy 108.37339 -335.692776)
			(xy 108.403939 -335.689254) (xy 108.432056 -335.676799) (xy 108.455192 -335.65654) (xy 108.471249 -335.630313)
			(xy 108.475526 -335.615534) (xy 108.482901 -335.588483) (xy 108.504534 -335.536757) (xy 108.533502 -335.488751)
			(xy 108.56918 -335.4455) (xy 108.610802 -335.407934) (xy 108.657472 -335.37686) (xy 108.708186 -335.352949)
			(xy 108.761852 -335.336714) (xy 108.817316 -335.328504) (xy 108.84535 -335.328006) (xy 108.872602 -335.328502)
			(xy 108.926553 -335.336252) (xy 108.978851 -335.351603) (xy 109.028432 -335.37424) (xy 109.074286 -335.403705)
			(xy 109.115479 -335.439395) (xy 109.151174 -335.480585) (xy 109.180642 -335.526437) (xy 109.203285 -335.576015)
			(xy 109.204161 -335.579) (xy 113.611117 -335.579) (xy 113.615285 -335.523382) (xy 113.627696 -335.469007)
			(xy 113.648071 -335.417088) (xy 113.675957 -335.368786) (xy 113.710731 -335.325179) (xy 113.751615 -335.287242)
			(xy 113.797696 -335.255822) (xy 113.847945 -335.23162) (xy 113.901241 -335.215178) (xy 113.956391 -335.206863)
			(xy 113.984278 -335.20634) (xy 114.011611 -335.206794) (xy 114.065691 -335.214766) (xy 114.118026 -335.230557)
			(xy 114.167491 -335.253828) (xy 114.213023 -335.284078) (xy 114.253644 -335.320659) (xy 114.288483 -335.362784)
			(xy 114.303048 -335.385918) (xy 114.310943 -335.398162) (xy 114.332423 -335.417831) (xy 114.358584 -335.430632)
			(xy 114.387295 -335.435522) (xy 114.416219 -335.432103) (xy 114.429794 -335.426812) (xy 114.453008 -335.417333)
			(xy 114.501339 -335.403978) (xy 114.551027 -335.397245) (xy 114.576098 -335.39684) (xy 114.601167 -335.397276)
			(xy 114.65085 -335.40402) (xy 114.699184 -335.417348) (xy 114.722402 -335.426812) (xy 114.736003 -335.43199)
			(xy 114.764891 -335.435369) (xy 114.793561 -335.430474) (xy 114.819692 -335.417701) (xy 114.841166 -335.398085)
			(xy 114.849148 -335.385918) (xy 114.863717 -335.362787) (xy 114.89856 -335.320666) (xy 114.939183 -335.284087)
			(xy 114.984714 -335.253836) (xy 115.034176 -335.23056) (xy 115.086507 -335.21476) (xy 115.140586 -335.206774)
			(xy 115.19525 -335.206774) (xy 115.249329 -335.21476) (xy 115.30166 -335.23056) (xy 115.351122 -335.253836)
			(xy 115.396653 -335.284087) (xy 115.437276 -335.320666) (xy 115.472119 -335.362787) (xy 115.486688 -335.385918)
			(xy 115.49464 -335.398121) (xy 115.516105 -335.41779) (xy 115.54225 -335.430596) (xy 115.570948 -335.435497)
			(xy 115.599861 -335.432094) (xy 115.613434 -335.426812) (xy 115.636643 -335.41732) (xy 115.684976 -335.40397)
			(xy 115.734666 -335.397243) (xy 115.759738 -335.39684) (xy 115.78658 -335.3973) (xy 115.839709 -335.405008)
			(xy 115.891181 -335.420261) (xy 115.939933 -335.442741) (xy 115.984954 -335.471983) (xy 116.025313 -335.507383)
			(xy 116.060175 -335.548208) (xy 116.088819 -335.593613) (xy 116.110651 -335.642658) (xy 116.118386 -335.668366)
			(xy 116.123076 -335.682853) (xy 116.13959 -335.708413) (xy 116.1629 -335.727976) (xy 116.190938 -335.739807)
			(xy 116.221216 -335.742856) (xy 116.251049 -335.736853) (xy 116.26469 -335.730088) (xy 116.29283 -335.715442)
			(xy 116.352784 -335.69472) (xy 116.415345 -335.684226) (xy 116.447062 -335.683606) (xy 116.465081 -335.683822)
			(xy 116.500956 -335.687259) (xy 116.51869 -335.690464) (xy 116.5339 -335.692788) (xy 116.564451 -335.689263)
			(xy 116.592569 -335.676805) (xy 116.615704 -335.656543) (xy 116.631761 -335.630314) (xy 116.636038 -335.615534)
			(xy 116.643402 -335.58848) (xy 116.665036 -335.536753) (xy 116.694005 -335.488747) (xy 116.729685 -335.445495)
			(xy 116.771308 -335.407929) (xy 116.81798 -335.376856) (xy 116.868695 -335.352946) (xy 116.922362 -335.336711)
			(xy 116.977827 -335.328503) (xy 117.005862 -335.328006) (xy 117.033115 -335.328491) (xy 117.087065 -335.336243)
			(xy 117.139364 -335.351595) (xy 117.188945 -335.374234) (xy 117.234799 -335.403699) (xy 117.275992 -335.439391)
			(xy 117.311686 -335.480582) (xy 117.341155 -335.526434) (xy 117.363797 -335.576014) (xy 117.364674 -335.579)
			(xy 121.771617 -335.579) (xy 121.775785 -335.523381) (xy 121.788196 -335.469004) (xy 121.808573 -335.417085)
			(xy 121.83646 -335.368782) (xy 121.871235 -335.325175) (xy 121.91212 -335.287238) (xy 121.958203 -335.255818)
			(xy 122.008454 -335.231617) (xy 122.061751 -335.215176) (xy 122.116903 -335.206862) (xy 122.14479 -335.20634)
			(xy 122.172123 -335.206784) (xy 122.226204 -335.214758) (xy 122.278539 -335.230551) (xy 122.328004 -335.253823)
			(xy 122.373536 -335.284075) (xy 122.414157 -335.320657) (xy 122.448995 -335.362784) (xy 122.46356 -335.385918)
			(xy 122.471444 -335.39817) (xy 122.492927 -335.417839) (xy 122.519091 -335.430639) (xy 122.547805 -335.435527)
			(xy 122.57673 -335.432105) (xy 122.590306 -335.426812) (xy 122.613518 -335.417329) (xy 122.66185 -335.403975)
			(xy 122.711539 -335.397245) (xy 122.73661 -335.39684) (xy 122.761679 -335.397272) (xy 122.811362 -335.404018)
			(xy 122.859696 -335.417347) (xy 122.882914 -335.426812) (xy 122.89651 -335.432003) (xy 122.925401 -335.435379)
			(xy 122.954073 -335.430481) (xy 122.980204 -335.417706) (xy 123.001678 -335.398087) (xy 123.00966 -335.385918)
			(xy 123.024229 -335.362787) (xy 123.059072 -335.320666) (xy 123.099695 -335.284087) (xy 123.145226 -335.253836)
			(xy 123.194688 -335.23056) (xy 123.247019 -335.21476) (xy 123.301098 -335.206774) (xy 123.355762 -335.206774)
			(xy 123.409841 -335.21476) (xy 123.462172 -335.23056) (xy 123.511634 -335.253836) (xy 123.557165 -335.284087)
			(xy 123.597788 -335.320666) (xy 123.632631 -335.362787) (xy 123.6472 -335.385918) (xy 123.655141 -335.398129)
			(xy 123.676608 -335.417798) (xy 123.702757 -335.430603) (xy 123.731457 -335.435502) (xy 123.760373 -335.432096)
			(xy 123.773946 -335.426812) (xy 123.797154 -335.417317) (xy 123.845488 -335.403968) (xy 123.895178 -335.397242)
			(xy 123.92025 -335.39684) (xy 123.948136 -335.397416) (xy 124.003286 -335.405721) (xy 124.056582 -335.422155)
			(xy 124.106833 -335.446348) (xy 124.152917 -335.477762) (xy 124.193803 -335.515694) (xy 124.197205 -335.51996)
			(xy 170.076618 -335.51996) (xy 170.076618 -335.435264) (xy 170.084669 -335.35095) (xy 170.100698 -335.267784)
			(xy 170.124559 -335.186517) (xy 170.156038 -335.107887) (xy 170.194849 -335.032606) (xy 170.240639 -334.961354)
			(xy 170.292995 -334.894778) (xy 170.351443 -334.83348) (xy 170.415453 -334.778015) (xy 170.484445 -334.728886)
			(xy 170.557795 -334.686537) (xy 170.634838 -334.651353) (xy 170.714877 -334.623651) (xy 170.797186 -334.603683)
			(xy 170.881021 -334.59163) (xy 170.965622 -334.5876) (xy 171.050223 -334.59163) (xy 171.134058 -334.603683)
			(xy 171.216367 -334.623651) (xy 171.296406 -334.651353) (xy 171.373449 -334.686537) (xy 171.446799 -334.728886)
			(xy 171.515791 -334.778015) (xy 171.579801 -334.83348) (xy 171.638249 -334.894778) (xy 171.690605 -334.961354)
			(xy 171.736395 -335.032606) (xy 171.775206 -335.107887) (xy 171.806685 -335.186517) (xy 171.830546 -335.267784)
			(xy 171.846575 -335.35095) (xy 171.854626 -335.435264) (xy 171.85513 -335.477612) (xy 171.854626 -335.51996)
			(xy 171.85402 -335.52631) (xy 176.26736 -335.52631) (xy 176.26736 -335.441614) (xy 176.275411 -335.3573)
			(xy 176.29144 -335.274134) (xy 176.315301 -335.192867) (xy 176.34678 -335.114237) (xy 176.385591 -335.038956)
			(xy 176.431381 -334.967704) (xy 176.483737 -334.901128) (xy 176.542185 -334.83983) (xy 176.606195 -334.784365)
			(xy 176.675187 -334.735236) (xy 176.748537 -334.692887) (xy 176.82558 -334.657703) (xy 176.905619 -334.630001)
			(xy 176.987928 -334.610033) (xy 177.071763 -334.59798) (xy 177.156364 -334.59395) (xy 177.240965 -334.59798)
			(xy 177.3248 -334.610033) (xy 177.407109 -334.630001) (xy 177.487148 -334.657703) (xy 177.564191 -334.692887)
			(xy 177.637541 -334.735236) (xy 177.706533 -334.784365) (xy 177.770543 -334.83983) (xy 177.828991 -334.901128)
			(xy 177.881347 -334.967704) (xy 177.927137 -335.038956) (xy 177.965948 -335.114237) (xy 177.997427 -335.192867)
			(xy 178.021288 -335.274134) (xy 178.037317 -335.3573) (xy 178.045368 -335.441614) (xy 178.045872 -335.483962)
			(xy 178.045368 -335.52631) (xy 182.46496 -335.52631) (xy 182.46496 -335.441614) (xy 182.473011 -335.3573)
			(xy 182.48904 -335.274134) (xy 182.512901 -335.192867) (xy 182.54438 -335.114237) (xy 182.583191 -335.038956)
			(xy 182.628981 -334.967704) (xy 182.681337 -334.901128) (xy 182.739785 -334.83983) (xy 182.803795 -334.784365)
			(xy 182.872787 -334.735236) (xy 182.946137 -334.692887) (xy 183.02318 -334.657703) (xy 183.103219 -334.630001)
			(xy 183.185528 -334.610033) (xy 183.269363 -334.59798) (xy 183.353964 -334.59395) (xy 183.438565 -334.59798)
			(xy 183.5224 -334.610033) (xy 183.604709 -334.630001) (xy 183.684748 -334.657703) (xy 183.761791 -334.692887)
			(xy 183.835141 -334.735236) (xy 183.904133 -334.784365) (xy 183.968143 -334.83983) (xy 184.026591 -334.901128)
			(xy 184.078947 -334.967704) (xy 184.124737 -335.038956) (xy 184.163548 -335.114237) (xy 184.195027 -335.192867)
			(xy 184.218888 -335.274134) (xy 184.234917 -335.3573) (xy 184.242968 -335.441614) (xy 184.243472 -335.483962)
			(xy 184.242968 -335.52631) (xy 184.234917 -335.610624) (xy 184.218888 -335.69379) (xy 184.195027 -335.775057)
			(xy 184.163548 -335.853687) (xy 184.124737 -335.928968) (xy 184.078947 -336.00022) (xy 184.026591 -336.066796)
			(xy 183.968143 -336.128094) (xy 183.904133 -336.183559) (xy 183.835141 -336.232688) (xy 183.761791 -336.275037)
			(xy 183.684748 -336.310221) (xy 183.604709 -336.337923) (xy 183.5224 -336.357891) (xy 183.438565 -336.369944)
			(xy 183.353964 -336.373975) (xy 183.269363 -336.369944) (xy 183.185528 -336.357891) (xy 183.103219 -336.337923)
			(xy 183.02318 -336.310221) (xy 182.946137 -336.275037) (xy 182.872787 -336.232688) (xy 182.803795 -336.183559)
			(xy 182.739785 -336.128094) (xy 182.681337 -336.066796) (xy 182.628981 -336.00022) (xy 182.583191 -335.928968)
			(xy 182.54438 -335.853687) (xy 182.512901 -335.775057) (xy 182.48904 -335.69379) (xy 182.473011 -335.610624)
			(xy 182.46496 -335.52631) (xy 178.045368 -335.52631) (xy 178.037317 -335.610624) (xy 178.021288 -335.69379)
			(xy 177.997427 -335.775057) (xy 177.965948 -335.853687) (xy 177.927137 -335.928968) (xy 177.881347 -336.00022)
			(xy 177.828991 -336.066796) (xy 177.770543 -336.128094) (xy 177.706533 -336.183559) (xy 177.637541 -336.232688)
			(xy 177.564191 -336.275037) (xy 177.487148 -336.310221) (xy 177.407109 -336.337923) (xy 177.3248 -336.357891)
			(xy 177.240965 -336.369944) (xy 177.156364 -336.373975) (xy 177.071763 -336.369944) (xy 176.987928 -336.357891)
			(xy 176.905619 -336.337923) (xy 176.82558 -336.310221) (xy 176.748537 -336.275037) (xy 176.675187 -336.232688)
			(xy 176.606195 -336.183559) (xy 176.542185 -336.128094) (xy 176.483737 -336.066796) (xy 176.431381 -336.00022)
			(xy 176.385591 -335.928968) (xy 176.34678 -335.853687) (xy 176.315301 -335.775057) (xy 176.29144 -335.69379)
			(xy 176.275411 -335.610624) (xy 176.26736 -335.52631) (xy 171.85402 -335.52631) (xy 171.846575 -335.604274)
			(xy 171.830546 -335.68744) (xy 171.806685 -335.768707) (xy 171.775206 -335.847337) (xy 171.736395 -335.922618)
			(xy 171.690605 -335.99387) (xy 171.638249 -336.060446) (xy 171.579801 -336.121744) (xy 171.515791 -336.177209)
			(xy 171.446799 -336.226338) (xy 171.373449 -336.268687) (xy 171.296406 -336.303871) (xy 171.216367 -336.331573)
			(xy 171.134058 -336.351541) (xy 171.050223 -336.363594) (xy 170.965622 -336.367625) (xy 170.881021 -336.363594)
			(xy 170.797186 -336.351541) (xy 170.714877 -336.331573) (xy 170.634838 -336.303871) (xy 170.557795 -336.268687)
			(xy 170.484445 -336.226338) (xy 170.415453 -336.177209) (xy 170.351443 -336.121744) (xy 170.292995 -336.060446)
			(xy 170.240639 -335.99387) (xy 170.194849 -335.922618) (xy 170.156038 -335.847337) (xy 170.124559 -335.768707)
			(xy 170.100698 -335.68744) (xy 170.084669 -335.604274) (xy 170.076618 -335.51996) (xy 124.197205 -335.51996)
			(xy 124.228579 -335.559296) (xy 124.256467 -335.607595) (xy 124.276844 -335.659511) (xy 124.289256 -335.713884)
			(xy 124.293424 -335.7695) (xy 124.289256 -335.825116) (xy 124.276844 -335.879489) (xy 124.256467 -335.931405)
			(xy 124.228579 -335.979704) (xy 124.193803 -336.023306) (xy 124.152917 -336.061238) (xy 124.106833 -336.092652)
			(xy 124.056582 -336.116845) (xy 124.003286 -336.133279) (xy 123.948136 -336.141584) (xy 123.92025 -336.142076)
			(xy 123.892918 -336.141593) (xy 123.838839 -336.133625) (xy 123.786506 -336.117839) (xy 123.737042 -336.094572)
			(xy 123.691509 -336.064327) (xy 123.650887 -336.02775) (xy 123.616046 -335.985629) (xy 123.60148 -335.962498)
			(xy 123.593554 -335.950276) (xy 123.572084 -335.930605) (xy 123.545931 -335.9178) (xy 123.517226 -335.912904)
			(xy 123.488308 -335.916316) (xy 123.474734 -335.921604) (xy 123.451517 -335.931076) (xy 123.403188 -335.944433)
			(xy 123.353501 -335.951169) (xy 123.32843 -335.951576) (xy 123.30336 -335.951163) (xy 123.253677 -335.944409)
			(xy 123.205343 -335.931072) (xy 123.182126 -335.921604) (xy 123.168553 -335.916343) (xy 123.13965 -335.912979)
			(xy 123.110969 -335.917892) (xy 123.084834 -335.930685) (xy 123.063359 -335.950321) (xy 123.05538 -335.962498)
			(xy 123.040811 -335.985629) (xy 123.005968 -336.02775) (xy 122.965345 -336.064329) (xy 122.919814 -336.09458)
			(xy 122.870352 -336.117856) (xy 122.818021 -336.133656) (xy 122.763942 -336.141642) (xy 122.709278 -336.141642)
			(xy 122.655199 -336.133656) (xy 122.602868 -336.117856) (xy 122.553406 -336.09458) (xy 122.507875 -336.064329)
			(xy 122.467252 -336.02775) (xy 122.432409 -335.985629) (xy 122.41784 -335.962498) (xy 122.409952 -335.950248)
			(xy 122.388471 -335.930577) (xy 122.362308 -335.917776) (xy 122.333594 -335.912888) (xy 122.304669 -335.91631)
			(xy 122.291094 -335.921604) (xy 122.267882 -335.931088) (xy 122.21955 -335.944441) (xy 122.169861 -335.951171)
			(xy 122.14479 -335.951576) (xy 122.116903 -335.951138) (xy 122.061751 -335.942824) (xy 122.008454 -335.926383)
			(xy 121.958203 -335.902182) (xy 121.91212 -335.870762) (xy 121.871235 -335.832825) (xy 121.83646 -335.789218)
			(xy 121.808573 -335.740915) (xy 121.788196 -335.688996) (xy 121.775785 -335.634619) (xy 121.771617 -335.579)
			(xy 117.364674 -335.579) (xy 117.379152 -335.628311) (xy 117.386908 -335.682261) (xy 117.38737 -335.709514)
			(xy 117.386856 -335.737087) (xy 117.378914 -335.791658) (xy 117.3632 -335.844517) (xy 117.340039 -335.894564)
			(xy 117.309915 -335.940755) (xy 117.273454 -335.982127) (xy 117.25275 -336.000344) (xy 117.241835 -336.010226)
			(xy 117.225755 -336.034879) (xy 117.217369 -336.063092) (xy 117.217371 -336.092526) (xy 117.225763 -336.120737)
			(xy 117.241847 -336.145388) (xy 117.25275 -336.155284) (xy 117.273472 -336.173483) (xy 117.30994 -336.214855)
			(xy 117.34007 -336.261046) (xy 117.363235 -336.311095) (xy 117.378951 -336.363959) (xy 117.386892 -336.418534)
			(xy 117.38689 -336.473684) (xy 117.378947 -336.528259) (xy 117.363229 -336.581121) (xy 117.340061 -336.631169)
			(xy 117.331207 -336.644742) (xy 118.31396 -336.644742) (xy 118.318031 -336.58912) (xy 118.330157 -336.534683)
			(xy 118.35008 -336.482592) (xy 118.377376 -336.433957) (xy 118.411462 -336.389814) (xy 118.451611 -336.351105)
			(xy 118.496969 -336.318654) (xy 118.546569 -336.293153) (xy 118.599353 -336.275146) (xy 118.654196 -336.265016)
			(xy 118.70993 -336.262979) (xy 118.765367 -336.269079) (xy 118.819324 -336.283185) (xy 118.870653 -336.304997)
			(xy 118.918259 -336.334051) (xy 118.961127 -336.369726) (xy 118.998344 -336.411263) (xy 119.029117 -336.457776)
			(xy 119.052789 -336.508273) (xy 119.068857 -336.56168) (xy 119.076977 -336.616856) (xy 119.077486 -336.644742)
			(xy 119.076977 -336.672628) (xy 119.068857 -336.727804) (xy 119.052789 -336.781211) (xy 119.029117 -336.831708)
			(xy 118.998344 -336.878221) (xy 118.961127 -336.919758) (xy 118.918259 -336.955433) (xy 118.870653 -336.984487)
			(xy 118.819324 -337.006299) (xy 118.765367 -337.020405) (xy 118.70993 -337.026505) (xy 118.654196 -337.024468)
			(xy 118.599353 -337.014338) (xy 118.546569 -336.996331) (xy 118.496969 -336.97083) (xy 118.451611 -336.938379)
			(xy 118.411462 -336.89967) (xy 118.377376 -336.855527) (xy 118.35008 -336.806892) (xy 118.330157 -336.754801)
			(xy 118.318031 -336.700364) (xy 118.31396 -336.644742) (xy 117.331207 -336.644742) (xy 117.309929 -336.67736)
			(xy 117.273459 -336.71873) (xy 117.25275 -336.736944) (xy 117.241835 -336.746826) (xy 117.225755 -336.771479)
			(xy 117.217369 -336.799692) (xy 117.217371 -336.829126) (xy 117.225763 -336.857337) (xy 117.241847 -336.881988)
			(xy 117.25275 -336.891884) (xy 117.273467 -336.910089) (xy 117.309934 -336.95146) (xy 117.340065 -336.997652)
			(xy 117.363229 -337.047701) (xy 117.378945 -337.100564) (xy 117.386884 -337.155139) (xy 117.38737 -337.182714)
			(xy 117.386958 -337.209969) (xy 117.379845 -337.259422) (xy 117.522496 -337.259422) (xy 117.526567 -337.2038)
			(xy 117.538693 -337.149363) (xy 117.558616 -337.097272) (xy 117.585912 -337.048637) (xy 117.619998 -337.004494)
			(xy 117.660147 -336.965785) (xy 117.705505 -336.933334) (xy 117.755105 -336.907833) (xy 117.807889 -336.889826)
			(xy 117.862732 -336.879696) (xy 117.918466 -336.877659) (xy 117.973903 -336.883759) (xy 118.02786 -336.897865)
			(xy 118.079189 -336.919677) (xy 118.126795 -336.948731) (xy 118.169663 -336.984406) (xy 118.20688 -337.025943)
			(xy 118.237653 -337.072456) (xy 118.261325 -337.122953) (xy 118.277393 -337.17636) (xy 118.285513 -337.231536)
			(xy 118.286022 -337.259422) (xy 118.285513 -337.287308) (xy 118.277393 -337.342484) (xy 118.261325 -337.395891)
			(xy 118.237653 -337.446388) (xy 118.20688 -337.492901) (xy 118.169663 -337.534438) (xy 118.126795 -337.570113)
			(xy 118.079189 -337.599167) (xy 118.02786 -337.620979) (xy 117.973903 -337.635085) (xy 117.918466 -337.641185)
			(xy 117.862732 -337.639148) (xy 117.807889 -337.629018) (xy 117.755105 -337.611011) (xy 117.705505 -337.58551)
			(xy 117.660147 -337.553059) (xy 117.619998 -337.51435) (xy 117.585912 -337.470207) (xy 117.558616 -337.421572)
			(xy 117.538693 -337.369481) (xy 117.526567 -337.315044) (xy 117.522496 -337.259422) (xy 117.379845 -337.259422)
			(xy 117.379198 -337.263924) (xy 117.363838 -337.316225) (xy 117.341192 -337.365808) (xy 117.311718 -337.411663)
			(xy 117.276019 -337.452856) (xy 117.234821 -337.48855) (xy 117.188962 -337.518016) (xy 117.139376 -337.540657)
			(xy 117.087073 -337.556009) (xy 117.033117 -337.563762) (xy 117.005862 -337.564222) (xy 116.978006 -337.563717)
			(xy 116.922891 -337.555588) (xy 116.869541 -337.539539) (xy 116.819089 -337.515909) (xy 116.772605 -337.4852)
			(xy 116.731076 -337.448063) (xy 116.695383 -337.405287) (xy 116.666284 -337.357779) (xy 116.644395 -337.306547)
			(xy 116.6368 -337.279742) (xy 116.632472 -337.265645) (xy 116.617096 -337.240501) (xy 116.595191 -337.220783)
			(xy 116.568575 -337.208127) (xy 116.539455 -337.203582) (xy 116.524786 -337.205066) (xy 116.511769 -337.206735)
			(xy 116.485585 -337.208515) (xy 116.472462 -337.208622) (xy 116.458313 -337.208532) (xy 116.43009 -337.206495)
			(xy 116.416074 -337.204558) (xy 116.402721 -337.203043) (xy 116.376039 -337.206134) (xy 116.351092 -337.216091)
			(xy 116.329615 -337.232222) (xy 116.313101 -337.253406) (xy 116.302698 -337.27817) (xy 116.300504 -337.291426)
			(xy 116.296414 -337.318579) (xy 116.281442 -337.37141) (xy 116.259052 -337.42155) (xy 116.229705 -337.467961)
			(xy 116.194009 -337.509686) (xy 116.152699 -337.545863) (xy 116.106629 -337.575744) (xy 116.056752 -337.598712)
			(xy 116.004098 -337.614293) (xy 115.949754 -337.622165) (xy 115.922298 -337.622642) (xy 115.895048 -337.622124)
			(xy 115.841103 -337.614368) (xy 115.788811 -337.599015) (xy 115.739236 -337.576376) (xy 115.693388 -337.546912)
			(xy 115.652198 -337.511224) (xy 115.616507 -337.470038) (xy 115.58704 -337.424192) (xy 115.564397 -337.374619)
			(xy 115.549039 -337.322328) (xy 115.541278 -337.268384) (xy 115.54079 -337.241134) (xy 115.541283 -337.21356)
			(xy 115.54923 -337.158989) (xy 115.56495 -337.10613) (xy 115.588115 -337.056084) (xy 115.618243 -337.009893)
			(xy 115.654705 -336.968521) (xy 115.67541 -336.950304) (xy 115.686272 -336.94037) (xy 115.702343 -336.915729)
			(xy 115.71073 -336.887531) (xy 115.710736 -336.858113) (xy 115.702362 -336.829911) (xy 115.686301 -336.805263)
			(xy 115.67541 -336.795364) (xy 115.65468 -336.777173) (xy 115.618211 -336.7358) (xy 115.588081 -336.689606)
			(xy 115.564918 -336.639554) (xy 115.549206 -336.586688) (xy 115.541272 -336.53211) (xy 115.54079 -336.504534)
			(xy 115.541227 -336.478032) (xy 115.548576 -336.425541) (xy 115.563125 -336.374573) (xy 115.584592 -336.326111)
			(xy 115.612563 -336.281089) (xy 115.629182 -336.26044) (xy 115.638623 -336.248295) (xy 115.650406 -336.219894)
			(xy 115.653226 -336.189276) (xy 115.646829 -336.159201) (xy 115.631793 -336.13238) (xy 115.609472 -336.111232)
			(xy 115.595908 -336.103976) (xy 115.572209 -336.091892) (xy 115.528229 -336.061964) (xy 115.48895 -336.026088)
			(xy 115.45517 -335.984993) (xy 115.440968 -335.962498) (xy 115.433053 -335.950267) (xy 115.41158 -335.930597)
			(xy 115.385424 -335.917793) (xy 115.356717 -335.912899) (xy 115.327796 -335.916314) (xy 115.314222 -335.921604)
			(xy 115.291007 -335.931079) (xy 115.242677 -335.944436) (xy 115.192989 -335.95117) (xy 115.167918 -335.951576)
			(xy 115.142849 -335.951134) (xy 115.093167 -335.944392) (xy 115.044832 -335.931067) (xy 115.021614 -335.921604)
			(xy 115.008009 -335.916436) (xy 114.979123 -335.913053) (xy 114.950453 -335.917945) (xy 114.924323 -335.930716)
			(xy 114.902849 -335.950331) (xy 114.894868 -335.962498) (xy 114.880299 -335.985629) (xy 114.845456 -336.02775)
			(xy 114.804833 -336.064329) (xy 114.759302 -336.09458) (xy 114.70984 -336.117856) (xy 114.657509 -336.133656)
			(xy 114.60343 -336.141642) (xy 114.548766 -336.141642) (xy 114.494687 -336.133656) (xy 114.442356 -336.117856)
			(xy 114.392894 -336.09458) (xy 114.347363 -336.064329) (xy 114.30674 -336.02775) (xy 114.271897 -335.985629)
			(xy 114.257328 -335.962498) (xy 114.249451 -335.95024) (xy 114.227967 -335.930569) (xy 114.201801 -335.917769)
			(xy 114.173085 -335.912883) (xy 114.144158 -335.916308) (xy 114.130582 -335.921604) (xy 114.107371 -335.931092)
			(xy 114.059039 -335.944443) (xy 114.00935 -335.951172) (xy 113.984278 -335.951576) (xy 113.956391 -335.951137)
			(xy 113.901241 -335.942822) (xy 113.847945 -335.92638) (xy 113.797696 -335.902178) (xy 113.751615 -335.870758)
			(xy 113.710731 -335.832821) (xy 113.675957 -335.789214) (xy 113.648071 -335.740912) (xy 113.627696 -335.688993)
			(xy 113.615285 -335.634618) (xy 113.611117 -335.579) (xy 109.204161 -335.579) (xy 109.21864 -335.628312)
			(xy 109.226396 -335.682262) (xy 109.226858 -335.709514) (xy 109.226348 -335.737087) (xy 109.218406 -335.791659)
			(xy 109.202691 -335.844518) (xy 109.17953 -335.894565) (xy 109.149404 -335.940755) (xy 109.112943 -335.982128)
			(xy 109.092238 -336.000344) (xy 109.081324 -336.010227) (xy 109.065246 -336.03488) (xy 109.056861 -336.063093)
			(xy 109.056864 -336.092525) (xy 109.065254 -336.120737) (xy 109.081336 -336.145387) (xy 109.092238 -336.155284)
			(xy 109.11296 -336.173483) (xy 109.149429 -336.214854) (xy 109.179561 -336.261046) (xy 109.202726 -336.311095)
			(xy 109.218443 -336.363958) (xy 109.226384 -336.418534) (xy 109.226383 -336.473684) (xy 109.218439 -336.52826)
			(xy 109.20272 -336.581122) (xy 109.179552 -336.63117) (xy 109.170698 -336.644742) (xy 110.153448 -336.644742)
			(xy 110.157519 -336.58912) (xy 110.169645 -336.534683) (xy 110.189568 -336.482592) (xy 110.216864 -336.433957)
			(xy 110.25095 -336.389814) (xy 110.291099 -336.351105) (xy 110.336457 -336.318654) (xy 110.386057 -336.293153)
			(xy 110.438841 -336.275146) (xy 110.493684 -336.265016) (xy 110.549418 -336.262979) (xy 110.604855 -336.269079)
			(xy 110.658812 -336.283185) (xy 110.710141 -336.304997) (xy 110.757747 -336.334051) (xy 110.800615 -336.369726)
			(xy 110.837832 -336.411263) (xy 110.868605 -336.457776) (xy 110.892277 -336.508273) (xy 110.908345 -336.56168)
			(xy 110.916465 -336.616856) (xy 110.916974 -336.644742) (xy 110.916465 -336.672628) (xy 110.908345 -336.727804)
			(xy 110.892277 -336.781211) (xy 110.868605 -336.831708) (xy 110.837832 -336.878221) (xy 110.800615 -336.919758)
			(xy 110.757747 -336.955433) (xy 110.710141 -336.984487) (xy 110.658812 -337.006299) (xy 110.604855 -337.020405)
			(xy 110.549418 -337.026505) (xy 110.493684 -337.024468) (xy 110.438841 -337.014338) (xy 110.386057 -336.996331)
			(xy 110.336457 -336.97083) (xy 110.291099 -336.938379) (xy 110.25095 -336.89967) (xy 110.216864 -336.855527)
			(xy 110.189568 -336.806892) (xy 110.169645 -336.754801) (xy 110.157519 -336.700364) (xy 110.153448 -336.644742)
			(xy 109.170698 -336.644742) (xy 109.149418 -336.677361) (xy 109.112947 -336.71873) (xy 109.092238 -336.736944)
			(xy 109.081324 -336.746827) (xy 109.065246 -336.77148) (xy 109.056861 -336.799693) (xy 109.056864 -336.829125)
			(xy 109.065254 -336.857337) (xy 109.081336 -336.881987) (xy 109.092238 -336.891884) (xy 109.112952 -336.910092)
			(xy 109.149421 -336.951462) (xy 109.179551 -336.997653) (xy 109.202716 -337.047702) (xy 109.218433 -337.100564)
			(xy 109.226372 -337.155139) (xy 109.226858 -337.182714) (xy 109.226458 -337.20997) (xy 109.218698 -337.263925)
			(xy 109.216141 -337.27263) (xy 109.505494 -337.27263) (xy 109.509565 -337.217008) (xy 109.521691 -337.162571)
			(xy 109.541614 -337.11048) (xy 109.56891 -337.061845) (xy 109.602996 -337.017702) (xy 109.643145 -336.978993)
			(xy 109.688503 -336.946542) (xy 109.738103 -336.921041) (xy 109.790887 -336.903034) (xy 109.84573 -336.892904)
			(xy 109.901464 -336.890867) (xy 109.956901 -336.896967) (xy 110.010858 -336.911073) (xy 110.062187 -336.932885)
			(xy 110.109793 -336.961939) (xy 110.152661 -336.997614) (xy 110.189878 -337.039151) (xy 110.220651 -337.085664)
			(xy 110.244323 -337.136161) (xy 110.260391 -337.189568) (xy 110.268511 -337.244744) (xy 110.26902 -337.27263)
			(xy 110.268511 -337.300516) (xy 110.260391 -337.355692) (xy 110.244323 -337.409099) (xy 110.220651 -337.459596)
			(xy 110.189878 -337.506109) (xy 110.152661 -337.547646) (xy 110.109793 -337.583321) (xy 110.062187 -337.612375)
			(xy 110.010858 -337.634187) (xy 109.956901 -337.648293) (xy 109.901464 -337.654393) (xy 109.84573 -337.652356)
			(xy 109.790887 -337.642226) (xy 109.738103 -337.624219) (xy 109.688503 -337.598718) (xy 109.643145 -337.566267)
			(xy 109.602996 -337.527558) (xy 109.56891 -337.483415) (xy 109.541614 -337.43478) (xy 109.521691 -337.382689)
			(xy 109.509565 -337.328252) (xy 109.505494 -337.27263) (xy 109.216141 -337.27263) (xy 109.203337 -337.316227)
			(xy 109.18069 -337.365811) (xy 109.151216 -337.411667) (xy 109.115515 -337.45286) (xy 109.074315 -337.488554)
			(xy 109.028455 -337.51802) (xy 108.978867 -337.54066) (xy 108.926563 -337.556011) (xy 108.872606 -337.563763)
			(xy 108.84535 -337.564222) (xy 108.817494 -337.563728) (xy 108.762378 -337.555598) (xy 108.709028 -337.539546)
			(xy 108.658576 -337.515915) (xy 108.612092 -337.485204) (xy 108.570563 -337.448066) (xy 108.534871 -337.405289)
			(xy 108.505771 -337.35778) (xy 108.483883 -337.306548) (xy 108.476288 -337.279742) (xy 108.471972 -337.26564)
			(xy 108.456594 -337.240496) (xy 108.434686 -337.220778) (xy 108.408067 -337.208123) (xy 108.378944 -337.20358)
			(xy 108.364274 -337.205066) (xy 108.351258 -337.206736) (xy 108.325073 -337.208515) (xy 108.31195 -337.208622)
			(xy 108.297801 -337.208523) (xy 108.269578 -337.206492) (xy 108.255562 -337.204558) (xy 108.24221 -337.203031)
			(xy 108.215527 -337.206124) (xy 108.19058 -337.216084) (xy 108.169103 -337.232218) (xy 108.152589 -337.253404)
			(xy 108.142186 -337.278169) (xy 108.139992 -337.291426) (xy 108.135913 -337.318581) (xy 108.120941 -337.371413)
			(xy 108.09855 -337.421553) (xy 108.069202 -337.467965) (xy 108.033504 -337.509691) (xy 107.992193 -337.545867)
			(xy 107.946122 -337.575748) (xy 107.896244 -337.598716) (xy 107.843588 -337.614295) (xy 107.789242 -337.622166)
			(xy 107.761786 -337.622642) (xy 107.734536 -337.622135) (xy 107.680591 -337.614378) (xy 107.628298 -337.599023)
			(xy 107.578723 -337.576382) (xy 107.532875 -337.546918) (xy 107.491686 -337.511229) (xy 107.455994 -337.470041)
			(xy 107.426527 -337.424194) (xy 107.403884 -337.37462) (xy 107.388526 -337.322329) (xy 107.380766 -337.268384)
			(xy 107.380278 -337.241134) (xy 107.380775 -337.213561) (xy 107.388722 -337.15899) (xy 107.404441 -337.106131)
			(xy 107.427606 -337.056085) (xy 107.457732 -337.009894) (xy 107.494194 -336.968521) (xy 107.514898 -336.950304)
			(xy 107.525761 -336.940371) (xy 107.541834 -336.91573) (xy 107.550222 -336.887532) (xy 107.550228 -336.858112)
			(xy 107.541853 -336.82991) (xy 107.52579 -336.805262) (xy 107.514898 -336.795364) (xy 107.494166 -336.777176)
			(xy 107.457697 -336.735802) (xy 107.427568 -336.689607) (xy 107.404406 -336.639555) (xy 107.388694 -336.586688)
			(xy 107.38076 -336.53211) (xy 107.380278 -336.504534) (xy 107.380717 -336.478032) (xy 107.388067 -336.425541)
			(xy 107.402615 -336.374573) (xy 107.424081 -336.326111) (xy 107.452052 -336.281089) (xy 107.46867 -336.26044)
			(xy 107.478115 -336.248298) (xy 107.489899 -336.219896) (xy 107.49272 -336.189276) (xy 107.486322 -336.1592)
			(xy 107.471284 -336.132379) (xy 107.448961 -336.111232) (xy 107.435396 -336.103976) (xy 107.411695 -336.091896)
			(xy 107.367716 -336.061966) (xy 107.328437 -336.026089) (xy 107.294658 -335.984993) (xy 107.280456 -335.962498)
			(xy 107.272553 -335.950259) (xy 107.251076 -335.930588) (xy 107.224917 -335.917786) (xy 107.196207 -335.912894)
			(xy 107.167285 -335.916313) (xy 107.15371 -335.921604) (xy 107.130496 -335.931083) (xy 107.082165 -335.944438)
			(xy 107.032477 -335.95117) (xy 107.007406 -335.951576) (xy 106.982337 -335.951138) (xy 106.932655 -335.944394)
			(xy 106.88432 -335.931067) (xy 106.861102 -335.921604) (xy 106.847502 -335.916424) (xy 106.818613 -335.913043)
			(xy 106.789942 -335.917938) (xy 106.763811 -335.930712) (xy 106.742337 -335.95033) (xy 106.734356 -335.962498)
			(xy 106.719787 -335.985629) (xy 106.684944 -336.02775) (xy 106.644321 -336.064329) (xy 106.59879 -336.09458)
			(xy 106.549328 -336.117856) (xy 106.496997 -336.133656) (xy 106.442918 -336.141642) (xy 106.388254 -336.141642)
			(xy 106.334175 -336.133656) (xy 106.281844 -336.117856) (xy 106.232382 -336.09458) (xy 106.186851 -336.064329)
			(xy 106.146228 -336.02775) (xy 106.111385 -335.985629) (xy 106.096816 -335.962498) (xy 106.088856 -335.9503)
			(xy 106.067395 -335.930629) (xy 106.041251 -335.917821) (xy 106.012555 -335.912919) (xy 105.983642 -335.916322)
			(xy 105.97007 -335.921604) (xy 105.946861 -335.931095) (xy 105.898528 -335.944446) (xy 105.848838 -335.951173)
			(xy 105.823766 -335.951576) (xy 105.79588 -335.951137) (xy 105.740731 -335.94282) (xy 105.687437 -335.926376)
			(xy 105.637189 -335.902174) (xy 105.591109 -335.870754) (xy 105.550227 -335.832817) (xy 105.515455 -335.78921)
			(xy 105.48757 -335.740909) (xy 105.467195 -335.688991) (xy 105.454785 -335.634617) (xy 105.450617 -335.579)
			(xy 101.043631 -335.579) (xy 101.058107 -335.62831) (xy 101.065861 -335.682261) (xy 101.066346 -335.709514)
			(xy 101.06584 -335.737087) (xy 101.057898 -335.791659) (xy 101.042183 -335.844519) (xy 101.01902 -335.894566)
			(xy 100.988894 -335.940756) (xy 100.952431 -335.982128) (xy 100.931726 -336.000344) (xy 100.920813 -336.010227)
			(xy 100.904737 -336.034881) (xy 100.896353 -336.063093) (xy 100.896356 -336.092525) (xy 100.904745 -336.120736)
			(xy 100.920825 -336.145386) (xy 100.931726 -336.155284) (xy 100.952444 -336.173485) (xy 100.988906 -336.214859)
			(xy 101.01903 -336.261052) (xy 101.04219 -336.311101) (xy 101.057903 -336.363962) (xy 101.065842 -336.418535)
			(xy 101.06584 -336.473683) (xy 101.057899 -336.528256) (xy 101.042184 -336.581116) (xy 101.019021 -336.631164)
			(xy 101.010165 -336.644742) (xy 101.992936 -336.644742) (xy 101.997007 -336.58912) (xy 102.009133 -336.534683)
			(xy 102.029056 -336.482592) (xy 102.056352 -336.433957) (xy 102.090438 -336.389814) (xy 102.130587 -336.351105)
			(xy 102.175945 -336.318654) (xy 102.225545 -336.293153) (xy 102.278329 -336.275146) (xy 102.333172 -336.265016)
			(xy 102.388906 -336.262979) (xy 102.444343 -336.269079) (xy 102.4983 -336.283185) (xy 102.549629 -336.304997)
			(xy 102.597235 -336.334051) (xy 102.640103 -336.369726) (xy 102.67732 -336.411263) (xy 102.708093 -336.457776)
			(xy 102.731765 -336.508273) (xy 102.747833 -336.56168) (xy 102.755953 -336.616856) (xy 102.756462 -336.644742)
			(xy 102.755953 -336.672628) (xy 102.747833 -336.727804) (xy 102.731765 -336.781211) (xy 102.708093 -336.831708)
			(xy 102.67732 -336.878221) (xy 102.640103 -336.919758) (xy 102.597235 -336.955433) (xy 102.549629 -336.984487)
			(xy 102.4983 -337.006299) (xy 102.444343 -337.020405) (xy 102.388906 -337.026505) (xy 102.333172 -337.024468)
			(xy 102.278329 -337.014338) (xy 102.225545 -336.996331) (xy 102.175945 -336.97083) (xy 102.130587 -336.938379)
			(xy 102.090438 -336.89967) (xy 102.056352 -336.855527) (xy 102.029056 -336.806892) (xy 102.009133 -336.754801)
			(xy 101.997007 -336.700364) (xy 101.992936 -336.644742) (xy 101.010165 -336.644742) (xy 100.988895 -336.677355)
			(xy 100.952431 -336.718728) (xy 100.931726 -336.736944) (xy 100.920813 -336.746827) (xy 100.904737 -336.771481)
			(xy 100.896353 -336.799693) (xy 100.896356 -336.829125) (xy 100.904745 -336.857336) (xy 100.920825 -336.881986)
			(xy 100.931726 -336.891884) (xy 100.952438 -336.910094) (xy 100.988907 -336.951464) (xy 101.019038 -336.997654)
			(xy 101.042204 -337.047702) (xy 101.05792 -337.100565) (xy 101.06586 -337.155139) (xy 101.066346 -337.182714)
			(xy 101.065835 -337.209964) (xy 101.063837 -337.223862) (xy 101.236524 -337.223862) (xy 101.240595 -337.16824)
			(xy 101.252721 -337.113803) (xy 101.272644 -337.061712) (xy 101.29994 -337.013077) (xy 101.334026 -336.968934)
			(xy 101.374175 -336.930225) (xy 101.419533 -336.897774) (xy 101.469133 -336.872273) (xy 101.521917 -336.854266)
			(xy 101.57676 -336.844136) (xy 101.632494 -336.842099) (xy 101.687931 -336.848199) (xy 101.741888 -336.862305)
			(xy 101.793217 -336.884117) (xy 101.840823 -336.913171) (xy 101.883691 -336.948846) (xy 101.920908 -336.990383)
			(xy 101.951681 -337.036896) (xy 101.975353 -337.087393) (xy 101.991421 -337.1408) (xy 101.999541 -337.195976)
			(xy 102.00005 -337.223862) (xy 101.999541 -337.251748) (xy 101.991421 -337.306924) (xy 101.975353 -337.360331)
			(xy 101.951681 -337.410828) (xy 101.920908 -337.457341) (xy 101.883691 -337.498878) (xy 101.840823 -337.534553)
			(xy 101.793217 -337.563607) (xy 101.741888 -337.585419) (xy 101.687931 -337.599525) (xy 101.632494 -337.605625)
			(xy 101.57676 -337.603588) (xy 101.521917 -337.593458) (xy 101.469133 -337.575451) (xy 101.419533 -337.54995)
			(xy 101.374175 -337.517499) (xy 101.334026 -337.47879) (xy 101.29994 -337.434647) (xy 101.272644 -337.386012)
			(xy 101.252721 -337.333921) (xy 101.240595 -337.279484) (xy 101.236524 -337.223862) (xy 101.063837 -337.223862)
			(xy 101.058078 -337.263909) (xy 101.042723 -337.316201) (xy 101.020083 -337.365775) (xy 100.990619 -337.411624)
			(xy 100.95493 -337.452813) (xy 100.913743 -337.488504) (xy 100.867897 -337.517971) (xy 100.818323 -337.540615)
			(xy 100.766032 -337.555973) (xy 100.712088 -337.563734) (xy 100.684838 -337.564222) (xy 100.656985 -337.563648)
			(xy 100.601872 -337.555531) (xy 100.548524 -337.539491) (xy 100.498072 -337.515871) (xy 100.451588 -337.48517)
			(xy 100.410058 -337.448041) (xy 100.374364 -337.405272) (xy 100.345263 -337.357771) (xy 100.323372 -337.306545)
			(xy 100.315776 -337.279742) (xy 100.311472 -337.265636) (xy 100.296091 -337.24049) (xy 100.274181 -337.220772)
			(xy 100.247558 -337.208119) (xy 100.218433 -337.203579) (xy 100.203762 -337.205066) (xy 100.190746 -337.206737)
			(xy 100.164561 -337.208516) (xy 100.151438 -337.208622) (xy 100.137289 -337.208524) (xy 100.109066 -337.206493)
			(xy 100.09505 -337.204558) (xy 100.081699 -337.203018) (xy 100.055015 -337.206115) (xy 100.030067 -337.216077)
			(xy 100.00859 -337.232213) (xy 99.992076 -337.253401) (xy 99.981673 -337.278168) (xy 99.97948 -337.291426)
			(xy 99.975413 -337.318584) (xy 99.96044 -337.371416) (xy 99.938048 -337.421557) (xy 99.908699 -337.46797)
			(xy 99.873 -337.509695) (xy 99.831687 -337.545872) (xy 99.785615 -337.575752) (xy 99.735735 -337.598719)
			(xy 99.683078 -337.614298) (xy 99.628731 -337.622166) (xy 99.601274 -337.622642) (xy 99.574024 -337.622146)
			(xy 99.520078 -337.614387) (xy 99.467786 -337.599031) (xy 99.418211 -337.576389) (xy 99.372362 -337.546923)
			(xy 99.331173 -337.511233) (xy 99.295482 -337.470045) (xy 99.266015 -337.424197) (xy 99.243372 -337.374622)
			(xy 99.228014 -337.32233) (xy 99.220254 -337.268384) (xy 99.219766 -337.241134) (xy 99.220232 -337.213559)
			(xy 99.228181 -337.158985) (xy 99.243905 -337.106124) (xy 99.267075 -337.056078) (xy 99.297208 -337.009889)
			(xy 99.333678 -336.968519) (xy 99.354386 -336.950304) (xy 99.36525 -336.940371) (xy 99.381326 -336.915731)
			(xy 99.389714 -336.887532) (xy 99.389721 -336.858112) (xy 99.381344 -336.829909) (xy 99.365279 -336.805262)
			(xy 99.354386 -336.795364) (xy 99.333651 -336.777178) (xy 99.297184 -336.735804) (xy 99.267055 -336.689609)
			(xy 99.243893 -336.639556) (xy 99.228182 -336.586689) (xy 99.220248 -336.53211) (xy 99.219766 -336.504534)
			(xy 99.220208 -336.478033) (xy 99.227557 -336.425541) (xy 99.242105 -336.374574) (xy 99.26357 -336.326112)
			(xy 99.29154 -336.281089) (xy 99.308158 -336.26044) (xy 99.317607 -336.2483) (xy 99.329393 -336.219898)
			(xy 99.332214 -336.189277) (xy 99.325816 -336.159199) (xy 99.310776 -336.132377) (xy 99.28845 -336.111231)
			(xy 99.274884 -336.103976) (xy 99.251197 -336.091869) (xy 99.207215 -336.061949) (xy 99.167932 -336.026079)
			(xy 99.134148 -335.98499) (xy 99.119944 -335.962498) (xy 99.112052 -335.950251) (xy 99.090572 -335.93058)
			(xy 99.06441 -335.917779) (xy 99.035698 -335.912889) (xy 99.006773 -335.916311) (xy 98.993198 -335.921604)
			(xy 98.969986 -335.931087) (xy 98.921654 -335.94444) (xy 98.871965 -335.951171) (xy 98.846894 -335.951576)
			(xy 98.821825 -335.951142) (xy 98.772142 -335.944396) (xy 98.723808 -335.931068) (xy 98.70059 -335.921604)
			(xy 98.686994 -335.916411) (xy 98.658103 -335.913032) (xy 98.62943 -335.91793) (xy 98.603298 -335.930707)
			(xy 98.581825 -335.950328) (xy 98.573844 -335.962498) (xy 98.559275 -335.985629) (xy 98.524432 -336.02775)
			(xy 98.483809 -336.064329) (xy 98.438278 -336.09458) (xy 98.388816 -336.117856) (xy 98.336485 -336.133656)
			(xy 98.282406 -336.141642) (xy 98.227742 -336.141642) (xy 98.173663 -336.133656) (xy 98.121332 -336.117856)
			(xy 98.07187 -336.09458) (xy 98.026339 -336.064329) (xy 97.985716 -336.02775) (xy 97.950873 -335.985629)
			(xy 97.936304 -335.962498) (xy 97.928355 -335.950292) (xy 97.906891 -335.930621) (xy 97.880744 -335.917814)
			(xy 97.852045 -335.912914) (xy 97.823131 -335.91632) (xy 97.809558 -335.921604) (xy 97.78635 -335.931099)
			(xy 97.738016 -335.944448) (xy 97.688326 -335.951174) (xy 97.663254 -335.951576) (xy 97.635368 -335.951136)
			(xy 97.580221 -335.942817) (xy 97.526928 -335.926373) (xy 97.476682 -335.90217) (xy 97.430604 -335.870749)
			(xy 97.389723 -335.832812) (xy 97.354952 -335.789207) (xy 97.327068 -335.740906) (xy 97.306694 -335.688989)
			(xy 97.294285 -335.634616) (xy 97.290117 -335.579) (xy 76.40701 -335.579) (xy 76.40701 -336.644742)
			(xy 93.832424 -336.644742) (xy 93.836495 -336.58912) (xy 93.848621 -336.534683) (xy 93.868544 -336.482592)
			(xy 93.89584 -336.433957) (xy 93.929926 -336.389814) (xy 93.970075 -336.351105) (xy 94.015433 -336.318654)
			(xy 94.065033 -336.293153) (xy 94.117817 -336.275146) (xy 94.17266 -336.265016) (xy 94.228394 -336.262979)
			(xy 94.283831 -336.269079) (xy 94.337788 -336.283185) (xy 94.389117 -336.304997) (xy 94.436723 -336.334051)
			(xy 94.479591 -336.369726) (xy 94.516808 -336.411263) (xy 94.547581 -336.457776) (xy 94.571253 -336.508273)
			(xy 94.587321 -336.56168) (xy 94.595441 -336.616856) (xy 94.59595 -336.644742) (xy 94.595441 -336.672628)
			(xy 94.587321 -336.727804) (xy 94.571253 -336.781211) (xy 94.547581 -336.831708) (xy 94.516808 -336.878221)
			(xy 94.479591 -336.919758) (xy 94.436723 -336.955433) (xy 94.389117 -336.984487) (xy 94.337788 -337.006299)
			(xy 94.283831 -337.020405) (xy 94.228394 -337.026505) (xy 94.17266 -337.024468) (xy 94.117817 -337.014338)
			(xy 94.065033 -336.996331) (xy 94.015433 -336.97083) (xy 93.970075 -336.938379) (xy 93.929926 -336.89967)
			(xy 93.89584 -336.855527) (xy 93.868544 -336.806892) (xy 93.848621 -336.754801) (xy 93.836495 -336.700364)
			(xy 93.832424 -336.644742) (xy 76.40701 -336.644742) (xy 76.40701 -337.352894) (xy 93.189296 -337.352894)
			(xy 93.193367 -337.297272) (xy 93.205493 -337.242835) (xy 93.225416 -337.190744) (xy 93.252712 -337.142109)
			(xy 93.286798 -337.097966) (xy 93.326947 -337.059257) (xy 93.372305 -337.026806) (xy 93.421905 -337.001305)
			(xy 93.474689 -336.983298) (xy 93.529532 -336.973168) (xy 93.585266 -336.971131) (xy 93.640703 -336.977231)
			(xy 93.69466 -336.991337) (xy 93.745989 -337.013149) (xy 93.793595 -337.042203) (xy 93.836463 -337.077878)
			(xy 93.87368 -337.119415) (xy 93.904453 -337.165928) (xy 93.928125 -337.216425) (xy 93.944193 -337.269832)
			(xy 93.952313 -337.325008) (xy 93.952822 -337.352894) (xy 93.952313 -337.38078) (xy 93.944193 -337.435956)
			(xy 93.928125 -337.489363) (xy 93.904453 -337.53986) (xy 93.87368 -337.586373) (xy 93.836463 -337.62791)
			(xy 93.793595 -337.663585) (xy 93.745989 -337.692639) (xy 93.69466 -337.714451) (xy 93.640703 -337.728557)
			(xy 93.585266 -337.734657) (xy 93.529532 -337.73262) (xy 93.474689 -337.72249) (xy 93.421905 -337.704483)
			(xy 93.372305 -337.678982) (xy 93.326947 -337.646531) (xy 93.286798 -337.607822) (xy 93.252712 -337.563679)
			(xy 93.225416 -337.515044) (xy 93.205493 -337.462953) (xy 93.193367 -337.408516) (xy 93.189296 -337.352894)
			(xy 76.40701 -337.352894) (xy 76.40701 -338.671662) (xy 84.701634 -338.671662) (xy 84.70209 -338.644953)
			(xy 84.709554 -338.592057) (xy 84.724317 -338.540718) (xy 84.746092 -338.491938) (xy 84.774452 -338.446669)
			(xy 84.808845 -338.405794) (xy 84.848599 -338.370111) (xy 84.892938 -338.340318) (xy 84.916772 -338.328254)
			(xy 84.929938 -338.321345) (xy 84.951847 -338.301262) (xy 84.967048 -338.275722) (xy 84.974254 -338.246888)
			(xy 84.972856 -338.2172) (xy 84.962971 -338.189171) (xy 84.954618 -338.17687) (xy 84.937282 -338.152202)
			(xy 84.909765 -338.098558) (xy 84.891027 -338.041254) (xy 84.881534 -337.981717) (xy 84.880958 -337.951572)
			(xy 84.881444 -337.924321) (xy 84.8892 -337.870373) (xy 84.904555 -337.818078) (xy 84.927197 -337.768501)
			(xy 84.956663 -337.722651) (xy 84.992354 -337.68146) (xy 85.033545 -337.645769) (xy 85.079395 -337.616303)
			(xy 85.128972 -337.593661) (xy 85.181267 -337.578306) (xy 85.235215 -337.57055) (xy 85.289717 -337.57055)
			(xy 85.343665 -337.578306) (xy 85.39596 -337.593661) (xy 85.445537 -337.616303) (xy 85.491387 -337.645769)
			(xy 85.532578 -337.68146) (xy 85.568269 -337.722651) (xy 85.597735 -337.768501) (xy 85.620377 -337.818078)
			(xy 85.635732 -337.870373) (xy 85.643488 -337.924321) (xy 85.643974 -337.951572) (xy 85.643543 -337.978282)
			(xy 85.636074 -338.031178) (xy 85.621306 -338.082518) (xy 85.599528 -338.131298) (xy 85.571165 -338.176567)
			(xy 85.536769 -338.217441) (xy 85.513487 -338.238338) (xy 94.63913 -338.238338) (xy 94.639701 -338.20865)
			(xy 94.648894 -338.149991) (xy 94.667066 -338.093465) (xy 94.693776 -338.040437) (xy 94.72838 -337.992188)
			(xy 94.770042 -337.949884) (xy 94.793562 -337.93176) (xy 94.804147 -337.923306) (xy 94.820861 -337.902002)
			(xy 94.831386 -337.877054) (xy 94.834982 -337.850216) (xy 94.831395 -337.823376) (xy 94.820877 -337.798425)
			(xy 94.80417 -337.777116) (xy 94.793562 -337.768692) (xy 94.77004 -337.750571) (xy 94.728382 -337.708263)
			(xy 94.69378 -337.660013) (xy 94.667069 -337.606985) (xy 94.648895 -337.55046) (xy 94.639696 -337.491801)
			(xy 94.63913 -337.462114) (xy 94.639616 -337.434863) (xy 94.647372 -337.380915) (xy 94.662727 -337.32862)
			(xy 94.685369 -337.279043) (xy 94.714835 -337.233193) (xy 94.750526 -337.192002) (xy 94.791717 -337.156311)
			(xy 94.837567 -337.126845) (xy 94.887144 -337.104203) (xy 94.939439 -337.088848) (xy 94.993387 -337.081092)
			(xy 95.047889 -337.081092) (xy 95.101837 -337.088848) (xy 95.154132 -337.104203) (xy 95.203709 -337.126845)
			(xy 95.249559 -337.156311) (xy 95.29075 -337.192002) (xy 95.326441 -337.233193) (xy 95.355907 -337.279043)
			(xy 95.378549 -337.32862) (xy 95.393904 -337.380915) (xy 95.40166 -337.434863) (xy 95.402146 -337.462114)
			(xy 95.401623 -337.491804) (xy 95.39242 -337.550465) (xy 95.37424 -337.606993) (xy 95.347521 -337.66002)
			(xy 95.335442 -337.676857) (xy 95.655521 -337.676857) (xy 95.655521 -337.622343) (xy 95.66328 -337.568384)
			(xy 95.678639 -337.516078) (xy 95.701286 -337.466491) (xy 95.730761 -337.420632) (xy 95.766462 -337.379435)
			(xy 95.807662 -337.343738) (xy 95.853524 -337.314268) (xy 95.903114 -337.291626) (xy 95.955421 -337.276272)
			(xy 96.009381 -337.268518) (xy 96.036638 -337.268058) (xy 96.061874 -337.268444) (xy 96.111908 -337.275066)
			(xy 96.160628 -337.288243) (xy 96.20718 -337.307742) (xy 96.22917 -337.320128) (xy 96.24216 -337.327118)
			(xy 96.270787 -337.334163) (xy 96.300234 -337.332729) (xy 96.328041 -337.322936) (xy 96.351888 -337.305602)
			(xy 96.369784 -337.282173) (xy 96.375474 -337.268566) (xy 96.386157 -337.241784) (xy 96.414448 -337.191543)
			(xy 96.44998 -337.146135) (xy 96.491944 -337.106593) (xy 96.539383 -337.07382) (xy 96.591215 -337.048563)
			(xy 96.64626 -337.031398) (xy 96.703261 -337.022716) (xy 96.73209 -337.022186) (xy 96.759342 -337.022665)
			(xy 96.813292 -337.03042) (xy 96.86559 -337.045775) (xy 96.915169 -337.068415) (xy 96.961022 -337.097882)
			(xy 97.002215 -337.133574) (xy 97.037909 -337.174765) (xy 97.067377 -337.220617) (xy 97.09002 -337.270195)
			(xy 97.105377 -337.322492) (xy 97.113134 -337.376442) (xy 97.113598 -337.403694) (xy 97.113073 -337.433599)
			(xy 97.103754 -337.492678) (xy 97.095056 -337.521296) (xy 97.091124 -337.53523) (xy 97.090201 -337.564145)
			(xy 97.097449 -337.592153) (xy 97.112281 -337.616992) (xy 97.1335 -337.636657) (xy 97.159394 -337.64956)
			(xy 97.173542 -337.652614) (xy 97.199616 -337.657777) (xy 97.25012 -337.674349) (xy 97.297832 -337.697774)
			(xy 97.34183 -337.727597) (xy 97.38126 -337.763241) (xy 97.415359 -337.804014) (xy 97.443465 -337.849128)
			(xy 97.465035 -337.897707) (xy 97.47965 -337.948811) (xy 97.487027 -338.00145) (xy 97.487486 -338.028026)
			(xy 97.487 -338.055277) (xy 97.479244 -338.109225) (xy 97.463889 -338.16152) (xy 97.441247 -338.211097)
			(xy 97.42374 -338.238338) (xy 102.799642 -338.238338) (xy 102.800208 -338.20865) (xy 102.809402 -338.149991)
			(xy 102.827574 -338.093464) (xy 102.854285 -338.040436) (xy 102.88889 -337.992187) (xy 102.930553 -337.949883)
			(xy 102.954074 -337.93176) (xy 102.964658 -337.923305) (xy 102.98137 -337.902001) (xy 102.991894 -337.877053)
			(xy 102.995489 -337.850216) (xy 102.991902 -337.823377) (xy 102.981386 -337.798426) (xy 102.964681 -337.777116)
			(xy 102.954074 -337.768692) (xy 102.930554 -337.750568) (xy 102.888895 -337.708261) (xy 102.854293 -337.660011)
			(xy 102.827582 -337.606984) (xy 102.809407 -337.550459) (xy 102.800208 -337.491801) (xy 102.799642 -337.462114)
			(xy 102.800128 -337.434863) (xy 102.807884 -337.380915) (xy 102.823239 -337.32862) (xy 102.845881 -337.279043)
			(xy 102.875347 -337.233193) (xy 102.911038 -337.192002) (xy 102.952229 -337.156311) (xy 102.998079 -337.126845)
			(xy 103.047656 -337.104203) (xy 103.099951 -337.088848) (xy 103.153899 -337.081092) (xy 103.208401 -337.081092)
			(xy 103.262349 -337.088848) (xy 103.314644 -337.104203) (xy 103.364221 -337.126845) (xy 103.410071 -337.156311)
			(xy 103.451262 -337.192002) (xy 103.486953 -337.233193) (xy 103.516419 -337.279043) (xy 103.539061 -337.32862)
			(xy 103.554416 -337.380915) (xy 103.562172 -337.434863) (xy 103.562658 -337.462114) (xy 103.56213 -337.491803)
			(xy 103.552928 -337.550464) (xy 103.534748 -337.606992) (xy 103.50803 -337.660019) (xy 103.495955 -337.676851)
			(xy 103.816144 -337.676851) (xy 103.816144 -337.622349) (xy 103.8239 -337.5684) (xy 103.839254 -337.516105)
			(xy 103.861893 -337.466527) (xy 103.891357 -337.420675) (xy 103.927047 -337.379482) (xy 103.968235 -337.343787)
			(xy 104.014083 -337.314317) (xy 104.063658 -337.291671) (xy 104.115952 -337.27631) (xy 104.169899 -337.268547)
			(xy 104.19715 -337.268058) (xy 104.222386 -337.268439) (xy 104.27242 -337.275063) (xy 104.32114 -337.288241)
			(xy 104.367692 -337.307741) (xy 104.389682 -337.320128) (xy 104.402665 -337.327132) (xy 104.431295 -337.334175)
			(xy 104.460744 -337.332738) (xy 104.488552 -337.322943) (xy 104.5124 -337.305606) (xy 104.530296 -337.282174)
			(xy 104.535986 -337.268566) (xy 104.546659 -337.24178) (xy 104.574951 -337.191539) (xy 104.610485 -337.14613)
			(xy 104.65245 -337.106588) (xy 104.699891 -337.073816) (xy 104.751724 -337.04856) (xy 104.80677 -337.031396)
			(xy 104.863772 -337.022715) (xy 104.892602 -337.022186) (xy 104.919853 -337.022676) (xy 104.9738 -337.030433)
			(xy 105.026095 -337.045788) (xy 105.075671 -337.068429) (xy 105.121522 -337.097894) (xy 105.162712 -337.133586)
			(xy 105.198403 -337.174775) (xy 105.22787 -337.220625) (xy 105.250511 -337.270202) (xy 105.265867 -337.322496)
			(xy 105.273624 -337.376443) (xy 105.27411 -337.403694) (xy 105.273584 -337.433599) (xy 105.264265 -337.492678)
			(xy 105.255568 -337.521296) (xy 105.251626 -337.535228) (xy 105.250703 -337.564145) (xy 105.257952 -337.592155)
			(xy 105.272786 -337.616995) (xy 105.294008 -337.63666) (xy 105.319904 -337.649562) (xy 105.334054 -337.652614)
			(xy 105.36013 -337.657768) (xy 105.410633 -337.674342) (xy 105.458346 -337.697768) (xy 105.502343 -337.727592)
			(xy 105.541773 -337.763237) (xy 105.575872 -337.804012) (xy 105.603978 -337.849126) (xy 105.625547 -337.897706)
			(xy 105.640162 -337.948811) (xy 105.647539 -338.001449) (xy 105.647998 -338.028026) (xy 105.647512 -338.055277)
			(xy 105.639756 -338.109225) (xy 105.624401 -338.16152) (xy 105.601759 -338.211097) (xy 105.584252 -338.238338)
			(xy 110.960154 -338.238338) (xy 110.960715 -338.20865) (xy 110.969909 -338.14999) (xy 110.988082 -338.093463)
			(xy 111.014794 -338.040435) (xy 111.0494 -337.992187) (xy 111.091064 -337.949883) (xy 111.114586 -337.93176)
			(xy 111.125169 -337.923305) (xy 111.141879 -337.902) (xy 111.152402 -337.877052) (xy 111.155996 -337.850216)
			(xy 111.15241 -337.823378) (xy 111.141895 -337.798427) (xy 111.125192 -337.777117) (xy 111.114586 -337.768692)
			(xy 111.091069 -337.750565) (xy 111.049409 -337.708259) (xy 111.014806 -337.66001) (xy 110.988095 -337.606983)
			(xy 110.96992 -337.550459) (xy 110.96072 -337.491801) (xy 110.960154 -337.462114) (xy 110.96064 -337.434863)
			(xy 110.968396 -337.380915) (xy 110.983751 -337.32862) (xy 111.006393 -337.279043) (xy 111.035859 -337.233193)
			(xy 111.07155 -337.192002) (xy 111.112741 -337.156311) (xy 111.158591 -337.126845) (xy 111.208168 -337.104203)
			(xy 111.260463 -337.088848) (xy 111.314411 -337.081092) (xy 111.368913 -337.081092) (xy 111.422861 -337.088848)
			(xy 111.475156 -337.104203) (xy 111.524733 -337.126845) (xy 111.570583 -337.156311) (xy 111.611774 -337.192002)
			(xy 111.647465 -337.233193) (xy 111.676931 -337.279043) (xy 111.699573 -337.32862) (xy 111.714928 -337.380915)
			(xy 111.722684 -337.434863) (xy 111.72317 -337.462114) (xy 111.722637 -337.491803) (xy 111.713435 -337.550464)
			(xy 111.695256 -337.606991) (xy 111.668539 -337.660018) (xy 111.656463 -337.676852) (xy 111.976644 -337.676852)
			(xy 111.976644 -337.622348) (xy 111.9844 -337.568399) (xy 111.999755 -337.516102) (xy 112.022395 -337.466523)
			(xy 112.05186 -337.420671) (xy 112.087551 -337.379478) (xy 112.12874 -337.343783) (xy 112.17459 -337.314313)
			(xy 112.224167 -337.291668) (xy 112.276462 -337.276308) (xy 112.33041 -337.268546) (xy 112.357662 -337.268058)
			(xy 112.382898 -337.268433) (xy 112.432933 -337.275059) (xy 112.481653 -337.288238) (xy 112.528204 -337.307741)
			(xy 112.550194 -337.320128) (xy 112.56317 -337.327146) (xy 112.591803 -337.334187) (xy 112.621253 -337.332748)
			(xy 112.649064 -337.322949) (xy 112.672912 -337.30561) (xy 112.690808 -337.282176) (xy 112.696498 -337.268566)
			(xy 112.707161 -337.241776) (xy 112.735454 -337.191534) (xy 112.770989 -337.146125) (xy 112.812956 -337.106583)
			(xy 112.860398 -337.073812) (xy 112.912233 -337.048556) (xy 112.96728 -337.031393) (xy 113.024284 -337.022714)
			(xy 113.053114 -337.022186) (xy 113.080365 -337.022665) (xy 113.134313 -337.030423) (xy 113.186608 -337.04578)
			(xy 113.236184 -337.068422) (xy 113.282034 -337.097889) (xy 113.323224 -337.133581) (xy 113.358916 -337.174772)
			(xy 113.388382 -337.220623) (xy 113.411023 -337.2702) (xy 113.426379 -337.322495) (xy 113.434136 -337.376443)
			(xy 113.434622 -337.403694) (xy 113.434096 -337.433599) (xy 113.424777 -337.492678) (xy 113.41608 -337.521296)
			(xy 113.412129 -337.535225) (xy 113.411206 -337.564145) (xy 113.418455 -337.592157) (xy 113.433291 -337.616998)
			(xy 113.454516 -337.636663) (xy 113.480415 -337.649563) (xy 113.494566 -337.652614) (xy 113.520644 -337.657759)
			(xy 113.571147 -337.674334) (xy 113.61886 -337.697762) (xy 113.662857 -337.727588) (xy 113.702286 -337.763233)
			(xy 113.736384 -337.804009) (xy 113.76449 -337.849124) (xy 113.78606 -337.897705) (xy 113.800674 -337.94881)
			(xy 113.808051 -338.001449) (xy 113.80851 -338.028026) (xy 113.808024 -338.055277) (xy 113.800268 -338.109225)
			(xy 113.784913 -338.16152) (xy 113.762271 -338.211097) (xy 113.744764 -338.238338) (xy 119.120666 -338.238338)
			(xy 119.121223 -338.20865) (xy 119.130417 -338.149989) (xy 119.148591 -338.093463) (xy 119.175304 -338.040434)
			(xy 119.209911 -337.992186) (xy 119.251576 -337.949883) (xy 119.275098 -337.93176) (xy 119.28568 -337.923304)
			(xy 119.302388 -337.901999) (xy 119.312909 -337.877051) (xy 119.316503 -337.850216) (xy 119.312918 -337.823379)
			(xy 119.302404 -337.798428) (xy 119.285703 -337.777118) (xy 119.275098 -337.768692) (xy 119.251583 -337.750562)
			(xy 119.209923 -337.708256) (xy 119.175319 -337.660008) (xy 119.148607 -337.606982) (xy 119.130432 -337.550458)
			(xy 119.121232 -337.491801) (xy 119.120666 -337.462114) (xy 119.121152 -337.434863) (xy 119.128908 -337.380915)
			(xy 119.144263 -337.32862) (xy 119.166905 -337.279043) (xy 119.196371 -337.233193) (xy 119.232062 -337.192002)
			(xy 119.273253 -337.156311) (xy 119.319103 -337.126845) (xy 119.36868 -337.104203) (xy 119.420975 -337.088848)
			(xy 119.474923 -337.081092) (xy 119.529425 -337.081092) (xy 119.583373 -337.088848) (xy 119.635668 -337.104203)
			(xy 119.685245 -337.126845) (xy 119.731095 -337.156311) (xy 119.772286 -337.192002) (xy 119.807977 -337.233193)
			(xy 119.837443 -337.279043) (xy 119.860085 -337.32862) (xy 119.87544 -337.380915) (xy 119.883196 -337.434863)
			(xy 119.883682 -337.462114) (xy 119.883144 -337.491803) (xy 119.873943 -337.550463) (xy 119.855765 -337.60699)
			(xy 119.829048 -337.660017) (xy 119.816972 -337.676852) (xy 120.137144 -337.676852) (xy 120.137144 -337.622348)
			(xy 120.1449 -337.568397) (xy 120.160255 -337.5161) (xy 120.182897 -337.46652) (xy 120.212363 -337.420667)
			(xy 120.248055 -337.379474) (xy 120.289246 -337.343779) (xy 120.335097 -337.314309) (xy 120.384676 -337.291665)
			(xy 120.436972 -337.276306) (xy 120.490922 -337.268546) (xy 120.518174 -337.268058) (xy 120.54341 -337.268428)
			(xy 120.593445 -337.275055) (xy 120.642165 -337.288236) (xy 120.688716 -337.30774) (xy 120.710706 -337.320128)
			(xy 120.723675 -337.32716) (xy 120.75231 -337.334199) (xy 120.781763 -337.332757) (xy 120.809575 -337.322956)
			(xy 120.833424 -337.305614) (xy 120.85132 -337.282177) (xy 120.85701 -337.268566) (xy 120.867663 -337.241771)
			(xy 120.895957 -337.191529) (xy 120.931494 -337.14612) (xy 120.973462 -337.106579) (xy 121.020905 -337.073807)
			(xy 121.072742 -337.048553) (xy 121.127791 -337.031391) (xy 121.184795 -337.022713) (xy 121.213626 -337.022186)
			(xy 121.240878 -337.022654) (xy 121.294826 -337.030413) (xy 121.34712 -337.045772) (xy 121.396697 -337.068415)
			(xy 121.442547 -337.097884) (xy 121.483737 -337.133577) (xy 121.519428 -337.174769) (xy 121.548894 -337.22062)
			(xy 121.571535 -337.270198) (xy 121.586891 -337.322494) (xy 121.594648 -337.376442) (xy 121.595134 -337.403694)
			(xy 121.594607 -337.433599) (xy 121.586865 -337.482688) (xy 123.707398 -337.482688) (xy 123.707925 -337.455116)
			(xy 123.715865 -337.400546) (xy 123.731578 -337.347687) (xy 123.754737 -337.297641) (xy 123.784858 -337.251449)
			(xy 123.821316 -337.210076) (xy 123.842018 -337.191858) (xy 123.852925 -337.18197) (xy 123.868994 -337.157316)
			(xy 123.877374 -337.129106) (xy 123.877372 -337.099678) (xy 123.868987 -337.071469) (xy 123.852915 -337.046818)
			(xy 123.842018 -337.036918) (xy 123.821316 -337.018697) (xy 123.784844 -336.977331) (xy 123.75471 -336.931143)
			(xy 123.731543 -336.881097) (xy 123.715825 -336.828236) (xy 123.707884 -336.773662) (xy 123.707398 -336.746088)
			(xy 123.707867 -336.718836) (xy 123.715625 -336.664888) (xy 123.730982 -336.612592) (xy 123.753625 -336.563014)
			(xy 123.783093 -336.517164) (xy 123.818786 -336.475974) (xy 123.859978 -336.440282) (xy 123.90583 -336.410816)
			(xy 123.955409 -336.388176) (xy 124.007705 -336.372821) (xy 124.061654 -336.365065) (xy 124.088906 -336.36458)
			(xy 124.101067 -336.364674) (xy 124.125343 -336.366197) (xy 124.13742 -336.367628) (xy 124.151183 -336.36885)
			(xy 124.178509 -336.364881) (xy 124.203774 -336.353739) (xy 124.225132 -336.336237) (xy 124.241022 -336.313655)
			(xy 124.250284 -336.287641) (xy 124.25172 -336.273902) (xy 124.254288 -336.245371) (xy 124.26677 -336.189468)
			(xy 124.287472 -336.136059) (xy 124.315929 -336.086348) (xy 124.351502 -336.041452) (xy 124.393389 -336.002382)
			(xy 124.440649 -335.970016) (xy 124.492218 -335.945083) (xy 124.546936 -335.928143) (xy 124.603572 -335.919578)
			(xy 124.632212 -335.919064) (xy 124.650231 -335.919288) (xy 124.686106 -335.92272) (xy 124.70384 -335.925922)
			(xy 124.719042 -335.928328) (xy 124.749605 -335.924788) (xy 124.77773 -335.912312) (xy 124.800866 -335.89203)
			(xy 124.816917 -335.865781) (xy 124.821188 -335.850992) (xy 124.828636 -335.823962) (xy 124.850258 -335.772237)
			(xy 124.879215 -335.724232) (xy 124.914884 -335.68098) (xy 124.956497 -335.643411) (xy 125.003158 -335.612335)
			(xy 125.053864 -335.588419) (xy 125.107523 -335.57218) (xy 125.162981 -335.563965) (xy 125.191012 -335.563464)
			(xy 125.218262 -335.563967) (xy 125.272208 -335.571724) (xy 125.324501 -335.587079) (xy 125.374076 -335.60972)
			(xy 125.419925 -335.639185) (xy 125.461114 -335.674874) (xy 125.496806 -335.716062) (xy 125.526273 -335.76191)
			(xy 125.548915 -335.811484) (xy 125.564273 -335.863776) (xy 125.572032 -335.917722) (xy 125.57252 -335.944972)
			(xy 125.572028 -335.972546) (xy 125.56408 -336.027117) (xy 125.54836 -336.079976) (xy 125.525194 -336.130022)
			(xy 125.495067 -336.176212) (xy 125.458605 -336.217585) (xy 125.4379 -336.235802) (xy 125.427031 -336.245729)
			(xy 125.410958 -336.270371) (xy 125.402572 -336.298572) (xy 125.402566 -336.327992) (xy 125.410943 -336.356195)
			(xy 125.427007 -336.380843) (xy 125.4379 -336.390742) (xy 125.458577 -336.408988) (xy 125.495041 -336.450356)
			(xy 125.525168 -336.496542) (xy 125.548331 -336.546585) (xy 125.564048 -336.599441) (xy 125.57199 -336.65401)
			(xy 125.571993 -336.709154) (xy 125.564056 -336.763723) (xy 125.548344 -336.816581) (xy 125.525186 -336.866626)
			(xy 125.495063 -336.912816) (xy 125.458603 -336.954186) (xy 125.4379 -336.972402) (xy 125.427031 -336.982329)
			(xy 125.410958 -337.006971) (xy 125.402572 -337.035172) (xy 125.402566 -337.064592) (xy 125.410943 -337.092795)
			(xy 125.427007 -337.117443) (xy 125.4379 -337.127342) (xy 125.458586 -337.14558) (xy 125.495059 -337.186943)
			(xy 125.525194 -337.233127) (xy 125.548364 -337.28317) (xy 125.564086 -337.336028) (xy 125.572031 -337.390599)
			(xy 125.57252 -337.418172) (xy 125.572019 -337.445424) (xy 125.567394 -337.477608) (xy 170.050211 -337.477608)
			(xy 170.054233 -337.391888) (xy 170.066264 -337.30692) (xy 170.0862 -337.223453) (xy 170.113863 -337.142219)
			(xy 170.149012 -337.063933) (xy 170.191338 -336.989282) (xy 170.240467 -336.918923) (xy 170.29597 -336.853473)
			(xy 170.357357 -336.793509) (xy 170.42409 -336.739556) (xy 170.495582 -336.692089) (xy 170.571204 -336.651525)
			(xy 170.650293 -336.618221) (xy 170.732153 -336.592469) (xy 170.816064 -336.574496) (xy 170.90129 -336.56446)
			(xy 170.987082 -336.562448) (xy 171.072684 -336.568479) (xy 171.157346 -336.582499) (xy 171.240323 -336.604385)
			(xy 171.320886 -336.633946) (xy 171.398326 -336.67092) (xy 171.471965 -336.714984) (xy 171.541153 -336.76575)
			(xy 171.605284 -336.822771) (xy 171.663793 -336.885547) (xy 171.716166 -336.953527) (xy 171.761944 -337.026112)
			(xy 171.800724 -337.102664) (xy 171.832165 -337.182512) (xy 171.855991 -337.264953) (xy 171.871992 -337.349263)
			(xy 171.880027 -337.434701) (xy 171.88053 -337.477608) (xy 171.880456 -337.483958) (xy 176.240953 -337.483958)
			(xy 176.244975 -337.398238) (xy 176.257006 -337.31327) (xy 176.276942 -337.229803) (xy 176.304605 -337.148569)
			(xy 176.339754 -337.070283) (xy 176.38208 -336.995632) (xy 176.431209 -336.925273) (xy 176.486712 -336.859823)
			(xy 176.548099 -336.799859) (xy 176.614832 -336.745906) (xy 176.686324 -336.698439) (xy 176.761946 -336.657875)
			(xy 176.841035 -336.624571) (xy 176.922895 -336.598819) (xy 177.006806 -336.580846) (xy 177.092032 -336.57081)
			(xy 177.177824 -336.568798) (xy 177.263426 -336.574829) (xy 177.348088 -336.588849) (xy 177.431065 -336.610735)
			(xy 177.511628 -336.640296) (xy 177.589068 -336.67727) (xy 177.662707 -336.721334) (xy 177.731895 -336.7721)
			(xy 177.796026 -336.829121) (xy 177.854535 -336.891897) (xy 177.906908 -336.959877) (xy 177.952686 -337.032462)
			(xy 177.991466 -337.109014) (xy 178.022907 -337.188862) (xy 178.046733 -337.271303) (xy 178.062734 -337.355613)
			(xy 178.070769 -337.441051) (xy 178.071272 -337.483958) (xy 182.439056 -337.483958) (xy 182.439544 -337.441682)
			(xy 182.447346 -337.35749) (xy 182.462882 -337.274377) (xy 182.486021 -337.193053) (xy 182.516565 -337.11421)
			(xy 182.554253 -337.038522) (xy 182.598764 -336.966634) (xy 182.649718 -336.89916) (xy 182.706681 -336.836675)
			(xy 182.769166 -336.779712) (xy 182.83664 -336.728758) (xy 182.908528 -336.684247) (xy 182.984216 -336.646559)
			(xy 183.063059 -336.616015) (xy 183.144383 -336.592876) (xy 183.227496 -336.57734) (xy 183.311688 -336.569538)
			(xy 183.39624 -336.569538) (xy 183.480432 -336.57734) (xy 183.563545 -336.592876) (xy 183.644869 -336.616015)
			(xy 183.723712 -336.646559) (xy 183.7994 -336.684247) (xy 183.871288 -336.728758) (xy 183.938762 -336.779712)
			(xy 184.001247 -336.836675) (xy 184.05821 -336.89916) (xy 184.109164 -336.966634) (xy 184.153675 -337.038522)
			(xy 184.191363 -337.11421) (xy 184.221907 -337.193053) (xy 184.245046 -337.274377) (xy 184.260582 -337.35749)
			(xy 184.268384 -337.441682) (xy 184.268872 -337.483958) (xy 184.268338 -337.527902) (xy 184.259914 -337.615385)
			(xy 184.243138 -337.701657) (xy 184.218167 -337.785923) (xy 184.185229 -337.867405) (xy 184.144629 -337.945353)
			(xy 184.096741 -338.019048) (xy 184.042007 -338.087812) (xy 183.98093 -338.151009) (xy 183.914074 -338.208057)
			(xy 183.842055 -338.258431) (xy 183.804052 -338.280502) (xy 183.792022 -338.28775) (xy 183.772209 -338.307642)
			(xy 183.758568 -338.332181) (xy 183.752134 -338.35951) (xy 183.753394 -338.387557) (xy 183.762252 -338.414199)
			(xy 183.778037 -338.437416) (xy 183.799554 -338.455452) (xy 183.81218 -338.461604) (xy 183.839112 -338.474322)
			(xy 183.889 -338.506852) (xy 183.911494 -338.526374) (xy 183.922936 -338.536019) (xy 183.949979 -338.548799)
			(xy 183.979566 -338.553185) (xy 184.009153 -338.548799) (xy 184.036196 -338.536019) (xy 184.047638 -338.526374)
			(xy 184.068792 -338.507958) (xy 184.115469 -338.476864) (xy 184.166199 -338.452947) (xy 184.219887 -338.436726)
			(xy 184.275373 -338.428551) (xy 184.303416 -338.428076) (xy 184.330787 -338.428514) (xy 184.384968 -338.436336)
			(xy 184.437473 -338.45183) (xy 184.487219 -338.474679) (xy 184.533184 -338.504411) (xy 184.554114 -338.522056)
			(xy 184.565442 -338.531292) (xy 184.591999 -338.543468) (xy 184.620916 -338.547641) (xy 184.649833 -338.543468)
			(xy 184.67639 -338.531292) (xy 184.687718 -338.522056) (xy 184.708664 -338.504435) (xy 184.754634 -338.474722)
			(xy 184.804378 -338.451883) (xy 184.856875 -338.436387) (xy 184.911048 -338.428553) (xy 184.938416 -338.428076)
			(xy 184.965667 -338.428563) (xy 185.019614 -338.436321) (xy 185.071908 -338.451677) (xy 185.121484 -338.474319)
			(xy 185.167333 -338.503786) (xy 185.208523 -338.539477) (xy 185.244214 -338.580667) (xy 185.273681 -338.626516)
			(xy 185.296323 -338.676092) (xy 185.311679 -338.728386) (xy 185.319437 -338.782333) (xy 185.319924 -338.809584)
			(xy 185.319467 -338.836955) (xy 185.31165 -338.891135) (xy 185.29616 -338.943639) (xy 185.273315 -338.993386)
			(xy 185.243587 -339.039351) (xy 185.225944 -339.060282) (xy 185.216727 -339.071623) (xy 185.204555 -339.098177)
			(xy 185.200381 -339.127088) (xy 185.204548 -339.156) (xy 185.216714 -339.182557) (xy 185.225944 -339.193886)
			(xy 185.24357 -339.214831) (xy 185.273298 -339.260796) (xy 185.296146 -339.31054) (xy 185.311645 -339.36304)
			(xy 185.319475 -339.417218) (xy 185.319477 -339.471958) (xy 185.31165 -339.526136) (xy 185.296154 -339.578637)
			(xy 185.273309 -339.628383) (xy 185.243585 -339.67435) (xy 185.225944 -339.695282) (xy 185.216727 -339.706623)
			(xy 185.204555 -339.733177) (xy 185.200381 -339.762088) (xy 185.204548 -339.791) (xy 185.216714 -339.817557)
			(xy 185.225944 -339.828886) (xy 185.24357 -339.849831) (xy 185.273298 -339.895796) (xy 185.296146 -339.94554)
			(xy 185.311645 -339.99804) (xy 185.319475 -340.052218) (xy 185.319477 -340.106958) (xy 185.31165 -340.161136)
			(xy 185.296154 -340.213637) (xy 185.273309 -340.263383) (xy 185.243585 -340.30935) (xy 185.225944 -340.330282)
			(xy 185.216727 -340.341623) (xy 185.204555 -340.368177) (xy 185.200381 -340.397088) (xy 185.204548 -340.426)
			(xy 185.216714 -340.452557) (xy 185.225944 -340.463886) (xy 185.24357 -340.484831) (xy 185.273298 -340.530796)
			(xy 185.296146 -340.58054) (xy 185.311645 -340.63304) (xy 185.319475 -340.687218) (xy 185.319477 -340.741958)
			(xy 185.31165 -340.796136) (xy 185.296154 -340.848637) (xy 185.273309 -340.898383) (xy 185.243585 -340.94435)
			(xy 185.225944 -340.965282) (xy 185.216727 -340.976623) (xy 185.204555 -341.003177) (xy 185.200381 -341.032088)
			(xy 185.204548 -341.061) (xy 185.216714 -341.087557) (xy 185.225944 -341.098886) (xy 185.24357 -341.119831)
			(xy 185.273298 -341.165796) (xy 185.296146 -341.21554) (xy 185.311645 -341.26804) (xy 185.319475 -341.322218)
			(xy 185.319477 -341.376958) (xy 185.31165 -341.431136) (xy 185.296154 -341.483637) (xy 185.273309 -341.533383)
			(xy 185.243585 -341.57935) (xy 185.225944 -341.600282) (xy 185.216727 -341.611623) (xy 185.204555 -341.638177)
			(xy 185.200381 -341.667088) (xy 185.204548 -341.696) (xy 185.216714 -341.722557) (xy 185.225944 -341.733886)
			(xy 185.24357 -341.754831) (xy 185.273298 -341.800796) (xy 185.296146 -341.85054) (xy 185.311645 -341.90304)
			(xy 185.319475 -341.957218) (xy 185.319477 -342.011958) (xy 185.31165 -342.066136) (xy 185.296154 -342.118637)
			(xy 185.273309 -342.168383) (xy 185.243585 -342.21435) (xy 185.225944 -342.235282) (xy 185.216727 -342.246623)
			(xy 185.204555 -342.273177) (xy 185.200381 -342.302088) (xy 185.204548 -342.331) (xy 185.216714 -342.357557)
			(xy 185.225944 -342.368886) (xy 185.243597 -342.389807) (xy 185.273306 -342.435783) (xy 185.296138 -342.485534)
			(xy 185.311626 -342.538037) (xy 185.319452 -342.592214) (xy 185.319924 -342.619584) (xy 185.319407 -342.646834)
			(xy 185.311653 -342.70078) (xy 185.296301 -342.753073) (xy 185.273663 -342.802649) (xy 185.2442 -342.848499)
			(xy 185.208511 -342.889689) (xy 185.167324 -342.92538) (xy 185.121477 -342.954847) (xy 185.071903 -342.97749)
			(xy 185.019611 -342.992846) (xy 184.965666 -343.000605) (xy 184.938416 -343.001092) (xy 184.911046 -343.000619)
			(xy 184.856867 -342.992803) (xy 184.804364 -342.977316) (xy 184.754617 -342.954475) (xy 184.70865 -342.924752)
			(xy 184.687718 -342.907112) (xy 184.67639 -342.897876) (xy 184.649833 -342.8857) (xy 184.620916 -342.881527)
			(xy 184.591999 -342.8857) (xy 184.565442 -342.897876) (xy 184.554114 -342.907112) (xy 184.533189 -342.92476)
			(xy 184.487214 -342.95447) (xy 184.437465 -342.977304) (xy 184.384963 -342.992793) (xy 184.330786 -343.000619)
			(xy 184.303416 -343.001092) (xy 184.275376 -343.000597) (xy 184.219898 -342.992398) (xy 184.166215 -342.976172)
			(xy 184.115483 -342.952271) (xy 184.068792 -342.921207) (xy 184.047638 -342.902794) (xy 184.036196 -342.893149)
			(xy 184.009153 -342.880369) (xy 183.979566 -342.875983) (xy 183.949979 -342.880369) (xy 183.922936 -342.893149)
			(xy 183.911494 -342.902794) (xy 183.890362 -342.921237) (xy 183.84368 -342.952329) (xy 183.792944 -342.97624)
			(xy 183.739251 -342.992455) (xy 183.683761 -343.000622) (xy 183.655716 -343.001092) (xy 183.628463 -343.00063)
			(xy 183.574511 -342.992875) (xy 183.522212 -342.97752) (xy 183.472631 -342.954878) (xy 183.426777 -342.92541)
			(xy 183.385584 -342.889716) (xy 183.34989 -342.848523) (xy 183.320422 -342.802669) (xy 183.29778 -342.753088)
			(xy 183.282425 -342.700789) (xy 183.27467 -342.646837) (xy 183.274208 -342.619584) (xy 183.274663 -342.592213)
			(xy 183.282483 -342.538034) (xy 183.297975 -342.48553) (xy 183.320819 -342.435784) (xy 183.350546 -342.389817)
			(xy 183.368188 -342.368886) (xy 183.377441 -342.357571) (xy 183.389618 -342.331009) (xy 183.393788 -342.302088)
			(xy 183.389611 -342.273168) (xy 183.377428 -342.246609) (xy 183.368188 -342.235282) (xy 183.350533 -342.214361)
			(xy 183.320812 -342.16839) (xy 183.29797 -342.118642) (xy 183.282477 -342.066138) (xy 183.27465 -342.011959)
			(xy 183.274652 -341.957217) (xy 183.282482 -341.903038) (xy 183.297979 -341.850535) (xy 183.320824 -341.800788)
			(xy 183.350548 -341.75482) (xy 183.368188 -341.733886) (xy 183.377441 -341.722571) (xy 183.389618 -341.696009)
			(xy 183.393788 -341.667088) (xy 183.389611 -341.638168) (xy 183.377428 -341.611609) (xy 183.368188 -341.600282)
			(xy 183.350533 -341.579361) (xy 183.320812 -341.53339) (xy 183.29797 -341.483642) (xy 183.282477 -341.431138)
			(xy 183.27465 -341.376959) (xy 183.274652 -341.322217) (xy 183.282482 -341.268038) (xy 183.297979 -341.215535)
			(xy 183.320824 -341.165788) (xy 183.350548 -341.11982) (xy 183.368188 -341.098886) (xy 183.377441 -341.087571)
			(xy 183.389618 -341.061009) (xy 183.393788 -341.032088) (xy 183.389611 -341.003168) (xy 183.377428 -340.976609)
			(xy 183.368188 -340.965282) (xy 183.350533 -340.944361) (xy 183.320812 -340.89839) (xy 183.29797 -340.848642)
			(xy 183.282477 -340.796138) (xy 183.27465 -340.741959) (xy 183.274652 -340.687217) (xy 183.282482 -340.633038)
			(xy 183.297979 -340.580535) (xy 183.320824 -340.530788) (xy 183.350548 -340.48482) (xy 183.368188 -340.463886)
			(xy 183.377441 -340.452571) (xy 183.389618 -340.426009) (xy 183.393788 -340.397088) (xy 183.389611 -340.368168)
			(xy 183.377428 -340.341609) (xy 183.368188 -340.330282) (xy 183.350533 -340.309361) (xy 183.320812 -340.26339)
			(xy 183.29797 -340.213642) (xy 183.282477 -340.161138) (xy 183.27465 -340.106959) (xy 183.274652 -340.052217)
			(xy 183.282482 -339.998038) (xy 183.297979 -339.945535) (xy 183.320824 -339.895788) (xy 183.350548 -339.84982)
			(xy 183.368188 -339.828886) (xy 183.377441 -339.817571) (xy 183.389618 -339.791009) (xy 183.393788 -339.762088)
			(xy 183.389611 -339.733168) (xy 183.377428 -339.706609) (xy 183.368188 -339.695282) (xy 183.350533 -339.674361)
			(xy 183.320812 -339.62839) (xy 183.29797 -339.578642) (xy 183.282477 -339.526138) (xy 183.27465 -339.471959)
			(xy 183.274652 -339.417217) (xy 183.282482 -339.363038) (xy 183.297979 -339.310535) (xy 183.320824 -339.260788)
			(xy 183.350548 -339.21482) (xy 183.368188 -339.193886) (xy 183.377441 -339.182571) (xy 183.389618 -339.156009)
			(xy 183.393788 -339.127088) (xy 183.389611 -339.098168) (xy 183.377428 -339.071609) (xy 183.368188 -339.060282)
			(xy 183.350572 -339.039331) (xy 183.320857 -338.993363) (xy 183.298017 -338.943621) (xy 183.28252 -338.891124)
			(xy 183.274686 -338.836952) (xy 183.274208 -338.809584) (xy 183.274668 -338.782851) (xy 183.282177 -338.729914)
			(xy 183.296991 -338.67854) (xy 183.318821 -338.629732) (xy 183.347239 -338.584443) (xy 183.364124 -338.563712)
			(xy 183.372832 -338.552699) (xy 183.384366 -338.527111) (xy 183.388505 -338.499351) (xy 183.384937 -338.471511)
			(xy 183.373932 -338.445692) (xy 183.356318 -338.423839) (xy 183.333425 -338.407602) (xy 183.306978 -338.398203)
			(xy 183.293004 -338.396834) (xy 183.250113 -338.393549) (xy 183.165193 -338.379781) (xy 183.081941 -338.358103)
			(xy 183.001091 -338.328705) (xy 182.923357 -338.291848) (xy 182.849427 -338.247857) (xy 182.779952 -338.19712)
			(xy 182.715547 -338.140086) (xy 182.65678 -338.077258) (xy 182.604169 -338.009191) (xy 182.558181 -337.936486)
			(xy 182.51922 -337.859785) (xy 182.487632 -337.779766) (xy 182.463694 -337.697135) (xy 182.447618 -337.612622)
			(xy 182.439547 -337.526972) (xy 182.439056 -337.483958) (xy 178.071272 -337.483958) (xy 178.070769 -337.526865)
			(xy 178.062734 -337.612303) (xy 178.046733 -337.696613) (xy 178.022907 -337.779054) (xy 177.991466 -337.858902)
			(xy 177.952686 -337.935454) (xy 177.906908 -338.008039) (xy 177.854535 -338.076019) (xy 177.796026 -338.138795)
			(xy 177.731895 -338.195816) (xy 177.662707 -338.246582) (xy 177.589068 -338.290646) (xy 177.511628 -338.32762)
			(xy 177.431065 -338.357181) (xy 177.348088 -338.379067) (xy 177.263426 -338.393087) (xy 177.177824 -338.399118)
			(xy 177.092032 -338.397106) (xy 177.006806 -338.38707) (xy 176.922895 -338.369097) (xy 176.841035 -338.343345)
			(xy 176.761946 -338.310041) (xy 176.686324 -338.269477) (xy 176.614832 -338.22201) (xy 176.548099 -338.168057)
			(xy 176.486712 -338.108093) (xy 176.431209 -338.042643) (xy 176.38208 -337.972284) (xy 176.339754 -337.897633)
			(xy 176.304605 -337.819347) (xy 176.276942 -337.738113) (xy 176.257006 -337.654646) (xy 176.244975 -337.569678)
			(xy 176.240953 -337.483958) (xy 171.880456 -337.483958) (xy 171.880027 -337.520515) (xy 171.871992 -337.605953)
			(xy 171.855991 -337.690263) (xy 171.832165 -337.772704) (xy 171.800724 -337.852552) (xy 171.761944 -337.929104)
			(xy 171.716166 -338.001689) (xy 171.663793 -338.069669) (xy 171.605284 -338.132445) (xy 171.541153 -338.189466)
			(xy 171.471965 -338.240232) (xy 171.398326 -338.284296) (xy 171.320886 -338.32127) (xy 171.240323 -338.350831)
			(xy 171.157346 -338.372717) (xy 171.072684 -338.386737) (xy 170.987082 -338.392768) (xy 170.90129 -338.390756)
			(xy 170.816064 -338.38072) (xy 170.732153 -338.362747) (xy 170.650293 -338.336995) (xy 170.571204 -338.303691)
			(xy 170.495582 -338.263127) (xy 170.42409 -338.21566) (xy 170.357357 -338.161707) (xy 170.29597 -338.101743)
			(xy 170.240467 -338.036293) (xy 170.191338 -337.965934) (xy 170.149012 -337.891283) (xy 170.113863 -337.812997)
			(xy 170.0862 -337.731763) (xy 170.066264 -337.648296) (xy 170.054233 -337.563328) (xy 170.050211 -337.477608)
			(xy 125.567394 -337.477608) (xy 125.564266 -337.499373) (xy 125.548914 -337.551669) (xy 125.526276 -337.601248)
			(xy 125.496812 -337.647101) (xy 125.461122 -337.688294) (xy 125.419933 -337.723988) (xy 125.374083 -337.753456)
			(xy 125.324506 -337.7761) (xy 125.272212 -337.791457) (xy 125.218264 -337.799216) (xy 125.191012 -337.79968)
			(xy 125.163156 -337.799161) (xy 125.10804 -337.791038) (xy 125.054689 -337.774993) (xy 125.004235 -337.751367)
			(xy 124.95775 -337.720659) (xy 124.916221 -337.683523) (xy 124.880528 -337.640747) (xy 124.85143 -337.593238)
			(xy 124.829543 -337.542006) (xy 124.82195 -337.5152) (xy 124.817696 -337.501077) (xy 124.802301 -337.475931)
			(xy 124.780378 -337.456216) (xy 124.753745 -337.443567) (xy 124.724611 -337.439033) (xy 124.709936 -337.440524)
			(xy 124.69692 -337.442198) (xy 124.670735 -337.443975) (xy 124.657612 -337.44408) (xy 124.639981 -337.443844)
			(xy 124.604873 -337.440538) (xy 124.587508 -337.437476) (xy 124.573734 -337.435253) (xy 124.545948 -337.437699)
			(xy 124.519864 -337.447584) (xy 124.497434 -337.464166) (xy 124.480337 -337.486207) (xy 124.469852 -337.512055)
			(xy 124.467874 -337.525868) (xy 124.464232 -337.553444) (xy 124.450001 -337.607215) (xy 124.428107 -337.658348)
			(xy 124.399017 -337.705757) (xy 124.363347 -337.748436) (xy 124.321855 -337.78548) (xy 124.27542 -337.816102)
			(xy 124.225029 -337.839652) (xy 124.171752 -337.85563) (xy 124.116717 -337.863699) (xy 124.088906 -337.864196)
			(xy 124.061653 -337.863739) (xy 124.007701 -337.855983) (xy 123.955402 -337.840627) (xy 123.905821 -337.817984)
			(xy 123.859968 -337.788516) (xy 123.818775 -337.752821) (xy 123.783081 -337.711628) (xy 123.753613 -337.665773)
			(xy 123.730971 -337.616192) (xy 123.715616 -337.563893) (xy 123.707861 -337.509941) (xy 123.707398 -337.482688)
			(xy 121.586865 -337.482688) (xy 121.585289 -337.492678) (xy 121.576592 -337.521296) (xy 121.572631 -337.535223)
			(xy 121.571708 -337.564145) (xy 121.578958 -337.592158) (xy 121.593796 -337.617001) (xy 121.615023 -337.636665)
			(xy 121.640926 -337.649564) (xy 121.655078 -337.652614) (xy 121.681143 -337.657824) (xy 121.731646 -337.674388)
			(xy 121.779359 -337.697805) (xy 121.823358 -337.727622) (xy 121.86279 -337.76326) (xy 121.89689 -337.804029)
			(xy 121.924998 -337.849138) (xy 121.94657 -337.897714) (xy 121.961186 -337.948815) (xy 121.968563 -338.001451)
			(xy 121.969022 -338.028026) (xy 121.968536 -338.055277) (xy 121.96078 -338.109225) (xy 121.945425 -338.16152)
			(xy 121.922783 -338.211097) (xy 121.893317 -338.256947) (xy 121.857626 -338.298138) (xy 121.816435 -338.333829)
			(xy 121.770585 -338.363295) (xy 121.721008 -338.385937) (xy 121.668713 -338.401292) (xy 121.614765 -338.409048)
			(xy 121.560263 -338.409048) (xy 121.506315 -338.401292) (xy 121.45402 -338.385937) (xy 121.404443 -338.363295)
			(xy 121.358593 -338.333829) (xy 121.317402 -338.298138) (xy 121.281711 -338.256947) (xy 121.252245 -338.211097)
			(xy 121.229603 -338.16152) (xy 121.214248 -338.109225) (xy 121.206492 -338.055277) (xy 121.206006 -338.028026)
			(xy 121.206536 -337.998121) (xy 121.215852 -337.939042) (xy 121.224548 -337.910424) (xy 121.228568 -337.896513)
			(xy 121.229471 -337.867586) (xy 121.222206 -337.83957) (xy 121.207357 -337.814728) (xy 121.186123 -337.795062)
			(xy 121.160217 -337.782159) (xy 121.146062 -337.779106) (xy 121.113226 -337.77251) (xy 121.050372 -337.749396)
			(xy 121.021094 -337.733132) (xy 121.008116 -337.72612) (xy 120.979485 -337.719086) (xy 120.950038 -337.720528)
			(xy 120.92223 -337.730325) (xy 120.898382 -337.74766) (xy 120.880483 -337.771087) (xy 120.87479 -337.784694)
			(xy 120.864116 -337.81148) (xy 120.835826 -337.861723) (xy 120.800294 -337.907134) (xy 120.758329 -337.946677)
			(xy 120.710889 -337.97945) (xy 120.659054 -338.004706) (xy 120.604007 -338.021869) (xy 120.547004 -338.030547)
			(xy 120.518174 -338.031074) (xy 120.490922 -338.030654) (xy 120.436972 -338.022894) (xy 120.384676 -338.007535)
			(xy 120.335097 -337.984891) (xy 120.289246 -337.955421) (xy 120.248055 -337.919726) (xy 120.212363 -337.878533)
			(xy 120.182897 -337.83268) (xy 120.160255 -337.7831) (xy 120.1449 -337.730803) (xy 120.137144 -337.676852)
			(xy 119.816972 -337.676852) (xy 119.794439 -337.708265) (xy 119.752772 -337.750569) (xy 119.72925 -337.768692)
			(xy 119.718621 -337.77709) (xy 119.701921 -337.798411) (xy 119.691409 -337.823371) (xy 119.687823 -337.850216)
			(xy 119.691417 -337.877059) (xy 119.701936 -337.902015) (xy 119.718643 -337.923331) (xy 119.72925 -337.93176)
			(xy 119.7528 -337.949847) (xy 119.794456 -337.992163) (xy 119.829054 -338.04042) (xy 119.85576 -338.093455)
			(xy 119.873928 -338.149986) (xy 119.88312 -338.208649) (xy 119.883682 -338.238338) (xy 119.883196 -338.265589)
			(xy 119.87544 -338.319537) (xy 119.860085 -338.371832) (xy 119.837443 -338.421409) (xy 119.807977 -338.467259)
			(xy 119.772286 -338.50845) (xy 119.731095 -338.544141) (xy 119.685245 -338.573607) (xy 119.642953 -338.592922)
			(xy 125.683518 -338.592922) (xy 125.684014 -338.564882) (xy 125.692213 -338.509403) (xy 125.708438 -338.455721)
			(xy 125.732339 -338.404989) (xy 125.763403 -338.358298) (xy 125.781816 -338.337144) (xy 125.791486 -338.325722)
			(xy 125.804259 -338.298671) (xy 125.808638 -338.269079) (xy 125.804246 -338.239489) (xy 125.791463 -338.212443)
			(xy 125.781816 -338.201) (xy 125.763361 -338.179878) (xy 125.732274 -338.133192) (xy 125.708366 -338.082454)
			(xy 125.692154 -338.028759) (xy 125.683988 -337.973267) (xy 125.683518 -337.945222) (xy 125.684004 -337.917971)
			(xy 125.69176 -337.864023) (xy 125.707115 -337.811728) (xy 125.729757 -337.762151) (xy 125.759223 -337.716301)
			(xy 125.794914 -337.67511) (xy 125.836105 -337.639419) (xy 125.881955 -337.609953) (xy 125.931532 -337.587311)
			(xy 125.983827 -337.571956) (xy 126.037775 -337.5642) (xy 126.092277 -337.5642) (xy 126.146225 -337.571956)
			(xy 126.19852 -337.587311) (xy 126.248097 -337.609953) (xy 126.293947 -337.639419) (xy 126.335138 -337.67511)
			(xy 126.370829 -337.716301) (xy 126.400295 -337.762151) (xy 126.422937 -337.811728) (xy 126.438292 -337.864023)
			(xy 126.446048 -337.917971) (xy 126.446534 -337.945222) (xy 126.446051 -337.973263) (xy 126.437847 -338.028741)
			(xy 126.421619 -338.082423) (xy 126.397715 -338.133155) (xy 126.366649 -338.179846) (xy 126.348236 -338.201)
			(xy 126.338617 -338.212462) (xy 126.325831 -338.239497) (xy 126.321439 -338.269079) (xy 126.325819 -338.298663)
			(xy 126.338594 -338.325703) (xy 126.348236 -338.337144) (xy 126.366656 -338.358295) (xy 126.39775 -338.404972)
			(xy 126.421665 -338.455703) (xy 126.437885 -338.509392) (xy 126.44606 -338.564879) (xy 126.446534 -338.592922)
			(xy 126.446048 -338.620173) (xy 126.438292 -338.674121) (xy 126.422937 -338.726416) (xy 126.400295 -338.775993)
			(xy 126.370829 -338.821843) (xy 126.335138 -338.863034) (xy 126.293947 -338.898725) (xy 126.248097 -338.928191)
			(xy 126.19852 -338.950833) (xy 126.146225 -338.966188) (xy 126.092277 -338.973944) (xy 126.037775 -338.973944)
			(xy 125.983827 -338.966188) (xy 125.931532 -338.950833) (xy 125.881955 -338.928191) (xy 125.836105 -338.898725)
			(xy 125.794914 -338.863034) (xy 125.759223 -338.821843) (xy 125.729757 -338.775993) (xy 125.707115 -338.726416)
			(xy 125.69176 -338.674121) (xy 125.684004 -338.620173) (xy 125.683518 -338.592922) (xy 119.642953 -338.592922)
			(xy 119.635668 -338.596249) (xy 119.583373 -338.611604) (xy 119.529425 -338.61936) (xy 119.474923 -338.61936)
			(xy 119.420975 -338.611604) (xy 119.36868 -338.596249) (xy 119.319103 -338.573607) (xy 119.273253 -338.544141)
			(xy 119.232062 -338.50845) (xy 119.196371 -338.467259) (xy 119.166905 -338.421409) (xy 119.144263 -338.371832)
			(xy 119.128908 -338.319537) (xy 119.121152 -338.265589) (xy 119.120666 -338.238338) (xy 113.744764 -338.238338)
			(xy 113.732805 -338.256947) (xy 113.697114 -338.298138) (xy 113.655923 -338.333829) (xy 113.610073 -338.363295)
			(xy 113.560496 -338.385937) (xy 113.508201 -338.401292) (xy 113.454253 -338.409048) (xy 113.399751 -338.409048)
			(xy 113.345803 -338.401292) (xy 113.293508 -338.385937) (xy 113.243931 -338.363295) (xy 113.198081 -338.333829)
			(xy 113.15689 -338.298138) (xy 113.121199 -338.256947) (xy 113.091733 -338.211097) (xy 113.069091 -338.16152)
			(xy 113.053736 -338.109225) (xy 113.04598 -338.055277) (xy 113.045494 -338.028026) (xy 113.046024 -337.998121)
			(xy 113.05534 -337.939042) (xy 113.064036 -337.910424) (xy 113.068065 -337.896515) (xy 113.068969 -337.867586)
			(xy 113.061702 -337.839569) (xy 113.046852 -337.814725) (xy 113.025615 -337.79506) (xy 112.999706 -337.782158)
			(xy 112.98555 -337.779106) (xy 112.952713 -337.772512) (xy 112.889859 -337.749397) (xy 112.860582 -337.733132)
			(xy 112.847611 -337.726106) (xy 112.818977 -337.719074) (xy 112.789528 -337.720518) (xy 112.761719 -337.730318)
			(xy 112.73787 -337.747656) (xy 112.719971 -337.771086) (xy 112.714278 -337.784694) (xy 112.70353 -337.811448)
			(xy 112.67525 -337.861689) (xy 112.639727 -337.907098) (xy 112.597773 -337.946642) (xy 112.550343 -337.979418)
			(xy 112.498519 -338.00468) (xy 112.443483 -338.021851) (xy 112.386488 -338.030541) (xy 112.357662 -338.031074)
			(xy 112.33041 -338.030654) (xy 112.276462 -338.022892) (xy 112.224167 -338.007532) (xy 112.17459 -337.984887)
			(xy 112.12874 -337.955417) (xy 112.087551 -337.919722) (xy 112.05186 -337.878529) (xy 112.022395 -337.832677)
			(xy 111.999755 -337.783098) (xy 111.9844 -337.730801) (xy 111.976644 -337.676852) (xy 111.656463 -337.676852)
			(xy 111.633929 -337.708266) (xy 111.592261 -337.750569) (xy 111.568738 -337.768692) (xy 111.558101 -337.777085)
			(xy 111.541386 -337.798403) (xy 111.530865 -337.823365) (xy 111.527276 -337.850216) (xy 111.530873 -337.877065)
			(xy 111.541402 -337.902024) (xy 111.558123 -337.923336) (xy 111.568738 -337.93176) (xy 111.592285 -337.94985)
			(xy 111.633942 -337.992165) (xy 111.668541 -338.040422) (xy 111.695247 -338.093455) (xy 111.713416 -338.149986)
			(xy 111.722608 -338.208649) (xy 111.72317 -338.238338) (xy 111.722684 -338.265589) (xy 111.714928 -338.319537)
			(xy 111.699573 -338.371832) (xy 111.676931 -338.421409) (xy 111.647465 -338.467259) (xy 111.611774 -338.50845)
			(xy 111.570583 -338.544141) (xy 111.524733 -338.573607) (xy 111.475156 -338.596249) (xy 111.422861 -338.611604)
			(xy 111.368913 -338.61936) (xy 111.314411 -338.61936) (xy 111.260463 -338.611604) (xy 111.208168 -338.596249)
			(xy 111.158591 -338.573607) (xy 111.112741 -338.544141) (xy 111.07155 -338.50845) (xy 111.035859 -338.467259)
			(xy 111.006393 -338.421409) (xy 110.983751 -338.371832) (xy 110.968396 -338.319537) (xy 110.96064 -338.265589)
			(xy 110.960154 -338.238338) (xy 105.584252 -338.238338) (xy 105.572293 -338.256947) (xy 105.536602 -338.298138)
			(xy 105.495411 -338.333829) (xy 105.449561 -338.363295) (xy 105.399984 -338.385937) (xy 105.347689 -338.401292)
			(xy 105.293741 -338.409048) (xy 105.239239 -338.409048) (xy 105.185291 -338.401292) (xy 105.132996 -338.385937)
			(xy 105.083419 -338.363295) (xy 105.037569 -338.333829) (xy 104.996378 -338.298138) (xy 104.960687 -338.256947)
			(xy 104.931221 -338.211097) (xy 104.908579 -338.16152) (xy 104.893224 -338.109225) (xy 104.885468 -338.055277)
			(xy 104.884982 -338.028026) (xy 104.885513 -337.998121) (xy 104.894828 -337.939042) (xy 104.903524 -337.910424)
			(xy 104.907562 -337.896517) (xy 104.908467 -337.867586) (xy 104.901199 -337.839567) (xy 104.886347 -337.814723)
			(xy 104.865107 -337.795057) (xy 104.839195 -337.782157) (xy 104.825038 -337.779106) (xy 104.7922 -337.772515)
			(xy 104.729347 -337.749398) (xy 104.70007 -337.733132) (xy 104.687106 -337.726092) (xy 104.65847 -337.719062)
			(xy 104.629018 -337.720509) (xy 104.601208 -337.730311) (xy 104.577358 -337.747652) (xy 104.559459 -337.771085)
			(xy 104.553766 -337.784694) (xy 104.543028 -337.811453) (xy 104.514746 -337.861693) (xy 104.479223 -337.907103)
			(xy 104.437267 -337.946647) (xy 104.389836 -337.979422) (xy 104.33801 -338.004683) (xy 104.282973 -338.021854)
			(xy 104.225977 -338.030542) (xy 104.19715 -338.031074) (xy 104.169899 -338.030653) (xy 104.115952 -338.02289)
			(xy 104.063658 -338.007529) (xy 104.014083 -337.984883) (xy 103.968235 -337.955413) (xy 103.927047 -337.919718)
			(xy 103.891357 -337.878525) (xy 103.861893 -337.832673) (xy 103.839254 -337.783095) (xy 103.8239 -337.7308)
			(xy 103.816144 -337.676851) (xy 103.495955 -337.676851) (xy 103.473419 -337.708267) (xy 103.43175 -337.75057)
			(xy 103.408226 -337.768692) (xy 103.39759 -337.777086) (xy 103.380877 -337.798404) (xy 103.370357 -337.823366)
			(xy 103.366769 -337.850216) (xy 103.370365 -337.877064) (xy 103.380893 -337.902023) (xy 103.397612 -337.923336)
			(xy 103.408226 -337.93176) (xy 103.43177 -337.949853) (xy 103.473428 -337.992167) (xy 103.508028 -338.040423)
			(xy 103.534735 -338.093456) (xy 103.552903 -338.149986) (xy 103.562096 -338.208649) (xy 103.562658 -338.238338)
			(xy 103.562172 -338.265589) (xy 103.554416 -338.319537) (xy 103.539061 -338.371832) (xy 103.516419 -338.421409)
			(xy 103.486953 -338.467259) (xy 103.451262 -338.50845) (xy 103.410071 -338.544141) (xy 103.364221 -338.573607)
			(xy 103.314644 -338.596249) (xy 103.262349 -338.611604) (xy 103.208401 -338.61936) (xy 103.153899 -338.61936)
			(xy 103.099951 -338.611604) (xy 103.047656 -338.596249) (xy 102.998079 -338.573607) (xy 102.952229 -338.544141)
			(xy 102.911038 -338.50845) (xy 102.875347 -338.467259) (xy 102.845881 -338.421409) (xy 102.823239 -338.371832)
			(xy 102.807884 -338.319537) (xy 102.800128 -338.265589) (xy 102.799642 -338.238338) (xy 97.42374 -338.238338)
			(xy 97.411781 -338.256947) (xy 97.37609 -338.298138) (xy 97.334899 -338.333829) (xy 97.289049 -338.363295)
			(xy 97.239472 -338.385937) (xy 97.187177 -338.401292) (xy 97.133229 -338.409048) (xy 97.078727 -338.409048)
			(xy 97.024779 -338.401292) (xy 96.972484 -338.385937) (xy 96.922907 -338.363295) (xy 96.877057 -338.333829)
			(xy 96.835866 -338.298138) (xy 96.800175 -338.256947) (xy 96.770709 -338.211097) (xy 96.748067 -338.16152)
			(xy 96.732712 -338.109225) (xy 96.724956 -338.055277) (xy 96.72447 -338.028026) (xy 96.725001 -337.998121)
			(xy 96.734316 -337.939042) (xy 96.743012 -337.910424) (xy 96.74706 -337.896519) (xy 96.747965 -337.867586)
			(xy 96.740696 -337.839565) (xy 96.725842 -337.81472) (xy 96.704599 -337.795054) (xy 96.678684 -337.782155)
			(xy 96.664526 -337.779106) (xy 96.631688 -337.772518) (xy 96.568835 -337.749399) (xy 96.539558 -337.733132)
			(xy 96.526602 -337.726078) (xy 96.497962 -337.71905) (xy 96.468508 -337.720499) (xy 96.440696 -337.730304)
			(xy 96.416846 -337.747648) (xy 96.398947 -337.771083) (xy 96.393254 -337.784694) (xy 96.382526 -337.811457)
			(xy 96.354243 -337.861698) (xy 96.318718 -337.907108) (xy 96.276761 -337.946651) (xy 96.229328 -337.979427)
			(xy 96.177501 -338.004687) (xy 96.122462 -338.021856) (xy 96.065465 -338.030542) (xy 96.036638 -338.031074)
			(xy 96.009381 -338.030682) (xy 95.955421 -338.022928) (xy 95.903114 -338.007574) (xy 95.853525 -337.984932)
			(xy 95.807662 -337.955462) (xy 95.766462 -337.919765) (xy 95.730761 -337.878568) (xy 95.701286 -337.832709)
			(xy 95.678639 -337.783122) (xy 95.66328 -337.730816) (xy 95.655521 -337.676857) (xy 95.335442 -337.676857)
			(xy 95.312908 -337.708268) (xy 95.271238 -337.75057) (xy 95.247714 -337.768692) (xy 95.237079 -337.777087)
			(xy 95.220368 -337.798405) (xy 95.209849 -337.823367) (xy 95.206262 -337.850216) (xy 95.209858 -337.877063)
			(xy 95.220384 -337.902021) (xy 95.237101 -337.923335) (xy 95.247714 -337.93176) (xy 95.271256 -337.949857)
			(xy 95.312914 -337.992169) (xy 95.347515 -338.040424) (xy 95.374222 -338.093457) (xy 95.392391 -338.149987)
			(xy 95.401584 -338.208649) (xy 95.402146 -338.238338) (xy 95.40166 -338.265589) (xy 95.393904 -338.319537)
			(xy 95.378549 -338.371832) (xy 95.355907 -338.421409) (xy 95.326441 -338.467259) (xy 95.29075 -338.50845)
			(xy 95.249559 -338.544141) (xy 95.203709 -338.573607) (xy 95.154132 -338.596249) (xy 95.101837 -338.611604)
			(xy 95.047889 -338.61936) (xy 94.993387 -338.61936) (xy 94.939439 -338.611604) (xy 94.887144 -338.596249)
			(xy 94.837567 -338.573607) (xy 94.791717 -338.544141) (xy 94.750526 -338.50845) (xy 94.714835 -338.467259)
			(xy 94.685369 -338.421409) (xy 94.662727 -338.371832) (xy 94.647372 -338.319537) (xy 94.639616 -338.265589)
			(xy 94.63913 -338.238338) (xy 85.513487 -338.238338) (xy 85.497013 -338.253124) (xy 85.452672 -338.282917)
			(xy 85.428836 -338.29498) (xy 85.415646 -338.301849) (xy 85.393733 -338.32194) (xy 85.378532 -338.347489)
			(xy 85.371329 -338.376332) (xy 85.372735 -338.406028) (xy 85.382631 -338.434062) (xy 85.39099 -338.446364)
			(xy 85.408342 -338.471021) (xy 85.435855 -338.524669) (xy 85.454589 -338.581976) (xy 85.464077 -338.641516)
			(xy 85.46465 -338.671662) (xy 85.464164 -338.698913) (xy 85.456408 -338.752861) (xy 85.441053 -338.805156)
			(xy 85.418411 -338.854733) (xy 85.388945 -338.900583) (xy 85.353254 -338.941774) (xy 85.312063 -338.977465)
			(xy 85.293803 -338.9892) (xy 89.129495 -338.9892) (xy 89.133664 -338.933573) (xy 89.146078 -338.879188)
			(xy 89.16646 -338.827262) (xy 89.194353 -338.778953) (xy 89.229135 -338.735342) (xy 89.27003 -338.697402)
			(xy 89.316122 -338.665981) (xy 89.366383 -338.641782) (xy 89.419689 -338.625344) (xy 89.47485 -338.617036)
			(xy 89.502742 -338.616544) (xy 89.530074 -338.617024) (xy 89.584153 -338.624991) (xy 89.636488 -338.640777)
			(xy 89.685952 -338.664044) (xy 89.731485 -338.69429) (xy 89.772107 -338.730868) (xy 89.806946 -338.77299)
			(xy 89.821512 -338.796122) (xy 89.829441 -338.808342) (xy 89.850912 -338.82801) (xy 89.877063 -338.840814)
			(xy 89.905767 -338.845711) (xy 89.934684 -338.842302) (xy 89.948258 -338.837016) (xy 89.971464 -338.827517)
			(xy 90.019799 -338.814169) (xy 90.06949 -338.807445) (xy 90.094562 -338.807044) (xy 90.119632 -338.807458)
			(xy 90.169315 -338.814212) (xy 90.217649 -338.827548) (xy 90.240866 -338.837016) (xy 90.254444 -338.84226)
			(xy 90.283344 -338.845625) (xy 90.312022 -338.840714) (xy 90.338156 -338.827926) (xy 90.359631 -338.808296)
			(xy 90.367612 -338.796122) (xy 90.382181 -338.772991) (xy 90.417024 -338.73087) (xy 90.457647 -338.694291)
			(xy 90.503178 -338.66404) (xy 90.55264 -338.640764) (xy 90.604971 -338.624964) (xy 90.65905 -338.616978)
			(xy 90.713714 -338.616978) (xy 90.767793 -338.624964) (xy 90.820124 -338.640764) (xy 90.869586 -338.66404)
			(xy 90.915117 -338.694291) (xy 90.95574 -338.73087) (xy 90.990583 -338.772991) (xy 91.005152 -338.796122)
			(xy 91.013043 -338.808369) (xy 91.034524 -338.828038) (xy 91.060686 -338.840838) (xy 91.089398 -338.845727)
			(xy 91.118322 -338.842308) (xy 91.131898 -338.837016) (xy 91.155111 -338.827536) (xy 91.203442 -338.814181)
			(xy 91.253131 -338.807449) (xy 91.278202 -338.807044) (xy 91.30584 -338.807554) (xy 91.360507 -338.815747)
			(xy 91.413365 -338.831923) (xy 91.463254 -338.855727) (xy 91.509081 -338.886638) (xy 91.549841 -338.923978)
			(xy 91.584639 -338.966928) (xy 91.612713 -339.014545) (xy 91.633448 -339.065787) (xy 91.640406 -339.09254)
			(xy 91.644031 -339.105642) (xy 91.657168 -339.129428) (xy 91.676113 -339.148908) (xy 91.699525 -339.162702)
			(xy 91.725746 -339.169834) (xy 91.752919 -339.169798) (xy 91.779121 -339.162598) (xy 91.791028 -339.15604)
			(xy 91.813174 -339.143407) (xy 91.860126 -339.123531) (xy 91.909309 -339.110095) (xy 91.959845 -339.103339)
			(xy 91.985338 -339.102954) (xy 91.993466 -339.102954) (xy 92.008325 -339.102719) (xy 92.036942 -339.094758)
			(xy 92.062067 -339.078913) (xy 92.081582 -339.056521) (xy 92.093844 -339.029466) (xy 92.096336 -339.014816)
			(xy 92.100451 -338.987679) (xy 92.115458 -338.934885) (xy 92.137872 -338.884785) (xy 92.167232 -338.838412)
			(xy 92.202933 -338.796724) (xy 92.244237 -338.76058) (xy 92.290293 -338.730725) (xy 92.34015 -338.707776)
			(xy 92.392781 -338.692205) (xy 92.447099 -338.684334) (xy 92.474542 -338.683854) (xy 92.501793 -338.684339)
			(xy 92.555738 -338.6921) (xy 92.608031 -338.707458) (xy 92.657606 -338.730102) (xy 92.703454 -338.759569)
			(xy 92.744643 -338.79526) (xy 92.780334 -338.836449) (xy 92.8098 -338.882298) (xy 92.832443 -338.931873)
			(xy 92.847801 -338.984166) (xy 92.848525 -338.9892) (xy 129.932095 -338.9892) (xy 129.936264 -338.933577)
			(xy 129.948676 -338.879196) (xy 129.969055 -338.827272) (xy 129.996944 -338.778966) (xy 130.031722 -338.735356)
			(xy 130.072612 -338.697416) (xy 130.118699 -338.665995) (xy 130.168955 -338.641793) (xy 130.222256 -338.625352)
			(xy 130.277412 -338.617039) (xy 130.305302 -338.616544) (xy 130.332635 -338.616977) (xy 130.386717 -338.624953)
			(xy 130.439052 -338.640747) (xy 130.488517 -338.664021) (xy 130.534049 -338.694275) (xy 130.57467 -338.730859)
			(xy 130.609508 -338.772987) (xy 130.624072 -338.796122) (xy 130.631944 -338.808383) (xy 130.65343 -338.828052)
			(xy 130.679597 -338.84085) (xy 130.708314 -338.845736) (xy 130.737242 -338.842311) (xy 130.750818 -338.837016)
			(xy 130.774029 -338.827529) (xy 130.822361 -338.814177) (xy 130.87205 -338.807448) (xy 130.897122 -338.807044)
			(xy 130.922191 -338.807471) (xy 130.971874 -338.814219) (xy 131.020209 -338.82755) (xy 131.043426 -338.837016)
			(xy 131.057019 -338.842218) (xy 131.085911 -338.845591) (xy 131.114584 -338.840691) (xy 131.140716 -338.827912)
			(xy 131.16219 -338.808292) (xy 131.170172 -338.796122) (xy 131.184741 -338.772991) (xy 131.219584 -338.73087)
			(xy 131.260207 -338.694291) (xy 131.305738 -338.66404) (xy 131.3552 -338.640764) (xy 131.407531 -338.624964)
			(xy 131.46161 -338.616978) (xy 131.516274 -338.616978) (xy 131.570353 -338.624964) (xy 131.622684 -338.640764)
			(xy 131.672146 -338.66404) (xy 131.717677 -338.694291) (xy 131.7583 -338.73087) (xy 131.793143 -338.772991)
			(xy 131.807712 -338.796122) (xy 131.815641 -338.808342) (xy 131.837112 -338.82801) (xy 131.863263 -338.840814)
			(xy 131.891967 -338.845711) (xy 131.920884 -338.842302) (xy 131.934458 -338.837016) (xy 131.957664 -338.827517)
			(xy 132.005999 -338.814169) (xy 132.05569 -338.807445) (xy 132.080762 -338.807044) (xy 132.105703 -338.807423)
			(xy 132.15514 -338.81407) (xy 132.203249 -338.827251) (xy 132.249171 -338.84673) (xy 132.292085 -338.872159)
			(xy 132.311902 -338.887308) (xy 132.3234 -338.89589) (xy 132.34993 -338.906786) (xy 132.378445 -338.909859)
			(xy 132.406688 -338.904866) (xy 132.432421 -338.892202) (xy 132.453607 -338.87287) (xy 132.461508 -338.860892)
			(xy 132.476508 -338.837421) (xy 132.512171 -338.794638) (xy 132.553678 -338.757497) (xy 132.600146 -338.726789)
			(xy 132.650587 -338.703166) (xy 132.703928 -338.687133) (xy 132.759033 -338.679028) (xy 132.786882 -338.67852)
			(xy 132.815037 -338.678965) (xy 132.870737 -338.687226) (xy 132.924618 -338.703587) (xy 132.975508 -338.727691)
			(xy 133.0223 -338.759016) (xy 133.06398 -338.796879) (xy 133.099639 -338.840459) (xy 133.128504 -338.888807)
			(xy 133.149947 -338.940874) (xy 133.157214 -338.96808) (xy 133.161562 -338.983021) (xy 133.177813 -339.009536)
			(xy 133.201287 -339.029935) (xy 133.229809 -339.042329) (xy 133.260739 -339.04557) (xy 133.276086 -339.04301)
			(xy 133.294869 -339.03944) (xy 133.332914 -339.035624) (xy 133.352032 -339.03539) (xy 133.379282 -339.035882)
			(xy 133.433226 -339.043642) (xy 133.485516 -339.059) (xy 133.535089 -339.081643) (xy 133.580935 -339.11111)
			(xy 133.622122 -339.146801) (xy 133.657809 -339.18799) (xy 133.687273 -339.233839) (xy 133.709911 -339.283414)
			(xy 133.725265 -339.335706) (xy 133.73302 -339.38965) (xy 133.73302 -339.44415) (xy 133.725265 -339.498094)
			(xy 133.709911 -339.550386) (xy 133.687273 -339.599961) (xy 133.657809 -339.64581) (xy 133.622122 -339.686999)
			(xy 133.580935 -339.72269) (xy 133.535089 -339.752157) (xy 133.485516 -339.7748) (xy 133.433226 -339.790158)
			(xy 133.379282 -339.797918) (xy 133.352032 -339.798406) (xy 133.323878 -339.797929) (xy 133.26818 -339.78967)
			(xy 133.214302 -339.773313) (xy 133.163413 -339.749212) (xy 133.116621 -339.717892) (xy 133.074942 -339.680033)
			(xy 133.039281 -339.636457) (xy 133.010414 -339.588113) (xy 132.988968 -339.53605) (xy 132.9817 -339.508846)
			(xy 132.977428 -339.493877) (xy 132.961165 -339.467351) (xy 132.937673 -339.446949) (xy 132.909129 -339.434563)
			(xy 132.878181 -339.431342) (xy 132.862828 -339.433916) (xy 132.844045 -339.437484) (xy 132.806 -339.441301)
			(xy 132.786882 -339.441536) (xy 132.760716 -339.441097) (xy 132.708871 -339.433986) (xy 132.658488 -339.419844)
			(xy 132.610515 -339.398938) (xy 132.565855 -339.371661) (xy 132.545328 -339.35543) (xy 132.533921 -339.346707)
			(xy 132.507553 -339.33537) (xy 132.47907 -339.331838) (xy 132.450732 -339.336391) (xy 132.424788 -339.348667)
			(xy 132.403298 -339.367692) (xy 132.395214 -339.37956) (xy 132.389483 -339.388432) (xy 132.377156 -339.405587)
			(xy 132.370576 -339.41385) (xy 132.361312 -339.426139) (xy 132.349909 -339.454705) (xy 132.347517 -339.485371)
			(xy 132.354353 -339.515361) (xy 132.369797 -339.541961) (xy 132.392453 -339.562764) (xy 132.406136 -339.569806)
			(xy 132.429267 -339.581168) (xy 132.472506 -339.609205) (xy 132.51157 -339.642817) (xy 132.545746 -339.681389)
			(xy 132.574408 -339.724217) (xy 132.597033 -339.770519) (xy 132.605526 -339.79485) (xy 132.610638 -339.808596)
			(xy 132.627402 -339.832642) (xy 132.650295 -339.850949) (xy 132.67744 -339.862015) (xy 132.706607 -339.864932)
			(xy 132.721096 -339.862668) (xy 132.739021 -339.859459) (xy 132.775277 -339.85602) (xy 132.793486 -339.85581)
			(xy 132.820739 -339.856268) (xy 132.874691 -339.864024) (xy 132.92699 -339.879379) (xy 132.976572 -339.902021)
			(xy 133.022426 -339.931489) (xy 133.063619 -339.967184) (xy 133.099313 -340.008377) (xy 133.128781 -340.054232)
			(xy 133.151422 -340.103813) (xy 133.166777 -340.156113) (xy 133.174532 -340.210065) (xy 133.174994 -340.237318)
			(xy 133.17474 -340.247732) (xy 133.174877 -340.262098) (xy 133.18214 -340.28988) (xy 133.196844 -340.314545)
			(xy 133.21783 -340.334145) (xy 133.24344 -340.347133) (xy 133.271652 -340.352484) (xy 133.285992 -340.351618)
			(xy 133.322568 -340.34984) (xy 133.349826 -340.350205) (xy 133.403787 -340.357959) (xy 133.456095 -340.373314)
			(xy 133.505686 -340.395958) (xy 133.551549 -340.425429) (xy 133.59275 -340.461127) (xy 133.628452 -340.502326)
			(xy 133.657927 -340.548186) (xy 133.680575 -340.597775) (xy 133.695934 -340.650082) (xy 133.703693 -340.704042)
			(xy 133.703693 -340.758558) (xy 133.695934 -340.812518) (xy 133.680575 -340.864825) (xy 133.657927 -340.914414)
			(xy 133.628452 -340.960274) (xy 133.59275 -341.001473) (xy 133.551549 -341.037171) (xy 133.505686 -341.066642)
			(xy 133.456095 -341.089286) (xy 133.403787 -341.104641) (xy 133.349826 -341.112395) (xy 133.322568 -341.112856)
			(xy 133.311557 -341.112774) (xy 133.289572 -341.111506) (xy 133.278626 -341.110316) (xy 133.263768 -341.109077)
			(xy 133.234433 -341.114331) (xy 133.207865 -341.127834) (xy 133.18633 -341.148435) (xy 133.171663 -341.174379)
			(xy 133.167882 -341.188802) (xy 133.161046 -341.216549) (xy 133.140188 -341.269751) (xy 133.111632 -341.31925)
			(xy 133.076016 -341.363938) (xy 133.034138 -341.402819) (xy 132.986931 -341.435023) (xy 132.935451 -341.45983)
			(xy 132.880849 -341.476686) (xy 132.824344 -341.485215) (xy 132.795772 -341.485728) (xy 132.766784 -341.485202)
			(xy 132.709477 -341.476427) (xy 132.654157 -341.459083) (xy 132.602097 -341.433569) (xy 132.554497 -341.400472)
			(xy 132.512452 -341.360556) (xy 132.476929 -341.314737) (xy 132.448748 -341.264073) (xy 132.428556 -341.209727)
			(xy 132.416818 -341.152952) (xy 132.414772 -341.124032) (xy 132.413612 -341.109956) (xy 132.40452 -341.083227)
			(xy 132.388444 -341.060018) (xy 132.366618 -341.042109) (xy 132.340716 -341.030875) (xy 132.312727 -341.027177)
			(xy 132.298694 -341.028782) (xy 132.28493 -341.030679) (xy 132.257216 -341.032711) (xy 132.243322 -341.032846)
			(xy 132.216073 -341.032301) (xy 132.162129 -341.024549) (xy 132.109838 -341.009198) (xy 132.060264 -340.986563)
			(xy 132.014415 -340.957102) (xy 131.973226 -340.921417) (xy 131.937534 -340.880233) (xy 131.908066 -340.834389)
			(xy 131.885423 -340.784818) (xy 131.870064 -340.732529) (xy 131.862303 -340.678587) (xy 131.861814 -340.651338)
			(xy 131.862301 -340.623764) (xy 131.870248 -340.569192) (xy 131.885969 -340.516332) (xy 131.909135 -340.466286)
			(xy 131.939264 -340.420096) (xy 131.975728 -340.378724) (xy 131.996434 -340.360508) (xy 132.00729 -340.350569)
			(xy 132.023358 -340.325929) (xy 132.031742 -340.297733) (xy 132.03175 -340.268316) (xy 132.023378 -340.240116)
			(xy 132.007322 -340.215468) (xy 131.996434 -340.205568) (xy 131.975711 -340.18737) (xy 131.93924 -340.145999)
			(xy 131.909109 -340.099807) (xy 131.885945 -340.049756) (xy 131.870231 -339.996891) (xy 131.862296 -339.942314)
			(xy 131.861814 -339.914738) (xy 131.862248 -339.888236) (xy 131.869597 -339.835744) (xy 131.884146 -339.784776)
			(xy 131.905614 -339.736314) (xy 131.933586 -339.691292) (xy 131.950206 -339.670644) (xy 131.959669 -339.658512)
			(xy 131.971464 -339.630107) (xy 131.974288 -339.599481) (xy 131.967888 -339.569398) (xy 131.95284 -339.542574)
			(xy 131.930504 -339.521431) (xy 131.916932 -339.51418) (xy 131.893237 -339.502088) (xy 131.849257 -339.472162)
			(xy 131.809977 -339.436289) (xy 131.776195 -339.395196) (xy 131.761992 -339.372702) (xy 131.754054 -339.360488)
			(xy 131.732587 -339.340817) (xy 131.706437 -339.328011) (xy 131.677736 -339.323113) (xy 131.648819 -339.326522)
			(xy 131.635246 -339.331808) (xy 131.61204 -339.341307) (xy 131.563705 -339.354654) (xy 131.514014 -339.361379)
			(xy 131.488942 -339.36178) (xy 131.463872 -339.361362) (xy 131.414189 -339.35461) (xy 131.365855 -339.341275)
			(xy 131.342638 -339.331808) (xy 131.329062 -339.326558) (xy 131.30016 -339.323191) (xy 131.27148 -339.328102)
			(xy 131.245345 -339.340892) (xy 131.223871 -339.360526) (xy 131.215892 -339.372702) (xy 131.201323 -339.395833)
			(xy 131.16648 -339.437954) (xy 131.125857 -339.474533) (xy 131.080326 -339.504784) (xy 131.030864 -339.52806)
			(xy 130.978533 -339.54386) (xy 130.924454 -339.551846) (xy 130.86979 -339.551846) (xy 130.815711 -339.54386)
			(xy 130.76338 -339.52806) (xy 130.713918 -339.504784) (xy 130.668387 -339.474533) (xy 130.627764 -339.437954)
			(xy 130.592921 -339.395833) (xy 130.578352 -339.372702) (xy 130.570452 -339.360461) (xy 130.548974 -339.34079)
			(xy 130.522815 -339.327987) (xy 130.494104 -339.323096) (xy 130.465181 -339.326516) (xy 130.451606 -339.331808)
			(xy 130.428393 -339.341288) (xy 130.380061 -339.354643) (xy 130.330373 -339.361375) (xy 130.305302 -339.36178)
			(xy 130.277412 -339.361361) (xy 130.222256 -339.353048) (xy 130.168955 -339.336607) (xy 130.118699 -339.312405)
			(xy 130.072612 -339.280984) (xy 130.031722 -339.243044) (xy 129.996944 -339.199434) (xy 129.969055 -339.151128)
			(xy 129.948676 -339.099204) (xy 129.936264 -339.044823) (xy 129.932095 -338.9892) (xy 92.848525 -338.9892)
			(xy 92.855562 -339.038111) (xy 92.85605 -339.065362) (xy 92.855523 -339.093963) (xy 92.846994 -339.150525)
			(xy 92.83012 -339.205182) (xy 92.80528 -339.256709) (xy 92.77303 -339.303952) (xy 92.734092 -339.345855)
			(xy 92.712032 -339.364066) (xy 92.701416 -339.373139) (xy 92.685125 -339.395806) (xy 92.675581 -339.422039)
			(xy 92.6735 -339.449875) (xy 92.679035 -339.477235) (xy 92.691773 -339.502074) (xy 92.710763 -339.522534)
			(xy 92.722446 -339.530182) (xy 92.746065 -339.545126) (xy 92.789079 -339.580814) (xy 92.826427 -339.622394)
			(xy 92.857311 -339.668977) (xy 92.881071 -339.719566) (xy 92.897198 -339.773079) (xy 92.905347 -339.828373)
			(xy 92.905834 -339.856318) (xy 92.905414 -339.882211) (xy 92.898413 -339.933522) (xy 92.884529 -339.983413)
			(xy 92.864018 -340.030964) (xy 92.849543 -340.054946) (xy 126.474472 -340.054946) (xy 126.478543 -339.999324)
			(xy 126.490669 -339.944887) (xy 126.510592 -339.892796) (xy 126.537888 -339.844161) (xy 126.571974 -339.800018)
			(xy 126.612123 -339.761309) (xy 126.657481 -339.728858) (xy 126.707081 -339.703357) (xy 126.759865 -339.68535)
			(xy 126.814708 -339.67522) (xy 126.870442 -339.673183) (xy 126.925879 -339.679283) (xy 126.979836 -339.693389)
			(xy 127.031165 -339.715201) (xy 127.078771 -339.744255) (xy 127.121639 -339.77993) (xy 127.158856 -339.821467)
			(xy 127.189629 -339.86798) (xy 127.213301 -339.918477) (xy 127.229369 -339.971884) (xy 127.237489 -340.02706)
			(xy 127.237998 -340.054946) (xy 127.237489 -340.082832) (xy 127.229369 -340.138008) (xy 127.213301 -340.191415)
			(xy 127.189629 -340.241912) (xy 127.158856 -340.288425) (xy 127.121639 -340.329962) (xy 127.078771 -340.365637)
			(xy 127.031165 -340.394691) (xy 126.979836 -340.416503) (xy 126.925879 -340.430609) (xy 126.870442 -340.436709)
			(xy 126.814708 -340.434672) (xy 126.759865 -340.424542) (xy 126.707081 -340.406535) (xy 126.657481 -340.381034)
			(xy 126.612123 -340.348583) (xy 126.571974 -340.309874) (xy 126.537888 -340.265731) (xy 126.510592 -340.217096)
			(xy 126.490669 -340.165005) (xy 126.478543 -340.110568) (xy 126.474472 -340.054946) (xy 92.849543 -340.054946)
			(xy 92.837257 -340.075301) (xy 92.80474 -340.115605) (xy 92.7862 -340.133686) (xy 92.776099 -340.143826)
			(xy 92.761486 -340.16842) (xy 92.754279 -340.196106) (xy 92.755045 -340.224704) (xy 92.763725 -340.251964)
			(xy 92.779634 -340.27574) (xy 92.790264 -340.285324) (xy 92.811084 -340.303523) (xy 92.847757 -340.344909)
			(xy 92.878062 -340.391161) (xy 92.901364 -340.441308) (xy 92.917173 -340.494297) (xy 92.925157 -340.549014)
			(xy 92.925646 -340.576662) (xy 92.925087 -340.603911) (xy 92.917336 -340.657854) (xy 92.910526 -340.681056)
			(xy 125.683008 -340.681056) (xy 125.687079 -340.625434) (xy 125.699205 -340.570997) (xy 125.719128 -340.518906)
			(xy 125.746424 -340.470271) (xy 125.78051 -340.426128) (xy 125.820659 -340.387419) (xy 125.866017 -340.354968)
			(xy 125.915617 -340.329467) (xy 125.968401 -340.31146) (xy 126.023244 -340.30133) (xy 126.078978 -340.299293)
			(xy 126.134415 -340.305393) (xy 126.188372 -340.319499) (xy 126.239701 -340.341311) (xy 126.287307 -340.370365)
			(xy 126.330175 -340.40604) (xy 126.367392 -340.447577) (xy 126.398165 -340.49409) (xy 126.421837 -340.544587)
			(xy 126.437905 -340.597994) (xy 126.446025 -340.65317) (xy 126.446534 -340.681056) (xy 126.446025 -340.708942)
			(xy 126.437905 -340.764118) (xy 126.421837 -340.817525) (xy 126.398165 -340.868022) (xy 126.367392 -340.914535)
			(xy 126.330175 -340.956072) (xy 126.287307 -340.991747) (xy 126.239701 -341.020801) (xy 126.188372 -341.042613)
			(xy 126.134415 -341.056719) (xy 126.078978 -341.062819) (xy 126.023244 -341.060782) (xy 125.968401 -341.050652)
			(xy 125.915617 -341.032645) (xy 125.866017 -341.007144) (xy 125.820659 -340.974693) (xy 125.78051 -340.935984)
			(xy 125.746424 -340.891841) (xy 125.719128 -340.843206) (xy 125.699205 -340.791115) (xy 125.687079 -340.736678)
			(xy 125.683008 -340.681056) (xy 92.910526 -340.681056) (xy 92.901988 -340.710145) (xy 92.879354 -340.759719)
			(xy 92.849895 -340.805568) (xy 92.814211 -340.846757) (xy 92.773029 -340.88245) (xy 92.727186 -340.911917)
			(xy 92.677616 -340.934561) (xy 92.625328 -340.94992) (xy 92.571386 -340.957681) (xy 92.544138 -340.95817)
			(xy 92.515061 -340.957651) (xy 92.45758 -340.948831) (xy 92.402103 -340.931388) (xy 92.349916 -340.905728)
			(xy 92.302229 -340.872445) (xy 92.260145 -340.83231) (xy 92.22464 -340.786252) (xy 92.196536 -340.73534)
			(xy 92.185998 -340.708234) (xy 92.180456 -340.694696) (xy 92.162994 -340.671244) (xy 92.1396 -340.653705)
			(xy 92.112194 -340.643518) (xy 92.083024 -340.641518) (xy 92.06865 -340.644226) (xy 92.048091 -340.648521)
			(xy 92.006339 -340.653098) (xy 91.985338 -340.65337) (xy 91.971122 -340.65321) (xy 91.942772 -340.65105)
			(xy 91.928696 -340.649052) (xy 91.913365 -340.647367) (xy 91.882917 -340.652173) (xy 91.855285 -340.665837)
			(xy 91.832982 -340.687116) (xy 91.818036 -340.714076) (xy 91.814396 -340.729062) (xy 91.807912 -340.757296)
			(xy 91.787671 -340.811571) (xy 91.759458 -340.862163) (xy 91.723922 -340.907908) (xy 91.68188 -340.947757)
			(xy 91.634297 -340.980792) (xy 91.582268 -341.006255) (xy 91.526987 -341.023561) (xy 91.469725 -341.032311)
			(xy 91.440762 -341.032846) (xy 91.413512 -341.032358) (xy 91.359566 -341.024597) (xy 91.307274 -341.009239)
			(xy 91.257699 -340.986596) (xy 91.21185 -340.957129) (xy 91.170662 -340.921438) (xy 91.134971 -340.88025)
			(xy 91.105504 -340.834401) (xy 91.082861 -340.784826) (xy 91.067503 -340.732534) (xy 91.059742 -340.678588)
			(xy 91.059254 -340.651338) (xy 91.059727 -340.623764) (xy 91.067675 -340.56919) (xy 91.083398 -340.51633)
			(xy 91.106566 -340.466283) (xy 91.136698 -340.420094) (xy 91.173166 -340.378723) (xy 91.193874 -340.360508)
			(xy 91.204735 -340.350572) (xy 91.220813 -340.325933) (xy 91.229203 -340.297735) (xy 91.22921 -340.268314)
			(xy 91.220833 -340.240112) (xy 91.204768 -340.215465) (xy 91.193874 -340.205568) (xy 91.173139 -340.187383)
			(xy 91.136672 -340.146008) (xy 91.106543 -340.099812) (xy 91.083382 -340.049759) (xy 91.06767 -339.996893)
			(xy 91.059736 -339.942314) (xy 91.059254 -339.914738) (xy 91.059701 -339.888237) (xy 91.06705 -339.835746)
			(xy 91.081596 -339.784778) (xy 91.10306 -339.736316) (xy 91.131029 -339.691293) (xy 91.147646 -339.670644)
			(xy 91.157095 -339.658503) (xy 91.168883 -339.630101) (xy 91.171706 -339.59948) (xy 91.165308 -339.569401)
			(xy 91.150267 -339.542579) (xy 91.127939 -339.521434) (xy 91.114372 -339.51418) (xy 91.090684 -339.502075)
			(xy 91.046702 -339.472154) (xy 91.00742 -339.436284) (xy 90.973636 -339.395194) (xy 90.959432 -339.372702)
			(xy 90.951551 -339.360448) (xy 90.930068 -339.340776) (xy 90.903903 -339.327975) (xy 90.875188 -339.323088)
			(xy 90.846262 -339.326513) (xy 90.832686 -339.331808) (xy 90.809475 -339.341295) (xy 90.761143 -339.354647)
			(xy 90.711454 -339.361376) (xy 90.686382 -339.36178) (xy 90.661313 -339.361349) (xy 90.61163 -339.354603)
			(xy 90.563296 -339.341273) (xy 90.540078 -339.331808) (xy 90.526487 -339.3266) (xy 90.497593 -339.323225)
			(xy 90.468919 -339.328125) (xy 90.442786 -339.340906) (xy 90.421312 -339.36053) (xy 90.413332 -339.372702)
			(xy 90.398763 -339.395833) (xy 90.36392 -339.437954) (xy 90.323297 -339.474533) (xy 90.277766 -339.504784)
			(xy 90.228304 -339.52806) (xy 90.175973 -339.54386) (xy 90.121894 -339.551846) (xy 90.06723 -339.551846)
			(xy 90.013151 -339.54386) (xy 89.96082 -339.52806) (xy 89.911358 -339.504784) (xy 89.865827 -339.474533)
			(xy 89.825204 -339.437954) (xy 89.790361 -339.395833) (xy 89.775792 -339.372702) (xy 89.767854 -339.360488)
			(xy 89.746387 -339.340817) (xy 89.720237 -339.328011) (xy 89.691536 -339.323113) (xy 89.662619 -339.326522)
			(xy 89.649046 -339.331808) (xy 89.62584 -339.341307) (xy 89.577505 -339.354654) (xy 89.527814 -339.361379)
			(xy 89.502742 -339.36178) (xy 89.47485 -339.361364) (xy 89.419689 -339.353056) (xy 89.366383 -339.336618)
			(xy 89.316122 -339.312419) (xy 89.27003 -339.280998) (xy 89.229135 -339.243058) (xy 89.194353 -339.199447)
			(xy 89.16646 -339.151138) (xy 89.146078 -339.099212) (xy 89.133664 -339.044827) (xy 89.129495 -338.9892)
			(xy 85.293803 -338.9892) (xy 85.266213 -339.006931) (xy 85.216636 -339.029573) (xy 85.164341 -339.044928)
			(xy 85.110393 -339.052684) (xy 85.055891 -339.052684) (xy 85.001943 -339.044928) (xy 84.949648 -339.029573)
			(xy 84.900071 -339.006931) (xy 84.854221 -338.977465) (xy 84.81303 -338.941774) (xy 84.777339 -338.900583)
			(xy 84.747873 -338.854733) (xy 84.725231 -338.805156) (xy 84.709876 -338.752861) (xy 84.70212 -338.698913)
			(xy 84.701634 -338.671662) (xy 76.40701 -338.671662) (xy 76.40701 -340.054946) (xy 85.671912 -340.054946)
			(xy 85.675983 -339.999324) (xy 85.688109 -339.944887) (xy 85.708032 -339.892796) (xy 85.735328 -339.844161)
			(xy 85.769414 -339.800018) (xy 85.809563 -339.761309) (xy 85.854921 -339.728858) (xy 85.904521 -339.703357)
			(xy 85.957305 -339.68535) (xy 86.012148 -339.67522) (xy 86.067882 -339.673183) (xy 86.123319 -339.679283)
			(xy 86.177276 -339.693389) (xy 86.228605 -339.715201) (xy 86.276211 -339.744255) (xy 86.319079 -339.77993)
			(xy 86.356296 -339.821467) (xy 86.387069 -339.86798) (xy 86.410741 -339.918477) (xy 86.426809 -339.971884)
			(xy 86.434929 -340.02706) (xy 86.435438 -340.054946) (xy 86.434929 -340.082832) (xy 86.426809 -340.138008)
			(xy 86.410741 -340.191415) (xy 86.387069 -340.241912) (xy 86.356296 -340.288425) (xy 86.319079 -340.329962)
			(xy 86.276211 -340.365637) (xy 86.228605 -340.394691) (xy 86.177276 -340.416503) (xy 86.123319 -340.430609)
			(xy 86.067882 -340.436709) (xy 86.012148 -340.434672) (xy 85.957305 -340.424542) (xy 85.904521 -340.406535)
			(xy 85.854921 -340.381034) (xy 85.809563 -340.348583) (xy 85.769414 -340.309874) (xy 85.735328 -340.265731)
			(xy 85.708032 -340.217096) (xy 85.688109 -340.165005) (xy 85.675983 -340.110568) (xy 85.671912 -340.054946)
			(xy 76.40701 -340.054946) (xy 76.40701 -341.059262) (xy 85.007448 -341.059262) (xy 85.011519 -341.00364)
			(xy 85.023645 -340.949203) (xy 85.043568 -340.897112) (xy 85.070864 -340.848477) (xy 85.10495 -340.804334)
			(xy 85.145099 -340.765625) (xy 85.190457 -340.733174) (xy 85.240057 -340.707673) (xy 85.292841 -340.689666)
			(xy 85.347684 -340.679536) (xy 85.403418 -340.677499) (xy 85.458855 -340.683599) (xy 85.512812 -340.697705)
			(xy 85.564141 -340.719517) (xy 85.611747 -340.748571) (xy 85.654615 -340.784246) (xy 85.691832 -340.825783)
			(xy 85.722605 -340.872296) (xy 85.746277 -340.922793) (xy 85.762345 -340.9762) (xy 85.770465 -341.031376)
			(xy 85.770974 -341.059262) (xy 85.770465 -341.087148) (xy 85.762345 -341.142324) (xy 85.746277 -341.195731)
			(xy 85.722605 -341.246228) (xy 85.691832 -341.292741) (xy 85.654615 -341.334278) (xy 85.611747 -341.369953)
			(xy 85.564141 -341.399007) (xy 85.512812 -341.420819) (xy 85.458855 -341.434925) (xy 85.403418 -341.441025)
			(xy 85.347684 -341.438988) (xy 85.292841 -341.428858) (xy 85.240057 -341.410851) (xy 85.190457 -341.38535)
			(xy 85.145099 -341.352899) (xy 85.10495 -341.31419) (xy 85.070864 -341.270047) (xy 85.043568 -341.221412)
			(xy 85.023645 -341.169321) (xy 85.011519 -341.114884) (xy 85.007448 -341.059262) (xy 76.40701 -341.059262)
			(xy 76.40701 -341.648542) (xy 86.478618 -341.648542) (xy 86.479196 -341.618855) (xy 86.488389 -341.560196)
			(xy 86.506559 -341.503671) (xy 86.533268 -341.450643) (xy 86.56787 -341.402394) (xy 86.609531 -341.360088)
			(xy 86.63305 -341.341964) (xy 86.643624 -341.333501) (xy 86.660324 -341.312195) (xy 86.670839 -341.28725)
			(xy 86.674432 -341.260418) (xy 86.670849 -341.233585) (xy 86.660342 -341.208636) (xy 86.64365 -341.187324)
			(xy 86.63305 -341.178896) (xy 86.609527 -341.160776) (xy 86.56787 -341.118467) (xy 86.533268 -341.070217)
			(xy 86.506558 -341.017189) (xy 86.488384 -340.960663) (xy 86.479184 -340.902005) (xy 86.478618 -340.872318)
			(xy 86.479104 -340.845067) (xy 86.48686 -340.791119) (xy 86.502215 -340.738824) (xy 86.524857 -340.689247)
			(xy 86.554323 -340.643397) (xy 86.590014 -340.602206) (xy 86.631205 -340.566515) (xy 86.677055 -340.537049)
			(xy 86.726632 -340.514407) (xy 86.778927 -340.499052) (xy 86.832875 -340.491296) (xy 86.887377 -340.491296)
			(xy 86.941325 -340.499052) (xy 86.99362 -340.514407) (xy 87.043197 -340.537049) (xy 87.089047 -340.566515)
			(xy 87.130238 -340.602206) (xy 87.165929 -340.643397) (xy 87.195395 -340.689247) (xy 87.218037 -340.738824)
			(xy 87.233392 -340.791119) (xy 87.241148 -340.845067) (xy 87.241634 -340.872318) (xy 87.241119 -340.902008)
			(xy 87.231915 -340.96067) (xy 87.213734 -341.017198) (xy 87.187013 -341.070226) (xy 87.174939 -341.087056)
			(xy 87.495025 -341.087056) (xy 87.495025 -341.032544) (xy 87.502783 -340.978586) (xy 87.518142 -340.926282)
			(xy 87.540788 -340.876696) (xy 87.570261 -340.830838) (xy 87.60596 -340.789642) (xy 87.647159 -340.753945)
			(xy 87.693019 -340.724476) (xy 87.742607 -340.701833) (xy 87.794912 -340.686478) (xy 87.84887 -340.678723)
			(xy 87.876126 -340.678262) (xy 87.901361 -340.678653) (xy 87.951396 -340.685273) (xy 88.000116 -340.698449)
			(xy 88.046667 -340.717947) (xy 88.068658 -340.730332) (xy 88.081597 -340.737424) (xy 88.110245 -340.744453)
			(xy 88.139706 -340.743) (xy 88.167523 -340.733188) (xy 88.191376 -340.715834) (xy 88.209273 -340.692386)
			(xy 88.214962 -340.67877) (xy 88.225657 -340.651993) (xy 88.253946 -340.601753) (xy 88.289477 -340.556344)
			(xy 88.331439 -340.516802) (xy 88.378876 -340.484029) (xy 88.430707 -340.458771) (xy 88.48575 -340.441604)
			(xy 88.542749 -340.43292) (xy 88.571578 -340.43239) (xy 88.59883 -340.432876) (xy 88.65278 -340.44063)
			(xy 88.705078 -340.455983) (xy 88.754657 -340.478623) (xy 88.800511 -340.508088) (xy 88.841703 -340.54378)
			(xy 88.877397 -340.58497) (xy 88.906866 -340.630821) (xy 88.929509 -340.6804) (xy 88.944865 -340.732696)
			(xy 88.952623 -340.786646) (xy 88.953086 -340.813898) (xy 88.952562 -340.843803) (xy 88.943242 -340.902883)
			(xy 88.934544 -340.9315) (xy 88.930537 -340.945417) (xy 88.929613 -340.974348) (xy 88.936868 -341.00237)
			(xy 88.951716 -341.027217) (xy 88.972956 -341.046881) (xy 88.998872 -341.059774) (xy 89.01303 -341.062818)
			(xy 89.039103 -341.067986) (xy 89.089607 -341.084557) (xy 89.13732 -341.107981) (xy 89.181318 -341.137803)
			(xy 89.220748 -341.173446) (xy 89.254847 -341.214219) (xy 89.282954 -341.259332) (xy 89.304524 -341.307912)
			(xy 89.319139 -341.359015) (xy 89.326516 -341.411654) (xy 89.326974 -341.43823) (xy 89.326488 -341.465481)
			(xy 89.318732 -341.519429) (xy 89.303377 -341.571724) (xy 89.280735 -341.621301) (xy 89.263228 -341.648542)
			(xy 127.281178 -341.648542) (xy 127.281772 -341.618856) (xy 127.290964 -341.560199) (xy 127.309132 -341.503674)
			(xy 127.335838 -341.450647) (xy 127.370437 -341.402397) (xy 127.412093 -341.360089) (xy 127.43561 -341.341964)
			(xy 127.446187 -341.333503) (xy 127.462893 -341.312198) (xy 127.473413 -341.287252) (xy 127.477007 -341.260418)
			(xy 127.473423 -341.233583) (xy 127.462912 -341.208633) (xy 127.446213 -341.187322) (xy 127.43561 -341.178896)
			(xy 127.4121 -341.16076) (xy 127.370439 -341.118456) (xy 127.335834 -341.07021) (xy 127.309121 -341.017184)
			(xy 127.290945 -340.960661) (xy 127.281744 -340.902005) (xy 127.281178 -340.872318) (xy 127.281664 -340.845067)
			(xy 127.28942 -340.791119) (xy 127.304775 -340.738824) (xy 127.327417 -340.689247) (xy 127.356883 -340.643397)
			(xy 127.392574 -340.602206) (xy 127.433765 -340.566515) (xy 127.479615 -340.537049) (xy 127.529192 -340.514407)
			(xy 127.581487 -340.499052) (xy 127.635435 -340.491296) (xy 127.689937 -340.491296) (xy 127.743885 -340.499052)
			(xy 127.79618 -340.514407) (xy 127.845757 -340.537049) (xy 127.891607 -340.566515) (xy 127.932798 -340.602206)
			(xy 127.968489 -340.643397) (xy 127.997955 -340.689247) (xy 128.020597 -340.738824) (xy 128.035952 -340.791119)
			(xy 128.043708 -340.845067) (xy 128.044194 -340.872318) (xy 128.043654 -340.902007) (xy 128.034453 -340.960667)
			(xy 128.016274 -341.017193) (xy 127.989558 -341.07022) (xy 127.977484 -341.087053) (xy 128.297648 -341.087053)
			(xy 128.297648 -341.032547) (xy 128.305405 -340.978597) (xy 128.32076 -340.926299) (xy 128.343402 -340.876719)
			(xy 128.372869 -340.830865) (xy 128.408562 -340.789672) (xy 128.449754 -340.753978) (xy 128.495606 -340.724509)
			(xy 128.545186 -340.701865) (xy 128.597483 -340.686508) (xy 128.651433 -340.678749) (xy 128.678686 -340.678262)
			(xy 128.703921 -340.67867) (xy 128.753954 -340.685286) (xy 128.802675 -340.698456) (xy 128.849227 -340.717949)
			(xy 128.871218 -340.730332) (xy 128.88418 -340.737377) (xy 128.912819 -340.744413) (xy 128.942273 -340.742969)
			(xy 128.970086 -340.733165) (xy 128.993936 -340.715821) (xy 129.011832 -340.692382) (xy 129.017522 -340.67877)
			(xy 129.02825 -340.652008) (xy 129.056536 -340.601769) (xy 129.092062 -340.556361) (xy 129.134019 -340.516818)
			(xy 129.181451 -340.484043) (xy 129.233277 -340.458783) (xy 129.288315 -340.441612) (xy 129.345311 -340.432923)
			(xy 129.374138 -340.43239) (xy 129.40139 -340.432842) (xy 129.455339 -340.440604) (xy 129.507634 -340.455964)
			(xy 129.557211 -340.478609) (xy 129.603061 -340.508079) (xy 129.644251 -340.543774) (xy 129.679942 -340.584967)
			(xy 129.709408 -340.63082) (xy 129.732049 -340.6804) (xy 129.747404 -340.732696) (xy 129.75516 -340.786646)
			(xy 129.755646 -340.813898) (xy 129.75512 -340.843803) (xy 129.745801 -340.902882) (xy 129.737104 -340.9315)
			(xy 129.733129 -340.945424) (xy 129.732206 -340.974348) (xy 129.739458 -341.002364) (xy 129.754299 -341.027207)
			(xy 129.77553 -341.046872) (xy 129.801436 -341.05977) (xy 129.81559 -341.062818) (xy 129.841657 -341.068015)
			(xy 129.892161 -341.084581) (xy 129.939874 -341.108) (xy 129.983873 -341.137818) (xy 130.023305 -341.173458)
			(xy 130.057405 -341.214228) (xy 130.085512 -341.259339) (xy 130.107083 -341.307916) (xy 130.121698 -341.359018)
			(xy 130.129076 -341.411654) (xy 130.129534 -341.43823) (xy 130.129048 -341.465481) (xy 130.121292 -341.519429)
			(xy 130.105937 -341.571724) (xy 130.083295 -341.621301) (xy 130.053829 -341.667151) (xy 130.018138 -341.708342)
			(xy 129.976947 -341.744033) (xy 129.931097 -341.773499) (xy 129.88152 -341.796141) (xy 129.829225 -341.811496)
			(xy 129.775277 -341.819252) (xy 129.720775 -341.819252) (xy 129.666827 -341.811496) (xy 129.614532 -341.796141)
			(xy 129.564955 -341.773499) (xy 129.519105 -341.744033) (xy 129.477914 -341.708342) (xy 129.442223 -341.667151)
			(xy 129.412757 -341.621301) (xy 129.390115 -341.571724) (xy 129.37476 -341.519429) (xy 129.367004 -341.465481)
			(xy 129.366518 -341.43823) (xy 129.367048 -341.408325) (xy 129.376364 -341.349246) (xy 129.38506 -341.320628)
			(xy 129.389144 -341.306731) (xy 129.390052 -341.27779) (xy 129.382781 -341.249762) (xy 129.367918 -341.224911)
			(xy 129.346665 -341.205246) (xy 129.320738 -341.192354) (xy 129.306574 -341.18931) (xy 129.273733 -341.182734)
			(xy 129.210882 -341.159606) (xy 129.181606 -341.143336) (xy 129.168622 -341.136337) (xy 129.139993 -341.1293)
			(xy 129.110547 -341.130739) (xy 129.082741 -341.140534) (xy 129.058894 -341.157867) (xy 129.040995 -341.181292)
			(xy 129.035302 -341.194898) (xy 129.02462 -341.22168) (xy 128.996331 -341.271923) (xy 128.9608 -341.317334)
			(xy 128.918836 -341.356877) (xy 128.871397 -341.38965) (xy 128.819563 -341.414906) (xy 128.764518 -341.43207)
			(xy 128.707516 -341.44075) (xy 128.678686 -341.441278) (xy 128.651433 -341.440851) (xy 128.597483 -341.433092)
			(xy 128.545186 -341.417735) (xy 128.495606 -341.395091) (xy 128.449754 -341.365622) (xy 128.408562 -341.329928)
			(xy 128.372869 -341.288735) (xy 128.343402 -341.242881) (xy 128.32076 -341.193301) (xy 128.305405 -341.141003)
			(xy 128.297648 -341.087053) (xy 127.977484 -341.087053) (xy 127.95495 -341.118469) (xy 127.913284 -341.160773)
			(xy 127.889762 -341.178896) (xy 127.879128 -341.187289) (xy 127.862426 -341.208611) (xy 127.851913 -341.233572)
			(xy 127.848327 -341.260418) (xy 127.851922 -341.287263) (xy 127.862444 -341.31222) (xy 127.879153 -341.333536)
			(xy 127.889762 -341.341964) (xy 127.913247 -341.360131) (xy 127.954911 -341.402427) (xy 127.989519 -341.450668)
			(xy 128.016237 -341.503687) (xy 128.034418 -341.560205) (xy 128.043625 -341.618857) (xy 128.044194 -341.648542)
			(xy 128.043708 -341.675793) (xy 128.035952 -341.729741) (xy 128.020597 -341.782036) (xy 127.997955 -341.831613)
			(xy 127.968489 -341.877463) (xy 127.932798 -341.918654) (xy 127.891607 -341.954345) (xy 127.845757 -341.983811)
			(xy 127.79618 -342.006453) (xy 127.743885 -342.021808) (xy 127.689937 -342.029564) (xy 127.635435 -342.029564)
			(xy 127.581487 -342.021808) (xy 127.529192 -342.006453) (xy 127.479615 -341.983811) (xy 127.433765 -341.954345)
			(xy 127.392574 -341.918654) (xy 127.356883 -341.877463) (xy 127.327417 -341.831613) (xy 127.304775 -341.782036)
			(xy 127.28942 -341.729741) (xy 127.281664 -341.675793) (xy 127.281178 -341.648542) (xy 89.263228 -341.648542)
			(xy 89.251269 -341.667151) (xy 89.215578 -341.708342) (xy 89.174387 -341.744033) (xy 89.128537 -341.773499)
			(xy 89.07896 -341.796141) (xy 89.026665 -341.811496) (xy 88.972717 -341.819252) (xy 88.918215 -341.819252)
			(xy 88.864267 -341.811496) (xy 88.811972 -341.796141) (xy 88.762395 -341.773499) (xy 88.716545 -341.744033)
			(xy 88.675354 -341.708342) (xy 88.639663 -341.667151) (xy 88.610197 -341.621301) (xy 88.587555 -341.571724)
			(xy 88.5722 -341.519429) (xy 88.564444 -341.465481) (xy 88.563958 -341.43823) (xy 88.564491 -341.408325)
			(xy 88.573805 -341.349246) (xy 88.5825 -341.320628) (xy 88.586553 -341.306724) (xy 88.587459 -341.277789)
			(xy 88.580191 -341.249768) (xy 88.565335 -341.224921) (xy 88.544091 -341.205255) (xy 88.518173 -341.192358)
			(xy 88.504014 -341.18931) (xy 88.471175 -341.182725) (xy 88.408323 -341.159603) (xy 88.379046 -341.143336)
			(xy 88.366097 -341.136266) (xy 88.337454 -341.12924) (xy 88.307998 -341.130691) (xy 88.280185 -341.140499)
			(xy 88.256334 -341.157846) (xy 88.238434 -341.181286) (xy 88.232742 -341.194898) (xy 88.222026 -341.221666)
			(xy 88.193742 -341.271908) (xy 88.158215 -341.317317) (xy 88.116256 -341.356861) (xy 88.068821 -341.389635)
			(xy 88.016993 -341.414895) (xy 87.961952 -341.432062) (xy 87.904954 -341.440747) (xy 87.876126 -341.441278)
			(xy 87.84887 -341.440877) (xy 87.794912 -341.433122) (xy 87.742607 -341.417767) (xy 87.693019 -341.395124)
			(xy 87.647159 -341.365655) (xy 87.60596 -341.329958) (xy 87.570261 -341.288762) (xy 87.540788 -341.242904)
			(xy 87.518142 -341.193318) (xy 87.502783 -341.141014) (xy 87.495025 -341.087056) (xy 87.174939 -341.087056)
			(xy 87.152399 -341.118473) (xy 87.110727 -341.160775) (xy 87.087202 -341.178896) (xy 87.076564 -341.187287)
			(xy 87.059855 -341.208607) (xy 87.049338 -341.233569) (xy 87.045751 -341.260418) (xy 87.049347 -341.287266)
			(xy 87.059874 -341.312224) (xy 87.07659 -341.333538) (xy 87.087202 -341.341964) (xy 87.110696 -341.36012)
			(xy 87.152357 -341.40242) (xy 87.186963 -341.450663) (xy 87.213679 -341.503684) (xy 87.231859 -341.560203)
			(xy 87.241065 -341.618856) (xy 87.241634 -341.648542) (xy 87.241148 -341.675793) (xy 87.233392 -341.729741)
			(xy 87.218037 -341.782036) (xy 87.195395 -341.831613) (xy 87.165929 -341.877463) (xy 87.130238 -341.918654)
			(xy 87.089047 -341.954345) (xy 87.043197 -341.983811) (xy 86.99362 -342.006453) (xy 86.941325 -342.021808)
			(xy 86.887377 -342.029564) (xy 86.832875 -342.029564) (xy 86.778927 -342.021808) (xy 86.726632 -342.006453)
			(xy 86.677055 -341.983811) (xy 86.631205 -341.954345) (xy 86.590014 -341.918654) (xy 86.554323 -341.877463)
			(xy 86.524857 -341.831613) (xy 86.502215 -341.782036) (xy 86.48686 -341.729741) (xy 86.479104 -341.675793)
			(xy 86.478618 -341.648542) (xy 76.40701 -341.648542) (xy 76.40701 -342.619584) (xy 168.52519 -342.619584)
			(xy 168.525649 -342.592214) (xy 168.533469 -342.538034) (xy 168.54896 -342.485531) (xy 168.571803 -342.435784)
			(xy 168.601528 -342.389818) (xy 168.61917 -342.368886) (xy 168.628425 -342.357571) (xy 168.640604 -342.33101)
			(xy 168.644775 -342.302088) (xy 168.640597 -342.273167) (xy 168.628412 -342.246608) (xy 168.61917 -342.235282)
			(xy 168.601512 -342.214363) (xy 168.571784 -342.168394) (xy 168.548937 -342.118645) (xy 168.53344 -342.066141)
			(xy 168.525612 -342.01196) (xy 168.525614 -341.957216) (xy 168.533446 -341.903035) (xy 168.548946 -341.850532)
			(xy 168.571796 -341.800785) (xy 168.601526 -341.754818) (xy 168.61917 -341.733886) (xy 168.628425 -341.722571)
			(xy 168.640604 -341.69601) (xy 168.644775 -341.667088) (xy 168.640597 -341.638167) (xy 168.628412 -341.611608)
			(xy 168.61917 -341.600282) (xy 168.601512 -341.579363) (xy 168.571784 -341.533394) (xy 168.548937 -341.483645)
			(xy 168.53344 -341.431141) (xy 168.525612 -341.37696) (xy 168.525614 -341.322216) (xy 168.533446 -341.268035)
			(xy 168.548946 -341.215532) (xy 168.571796 -341.165785) (xy 168.601526 -341.119818) (xy 168.61917 -341.098886)
			(xy 168.628425 -341.087571) (xy 168.640604 -341.06101) (xy 168.644775 -341.032088) (xy 168.640597 -341.003167)
			(xy 168.628412 -340.976608) (xy 168.61917 -340.965282) (xy 168.601512 -340.944363) (xy 168.571784 -340.898394)
			(xy 168.548937 -340.848645) (xy 168.53344 -340.796141) (xy 168.525612 -340.74196) (xy 168.525614 -340.687216)
			(xy 168.533446 -340.633035) (xy 168.548946 -340.580532) (xy 168.571796 -340.530785) (xy 168.601526 -340.484818)
			(xy 168.61917 -340.463886) (xy 168.628425 -340.452571) (xy 168.640604 -340.42601) (xy 168.644775 -340.397088)
			(xy 168.640597 -340.368167) (xy 168.628412 -340.341608) (xy 168.61917 -340.330282) (xy 168.601512 -340.309363)
			(xy 168.571784 -340.263394) (xy 168.548937 -340.213645) (xy 168.53344 -340.161141) (xy 168.525612 -340.10696)
			(xy 168.525614 -340.052216) (xy 168.533446 -339.998035) (xy 168.548946 -339.945532) (xy 168.571796 -339.895785)
			(xy 168.601526 -339.849818) (xy 168.61917 -339.828886) (xy 168.628425 -339.817571) (xy 168.640604 -339.79101)
			(xy 168.644775 -339.762088) (xy 168.640597 -339.733167) (xy 168.628412 -339.706608) (xy 168.61917 -339.695282)
			(xy 168.601512 -339.674363) (xy 168.571784 -339.628394) (xy 168.548937 -339.578645) (xy 168.53344 -339.526141)
			(xy 168.525612 -339.47196) (xy 168.525614 -339.417216) (xy 168.533446 -339.363035) (xy 168.548946 -339.310532)
			(xy 168.571796 -339.260785) (xy 168.601526 -339.214818) (xy 168.61917 -339.193886) (xy 168.628425 -339.182571)
			(xy 168.640604 -339.15601) (xy 168.644775 -339.127088) (xy 168.640597 -339.098167) (xy 168.628412 -339.071608)
			(xy 168.61917 -339.060282) (xy 168.601551 -339.039334) (xy 168.571837 -338.993365) (xy 168.548998 -338.943621)
			(xy 168.533502 -338.891125) (xy 168.525668 -338.836952) (xy 168.52519 -338.809584) (xy 168.525663 -338.782332)
			(xy 168.533422 -338.728384) (xy 168.548779 -338.676089) (xy 168.571421 -338.626512) (xy 168.600889 -338.580662)
			(xy 168.636582 -338.539472) (xy 168.677773 -338.503781) (xy 168.723625 -338.474315) (xy 168.773203 -338.451674)
			(xy 168.825498 -338.436319) (xy 168.879446 -338.428562) (xy 168.906698 -338.428076) (xy 168.934069 -338.428525)
			(xy 168.98825 -338.436344) (xy 169.040754 -338.451836) (xy 169.0905 -338.474682) (xy 169.136466 -338.504412)
			(xy 169.157396 -338.522056) (xy 169.168724 -338.531292) (xy 169.195281 -338.543468) (xy 169.224198 -338.547641)
			(xy 169.253115 -338.543468) (xy 169.279672 -338.531292) (xy 169.291 -338.522056) (xy 169.311915 -338.504396)
			(xy 169.357893 -338.474689) (xy 169.407645 -338.451858) (xy 169.460149 -338.436371) (xy 169.514328 -338.428547)
			(xy 169.541698 -338.428076) (xy 169.569738 -338.428571) (xy 169.625216 -338.436772) (xy 169.678898 -338.452997)
			(xy 169.72963 -338.476899) (xy 169.776322 -338.507962) (xy 169.797476 -338.526374) (xy 169.808918 -338.536019)
			(xy 169.835961 -338.548799) (xy 169.865548 -338.553185) (xy 169.895135 -338.548799) (xy 169.922178 -338.536019)
			(xy 169.93362 -338.526374) (xy 169.954781 -338.507967) (xy 170.001456 -338.476871) (xy 170.052184 -338.452953)
			(xy 170.105871 -338.43673) (xy 170.161356 -338.428552) (xy 170.189398 -338.428076) (xy 170.216648 -338.42858)
			(xy 170.270595 -338.436335) (xy 170.322888 -338.451689) (xy 170.372464 -338.474329) (xy 170.418314 -338.503794)
			(xy 170.459504 -338.539483) (xy 170.495195 -338.580672) (xy 170.524662 -338.62652) (xy 170.547304 -338.676095)
			(xy 170.562661 -338.728388) (xy 170.570419 -338.782334) (xy 170.570906 -338.809584) (xy 170.570429 -338.836954)
			(xy 170.562614 -338.891132) (xy 170.547127 -338.943635) (xy 170.524288 -338.993382) (xy 170.494566 -339.03935)
			(xy 170.476926 -339.060282) (xy 170.467702 -339.07162) (xy 170.45552 -339.098173) (xy 170.451343 -339.127088)
			(xy 170.455513 -339.156003) (xy 170.467689 -339.18256) (xy 170.476926 -339.193886) (xy 170.494553 -339.214831)
			(xy 170.524282 -339.260795) (xy 170.547131 -339.310539) (xy 170.562631 -339.36304) (xy 170.570462 -339.417218)
			(xy 170.570464 -339.471958) (xy 170.562636 -339.526137) (xy 170.54714 -339.578638) (xy 170.524294 -339.628384)
			(xy 170.494568 -339.67435) (xy 170.476926 -339.695282) (xy 170.467702 -339.70662) (xy 170.45552 -339.733173)
			(xy 170.451343 -339.762088) (xy 170.455513 -339.791003) (xy 170.467689 -339.81756) (xy 170.476926 -339.828886)
			(xy 170.494553 -339.849831) (xy 170.524282 -339.895795) (xy 170.547131 -339.945539) (xy 170.562631 -339.99804)
			(xy 170.570462 -340.052218) (xy 170.570464 -340.106958) (xy 170.562636 -340.161137) (xy 170.54714 -340.213638)
			(xy 170.524294 -340.263384) (xy 170.494568 -340.30935) (xy 170.476926 -340.330282) (xy 170.467702 -340.34162)
			(xy 170.45552 -340.368173) (xy 170.451343 -340.397088) (xy 170.455513 -340.426003) (xy 170.467689 -340.45256)
			(xy 170.476926 -340.463886) (xy 170.494553 -340.484831) (xy 170.524282 -340.530795) (xy 170.547131 -340.580539)
			(xy 170.562631 -340.63304) (xy 170.570462 -340.687218) (xy 170.570464 -340.741958) (xy 170.562636 -340.796137)
			(xy 170.54714 -340.848638) (xy 170.524294 -340.898384) (xy 170.494568 -340.94435) (xy 170.476926 -340.965282)
			(xy 170.467702 -340.97662) (xy 170.45552 -341.003173) (xy 170.451343 -341.032088) (xy 170.455513 -341.061003)
			(xy 170.467689 -341.08756) (xy 170.476926 -341.098886) (xy 170.494553 -341.119831) (xy 170.524282 -341.165795)
			(xy 170.547131 -341.215539) (xy 170.562631 -341.26804) (xy 170.570462 -341.322218) (xy 170.570464 -341.376958)
			(xy 170.562636 -341.431137) (xy 170.54714 -341.483638) (xy 170.524294 -341.533384) (xy 170.494568 -341.57935)
			(xy 170.476926 -341.600282) (xy 170.467702 -341.61162) (xy 170.45552 -341.638173) (xy 170.451343 -341.667088)
			(xy 170.455513 -341.696003) (xy 170.467689 -341.72256) (xy 170.476926 -341.733886) (xy 170.494553 -341.754831)
			(xy 170.524282 -341.800795) (xy 170.547131 -341.850539) (xy 170.562631 -341.90304) (xy 170.570462 -341.957218)
			(xy 170.570464 -342.011958) (xy 170.562636 -342.066137) (xy 170.54714 -342.118638) (xy 170.524294 -342.168384)
			(xy 170.494568 -342.21435) (xy 170.476926 -342.235282) (xy 170.467702 -342.24662) (xy 170.45552 -342.273173)
			(xy 170.451343 -342.302088) (xy 170.455513 -342.331003) (xy 170.467689 -342.35756) (xy 170.476926 -342.368886)
			(xy 170.494576 -342.389809) (xy 170.524285 -342.435785) (xy 170.547119 -342.485535) (xy 170.562607 -342.538037)
			(xy 170.570433 -342.592214) (xy 170.570906 -342.619584) (xy 173.495462 -342.619584) (xy 173.495904 -342.592213)
			(xy 173.503725 -342.538032) (xy 173.519219 -342.485528) (xy 173.542067 -342.435781) (xy 173.571797 -342.389816)
			(xy 173.589442 -342.368886) (xy 173.598691 -342.357569) (xy 173.610861 -342.331007) (xy 173.615029 -342.302088)
			(xy 173.610854 -342.27317) (xy 173.598678 -342.246611) (xy 173.589442 -342.235282) (xy 173.571785 -342.214362)
			(xy 173.54206 -342.168393) (xy 173.519214 -342.118644) (xy 173.503719 -342.06614) (xy 173.495891 -342.011959)
			(xy 173.495893 -341.957216) (xy 173.503724 -341.903036) (xy 173.519223 -341.850533) (xy 173.542071 -341.800786)
			(xy 173.5718 -341.754818) (xy 173.589442 -341.733886) (xy 173.598691 -341.722569) (xy 173.610861 -341.696007)
			(xy 173.615029 -341.667088) (xy 173.610854 -341.63817) (xy 173.598678 -341.611611) (xy 173.589442 -341.600282)
			(xy 173.571785 -341.579362) (xy 173.54206 -341.533393) (xy 173.519214 -341.483644) (xy 173.503719 -341.43114)
			(xy 173.495891 -341.376959) (xy 173.495893 -341.322216) (xy 173.503724 -341.268036) (xy 173.519223 -341.215533)
			(xy 173.542071 -341.165786) (xy 173.5718 -341.119818) (xy 173.589442 -341.098886) (xy 173.598691 -341.087569)
			(xy 173.610861 -341.061007) (xy 173.615029 -341.032088) (xy 173.610854 -341.00317) (xy 173.598678 -340.976611)
			(xy 173.589442 -340.965282) (xy 173.571785 -340.944362) (xy 173.54206 -340.898393) (xy 173.519214 -340.848644)
			(xy 173.503719 -340.79614) (xy 173.495891 -340.741959) (xy 173.495893 -340.687216) (xy 173.503724 -340.633036)
			(xy 173.519223 -340.580533) (xy 173.542071 -340.530786) (xy 173.5718 -340.484818) (xy 173.589442 -340.463886)
			(xy 173.598691 -340.452569) (xy 173.610861 -340.426007) (xy 173.615029 -340.397088) (xy 173.610854 -340.36817)
			(xy 173.598678 -340.341611) (xy 173.589442 -340.330282) (xy 173.571785 -340.309362) (xy 173.54206 -340.263393)
			(xy 173.519214 -340.213644) (xy 173.503719 -340.16114) (xy 173.495891 -340.106959) (xy 173.495893 -340.052216)
			(xy 173.503724 -339.998036) (xy 173.519223 -339.945533) (xy 173.542071 -339.895786) (xy 173.5718 -339.849818)
			(xy 173.589442 -339.828886) (xy 173.598691 -339.817569) (xy 173.610861 -339.791007) (xy 173.615029 -339.762088)
			(xy 173.610854 -339.73317) (xy 173.598678 -339.706611) (xy 173.589442 -339.695282) (xy 173.571785 -339.674362)
			(xy 173.54206 -339.628393) (xy 173.519214 -339.578644) (xy 173.503719 -339.52614) (xy 173.495891 -339.471959)
			(xy 173.495893 -339.417216) (xy 173.503724 -339.363036) (xy 173.519223 -339.310533) (xy 173.542071 -339.260786)
			(xy 173.5718 -339.214818) (xy 173.589442 -339.193886) (xy 173.598691 -339.182569) (xy 173.610861 -339.156007)
			(xy 173.615029 -339.127088) (xy 173.610854 -339.09817) (xy 173.598678 -339.071611) (xy 173.589442 -339.060282)
			(xy 173.571834 -339.039324) (xy 173.542116 -338.993359) (xy 173.519274 -338.943618) (xy 173.503775 -338.891123)
			(xy 173.49594 -338.836952) (xy 173.495462 -338.809584) (xy 173.495963 -338.782334) (xy 173.503721 -338.728388)
			(xy 173.519076 -338.676095) (xy 173.541717 -338.62652) (xy 173.571182 -338.580671) (xy 173.606872 -338.539482)
			(xy 173.64806 -338.503791) (xy 173.693908 -338.474324) (xy 173.743482 -338.451681) (xy 173.795774 -338.436324)
			(xy 173.84972 -338.428564) (xy 173.87697 -338.428076) (xy 173.90501 -338.428587) (xy 173.960487 -338.436784)
			(xy 174.014169 -338.453006) (xy 174.064901 -338.476904) (xy 174.111593 -338.507964) (xy 174.132748 -338.526374)
			(xy 174.14419 -338.536019) (xy 174.171233 -338.548799) (xy 174.20082 -338.553185) (xy 174.230407 -338.548799)
			(xy 174.25745 -338.536019) (xy 174.268892 -338.526374) (xy 174.290025 -338.507932) (xy 174.336707 -338.476842)
			(xy 174.387443 -338.45293) (xy 174.441136 -338.436715) (xy 174.496626 -338.428547) (xy 174.52467 -338.428076)
			(xy 174.55204 -338.428541) (xy 174.60622 -338.436356) (xy 174.658724 -338.451845) (xy 174.708471 -338.474687)
			(xy 174.754437 -338.504413) (xy 174.775368 -338.522056) (xy 174.786696 -338.531292) (xy 174.813253 -338.543468)
			(xy 174.84217 -338.547641) (xy 174.871087 -338.543468) (xy 174.897644 -338.531292) (xy 174.908972 -338.522056)
			(xy 174.929898 -338.504409) (xy 174.975873 -338.4747) (xy 175.025622 -338.451866) (xy 175.078124 -338.436377)
			(xy 175.132301 -338.428549) (xy 175.15967 -338.428076) (xy 175.186921 -338.428583) (xy 175.24087 -338.436336)
			(xy 175.293166 -338.451687) (xy 175.342745 -338.474325) (xy 175.388597 -338.503788) (xy 175.42979 -338.539477)
			(xy 175.465484 -338.580666) (xy 175.494953 -338.626515) (xy 175.517597 -338.676091) (xy 175.532955 -338.728385)
			(xy 175.540714 -338.782333) (xy 175.541178 -338.809584) (xy 175.540708 -338.836954) (xy 175.532892 -338.891133)
			(xy 175.517404 -338.943637) (xy 175.494563 -338.993383) (xy 175.464839 -339.03935) (xy 175.447198 -339.060282)
			(xy 175.437977 -339.071621) (xy 175.425798 -339.098174) (xy 175.421622 -339.127088) (xy 175.425791 -339.156002)
			(xy 175.437964 -339.182559) (xy 175.447198 -339.193886) (xy 175.464822 -339.214832) (xy 175.494546 -339.260798)
			(xy 175.51739 -339.310542) (xy 175.532887 -339.363042) (xy 175.540716 -339.417218) (xy 175.540718 -339.471958)
			(xy 175.532892 -339.526134) (xy 175.517399 -339.578635) (xy 175.494557 -339.628381) (xy 175.464837 -339.674349)
			(xy 175.447198 -339.695282) (xy 175.437977 -339.706621) (xy 175.425798 -339.733174) (xy 175.421622 -339.762088)
			(xy 175.425791 -339.791002) (xy 175.437964 -339.817559) (xy 175.447198 -339.828886) (xy 175.464822 -339.849832)
			(xy 175.494546 -339.895798) (xy 175.51739 -339.945542) (xy 175.532887 -339.998042) (xy 175.540716 -340.052218)
			(xy 175.540718 -340.106958) (xy 175.532892 -340.161134) (xy 175.517399 -340.213635) (xy 175.494557 -340.263381)
			(xy 175.464837 -340.309349) (xy 175.447198 -340.330282) (xy 175.437977 -340.341621) (xy 175.425798 -340.368174)
			(xy 175.421622 -340.397088) (xy 175.425791 -340.426002) (xy 175.437964 -340.452559) (xy 175.447198 -340.463886)
			(xy 175.464822 -340.484832) (xy 175.494546 -340.530798) (xy 175.51739 -340.580542) (xy 175.532887 -340.633042)
			(xy 175.540716 -340.687218) (xy 175.540718 -340.741958) (xy 175.532892 -340.796134) (xy 175.517399 -340.848635)
			(xy 175.494557 -340.898381) (xy 175.464837 -340.944349) (xy 175.447198 -340.965282) (xy 175.437977 -340.976621)
			(xy 175.425798 -341.003174) (xy 175.421622 -341.032088) (xy 175.425791 -341.061002) (xy 175.437964 -341.087559)
			(xy 175.447198 -341.098886) (xy 175.464822 -341.119832) (xy 175.494546 -341.165798) (xy 175.51739 -341.215542)
			(xy 175.532887 -341.268042) (xy 175.540716 -341.322218) (xy 175.540718 -341.376958) (xy 175.532892 -341.431134)
			(xy 175.517399 -341.483635) (xy 175.494557 -341.533381) (xy 175.464837 -341.579349) (xy 175.447198 -341.600282)
			(xy 175.437977 -341.611621) (xy 175.425798 -341.638174) (xy 175.421622 -341.667088) (xy 175.425791 -341.696002)
			(xy 175.437964 -341.722559) (xy 175.447198 -341.733886) (xy 175.464822 -341.754832) (xy 175.494546 -341.800798)
			(xy 175.51739 -341.850542) (xy 175.532887 -341.903042) (xy 175.540716 -341.957218) (xy 175.540718 -342.011958)
			(xy 175.532892 -342.066134) (xy 175.517399 -342.118635) (xy 175.494557 -342.168381) (xy 175.464837 -342.214349)
			(xy 175.447198 -342.235282) (xy 175.437977 -342.246621) (xy 175.425798 -342.273174) (xy 175.421622 -342.302088)
			(xy 175.425791 -342.331002) (xy 175.437964 -342.357559) (xy 175.447198 -342.368886) (xy 175.464844 -342.389813)
			(xy 175.494555 -342.435787) (xy 175.517389 -342.485536) (xy 175.532879 -342.538038) (xy 175.540705 -342.592214)
			(xy 175.541178 -342.619584) (xy 178.20259 -342.619584) (xy 178.203049 -342.592214) (xy 178.210869 -342.538034)
			(xy 178.22636 -342.485531) (xy 178.249203 -342.435784) (xy 178.278928 -342.389818) (xy 178.29657 -342.368886)
			(xy 178.305825 -342.357571) (xy 178.318004 -342.33101) (xy 178.322175 -342.302088) (xy 178.317997 -342.273167)
			(xy 178.305812 -342.246608) (xy 178.29657 -342.235282) (xy 178.278912 -342.214363) (xy 178.249184 -342.168394)
			(xy 178.226337 -342.118645) (xy 178.21084 -342.066141) (xy 178.203012 -342.01196) (xy 178.203014 -341.957216)
			(xy 178.210846 -341.903035) (xy 178.226346 -341.850532) (xy 178.249196 -341.800785) (xy 178.278926 -341.754818)
			(xy 178.29657 -341.733886) (xy 178.305825 -341.722571) (xy 178.318004 -341.69601) (xy 178.322175 -341.667088)
			(xy 178.317997 -341.638167) (xy 178.305812 -341.611608) (xy 178.29657 -341.600282) (xy 178.278912 -341.579363)
			(xy 178.249184 -341.533394) (xy 178.226337 -341.483645) (xy 178.21084 -341.431141) (xy 178.203012 -341.37696)
			(xy 178.203014 -341.322216) (xy 178.210846 -341.268035) (xy 178.226346 -341.215532) (xy 178.249196 -341.165785)
			(xy 178.278926 -341.119818) (xy 178.29657 -341.098886) (xy 178.305825 -341.087571) (xy 178.318004 -341.06101)
			(xy 178.322175 -341.032088) (xy 178.317997 -341.003167) (xy 178.305812 -340.976608) (xy 178.29657 -340.965282)
			(xy 178.278912 -340.944363) (xy 178.249184 -340.898394) (xy 178.226337 -340.848645) (xy 178.21084 -340.796141)
			(xy 178.203012 -340.74196) (xy 178.203014 -340.687216) (xy 178.210846 -340.633035) (xy 178.226346 -340.580532)
			(xy 178.249196 -340.530785) (xy 178.278926 -340.484818) (xy 178.29657 -340.463886) (xy 178.305825 -340.452571)
			(xy 178.318004 -340.42601) (xy 178.322175 -340.397088) (xy 178.317997 -340.368167) (xy 178.305812 -340.341608)
			(xy 178.29657 -340.330282) (xy 178.278912 -340.309363) (xy 178.249184 -340.263394) (xy 178.226337 -340.213645)
			(xy 178.21084 -340.161141) (xy 178.203012 -340.10696) (xy 178.203014 -340.052216) (xy 178.210846 -339.998035)
			(xy 178.226346 -339.945532) (xy 178.249196 -339.895785) (xy 178.278926 -339.849818) (xy 178.29657 -339.828886)
			(xy 178.305825 -339.817571) (xy 178.318004 -339.79101) (xy 178.322175 -339.762088) (xy 178.317997 -339.733167)
			(xy 178.305812 -339.706608) (xy 178.29657 -339.695282) (xy 178.278912 -339.674363) (xy 178.249184 -339.628394)
			(xy 178.226337 -339.578645) (xy 178.21084 -339.526141) (xy 178.203012 -339.47196) (xy 178.203014 -339.417216)
			(xy 178.210846 -339.363035) (xy 178.226346 -339.310532) (xy 178.249196 -339.260785) (xy 178.278926 -339.214818)
			(xy 178.29657 -339.193886) (xy 178.305825 -339.182571) (xy 178.318004 -339.15601) (xy 178.322175 -339.127088)
			(xy 178.317997 -339.098167) (xy 178.305812 -339.071608) (xy 178.29657 -339.060282) (xy 178.278951 -339.039334)
			(xy 178.249237 -338.993365) (xy 178.226398 -338.943621) (xy 178.210902 -338.891125) (xy 178.203068 -338.836952)
			(xy 178.20259 -338.809584) (xy 178.203063 -338.782332) (xy 178.210822 -338.728384) (xy 178.226179 -338.676089)
			(xy 178.248821 -338.626512) (xy 178.278289 -338.580662) (xy 178.313982 -338.539472) (xy 178.355173 -338.503781)
			(xy 178.401025 -338.474315) (xy 178.450603 -338.451674) (xy 178.502898 -338.436319) (xy 178.556846 -338.428562)
			(xy 178.584098 -338.428076) (xy 178.611469 -338.428525) (xy 178.66565 -338.436344) (xy 178.718154 -338.451836)
			(xy 178.7679 -338.474682) (xy 178.813866 -338.504412) (xy 178.834796 -338.522056) (xy 178.846124 -338.531292)
			(xy 178.872681 -338.543468) (xy 178.901598 -338.547641) (xy 178.930515 -338.543468) (xy 178.957072 -338.531292)
			(xy 178.9684 -338.522056) (xy 178.989315 -338.504396) (xy 179.035293 -338.474689) (xy 179.085045 -338.451858)
			(xy 179.137549 -338.436371) (xy 179.191728 -338.428547) (xy 179.219098 -338.428076) (xy 179.247138 -338.428571)
			(xy 179.302616 -338.436772) (xy 179.356298 -338.452997) (xy 179.40703 -338.476899) (xy 179.453722 -338.507962)
			(xy 179.474876 -338.526374) (xy 179.486318 -338.536019) (xy 179.513361 -338.548799) (xy 179.542948 -338.553185)
			(xy 179.572535 -338.548799) (xy 179.599578 -338.536019) (xy 179.61102 -338.526374) (xy 179.632181 -338.507967)
			(xy 179.678856 -338.476871) (xy 179.729584 -338.452953) (xy 179.783271 -338.43673) (xy 179.838756 -338.428552)
			(xy 179.866798 -338.428076) (xy 179.894048 -338.42858) (xy 179.947995 -338.436335) (xy 180.000288 -338.451689)
			(xy 180.049864 -338.474329) (xy 180.095714 -338.503794) (xy 180.136904 -338.539483) (xy 180.172595 -338.580672)
			(xy 180.202062 -338.62652) (xy 180.224704 -338.676095) (xy 180.240061 -338.728388) (xy 180.247819 -338.782334)
			(xy 180.248306 -338.809584) (xy 180.247829 -338.836954) (xy 180.240014 -338.891132) (xy 180.224527 -338.943635)
			(xy 180.201688 -338.993382) (xy 180.171966 -339.03935) (xy 180.154326 -339.060282) (xy 180.145102 -339.07162)
			(xy 180.13292 -339.098173) (xy 180.128743 -339.127088) (xy 180.132913 -339.156003) (xy 180.145089 -339.18256)
			(xy 180.154326 -339.193886) (xy 180.171953 -339.214831) (xy 180.201682 -339.260795) (xy 180.224531 -339.310539)
			(xy 180.240031 -339.36304) (xy 180.247862 -339.417218) (xy 180.247864 -339.471958) (xy 180.240036 -339.526137)
			(xy 180.22454 -339.578638) (xy 180.201694 -339.628384) (xy 180.171968 -339.67435) (xy 180.154326 -339.695282)
			(xy 180.145102 -339.70662) (xy 180.13292 -339.733173) (xy 180.128743 -339.762088) (xy 180.132913 -339.791003)
			(xy 180.145089 -339.81756) (xy 180.154326 -339.828886) (xy 180.171953 -339.849831) (xy 180.201682 -339.895795)
			(xy 180.224531 -339.945539) (xy 180.240031 -339.99804) (xy 180.247862 -340.052218) (xy 180.247864 -340.106958)
			(xy 180.240036 -340.161137) (xy 180.22454 -340.213638) (xy 180.201694 -340.263384) (xy 180.171968 -340.30935)
			(xy 180.154326 -340.330282) (xy 180.145102 -340.34162) (xy 180.13292 -340.368173) (xy 180.128743 -340.397088)
			(xy 180.132913 -340.426003) (xy 180.145089 -340.45256) (xy 180.154326 -340.463886) (xy 180.171953 -340.484831)
			(xy 180.201682 -340.530795) (xy 180.224531 -340.580539) (xy 180.240031 -340.63304) (xy 180.247862 -340.687218)
			(xy 180.247864 -340.741958) (xy 180.240036 -340.796137) (xy 180.22454 -340.848638) (xy 180.201694 -340.898384)
			(xy 180.171968 -340.94435) (xy 180.154326 -340.965282) (xy 180.145102 -340.97662) (xy 180.13292 -341.003173)
			(xy 180.128743 -341.032088) (xy 180.132913 -341.061003) (xy 180.145089 -341.08756) (xy 180.154326 -341.098886)
			(xy 180.171953 -341.119831) (xy 180.201682 -341.165795) (xy 180.224531 -341.215539) (xy 180.240031 -341.26804)
			(xy 180.247862 -341.322218) (xy 180.247864 -341.376958) (xy 180.240036 -341.431137) (xy 180.22454 -341.483638)
			(xy 180.201694 -341.533384) (xy 180.171968 -341.57935) (xy 180.154326 -341.600282) (xy 180.145102 -341.61162)
			(xy 180.13292 -341.638173) (xy 180.128743 -341.667088) (xy 180.132913 -341.696003) (xy 180.145089 -341.72256)
			(xy 180.154326 -341.733886) (xy 180.171953 -341.754831) (xy 180.201682 -341.800795) (xy 180.224531 -341.850539)
			(xy 180.240031 -341.90304) (xy 180.247862 -341.957218) (xy 180.247864 -342.011958) (xy 180.240036 -342.066137)
			(xy 180.22454 -342.118638) (xy 180.201694 -342.168384) (xy 180.171968 -342.21435) (xy 180.154326 -342.235282)
			(xy 180.145102 -342.24662) (xy 180.13292 -342.273173) (xy 180.128743 -342.302088) (xy 180.132913 -342.331003)
			(xy 180.145089 -342.35756) (xy 180.154326 -342.368886) (xy 180.171976 -342.389809) (xy 180.201685 -342.435785)
			(xy 180.224519 -342.485535) (xy 180.240007 -342.538037) (xy 180.247833 -342.592214) (xy 180.248306 -342.619584)
			(xy 180.24783 -342.646837) (xy 180.240075 -342.700787) (xy 180.224721 -342.753085) (xy 180.20208 -342.802665)
			(xy 180.172614 -342.848518) (xy 180.136921 -342.889711) (xy 180.09573 -342.925405) (xy 180.049877 -342.954873)
			(xy 180.000298 -342.977516) (xy 179.948001 -342.992872) (xy 179.894051 -343.000629) (xy 179.866798 -343.001092)
			(xy 179.838757 -343.000608) (xy 179.783279 -342.992406) (xy 179.729596 -342.976178) (xy 179.678864 -342.952274)
			(xy 179.632173 -342.921208) (xy 179.61102 -342.902794) (xy 179.599578 -342.893149) (xy 179.572535 -342.880369)
			(xy 179.542948 -342.875983) (xy 179.513361 -342.880369) (xy 179.486318 -342.893149) (xy 179.474876 -342.902794)
			(xy 179.453712 -342.921198) (xy 179.407039 -342.952296) (xy 179.356311 -342.976215) (xy 179.302625 -342.992438)
			(xy 179.24714 -343.000616) (xy 179.219098 -343.001092) (xy 179.191728 -343.000629) (xy 179.137548 -342.992811)
			(xy 179.085045 -342.977321) (xy 179.035298 -342.954479) (xy 178.989332 -342.924753) (xy 178.9684 -342.907112)
			(xy 178.957072 -342.897876) (xy 178.930515 -342.8857) (xy 178.901598 -342.881527) (xy 178.872681 -342.8857)
			(xy 178.846124 -342.897876) (xy 178.834796 -342.907112) (xy 178.813878 -342.924768) (xy 178.767901 -342.954477)
			(xy 178.71815 -342.97731) (xy 178.665646 -342.992797) (xy 178.611468 -343.00062) (xy 178.584098 -343.001092)
			(xy 178.556844 -343.000646) (xy 178.502892 -342.992889) (xy 178.450593 -342.977532) (xy 178.401012 -342.954888)
			(xy 178.355158 -342.925418) (xy 178.313965 -342.889723) (xy 178.278271 -342.848528) (xy 178.248804 -342.802673)
			(xy 178.226162 -342.75309) (xy 178.210807 -342.70079) (xy 178.203052 -342.646838) (xy 178.20259 -342.619584)
			(xy 175.541178 -342.619584) (xy 175.54073 -342.646838) (xy 175.532974 -342.700791) (xy 175.517619 -342.753091)
			(xy 175.494976 -342.802673) (xy 175.465507 -342.848528) (xy 175.429811 -342.889721) (xy 175.388616 -342.925415)
			(xy 175.342761 -342.954883) (xy 175.293178 -342.977524) (xy 175.240877 -342.992877) (xy 175.186924 -343.000631)
			(xy 175.15967 -343.001092) (xy 175.132299 -343.000645) (xy 175.078119 -342.992823) (xy 175.025616 -342.97733)
			(xy 174.975869 -342.954484) (xy 174.929903 -342.924755) (xy 174.908972 -342.907112) (xy 174.897644 -342.897876)
			(xy 174.871087 -342.8857) (xy 174.84217 -342.881527) (xy 174.813253 -342.8857) (xy 174.786696 -342.897876)
			(xy 174.775368 -342.907112) (xy 174.754423 -342.924735) (xy 174.708453 -342.954448) (xy 174.658709 -342.977287)
			(xy 174.606211 -342.992782) (xy 174.552038 -343.000615) (xy 174.52467 -343.001092) (xy 174.496629 -343.000624)
			(xy 174.441149 -342.992418) (xy 174.387467 -342.976187) (xy 174.336735 -342.952279) (xy 174.290045 -342.921209)
			(xy 174.268892 -342.902794) (xy 174.25745 -342.893149) (xy 174.230407 -342.880369) (xy 174.20082 -342.875983)
			(xy 174.171233 -342.880369) (xy 174.14419 -342.893149) (xy 174.132748 -342.902794) (xy 174.111595 -342.921212)
			(xy 174.064919 -342.952307) (xy 174.014188 -342.976223) (xy 173.9605 -342.992444) (xy 173.905013 -343.000618)
			(xy 173.87697 -343.001092) (xy 173.849717 -343.00065) (xy 173.795767 -342.992889) (xy 173.743471 -342.977529)
			(xy 173.693892 -342.954883) (xy 173.648041 -342.925413) (xy 173.606851 -342.889717) (xy 173.57116 -342.848522)
			(xy 173.541694 -342.802667) (xy 173.519055 -342.753086) (xy 173.503701 -342.700788) (xy 173.495947 -342.646837)
			(xy 173.495462 -342.619584) (xy 170.570906 -342.619584) (xy 170.57043 -342.646837) (xy 170.562675 -342.700787)
			(xy 170.547321 -342.753085) (xy 170.52468 -342.802665) (xy 170.495214 -342.848518) (xy 170.459521 -342.889711)
			(xy 170.41833 -342.925405) (xy 170.372477 -342.954873) (xy 170.322898 -342.977516) (xy 170.270601 -342.992872)
			(xy 170.216651 -343.000629) (xy 170.189398 -343.001092) (xy 170.161357 -343.000608) (xy 170.105879 -342.992406)
			(xy 170.052196 -342.976178) (xy 170.001464 -342.952274) (xy 169.954773 -342.921208) (xy 169.93362 -342.902794)
			(xy 169.922178 -342.893149) (xy 169.895135 -342.880369) (xy 169.865548 -342.875983) (xy 169.835961 -342.880369)
			(xy 169.808918 -342.893149) (xy 169.797476 -342.902794) (xy 169.776312 -342.921198) (xy 169.729639 -342.952296)
			(xy 169.678911 -342.976215) (xy 169.625225 -342.992438) (xy 169.56974 -343.000616) (xy 169.541698 -343.001092)
			(xy 169.514328 -343.000629) (xy 169.460148 -342.992811) (xy 169.407645 -342.977321) (xy 169.357898 -342.954479)
			(xy 169.311932 -342.924753) (xy 169.291 -342.907112) (xy 169.279672 -342.897876) (xy 169.253115 -342.8857)
			(xy 169.224198 -342.881527) (xy 169.195281 -342.8857) (xy 169.168724 -342.897876) (xy 169.157396 -342.907112)
			(xy 169.136478 -342.924768) (xy 169.090501 -342.954477) (xy 169.04075 -342.97731) (xy 168.988246 -342.992797)
			(xy 168.934068 -343.00062) (xy 168.906698 -343.001092) (xy 168.879444 -343.000646) (xy 168.825492 -342.992889)
			(xy 168.773193 -342.977532) (xy 168.723612 -342.954888) (xy 168.677758 -342.925418) (xy 168.636565 -342.889723)
			(xy 168.600871 -342.848528) (xy 168.571404 -342.802673) (xy 168.548762 -342.75309) (xy 168.533407 -342.70079)
			(xy 168.525652 -342.646838) (xy 168.52519 -342.619584) (xy 76.40701 -342.619584) (xy 76.40701 -344.386662)
			(xy 76.764134 -344.386662) (xy 76.76463 -344.358787) (xy 76.772738 -344.30363) (xy 76.78879 -344.250241)
			(xy 76.812445 -344.199758) (xy 76.843197 -344.153257) (xy 76.861416 -344.132154) (xy 76.870999 -344.120785)
			(xy 76.883633 -344.093879) (xy 76.887962 -344.064472) (xy 76.883617 -344.035068) (xy 76.870968 -344.008169)
			(xy 76.861416 -343.996772) (xy 76.843231 -343.975642) (xy 76.812482 -343.929145) (xy 76.788826 -343.878668)
			(xy 76.772767 -343.825287) (xy 76.764646 -343.770136) (xy 76.764134 -343.742264) (xy 76.76462 -343.715013)
			(xy 76.772376 -343.661065) (xy 76.787731 -343.60877) (xy 76.810373 -343.559193) (xy 76.839839 -343.513343)
			(xy 76.87553 -343.472152) (xy 76.916721 -343.436461) (xy 76.962571 -343.406995) (xy 77.012148 -343.384353)
			(xy 77.064443 -343.368998) (xy 77.118391 -343.361242) (xy 77.172893 -343.361242) (xy 77.226841 -343.368998)
			(xy 77.279136 -343.384353) (xy 77.328713 -343.406995) (xy 77.374563 -343.436461) (xy 77.415754 -343.472152)
			(xy 77.451445 -343.513343) (xy 77.480911 -343.559193) (xy 77.503553 -343.60877) (xy 77.518908 -343.661065)
			(xy 77.526664 -343.715013) (xy 77.52715 -343.742264) (xy 77.526649 -343.770139) (xy 77.518539 -343.825295)
			(xy 77.502486 -343.878683) (xy 77.478834 -343.929165) (xy 77.448085 -343.975667) (xy 77.429868 -343.996772)
			(xy 77.420413 -344.008221) (xy 77.407861 -344.035111) (xy 77.403551 -344.064472) (xy 77.404598 -344.071632)
			(xy 96.449892 -344.071632) (xy 96.449892 -343.986936) (xy 96.457943 -343.902622) (xy 96.473972 -343.819456)
			(xy 96.497833 -343.738189) (xy 96.529312 -343.659559) (xy 96.568123 -343.584278) (xy 96.613913 -343.513026)
			(xy 96.666269 -343.44645) (xy 96.724717 -343.385152) (xy 96.788727 -343.329687) (xy 96.857719 -343.280558)
			(xy 96.931069 -343.238209) (xy 97.008112 -343.203025) (xy 97.088151 -343.175323) (xy 97.17046 -343.155355)
			(xy 97.254295 -343.143302) (xy 97.338896 -343.139272) (xy 97.423497 -343.143302) (xy 97.507332 -343.155355)
			(xy 97.589641 -343.175323) (xy 97.66968 -343.203025) (xy 97.746723 -343.238209) (xy 97.820073 -343.280558)
			(xy 97.889065 -343.329687) (xy 97.953075 -343.385152) (xy 98.011523 -343.44645) (xy 98.063879 -343.513026)
			(xy 98.109669 -343.584278) (xy 98.14848 -343.659559) (xy 98.179959 -343.738189) (xy 98.20382 -343.819456)
			(xy 98.219849 -343.902622) (xy 98.2279 -343.986936) (xy 98.228404 -344.029284) (xy 98.974405 -344.029284)
			(xy 98.978441 -343.945837) (xy 98.990513 -343.863169) (xy 99.010506 -343.782052) (xy 99.038235 -343.703243)
			(xy 99.073441 -343.627478) (xy 99.115795 -343.555465) (xy 99.164901 -343.487876) (xy 99.220302 -343.425342)
			(xy 99.281479 -343.368447) (xy 99.347862 -343.317721) (xy 99.41883 -343.27364) (xy 99.493722 -343.236614)
			(xy 99.571838 -343.206988) (xy 99.652448 -343.18504) (xy 99.7348 -343.170975) (xy 99.818126 -343.164923)
			(xy 99.901646 -343.166942) (xy 99.984582 -343.177012) (xy 100.066158 -343.19504) (xy 100.145614 -343.220857)
			(xy 100.222207 -343.254222) (xy 100.295223 -343.294823) (xy 100.363979 -343.342282) (xy 100.427833 -343.396155)
			(xy 100.48619 -343.45594) (xy 100.538505 -343.521077) (xy 100.584288 -343.59096) (xy 100.623113 -343.664935)
			(xy 100.654618 -343.742312) (xy 100.678507 -343.822369) (xy 100.694558 -343.904357) (xy 100.702621 -343.987512)
			(xy 100.703126 -344.029284) (xy 100.702621 -344.071056) (xy 100.702565 -344.071632) (xy 104.010456 -344.071632)
			(xy 104.010456 -343.986936) (xy 104.018507 -343.902622) (xy 104.034536 -343.819456) (xy 104.058397 -343.738189)
			(xy 104.089876 -343.659559) (xy 104.128687 -343.584278) (xy 104.174477 -343.513026) (xy 104.226833 -343.44645)
			(xy 104.285281 -343.385152) (xy 104.349291 -343.329687) (xy 104.418283 -343.280558) (xy 104.491633 -343.238209)
			(xy 104.568676 -343.203025) (xy 104.648715 -343.175323) (xy 104.731024 -343.155355) (xy 104.814859 -343.143302)
			(xy 104.89946 -343.139272) (xy 104.984061 -343.143302) (xy 105.067896 -343.155355) (xy 105.150205 -343.175323)
			(xy 105.230244 -343.203025) (xy 105.307287 -343.238209) (xy 105.380637 -343.280558) (xy 105.449629 -343.329687)
			(xy 105.513639 -343.385152) (xy 105.572087 -343.44645) (xy 105.624443 -343.513026) (xy 105.670233 -343.584278)
			(xy 105.709044 -343.659559) (xy 105.740523 -343.738189) (xy 105.764384 -343.819456) (xy 105.780413 -343.902622)
			(xy 105.788464 -343.986936) (xy 105.788968 -344.029284) (xy 106.534969 -344.029284) (xy 106.539005 -343.945837)
			(xy 106.551077 -343.863169) (xy 106.57107 -343.782052) (xy 106.598799 -343.703243) (xy 106.634005 -343.627478)
			(xy 106.676359 -343.555465) (xy 106.725465 -343.487876) (xy 106.780866 -343.425342) (xy 106.842043 -343.368447)
			(xy 106.908426 -343.317721) (xy 106.979394 -343.27364) (xy 107.054286 -343.236614) (xy 107.132402 -343.206988)
			(xy 107.213012 -343.18504) (xy 107.295364 -343.170975) (xy 107.37869 -343.164923) (xy 107.46221 -343.166942)
			(xy 107.545146 -343.177012) (xy 107.626722 -343.19504) (xy 107.706178 -343.220857) (xy 107.782771 -343.254222)
			(xy 107.855787 -343.294823) (xy 107.924543 -343.342282) (xy 107.988397 -343.396155) (xy 108.046754 -343.45594)
			(xy 108.099069 -343.521077) (xy 108.144852 -343.59096) (xy 108.183677 -343.664935) (xy 108.215182 -343.742312)
			(xy 108.239071 -343.822369) (xy 108.255122 -343.904357) (xy 108.263185 -343.987512) (xy 108.26369 -344.029284)
			(xy 108.263185 -344.071056) (xy 108.263129 -344.071632) (xy 111.7158 -344.071632) (xy 111.7158 -343.986936)
			(xy 111.723851 -343.902622) (xy 111.73988 -343.819456) (xy 111.763741 -343.738189) (xy 111.79522 -343.659559)
			(xy 111.834031 -343.584278) (xy 111.879821 -343.513026) (xy 111.932177 -343.44645) (xy 111.990625 -343.385152)
			(xy 112.054635 -343.329687) (xy 112.123627 -343.280558) (xy 112.196977 -343.238209) (xy 112.27402 -343.203025)
			(xy 112.354059 -343.175323) (xy 112.436368 -343.155355) (xy 112.520203 -343.143302) (xy 112.604804 -343.139272)
			(xy 112.689405 -343.143302) (xy 112.77324 -343.155355) (xy 112.855549 -343.175323) (xy 112.935588 -343.203025)
			(xy 113.012631 -343.238209) (xy 113.085981 -343.280558) (xy 113.154973 -343.329687) (xy 113.218983 -343.385152)
			(xy 113.277431 -343.44645) (xy 113.329787 -343.513026) (xy 113.375577 -343.584278) (xy 113.414388 -343.659559)
			(xy 113.445867 -343.738189) (xy 113.469728 -343.819456) (xy 113.485757 -343.902622) (xy 113.493808 -343.986936)
			(xy 113.494312 -344.029284) (xy 114.240313 -344.029284) (xy 114.244349 -343.945837) (xy 114.256421 -343.863169)
			(xy 114.276414 -343.782052) (xy 114.304143 -343.703243) (xy 114.339349 -343.627478) (xy 114.381703 -343.555465)
			(xy 114.430809 -343.487876) (xy 114.48621 -343.425342) (xy 114.547387 -343.368447) (xy 114.61377 -343.317721)
			(xy 114.684738 -343.27364) (xy 114.75963 -343.236614) (xy 114.837746 -343.206988) (xy 114.918356 -343.18504)
			(xy 115.000708 -343.170975) (xy 115.084034 -343.164923) (xy 115.167554 -343.166942) (xy 115.25049 -343.177012)
			(xy 115.332066 -343.19504) (xy 115.411522 -343.220857) (xy 115.488115 -343.254222) (xy 115.561131 -343.294823)
			(xy 115.629887 -343.342282) (xy 115.693741 -343.396155) (xy 115.752098 -343.45594) (xy 115.804413 -343.521077)
			(xy 115.850196 -343.59096) (xy 115.889021 -343.664935) (xy 115.920526 -343.742312) (xy 115.944415 -343.822369)
			(xy 115.960466 -343.904357) (xy 115.964765 -343.948696) (xy 119.176796 -343.948696) (xy 119.176796 -343.864)
			(xy 119.184847 -343.779686) (xy 119.200876 -343.69652) (xy 119.224737 -343.615253) (xy 119.256216 -343.536623)
			(xy 119.295027 -343.461342) (xy 119.340817 -343.39009) (xy 119.393173 -343.323514) (xy 119.451621 -343.262216)
			(xy 119.515631 -343.206751) (xy 119.584623 -343.157622) (xy 119.657973 -343.115273) (xy 119.735016 -343.080089)
			(xy 119.815055 -343.052387) (xy 119.897364 -343.032419) (xy 119.981199 -343.020366) (xy 120.0658 -343.016336)
			(xy 120.150401 -343.020366) (xy 120.234236 -343.032419) (xy 120.316545 -343.052387) (xy 120.396584 -343.080089)
			(xy 120.473627 -343.115273) (xy 120.546977 -343.157622) (xy 120.615969 -343.206751) (xy 120.679979 -343.262216)
			(xy 120.738427 -343.323514) (xy 120.790783 -343.39009) (xy 120.836573 -343.461342) (xy 120.875384 -343.536623)
			(xy 120.906863 -343.615253) (xy 120.930724 -343.69652) (xy 120.946753 -343.779686) (xy 120.954804 -343.864)
			(xy 120.955308 -343.906348) (xy 121.701309 -343.906348) (xy 121.705345 -343.822901) (xy 121.717417 -343.740233)
			(xy 121.73741 -343.659116) (xy 121.765139 -343.580307) (xy 121.800345 -343.504542) (xy 121.842699 -343.432529)
			(xy 121.891805 -343.36494) (xy 121.947206 -343.302406) (xy 122.008383 -343.245511) (xy 122.074766 -343.194785)
			(xy 122.145734 -343.150704) (xy 122.220626 -343.113678) (xy 122.298742 -343.084052) (xy 122.379352 -343.062104)
			(xy 122.461704 -343.048039) (xy 122.54503 -343.041987) (xy 122.62855 -343.044006) (xy 122.711486 -343.054076)
			(xy 122.793062 -343.072104) (xy 122.872518 -343.097921) (xy 122.949111 -343.131286) (xy 123.022127 -343.171887)
			(xy 123.090883 -343.219346) (xy 123.154737 -343.273219) (xy 123.213094 -343.333004) (xy 123.265409 -343.398141)
			(xy 123.311192 -343.468024) (xy 123.350017 -343.541999) (xy 123.381522 -343.619376) (xy 123.405411 -343.699433)
			(xy 123.421462 -343.781421) (xy 123.429525 -343.864576) (xy 123.43003 -343.906348) (xy 123.429525 -343.94812)
			(xy 123.421462 -344.031275) (xy 123.405411 -344.113263) (xy 123.381522 -344.19332) (xy 123.350017 -344.270697)
			(xy 123.311192 -344.344672) (xy 123.28984 -344.377264) (xy 133.84403 -344.377264) (xy 133.844468 -344.349893)
			(xy 133.852291 -344.295712) (xy 133.867787 -344.243208) (xy 133.890635 -344.193462) (xy 133.920366 -344.147497)
			(xy 133.93801 -344.126566) (xy 133.947281 -344.115264) (xy 133.959453 -344.088697) (xy 133.963618 -344.059773)
			(xy 133.959437 -344.030851) (xy 133.947251 -344.00429) (xy 133.93801 -343.992962) (xy 133.920388 -343.972016)
			(xy 133.890673 -343.926047) (xy 133.867834 -343.876303) (xy 133.852339 -343.823806) (xy 133.844506 -343.769632)
			(xy 133.84403 -343.742264) (xy 133.844516 -343.715013) (xy 133.852272 -343.661065) (xy 133.867627 -343.60877)
			(xy 133.890269 -343.559193) (xy 133.919735 -343.513343) (xy 133.955426 -343.472152) (xy 133.996617 -343.436461)
			(xy 134.042467 -343.406995) (xy 134.092044 -343.384353) (xy 134.144339 -343.368998) (xy 134.198287 -343.361242)
			(xy 134.252789 -343.361242) (xy 134.306737 -343.368998) (xy 134.359032 -343.384353) (xy 134.408609 -343.406995)
			(xy 134.454459 -343.436461) (xy 134.485224 -343.463118) (xy 143.511522 -343.463118) (xy 143.515593 -343.407496)
			(xy 143.527719 -343.353059) (xy 143.547642 -343.300968) (xy 143.574938 -343.252333) (xy 143.609024 -343.20819)
			(xy 143.649173 -343.169481) (xy 143.694531 -343.13703) (xy 143.744131 -343.111529) (xy 143.796915 -343.093522)
			(xy 143.851758 -343.083392) (xy 143.907492 -343.081355) (xy 143.962929 -343.087455) (xy 144.016886 -343.101561)
			(xy 144.068215 -343.123373) (xy 144.115821 -343.152427) (xy 144.158689 -343.188102) (xy 144.195906 -343.229639)
			(xy 144.226679 -343.276152) (xy 144.250351 -343.326649) (xy 144.266419 -343.380056) (xy 144.274539 -343.435232)
			(xy 144.275048 -343.463118) (xy 144.274539 -343.491004) (xy 144.26855 -343.531698) (xy 144.792952 -343.531698)
			(xy 144.797023 -343.476076) (xy 144.809149 -343.421639) (xy 144.829072 -343.369548) (xy 144.856368 -343.320913)
			(xy 144.890454 -343.27677) (xy 144.930603 -343.238061) (xy 144.975961 -343.20561) (xy 145.025561 -343.180109)
			(xy 145.078345 -343.162102) (xy 145.133188 -343.151972) (xy 145.188922 -343.149935) (xy 145.244359 -343.156035)
			(xy 145.298316 -343.170141) (xy 145.349645 -343.191953) (xy 145.397251 -343.221007) (xy 145.440119 -343.256682)
			(xy 145.477336 -343.298219) (xy 145.508109 -343.344732) (xy 145.531781 -343.395229) (xy 145.547849 -343.448636)
			(xy 145.555969 -343.503812) (xy 145.556478 -343.531698) (xy 145.555969 -343.559584) (xy 145.547849 -343.61476)
			(xy 145.531781 -343.668167) (xy 145.508109 -343.718664) (xy 145.477336 -343.765177) (xy 145.440119 -343.806714)
			(xy 145.397251 -343.842389) (xy 145.349645 -343.871443) (xy 145.298316 -343.893255) (xy 145.244359 -343.907361)
			(xy 145.188922 -343.913461) (xy 145.133188 -343.911424) (xy 145.078345 -343.901294) (xy 145.025561 -343.883287)
			(xy 144.975961 -343.857786) (xy 144.930603 -343.825335) (xy 144.890454 -343.786626) (xy 144.856368 -343.742483)
			(xy 144.829072 -343.693848) (xy 144.809149 -343.641757) (xy 144.797023 -343.58732) (xy 144.792952 -343.531698)
			(xy 144.26855 -343.531698) (xy 144.266419 -343.54618) (xy 144.250351 -343.599587) (xy 144.226679 -343.650084)
			(xy 144.195906 -343.696597) (xy 144.158689 -343.738134) (xy 144.115821 -343.773809) (xy 144.068215 -343.802863)
			(xy 144.016886 -343.824675) (xy 143.962929 -343.838781) (xy 143.907492 -343.844881) (xy 143.851758 -343.842844)
			(xy 143.796915 -343.832714) (xy 143.744131 -343.814707) (xy 143.694531 -343.789206) (xy 143.649173 -343.756755)
			(xy 143.609024 -343.718046) (xy 143.574938 -343.673903) (xy 143.547642 -343.625268) (xy 143.527719 -343.573177)
			(xy 143.515593 -343.51874) (xy 143.511522 -343.463118) (xy 134.485224 -343.463118) (xy 134.49565 -343.472152)
			(xy 134.531341 -343.513343) (xy 134.560807 -343.559193) (xy 134.583449 -343.60877) (xy 134.598804 -343.661065)
			(xy 134.60656 -343.715013) (xy 134.607046 -343.742264) (xy 134.606572 -343.769634) (xy 134.598758 -343.823813)
			(xy 134.583272 -343.876317) (xy 134.560431 -343.926064) (xy 134.530707 -343.972031) (xy 134.513066 -343.992962)
			(xy 134.503867 -344.004316) (xy 134.491689 -344.030865) (xy 134.487511 -344.059773) (xy 134.491674 -344.088683)
			(xy 134.503837 -344.115238) (xy 134.513066 -344.126566) (xy 134.530697 -344.147504) (xy 134.560411 -344.193475)
			(xy 134.583249 -344.243221) (xy 134.598742 -344.29572) (xy 134.606572 -344.349895) (xy 134.607046 -344.377264)
			(xy 134.60656 -344.404515) (xy 134.598804 -344.458463) (xy 134.583449 -344.510758) (xy 134.560807 -344.560335)
			(xy 134.531341 -344.606185) (xy 134.49565 -344.647376) (xy 134.454459 -344.683067) (xy 134.408609 -344.712533)
			(xy 134.359032 -344.735175) (xy 134.306737 -344.75053) (xy 134.252789 -344.758286) (xy 134.198287 -344.758286)
			(xy 134.144339 -344.75053) (xy 134.092044 -344.735175) (xy 134.042467 -344.712533) (xy 133.996617 -344.683067)
			(xy 133.955426 -344.647376) (xy 133.919735 -344.606185) (xy 133.890269 -344.560335) (xy 133.867627 -344.510758)
			(xy 133.852272 -344.458463) (xy 133.844516 -344.404515) (xy 133.84403 -344.377264) (xy 123.28984 -344.377264)
			(xy 123.265409 -344.414555) (xy 123.213094 -344.479692) (xy 123.154737 -344.539477) (xy 123.090883 -344.59335)
			(xy 123.022127 -344.640809) (xy 122.949111 -344.68141) (xy 122.872518 -344.714775) (xy 122.793062 -344.740592)
			(xy 122.711486 -344.75862) (xy 122.62855 -344.76869) (xy 122.54503 -344.770709) (xy 122.461704 -344.764657)
			(xy 122.379352 -344.750592) (xy 122.298742 -344.728644) (xy 122.220626 -344.699018) (xy 122.145734 -344.661992)
			(xy 122.074766 -344.617911) (xy 122.008383 -344.567185) (xy 121.947206 -344.51029) (xy 121.891805 -344.447756)
			(xy 121.842699 -344.380167) (xy 121.800345 -344.308154) (xy 121.765139 -344.232389) (xy 121.73741 -344.15358)
			(xy 121.717417 -344.072463) (xy 121.705345 -343.989795) (xy 121.701309 -343.906348) (xy 120.955308 -343.906348)
			(xy 120.954804 -343.948696) (xy 120.946753 -344.03301) (xy 120.930724 -344.116176) (xy 120.906863 -344.197443)
			(xy 120.875384 -344.276073) (xy 120.836573 -344.351354) (xy 120.790783 -344.422606) (xy 120.738427 -344.489182)
			(xy 120.679979 -344.55048) (xy 120.615969 -344.605945) (xy 120.546977 -344.655074) (xy 120.473627 -344.697423)
			(xy 120.396584 -344.732607) (xy 120.316545 -344.760309) (xy 120.23579 -344.7799) (xy 138.092587 -344.7799)
			(xy 138.096756 -344.724274) (xy 138.109169 -344.669891) (xy 138.129549 -344.617966) (xy 138.15744 -344.569658)
			(xy 138.19222 -344.526046) (xy 138.233112 -344.488106) (xy 138.279202 -344.456684) (xy 138.32946 -344.432482)
			(xy 138.382764 -344.416042) (xy 138.437923 -344.40773) (xy 138.465814 -344.407236) (xy 138.493148 -344.407663)
			(xy 138.547229 -344.41564) (xy 138.599565 -344.431436) (xy 138.649029 -344.454711) (xy 138.694561 -344.484966)
			(xy 138.735182 -344.52155) (xy 138.77002 -344.563679) (xy 138.784584 -344.586814) (xy 138.792541 -344.599014)
			(xy 138.814004 -344.618683) (xy 138.840148 -344.63149) (xy 138.868845 -344.636392) (xy 138.897758 -344.63299)
			(xy 138.91133 -344.627708) (xy 138.934539 -344.618217) (xy 138.982873 -344.604867) (xy 139.032562 -344.598139)
			(xy 139.057634 -344.597736) (xy 139.082703 -344.59816) (xy 139.132386 -344.604909) (xy 139.180721 -344.618242)
			(xy 139.203938 -344.627708) (xy 139.217525 -344.632926) (xy 139.246421 -344.636297) (xy 139.275096 -344.631393)
			(xy 139.301229 -344.618611) (xy 139.322703 -344.598986) (xy 139.330684 -344.586814) (xy 139.345253 -344.563683)
			(xy 139.380096 -344.521562) (xy 139.420719 -344.484983) (xy 139.46625 -344.454732) (xy 139.515712 -344.431456)
			(xy 139.568043 -344.415656) (xy 139.622122 -344.40767) (xy 139.676786 -344.40767) (xy 139.730865 -344.415656)
			(xy 139.783196 -344.431456) (xy 139.832658 -344.454732) (xy 139.878189 -344.484983) (xy 139.918812 -344.521562)
			(xy 139.953655 -344.563683) (xy 139.968224 -344.586814) (xy 139.976143 -344.599041) (xy 139.997616 -344.61871)
			(xy 140.023771 -344.631514) (xy 140.052476 -344.636408) (xy 140.081396 -344.632996) (xy 140.09497 -344.627708)
			(xy 140.118187 -344.618236) (xy 140.166516 -344.604878) (xy 140.216203 -344.598143) (xy 140.241274 -344.597736)
			(xy 140.268118 -344.598183) (xy 140.32125 -344.605885) (xy 140.372727 -344.621134) (xy 140.421482 -344.643612)
			(xy 140.466505 -344.672856) (xy 140.506866 -344.70826) (xy 140.541726 -344.74909) (xy 140.570366 -344.7945)
			(xy 140.592192 -344.843551) (xy 140.599922 -344.869262) (xy 140.604566 -344.883766) (xy 140.621088 -344.909332)
			(xy 140.644408 -344.928897) (xy 140.672456 -344.940726) (xy 140.702743 -344.943768) (xy 140.732583 -344.937755)
			(xy 140.746226 -344.930984) (xy 140.774377 -344.916361) (xy 140.834326 -344.89563) (xy 140.896882 -344.885128)
			(xy 140.928598 -344.884502) (xy 140.946617 -344.884727) (xy 140.982492 -344.888158) (xy 141.000226 -344.89136)
			(xy 141.015432 -344.893723) (xy 141.045988 -344.890188) (xy 141.074107 -344.877721) (xy 141.097243 -344.85745)
			(xy 141.113299 -344.831213) (xy 141.117574 -344.81643) (xy 141.124994 -344.789393) (xy 141.146623 -344.737669)
			(xy 141.175586 -344.689666) (xy 141.21126 -344.646416) (xy 141.252876 -344.608849) (xy 141.29954 -344.577774)
			(xy 141.350247 -344.55386) (xy 141.403907 -344.53762) (xy 141.459366 -344.529404) (xy 141.487398 -344.528902)
			(xy 141.514651 -344.529357) (xy 141.568603 -344.537114) (xy 141.620902 -344.55247) (xy 141.670482 -344.575113)
			(xy 141.716336 -344.604582) (xy 141.757529 -344.640277) (xy 141.793223 -344.68147) (xy 141.82269 -344.727325)
			(xy 141.845332 -344.776906) (xy 141.860688 -344.829205) (xy 141.868443 -344.883157) (xy 141.868906 -344.91041)
			(xy 141.868376 -344.937982) (xy 141.860437 -344.992552) (xy 141.844724 -345.045411) (xy 141.821566 -345.095457)
			(xy 141.791445 -345.141648) (xy 141.754988 -345.183022) (xy 141.734286 -345.20124) (xy 141.72338 -345.211129)
			(xy 141.707311 -345.235783) (xy 141.69893 -345.263992) (xy 141.698932 -345.293421) (xy 141.707317 -345.321629)
			(xy 141.723389 -345.34628) (xy 141.734286 -345.35618) (xy 141.755002 -345.374385) (xy 141.791467 -345.415757)
			(xy 141.821594 -345.461948) (xy 141.844757 -345.511997) (xy 141.860472 -345.564859) (xy 141.868412 -345.619432)
			(xy 141.868411 -345.674581) (xy 141.860469 -345.729154) (xy 141.844752 -345.782016) (xy 141.843402 -345.784932)
			(xy 144.561812 -345.784932) (xy 144.565883 -345.72931) (xy 144.578009 -345.674873) (xy 144.597932 -345.622782)
			(xy 144.625228 -345.574147) (xy 144.659314 -345.530004) (xy 144.699463 -345.491295) (xy 144.744821 -345.458844)
			(xy 144.794421 -345.433343) (xy 144.847205 -345.415336) (xy 144.902048 -345.405206) (xy 144.957782 -345.403169)
			(xy 145.013219 -345.409269) (xy 145.067176 -345.423375) (xy 145.118505 -345.445187) (xy 145.166111 -345.474241)
			(xy 145.208979 -345.509916) (xy 145.246196 -345.551453) (xy 145.276969 -345.597966) (xy 145.300641 -345.648463)
			(xy 145.316709 -345.70187) (xy 145.324829 -345.757046) (xy 145.325338 -345.784932) (xy 145.324829 -345.812818)
			(xy 145.316709 -345.867994) (xy 145.300641 -345.921401) (xy 145.276969 -345.971898) (xy 145.246196 -346.018411)
			(xy 145.208979 -346.059948) (xy 145.166111 -346.095623) (xy 145.118505 -346.124677) (xy 145.067176 -346.146489)
			(xy 145.013219 -346.160595) (xy 144.957782 -346.166695) (xy 144.902048 -346.164658) (xy 144.847205 -346.154528)
			(xy 144.794421 -346.136521) (xy 144.744821 -346.11102) (xy 144.699463 -346.078569) (xy 144.659314 -346.03986)
			(xy 144.625228 -345.995717) (xy 144.597932 -345.947082) (xy 144.578009 -345.894991) (xy 144.565883 -345.840554)
			(xy 144.561812 -345.784932) (xy 141.843402 -345.784932) (xy 141.821588 -345.832063) (xy 141.791459 -345.878254)
			(xy 141.754993 -345.919625) (xy 141.734286 -345.93784) (xy 141.72338 -345.947729) (xy 141.707311 -345.972383)
			(xy 141.69893 -346.000592) (xy 141.698932 -346.030021) (xy 141.707317 -346.058229) (xy 141.723389 -346.08288)
			(xy 141.734286 -346.09278) (xy 141.754988 -346.111001) (xy 141.791459 -346.152368) (xy 141.821593 -346.198555)
			(xy 141.844761 -346.248601) (xy 141.860479 -346.301462) (xy 141.86842 -346.356036) (xy 141.868906 -346.38361)
			(xy 141.868432 -346.410862) (xy 141.860674 -346.46481) (xy 141.845317 -346.517105) (xy 141.822675 -346.566682)
			(xy 141.793207 -346.612533) (xy 141.757514 -346.653723) (xy 141.716323 -346.689414) (xy 141.670472 -346.71888)
			(xy 141.620894 -346.741521) (xy 141.568598 -346.756876) (xy 141.51465 -346.764632) (xy 141.487398 -346.765118)
			(xy 141.459543 -346.764584) (xy 141.404429 -346.75646) (xy 141.35108 -346.740415) (xy 141.300628 -346.716789)
			(xy 141.254143 -346.686084) (xy 141.212614 -346.64895) (xy 141.17692 -346.606177) (xy 141.14782 -346.558672)
			(xy 141.125931 -346.507442) (xy 141.118336 -346.480638) (xy 141.114074 -346.466517) (xy 141.098685 -346.441368)
			(xy 141.076764 -346.42165) (xy 141.050131 -346.409) (xy 141.020997 -346.404469) (xy 141.006322 -346.405962)
			(xy 140.993305 -346.407627) (xy 140.967121 -346.40941) (xy 140.953998 -346.409518) (xy 140.939849 -346.409424)
			(xy 140.911626 -346.40739) (xy 140.89761 -346.405454) (xy 140.884268 -346.403791) (xy 140.857565 -346.406899)
			(xy 140.832604 -346.416882) (xy 140.811121 -346.433043) (xy 140.794611 -346.454258) (xy 140.784222 -346.479052)
			(xy 140.78204 -346.492322) (xy 140.777912 -346.519469) (xy 140.762943 -346.572297) (xy 140.740556 -346.622434)
			(xy 140.711213 -346.668844) (xy 140.67552 -346.710569) (xy 140.634215 -346.746746) (xy 140.588151 -346.776628)
			(xy 140.538278 -346.799598) (xy 140.485628 -346.815183) (xy 140.431288 -346.823058) (xy 140.403834 -346.823538)
			(xy 140.376583 -346.823013) (xy 140.322636 -346.815262) (xy 140.270341 -346.799911) (xy 140.220763 -346.777275)
			(xy 140.174911 -346.747813) (xy 140.133719 -346.712126) (xy 140.098025 -346.67094) (xy 140.068556 -346.625093)
			(xy 140.045911 -346.575519) (xy 140.030552 -346.523226) (xy 140.022791 -346.469281) (xy 140.022326 -346.44203)
			(xy 140.022803 -346.414456) (xy 140.030752 -346.359883) (xy 140.046474 -346.307023) (xy 140.069642 -346.256977)
			(xy 140.099773 -346.210787) (xy 140.136239 -346.169416) (xy 140.156946 -346.1512) (xy 140.167817 -346.141273)
			(xy 140.183899 -346.116633) (xy 140.192291 -346.088431) (xy 140.192296 -346.059007) (xy 140.183915 -346.030802)
			(xy 140.167843 -346.006156) (xy 140.156946 -345.99626) (xy 140.13627 -345.978011) (xy 140.099795 -345.936651)
			(xy 140.069657 -345.89047) (xy 140.046485 -345.840429) (xy 140.030762 -345.787573) (xy 140.022815 -345.733003)
			(xy 140.022326 -345.70543) (xy 140.022752 -345.678928) (xy 140.030103 -345.626435) (xy 140.044654 -345.575467)
			(xy 140.066123 -345.527005) (xy 140.094098 -345.481984) (xy 140.110718 -345.461336) (xy 140.120186 -345.449208)
			(xy 140.131978 -345.420802) (xy 140.1348 -345.390175) (xy 140.128399 -345.360092) (xy 140.113351 -345.333268)
			(xy 140.091015 -345.312124) (xy 140.077444 -345.304872) (xy 140.05375 -345.292778) (xy 140.009769 -345.262853)
			(xy 139.970489 -345.22698) (xy 139.936707 -345.185888) (xy 139.922504 -345.163394) (xy 139.914556 -345.151187)
			(xy 139.893091 -345.131517) (xy 139.866945 -345.11871) (xy 139.838245 -345.11381) (xy 139.809331 -345.117216)
			(xy 139.795758 -345.1225) (xy 139.77255 -345.131995) (xy 139.724216 -345.145344) (xy 139.674526 -345.15207)
			(xy 139.649454 -345.152472) (xy 139.624385 -345.152051) (xy 139.574701 -345.1453) (xy 139.526367 -345.131967)
			(xy 139.50315 -345.1225) (xy 139.489568 -345.117266) (xy 139.46067 -345.113897) (xy 139.431992 -345.118804)
			(xy 139.405858 -345.13159) (xy 139.384384 -345.15122) (xy 139.376404 -345.163394) (xy 139.361835 -345.186525)
			(xy 139.326992 -345.228646) (xy 139.286369 -345.265225) (xy 139.240838 -345.295476) (xy 139.191376 -345.318752)
			(xy 139.139045 -345.334552) (xy 139.084966 -345.342538) (xy 139.030302 -345.342538) (xy 138.976223 -345.334552)
			(xy 138.923892 -345.318752) (xy 138.87443 -345.295476) (xy 138.828899 -345.265225) (xy 138.788276 -345.228646)
			(xy 138.753433 -345.186525) (xy 138.738864 -345.163394) (xy 138.730954 -345.15116) (xy 138.709479 -345.13149)
			(xy 138.683322 -345.118687) (xy 138.654614 -345.113794) (xy 138.625692 -345.11721) (xy 138.612118 -345.1225)
			(xy 138.588903 -345.131976) (xy 138.540573 -345.145332) (xy 138.490885 -345.152066) (xy 138.465814 -345.152472)
			(xy 138.437923 -345.15207) (xy 138.382764 -345.143758) (xy 138.32946 -345.127318) (xy 138.279202 -345.103116)
			(xy 138.233112 -345.071694) (xy 138.19222 -345.033754) (xy 138.15744 -344.990143) (xy 138.129549 -344.941834)
			(xy 138.109169 -344.889909) (xy 138.096756 -344.835526) (xy 138.092587 -344.7799) (xy 120.23579 -344.7799)
			(xy 120.234236 -344.780277) (xy 120.150401 -344.79233) (xy 120.0658 -344.796361) (xy 119.981199 -344.79233)
			(xy 119.897364 -344.780277) (xy 119.815055 -344.760309) (xy 119.735016 -344.732607) (xy 119.657973 -344.697423)
			(xy 119.584623 -344.655074) (xy 119.515631 -344.605945) (xy 119.451621 -344.55048) (xy 119.393173 -344.489182)
			(xy 119.340817 -344.422606) (xy 119.295027 -344.351354) (xy 119.256216 -344.276073) (xy 119.224737 -344.197443)
			(xy 119.200876 -344.116176) (xy 119.184847 -344.03301) (xy 119.176796 -343.948696) (xy 115.964765 -343.948696)
			(xy 115.968529 -343.987512) (xy 115.969034 -344.029284) (xy 115.968529 -344.071056) (xy 115.960466 -344.154211)
			(xy 115.944415 -344.236199) (xy 115.920526 -344.316256) (xy 115.889021 -344.393633) (xy 115.850196 -344.467608)
			(xy 115.804413 -344.537491) (xy 115.752098 -344.602628) (xy 115.693741 -344.662413) (xy 115.629887 -344.716286)
			(xy 115.561131 -344.763745) (xy 115.488115 -344.804346) (xy 115.411522 -344.837711) (xy 115.332066 -344.863528)
			(xy 115.25049 -344.881556) (xy 115.167554 -344.891626) (xy 115.084034 -344.893645) (xy 115.000708 -344.887593)
			(xy 114.918356 -344.873528) (xy 114.837746 -344.85158) (xy 114.75963 -344.821954) (xy 114.684738 -344.784928)
			(xy 114.61377 -344.740847) (xy 114.547387 -344.690121) (xy 114.48621 -344.633226) (xy 114.430809 -344.570692)
			(xy 114.381703 -344.503103) (xy 114.339349 -344.43109) (xy 114.304143 -344.355325) (xy 114.276414 -344.276516)
			(xy 114.256421 -344.195399) (xy 114.244349 -344.112731) (xy 114.240313 -344.029284) (xy 113.494312 -344.029284)
			(xy 113.493808 -344.071632) (xy 113.485757 -344.155946) (xy 113.469728 -344.239112) (xy 113.445867 -344.320379)
			(xy 113.414388 -344.399009) (xy 113.375577 -344.47429) (xy 113.329787 -344.545542) (xy 113.277431 -344.612118)
			(xy 113.218983 -344.673416) (xy 113.154973 -344.728881) (xy 113.085981 -344.77801) (xy 113.012631 -344.820359)
			(xy 112.935588 -344.855543) (xy 112.855549 -344.883245) (xy 112.77324 -344.903213) (xy 112.689405 -344.915266)
			(xy 112.604804 -344.919297) (xy 112.520203 -344.915266) (xy 112.436368 -344.903213) (xy 112.354059 -344.883245)
			(xy 112.27402 -344.855543) (xy 112.196977 -344.820359) (xy 112.123627 -344.77801) (xy 112.054635 -344.728881)
			(xy 111.990625 -344.673416) (xy 111.932177 -344.612118) (xy 111.879821 -344.545542) (xy 111.834031 -344.47429)
			(xy 111.79522 -344.399009) (xy 111.763741 -344.320379) (xy 111.73988 -344.239112) (xy 111.723851 -344.155946)
			(xy 111.7158 -344.071632) (xy 108.263129 -344.071632) (xy 108.255122 -344.154211) (xy 108.239071 -344.236199)
			(xy 108.215182 -344.316256) (xy 108.183677 -344.393633) (xy 108.144852 -344.467608) (xy 108.099069 -344.537491)
			(xy 108.046754 -344.602628) (xy 107.988397 -344.662413) (xy 107.924543 -344.716286) (xy 107.855787 -344.763745)
			(xy 107.782771 -344.804346) (xy 107.706178 -344.837711) (xy 107.626722 -344.863528) (xy 107.545146 -344.881556)
			(xy 107.46221 -344.891626) (xy 107.37869 -344.893645) (xy 107.295364 -344.887593) (xy 107.213012 -344.873528)
			(xy 107.132402 -344.85158) (xy 107.054286 -344.821954) (xy 106.979394 -344.784928) (xy 106.908426 -344.740847)
			(xy 106.842043 -344.690121) (xy 106.780866 -344.633226) (xy 106.725465 -344.570692) (xy 106.676359 -344.503103)
			(xy 106.634005 -344.43109) (xy 106.598799 -344.355325) (xy 106.57107 -344.276516) (xy 106.551077 -344.195399)
			(xy 106.539005 -344.112731) (xy 106.534969 -344.029284) (xy 105.788968 -344.029284) (xy 105.788464 -344.071632)
			(xy 105.780413 -344.155946) (xy 105.764384 -344.239112) (xy 105.740523 -344.320379) (xy 105.709044 -344.399009)
			(xy 105.670233 -344.47429) (xy 105.624443 -344.545542) (xy 105.572087 -344.612118) (xy 105.513639 -344.673416)
			(xy 105.449629 -344.728881) (xy 105.380637 -344.77801) (xy 105.307287 -344.820359) (xy 105.230244 -344.855543)
			(xy 105.150205 -344.883245) (xy 105.067896 -344.903213) (xy 104.984061 -344.915266) (xy 104.89946 -344.919297)
			(xy 104.814859 -344.915266) (xy 104.731024 -344.903213) (xy 104.648715 -344.883245) (xy 104.568676 -344.855543)
			(xy 104.491633 -344.820359) (xy 104.418283 -344.77801) (xy 104.349291 -344.728881) (xy 104.285281 -344.673416)
			(xy 104.226833 -344.612118) (xy 104.174477 -344.545542) (xy 104.128687 -344.47429) (xy 104.089876 -344.399009)
			(xy 104.058397 -344.320379) (xy 104.034536 -344.239112) (xy 104.018507 -344.155946) (xy 104.010456 -344.071632)
			(xy 100.702565 -344.071632) (xy 100.694558 -344.154211) (xy 100.678507 -344.236199) (xy 100.654618 -344.316256)
			(xy 100.623113 -344.393633) (xy 100.584288 -344.467608) (xy 100.538505 -344.537491) (xy 100.48619 -344.602628)
			(xy 100.427833 -344.662413) (xy 100.363979 -344.716286) (xy 100.295223 -344.763745) (xy 100.222207 -344.804346)
			(xy 100.145614 -344.837711) (xy 100.066158 -344.863528) (xy 99.984582 -344.881556) (xy 99.901646 -344.891626)
			(xy 99.818126 -344.893645) (xy 99.7348 -344.887593) (xy 99.652448 -344.873528) (xy 99.571838 -344.85158)
			(xy 99.493722 -344.821954) (xy 99.41883 -344.784928) (xy 99.347862 -344.740847) (xy 99.281479 -344.690121)
			(xy 99.220302 -344.633226) (xy 99.164901 -344.570692) (xy 99.115795 -344.503103) (xy 99.073441 -344.43109)
			(xy 99.038235 -344.355325) (xy 99.010506 -344.276516) (xy 98.990513 -344.195399) (xy 98.978441 -344.112731)
			(xy 98.974405 -344.029284) (xy 98.228404 -344.029284) (xy 98.2279 -344.071632) (xy 98.219849 -344.155946)
			(xy 98.20382 -344.239112) (xy 98.179959 -344.320379) (xy 98.14848 -344.399009) (xy 98.109669 -344.47429)
			(xy 98.063879 -344.545542) (xy 98.011523 -344.612118) (xy 97.953075 -344.673416) (xy 97.889065 -344.728881)
			(xy 97.820073 -344.77801) (xy 97.746723 -344.820359) (xy 97.66968 -344.855543) (xy 97.589641 -344.883245)
			(xy 97.507332 -344.903213) (xy 97.423497 -344.915266) (xy 97.338896 -344.919297) (xy 97.254295 -344.915266)
			(xy 97.17046 -344.903213) (xy 97.088151 -344.883245) (xy 97.008112 -344.855543) (xy 96.931069 -344.820359)
			(xy 96.857719 -344.77801) (xy 96.788727 -344.728881) (xy 96.724717 -344.673416) (xy 96.666269 -344.612118)
			(xy 96.613913 -344.545542) (xy 96.568123 -344.47429) (xy 96.529312 -344.399009) (xy 96.497833 -344.320379)
			(xy 96.473972 -344.239112) (xy 96.457943 -344.155946) (xy 96.449892 -344.071632) (xy 77.404598 -344.071632)
			(xy 77.407845 -344.093836) (xy 77.420383 -344.120733) (xy 77.429868 -344.132154) (xy 77.448078 -344.153263)
			(xy 77.478821 -344.199767) (xy 77.50247 -344.250249) (xy 77.518524 -344.303635) (xy 77.52664 -344.358788)
			(xy 77.52715 -344.386662) (xy 77.526664 -344.413913) (xy 77.518908 -344.467861) (xy 77.503553 -344.520156)
			(xy 77.480911 -344.569733) (xy 77.451445 -344.615583) (xy 77.415754 -344.656774) (xy 77.374563 -344.692465)
			(xy 77.328713 -344.721931) (xy 77.279136 -344.744573) (xy 77.226841 -344.759928) (xy 77.172893 -344.767684)
			(xy 77.118391 -344.767684) (xy 77.064443 -344.759928) (xy 77.012148 -344.744573) (xy 76.962571 -344.721931)
			(xy 76.916721 -344.692465) (xy 76.87553 -344.656774) (xy 76.839839 -344.615583) (xy 76.810373 -344.569733)
			(xy 76.787731 -344.520156) (xy 76.772376 -344.467861) (xy 76.76462 -344.413913) (xy 76.764134 -344.386662)
			(xy 76.40701 -344.386662) (xy 76.40701 -344.7799) (xy 80.968987 -344.7799) (xy 80.973156 -344.724273)
			(xy 80.98557 -344.669888) (xy 81.005951 -344.617961) (xy 81.033844 -344.569652) (xy 81.068626 -344.526041)
			(xy 81.109519 -344.4881) (xy 81.155611 -344.456678) (xy 81.205871 -344.432478) (xy 81.259178 -344.416039)
			(xy 81.314338 -344.407729) (xy 81.34223 -344.407236) (xy 81.369561 -344.407729) (xy 81.42364 -344.415694)
			(xy 81.475974 -344.431479) (xy 81.525438 -344.454743) (xy 81.570971 -344.484988) (xy 81.611594 -344.521563)
			(xy 81.646434 -344.563683) (xy 81.661 -344.586814) (xy 81.668942 -344.599025) (xy 81.690409 -344.618694)
			(xy 81.716557 -344.631499) (xy 81.745257 -344.636399) (xy 81.774173 -344.632992) (xy 81.787746 -344.627708)
			(xy 81.810954 -344.618212) (xy 81.859288 -344.604863) (xy 81.908978 -344.598138) (xy 81.93405 -344.597736)
			(xy 81.95912 -344.598155) (xy 82.008803 -344.604906) (xy 82.057137 -344.618241) (xy 82.080354 -344.627708)
			(xy 82.093935 -344.632943) (xy 82.122834 -344.63631) (xy 82.151511 -344.631403) (xy 82.177645 -344.618617)
			(xy 82.199119 -344.598987) (xy 82.2071 -344.586814) (xy 82.221669 -344.563683) (xy 82.256512 -344.521562)
			(xy 82.297135 -344.484983) (xy 82.342666 -344.454732) (xy 82.392128 -344.431456) (xy 82.444459 -344.415656)
			(xy 82.498538 -344.40767) (xy 82.553202 -344.40767) (xy 82.607281 -344.415656) (xy 82.659612 -344.431456)
			(xy 82.709074 -344.454732) (xy 82.754605 -344.484983) (xy 82.795228 -344.521562) (xy 82.830071 -344.563683)
			(xy 82.84464 -344.586814) (xy 82.852544 -344.599052) (xy 82.874021 -344.618721) (xy 82.90018 -344.631523)
			(xy 82.928889 -344.636415) (xy 82.957811 -344.632998) (xy 82.971386 -344.627708) (xy 82.994601 -344.618231)
			(xy 83.042931 -344.604875) (xy 83.092619 -344.598142) (xy 83.11769 -344.597736) (xy 83.144534 -344.598169)
			(xy 83.197667 -344.605873) (xy 83.249144 -344.621124) (xy 83.297899 -344.643605) (xy 83.342923 -344.67285)
			(xy 83.383283 -344.708255) (xy 83.418143 -344.749087) (xy 83.446783 -344.794498) (xy 83.468608 -344.843551)
			(xy 83.476338 -344.869262) (xy 83.480962 -344.883774) (xy 83.497487 -344.909342) (xy 83.520811 -344.928908)
			(xy 83.548863 -344.940736) (xy 83.579155 -344.943775) (xy 83.608998 -344.937758) (xy 83.622642 -344.930984)
			(xy 83.65079 -344.916355) (xy 83.71074 -344.895627) (xy 83.773298 -344.885126) (xy 83.805014 -344.884502)
			(xy 83.828133 -344.884836) (xy 83.874034 -344.890404) (xy 83.918922 -344.901491) (xy 83.94065 -344.909394)
			(xy 83.954434 -344.914181) (xy 83.983516 -344.916438) (xy 84.012051 -344.910385) (xy 84.037712 -344.896514)
			(xy 84.058407 -344.875956) (xy 84.072448 -344.850388) (xy 84.076032 -344.836242) (xy 84.082655 -344.808282)
			(xy 84.103249 -344.754639) (xy 84.131655 -344.704692) (xy 84.167231 -344.65957) (xy 84.209172 -344.620294)
			(xy 84.25653 -344.587753) (xy 84.308232 -344.562682) (xy 84.363109 -344.545649) (xy 84.41992 -344.537039)
			(xy 84.44865 -344.536522) (xy 84.475903 -344.537002) (xy 84.529855 -344.544753) (xy 84.582154 -344.560104)
			(xy 84.631736 -344.582743) (xy 84.677591 -344.612208) (xy 84.718785 -344.647901) (xy 84.75448 -344.689093)
			(xy 84.783947 -344.734946) (xy 84.806589 -344.784527) (xy 84.821943 -344.836826) (xy 84.829697 -344.890777)
			(xy 84.830158 -344.91803) (xy 84.82972 -344.945401) (xy 84.821897 -344.999582) (xy 84.806402 -345.052086)
			(xy 84.783554 -345.101832) (xy 84.753822 -345.147798) (xy 84.736178 -345.168728) (xy 84.726914 -345.180034)
			(xy 84.714743 -345.2066) (xy 84.710577 -345.235523) (xy 84.714756 -345.264444) (xy 84.726939 -345.291004)
			(xy 84.736178 -345.302332) (xy 84.753795 -345.323282) (xy 84.783511 -345.369249) (xy 84.806352 -345.418992)
			(xy 84.821848 -345.471489) (xy 84.829681 -345.525662) (xy 84.830158 -345.55303) (xy 84.829659 -345.580604)
			(xy 84.821715 -345.635176) (xy 84.805998 -345.688035) (xy 84.782834 -345.738082) (xy 84.752707 -345.784272)
			(xy 84.716243 -345.825644) (xy 84.695538 -345.84386) (xy 84.684608 -345.853726) (xy 84.668531 -345.878384)
			(xy 84.660147 -345.906601) (xy 84.660153 -345.936037) (xy 84.668547 -345.964251) (xy 84.684633 -345.988903)
			(xy 84.695538 -345.9988) (xy 84.71626 -346.016999) (xy 84.752728 -346.058371) (xy 84.782858 -346.104564)
			(xy 84.806021 -346.154614) (xy 84.821736 -346.207479) (xy 84.829674 -346.262055) (xy 84.830158 -346.28963)
			(xy 84.829773 -346.316886) (xy 84.822011 -346.370842) (xy 84.806648 -346.423145) (xy 84.783998 -346.472728)
			(xy 84.754523 -346.518584) (xy 84.718821 -346.559777) (xy 84.67762 -346.595471) (xy 84.631758 -346.624937)
			(xy 84.58217 -346.647576) (xy 84.529864 -346.662928) (xy 84.475906 -346.670679) (xy 84.44865 -346.671138)
			(xy 84.420776 -346.670626) (xy 84.365624 -346.662506) (xy 84.31224 -346.646446) (xy 84.261761 -346.622788)
			(xy 84.215263 -346.592036) (xy 84.173735 -346.554845) (xy 84.138062 -346.512006) (xy 84.109002 -346.464432)
			(xy 84.097622 -346.438982) (xy 84.090901 -346.424856) (xy 84.070496 -346.40117) (xy 84.043891 -346.384752)
			(xy 84.013571 -346.377136) (xy 83.982366 -346.379032) (xy 83.967574 -346.384118) (xy 83.945612 -346.392165)
			(xy 83.900228 -346.403485) (xy 83.853801 -346.409176) (xy 83.830414 -346.409518) (xy 83.816265 -346.409423)
			(xy 83.788042 -346.407389) (xy 83.774026 -346.405454) (xy 83.760682 -346.403807) (xy 83.733981 -346.406912)
			(xy 83.709021 -346.41689) (xy 83.687538 -346.433048) (xy 83.671028 -346.454261) (xy 83.660638 -346.479053)
			(xy 83.658456 -346.492322) (xy 83.654312 -346.519466) (xy 83.639344 -346.572293) (xy 83.616959 -346.622429)
			(xy 83.587617 -346.668838) (xy 83.551926 -346.710563) (xy 83.510623 -346.74674) (xy 83.464561 -346.776623)
			(xy 83.41469 -346.799594) (xy 83.362042 -346.81518) (xy 83.307703 -346.823057) (xy 83.28025 -346.823538)
			(xy 83.253 -346.822998) (xy 83.199053 -346.815249) (xy 83.146759 -346.799901) (xy 83.097181 -346.777266)
			(xy 83.051329 -346.747806) (xy 83.010136 -346.71212) (xy 82.974442 -346.670935) (xy 82.944972 -346.62509)
			(xy 82.922327 -346.575517) (xy 82.906968 -346.523225) (xy 82.899207 -346.46928) (xy 82.898742 -346.44203)
			(xy 82.899214 -346.414456) (xy 82.907163 -346.359882) (xy 82.922886 -346.307022) (xy 82.946055 -346.256976)
			(xy 82.976187 -346.210786) (xy 83.012655 -346.169415) (xy 83.033362 -346.1512) (xy 83.044232 -346.141273)
			(xy 83.060311 -346.116632) (xy 83.068702 -346.088431) (xy 83.068707 -346.059008) (xy 83.060328 -346.030803)
			(xy 83.044258 -346.006157) (xy 83.033362 -345.99626) (xy 83.012669 -345.978029) (xy 82.976199 -345.936664)
			(xy 82.946066 -345.890478) (xy 82.922897 -345.840434) (xy 82.907176 -345.787575) (xy 82.899231 -345.733003)
			(xy 82.898742 -345.70543) (xy 82.899165 -345.678928) (xy 82.906516 -345.626435) (xy 82.921067 -345.575466)
			(xy 82.942537 -345.527005) (xy 82.970513 -345.481984) (xy 82.987134 -345.461336) (xy 82.996597 -345.449205)
			(xy 83.008386 -345.420799) (xy 83.011207 -345.390174) (xy 83.004807 -345.360093) (xy 82.989762 -345.33327)
			(xy 82.96743 -345.312125) (xy 82.95386 -345.304872) (xy 82.930169 -345.292774) (xy 82.886187 -345.26285)
			(xy 82.846906 -345.226979) (xy 82.813123 -345.185887) (xy 82.79892 -345.163394) (xy 82.790957 -345.151198)
			(xy 82.769496 -345.131528) (xy 82.743354 -345.11872) (xy 82.714658 -345.113817) (xy 82.685746 -345.117219)
			(xy 82.672174 -345.1225) (xy 82.648964 -345.13199) (xy 82.600631 -345.145341) (xy 82.550942 -345.152069)
			(xy 82.52587 -345.152472) (xy 82.500801 -345.152046) (xy 82.451118 -345.145297) (xy 82.402783 -345.131966)
			(xy 82.379566 -345.1225) (xy 82.365978 -345.117283) (xy 82.337083 -345.11391) (xy 82.308408 -345.118814)
			(xy 82.282275 -345.131596) (xy 82.2608 -345.151222) (xy 82.25282 -345.163394) (xy 82.238251 -345.186525)
			(xy 82.203408 -345.228646) (xy 82.162785 -345.265225) (xy 82.117254 -345.295476) (xy 82.067792 -345.318752)
			(xy 82.015461 -345.334552) (xy 81.961382 -345.342538) (xy 81.906718 -345.342538) (xy 81.852639 -345.334552)
			(xy 81.800308 -345.318752) (xy 81.750846 -345.295476) (xy 81.705315 -345.265225) (xy 81.664692 -345.228646)
			(xy 81.629849 -345.186525) (xy 81.61528 -345.163394) (xy 81.607355 -345.151171) (xy 81.585884 -345.131501)
			(xy 81.559731 -345.118696) (xy 81.531026 -345.113801) (xy 81.502108 -345.117212) (xy 81.488534 -345.1225)
			(xy 81.465317 -345.131971) (xy 81.416988 -345.145329) (xy 81.367301 -345.152065) (xy 81.34223 -345.152472)
			(xy 81.314338 -345.152071) (xy 81.259178 -345.143761) (xy 81.205871 -345.127322) (xy 81.155611 -345.103122)
			(xy 81.109519 -345.0717) (xy 81.068626 -345.033759) (xy 81.033844 -344.990148) (xy 81.005951 -344.941839)
			(xy 80.98557 -344.889912) (xy 80.973156 -344.835527) (xy 80.968987 -344.7799) (xy 76.40701 -344.7799)
			(xy 76.40701 -345.845638) (xy 77.5114 -345.845638) (xy 77.515471 -345.790016) (xy 77.527597 -345.735579)
			(xy 77.54752 -345.683488) (xy 77.574816 -345.634853) (xy 77.608902 -345.59071) (xy 77.649051 -345.552001)
			(xy 77.694409 -345.51955) (xy 77.744009 -345.494049) (xy 77.796793 -345.476042) (xy 77.851636 -345.465912)
			(xy 77.90737 -345.463875) (xy 77.962807 -345.469975) (xy 78.016764 -345.484081) (xy 78.068093 -345.505893)
			(xy 78.115699 -345.534947) (xy 78.158567 -345.570622) (xy 78.195784 -345.612159) (xy 78.226557 -345.658672)
			(xy 78.250229 -345.709169) (xy 78.266297 -345.762576) (xy 78.274417 -345.817752) (xy 78.274926 -345.845638)
			(xy 78.274417 -345.873524) (xy 78.266297 -345.9287) (xy 78.250229 -345.982107) (xy 78.226557 -346.032604)
			(xy 78.195784 -346.079117) (xy 78.158567 -346.120654) (xy 78.115699 -346.156329) (xy 78.068093 -346.185383)
			(xy 78.016764 -346.207195) (xy 77.962807 -346.221301) (xy 77.90737 -346.227401) (xy 77.851636 -346.225364)
			(xy 77.796793 -346.215234) (xy 77.744009 -346.197227) (xy 77.694409 -346.171726) (xy 77.649051 -346.139275)
			(xy 77.608902 -346.100566) (xy 77.574816 -346.056423) (xy 77.54752 -346.007788) (xy 77.527597 -345.955697)
			(xy 77.515471 -345.90126) (xy 77.5114 -345.845638) (xy 76.40701 -345.845638) (xy 76.40701 -346.825062)
			(xy 76.846936 -346.825062) (xy 76.851007 -346.76944) (xy 76.863133 -346.715003) (xy 76.883056 -346.662912)
			(xy 76.910352 -346.614277) (xy 76.944438 -346.570134) (xy 76.984587 -346.531425) (xy 77.029945 -346.498974)
			(xy 77.079545 -346.473473) (xy 77.132329 -346.455466) (xy 77.187172 -346.445336) (xy 77.242906 -346.443299)
			(xy 77.298343 -346.449399) (xy 77.3523 -346.463505) (xy 77.403629 -346.485317) (xy 77.451235 -346.514371)
			(xy 77.494103 -346.550046) (xy 77.53132 -346.591583) (xy 77.562093 -346.638096) (xy 77.585765 -346.688593)
			(xy 77.601833 -346.742) (xy 77.609953 -346.797176) (xy 77.610462 -346.825062) (xy 77.609953 -346.852948)
			(xy 77.601833 -346.908124) (xy 77.585765 -346.961531) (xy 77.562093 -347.012028) (xy 77.53132 -347.058541)
			(xy 77.494103 -347.100078) (xy 77.451235 -347.135753) (xy 77.403629 -347.164807) (xy 77.3523 -347.186619)
			(xy 77.298343 -347.200725) (xy 77.242906 -347.206825) (xy 77.187172 -347.204788) (xy 77.132329 -347.194658)
			(xy 77.079545 -347.176651) (xy 77.029945 -347.15115) (xy 76.984587 -347.118699) (xy 76.944438 -347.07999)
			(xy 76.910352 -347.035847) (xy 76.883056 -346.987212) (xy 76.863133 -346.935121) (xy 76.851007 -346.880684)
			(xy 76.846936 -346.825062) (xy 76.40701 -346.825062) (xy 76.40701 -347.439234) (xy 78.318106 -347.439234)
			(xy 78.318683 -347.409547) (xy 78.327877 -347.350889) (xy 78.346048 -347.294363) (xy 78.372757 -347.241335)
			(xy 78.407359 -347.193086) (xy 78.449019 -347.15078) (xy 78.472538 -347.132656) (xy 78.483121 -347.124203)
			(xy 78.499823 -347.102895) (xy 78.510339 -347.077947) (xy 78.513931 -347.051113) (xy 78.510346 -347.024278)
			(xy 78.499836 -346.999328) (xy 78.48314 -346.978016) (xy 78.472538 -346.969588) (xy 78.44903 -346.951449)
			(xy 78.407367 -346.909147) (xy 78.372762 -346.860901) (xy 78.346048 -346.807876) (xy 78.327872 -346.751353)
			(xy 78.318672 -346.692697) (xy 78.318106 -346.66301) (xy 78.318592 -346.635759) (xy 78.326348 -346.581811)
			(xy 78.341703 -346.529516) (xy 78.364345 -346.479939) (xy 78.393811 -346.434089) (xy 78.429502 -346.392898)
			(xy 78.470693 -346.357207) (xy 78.516543 -346.327741) (xy 78.56612 -346.305099) (xy 78.618415 -346.289744)
			(xy 78.672363 -346.281988) (xy 78.726865 -346.281988) (xy 78.780813 -346.289744) (xy 78.833108 -346.305099)
			(xy 78.882685 -346.327741) (xy 78.928535 -346.357207) (xy 78.969726 -346.392898) (xy 79.005417 -346.434089)
			(xy 79.034883 -346.479939) (xy 79.057525 -346.529516) (xy 79.07288 -346.581811) (xy 79.080636 -346.635759)
			(xy 79.081122 -346.66301) (xy 79.080565 -346.692698) (xy 79.071366 -346.751356) (xy 79.05319 -346.807882)
			(xy 79.026477 -346.860909) (xy 79.014394 -346.877756) (xy 79.334517 -346.877756) (xy 79.334517 -346.823244)
			(xy 79.342275 -346.769286) (xy 79.357633 -346.716982) (xy 79.380279 -346.667396) (xy 79.409751 -346.621537)
			(xy 79.44545 -346.58034) (xy 79.486649 -346.544643) (xy 79.532508 -346.515172) (xy 79.582095 -346.492528)
			(xy 79.6344 -346.477172) (xy 79.688358 -346.469416) (xy 79.715614 -346.468954) (xy 79.740849 -346.469351)
			(xy 79.790883 -346.47597) (xy 79.839603 -346.489143) (xy 79.886155 -346.50864) (xy 79.908146 -346.521024)
			(xy 79.92109 -346.528106) (xy 79.949736 -346.535138) (xy 79.979196 -346.533688) (xy 80.007013 -346.523877)
			(xy 80.030865 -346.506525) (xy 80.048761 -346.483078) (xy 80.05445 -346.469462) (xy 80.065151 -346.442688)
			(xy 80.09344 -346.392448) (xy 80.12897 -346.34704) (xy 80.170931 -346.307498) (xy 80.218368 -346.274725)
			(xy 80.270197 -346.249466) (xy 80.325239 -346.232299) (xy 80.382238 -346.223613) (xy 80.411066 -346.223082)
			(xy 80.438318 -346.223587) (xy 80.492266 -346.231339) (xy 80.544563 -346.24669) (xy 80.594142 -346.269328)
			(xy 80.639995 -346.298792) (xy 80.681188 -346.334481) (xy 80.716882 -346.37567) (xy 80.746351 -346.421519)
			(xy 80.768994 -346.471096) (xy 80.784352 -346.52339) (xy 80.79211 -346.577338) (xy 80.792574 -346.60459)
			(xy 80.792049 -346.634495) (xy 80.782729 -346.693574) (xy 80.774032 -346.722192) (xy 80.769931 -346.736084)
			(xy 80.769028 -346.765028) (xy 80.776304 -346.793057) (xy 80.791169 -346.817907) (xy 80.812425 -346.837573)
			(xy 80.838354 -346.850466) (xy 80.852518 -346.85351) (xy 80.878588 -346.858694) (xy 80.929091 -346.875263)
			(xy 80.976803 -346.898685) (xy 81.020801 -346.928505) (xy 81.060232 -346.964146) (xy 81.094332 -347.004918)
			(xy 81.122439 -347.050029) (xy 81.144009 -347.098607) (xy 81.158625 -347.149709) (xy 81.166003 -347.202346)
			(xy 81.166462 -347.228922) (xy 81.165976 -347.256173) (xy 81.15822 -347.310121) (xy 81.142865 -347.362416)
			(xy 81.120223 -347.411993) (xy 81.090757 -347.457843) (xy 81.055066 -347.499034) (xy 81.013875 -347.534725)
			(xy 80.968025 -347.564191) (xy 80.918448 -347.586833) (xy 80.866153 -347.602188) (xy 80.812205 -347.609944)
			(xy 80.757703 -347.609944) (xy 80.703755 -347.602188) (xy 80.65146 -347.586833) (xy 80.601883 -347.564191)
			(xy 80.556033 -347.534725) (xy 80.514842 -347.499034) (xy 80.479151 -347.457843) (xy 80.449685 -347.411993)
			(xy 80.427043 -347.362416) (xy 80.411688 -347.310121) (xy 80.403932 -347.256173) (xy 80.403446 -347.228922)
			(xy 80.403977 -347.199017) (xy 80.413293 -347.139938) (xy 80.421988 -347.11132) (xy 80.426059 -347.097421)
			(xy 80.426964 -347.068483) (xy 80.419693 -347.040458) (xy 80.404833 -347.01561) (xy 80.383585 -346.995944)
			(xy 80.357663 -346.983049) (xy 80.343502 -346.980002) (xy 80.310662 -346.97342) (xy 80.24781 -346.950297)
			(xy 80.218534 -346.934028) (xy 80.205591 -346.926948) (xy 80.176946 -346.919925) (xy 80.147488 -346.921379)
			(xy 80.119674 -346.931189) (xy 80.095823 -346.948537) (xy 80.077923 -346.971977) (xy 80.07223 -346.98559)
			(xy 80.06152 -347.012361) (xy 80.033235 -347.062603) (xy 79.997708 -347.108013) (xy 79.955748 -347.147557)
			(xy 79.908313 -347.180331) (xy 79.856483 -347.20559) (xy 79.801441 -347.222757) (xy 79.744442 -347.23144)
			(xy 79.715614 -347.23197) (xy 79.688358 -347.231584) (xy 79.6344 -347.223828) (xy 79.582095 -347.208472)
			(xy 79.532508 -347.185828) (xy 79.486649 -347.156357) (xy 79.44545 -347.12066) (xy 79.409751 -347.079463)
			(xy 79.380279 -347.033604) (xy 79.357633 -346.984018) (xy 79.342275 -346.931714) (xy 79.334517 -346.877756)
			(xy 79.014394 -346.877756) (xy 78.991872 -346.909158) (xy 78.95021 -346.951464) (xy 78.92669 -346.969588)
			(xy 78.916061 -346.977989) (xy 78.899354 -346.999307) (xy 78.888838 -347.024267) (xy 78.885251 -347.051113)
			(xy 78.888845 -347.077958) (xy 78.899368 -347.102916) (xy 78.91608 -347.12423) (xy 78.92669 -347.132656)
			(xy 78.950225 -347.150762) (xy 78.991885 -347.193071) (xy 79.026487 -347.241324) (xy 79.053195 -347.294356)
			(xy 79.071366 -347.350884) (xy 79.08056 -347.409545) (xy 79.081122 -347.439234) (xy 79.080636 -347.466485)
			(xy 79.07288 -347.520433) (xy 79.057525 -347.572728) (xy 79.034883 -347.622305) (xy 79.005417 -347.668155)
			(xy 78.969726 -347.709346) (xy 78.928535 -347.745037) (xy 78.882685 -347.774503) (xy 78.833108 -347.797145)
			(xy 78.780813 -347.8125) (xy 78.726865 -347.820256) (xy 78.672363 -347.820256) (xy 78.618415 -347.8125)
			(xy 78.56612 -347.797145) (xy 78.516543 -347.774503) (xy 78.470693 -347.745037) (xy 78.429502 -347.709346)
			(xy 78.393811 -347.668155) (xy 78.364345 -347.622305) (xy 78.341703 -347.572728) (xy 78.326348 -347.520433)
			(xy 78.318592 -347.466485) (xy 78.318106 -347.439234) (xy 76.40701 -347.439234) (xy 76.40701 -350.505014)
			(xy 76.530962 -350.505014) (xy 76.531383 -350.478634) (xy 76.538647 -350.426376) (xy 76.553037 -350.375617)
			(xy 76.57428 -350.327322) (xy 76.601971 -350.282413) (xy 76.635582 -350.241745) (xy 76.674473 -350.206093)
			(xy 76.717903 -350.176136) (xy 76.741274 -350.163892) (xy 76.75362 -350.157169) (xy 76.774345 -350.138196)
			(xy 76.789105 -350.114286) (xy 76.796777 -350.087256) (xy 76.796779 -350.059157) (xy 76.78911 -350.032125)
			(xy 76.774353 -350.008213) (xy 76.75363 -349.989238) (xy 76.741274 -349.982536) (xy 76.717904 -349.970295)
			(xy 76.67448 -349.940332) (xy 76.635596 -349.904676) (xy 76.60199 -349.864006) (xy 76.574303 -349.819098)
			(xy 76.553063 -349.770805) (xy 76.538673 -349.720048) (xy 76.531408 -349.667793) (xy 76.530962 -349.641414)
			(xy 76.531491 -349.614164) (xy 76.539245 -349.56022) (xy 76.554597 -349.507928) (xy 76.577234 -349.458353)
			(xy 76.606696 -349.412504) (xy 76.642383 -349.371314) (xy 76.683569 -349.335623) (xy 76.729414 -349.306155)
			(xy 76.778987 -349.283512) (xy 76.831277 -349.268154) (xy 76.885221 -349.260394) (xy 76.91247 -349.259906)
			(xy 76.94015 -349.260455) (xy 76.994927 -349.268466) (xy 77.047971 -349.284308) (xy 77.098169 -349.307651)
			(xy 77.144466 -349.338002) (xy 77.185891 -349.374727) (xy 77.221574 -349.417052) (xy 77.250765 -349.464089)
			(xy 77.272852 -349.514852) (xy 77.287371 -349.568274) (xy 77.291184 -349.595694) (xy 77.296518 -349.640652)
			(xy 83.233514 -349.640652) (xy 87.012526 -345.86164) (xy 87.030623 -345.844385) (xy 87.072167 -345.816573)
			(xy 87.118338 -345.797399) (xy 87.167362 -345.7876) (xy 87.192358 -345.786964) (xy 97.289366 -345.786964)
			(xy 97.314362 -345.787609) (xy 97.363385 -345.797408) (xy 97.409556 -345.816579) (xy 97.451102 -345.844385)
			(xy 97.452416 -345.845638) (xy 134.634984 -345.845638) (xy 134.639055 -345.790016) (xy 134.651181 -345.735579)
			(xy 134.671104 -345.683488) (xy 134.6984 -345.634853) (xy 134.732486 -345.59071) (xy 134.772635 -345.552001)
			(xy 134.817993 -345.51955) (xy 134.867593 -345.494049) (xy 134.920377 -345.476042) (xy 134.97522 -345.465912)
			(xy 135.030954 -345.463875) (xy 135.086391 -345.469975) (xy 135.140348 -345.484081) (xy 135.191677 -345.505893)
			(xy 135.239283 -345.534947) (xy 135.282151 -345.570622) (xy 135.319368 -345.612159) (xy 135.350141 -345.658672)
			(xy 135.373813 -345.709169) (xy 135.389881 -345.762576) (xy 135.398001 -345.817752) (xy 135.39851 -345.845638)
			(xy 135.398001 -345.873524) (xy 135.389881 -345.9287) (xy 135.373813 -345.982107) (xy 135.350141 -346.032604)
			(xy 135.319368 -346.079117) (xy 135.282151 -346.120654) (xy 135.239283 -346.156329) (xy 135.191677 -346.185383)
			(xy 135.140348 -346.207195) (xy 135.086391 -346.221301) (xy 135.030954 -346.227401) (xy 134.97522 -346.225364)
			(xy 134.920377 -346.215234) (xy 134.867593 -346.197227) (xy 134.817993 -346.171726) (xy 134.772635 -346.139275)
			(xy 134.732486 -346.100566) (xy 134.6984 -346.056423) (xy 134.671104 -346.007788) (xy 134.651181 -345.955697)
			(xy 134.639055 -345.90126) (xy 134.634984 -345.845638) (xy 97.452416 -345.845638) (xy 97.469198 -345.86164)
			(xy 98.117504 -346.509848) (xy 133.965948 -346.509848) (xy 133.970019 -346.454226) (xy 133.982145 -346.399789)
			(xy 134.002068 -346.347698) (xy 134.029364 -346.299063) (xy 134.06345 -346.25492) (xy 134.103599 -346.216211)
			(xy 134.148957 -346.18376) (xy 134.198557 -346.158259) (xy 134.251341 -346.140252) (xy 134.306184 -346.130122)
			(xy 134.361918 -346.128085) (xy 134.417355 -346.134185) (xy 134.471312 -346.148291) (xy 134.522641 -346.170103)
			(xy 134.570247 -346.199157) (xy 134.613115 -346.234832) (xy 134.650332 -346.276369) (xy 134.681105 -346.322882)
			(xy 134.704777 -346.373379) (xy 134.720845 -346.426786) (xy 134.728965 -346.481962) (xy 134.729474 -346.509848)
			(xy 134.728965 -346.537734) (xy 134.720845 -346.59291) (xy 134.704777 -346.646317) (xy 134.681105 -346.696814)
			(xy 134.650332 -346.743327) (xy 134.613115 -346.784864) (xy 134.570247 -346.820539) (xy 134.522641 -346.849593)
			(xy 134.471312 -346.871405) (xy 134.417355 -346.885511) (xy 134.361918 -346.891611) (xy 134.306184 -346.889574)
			(xy 134.251341 -346.879444) (xy 134.198557 -346.861437) (xy 134.148957 -346.835936) (xy 134.103599 -346.803485)
			(xy 134.06345 -346.764776) (xy 134.029364 -346.720633) (xy 134.002068 -346.671998) (xy 133.982145 -346.619907)
			(xy 133.970019 -346.56547) (xy 133.965948 -346.509848) (xy 98.117504 -346.509848) (xy 99.047031 -347.439234)
			(xy 135.44169 -347.439234) (xy 135.442274 -347.409547) (xy 135.451467 -347.35089) (xy 135.469637 -347.294364)
			(xy 135.496345 -347.241337) (xy 135.530946 -347.193087) (xy 135.572604 -347.150781) (xy 135.596122 -347.132656)
			(xy 135.606706 -347.124204) (xy 135.623411 -347.102896) (xy 135.633929 -347.077948) (xy 135.637521 -347.051113)
			(xy 135.633936 -347.024277) (xy 135.623424 -346.999326) (xy 135.606725 -346.978015) (xy 135.596122 -346.969588)
			(xy 135.572611 -346.951453) (xy 135.530949 -346.90915) (xy 135.496344 -346.860903) (xy 135.469631 -346.807878)
			(xy 135.451455 -346.751354) (xy 135.442256 -346.692697) (xy 135.44169 -346.66301) (xy 135.442176 -346.635759)
			(xy 135.449932 -346.581811) (xy 135.465287 -346.529516) (xy 135.487929 -346.479939) (xy 135.517395 -346.434089)
			(xy 135.553086 -346.392898) (xy 135.594277 -346.357207) (xy 135.640127 -346.327741) (xy 135.689704 -346.305099)
			(xy 135.741999 -346.289744) (xy 135.795947 -346.281988) (xy 135.850449 -346.281988) (xy 135.904397 -346.289744)
			(xy 135.956692 -346.305099) (xy 136.006269 -346.327741) (xy 136.052119 -346.357207) (xy 136.09331 -346.392898)
			(xy 136.129001 -346.434089) (xy 136.158467 -346.479939) (xy 136.181109 -346.529516) (xy 136.196464 -346.581811)
			(xy 136.20422 -346.635759) (xy 136.204706 -346.66301) (xy 136.204156 -346.692698) (xy 136.194956 -346.751357)
			(xy 136.176779 -346.807883) (xy 136.150065 -346.860911) (xy 136.137984 -346.877754) (xy 136.45814 -346.877754)
			(xy 136.45814 -346.823246) (xy 136.465897 -346.769293) (xy 136.481254 -346.716993) (xy 136.503897 -346.667411)
			(xy 136.533366 -346.621557) (xy 136.569061 -346.580362) (xy 136.610255 -346.544667) (xy 136.65611 -346.515198)
			(xy 136.705692 -346.492554) (xy 136.757991 -346.477198) (xy 136.811944 -346.46944) (xy 136.839198 -346.468954)
			(xy 136.864433 -346.469358) (xy 136.914467 -346.475975) (xy 136.963187 -346.489146) (xy 137.009739 -346.508641)
			(xy 137.03173 -346.521024) (xy 137.044684 -346.528087) (xy 137.073326 -346.535122) (xy 137.102783 -346.533675)
			(xy 137.130598 -346.523868) (xy 137.154449 -346.506519) (xy 137.172345 -346.483076) (xy 137.178034 -346.469462)
			(xy 137.188748 -346.442694) (xy 137.217036 -346.392454) (xy 137.252564 -346.347046) (xy 137.294524 -346.307505)
			(xy 137.341958 -346.27473) (xy 137.393785 -346.249471) (xy 137.448825 -346.232302) (xy 137.505822 -346.223614)
			(xy 137.53465 -346.223082) (xy 137.561901 -346.223602) (xy 137.61585 -346.231352) (xy 137.668146 -346.246701)
			(xy 137.717725 -346.269337) (xy 137.763578 -346.298799) (xy 137.804771 -346.334487) (xy 137.840465 -346.375674)
			(xy 137.869934 -346.421522) (xy 137.892578 -346.471098) (xy 137.907936 -346.523392) (xy 137.915694 -346.577339)
			(xy 137.916158 -346.60459) (xy 137.915629 -346.634495) (xy 137.906312 -346.693574) (xy 137.897616 -346.722192)
			(xy 137.893528 -346.736087) (xy 137.892626 -346.765028) (xy 137.8999 -346.793054) (xy 137.914763 -346.817903)
			(xy 137.936014 -346.837569) (xy 137.961939 -346.850464) (xy 137.976102 -346.85351) (xy 138.002169 -346.858706)
			(xy 138.052672 -346.875273) (xy 138.100385 -346.898693) (xy 138.144384 -346.928511) (xy 138.183815 -346.964151)
			(xy 138.217914 -347.004921) (xy 138.246022 -347.050032) (xy 138.267593 -347.098609) (xy 138.282209 -347.14971)
			(xy 138.289587 -347.202347) (xy 138.290046 -347.228922) (xy 138.28956 -347.256173) (xy 138.281804 -347.310121)
			(xy 138.266449 -347.362416) (xy 138.243807 -347.411993) (xy 138.214341 -347.457843) (xy 138.17865 -347.499034)
			(xy 138.137459 -347.534725) (xy 138.091609 -347.564191) (xy 138.042032 -347.586833) (xy 137.989737 -347.602188)
			(xy 137.935789 -347.609944) (xy 137.881287 -347.609944) (xy 137.827339 -347.602188) (xy 137.775044 -347.586833)
			(xy 137.725467 -347.564191) (xy 137.679617 -347.534725) (xy 137.638426 -347.499034) (xy 137.602735 -347.457843)
			(xy 137.573269 -347.411993) (xy 137.550627 -347.362416) (xy 137.535272 -347.310121) (xy 137.527516 -347.256173)
			(xy 137.52703 -347.228922) (xy 137.527558 -347.199017) (xy 137.536875 -347.139938) (xy 137.545572 -347.11132)
			(xy 137.549656 -347.097423) (xy 137.550561 -347.068483) (xy 137.543289 -347.040456) (xy 137.528427 -347.015606)
			(xy 137.507175 -346.995941) (xy 137.481249 -346.983047) (xy 137.467086 -346.980002) (xy 137.434246 -346.973424)
			(xy 137.371394 -346.950298) (xy 137.342118 -346.934028) (xy 137.329125 -346.927047) (xy 137.3005 -346.920009)
			(xy 137.271058 -346.921446) (xy 137.243253 -346.931237) (xy 137.219407 -346.948565) (xy 137.201508 -346.971986)
			(xy 137.195814 -346.98559) (xy 137.185117 -347.012366) (xy 137.156831 -347.062609) (xy 137.121302 -347.10802)
			(xy 137.07934 -347.147563) (xy 137.031903 -347.180337) (xy 136.980071 -347.205595) (xy 136.925028 -347.22276)
			(xy 136.868027 -347.231441) (xy 136.839198 -347.23197) (xy 136.811944 -347.23156) (xy 136.757991 -347.223802)
			(xy 136.705692 -347.208446) (xy 136.65611 -347.185802) (xy 136.610255 -347.156333) (xy 136.569061 -347.120638)
			(xy 136.533366 -347.079443) (xy 136.503897 -347.033589) (xy 136.481254 -346.984007) (xy 136.465897 -346.931707)
			(xy 136.45814 -346.877754) (xy 136.137984 -346.877754) (xy 136.115458 -346.909159) (xy 136.073795 -346.951464)
			(xy 136.050274 -346.969588) (xy 136.039646 -346.97799) (xy 136.022942 -346.999309) (xy 136.012428 -347.024268)
			(xy 136.008841 -347.051113) (xy 136.012435 -347.077957) (xy 136.022956 -347.102914) (xy 136.039665 -347.124229)
			(xy 136.050274 -347.132656) (xy 136.073806 -347.150766) (xy 136.115466 -347.193074) (xy 136.150069 -347.241326)
			(xy 136.176779 -347.294357) (xy 136.19495 -347.350885) (xy 136.204144 -347.409546) (xy 136.204706 -347.439234)
			(xy 136.20422 -347.466485) (xy 136.196464 -347.520433) (xy 136.181109 -347.572728) (xy 136.158467 -347.622305)
			(xy 136.129001 -347.668155) (xy 136.09331 -347.709346) (xy 136.052119 -347.745037) (xy 136.006269 -347.774503)
			(xy 135.956692 -347.797145) (xy 135.904397 -347.8125) (xy 135.850449 -347.820256) (xy 135.795947 -347.820256)
			(xy 135.741999 -347.8125) (xy 135.689704 -347.797145) (xy 135.640127 -347.774503) (xy 135.594277 -347.745037)
			(xy 135.553086 -347.709346) (xy 135.517395 -347.668155) (xy 135.487929 -347.622305) (xy 135.465287 -347.572728)
			(xy 135.449932 -347.520433) (xy 135.442176 -347.466485) (xy 135.44169 -347.439234) (xy 99.047031 -347.439234)
			(xy 99.144836 -347.537024) (xy 110.666784 -347.537024) (xy 110.69178 -347.537669) (xy 110.740802 -347.547471)
			(xy 110.786972 -347.566642) (xy 110.828519 -347.594446) (xy 110.846616 -347.6117) (xy 113.711582 -350.476496)
			(xy 115.595396 -350.476496) (xy 115.595396 -350.3918) (xy 115.603447 -350.307486) (xy 115.619476 -350.22432)
			(xy 115.643337 -350.143053) (xy 115.674816 -350.064423) (xy 115.713627 -349.989142) (xy 115.759417 -349.91789)
			(xy 115.811773 -349.851314) (xy 115.870221 -349.790016) (xy 115.934231 -349.734551) (xy 116.003223 -349.685422)
			(xy 116.076573 -349.643073) (xy 116.153616 -349.607889) (xy 116.233655 -349.580187) (xy 116.315964 -349.560219)
			(xy 116.399799 -349.548166) (xy 116.4844 -349.544136) (xy 116.569001 -349.548166) (xy 116.652836 -349.560219)
			(xy 116.735145 -349.580187) (xy 116.815184 -349.607889) (xy 116.892227 -349.643073) (xy 116.965577 -349.685422)
			(xy 117.034569 -349.734551) (xy 117.098579 -349.790016) (xy 117.157027 -349.851314) (xy 117.209383 -349.91789)
			(xy 117.255173 -349.989142) (xy 117.293984 -350.064423) (xy 117.325463 -350.143053) (xy 117.349324 -350.22432)
			(xy 117.365353 -350.307486) (xy 117.373404 -350.3918) (xy 117.373908 -350.434148) (xy 118.119909 -350.434148)
			(xy 118.123945 -350.350701) (xy 118.136017 -350.268033) (xy 118.15601 -350.186916) (xy 118.183739 -350.108107)
			(xy 118.218945 -350.032342) (xy 118.261299 -349.960329) (xy 118.310405 -349.89274) (xy 118.365806 -349.830206)
			(xy 118.426983 -349.773311) (xy 118.493366 -349.722585) (xy 118.564334 -349.678504) (xy 118.639226 -349.641478)
			(xy 118.717342 -349.611852) (xy 118.797952 -349.589904) (xy 118.880304 -349.575839) (xy 118.96363 -349.569787)
			(xy 119.04715 -349.571806) (xy 119.130086 -349.581876) (xy 119.211662 -349.599904) (xy 119.291118 -349.625721)
			(xy 119.367711 -349.659086) (xy 119.440727 -349.699687) (xy 119.509483 -349.747146) (xy 119.573337 -349.801019)
			(xy 119.631694 -349.860804) (xy 119.684009 -349.925941) (xy 119.729792 -349.995824) (xy 119.768617 -350.069799)
			(xy 119.800122 -350.147176) (xy 119.824011 -350.227233) (xy 119.840062 -350.309221) (xy 119.848125 -350.392376)
			(xy 119.84863 -350.434148) (xy 119.848125 -350.47592) (xy 119.840062 -350.559075) (xy 119.824011 -350.641063)
			(xy 119.800122 -350.72112) (xy 119.768617 -350.798497) (xy 119.729792 -350.872472) (xy 119.684009 -350.942355)
			(xy 119.631694 -351.007492) (xy 119.573337 -351.067277) (xy 119.509483 -351.12115) (xy 119.440727 -351.168609)
			(xy 119.367711 -351.20921) (xy 119.291118 -351.242575) (xy 119.211662 -351.268392) (xy 119.130086 -351.28642)
			(xy 119.04715 -351.29649) (xy 118.96363 -351.298509) (xy 118.880304 -351.292457) (xy 118.797952 -351.278392)
			(xy 118.717342 -351.256444) (xy 118.639226 -351.226818) (xy 118.564334 -351.189792) (xy 118.493366 -351.145711)
			(xy 118.426983 -351.094985) (xy 118.365806 -351.03809) (xy 118.310405 -350.975556) (xy 118.261299 -350.907967)
			(xy 118.218945 -350.835954) (xy 118.183739 -350.760189) (xy 118.15601 -350.68138) (xy 118.136017 -350.600263)
			(xy 118.123945 -350.517595) (xy 118.119909 -350.434148) (xy 117.373908 -350.434148) (xy 117.373404 -350.476496)
			(xy 117.365353 -350.56081) (xy 117.349324 -350.643976) (xy 117.325463 -350.725243) (xy 117.293984 -350.803873)
			(xy 117.255173 -350.879154) (xy 117.209383 -350.950406) (xy 117.157027 -351.016982) (xy 117.098579 -351.07828)
			(xy 117.034569 -351.133745) (xy 116.965577 -351.182874) (xy 116.892227 -351.225223) (xy 116.815184 -351.260407)
			(xy 116.735145 -351.288109) (xy 116.652836 -351.308077) (xy 116.569001 -351.32013) (xy 116.4844 -351.324161)
			(xy 116.399799 -351.32013) (xy 116.315964 -351.308077) (xy 116.233655 -351.288109) (xy 116.153616 -351.260407)
			(xy 116.076573 -351.225223) (xy 116.003223 -351.182874) (xy 115.934231 -351.133745) (xy 115.870221 -351.07828)
			(xy 115.811773 -351.016982) (xy 115.759417 -350.950406) (xy 115.713627 -350.879154) (xy 115.674816 -350.803873)
			(xy 115.643337 -350.725243) (xy 115.619476 -350.643976) (xy 115.603447 -350.56081) (xy 115.595396 -350.476496)
			(xy 113.711582 -350.476496) (xy 115.11661 -351.88144) (xy 117.430042 -351.88144) (xy 117.455037 -351.882106)
			(xy 117.504058 -351.8919) (xy 117.550229 -351.911065) (xy 117.591777 -351.938864) (xy 117.609874 -351.956116)
			(xy 118.195598 -352.54184) (xy 118.212797 -352.559971) (xy 118.240545 -352.601522) (xy 118.259659 -352.647685)
			(xy 118.269406 -352.69669) (xy 118.27002 -352.721672) (xy 118.27002 -353.659948) (xy 165.655242 -353.659948)
			(xy 165.659313 -353.604326) (xy 165.671439 -353.549889) (xy 165.691362 -353.497798) (xy 165.718658 -353.449163)
			(xy 165.752744 -353.40502) (xy 165.792893 -353.366311) (xy 165.838251 -353.33386) (xy 165.887851 -353.308359)
			(xy 165.940635 -353.290352) (xy 165.995478 -353.280222) (xy 166.051212 -353.278185) (xy 166.106649 -353.284285)
			(xy 166.160606 -353.298391) (xy 166.211935 -353.320203) (xy 166.259541 -353.349257) (xy 166.302409 -353.384932)
			(xy 166.339626 -353.426469) (xy 166.370399 -353.472982) (xy 166.394071 -353.523479) (xy 166.410139 -353.576886)
			(xy 166.418259 -353.632062) (xy 166.418768 -353.659948) (xy 166.418259 -353.687834) (xy 166.410139 -353.74301)
			(xy 166.394071 -353.796417) (xy 166.370399 -353.846914) (xy 166.339626 -353.893427) (xy 166.302409 -353.934964)
			(xy 166.259541 -353.970639) (xy 166.211935 -353.999693) (xy 166.160606 -354.021505) (xy 166.106649 -354.035611)
			(xy 166.051212 -354.041711) (xy 165.995478 -354.039674) (xy 165.940635 -354.029544) (xy 165.887851 -354.011537)
			(xy 165.838251 -353.986036) (xy 165.792893 -353.953585) (xy 165.752744 -353.914876) (xy 165.718658 -353.870733)
			(xy 165.691362 -353.822098) (xy 165.671439 -353.770007) (xy 165.659313 -353.71557) (xy 165.655242 -353.659948)
			(xy 118.27002 -353.659948) (xy 118.27002 -353.867212) (xy 118.269406 -353.892195) (xy 118.259664 -353.941204)
			(xy 118.240558 -353.987374) (xy 118.212819 -354.028934) (xy 118.195598 -354.047044) (xy 117.613938 -354.628704)
			(xy 117.595863 -354.645983) (xy 117.574618 -354.6602) (xy 165.673276 -354.6602) (xy 165.677347 -354.604578)
			(xy 165.689473 -354.550141) (xy 165.709396 -354.49805) (xy 165.736692 -354.449415) (xy 165.770778 -354.405272)
			(xy 165.810927 -354.366563) (xy 165.856285 -354.334112) (xy 165.905885 -354.308611) (xy 165.958669 -354.290604)
			(xy 166.013512 -354.280474) (xy 166.069246 -354.278437) (xy 166.124683 -354.284537) (xy 166.17864 -354.298643)
			(xy 166.229969 -354.320455) (xy 166.277575 -354.349509) (xy 166.320443 -354.385184) (xy 166.35766 -354.426721)
			(xy 166.388433 -354.473234) (xy 166.412105 -354.523731) (xy 166.428173 -354.577138) (xy 166.436293 -354.632314)
			(xy 166.436802 -354.6602) (xy 166.436293 -354.688086) (xy 166.428173 -354.743262) (xy 166.412105 -354.796669)
			(xy 166.388433 -354.847166) (xy 166.35766 -354.893679) (xy 166.320443 -354.935216) (xy 166.277575 -354.970891)
			(xy 166.229969 -354.999945) (xy 166.180704 -355.02088) (xy 168.06799 -355.02088) (xy 168.068468 -354.992839)
			(xy 168.076672 -354.93736) (xy 168.092902 -354.883678) (xy 168.116807 -354.832946) (xy 168.147874 -354.786255)
			(xy 168.166288 -354.765102) (xy 168.175903 -354.753637) (xy 168.188686 -354.726603) (xy 168.193077 -354.697022)
			(xy 168.188699 -354.66744) (xy 168.175928 -354.6404) (xy 168.166288 -354.628958) (xy 168.147872 -354.607803)
			(xy 168.116777 -354.561127) (xy 168.092861 -354.510397) (xy 168.07664 -354.456709) (xy 168.068464 -354.401223)
			(xy 168.06799 -354.37318) (xy 168.068476 -354.345929) (xy 168.076232 -354.291981) (xy 168.091587 -354.239686)
			(xy 168.114229 -354.190109) (xy 168.143695 -354.144259) (xy 168.179386 -354.103068) (xy 168.220577 -354.067377)
			(xy 168.266427 -354.037911) (xy 168.316004 -354.015269) (xy 168.368299 -353.999914) (xy 168.422247 -353.992158)
			(xy 168.476749 -353.992158) (xy 168.530697 -353.999914) (xy 168.582992 -354.015269) (xy 168.632569 -354.037911)
			(xy 168.678419 -354.067377) (xy 168.71961 -354.103068) (xy 168.755301 -354.144259) (xy 168.784767 -354.190109)
			(xy 168.807409 -354.239686) (xy 168.822764 -354.291981) (xy 168.83052 -354.345929) (xy 168.831006 -354.37318)
			(xy 168.830505 -354.40122) (xy 168.822306 -354.456698) (xy 168.806083 -354.51038) (xy 168.782182 -354.561112)
			(xy 168.75112 -354.607804) (xy 168.732708 -354.628958) (xy 168.728189 -354.634292) (xy 176.045366 -354.634292)
			(xy 176.049437 -354.57867) (xy 176.061563 -354.524233) (xy 176.081486 -354.472142) (xy 176.108782 -354.423507)
			(xy 176.142868 -354.379364) (xy 176.183017 -354.340655) (xy 176.228375 -354.308204) (xy 176.277975 -354.282703)
			(xy 176.330759 -354.264696) (xy 176.385602 -354.254566) (xy 176.441336 -354.252529) (xy 176.496773 -354.258629)
			(xy 176.55073 -354.272735) (xy 176.602059 -354.294547) (xy 176.649665 -354.323601) (xy 176.692533 -354.359276)
			(xy 176.72975 -354.400813) (xy 176.760523 -354.447326) (xy 176.784195 -354.497823) (xy 176.800263 -354.55123)
			(xy 176.808383 -354.606406) (xy 176.808892 -354.634292) (xy 176.808383 -354.662178) (xy 176.800263 -354.717354)
			(xy 176.784195 -354.770761) (xy 176.760523 -354.821258) (xy 176.72975 -354.867771) (xy 176.692533 -354.909308)
			(xy 176.649665 -354.944983) (xy 176.602059 -354.974037) (xy 176.55073 -354.995849) (xy 176.496773 -355.009955)
			(xy 176.455195 -355.01453) (xy 177.756312 -355.01453) (xy 177.756793 -354.98716) (xy 177.764607 -354.932982)
			(xy 177.780092 -354.880479) (xy 177.802931 -354.830732) (xy 177.832652 -354.784764) (xy 177.850292 -354.763832)
			(xy 177.859501 -354.752483) (xy 177.871683 -354.725934) (xy 177.875861 -354.697023) (xy 177.871695 -354.66811)
			(xy 177.859525 -354.641555) (xy 177.850292 -354.630228) (xy 177.832651 -354.609297) (xy 177.80294 -354.563324)
			(xy 177.780104 -354.513576) (xy 177.764614 -354.461075) (xy 177.756786 -354.406899) (xy 177.756312 -354.37953)
			(xy 177.756798 -354.352279) (xy 177.764554 -354.298331) (xy 177.779909 -354.246036) (xy 177.802551 -354.196459)
			(xy 177.832017 -354.150609) (xy 177.867708 -354.109418) (xy 177.908899 -354.073727) (xy 177.954749 -354.044261)
			(xy 178.004326 -354.021619) (xy 178.056621 -354.006264) (xy 178.110569 -353.998508) (xy 178.165071 -353.998508)
			(xy 178.219019 -354.006264) (xy 178.271314 -354.021619) (xy 178.320891 -354.044261) (xy 178.366741 -354.073727)
			(xy 178.407932 -354.109418) (xy 178.443623 -354.150609) (xy 178.473089 -354.196459) (xy 178.495731 -354.246036)
			(xy 178.511086 -354.298331) (xy 178.518842 -354.352279) (xy 178.519328 -354.37953) (xy 178.518897 -354.406902)
			(xy 178.511073 -354.461083) (xy 178.495577 -354.513587) (xy 178.472727 -354.563334) (xy 178.442994 -354.609298)
			(xy 178.425348 -354.630228) (xy 178.419106 -354.637848) (xy 185.603386 -354.637848) (xy 185.607457 -354.582226)
			(xy 185.619583 -354.527789) (xy 185.639506 -354.475698) (xy 185.666802 -354.427063) (xy 185.700888 -354.38292)
			(xy 185.741037 -354.344211) (xy 185.786395 -354.31176) (xy 185.835995 -354.286259) (xy 185.888779 -354.268252)
			(xy 185.943622 -354.258122) (xy 185.999356 -354.256085) (xy 186.054793 -354.262185) (xy 186.10875 -354.276291)
			(xy 186.160079 -354.298103) (xy 186.207685 -354.327157) (xy 186.250553 -354.362832) (xy 186.28777 -354.404369)
			(xy 186.318543 -354.450882) (xy 186.342215 -354.501379) (xy 186.358283 -354.554786) (xy 186.366403 -354.609962)
			(xy 186.366912 -354.637848) (xy 186.366403 -354.665734) (xy 186.358283 -354.72091) (xy 186.342215 -354.774317)
			(xy 186.318543 -354.824814) (xy 186.28777 -354.871327) (xy 186.250553 -354.912864) (xy 186.207685 -354.948539)
			(xy 186.160079 -354.977593) (xy 186.10875 -354.999405) (xy 186.054793 -355.013511) (xy 185.999356 -355.019611)
			(xy 185.943622 -355.017574) (xy 185.888779 -355.007444) (xy 185.835995 -354.989437) (xy 185.786395 -354.963936)
			(xy 185.741037 -354.931485) (xy 185.700888 -354.892776) (xy 185.666802 -354.848633) (xy 185.639506 -354.799998)
			(xy 185.619583 -354.747907) (xy 185.607457 -354.69347) (xy 185.603386 -354.637848) (xy 178.419106 -354.637848)
			(xy 178.416086 -354.641535) (xy 178.403918 -354.668101) (xy 178.399754 -354.697023) (xy 178.403931 -354.725942)
			(xy 178.416111 -354.752503) (xy 178.425348 -354.763832) (xy 178.442961 -354.784786) (xy 178.472678 -354.830752)
			(xy 178.49552 -354.880494) (xy 178.511017 -354.93299) (xy 178.518851 -354.987162) (xy 178.519328 -355.01453)
			(xy 178.518842 -355.041781) (xy 178.511086 -355.095729) (xy 178.495731 -355.148024) (xy 178.473089 -355.197601)
			(xy 178.443623 -355.243451) (xy 178.407932 -355.284642) (xy 178.366741 -355.320333) (xy 178.320891 -355.349799)
			(xy 178.271314 -355.372441) (xy 178.219019 -355.387796) (xy 178.165071 -355.395552) (xy 178.110569 -355.395552)
			(xy 178.056621 -355.387796) (xy 178.004326 -355.372441) (xy 177.954749 -355.349799) (xy 177.908899 -355.320333)
			(xy 177.867708 -355.284642) (xy 177.832017 -355.243451) (xy 177.802551 -355.197601) (xy 177.779909 -355.148024)
			(xy 177.764554 -355.095729) (xy 177.756798 -355.041781) (xy 177.756312 -355.01453) (xy 176.455195 -355.01453)
			(xy 176.441336 -355.016055) (xy 176.385602 -355.014018) (xy 176.330759 -355.003888) (xy 176.277975 -354.985881)
			(xy 176.228375 -354.96038) (xy 176.183017 -354.927929) (xy 176.142868 -354.88922) (xy 176.108782 -354.845077)
			(xy 176.081486 -354.796442) (xy 176.061563 -354.744351) (xy 176.049437 -354.689914) (xy 176.045366 -354.634292)
			(xy 168.728189 -354.634292) (xy 168.723034 -354.640377) (xy 168.710259 -354.667429) (xy 168.705879 -354.697022)
			(xy 168.710272 -354.726614) (xy 168.723059 -354.75366) (xy 168.732708 -354.765102) (xy 168.751151 -354.786234)
			(xy 168.782243 -354.832916) (xy 168.806154 -354.883652) (xy 168.822368 -354.937345) (xy 168.830536 -354.992835)
			(xy 168.831006 -355.02088) (xy 168.83052 -355.048131) (xy 168.822764 -355.102079) (xy 168.807409 -355.154374)
			(xy 168.784767 -355.203951) (xy 168.755301 -355.249801) (xy 168.71961 -355.290992) (xy 168.678419 -355.326683)
			(xy 168.632569 -355.356149) (xy 168.582992 -355.378791) (xy 168.530697 -355.394146) (xy 168.476749 -355.401902)
			(xy 168.422247 -355.401902) (xy 168.368299 -355.394146) (xy 168.316004 -355.378791) (xy 168.266427 -355.356149)
			(xy 168.220577 -355.326683) (xy 168.179386 -355.290992) (xy 168.143695 -355.249801) (xy 168.114229 -355.203951)
			(xy 168.091587 -355.154374) (xy 168.076232 -355.102079) (xy 168.068476 -355.048131) (xy 168.06799 -355.02088)
			(xy 166.180704 -355.02088) (xy 166.17864 -355.021757) (xy 166.124683 -355.035863) (xy 166.069246 -355.041963)
			(xy 166.013512 -355.039926) (xy 165.958669 -355.029796) (xy 165.905885 -355.011789) (xy 165.856285 -354.986288)
			(xy 165.810927 -354.953837) (xy 165.770778 -354.915128) (xy 165.736692 -354.870985) (xy 165.709396 -354.82235)
			(xy 165.689473 -354.770259) (xy 165.677347 -354.715822) (xy 165.673276 -354.6602) (xy 117.574618 -354.6602)
			(xy 117.554311 -354.673789) (xy 117.508133 -354.692956) (xy 117.459104 -354.702747) (xy 117.434106 -354.70338)
			(xy 117.051328 -354.70338) (xy 117.04447 -354.746306) (xy 117.039909 -354.772965) (xy 117.024172 -354.82471)
			(xy 117.001282 -354.873713) (xy 116.971699 -354.918991) (xy 116.936017 -354.959635) (xy 116.89495 -354.994831)
			(xy 116.849322 -355.023872) (xy 116.80005 -355.046176) (xy 116.748121 -355.061295) (xy 116.694577 -355.068927)
			(xy 116.667534 -355.069394) (xy 116.640281 -355.068913) (xy 116.58633 -355.06116) (xy 116.534032 -355.045808)
			(xy 116.484451 -355.023168) (xy 116.438597 -354.993703) (xy 116.397404 -354.958011) (xy 116.361709 -354.916819)
			(xy 116.332241 -354.870967) (xy 116.309599 -354.821387) (xy 116.294244 -354.769089) (xy 116.286488 -354.715139)
			(xy 116.286026 -354.687886) (xy 116.286472 -354.661506) (xy 116.293727 -354.609248) (xy 116.30811 -354.558488)
			(xy 116.329348 -354.510192) (xy 116.357036 -354.465282) (xy 116.390646 -354.424613) (xy 116.429536 -354.388961)
			(xy 116.472967 -354.359006) (xy 116.496338 -354.346764) (xy 116.508712 -354.340085) (xy 116.529447 -354.321108)
			(xy 116.544213 -354.29719) (xy 116.551887 -354.270148) (xy 116.551885 -354.242039) (xy 116.544208 -354.214999)
			(xy 116.529439 -354.191082) (xy 116.508701 -354.172108) (xy 116.496338 -354.165408) (xy 116.472948 -354.153203)
			(xy 116.429525 -354.123234) (xy 116.390642 -354.087572) (xy 116.357039 -354.046897) (xy 116.329355 -354.001983)
			(xy 116.308118 -353.953686) (xy 116.293731 -353.902924) (xy 116.28647 -353.850666) (xy 116.286026 -353.824286)
			(xy 116.286442 -353.797031) (xy 116.294202 -353.743077) (xy 116.309561 -353.690776) (xy 116.332208 -353.641193)
			(xy 116.361681 -353.595339) (xy 116.397379 -353.554145) (xy 116.438577 -353.518452) (xy 116.484436 -353.488985)
			(xy 116.534021 -353.466344) (xy 116.586324 -353.450991) (xy 116.640279 -353.443239) (xy 116.667534 -353.442778)
			(xy 116.694789 -353.443239) (xy 116.748747 -353.450976) (xy 116.801054 -353.466315) (xy 116.850645 -353.488945)
			(xy 116.896508 -353.518403) (xy 116.937711 -353.554091) (xy 116.973414 -353.595281) (xy 117.002889 -353.641135)
			(xy 117.025537 -353.690717) (xy 117.040895 -353.743018) (xy 117.045232 -353.76993) (xy 117.051328 -353.813364)
			(xy 117.170708 -353.813364) (xy 117.380512 -353.603814) (xy 117.380512 -352.98507) (xy 117.166644 -352.771456)
			(xy 114.853212 -352.771456) (xy 114.828216 -352.770819) (xy 114.779193 -352.761016) (xy 114.733022 -352.741843)
			(xy 114.691476 -352.714035) (xy 114.67338 -352.69678) (xy 110.403386 -348.42704) (xy 98.881438 -348.42704)
			(xy 98.856442 -348.426392) (xy 98.80742 -348.416593) (xy 98.761249 -348.397423) (xy 98.719702 -348.369618)
			(xy 98.701606 -348.352364) (xy 97.025968 -346.67698) (xy 87.455756 -346.67698) (xy 83.676744 -350.455738)
			(xy 83.658626 -350.472951) (xy 83.619351 -350.499172) (xy 88.330532 -350.499172) (xy 88.33109 -350.470256)
			(xy 88.339809 -350.413086) (xy 88.357058 -350.357888) (xy 88.382442 -350.305926) (xy 88.41538 -350.258391)
			(xy 88.455115 -350.216373) (xy 88.477598 -350.198182) (xy 88.48943 -350.188315) (xy 88.506945 -350.162982)
			(xy 88.516117 -350.133582) (xy 88.516112 -350.102784) (xy 88.50693 -350.073387) (xy 88.489406 -350.04806)
			(xy 88.477598 -350.038162) (xy 88.455096 -350.019993) (xy 88.415362 -349.977969) (xy 88.382425 -349.930429)
			(xy 88.35704 -349.878463) (xy 88.339788 -349.823262) (xy 88.331064 -349.766089) (xy 88.330532 -349.737172)
			(xy 88.330929 -349.709917) (xy 88.338691 -349.655961) (xy 88.354052 -349.60366) (xy 88.376701 -349.554077)
			(xy 88.406176 -349.508222) (xy 88.441876 -349.467028) (xy 88.483076 -349.431335) (xy 88.528936 -349.401868)
			(xy 88.578523 -349.379229) (xy 88.630828 -349.363876) (xy 88.684785 -349.356124) (xy 88.71204 -349.355664)
			(xy 88.738273 -349.356089) (xy 88.790245 -349.363261) (xy 88.840747 -349.377481) (xy 88.888827 -349.398478)
			(xy 88.91143 -349.411798) (xy 88.921042 -349.417123) (xy 88.942853 -349.419676) (xy 88.963746 -349.412914)
			(xy 88.979926 -349.398067) (xy 88.988453 -349.377831) (xy 88.988646 -349.36684) (xy 88.988392 -349.353632)
			(xy 88.988456 -349.342494) (xy 88.989728 -349.320255) (xy 88.990932 -349.309182) (xy 88.992189 -349.294211)
			(xy 88.986907 -349.264651) (xy 88.973257 -349.237904) (xy 88.952417 -349.216283) (xy 88.926191 -349.201657)
			(xy 88.896845 -349.19529) (xy 88.866916 -349.197734) (xy 88.852756 -349.202756) (xy 88.830293 -349.2113)
			(xy 88.78375 -349.223283) (xy 88.73607 -349.229319) (xy 88.71204 -349.22968) (xy 88.684783 -349.229276)
			(xy 88.630824 -349.221523) (xy 88.578517 -349.206169) (xy 88.528929 -349.183527) (xy 88.483067 -349.154058)
			(xy 88.441866 -349.118362) (xy 88.406166 -349.077165) (xy 88.376692 -349.031307) (xy 88.354045 -348.98172)
			(xy 88.338686 -348.929415) (xy 88.330927 -348.875457) (xy 88.330927 -348.820943) (xy 88.338686 -348.766985)
			(xy 88.354045 -348.71468) (xy 88.376692 -348.665093) (xy 88.406166 -348.619235) (xy 88.441866 -348.578038)
			(xy 88.483067 -348.542342) (xy 88.528929 -348.512873) (xy 88.578517 -348.490231) (xy 88.630824 -348.474877)
			(xy 88.684783 -348.467124) (xy 88.71204 -348.466664) (xy 88.736204 -348.467041) (xy 88.784147 -348.473135)
			(xy 88.830936 -348.485233) (xy 88.853518 -348.493842) (xy 88.868007 -348.499123) (xy 88.89874 -348.501541)
			(xy 88.928796 -348.494686) (xy 88.955441 -348.479182) (xy 88.976252 -348.456438) (xy 88.989334 -348.428524)
			(xy 88.991948 -348.413324) (xy 88.996023 -348.386221) (xy 89.011078 -348.333521) (xy 89.033522 -348.283519)
			(xy 89.062893 -348.237245) (xy 89.098585 -348.195651) (xy 89.139864 -348.159596) (xy 89.18588 -348.129821)
			(xy 89.235683 -348.106939) (xy 89.28825 -348.091423) (xy 89.342496 -348.083591) (xy 89.3699 -348.083124)
			(xy 89.398817 -348.083633) (xy 89.455989 -348.092363) (xy 89.511189 -348.109622) (xy 89.563151 -348.135015)
			(xy 89.610684 -348.167961) (xy 89.6527 -348.207704) (xy 89.67089 -348.23019) (xy 89.680787 -348.241995)
			(xy 89.706111 -348.259514) (xy 89.735504 -348.26869) (xy 89.766296 -348.26869) (xy 89.795689 -348.259514)
			(xy 89.821013 -348.241995) (xy 89.83091 -348.23019) (xy 89.849093 -348.2077) (xy 89.891115 -348.167965)
			(xy 89.938651 -348.135027) (xy 89.990614 -348.10964) (xy 90.045813 -348.092385) (xy 90.102984 -348.083658)
			(xy 90.1319 -348.083124) (xy 90.159154 -348.083546) (xy 90.213106 -348.091303) (xy 90.265405 -348.106659)
			(xy 90.314986 -348.129302) (xy 90.360841 -348.158771) (xy 90.402034 -348.194466) (xy 90.437729 -348.235659)
			(xy 90.467198 -348.281514) (xy 90.489841 -348.331095) (xy 90.505197 -348.383394) (xy 90.512954 -348.437346)
			(xy 90.512954 -348.491854) (xy 90.509949 -348.512757) (xy 90.715215 -348.512757) (xy 90.715215 -348.458243)
			(xy 90.722974 -348.404283) (xy 90.738333 -348.351976) (xy 90.760981 -348.302388) (xy 90.790456 -348.256528)
			(xy 90.826157 -348.21533) (xy 90.867359 -348.179633) (xy 90.913222 -348.150163) (xy 90.962812 -348.12752)
			(xy 91.01512 -348.112166) (xy 91.06908 -348.104412) (xy 91.096338 -348.103952) (xy 91.125254 -348.104495)
			(xy 91.182425 -348.113217) (xy 91.237624 -348.130468) (xy 91.289586 -348.155855) (xy 91.337121 -348.188795)
			(xy 91.379138 -348.228534) (xy 91.397328 -348.251018) (xy 91.407225 -348.262823) (xy 91.432549 -348.280342)
			(xy 91.461942 -348.289518) (xy 91.492734 -348.289518) (xy 91.522127 -348.280342) (xy 91.547451 -348.262823)
			(xy 91.557348 -348.251018) (xy 91.574101 -348.230235) (xy 91.612455 -348.193105) (xy 91.655609 -348.161683)
			(xy 91.702723 -348.136584) (xy 91.752875 -348.118298) (xy 91.805086 -348.107181) (xy 91.858338 -348.103451)
			(xy 91.91159 -348.107181) (xy 91.963801 -348.118298) (xy 92.013953 -348.136584) (xy 92.061067 -348.161683)
			(xy 92.104221 -348.193105) (xy 92.142575 -348.230235) (xy 92.159328 -348.251018) (xy 92.169225 -348.262823)
			(xy 92.194549 -348.280342) (xy 92.223942 -348.289518) (xy 92.254734 -348.289518) (xy 92.284127 -348.280342)
			(xy 92.309451 -348.262823) (xy 92.319348 -348.251018) (xy 92.336101 -348.230235) (xy 92.374455 -348.193105)
			(xy 92.417609 -348.161683) (xy 92.464723 -348.136584) (xy 92.514875 -348.118298) (xy 92.567086 -348.107181)
			(xy 92.620338 -348.103451) (xy 92.67359 -348.107181) (xy 92.725801 -348.118298) (xy 92.775953 -348.136584)
			(xy 92.823067 -348.161683) (xy 92.866221 -348.193105) (xy 92.904575 -348.230235) (xy 92.921328 -348.251018)
			(xy 92.931225 -348.262823) (xy 92.956549 -348.280342) (xy 92.985942 -348.289518) (xy 93.016734 -348.289518)
			(xy 93.046127 -348.280342) (xy 93.071451 -348.262823) (xy 93.081348 -348.251018) (xy 93.099573 -348.228563)
			(xy 93.141585 -348.188825) (xy 93.189113 -348.155882) (xy 93.241067 -348.130489) (xy 93.296259 -348.113227)
			(xy 93.353424 -348.104491) (xy 93.382338 -348.103952) (xy 93.410905 -348.104492) (xy 93.467399 -348.113024)
			(xy 93.521992 -348.129875) (xy 93.573466 -348.15467) (xy 93.620672 -348.186857) (xy 93.662557 -348.225716)
			(xy 93.680788 -348.247716) (xy 93.690372 -348.258945) (xy 93.714608 -348.275783) (xy 93.742643 -348.284996)
			(xy 93.772143 -348.285814) (xy 93.800646 -348.278172) (xy 93.825779 -348.262704) (xy 93.835982 -348.252034)
			(xy 93.854145 -348.232411) (xy 93.895029 -348.197953) (xy 93.940324 -348.16954) (xy 93.989143 -348.147728)
			(xy 94.040528 -348.132946) (xy 94.093473 -348.125482) (xy 94.120208 -348.125034) (xy 94.149123 -348.125606)
			(xy 94.206292 -348.134322) (xy 94.261491 -348.151568) (xy 94.313453 -348.17695) (xy 94.360988 -348.209885)
			(xy 94.403007 -348.249618) (xy 94.421198 -348.2721) (xy 94.431095 -348.283905) (xy 94.456419 -348.301424)
			(xy 94.485812 -348.3106) (xy 94.516604 -348.3106) (xy 94.545997 -348.301424) (xy 94.571321 -348.283905)
			(xy 94.581218 -348.2721) (xy 94.599399 -348.249608) (xy 94.641421 -348.209873) (xy 94.688958 -348.176935)
			(xy 94.740921 -348.151548) (xy 94.79612 -348.134294) (xy 94.853291 -348.125568) (xy 94.882208 -348.125034)
			(xy 94.909462 -348.125436) (xy 94.963415 -348.133195) (xy 95.015714 -348.148552) (xy 95.065296 -348.171196)
			(xy 95.11115 -348.200666) (xy 95.152344 -348.236362) (xy 95.188039 -348.277556) (xy 95.217508 -348.323411)
			(xy 95.240151 -348.372993) (xy 95.255507 -348.425293) (xy 95.263264 -348.479246) (xy 95.263264 -348.512752)
			(xy 95.383338 -348.512752) (xy 95.383338 -348.458248) (xy 95.391094 -348.404299) (xy 95.406448 -348.352003)
			(xy 95.429088 -348.302424) (xy 95.458553 -348.256571) (xy 95.494242 -348.215378) (xy 95.535431 -348.179683)
			(xy 95.58128 -348.150212) (xy 95.630856 -348.127565) (xy 95.68315 -348.112204) (xy 95.737098 -348.104441)
			(xy 95.76435 -348.103952) (xy 95.793267 -348.104486) (xy 95.850438 -348.113209) (xy 95.905637 -348.130463)
			(xy 95.9576 -348.155851) (xy 96.005134 -348.188793) (xy 96.04715 -348.228533) (xy 96.06534 -348.251018)
			(xy 96.075237 -348.262823) (xy 96.100561 -348.280342) (xy 96.129954 -348.289518) (xy 96.160746 -348.289518)
			(xy 96.190139 -348.280342) (xy 96.215463 -348.262823) (xy 96.22536 -348.251018) (xy 96.243578 -348.228557)
			(xy 96.285592 -348.18882) (xy 96.333121 -348.155878) (xy 96.385077 -348.130485) (xy 96.44027 -348.113224)
			(xy 96.497436 -348.10449) (xy 96.52635 -348.103952) (xy 96.553602 -348.104492) (xy 96.607553 -348.112242)
			(xy 96.659851 -348.127592) (xy 96.709433 -348.15023) (xy 96.755287 -348.179693) (xy 96.796482 -348.215383)
			(xy 96.832177 -348.256573) (xy 96.861646 -348.302423) (xy 96.88429 -348.352002) (xy 96.899647 -348.404298)
			(xy 96.907405 -348.458248) (xy 96.907405 -348.512752) (xy 96.899647 -348.566702) (xy 96.88429 -348.618998)
			(xy 96.861646 -348.668577) (xy 96.832177 -348.714427) (xy 96.796482 -348.755617) (xy 96.755287 -348.791307)
			(xy 96.709433 -348.82077) (xy 96.659851 -348.843408) (xy 96.607553 -348.858758) (xy 96.553602 -348.866508)
			(xy 96.52635 -348.866968) (xy 96.497434 -348.866426) (xy 96.440263 -348.857704) (xy 96.385064 -348.840451)
			(xy 96.333102 -348.815064) (xy 96.285568 -348.782124) (xy 96.24355 -348.742386) (xy 96.22536 -348.719902)
			(xy 96.215463 -348.708097) (xy 96.190139 -348.690578) (xy 96.160746 -348.681402) (xy 96.129954 -348.681402)
			(xy 96.100561 -348.690578) (xy 96.075237 -348.708097) (xy 96.06534 -348.719902) (xy 96.047127 -348.742367)
			(xy 96.005112 -348.782103) (xy 95.957581 -348.815044) (xy 95.905624 -348.840436) (xy 95.850431 -348.857696)
			(xy 95.793265 -348.86643) (xy 95.76435 -348.866968) (xy 95.737098 -348.866559) (xy 95.68315 -348.858796)
			(xy 95.630856 -348.843435) (xy 95.58128 -348.820788) (xy 95.535431 -348.791317) (xy 95.494242 -348.755622)
			(xy 95.458553 -348.714429) (xy 95.429088 -348.668576) (xy 95.406448 -348.618997) (xy 95.391094 -348.566701)
			(xy 95.383338 -348.512752) (xy 95.263264 -348.512752) (xy 95.263264 -348.533754) (xy 95.255507 -348.587707)
			(xy 95.240151 -348.640007) (xy 95.217508 -348.689589) (xy 95.188039 -348.735444) (xy 95.152344 -348.776638)
			(xy 95.11115 -348.812334) (xy 95.065296 -348.841804) (xy 95.015714 -348.864448) (xy 94.963415 -348.879805)
			(xy 94.909462 -348.887564) (xy 94.882208 -348.88805) (xy 94.85329 -348.887545) (xy 94.796118 -348.878816)
			(xy 94.740918 -348.861556) (xy 94.688956 -348.836162) (xy 94.641422 -348.803216) (xy 94.599407 -348.763471)
			(xy 94.581218 -348.740984) (xy 94.571321 -348.729179) (xy 94.545997 -348.71166) (xy 94.516604 -348.702484)
			(xy 94.485812 -348.702484) (xy 94.456419 -348.71166) (xy 94.431095 -348.729179) (xy 94.421198 -348.740984)
			(xy 94.403004 -348.763465) (xy 94.360985 -348.803201) (xy 94.313451 -348.836141) (xy 94.26149 -348.86153)
			(xy 94.206293 -348.878786) (xy 94.149124 -348.887515) (xy 94.120208 -348.88805) (xy 94.091642 -348.887476)
			(xy 94.03515 -348.878952) (xy 93.980557 -348.862107) (xy 93.929083 -348.837318) (xy 93.881876 -348.805137)
			(xy 93.83999 -348.766284) (xy 93.821758 -348.744286) (xy 93.812126 -348.733102) (xy 93.787903 -348.716262)
			(xy 93.75988 -348.707045) (xy 93.730391 -348.706217) (xy 93.701895 -348.713849) (xy 93.676767 -348.729304)
			(xy 93.666564 -348.739968) (xy 93.648379 -348.759569) (xy 93.607499 -348.794029) (xy 93.562209 -348.822445)
			(xy 93.513395 -348.84426) (xy 93.462014 -348.859047) (xy 93.409071 -348.866516) (xy 93.382338 -348.866968)
			(xy 93.353422 -348.866435) (xy 93.29625 -348.85771) (xy 93.241051 -348.840456) (xy 93.189089 -348.815068)
			(xy 93.141555 -348.782126) (xy 93.099538 -348.742387) (xy 93.081348 -348.719902) (xy 93.071451 -348.708097)
			(xy 93.046127 -348.690578) (xy 93.016734 -348.681402) (xy 92.985942 -348.681402) (xy 92.956549 -348.690578)
			(xy 92.931225 -348.708097) (xy 92.921328 -348.719902) (xy 92.904575 -348.740685) (xy 92.866221 -348.777815)
			(xy 92.823067 -348.809237) (xy 92.775953 -348.834336) (xy 92.725801 -348.852622) (xy 92.67359 -348.863739)
			(xy 92.620338 -348.867469) (xy 92.567086 -348.863739) (xy 92.514875 -348.852622) (xy 92.464723 -348.834336)
			(xy 92.417609 -348.809237) (xy 92.374455 -348.777815) (xy 92.336101 -348.740685) (xy 92.319348 -348.719902)
			(xy 92.309451 -348.708097) (xy 92.284127 -348.690578) (xy 92.254734 -348.681402) (xy 92.223942 -348.681402)
			(xy 92.194549 -348.690578) (xy 92.169225 -348.708097) (xy 92.159328 -348.719902) (xy 92.142575 -348.740685)
			(xy 92.104221 -348.777815) (xy 92.061067 -348.809237) (xy 92.013953 -348.834336) (xy 91.963801 -348.852622)
			(xy 91.91159 -348.863739) (xy 91.858338 -348.867469) (xy 91.805086 -348.863739) (xy 91.752875 -348.852622)
			(xy 91.702723 -348.834336) (xy 91.655609 -348.809237) (xy 91.612455 -348.777815) (xy 91.574101 -348.740685)
			(xy 91.557348 -348.719902) (xy 91.547451 -348.708097) (xy 91.522127 -348.690578) (xy 91.492734 -348.681402)
			(xy 91.461942 -348.681402) (xy 91.432549 -348.690578) (xy 91.407225 -348.708097) (xy 91.397328 -348.719902)
			(xy 91.379122 -348.742372) (xy 91.337105 -348.782108) (xy 91.289573 -348.815049) (xy 91.237615 -348.840439)
			(xy 91.18242 -348.857699) (xy 91.125253 -348.866431) (xy 91.096338 -348.866968) (xy 91.06908 -348.866588)
			(xy 91.01512 -348.858834) (xy 90.962812 -348.84348) (xy 90.913222 -348.820837) (xy 90.867359 -348.791367)
			(xy 90.826157 -348.75567) (xy 90.790456 -348.714472) (xy 90.760981 -348.668612) (xy 90.738333 -348.619024)
			(xy 90.722974 -348.566717) (xy 90.715215 -348.512757) (xy 90.509949 -348.512757) (xy 90.505197 -348.545806)
			(xy 90.489841 -348.598105) (xy 90.467198 -348.647686) (xy 90.437729 -348.693541) (xy 90.402034 -348.734734)
			(xy 90.360841 -348.770429) (xy 90.314986 -348.799898) (xy 90.265405 -348.822541) (xy 90.213106 -348.837897)
			(xy 90.159154 -348.845654) (xy 90.1319 -348.84614) (xy 90.102982 -348.845644) (xy 90.045809 -348.836914)
			(xy 89.990608 -348.819653) (xy 89.938646 -348.794257) (xy 89.891113 -348.761308) (xy 89.849098 -348.721562)
			(xy 89.83091 -348.699074) (xy 89.821013 -348.687269) (xy 89.795689 -348.66975) (xy 89.766296 -348.660574)
			(xy 89.735504 -348.660574) (xy 89.706111 -348.66975) (xy 89.680787 -348.687269) (xy 89.67089 -348.699074)
			(xy 89.652698 -348.721557) (xy 89.610679 -348.761293) (xy 89.563145 -348.794233) (xy 89.511184 -348.819622)
			(xy 89.455986 -348.836878) (xy 89.398816 -348.845606) (xy 89.3699 -348.84614) (xy 89.343668 -348.845697)
			(xy 89.291696 -348.838529) (xy 89.241195 -348.824316) (xy 89.193114 -348.803323) (xy 89.17051 -348.790006)
			(xy 89.160875 -348.784726) (xy 89.139075 -348.782162) (xy 89.118188 -348.788913) (xy 89.102011 -348.80375)
			(xy 89.093486 -348.823978) (xy 89.093294 -348.834964) (xy 89.093548 -348.848172) (xy 89.093485 -348.85931)
			(xy 89.092212 -348.881549) (xy 89.091008 -348.892622) (xy 89.089693 -348.907591) (xy 89.094978 -348.937162)
			(xy 89.108636 -348.963917) (xy 89.129485 -348.985543) (xy 89.155724 -349.000168) (xy 89.185082 -349.00653)
			(xy 89.215021 -349.004077) (xy 89.229184 -348.999048) (xy 89.251653 -348.990521) (xy 89.298193 -348.978532)
			(xy 89.34587 -348.972489) (xy 89.3699 -348.972124) (xy 89.398817 -348.972633) (xy 89.455989 -348.981363)
			(xy 89.511189 -348.998622) (xy 89.563151 -349.024015) (xy 89.610684 -349.056961) (xy 89.6527 -349.096704)
			(xy 89.67089 -349.11919) (xy 89.680787 -349.130995) (xy 89.706111 -349.148514) (xy 89.735504 -349.15769)
			(xy 89.766296 -349.15769) (xy 89.795689 -349.148514) (xy 89.821013 -349.130995) (xy 89.83091 -349.11919)
			(xy 89.849093 -349.0967) (xy 89.891115 -349.056965) (xy 89.938651 -349.024027) (xy 89.990614 -348.99864)
			(xy 90.045813 -348.981385) (xy 90.102984 -348.972658) (xy 90.1319 -348.972124) (xy 90.159154 -348.972555)
			(xy 90.213108 -348.980313) (xy 90.265408 -348.995671) (xy 90.314991 -349.018316) (xy 90.360845 -349.047787)
			(xy 90.402039 -349.083484) (xy 90.437733 -349.12468) (xy 90.4672 -349.170537) (xy 90.48984 -349.220122)
			(xy 90.505194 -349.272423) (xy 90.512947 -349.326378) (xy 90.513408 -349.353632) (xy 90.512876 -349.382549)
			(xy 90.504154 -349.439721) (xy 90.486902 -349.494921) (xy 90.461513 -349.546884) (xy 90.42857 -349.594417)
			(xy 90.388828 -349.636433) (xy 90.366342 -349.654622) (xy 90.354502 -349.664483) (xy 90.33698 -349.689815)
			(xy 90.327805 -349.719219) (xy 90.327811 -349.750021) (xy 90.336997 -349.779421) (xy 90.354529 -349.804746)
			(xy 90.366342 -349.814642) (xy 90.387156 -349.831358) (xy 90.424287 -349.869715) (xy 90.455708 -349.912875)
			(xy 90.480807 -349.959992) (xy 90.499092 -350.010149) (xy 90.510206 -350.062365) (xy 90.513933 -350.11562)
			(xy 90.512473 -350.13646) (xy 90.71483 -350.13646) (xy 90.71538 -350.107544) (xy 90.724101 -350.050374)
			(xy 90.741352 -349.995175) (xy 90.766737 -349.943213) (xy 90.799676 -349.895678) (xy 90.839412 -349.853661)
			(xy 90.861896 -349.83547) (xy 90.87374 -349.825616) (xy 90.891256 -349.80028) (xy 90.900426 -349.770876)
			(xy 90.900419 -349.740075) (xy 90.891234 -349.710676) (xy 90.873706 -349.685348) (xy 90.861896 -349.67545)
			(xy 90.839436 -349.657232) (xy 90.799699 -349.615218) (xy 90.766758 -349.567688) (xy 90.741365 -349.515732)
			(xy 90.724104 -349.46054) (xy 90.715369 -349.403374) (xy 90.71483 -349.37446) (xy 90.715241 -349.347206)
			(xy 90.723004 -349.293254) (xy 90.738366 -349.240955) (xy 90.761014 -349.191375) (xy 90.790488 -349.145523)
			(xy 90.826188 -349.104332) (xy 90.867386 -349.068642) (xy 90.913244 -349.039177) (xy 90.962828 -349.016538)
			(xy 91.01513 -349.001187) (xy 91.069084 -348.993435) (xy 91.096338 -348.992952) (xy 91.125254 -348.993495)
			(xy 91.182425 -349.002217) (xy 91.237624 -349.019468) (xy 91.289586 -349.044855) (xy 91.337121 -349.077795)
			(xy 91.379138 -349.117534) (xy 91.397328 -349.140018) (xy 91.407225 -349.151823) (xy 91.432549 -349.169342)
			(xy 91.461942 -349.178518) (xy 91.492734 -349.178518) (xy 91.522127 -349.169342) (xy 91.547451 -349.151823)
			(xy 91.557348 -349.140018) (xy 91.574101 -349.119235) (xy 91.612455 -349.082105) (xy 91.655609 -349.050683)
			(xy 91.702723 -349.025584) (xy 91.752875 -349.007298) (xy 91.805086 -348.996181) (xy 91.858338 -348.992451)
			(xy 91.91159 -348.996181) (xy 91.963801 -349.007298) (xy 92.013953 -349.025584) (xy 92.061067 -349.050683)
			(xy 92.104221 -349.082105) (xy 92.142575 -349.119235) (xy 92.159328 -349.140018) (xy 92.169225 -349.151823)
			(xy 92.194549 -349.169342) (xy 92.223942 -349.178518) (xy 92.254734 -349.178518) (xy 92.284127 -349.169342)
			(xy 92.309451 -349.151823) (xy 92.319348 -349.140018) (xy 92.336101 -349.119235) (xy 92.374455 -349.082105)
			(xy 92.417609 -349.050683) (xy 92.464723 -349.025584) (xy 92.514875 -349.007298) (xy 92.567086 -348.996181)
			(xy 92.620338 -348.992451) (xy 92.67359 -348.996181) (xy 92.725801 -349.007298) (xy 92.775953 -349.025584)
			(xy 92.823067 -349.050683) (xy 92.866221 -349.082105) (xy 92.904575 -349.119235) (xy 92.921328 -349.140018)
			(xy 92.931225 -349.151823) (xy 92.956549 -349.169342) (xy 92.985942 -349.178518) (xy 93.016734 -349.178518)
			(xy 93.046127 -349.169342) (xy 93.071451 -349.151823) (xy 93.081348 -349.140018) (xy 93.099573 -349.117563)
			(xy 93.141585 -349.077825) (xy 93.189113 -349.044882) (xy 93.241067 -349.019489) (xy 93.296259 -349.002227)
			(xy 93.353424 -348.993491) (xy 93.382338 -348.992952) (xy 93.410905 -348.993492) (xy 93.467399 -349.002024)
			(xy 93.521992 -349.018875) (xy 93.573466 -349.04367) (xy 93.620672 -349.075857) (xy 93.662557 -349.114716)
			(xy 93.680788 -349.136716) (xy 93.690372 -349.147945) (xy 93.714608 -349.164783) (xy 93.742643 -349.173996)
			(xy 93.772143 -349.174814) (xy 93.800646 -349.167172) (xy 93.825779 -349.151704) (xy 93.835982 -349.141034)
			(xy 93.854145 -349.121411) (xy 93.895029 -349.086953) (xy 93.940324 -349.05854) (xy 93.989143 -349.036728)
			(xy 94.040528 -349.021946) (xy 94.093473 -349.014482) (xy 94.120208 -349.014034) (xy 94.149123 -349.014606)
			(xy 94.206292 -349.023322) (xy 94.261491 -349.040568) (xy 94.313453 -349.06595) (xy 94.360988 -349.098885)
			(xy 94.403007 -349.138618) (xy 94.421198 -349.1611) (xy 94.431095 -349.172905) (xy 94.456419 -349.190424)
			(xy 94.485812 -349.1996) (xy 94.516604 -349.1996) (xy 94.545997 -349.190424) (xy 94.571321 -349.172905)
			(xy 94.581218 -349.1611) (xy 94.599399 -349.138608) (xy 94.641421 -349.098873) (xy 94.688958 -349.065935)
			(xy 94.740921 -349.040548) (xy 94.79612 -349.023294) (xy 94.853291 -349.014568) (xy 94.882208 -349.014034)
			(xy 94.909463 -349.014448) (xy 94.963418 -349.022207) (xy 95.015719 -349.037566) (xy 95.065302 -349.060213)
			(xy 95.111157 -349.089686) (xy 95.152351 -349.125385) (xy 95.188044 -349.166583) (xy 95.217511 -349.212442)
			(xy 95.240151 -349.262028) (xy 95.255503 -349.314331) (xy 95.263256 -349.368287) (xy 95.263716 -349.395542)
			(xy 95.26314 -349.424984) (xy 95.254075 -349.483167) (xy 95.236182 -349.539267) (xy 95.209886 -349.591954)
			(xy 95.17581 -349.639978) (xy 95.134764 -349.682198) (xy 95.11157 -349.700342) (xy 95.101069 -349.708669)
			(xy 95.084553 -349.729767) (xy 95.074096 -349.754435) (xy 95.070417 -349.780975) (xy 95.073771 -349.807558)
			(xy 95.083926 -349.832353) (xy 95.100182 -349.853651) (xy 95.110554 -349.86214) (xy 95.133163 -349.880342)
			(xy 95.173168 -349.922394) (xy 95.20634 -349.970022) (xy 95.231914 -350.022125) (xy 95.249298 -350.077501)
			(xy 95.258093 -350.134872) (xy 95.258123 -350.136475) (xy 95.382291 -350.136475) (xy 95.386025 -350.083218)
			(xy 95.397148 -350.031001) (xy 95.415441 -349.980845) (xy 95.440549 -349.933729) (xy 95.471979 -349.890574)
			(xy 95.50912 -349.852222) (xy 95.529908 -349.83547) (xy 95.541751 -349.825615) (xy 95.559264 -349.800279)
			(xy 95.568434 -349.770875) (xy 95.568426 -349.740076) (xy 95.559243 -349.710677) (xy 95.541717 -349.685349)
			(xy 95.529908 -349.67545) (xy 95.50745 -349.657229) (xy 95.467713 -349.615216) (xy 95.434771 -349.567687)
			(xy 95.409378 -349.515732) (xy 95.392116 -349.460539) (xy 95.383381 -349.403374) (xy 95.382842 -349.37446)
			(xy 95.383218 -349.347204) (xy 95.390982 -349.293247) (xy 95.406345 -349.240945) (xy 95.428996 -349.191361)
			(xy 95.458473 -349.145506) (xy 95.494176 -349.104312) (xy 95.535378 -349.068619) (xy 95.58124 -349.039153)
			(xy 95.630829 -349.016514) (xy 95.683135 -349.001162) (xy 95.737094 -348.993411) (xy 95.76435 -348.992952)
			(xy 95.793267 -348.993486) (xy 95.850438 -349.002209) (xy 95.905637 -349.019463) (xy 95.9576 -349.044851)
			(xy 96.005134 -349.077793) (xy 96.04715 -349.117533) (xy 96.06534 -349.140018) (xy 96.075237 -349.151823)
			(xy 96.100561 -349.169342) (xy 96.129954 -349.178518) (xy 96.160746 -349.178518) (xy 96.190139 -349.169342)
			(xy 96.215463 -349.151823) (xy 96.22536 -349.140018) (xy 96.243578 -349.117557) (xy 96.285592 -349.07782)
			(xy 96.333121 -349.044878) (xy 96.385077 -349.019485) (xy 96.44027 -349.002224) (xy 96.497436 -348.99349)
			(xy 96.52635 -348.992952) (xy 96.5536 -348.993502) (xy 96.607546 -349.001251) (xy 96.659839 -349.016598)
			(xy 96.709417 -349.039232) (xy 96.755268 -349.068691) (xy 96.79646 -349.104376) (xy 96.832155 -349.14556)
			(xy 96.861625 -349.191404) (xy 96.88427 -349.240976) (xy 96.89963 -349.293266) (xy 96.907392 -349.34721)
			(xy 96.907858 -349.37446) (xy 96.907327 -349.403377) (xy 96.898603 -349.460548) (xy 96.881348 -349.515747)
			(xy 96.855959 -349.567709) (xy 96.823017 -349.615243) (xy 96.783277 -349.65726) (xy 96.760792 -349.67545)
			(xy 96.749029 -349.685392) (xy 96.731514 -349.710704) (xy 96.722336 -349.740085) (xy 96.722329 -349.770866)
			(xy 96.731493 -349.800251) (xy 96.748995 -349.825572) (xy 96.760792 -349.83547) (xy 96.781538 -349.852269)
			(xy 96.818672 -349.890615) (xy 96.850097 -349.933763) (xy 96.875201 -349.980871) (xy 96.893491 -350.031019)
			(xy 96.904612 -350.083227) (xy 96.908345 -350.136475) (xy 96.904619 -350.189724) (xy 96.893505 -350.241934)
			(xy 96.875221 -350.292084) (xy 96.850124 -350.339195) (xy 96.818704 -350.382347) (xy 96.781574 -350.420698)
			(xy 96.760792 -350.43745) (xy 96.749029 -350.447392) (xy 96.731514 -350.472704) (xy 96.722336 -350.502085)
			(xy 96.722329 -350.532866) (xy 96.731493 -350.562251) (xy 96.748995 -350.587572) (xy 96.760792 -350.59747)
			(xy 96.783259 -350.61568) (xy 96.822996 -350.657696) (xy 96.855937 -350.705226) (xy 96.881328 -350.757184)
			(xy 96.898588 -350.812378) (xy 96.907321 -350.869545) (xy 96.907858 -350.89846) (xy 96.907407 -350.925714)
			(xy 96.899655 -350.979668) (xy 96.884301 -351.031969) (xy 96.86166 -351.081553) (xy 96.832191 -351.127408)
			(xy 96.796496 -351.168603) (xy 96.7553 -351.204297) (xy 96.709444 -351.233764) (xy 96.65986 -351.256405)
			(xy 96.607558 -351.271757) (xy 96.553604 -351.279508) (xy 96.52635 -351.279968) (xy 96.497434 -351.279426)
			(xy 96.440263 -351.270704) (xy 96.385064 -351.253451) (xy 96.333102 -351.228064) (xy 96.285568 -351.195124)
			(xy 96.24355 -351.155386) (xy 96.22536 -351.132902) (xy 96.215463 -351.121097) (xy 96.190139 -351.103578)
			(xy 96.160746 -351.094402) (xy 96.129954 -351.094402) (xy 96.100561 -351.103578) (xy 96.075237 -351.121097)
			(xy 96.06534 -351.132902) (xy 96.047127 -351.155367) (xy 96.005112 -351.195103) (xy 95.957581 -351.228044)
			(xy 95.905624 -351.253436) (xy 95.850431 -351.270696) (xy 95.793265 -351.27943) (xy 95.76435 -351.279968)
			(xy 95.737097 -351.279498) (xy 95.683144 -351.271747) (xy 95.630844 -351.256395) (xy 95.581261 -351.233756)
			(xy 95.535406 -351.204289) (xy 95.494211 -351.168596) (xy 95.458517 -351.127402) (xy 95.429049 -351.081548)
			(xy 95.406408 -351.031966) (xy 95.391055 -350.979666) (xy 95.383303 -350.925713) (xy 95.382842 -350.89846)
			(xy 95.383387 -350.869544) (xy 95.392108 -350.812373) (xy 95.40936 -350.757174) (xy 95.434746 -350.705212)
			(xy 95.467686 -350.657678) (xy 95.507424 -350.61566) (xy 95.529908 -350.59747) (xy 95.541751 -350.587615)
			(xy 95.559264 -350.562279) (xy 95.568434 -350.532875) (xy 95.568426 -350.502076) (xy 95.559243 -350.472677)
			(xy 95.541717 -350.447349) (xy 95.529908 -350.43745) (xy 95.509083 -350.420745) (xy 95.471948 -350.382388)
			(xy 95.440522 -350.339229) (xy 95.415421 -350.29211) (xy 95.397134 -350.241951) (xy 95.386018 -350.189733)
			(xy 95.382291 -350.136475) (xy 95.258123 -350.136475) (xy 95.258636 -350.163892) (xy 95.25815 -350.191143)
			(xy 95.250394 -350.245091) (xy 95.235039 -350.297386) (xy 95.212397 -350.346963) (xy 95.182931 -350.392813)
			(xy 95.14724 -350.434004) (xy 95.106049 -350.469695) (xy 95.060199 -350.499161) (xy 95.010622 -350.521803)
			(xy 94.958327 -350.537158) (xy 94.904379 -350.544914) (xy 94.849877 -350.544914) (xy 94.795929 -350.537158)
			(xy 94.743634 -350.521803) (xy 94.694057 -350.499161) (xy 94.648207 -350.469695) (xy 94.607016 -350.434004)
			(xy 94.571325 -350.392813) (xy 94.541859 -350.346963) (xy 94.519217 -350.297386) (xy 94.503862 -350.245091)
			(xy 94.496106 -350.191143) (xy 94.49562 -350.163892) (xy 94.496134 -350.134447) (xy 94.50521 -350.076261)
			(xy 94.523114 -350.020159) (xy 94.549422 -349.967472) (xy 94.583509 -349.91945) (xy 94.624567 -349.877233)
			(xy 94.647766 -349.859092) (xy 94.65823 -349.850724) (xy 94.67474 -349.829634) (xy 94.685196 -349.804975)
			(xy 94.688878 -349.778445) (xy 94.685532 -349.751871) (xy 94.675388 -349.727082) (xy 94.659146 -349.705784)
			(xy 94.648782 -349.697294) (xy 94.63008 -349.682385) (xy 94.596195 -349.648631) (xy 94.581218 -349.629984)
			(xy 94.571321 -349.618179) (xy 94.545997 -349.60066) (xy 94.516604 -349.591484) (xy 94.485812 -349.591484)
			(xy 94.456419 -349.60066) (xy 94.431095 -349.618179) (xy 94.421198 -349.629984) (xy 94.403004 -349.652465)
			(xy 94.360985 -349.692201) (xy 94.313451 -349.725141) (xy 94.26149 -349.75053) (xy 94.206293 -349.767786)
			(xy 94.149124 -349.776515) (xy 94.120208 -349.77705) (xy 94.091642 -349.776476) (xy 94.03515 -349.767952)
			(xy 93.980557 -349.751107) (xy 93.929083 -349.726318) (xy 93.881876 -349.694137) (xy 93.83999 -349.655284)
			(xy 93.821758 -349.633286) (xy 93.812126 -349.622102) (xy 93.787903 -349.605262) (xy 93.75988 -349.596045)
			(xy 93.730391 -349.595217) (xy 93.701895 -349.602849) (xy 93.676767 -349.618304) (xy 93.666564 -349.628968)
			(xy 93.648379 -349.648569) (xy 93.607499 -349.683029) (xy 93.562209 -349.711445) (xy 93.513395 -349.73326)
			(xy 93.462014 -349.748047) (xy 93.409071 -349.755516) (xy 93.382338 -349.755968) (xy 93.353422 -349.755435)
			(xy 93.29625 -349.74671) (xy 93.241051 -349.729456) (xy 93.189089 -349.704068) (xy 93.141555 -349.671126)
			(xy 93.099538 -349.631387) (xy 93.081348 -349.608902) (xy 93.071451 -349.597097) (xy 93.046127 -349.579578)
			(xy 93.016734 -349.570402) (xy 92.985942 -349.570402) (xy 92.956549 -349.579578) (xy 92.931225 -349.597097)
			(xy 92.921328 -349.608902) (xy 92.904575 -349.629685) (xy 92.866221 -349.666815) (xy 92.823067 -349.698237)
			(xy 92.775953 -349.723336) (xy 92.725801 -349.741622) (xy 92.67359 -349.752739) (xy 92.620338 -349.756469)
			(xy 92.567086 -349.752739) (xy 92.514875 -349.741622) (xy 92.464723 -349.723336) (xy 92.417609 -349.698237)
			(xy 92.374455 -349.666815) (xy 92.336101 -349.629685) (xy 92.319348 -349.608902) (xy 92.309451 -349.597097)
			(xy 92.284127 -349.579578) (xy 92.254734 -349.570402) (xy 92.223942 -349.570402) (xy 92.194549 -349.579578)
			(xy 92.169225 -349.597097) (xy 92.159328 -349.608902) (xy 92.142575 -349.629685) (xy 92.104221 -349.666815)
			(xy 92.061067 -349.698237) (xy 92.013953 -349.723336) (xy 91.963801 -349.741622) (xy 91.91159 -349.752739)
			(xy 91.858338 -349.756469) (xy 91.805086 -349.752739) (xy 91.752875 -349.741622) (xy 91.702723 -349.723336)
			(xy 91.655609 -349.698237) (xy 91.612455 -349.666815) (xy 91.574101 -349.629685) (xy 91.557348 -349.608902)
			(xy 91.547451 -349.597097) (xy 91.522127 -349.579578) (xy 91.492734 -349.570402) (xy 91.461942 -349.570402)
			(xy 91.432549 -349.579578) (xy 91.407225 -349.597097) (xy 91.397328 -349.608902) (xy 91.382552 -349.627303)
			(xy 91.34918 -349.660673) (xy 91.33078 -349.67545) (xy 91.319018 -349.685393) (xy 91.301506 -349.710705)
			(xy 91.292329 -349.740086) (xy 91.292321 -349.770865) (xy 91.301484 -349.80025) (xy 91.318984 -349.825571)
			(xy 91.33078 -349.83547) (xy 91.353245 -349.853683) (xy 91.392982 -349.895698) (xy 91.425924 -349.943228)
			(xy 91.451316 -349.995185) (xy 91.468576 -350.050379) (xy 91.477309 -350.107545) (xy 91.477846 -350.13646)
			(xy 91.47736 -350.163711) (xy 91.469604 -350.217659) (xy 91.454249 -350.269954) (xy 91.431607 -350.319531)
			(xy 91.402141 -350.365381) (xy 91.36645 -350.406572) (xy 91.325259 -350.442263) (xy 91.279409 -350.471729)
			(xy 91.229832 -350.494371) (xy 91.177537 -350.509726) (xy 91.123589 -350.517482) (xy 91.069087 -350.517482)
			(xy 91.015139 -350.509726) (xy 90.962844 -350.494371) (xy 90.913267 -350.471729) (xy 90.867417 -350.442263)
			(xy 90.826226 -350.406572) (xy 90.790535 -350.365381) (xy 90.761069 -350.319531) (xy 90.738427 -350.269954)
			(xy 90.723072 -350.217659) (xy 90.715316 -350.163711) (xy 90.71483 -350.13646) (xy 90.512473 -350.13646)
			(xy 90.510201 -350.168874) (xy 90.499081 -350.221089) (xy 90.480791 -350.271244) (xy 90.455688 -350.318359)
			(xy 90.424262 -350.361515) (xy 90.387127 -350.399869) (xy 90.366342 -350.416622) (xy 90.354502 -350.426483)
			(xy 90.33698 -350.451815) (xy 90.327805 -350.481219) (xy 90.327811 -350.512021) (xy 90.336997 -350.541421)
			(xy 90.354529 -350.566746) (xy 90.366342 -350.576642) (xy 90.388854 -350.594799) (xy 90.428586 -350.636827)
			(xy 90.46152 -350.684369) (xy 90.486903 -350.736337) (xy 90.504154 -350.79154) (xy 90.512876 -350.848714)
			(xy 90.513408 -350.877632) (xy 90.512952 -350.904884) (xy 90.505191 -350.958833) (xy 90.489832 -351.011128)
			(xy 90.467187 -351.060705) (xy 90.437717 -351.106556) (xy 90.402023 -351.147746) (xy 90.36083 -351.183437)
			(xy 90.314977 -351.212902) (xy 90.265398 -351.235543) (xy 90.213102 -351.250898) (xy 90.159152 -351.258654)
			(xy 90.1319 -351.25914) (xy 90.102982 -351.258644) (xy 90.045809 -351.249914) (xy 89.990608 -351.232653)
			(xy 89.938646 -351.207257) (xy 89.891113 -351.174308) (xy 89.849098 -351.134562) (xy 89.83091 -351.112074)
			(xy 89.821013 -351.100269) (xy 89.795689 -351.08275) (xy 89.766296 -351.073574) (xy 89.735504 -351.073574)
			(xy 89.706111 -351.08275) (xy 89.680787 -351.100269) (xy 89.67089 -351.112074) (xy 89.652698 -351.134557)
			(xy 89.610679 -351.174293) (xy 89.563145 -351.207233) (xy 89.511184 -351.232622) (xy 89.455986 -351.249878)
			(xy 89.398816 -351.258606) (xy 89.3699 -351.25914) (xy 89.342694 -351.258661) (xy 89.288835 -351.250917)
			(xy 89.236622 -351.235599) (xy 89.187116 -351.21302) (xy 89.141319 -351.183636) (xy 89.100161 -351.148044)
			(xy 89.064477 -351.106966) (xy 89.03499 -351.061235) (xy 89.0123 -351.011779) (xy 88.996866 -350.959601)
			(xy 88.992456 -350.93275) (xy 88.989721 -350.91765) (xy 88.976444 -350.889996) (xy 88.955567 -350.867522)
			(xy 88.928965 -350.852247) (xy 88.89903 -350.845546) (xy 88.868455 -350.84802) (xy 88.854026 -350.853248)
			(xy 88.831378 -350.861945) (xy 88.784423 -350.874154) (xy 88.736298 -350.880304) (xy 88.71204 -350.88068)
			(xy 88.684787 -350.880207) (xy 88.630835 -350.872455) (xy 88.578535 -350.857103) (xy 88.528954 -350.834463)
			(xy 88.483099 -350.804996) (xy 88.441905 -350.769303) (xy 88.406211 -350.728111) (xy 88.376743 -350.682257)
			(xy 88.354101 -350.632676) (xy 88.338747 -350.580377) (xy 88.330993 -350.526425) (xy 88.330532 -350.499172)
			(xy 83.619351 -350.499172) (xy 83.61707 -350.500695) (xy 83.570902 -350.519805) (xy 83.521895 -350.529548)
			(xy 83.496912 -350.53016) (xy 77.295502 -350.53016) (xy 77.288136 -350.57207) (xy 77.283004 -350.598181)
			(xy 77.266442 -350.648751) (xy 77.243016 -350.69653) (xy 77.213181 -350.740593) (xy 77.177516 -350.780084)
			(xy 77.13671 -350.814239) (xy 77.091556 -350.842395) (xy 77.04293 -350.864007) (xy 76.991772 -350.878655)
			(xy 76.939076 -350.886056) (xy 76.91247 -350.886522) (xy 76.885219 -350.88605) (xy 76.831271 -350.87829)
			(xy 76.778977 -350.862932) (xy 76.729401 -350.840288) (xy 76.683551 -350.81082) (xy 76.642362 -350.775127)
			(xy 76.60667 -350.733936) (xy 76.577204 -350.688085) (xy 76.554563 -350.638508) (xy 76.539207 -350.586213)
			(xy 76.531449 -350.532265) (xy 76.530962 -350.505014) (xy 76.40701 -350.505014) (xy 76.40701 -350.7486)
			(xy 76.421742 -350.76384) (xy 76.679552 -351.021396) (xy 76.949674 -351.700592) (xy 103.994964 -351.700592)
			(xy 103.999035 -351.64497) (xy 104.011161 -351.590533) (xy 104.031084 -351.538442) (xy 104.05838 -351.489807)
			(xy 104.092466 -351.445664) (xy 104.132615 -351.406955) (xy 104.177973 -351.374504) (xy 104.227573 -351.349003)
			(xy 104.280357 -351.330996) (xy 104.3352 -351.320866) (xy 104.390934 -351.318829) (xy 104.446371 -351.324929)
			(xy 104.500328 -351.339035) (xy 104.551657 -351.360847) (xy 104.599263 -351.389901) (xy 104.642131 -351.425576)
			(xy 104.679348 -351.467113) (xy 104.710121 -351.513626) (xy 104.733793 -351.564123) (xy 104.749861 -351.61753)
			(xy 104.757981 -351.672706) (xy 104.75849 -351.700592) (xy 104.757981 -351.728478) (xy 104.749861 -351.783654)
			(xy 104.733793 -351.837061) (xy 104.721086 -351.864168) (xy 104.858564 -351.864168) (xy 104.862635 -351.808546)
			(xy 104.874761 -351.754109) (xy 104.894684 -351.702018) (xy 104.92198 -351.653383) (xy 104.956066 -351.60924)
			(xy 104.996215 -351.570531) (xy 105.041573 -351.53808) (xy 105.091173 -351.512579) (xy 105.143957 -351.494572)
			(xy 105.1988 -351.484442) (xy 105.254534 -351.482405) (xy 105.309971 -351.488505) (xy 105.357567 -351.500948)
			(xy 105.871262 -351.500948) (xy 105.875333 -351.445326) (xy 105.887459 -351.390889) (xy 105.907382 -351.338798)
			(xy 105.934678 -351.290163) (xy 105.968764 -351.24602) (xy 106.008913 -351.207311) (xy 106.054271 -351.17486)
			(xy 106.103871 -351.149359) (xy 106.156655 -351.131352) (xy 106.211498 -351.121222) (xy 106.267232 -351.119185)
			(xy 106.322669 -351.125285) (xy 106.376626 -351.139391) (xy 106.427955 -351.161203) (xy 106.475561 -351.190257)
			(xy 106.518429 -351.225932) (xy 106.555646 -351.267469) (xy 106.586419 -351.313982) (xy 106.610091 -351.364479)
			(xy 106.626159 -351.417886) (xy 106.634279 -351.473062) (xy 106.634788 -351.500948) (xy 106.887262 -351.500948)
			(xy 106.891333 -351.445326) (xy 106.903459 -351.390889) (xy 106.923382 -351.338798) (xy 106.950678 -351.290163)
			(xy 106.984764 -351.24602) (xy 107.024913 -351.207311) (xy 107.070271 -351.17486) (xy 107.119871 -351.149359)
			(xy 107.172655 -351.131352) (xy 107.227498 -351.121222) (xy 107.283232 -351.119185) (xy 107.338669 -351.125285)
			(xy 107.392626 -351.139391) (xy 107.443955 -351.161203) (xy 107.491561 -351.190257) (xy 107.534429 -351.225932)
			(xy 107.571646 -351.267469) (xy 107.602419 -351.313982) (xy 107.626091 -351.364479) (xy 107.642159 -351.417886)
			(xy 107.650279 -351.473062) (xy 107.650788 -351.500948) (xy 107.903262 -351.500948) (xy 107.907333 -351.445326)
			(xy 107.919459 -351.390889) (xy 107.939382 -351.338798) (xy 107.966678 -351.290163) (xy 108.000764 -351.24602)
			(xy 108.040913 -351.207311) (xy 108.086271 -351.17486) (xy 108.135871 -351.149359) (xy 108.188655 -351.131352)
			(xy 108.243498 -351.121222) (xy 108.299232 -351.119185) (xy 108.354669 -351.125285) (xy 108.408626 -351.139391)
			(xy 108.459955 -351.161203) (xy 108.507561 -351.190257) (xy 108.550429 -351.225932) (xy 108.587646 -351.267469)
			(xy 108.618419 -351.313982) (xy 108.642091 -351.364479) (xy 108.658159 -351.417886) (xy 108.666279 -351.473062)
			(xy 108.666788 -351.500948) (xy 108.919262 -351.500948) (xy 108.923333 -351.445326) (xy 108.935459 -351.390889)
			(xy 108.955382 -351.338798) (xy 108.982678 -351.290163) (xy 109.016764 -351.24602) (xy 109.056913 -351.207311)
			(xy 109.102271 -351.17486) (xy 109.151871 -351.149359) (xy 109.204655 -351.131352) (xy 109.259498 -351.121222)
			(xy 109.315232 -351.119185) (xy 109.370669 -351.125285) (xy 109.424626 -351.139391) (xy 109.475955 -351.161203)
			(xy 109.523561 -351.190257) (xy 109.566429 -351.225932) (xy 109.603646 -351.267469) (xy 109.634419 -351.313982)
			(xy 109.658091 -351.364479) (xy 109.674159 -351.417886) (xy 109.680028 -351.457768) (xy 111.131602 -351.457768)
			(xy 111.135673 -351.402146) (xy 111.147799 -351.347709) (xy 111.167722 -351.295618) (xy 111.195018 -351.246983)
			(xy 111.229104 -351.20284) (xy 111.269253 -351.164131) (xy 111.314611 -351.13168) (xy 111.364211 -351.106179)
			(xy 111.416995 -351.088172) (xy 111.471838 -351.078042) (xy 111.527572 -351.076005) (xy 111.583009 -351.082105)
			(xy 111.636966 -351.096211) (xy 111.688295 -351.118023) (xy 111.735901 -351.147077) (xy 111.778769 -351.182752)
			(xy 111.815986 -351.224289) (xy 111.846759 -351.270802) (xy 111.870431 -351.321299) (xy 111.886499 -351.374706)
			(xy 111.894619 -351.429882) (xy 111.895128 -351.457768) (xy 111.894619 -351.485654) (xy 111.886499 -351.54083)
			(xy 111.870431 -351.594237) (xy 111.846759 -351.644734) (xy 111.815986 -351.691247) (xy 111.778769 -351.732784)
			(xy 111.735901 -351.768459) (xy 111.688295 -351.797513) (xy 111.636966 -351.819325) (xy 111.583009 -351.833431)
			(xy 111.527572 -351.839531) (xy 111.471838 -351.837494) (xy 111.416995 -351.827364) (xy 111.364211 -351.809357)
			(xy 111.314611 -351.783856) (xy 111.269253 -351.751405) (xy 111.229104 -351.712696) (xy 111.195018 -351.668553)
			(xy 111.167722 -351.619918) (xy 111.147799 -351.567827) (xy 111.135673 -351.51339) (xy 111.131602 -351.457768)
			(xy 109.680028 -351.457768) (xy 109.682279 -351.473062) (xy 109.682788 -351.500948) (xy 109.682279 -351.528834)
			(xy 109.674159 -351.58401) (xy 109.658091 -351.637417) (xy 109.634419 -351.687914) (xy 109.603646 -351.734427)
			(xy 109.566429 -351.775964) (xy 109.523561 -351.811639) (xy 109.475955 -351.840693) (xy 109.424626 -351.862505)
			(xy 109.370669 -351.876611) (xy 109.315232 -351.882711) (xy 109.259498 -351.880674) (xy 109.204655 -351.870544)
			(xy 109.151871 -351.852537) (xy 109.102271 -351.827036) (xy 109.056913 -351.794585) (xy 109.016764 -351.755876)
			(xy 108.982678 -351.711733) (xy 108.955382 -351.663098) (xy 108.935459 -351.611007) (xy 108.923333 -351.55657)
			(xy 108.919262 -351.500948) (xy 108.666788 -351.500948) (xy 108.666279 -351.528834) (xy 108.658159 -351.58401)
			(xy 108.642091 -351.637417) (xy 108.618419 -351.687914) (xy 108.587646 -351.734427) (xy 108.550429 -351.775964)
			(xy 108.507561 -351.811639) (xy 108.459955 -351.840693) (xy 108.408626 -351.862505) (xy 108.354669 -351.876611)
			(xy 108.299232 -351.882711) (xy 108.243498 -351.880674) (xy 108.188655 -351.870544) (xy 108.135871 -351.852537)
			(xy 108.086271 -351.827036) (xy 108.040913 -351.794585) (xy 108.000764 -351.755876) (xy 107.966678 -351.711733)
			(xy 107.939382 -351.663098) (xy 107.919459 -351.611007) (xy 107.907333 -351.55657) (xy 107.903262 -351.500948)
			(xy 107.650788 -351.500948) (xy 107.650279 -351.528834) (xy 107.642159 -351.58401) (xy 107.626091 -351.637417)
			(xy 107.602419 -351.687914) (xy 107.571646 -351.734427) (xy 107.534429 -351.775964) (xy 107.491561 -351.811639)
			(xy 107.443955 -351.840693) (xy 107.392626 -351.862505) (xy 107.338669 -351.876611) (xy 107.283232 -351.882711)
			(xy 107.227498 -351.880674) (xy 107.172655 -351.870544) (xy 107.119871 -351.852537) (xy 107.070271 -351.827036)
			(xy 107.024913 -351.794585) (xy 106.984764 -351.755876) (xy 106.950678 -351.711733) (xy 106.923382 -351.663098)
			(xy 106.903459 -351.611007) (xy 106.891333 -351.55657) (xy 106.887262 -351.500948) (xy 106.634788 -351.500948)
			(xy 106.634279 -351.528834) (xy 106.626159 -351.58401) (xy 106.610091 -351.637417) (xy 106.586419 -351.687914)
			(xy 106.555646 -351.734427) (xy 106.518429 -351.775964) (xy 106.475561 -351.811639) (xy 106.427955 -351.840693)
			(xy 106.376626 -351.862505) (xy 106.322669 -351.876611) (xy 106.267232 -351.882711) (xy 106.211498 -351.880674)
			(xy 106.156655 -351.870544) (xy 106.103871 -351.852537) (xy 106.054271 -351.827036) (xy 106.008913 -351.794585)
			(xy 105.968764 -351.755876) (xy 105.934678 -351.711733) (xy 105.907382 -351.663098) (xy 105.887459 -351.611007)
			(xy 105.875333 -351.55657) (xy 105.871262 -351.500948) (xy 105.357567 -351.500948) (xy 105.363928 -351.502611)
			(xy 105.415257 -351.524423) (xy 105.462863 -351.553477) (xy 105.505731 -351.589152) (xy 105.542948 -351.630689)
			(xy 105.573721 -351.677202) (xy 105.597393 -351.727699) (xy 105.613461 -351.781106) (xy 105.621581 -351.836282)
			(xy 105.62209 -351.864168) (xy 105.621581 -351.892054) (xy 105.613461 -351.94723) (xy 105.597393 -352.000637)
			(xy 105.573721 -352.051134) (xy 105.542948 -352.097647) (xy 105.505731 -352.139184) (xy 105.462863 -352.174859)
			(xy 105.415257 -352.203913) (xy 105.363928 -352.225725) (xy 105.309971 -352.239831) (xy 105.254534 -352.245931)
			(xy 105.1988 -352.243894) (xy 105.143957 -352.233764) (xy 105.091173 -352.215757) (xy 105.041573 -352.190256)
			(xy 104.996215 -352.157805) (xy 104.956066 -352.119096) (xy 104.92198 -352.074953) (xy 104.894684 -352.026318)
			(xy 104.874761 -351.974227) (xy 104.862635 -351.91979) (xy 104.858564 -351.864168) (xy 104.721086 -351.864168)
			(xy 104.710121 -351.887558) (xy 104.679348 -351.934071) (xy 104.642131 -351.975608) (xy 104.599263 -352.011283)
			(xy 104.551657 -352.040337) (xy 104.500328 -352.062149) (xy 104.446371 -352.076255) (xy 104.390934 -352.082355)
			(xy 104.3352 -352.080318) (xy 104.280357 -352.070188) (xy 104.227573 -352.052181) (xy 104.177973 -352.02668)
			(xy 104.132615 -351.994229) (xy 104.092466 -351.95552) (xy 104.05838 -351.911377) (xy 104.031084 -351.862742)
			(xy 104.011161 -351.810651) (xy 103.999035 -351.756214) (xy 103.994964 -351.700592) (xy 76.949674 -351.700592)
			(xy 77.226363 -352.396298) (xy 110.560102 -352.396298) (xy 110.564173 -352.340676) (xy 110.576299 -352.286239)
			(xy 110.596222 -352.234148) (xy 110.623518 -352.185513) (xy 110.657604 -352.14137) (xy 110.697753 -352.102661)
			(xy 110.743111 -352.07021) (xy 110.792711 -352.044709) (xy 110.845495 -352.026702) (xy 110.900338 -352.016572)
			(xy 110.956072 -352.014535) (xy 111.011509 -352.020635) (xy 111.065466 -352.034741) (xy 111.116795 -352.056553)
			(xy 111.164401 -352.085607) (xy 111.207269 -352.121282) (xy 111.244486 -352.162819) (xy 111.275259 -352.209332)
			(xy 111.298931 -352.259829) (xy 111.314999 -352.313236) (xy 111.323119 -352.368412) (xy 111.323628 -352.396298)
			(xy 111.323119 -352.424184) (xy 111.314999 -352.47936) (xy 111.298931 -352.532767) (xy 111.275259 -352.583264)
			(xy 111.244486 -352.629777) (xy 111.207269 -352.671314) (xy 111.164401 -352.706989) (xy 111.116795 -352.736043)
			(xy 111.065466 -352.757855) (xy 111.011509 -352.771961) (xy 110.956072 -352.778061) (xy 110.900338 -352.776024)
			(xy 110.845495 -352.765894) (xy 110.792711 -352.747887) (xy 110.743111 -352.722386) (xy 110.697753 -352.689935)
			(xy 110.657604 -352.651226) (xy 110.623518 -352.607083) (xy 110.596222 -352.558448) (xy 110.576299 -352.506357)
			(xy 110.564173 -352.45192) (xy 110.560102 -352.396298) (xy 77.226363 -352.396298) (xy 77.400013 -352.832924)
			(xy 112.35385 -352.832924) (xy 112.357921 -352.777302) (xy 112.370047 -352.722865) (xy 112.38997 -352.670774)
			(xy 112.417266 -352.622139) (xy 112.451352 -352.577996) (xy 112.491501 -352.539287) (xy 112.536859 -352.506836)
			(xy 112.586459 -352.481335) (xy 112.639243 -352.463328) (xy 112.694086 -352.453198) (xy 112.74982 -352.451161)
			(xy 112.805257 -352.457261) (xy 112.859214 -352.471367) (xy 112.910543 -352.493179) (xy 112.958149 -352.522233)
			(xy 113.001017 -352.557908) (xy 113.038234 -352.599445) (xy 113.069007 -352.645958) (xy 113.092679 -352.696455)
			(xy 113.108747 -352.749862) (xy 113.116867 -352.805038) (xy 113.117376 -352.832924) (xy 113.116867 -352.86081)
			(xy 113.108747 -352.915986) (xy 113.092679 -352.969393) (xy 113.069007 -353.01989) (xy 113.038234 -353.066403)
			(xy 113.001017 -353.10794) (xy 112.958149 -353.143615) (xy 112.910543 -353.172669) (xy 112.859214 -353.194481)
			(xy 112.805257 -353.208587) (xy 112.74982 -353.214687) (xy 112.694086 -353.21265) (xy 112.639243 -353.20252)
			(xy 112.586459 -353.184513) (xy 112.536859 -353.159012) (xy 112.491501 -353.126561) (xy 112.451352 -353.087852)
			(xy 112.417266 -353.043709) (xy 112.38997 -352.995074) (xy 112.370047 -352.942983) (xy 112.357921 -352.888546)
			(xy 112.35385 -352.832924) (xy 77.400013 -352.832924) (xy 79.46644 -358.028748) (xy 81.432146 -359.994454)
			(xy 87.567516 -359.994454) (xy 87.568039 -359.964944) (xy 87.577109 -359.906626) (xy 87.595057 -359.850402)
			(xy 87.621454 -359.797615) (xy 87.655669 -359.749525) (xy 87.696885 -359.707282) (xy 87.72017 -359.689146)
			(xy 87.731669 -359.679895) (xy 87.749252 -359.65621) (xy 87.759335 -359.628487) (xy 87.761075 -359.59904)
			(xy 87.754328 -359.570324) (xy 87.739657 -359.544732) (xy 87.729314 -359.534206) (xy 87.710907 -359.516162)
			(xy 87.678669 -359.475943) (xy 87.652144 -359.431746) (xy 87.631817 -359.384378) (xy 87.618058 -359.334703)
			(xy 87.611119 -359.283627) (xy 87.610696 -359.257854) (xy 87.611135 -359.230601) (xy 87.618898 -359.176652)
			(xy 87.634259 -359.124356) (xy 87.656906 -359.074778) (xy 87.686377 -359.028928) (xy 87.722074 -358.987738)
			(xy 87.763268 -358.952047) (xy 87.809122 -358.922582) (xy 87.858703 -358.899942) (xy 87.911001 -358.884587)
			(xy 87.964951 -358.876831) (xy 87.992204 -358.876346) (xy 88.020942 -358.876882) (xy 88.077768 -358.885504)
			(xy 88.132658 -358.902552) (xy 88.18437 -358.92764) (xy 88.231734 -358.960201) (xy 88.253062 -358.97947)
			(xy 88.264929 -358.989692) (xy 88.293199 -359.003124) (xy 88.324209 -359.007369) (xy 88.35505 -359.002028)
			(xy 88.382827 -358.987604) (xy 88.394286 -358.97693) (xy 88.403382 -358.96806) (xy 88.422574 -358.951408)
			(xy 88.43264 -358.943656) (xy 88.444447 -358.933923) (xy 88.462142 -358.908978) (xy 88.471662 -358.879914)
			(xy 88.472154 -358.849335) (xy 88.463574 -358.81998) (xy 88.44669 -358.794479) (xy 88.43518 -358.784398)
			(xy 88.413773 -358.766185) (xy 88.376036 -358.724534) (xy 88.344817 -358.677798) (xy 88.320791 -358.626987)
			(xy 88.30448 -358.573202) (xy 88.296234 -358.517606) (xy 88.295734 -358.489504) (xy 88.296173 -358.463163)
			(xy 88.303428 -358.410981) (xy 88.317788 -358.360293) (xy 88.338978 -358.31206) (xy 88.366598 -358.267197)
			(xy 88.400123 -358.226557) (xy 88.438915 -358.190911) (xy 88.460326 -358.17556) (xy 88.472459 -358.166357)
			(xy 88.491238 -358.142411) (xy 88.502137 -358.113999) (xy 88.504189 -358.083637) (xy 88.497214 -358.054017)
			(xy 88.481828 -358.027762) (xy 88.470994 -358.017064) (xy 88.451748 -357.998917) (xy 88.417965 -357.958213)
			(xy 88.390127 -357.913234) (xy 88.368767 -357.864841) (xy 88.354294 -357.813962) (xy 88.346986 -357.761573)
			(xy 88.346534 -357.735124) (xy 88.347047 -357.707644) (xy 88.354936 -357.653254) (xy 88.370553 -357.600559)
			(xy 88.393575 -357.550654) (xy 88.423525 -357.504572) (xy 88.459782 -357.463268) (xy 88.501594 -357.427598)
			(xy 88.524588 -357.412544) (xy 88.536216 -357.404727) (xy 88.554933 -357.383886) (xy 88.567286 -357.358745)
			(xy 88.572344 -357.331193) (xy 88.569727 -357.303304) (xy 88.559632 -357.277174) (xy 88.542819 -357.254769)
			(xy 88.531954 -357.24592) (xy 88.509103 -357.227703) (xy 88.468635 -357.185548) (xy 88.435063 -357.137719)
			(xy 88.409171 -357.085333) (xy 88.391564 -357.029614) (xy 88.382653 -356.971862) (xy 88.382094 -356.942644)
			(xy 88.382629 -356.913474) (xy 88.391536 -356.855819) (xy 88.409119 -356.800192) (xy 88.434968 -356.747892)
			(xy 88.468479 -356.700137) (xy 88.508871 -356.658042) (xy 88.5317 -356.639876) (xy 88.54349 -356.630122)
			(xy 88.561192 -356.605185) (xy 88.570719 -356.576125) (xy 88.571214 -356.545548) (xy 88.562635 -356.516195)
			(xy 88.54575 -356.490697) (xy 88.53424 -356.480618) (xy 88.512834 -356.462404) (xy 88.475099 -356.420752)
			(xy 88.443881 -356.374015) (xy 88.419855 -356.323205) (xy 88.403543 -356.269421) (xy 88.395295 -356.213826)
			(xy 88.394794 -356.185724) (xy 88.395234 -356.15908) (xy 88.40264 -356.106308) (xy 88.417325 -356.055083)
			(xy 88.439004 -356.006404) (xy 88.467252 -355.961219) (xy 88.50152 -355.920409) (xy 88.521032 -355.90226)
			(xy 88.530713 -355.892925) (xy 88.545327 -355.870366) (xy 88.553537 -355.844771) (xy 88.554773 -355.81792)
			(xy 88.548948 -355.791679) (xy 88.536467 -355.767873) (xy 88.527636 -355.757734) (xy 88.508665 -355.736462)
			(xy 88.476607 -355.689336) (xy 88.451906 -355.637971) (xy 88.435109 -355.583507) (xy 88.42659 -355.527151)
			(xy 88.426036 -355.498654) (xy 88.426435 -355.4714) (xy 88.434199 -355.417446) (xy 88.449562 -355.365147)
			(xy 88.472212 -355.315567) (xy 88.501687 -355.269715) (xy 88.537388 -355.228524) (xy 88.578587 -355.192833)
			(xy 88.624446 -355.163369) (xy 88.674032 -355.140731) (xy 88.726335 -355.12538) (xy 88.78029 -355.117629)
			(xy 88.807544 -355.117146) (xy 88.834954 -355.117634) (xy 88.889209 -355.125473) (xy 88.941784 -355.140999)
			(xy 88.991595 -355.163892) (xy 89.037615 -355.193679) (xy 89.078897 -355.229748) (xy 89.097104 -355.250242)
			(xy 89.106461 -355.260357) (xy 89.12933 -355.275699) (xy 89.155469 -355.284364) (xy 89.182974 -355.285721)
			(xy 89.20984 -355.279669) (xy 89.234107 -355.266652) (xy 89.254008 -355.247617) (xy 89.261442 -355.236018)
			(xy 89.276312 -355.212088) (xy 89.31195 -355.168457) (xy 89.353619 -355.130542) (xy 89.400412 -355.099171)
			(xy 89.451312 -355.075025) (xy 89.50521 -355.058629) (xy 89.560934 -355.050342) (xy 89.589102 -355.049836)
			(xy 89.61802 -355.050339) (xy 89.675192 -355.05907) (xy 89.730392 -355.07633) (xy 89.782354 -355.101724)
			(xy 89.829887 -355.134671) (xy 89.871903 -355.174415) (xy 89.890092 -355.196902) (xy 89.899989 -355.208707)
			(xy 89.925313 -355.226226) (xy 89.954706 -355.235402) (xy 89.985498 -355.235402) (xy 90.014891 -355.226226)
			(xy 90.040215 -355.208707) (xy 90.050112 -355.196902) (xy 90.066865 -355.176119) (xy 90.105219 -355.138989)
			(xy 90.148373 -355.107567) (xy 90.195487 -355.082468) (xy 90.245639 -355.064182) (xy 90.29785 -355.053065)
			(xy 90.351102 -355.049335) (xy 90.404354 -355.053065) (xy 90.456565 -355.064182) (xy 90.506717 -355.082468)
			(xy 90.553831 -355.107567) (xy 90.596985 -355.138989) (xy 90.635339 -355.176119) (xy 90.652092 -355.196902)
			(xy 90.661989 -355.208707) (xy 90.687313 -355.226226) (xy 90.716706 -355.235402) (xy 90.747498 -355.235402)
			(xy 90.776891 -355.226226) (xy 90.802215 -355.208707) (xy 90.812112 -355.196902) (xy 90.830297 -355.174413)
			(xy 90.872318 -355.134678) (xy 90.919854 -355.10174) (xy 90.971816 -355.076352) (xy 91.027015 -355.059097)
			(xy 91.084186 -355.05037) (xy 91.113102 -355.049836) (xy 91.142411 -355.05037) (xy 91.200337 -355.059342)
			(xy 91.256208 -355.077074) (xy 91.308707 -355.103148) (xy 91.356596 -355.13695) (xy 91.398748 -355.177684)
			(xy 91.416886 -355.200712) (xy 91.426627 -355.212609) (xy 91.451624 -355.230485) (xy 91.48081 -355.240107)
			(xy 91.511537 -355.240603) (xy 91.541018 -355.231927) (xy 91.566578 -355.214866) (xy 91.576652 -355.203252)
			(xy 91.594896 -355.181695) (xy 91.636601 -355.143621) (xy 91.683463 -355.112111) (xy 91.734459 -355.087854)
			(xy 91.788474 -355.07138) (xy 91.844327 -355.063049) (xy 91.872562 -355.062536) (xy 91.901479 -355.063068)
			(xy 91.95865 -355.071792) (xy 92.013849 -355.089047) (xy 92.065811 -355.114436) (xy 92.113345 -355.147377)
			(xy 92.155362 -355.187117) (xy 92.173552 -355.209602) (xy 92.183449 -355.221407) (xy 92.208773 -355.238926)
			(xy 92.238166 -355.248102) (xy 92.268958 -355.248102) (xy 92.298351 -355.238926) (xy 92.323675 -355.221407)
			(xy 92.333572 -355.209602) (xy 92.350325 -355.188819) (xy 92.388679 -355.151689) (xy 92.431833 -355.120267)
			(xy 92.478947 -355.095168) (xy 92.529099 -355.076882) (xy 92.58131 -355.065765) (xy 92.634562 -355.062035)
			(xy 92.687814 -355.065765) (xy 92.740025 -355.076882) (xy 92.790177 -355.095168) (xy 92.837291 -355.120267)
			(xy 92.880445 -355.151689) (xy 92.918799 -355.188819) (xy 92.935552 -355.209602) (xy 92.945449 -355.221407)
			(xy 92.970773 -355.238926) (xy 93.000166 -355.248102) (xy 93.030958 -355.248102) (xy 93.060351 -355.238926)
			(xy 93.085675 -355.221407) (xy 93.095572 -355.209602) (xy 93.112325 -355.188819) (xy 93.150679 -355.151689)
			(xy 93.193833 -355.120267) (xy 93.240947 -355.095168) (xy 93.291099 -355.076882) (xy 93.34331 -355.065765)
			(xy 93.396562 -355.062035) (xy 93.449814 -355.065765) (xy 93.502025 -355.076882) (xy 93.552177 -355.095168)
			(xy 93.599291 -355.120267) (xy 93.642445 -355.151689) (xy 93.680799 -355.188819) (xy 93.697552 -355.209602)
			(xy 93.707449 -355.221407) (xy 93.732773 -355.238926) (xy 93.762166 -355.248102) (xy 93.792958 -355.248102)
			(xy 93.822351 -355.238926) (xy 93.847675 -355.221407) (xy 93.857572 -355.209602) (xy 93.874325 -355.188819)
			(xy 93.912679 -355.151689) (xy 93.955833 -355.120267) (xy 94.002947 -355.095168) (xy 94.053099 -355.076882)
			(xy 94.10531 -355.065765) (xy 94.158562 -355.062035) (xy 94.211814 -355.065765) (xy 94.264025 -355.076882)
			(xy 94.314177 -355.095168) (xy 94.361291 -355.120267) (xy 94.404445 -355.151689) (xy 94.442799 -355.188819)
			(xy 94.459552 -355.209602) (xy 94.469449 -355.221407) (xy 94.494773 -355.238926) (xy 94.524166 -355.248102)
			(xy 94.554958 -355.248102) (xy 94.584351 -355.238926) (xy 94.609675 -355.221407) (xy 94.619572 -355.209602)
			(xy 94.637779 -355.187132) (xy 94.679796 -355.147396) (xy 94.727327 -355.114456) (xy 94.779285 -355.089065)
			(xy 94.83448 -355.071805) (xy 94.891647 -355.063073) (xy 94.920562 -355.062536) (xy 94.946814 -355.062978)
			(xy 94.998823 -355.070162) (xy 95.049354 -355.084412) (xy 95.097454 -355.10546) (xy 95.142211 -355.132907)
			(xy 95.182779 -355.166235) (xy 95.218392 -355.204813) (xy 95.233744 -355.226112) (xy 95.242108 -355.237325)
			(xy 95.263733 -355.255051) (xy 95.289357 -355.266248) (xy 95.317056 -355.270076) (xy 95.344755 -355.266248)
			(xy 95.370379 -355.255051) (xy 95.392004 -355.237325) (xy 95.400368 -355.226112) (xy 95.415735 -355.204826)
			(xy 95.451355 -355.166259) (xy 95.491925 -355.132939) (xy 95.536679 -355.105493) (xy 95.584773 -355.084441)
			(xy 95.635297 -355.070179) (xy 95.6873 -355.062976) (xy 95.71355 -355.062536) (xy 95.742466 -355.063076)
			(xy 95.799637 -355.071799) (xy 95.854836 -355.089052) (xy 95.906798 -355.114439) (xy 95.954333 -355.147379)
			(xy 95.99635 -355.187118) (xy 96.01454 -355.209602) (xy 96.024437 -355.221407) (xy 96.049761 -355.238926)
			(xy 96.079154 -355.248102) (xy 96.109946 -355.248102) (xy 96.139339 -355.238926) (xy 96.164663 -355.221407)
			(xy 96.17456 -355.209602) (xy 96.192774 -355.187138) (xy 96.234789 -355.147402) (xy 96.282319 -355.11446)
			(xy 96.334276 -355.089068) (xy 96.389469 -355.071808) (xy 96.446635 -355.063074) (xy 96.47555 -355.062536)
			(xy 96.502804 -355.063002) (xy 96.556757 -355.070753) (xy 96.609057 -355.086105) (xy 96.65864 -355.108745)
			(xy 96.704496 -355.138212) (xy 96.74569 -355.173906) (xy 96.781384 -355.2151) (xy 96.810852 -355.260955)
			(xy 96.833493 -355.310537) (xy 96.848845 -355.362837) (xy 96.856598 -355.41679) (xy 96.857058 -355.444044)
			(xy 96.856516 -355.47296) (xy 96.847794 -355.530131) (xy 96.830542 -355.58533) (xy 96.805155 -355.637292)
			(xy 96.772215 -355.684827) (xy 96.732476 -355.726844) (xy 96.709992 -355.745034) (xy 96.698145 -355.754885)
			(xy 96.680632 -355.780222) (xy 96.671463 -355.809627) (xy 96.671471 -355.840427) (xy 96.680655 -355.869827)
			(xy 96.698182 -355.895155) (xy 96.709992 -355.905054) (xy 96.730821 -355.921754) (xy 96.767956 -355.960111)
			(xy 96.799382 -356.003272) (xy 96.824483 -356.050391) (xy 96.84277 -356.10055) (xy 96.853885 -356.152769)
			(xy 96.857612 -356.206027) (xy 96.853878 -356.259285) (xy 96.842755 -356.311502) (xy 96.824461 -356.361658)
			(xy 96.799353 -356.408774) (xy 96.767921 -356.45193) (xy 96.73078 -356.490282) (xy 96.709992 -356.507034)
			(xy 96.698145 -356.516885) (xy 96.680632 -356.542222) (xy 96.671463 -356.571627) (xy 96.671471 -356.602427)
			(xy 96.680655 -356.631827) (xy 96.698182 -356.657155) (xy 96.709992 -356.667054) (xy 96.730821 -356.683754)
			(xy 96.767956 -356.722111) (xy 96.799382 -356.765272) (xy 96.824483 -356.812391) (xy 96.84277 -356.86255)
			(xy 96.853885 -356.914769) (xy 96.857612 -356.968027) (xy 96.853878 -357.021285) (xy 96.842755 -357.073502)
			(xy 96.824461 -357.123658) (xy 96.799353 -357.170774) (xy 96.767921 -357.21393) (xy 96.73078 -357.252282)
			(xy 96.709992 -357.269034) (xy 96.698145 -357.278885) (xy 96.680632 -357.304222) (xy 96.671463 -357.333627)
			(xy 96.671471 -357.364427) (xy 96.680655 -357.393827) (xy 96.698182 -357.419155) (xy 96.709992 -357.429054)
			(xy 96.730821 -357.445754) (xy 96.767956 -357.484111) (xy 96.799382 -357.527272) (xy 96.824483 -357.574391)
			(xy 96.84277 -357.62455) (xy 96.853885 -357.676769) (xy 96.857612 -357.730027) (xy 96.853878 -357.783285)
			(xy 96.842755 -357.835502) (xy 96.824461 -357.885658) (xy 96.799353 -357.932774) (xy 96.767921 -357.97593)
			(xy 96.73078 -358.014282) (xy 96.709992 -358.031034) (xy 96.698145 -358.040885) (xy 96.680632 -358.066222)
			(xy 96.671463 -358.095627) (xy 96.671471 -358.126427) (xy 96.680655 -358.155827) (xy 96.698182 -358.181155)
			(xy 96.709992 -358.191054) (xy 96.730821 -358.207754) (xy 96.743913 -358.221277) (xy 103.496811 -358.221277)
			(xy 103.504564 -358.167319) (xy 103.519917 -358.115013) (xy 103.542559 -358.065425) (xy 103.572026 -358.019564)
			(xy 103.607721 -357.978364) (xy 103.648916 -357.942663) (xy 103.694772 -357.913188) (xy 103.744356 -357.890539)
			(xy 103.796659 -357.875177) (xy 103.850616 -357.867415) (xy 103.877872 -357.86695) (xy 103.894015 -357.867093)
			(xy 103.926189 -357.869764) (xy 103.942134 -357.872284) (xy 103.956157 -357.874251) (xy 103.9843 -357.871191)
			(xy 104.01052 -357.860522) (xy 104.032803 -357.843063) (xy 104.049435 -357.820157) (xy 104.059139 -357.793564)
			(xy 104.061168 -357.765328) (xy 104.05872 -357.75138) (xy 104.054913 -357.732111) (xy 104.050845 -357.693042)
			(xy 104.050592 -357.673402) (xy 104.051053 -357.646149) (xy 104.05881 -357.592198) (xy 104.074166 -357.539899)
			(xy 104.096808 -357.490319) (xy 104.126276 -357.444465) (xy 104.16197 -357.403272) (xy 104.203163 -357.367578)
			(xy 104.249016 -357.33811) (xy 104.298596 -357.315467) (xy 104.350894 -357.300111) (xy 104.404846 -357.292353)
			(xy 104.459352 -357.292353) (xy 104.513303 -357.30011) (xy 104.565601 -357.315466) (xy 104.615182 -357.338109)
			(xy 104.661035 -357.367577) (xy 104.702228 -357.40327) (xy 104.737922 -357.444463) (xy 104.767391 -357.490317)
			(xy 104.790033 -357.539897) (xy 104.805389 -357.592195) (xy 104.813147 -357.646146) (xy 104.813147 -357.700652)
			(xy 104.80539 -357.754604) (xy 104.790034 -357.806902) (xy 104.767391 -357.856482) (xy 104.737923 -357.902336)
			(xy 104.702229 -357.943529) (xy 104.661036 -357.979223) (xy 104.615183 -358.008691) (xy 104.565602 -358.031333)
			(xy 104.513304 -358.04669) (xy 104.459353 -358.054447) (xy 104.4321 -358.05491) (xy 104.415957 -358.054772)
			(xy 104.383783 -358.052097) (xy 104.367838 -358.049576) (xy 104.353814 -358.047629) (xy 104.325679 -358.050694)
			(xy 104.299465 -358.061365) (xy 104.277187 -358.07882) (xy 104.260555 -358.10172) (xy 104.250848 -358.128305)
			(xy 104.248811 -358.156533) (xy 104.251252 -358.17048) (xy 104.255053 -358.18975) (xy 104.259125 -358.228818)
			(xy 104.25938 -358.248458) (xy 104.25899 -358.275714) (xy 104.251238 -358.329672) (xy 104.235886 -358.381978)
			(xy 104.213246 -358.431566) (xy 104.183779 -358.477428) (xy 104.148086 -358.518629) (xy 104.106892 -358.554332)
			(xy 104.061036 -358.583808) (xy 104.011452 -358.606458) (xy 103.95915 -358.621821) (xy 103.905193 -358.629584)
			(xy 103.850681 -358.62959) (xy 103.796723 -358.621837) (xy 103.744418 -358.606484) (xy 103.694829 -358.583844)
			(xy 103.648968 -358.554376) (xy 103.607767 -358.518682) (xy 103.572066 -358.477488) (xy 103.54259 -358.431632)
			(xy 103.51994 -358.382048) (xy 103.504578 -358.329745) (xy 103.496815 -358.275789) (xy 103.496811 -358.221277)
			(xy 96.743913 -358.221277) (xy 96.767956 -358.246111) (xy 96.799382 -358.289272) (xy 96.824483 -358.336391)
			(xy 96.84277 -358.38655) (xy 96.853885 -358.438769) (xy 96.857612 -358.492027) (xy 96.853878 -358.545285)
			(xy 96.842755 -358.597502) (xy 96.824461 -358.647658) (xy 96.799353 -358.694774) (xy 96.767921 -358.73793)
			(xy 96.73078 -358.776282) (xy 96.709992 -358.793034) (xy 96.698145 -358.802885) (xy 96.680632 -358.828222)
			(xy 96.671463 -358.857627) (xy 96.671471 -358.888427) (xy 96.674997 -358.899714) (xy 98.910138 -358.899714)
			(xy 98.914209 -358.844092) (xy 98.926335 -358.789655) (xy 98.946258 -358.737564) (xy 98.973554 -358.688929)
			(xy 99.00764 -358.644786) (xy 99.047789 -358.606077) (xy 99.093147 -358.573626) (xy 99.142747 -358.548125)
			(xy 99.195531 -358.530118) (xy 99.250374 -358.519988) (xy 99.306108 -358.517951) (xy 99.361545 -358.524051)
			(xy 99.415502 -358.538157) (xy 99.466831 -358.559969) (xy 99.514437 -358.589023) (xy 99.557305 -358.624698)
			(xy 99.594522 -358.666235) (xy 99.625295 -358.712748) (xy 99.648967 -358.763245) (xy 99.665035 -358.816652)
			(xy 99.673155 -358.871828) (xy 99.673664 -358.899714) (xy 99.673155 -358.9276) (xy 99.665035 -358.982776)
			(xy 99.648967 -359.036183) (xy 99.625295 -359.08668) (xy 99.594522 -359.133193) (xy 99.557305 -359.17473)
			(xy 99.541355 -359.188004) (xy 104.05313 -359.188004) (xy 104.057201 -359.132382) (xy 104.069327 -359.077945)
			(xy 104.08925 -359.025854) (xy 104.116546 -358.977219) (xy 104.150632 -358.933076) (xy 104.190781 -358.894367)
			(xy 104.236139 -358.861916) (xy 104.285739 -358.836415) (xy 104.338523 -358.818408) (xy 104.393366 -358.808278)
			(xy 104.4491 -358.806241) (xy 104.504537 -358.812341) (xy 104.558494 -358.826447) (xy 104.609823 -358.848259)
			(xy 104.657429 -358.877313) (xy 104.700297 -358.912988) (xy 104.737514 -358.954525) (xy 104.768287 -359.001038)
			(xy 104.791959 -359.051535) (xy 104.808027 -359.104942) (xy 104.816147 -359.160118) (xy 104.816656 -359.188004)
			(xy 104.816147 -359.21589) (xy 104.808027 -359.271066) (xy 104.791959 -359.324473) (xy 104.768287 -359.37497)
			(xy 104.737514 -359.421483) (xy 104.700297 -359.46302) (xy 104.657429 -359.498695) (xy 104.609823 -359.527749)
			(xy 104.558494 -359.549561) (xy 104.504537 -359.563667) (xy 104.4491 -359.569767) (xy 104.393366 -359.56773)
			(xy 104.338523 -359.5576) (xy 104.285739 -359.539593) (xy 104.236139 -359.514092) (xy 104.190781 -359.481641)
			(xy 104.150632 -359.442932) (xy 104.116546 -359.398789) (xy 104.08925 -359.350154) (xy 104.069327 -359.298063)
			(xy 104.057201 -359.243626) (xy 104.05313 -359.188004) (xy 99.541355 -359.188004) (xy 99.514437 -359.210405)
			(xy 99.466831 -359.239459) (xy 99.415502 -359.261271) (xy 99.361545 -359.275377) (xy 99.306108 -359.281477)
			(xy 99.250374 -359.27944) (xy 99.195531 -359.26931) (xy 99.142747 -359.251303) (xy 99.093147 -359.225802)
			(xy 99.047789 -359.193351) (xy 99.00764 -359.154642) (xy 98.973554 -359.110499) (xy 98.946258 -359.061864)
			(xy 98.926335 -359.009773) (xy 98.914209 -358.955336) (xy 98.910138 -358.899714) (xy 96.674997 -358.899714)
			(xy 96.680655 -358.917827) (xy 96.698182 -358.943155) (xy 96.709992 -358.953054) (xy 96.732452 -358.971273)
			(xy 96.772189 -359.013287) (xy 96.805131 -359.060816) (xy 96.830523 -359.112772) (xy 96.847785 -359.167964)
			(xy 96.85652 -359.22513) (xy 96.857058 -359.254044) (xy 96.856686 -359.2813) (xy 96.848922 -359.335257)
			(xy 96.833557 -359.38756) (xy 96.810906 -359.437143) (xy 96.781429 -359.482999) (xy 96.745726 -359.524192)
			(xy 96.704523 -359.559885) (xy 96.658661 -359.589351) (xy 96.609072 -359.61199) (xy 96.556765 -359.627342)
			(xy 96.502806 -359.635093) (xy 96.47555 -359.635552) (xy 96.446634 -359.635016) (xy 96.389462 -359.626293)
			(xy 96.334263 -359.60904) (xy 96.282301 -359.583652) (xy 96.234767 -359.55071) (xy 96.19275 -359.510971)
			(xy 96.17456 -359.488486) (xy 96.164663 -359.476681) (xy 96.139339 -359.459162) (xy 96.109946 -359.449986)
			(xy 96.079154 -359.449986) (xy 96.049761 -359.459162) (xy 96.024437 -359.476681) (xy 96.01454 -359.488486)
			(xy 95.999762 -359.506885) (xy 95.966391 -359.540256) (xy 95.947992 -359.555034) (xy 95.936145 -359.564885)
			(xy 95.918632 -359.590222) (xy 95.909463 -359.619627) (xy 95.909471 -359.650427) (xy 95.918655 -359.679827)
			(xy 95.936182 -359.705155) (xy 95.947992 -359.715054) (xy 95.970452 -359.733273) (xy 96.010189 -359.775287)
			(xy 96.043131 -359.822816) (xy 96.068523 -359.874772) (xy 96.085785 -359.929964) (xy 96.094203 -359.985056)
			(xy 101.469696 -359.985056) (xy 101.473767 -359.929434) (xy 101.485893 -359.874997) (xy 101.505816 -359.822906)
			(xy 101.533112 -359.774271) (xy 101.567198 -359.730128) (xy 101.607347 -359.691419) (xy 101.652705 -359.658968)
			(xy 101.702305 -359.633467) (xy 101.755089 -359.61546) (xy 101.809932 -359.60533) (xy 101.865666 -359.603293)
			(xy 101.921103 -359.609393) (xy 101.97506 -359.623499) (xy 102.026389 -359.645311) (xy 102.073995 -359.674365)
			(xy 102.116863 -359.71004) (xy 102.15408 -359.751577) (xy 102.184853 -359.79809) (xy 102.208525 -359.848587)
			(xy 102.224593 -359.901994) (xy 102.232713 -359.95717) (xy 102.233222 -359.985056) (xy 102.232713 -360.012942)
			(xy 102.224593 -360.068118) (xy 102.208525 -360.121525) (xy 102.184853 -360.172022) (xy 102.155123 -360.216958)
			(xy 103.98963 -360.216958) (xy 103.993701 -360.161336) (xy 104.005827 -360.106899) (xy 104.02575 -360.054808)
			(xy 104.053046 -360.006173) (xy 104.087132 -359.96203) (xy 104.127281 -359.923321) (xy 104.172639 -359.89087)
			(xy 104.222239 -359.865369) (xy 104.275023 -359.847362) (xy 104.329866 -359.837232) (xy 104.3856 -359.835195)
			(xy 104.441037 -359.841295) (xy 104.494994 -359.855401) (xy 104.546323 -359.877213) (xy 104.593929 -359.906267)
			(xy 104.636797 -359.941942) (xy 104.674014 -359.983479) (xy 104.704787 -360.029992) (xy 104.728459 -360.080489)
			(xy 104.744527 -360.133896) (xy 104.752647 -360.189072) (xy 104.753156 -360.216958) (xy 104.752647 -360.244844)
			(xy 104.744527 -360.30002) (xy 104.728459 -360.353427) (xy 104.704787 -360.403924) (xy 104.674014 -360.450437)
			(xy 104.636797 -360.491974) (xy 104.593929 -360.527649) (xy 104.546323 -360.556703) (xy 104.494994 -360.578515)
			(xy 104.441037 -360.592621) (xy 104.3856 -360.598721) (xy 104.329866 -360.596684) (xy 104.275023 -360.586554)
			(xy 104.222239 -360.568547) (xy 104.172639 -360.543046) (xy 104.127281 -360.510595) (xy 104.087132 -360.471886)
			(xy 104.053046 -360.427743) (xy 104.02575 -360.379108) (xy 104.005827 -360.327017) (xy 103.993701 -360.27258)
			(xy 103.98963 -360.216958) (xy 102.155123 -360.216958) (xy 102.15408 -360.218535) (xy 102.116863 -360.260072)
			(xy 102.073995 -360.295747) (xy 102.026389 -360.324801) (xy 101.97506 -360.346613) (xy 101.921103 -360.360719)
			(xy 101.865666 -360.366819) (xy 101.809932 -360.364782) (xy 101.755089 -360.354652) (xy 101.702305 -360.336645)
			(xy 101.652705 -360.311144) (xy 101.607347 -360.278693) (xy 101.567198 -360.239984) (xy 101.533112 -360.195841)
			(xy 101.505816 -360.147206) (xy 101.485893 -360.095115) (xy 101.473767 -360.040678) (xy 101.469696 -359.985056)
			(xy 96.094203 -359.985056) (xy 96.09452 -359.98713) (xy 96.095058 -360.016044) (xy 96.094686 -360.0433)
			(xy 96.086922 -360.097257) (xy 96.071557 -360.14956) (xy 96.048906 -360.199143) (xy 96.019429 -360.244999)
			(xy 95.983726 -360.286192) (xy 95.942523 -360.321885) (xy 95.896661 -360.351351) (xy 95.847072 -360.37399)
			(xy 95.794765 -360.389342) (xy 95.740806 -360.397093) (xy 95.71355 -360.397552) (xy 95.687299 -360.397106)
			(xy 95.635289 -360.389924) (xy 95.584757 -360.375674) (xy 95.536658 -360.354627) (xy 95.491901 -360.32718)
			(xy 95.451332 -360.293853) (xy 95.415719 -360.255275) (xy 95.400368 -360.233976) (xy 95.392004 -360.222763)
			(xy 95.370379 -360.205037) (xy 95.344755 -360.19384) (xy 95.317056 -360.190012) (xy 95.289357 -360.19384)
			(xy 95.263733 -360.205037) (xy 95.242108 -360.222763) (xy 95.233744 -360.233976) (xy 95.218366 -360.255254)
			(xy 95.182748 -360.293821) (xy 95.14218 -360.327143) (xy 95.097428 -360.35459) (xy 95.049336 -360.375643)
			(xy 94.998813 -360.389907) (xy 94.946811 -360.397111) (xy 94.920562 -360.397552) (xy 94.892056 -360.397013)
			(xy 94.835678 -360.388524) (xy 94.781192 -360.37174) (xy 94.729809 -360.347035) (xy 94.682675 -360.31496)
			(xy 94.640838 -360.276228) (xy 94.62262 -360.254296) (xy 94.61269 -360.242603) (xy 94.587311 -360.225391)
			(xy 94.557967 -360.216484) (xy 94.527302 -360.216686) (xy 94.498078 -360.225979) (xy 94.472927 -360.243524)
			(xy 94.463108 -360.255312) (xy 94.444916 -360.277794) (xy 94.402896 -360.317529) (xy 94.355361 -360.350468)
			(xy 94.3034 -360.375856) (xy 94.248203 -360.393113) (xy 94.191034 -360.401843) (xy 94.162118 -360.402378)
			(xy 94.132824 -360.401817) (xy 94.074926 -360.392855) (xy 94.019076 -360.375156) (xy 93.966585 -360.349134)
			(xy 93.918685 -360.315399) (xy 93.876499 -360.274744) (xy 93.858334 -360.251756) (xy 93.849905 -360.241474)
			(xy 93.828885 -360.225217) (xy 93.804384 -360.214928) (xy 93.778059 -360.211303) (xy 93.751689 -360.214588)
			(xy 93.727058 -360.22456) (xy 93.70583 -360.240545) (xy 93.697298 -360.25074) (xy 93.679113 -360.27319)
			(xy 93.637118 -360.312862) (xy 93.589619 -360.345747) (xy 93.537703 -360.371091) (xy 93.482559 -360.388314)
			(xy 93.425448 -360.397022) (xy 93.396562 -360.397552) (xy 93.367646 -360.397008) (xy 93.310475 -360.388287)
			(xy 93.255276 -360.371035) (xy 93.203314 -360.345648) (xy 93.155779 -360.312709) (xy 93.113762 -360.27297)
			(xy 93.095572 -360.250486) (xy 93.085675 -360.238681) (xy 93.060351 -360.221162) (xy 93.030958 -360.211986)
			(xy 93.000166 -360.211986) (xy 92.970773 -360.221162) (xy 92.945449 -360.238681) (xy 92.935552 -360.250486)
			(xy 92.918799 -360.271269) (xy 92.880445 -360.308399) (xy 92.837291 -360.339821) (xy 92.790177 -360.36492)
			(xy 92.740025 -360.383206) (xy 92.687814 -360.394323) (xy 92.634562 -360.398053) (xy 92.58131 -360.394323)
			(xy 92.529099 -360.383206) (xy 92.478947 -360.36492) (xy 92.431833 -360.339821) (xy 92.388679 -360.308399)
			(xy 92.350325 -360.271269) (xy 92.333572 -360.250486) (xy 92.323675 -360.238681) (xy 92.298351 -360.221162)
			(xy 92.268958 -360.211986) (xy 92.238166 -360.211986) (xy 92.208773 -360.221162) (xy 92.183449 -360.238681)
			(xy 92.173552 -360.250486) (xy 92.156799 -360.271269) (xy 92.118445 -360.308399) (xy 92.075291 -360.339821)
			(xy 92.028177 -360.36492) (xy 91.978025 -360.383206) (xy 91.925814 -360.394323) (xy 91.872562 -360.398053)
			(xy 91.81931 -360.394323) (xy 91.767099 -360.383206) (xy 91.716947 -360.36492) (xy 91.669833 -360.339821)
			(xy 91.626679 -360.308399) (xy 91.588325 -360.271269) (xy 91.571572 -360.250486) (xy 91.561675 -360.238681)
			(xy 91.536351 -360.221162) (xy 91.506958 -360.211986) (xy 91.476166 -360.211986) (xy 91.446773 -360.221162)
			(xy 91.421449 -360.238681) (xy 91.411552 -360.250486) (xy 91.393328 -360.272942) (xy 91.351316 -360.312679)
			(xy 91.303788 -360.345622) (xy 91.251833 -360.371015) (xy 91.196641 -360.388277) (xy 91.139476 -360.397013)
			(xy 91.110562 -360.397552) (xy 91.084492 -360.397123) (xy 91.03284 -360.39001) (xy 90.982635 -360.375936)
			(xy 90.934812 -360.355161) (xy 90.890261 -360.328073) (xy 90.84981 -360.295175) (xy 90.81421 -360.25708)
			(xy 90.784126 -360.214495) (xy 90.771726 -360.191558) (xy 90.764913 -360.179441) (xy 90.745946 -360.159136)
			(xy 90.722205 -360.1447) (xy 90.695449 -360.137204) (xy 90.667663 -360.137204) (xy 90.640907 -360.1447)
			(xy 90.617166 -360.159136) (xy 90.598199 -360.179441) (xy 90.591386 -360.191558) (xy 90.578996 -360.214503)
			(xy 90.548924 -360.257102) (xy 90.51333 -360.295209) (xy 90.472879 -360.328114) (xy 90.428324 -360.355203)
			(xy 90.380494 -360.375973) (xy 90.330282 -360.390036) (xy 90.278622 -360.397131) (xy 90.25255 -360.397552)
			(xy 90.22617 -360.397098) (xy 90.173911 -360.389833) (xy 90.123153 -360.375435) (xy 90.074863 -360.354179)
			(xy 90.029964 -360.326471) (xy 89.989312 -360.292839) (xy 89.953683 -360.253925) (xy 89.938352 -360.232452)
			(xy 89.930165 -360.221296) (xy 89.908954 -360.203541) (xy 89.883751 -360.192138) (xy 89.856412 -360.187927)
			(xy 89.828946 -360.191218) (xy 89.803376 -360.201768) (xy 89.78158 -360.218802) (xy 89.772998 -360.229658)
			(xy 89.754877 -360.253141) (xy 89.712594 -360.294738) (xy 89.664381 -360.329286) (xy 89.6114 -360.355953)
			(xy 89.55493 -360.374095) (xy 89.496331 -360.383274) (xy 89.466674 -360.383836) (xy 89.440711 -360.38336)
			(xy 89.389265 -360.376319) (xy 89.339247 -360.36237) (xy 89.291582 -360.341771) (xy 89.247148 -360.314902)
			(xy 89.206765 -360.282259) (xy 89.17118 -360.244444) (xy 89.141048 -360.202155) (xy 89.1286 -360.179366)
			(xy 89.121978 -360.16751) (xy 89.103535 -360.147587) (xy 89.080488 -360.133238) (xy 89.054472 -360.12548)
			(xy 89.02733 -360.124862) (xy 89.000988 -360.131428) (xy 88.977312 -360.144712) (xy 88.95798 -360.163774)
			(xy 88.9508 -360.175302) (xy 88.936041 -360.199594) (xy 88.900425 -360.243892) (xy 88.858631 -360.282415)
			(xy 88.811584 -360.314311) (xy 88.760326 -360.338875) (xy 88.705991 -360.355562) (xy 88.649782 -360.364004)
			(xy 88.621362 -360.364532) (xy 88.592623 -360.364023) (xy 88.535795 -360.355395) (xy 88.480904 -360.338341)
			(xy 88.429193 -360.313247) (xy 88.381831 -360.28068) (xy 88.360504 -360.261408) (xy 88.348663 -360.251155)
			(xy 88.320383 -360.237729) (xy 88.289366 -360.233492) (xy 88.258521 -360.23884) (xy 88.23074 -360.253271)
			(xy 88.21928 -360.263948) (xy 88.197663 -360.284818) (xy 88.149082 -360.320173) (xy 88.095557 -360.347473)
			(xy 88.038414 -360.366042) (xy 87.979067 -360.375421) (xy 87.949024 -360.375962) (xy 87.92177 -360.375522)
			(xy 87.867815 -360.367767) (xy 87.815514 -360.352412) (xy 87.765931 -360.329769) (xy 87.720076 -360.300299)
			(xy 87.678882 -360.264603) (xy 87.643188 -360.223407) (xy 87.613721 -360.177549) (xy 87.59108 -360.127965)
			(xy 87.575728 -360.075663) (xy 87.567976 -360.021708) (xy 87.567516 -359.994454) (xy 81.432146 -359.994454)
			(xy 81.867502 -360.42981) (xy 99.3173 -360.42981) (xy 99.321371 -360.374188) (xy 99.333497 -360.319751)
			(xy 99.35342 -360.26766) (xy 99.380716 -360.219025) (xy 99.414802 -360.174882) (xy 99.454951 -360.136173)
			(xy 99.500309 -360.103722) (xy 99.549909 -360.078221) (xy 99.602693 -360.060214) (xy 99.657536 -360.050084)
			(xy 99.71327 -360.048047) (xy 99.768707 -360.054147) (xy 99.822664 -360.068253) (xy 99.873993 -360.090065)
			(xy 99.921599 -360.119119) (xy 99.964467 -360.154794) (xy 100.001684 -360.196331) (xy 100.032457 -360.242844)
			(xy 100.056129 -360.293341) (xy 100.072197 -360.346748) (xy 100.080317 -360.401924) (xy 100.080826 -360.42981)
			(xy 100.080317 -360.457696) (xy 100.072197 -360.512872) (xy 100.056129 -360.566279) (xy 100.032457 -360.616776)
			(xy 100.001684 -360.663289) (xy 99.964467 -360.704826) (xy 99.921599 -360.740501) (xy 99.873993 -360.769555)
			(xy 99.822664 -360.791367) (xy 99.768707 -360.805473) (xy 99.71327 -360.811573) (xy 99.657536 -360.809536)
			(xy 99.602693 -360.799406) (xy 99.549909 -360.781399) (xy 99.500309 -360.755898) (xy 99.454951 -360.723447)
			(xy 99.414802 -360.684738) (xy 99.380716 -360.640595) (xy 99.35342 -360.59196) (xy 99.333497 -360.539869)
			(xy 99.321371 -360.485432) (xy 99.3173 -360.42981) (xy 81.867502 -360.42981) (xy 83.058762 -361.62107)
			(xy 83.857825 -361.952032) (xy 102.011732 -361.952032) (xy 102.015803 -361.89641) (xy 102.027929 -361.841973)
			(xy 102.047852 -361.789882) (xy 102.075148 -361.741247) (xy 102.109234 -361.697104) (xy 102.149383 -361.658395)
			(xy 102.194741 -361.625944) (xy 102.244341 -361.600443) (xy 102.297125 -361.582436) (xy 102.351968 -361.572306)
			(xy 102.407702 -361.570269) (xy 102.463139 -361.576369) (xy 102.517096 -361.590475) (xy 102.568425 -361.612287)
			(xy 102.616031 -361.641341) (xy 102.658899 -361.677016) (xy 102.696116 -361.718553) (xy 102.726889 -361.765066)
			(xy 102.750561 -361.815563) (xy 102.766629 -361.86897) (xy 102.774749 -361.924146) (xy 102.775188 -361.948222)
			(xy 103.776778 -361.948222) (xy 103.780849 -361.8926) (xy 103.792975 -361.838163) (xy 103.812898 -361.786072)
			(xy 103.840194 -361.737437) (xy 103.87428 -361.693294) (xy 103.914429 -361.654585) (xy 103.959787 -361.622134)
			(xy 104.009387 -361.596633) (xy 104.062171 -361.578626) (xy 104.117014 -361.568496) (xy 104.172748 -361.566459)
			(xy 104.228185 -361.572559) (xy 104.282142 -361.586665) (xy 104.333471 -361.608477) (xy 104.381077 -361.637531)
			(xy 104.423945 -361.673206) (xy 104.461162 -361.714743) (xy 104.491935 -361.761256) (xy 104.515607 -361.811753)
			(xy 104.531675 -361.86516) (xy 104.539795 -361.920336) (xy 104.540304 -361.948222) (xy 104.539795 -361.976108)
			(xy 104.531675 -362.031284) (xy 104.515607 -362.084691) (xy 104.491935 -362.135188) (xy 104.461162 -362.181701)
			(xy 104.423945 -362.223238) (xy 104.381077 -362.258913) (xy 104.333471 -362.287967) (xy 104.282142 -362.309779)
			(xy 104.229145 -362.323634) (xy 105.517186 -362.323634) (xy 105.521257 -362.268012) (xy 105.533383 -362.213575)
			(xy 105.553306 -362.161484) (xy 105.580602 -362.112849) (xy 105.614688 -362.068706) (xy 105.654837 -362.029997)
			(xy 105.700195 -361.997546) (xy 105.749795 -361.972045) (xy 105.802579 -361.954038) (xy 105.857422 -361.943908)
			(xy 105.913156 -361.941871) (xy 105.968593 -361.947971) (xy 106.02255 -361.962077) (xy 106.073879 -361.983889)
			(xy 106.121485 -362.012943) (xy 106.164353 -362.048618) (xy 106.20157 -362.090155) (xy 106.232343 -362.136668)
			(xy 106.256015 -362.187165) (xy 106.272083 -362.240572) (xy 106.280203 -362.295748) (xy 106.280712 -362.323634)
			(xy 106.280203 -362.35152) (xy 106.272083 -362.406696) (xy 106.256015 -362.460103) (xy 106.232343 -362.5106)
			(xy 106.20157 -362.557113) (xy 106.164353 -362.59865) (xy 106.121485 -362.634325) (xy 106.073879 -362.663379)
			(xy 106.02255 -362.685191) (xy 105.968593 -362.699297) (xy 105.913156 -362.705397) (xy 105.857422 -362.70336)
			(xy 105.802579 -362.69323) (xy 105.749795 -362.675223) (xy 105.700195 -362.649722) (xy 105.654837 -362.617271)
			(xy 105.614688 -362.578562) (xy 105.580602 -362.534419) (xy 105.553306 -362.485784) (xy 105.533383 -362.433693)
			(xy 105.521257 -362.379256) (xy 105.517186 -362.323634) (xy 104.229145 -362.323634) (xy 104.228185 -362.323885)
			(xy 104.172748 -362.329985) (xy 104.117014 -362.327948) (xy 104.062171 -362.317818) (xy 104.009387 -362.299811)
			(xy 103.959787 -362.27431) (xy 103.914429 -362.241859) (xy 103.87428 -362.20315) (xy 103.840194 -362.159007)
			(xy 103.812898 -362.110372) (xy 103.792975 -362.058281) (xy 103.780849 -362.003844) (xy 103.776778 -361.948222)
			(xy 102.775188 -361.948222) (xy 102.775258 -361.952032) (xy 102.774749 -361.979918) (xy 102.766629 -362.035094)
			(xy 102.750561 -362.088501) (xy 102.726889 -362.138998) (xy 102.696116 -362.185511) (xy 102.658899 -362.227048)
			(xy 102.616031 -362.262723) (xy 102.568425 -362.291777) (xy 102.517096 -362.313589) (xy 102.463139 -362.327695)
			(xy 102.407702 -362.333795) (xy 102.351968 -362.331758) (xy 102.297125 -362.321628) (xy 102.244341 -362.303621)
			(xy 102.194741 -362.27812) (xy 102.149383 -362.245669) (xy 102.109234 -362.20696) (xy 102.075148 -362.162817)
			(xy 102.047852 -362.114182) (xy 102.027929 -362.062091) (xy 102.015803 -362.007654) (xy 102.011732 -361.952032)
			(xy 83.857825 -361.952032) (xy 85.985799 -362.833412) (xy 96.770188 -362.833412) (xy 96.774259 -362.77779)
			(xy 96.786385 -362.723353) (xy 96.806308 -362.671262) (xy 96.833604 -362.622627) (xy 96.86769 -362.578484)
			(xy 96.907839 -362.539775) (xy 96.953197 -362.507324) (xy 97.002797 -362.481823) (xy 97.055581 -362.463816)
			(xy 97.110424 -362.453686) (xy 97.166158 -362.451649) (xy 97.221595 -362.457749) (xy 97.275552 -362.471855)
			(xy 97.326881 -362.493667) (xy 97.374487 -362.522721) (xy 97.417355 -362.558396) (xy 97.454572 -362.599933)
			(xy 97.485345 -362.646446) (xy 97.509017 -362.696943) (xy 97.525085 -362.75035) (xy 97.533205 -362.805526)
			(xy 97.533714 -362.833412) (xy 97.533205 -362.861298) (xy 97.525085 -362.916474) (xy 97.509017 -362.969881)
			(xy 97.485345 -363.020378) (xy 97.454572 -363.066891) (xy 97.425489 -363.09935) (xy 97.87204 -363.09935)
			(xy 97.876111 -363.043728) (xy 97.888237 -362.989291) (xy 97.90816 -362.9372) (xy 97.935456 -362.888565)
			(xy 97.969542 -362.844422) (xy 98.009691 -362.805713) (xy 98.055049 -362.773262) (xy 98.104649 -362.747761)
			(xy 98.157433 -362.729754) (xy 98.212276 -362.719624) (xy 98.26801 -362.717587) (xy 98.323447 -362.723687)
			(xy 98.377404 -362.737793) (xy 98.428733 -362.759605) (xy 98.476339 -362.788659) (xy 98.519207 -362.824334)
			(xy 98.556424 -362.865871) (xy 98.587197 -362.912384) (xy 98.610869 -362.962881) (xy 98.626937 -363.016288)
			(xy 98.635057 -363.071464) (xy 98.635566 -363.09935) (xy 98.635057 -363.127236) (xy 98.631947 -363.148372)
			(xy 106.262676 -363.148372) (xy 106.266747 -363.09275) (xy 106.278873 -363.038313) (xy 106.298796 -362.986222)
			(xy 106.326092 -362.937587) (xy 106.360178 -362.893444) (xy 106.400327 -362.854735) (xy 106.445685 -362.822284)
			(xy 106.495285 -362.796783) (xy 106.548069 -362.778776) (xy 106.602912 -362.768646) (xy 106.658646 -362.766609)
			(xy 106.714083 -362.772709) (xy 106.76804 -362.786815) (xy 106.819369 -362.808627) (xy 106.866975 -362.837681)
			(xy 106.909843 -362.873356) (xy 106.94706 -362.914893) (xy 106.977833 -362.961406) (xy 107.001505 -363.011903)
			(xy 107.017573 -363.06531) (xy 107.025693 -363.120486) (xy 107.026202 -363.148372) (xy 107.025693 -363.176258)
			(xy 107.017573 -363.231434) (xy 107.001505 -363.284841) (xy 106.977833 -363.335338) (xy 106.94706 -363.381851)
			(xy 106.909843 -363.423388) (xy 106.866975 -363.459063) (xy 106.819369 -363.488117) (xy 106.76804 -363.509929)
			(xy 106.714083 -363.524035) (xy 106.658646 -363.530135) (xy 106.602912 -363.528098) (xy 106.548069 -363.517968)
			(xy 106.495285 -363.499961) (xy 106.445685 -363.47446) (xy 106.400327 -363.442009) (xy 106.360178 -363.4033)
			(xy 106.326092 -363.359157) (xy 106.298796 -363.310522) (xy 106.278873 -363.258431) (xy 106.266747 -363.203994)
			(xy 106.262676 -363.148372) (xy 98.631947 -363.148372) (xy 98.626937 -363.182412) (xy 98.610869 -363.235819)
			(xy 98.587197 -363.286316) (xy 98.556424 -363.332829) (xy 98.519207 -363.374366) (xy 98.476339 -363.410041)
			(xy 98.428733 -363.439095) (xy 98.377404 -363.460907) (xy 98.323447 -363.475013) (xy 98.26801 -363.481113)
			(xy 98.212276 -363.479076) (xy 98.157433 -363.468946) (xy 98.104649 -363.450939) (xy 98.055049 -363.425438)
			(xy 98.009691 -363.392987) (xy 97.969542 -363.354278) (xy 97.935456 -363.310135) (xy 97.90816 -363.2615)
			(xy 97.888237 -363.209409) (xy 97.876111 -363.154972) (xy 97.87204 -363.09935) (xy 97.425489 -363.09935)
			(xy 97.417355 -363.108428) (xy 97.374487 -363.144103) (xy 97.326881 -363.173157) (xy 97.275552 -363.194969)
			(xy 97.221595 -363.209075) (xy 97.166158 -363.215175) (xy 97.110424 -363.213138) (xy 97.055581 -363.203008)
			(xy 97.002797 -363.185001) (xy 96.953197 -363.1595) (xy 96.907839 -363.127049) (xy 96.86769 -363.08834)
			(xy 96.833604 -363.044197) (xy 96.806308 -362.995562) (xy 96.786385 -362.943471) (xy 96.774259 -362.889034)
			(xy 96.770188 -362.833412) (xy 85.985799 -362.833412) (xy 87.969659 -363.655102) (xy 98.85248 -363.655102)
			(xy 98.856551 -363.59948) (xy 98.868677 -363.545043) (xy 98.8886 -363.492952) (xy 98.915896 -363.444317)
			(xy 98.949982 -363.400174) (xy 98.990131 -363.361465) (xy 99.035489 -363.329014) (xy 99.085089 -363.303513)
			(xy 99.137873 -363.285506) (xy 99.192716 -363.275376) (xy 99.24845 -363.273339) (xy 99.303887 -363.279439)
			(xy 99.357844 -363.293545) (xy 99.409173 -363.315357) (xy 99.456779 -363.344411) (xy 99.499647 -363.380086)
			(xy 99.536864 -363.421623) (xy 99.567637 -363.468136) (xy 99.591309 -363.518633) (xy 99.607377 -363.57204)
			(xy 99.615497 -363.627216) (xy 99.615691 -363.63783) (xy 104.371646 -363.63783) (xy 104.375717 -363.582208)
			(xy 104.387843 -363.527771) (xy 104.407766 -363.47568) (xy 104.435062 -363.427045) (xy 104.469148 -363.382902)
			(xy 104.509297 -363.344193) (xy 104.554655 -363.311742) (xy 104.604255 -363.286241) (xy 104.657039 -363.268234)
			(xy 104.711882 -363.258104) (xy 104.767616 -363.256067) (xy 104.823053 -363.262167) (xy 104.87701 -363.276273)
			(xy 104.928339 -363.298085) (xy 104.975945 -363.327139) (xy 105.018813 -363.362814) (xy 105.05603 -363.404351)
			(xy 105.086803 -363.450864) (xy 105.110475 -363.501361) (xy 105.126543 -363.554768) (xy 105.134663 -363.609944)
			(xy 105.135172 -363.63783) (xy 105.134663 -363.665716) (xy 105.126543 -363.720892) (xy 105.110475 -363.774299)
			(xy 105.086803 -363.824796) (xy 105.05603 -363.871309) (xy 105.018813 -363.912846) (xy 104.975945 -363.948521)
			(xy 104.928339 -363.977575) (xy 104.87701 -363.999387) (xy 104.823053 -364.013493) (xy 104.767616 -364.019593)
			(xy 104.711882 -364.017556) (xy 104.657039 -364.007426) (xy 104.604255 -363.989419) (xy 104.554655 -363.963918)
			(xy 104.509297 -363.931467) (xy 104.469148 -363.892758) (xy 104.435062 -363.848615) (xy 104.407766 -363.79998)
			(xy 104.387843 -363.747889) (xy 104.375717 -363.693452) (xy 104.371646 -363.63783) (xy 99.615691 -363.63783)
			(xy 99.616006 -363.655102) (xy 99.615497 -363.682988) (xy 99.607377 -363.738164) (xy 99.591309 -363.791571)
			(xy 99.567637 -363.842068) (xy 99.536864 -363.888581) (xy 99.499647 -363.930118) (xy 99.456779 -363.965793)
			(xy 99.409173 -363.994847) (xy 99.357844 -364.016659) (xy 99.303887 -364.030765) (xy 99.24845 -364.036865)
			(xy 99.192716 -364.034828) (xy 99.137873 -364.024698) (xy 99.085089 -364.006691) (xy 99.035489 -363.98119)
			(xy 98.990131 -363.948739) (xy 98.949982 -363.91003) (xy 98.915896 -363.865887) (xy 98.8886 -363.817252)
			(xy 98.868677 -363.765161) (xy 98.856551 -363.710724) (xy 98.85248 -363.655102) (xy 87.969659 -363.655102)
			(xy 89.019541 -364.08995) (xy 97.5774 -364.08995) (xy 97.581471 -364.034328) (xy 97.593597 -363.979891)
			(xy 97.61352 -363.9278) (xy 97.640816 -363.879165) (xy 97.674902 -363.835022) (xy 97.715051 -363.796313)
			(xy 97.760409 -363.763862) (xy 97.810009 -363.738361) (xy 97.862793 -363.720354) (xy 97.917636 -363.710224)
			(xy 97.97337 -363.708187) (xy 98.028807 -363.714287) (xy 98.082764 -363.728393) (xy 98.134093 -363.750205)
			(xy 98.181699 -363.779259) (xy 98.224567 -363.814934) (xy 98.261784 -363.856471) (xy 98.292557 -363.902984)
			(xy 98.316229 -363.953481) (xy 98.332297 -364.006888) (xy 98.340417 -364.062064) (xy 98.340926 -364.08995)
			(xy 98.340417 -364.117836) (xy 98.332297 -364.173012) (xy 98.316229 -364.226419) (xy 98.292557 -364.276916)
			(xy 98.261784 -364.323429) (xy 98.224567 -364.364966) (xy 98.181699 -364.400641) (xy 98.134093 -364.429695)
			(xy 98.082764 -364.451507) (xy 98.028807 -364.465613) (xy 97.97337 -364.471713) (xy 97.917636 -364.469676)
			(xy 97.862793 -364.459546) (xy 97.810009 -364.441539) (xy 97.760409 -364.416038) (xy 97.715051 -364.383587)
			(xy 97.674902 -364.344878) (xy 97.640816 -364.300735) (xy 97.61352 -364.2521) (xy 97.593597 -364.200009)
			(xy 97.581471 -364.145572) (xy 97.5774 -364.08995) (xy 89.019541 -364.08995) (xy 90.144392 -364.555849)
			(xy 98.876386 -364.555849) (xy 98.876386 -364.501351) (xy 98.884141 -364.447408) (xy 98.899494 -364.395118)
			(xy 98.922131 -364.345545) (xy 98.951593 -364.299697) (xy 98.987279 -364.258509) (xy 99.028464 -364.222818)
			(xy 99.074308 -364.193351) (xy 99.123879 -364.170708) (xy 99.176167 -364.15535) (xy 99.230109 -364.147589)
			(xy 99.257358 -364.1471) (xy 99.283582 -364.147509) (xy 99.335533 -364.154713) (xy 99.386009 -364.168963)
			(xy 99.434058 -364.189991) (xy 99.478774 -364.2174) (xy 99.519316 -364.250675) (xy 99.554919 -364.289188)
			(xy 99.584913 -364.332214) (xy 99.59721 -364.35538) (xy 99.604539 -364.368759) (xy 99.625777 -364.390643)
			(xy 99.652525 -364.405289) (xy 99.682403 -364.411393) (xy 99.712753 -364.408413) (xy 99.740873 -364.396614)
			(xy 99.764262 -364.377045) (xy 99.772978 -364.364524) (xy 99.788181 -364.342039) (xy 99.823848 -364.301132)
			(xy 99.864955 -364.265695) (xy 99.91067 -364.236444) (xy 99.960071 -364.213969) (xy 100.012159 -364.198724)
			(xy 100.065882 -364.191018) (xy 100.093018 -364.190534) (xy 100.120271 -364.190937) (xy 100.174223 -364.198697)
			(xy 100.226521 -364.214055) (xy 100.276102 -364.2367) (xy 100.321955 -364.26617) (xy 100.363148 -364.301865)
			(xy 100.398841 -364.343059) (xy 100.428309 -364.388914) (xy 100.439674 -364.4138) (xy 106.12069 -364.4138)
			(xy 106.124761 -364.358178) (xy 106.136887 -364.303741) (xy 106.15681 -364.25165) (xy 106.184106 -364.203015)
			(xy 106.218192 -364.158872) (xy 106.258341 -364.120163) (xy 106.303699 -364.087712) (xy 106.353299 -364.062211)
			(xy 106.406083 -364.044204) (xy 106.460926 -364.034074) (xy 106.51666 -364.032037) (xy 106.572097 -364.038137)
			(xy 106.626054 -364.052243) (xy 106.677383 -364.074055) (xy 106.724989 -364.103109) (xy 106.767857 -364.138784)
			(xy 106.805074 -364.180321) (xy 106.835847 -364.226834) (xy 106.859519 -364.277331) (xy 106.869398 -364.310168)
			(xy 107.575602 -364.310168) (xy 107.579673 -364.254546) (xy 107.591799 -364.200109) (xy 107.611722 -364.148018)
			(xy 107.639018 -364.099383) (xy 107.673104 -364.05524) (xy 107.713253 -364.016531) (xy 107.758611 -363.98408)
			(xy 107.808211 -363.958579) (xy 107.860995 -363.940572) (xy 107.915838 -363.930442) (xy 107.971572 -363.928405)
			(xy 108.027009 -363.934505) (xy 108.080966 -363.948611) (xy 108.132295 -363.970423) (xy 108.179901 -363.999477)
			(xy 108.222769 -364.035152) (xy 108.259986 -364.076689) (xy 108.290759 -364.123202) (xy 108.314431 -364.173699)
			(xy 108.330499 -364.227106) (xy 108.338619 -364.282282) (xy 108.339128 -364.310168) (xy 108.338619 -364.338054)
			(xy 108.330499 -364.39323) (xy 108.314431 -364.446637) (xy 108.290759 -364.497134) (xy 108.259986 -364.543647)
			(xy 108.222769 -364.585184) (xy 108.179901 -364.620859) (xy 108.132295 -364.649913) (xy 108.080966 -364.671725)
			(xy 108.027009 -364.685831) (xy 107.971572 -364.691931) (xy 107.915838 -364.689894) (xy 107.860995 -364.679764)
			(xy 107.808211 -364.661757) (xy 107.758611 -364.636256) (xy 107.713253 -364.603805) (xy 107.673104 -364.565096)
			(xy 107.639018 -364.520953) (xy 107.611722 -364.472318) (xy 107.591799 -364.420227) (xy 107.579673 -364.36579)
			(xy 107.575602 -364.310168) (xy 106.869398 -364.310168) (xy 106.875587 -364.330738) (xy 106.883707 -364.385914)
			(xy 106.884216 -364.4138) (xy 106.883707 -364.441686) (xy 106.875587 -364.496862) (xy 106.859519 -364.550269)
			(xy 106.835847 -364.600766) (xy 106.805074 -364.647279) (xy 106.767857 -364.688816) (xy 106.724989 -364.724491)
			(xy 106.677383 -364.753545) (xy 106.626054 -364.775357) (xy 106.572097 -364.789463) (xy 106.51666 -364.795563)
			(xy 106.460926 -364.793526) (xy 106.406083 -364.783396) (xy 106.353299 -364.765389) (xy 106.303699 -364.739888)
			(xy 106.258341 -364.707437) (xy 106.218192 -364.668728) (xy 106.184106 -364.624585) (xy 106.15681 -364.57595)
			(xy 106.136887 -364.523859) (xy 106.124761 -364.469422) (xy 106.12069 -364.4138) (xy 100.439674 -364.4138)
			(xy 100.450951 -364.438495) (xy 100.466307 -364.490794) (xy 100.474064 -364.544747) (xy 100.474064 -364.599253)
			(xy 100.466307 -364.653206) (xy 100.450951 -364.705505) (xy 100.428309 -364.755086) (xy 100.398841 -364.800941)
			(xy 100.363148 -364.842135) (xy 100.321955 -364.87783) (xy 100.276102 -364.9073) (xy 100.226521 -364.929945)
			(xy 100.174223 -364.945303) (xy 100.120271 -364.953063) (xy 100.093018 -364.95355) (xy 100.066795 -364.953133)
			(xy 100.014845 -364.945928) (xy 99.964371 -364.931677) (xy 99.916323 -364.910649) (xy 99.871607 -364.883241)
			(xy 99.831065 -364.849968) (xy 99.795461 -364.811457) (xy 99.765465 -364.768435) (xy 99.753166 -364.74527)
			(xy 99.745729 -364.731955) (xy 99.724517 -364.710068) (xy 99.697791 -364.695415) (xy 99.667931 -364.6893)
			(xy 99.637597 -364.692269) (xy 99.609489 -364.704056) (xy 99.58611 -364.723612) (xy 99.577398 -364.736126)
			(xy 99.562228 -364.758633) (xy 99.526553 -364.799537) (xy 99.48544 -364.834971) (xy 99.439719 -364.864219)
			(xy 99.390314 -364.886691) (xy 99.338222 -364.901931) (xy 99.284496 -364.909633) (xy 99.257358 -364.910116)
			(xy 99.230109 -364.909611) (xy 99.176167 -364.90185) (xy 99.123879 -364.886492) (xy 99.074308 -364.863849)
			(xy 99.028464 -364.834382) (xy 98.987279 -364.798691) (xy 98.951593 -364.757503) (xy 98.922131 -364.711655)
			(xy 98.899494 -364.662082) (xy 98.884141 -364.609792) (xy 98.876386 -364.555849) (xy 90.144392 -364.555849)
			(xy 91.555325 -365.14024) (xy 106.985814 -365.14024) (xy 106.989885 -365.084618) (xy 107.002011 -365.030181)
			(xy 107.021934 -364.97809) (xy 107.04923 -364.929455) (xy 107.083316 -364.885312) (xy 107.123465 -364.846603)
			(xy 107.168823 -364.814152) (xy 107.218423 -364.788651) (xy 107.271207 -364.770644) (xy 107.32605 -364.760514)
			(xy 107.381784 -364.758477) (xy 107.437221 -364.764577) (xy 107.491178 -364.778683) (xy 107.542507 -364.800495)
			(xy 107.590113 -364.829549) (xy 107.632981 -364.865224) (xy 107.670198 -364.906761) (xy 107.700971 -364.953274)
			(xy 107.724643 -365.003771) (xy 107.740711 -365.057178) (xy 107.748831 -365.112354) (xy 107.74934 -365.14024)
			(xy 107.748831 -365.168126) (xy 107.740711 -365.223302) (xy 107.724643 -365.276709) (xy 107.700971 -365.327206)
			(xy 107.670198 -365.373719) (xy 107.632981 -365.415256) (xy 107.590113 -365.450931) (xy 107.542507 -365.479985)
			(xy 107.491178 -365.501797) (xy 107.437221 -365.515903) (xy 107.381784 -365.522003) (xy 107.32605 -365.519966)
			(xy 107.271207 -365.509836) (xy 107.218423 -365.491829) (xy 107.168823 -365.466328) (xy 107.123465 -365.433877)
			(xy 107.083316 -365.395168) (xy 107.04923 -365.351025) (xy 107.021934 -365.30239) (xy 107.002011 -365.250299)
			(xy 106.989885 -365.195862) (xy 106.985814 -365.14024) (xy 91.555325 -365.14024) (xy 92.646908 -365.59236)
			(xy 100.41077 -365.59236) (xy 100.414841 -365.536738) (xy 100.426967 -365.482301) (xy 100.44689 -365.43021)
			(xy 100.474186 -365.381575) (xy 100.508272 -365.337432) (xy 100.548421 -365.298723) (xy 100.593779 -365.266272)
			(xy 100.643379 -365.240771) (xy 100.696163 -365.222764) (xy 100.751006 -365.212634) (xy 100.80674 -365.210597)
			(xy 100.862177 -365.216697) (xy 100.916134 -365.230803) (xy 100.967463 -365.252615) (xy 101.015069 -365.281669)
			(xy 101.057937 -365.317344) (xy 101.095154 -365.358881) (xy 101.125927 -365.405394) (xy 101.149599 -365.455891)
			(xy 101.165667 -365.509298) (xy 101.173787 -365.564474) (xy 101.174296 -365.59236) (xy 101.173787 -365.620246)
			(xy 101.165667 -365.675422) (xy 101.149599 -365.728829) (xy 101.125927 -365.779326) (xy 101.095154 -365.825839)
			(xy 101.057937 -365.867376) (xy 101.015069 -365.903051) (xy 100.967463 -365.932105) (xy 100.916134 -365.953917)
			(xy 100.906858 -365.956342) (xy 101.533958 -365.956342) (xy 101.538029 -365.90072) (xy 101.550155 -365.846283)
			(xy 101.570078 -365.794192) (xy 101.597374 -365.745557) (xy 101.63146 -365.701414) (xy 101.671609 -365.662705)
			(xy 101.716967 -365.630254) (xy 101.766567 -365.604753) (xy 101.819351 -365.586746) (xy 101.874194 -365.576616)
			(xy 101.929928 -365.574579) (xy 101.985365 -365.580679) (xy 102.039322 -365.594785) (xy 102.090651 -365.616597)
			(xy 102.138257 -365.645651) (xy 102.181125 -365.681326) (xy 102.218342 -365.722863) (xy 102.249115 -365.769376)
			(xy 102.272787 -365.819873) (xy 102.288855 -365.87328) (xy 102.296975 -365.928456) (xy 102.297484 -365.956342)
			(xy 102.296975 -365.984228) (xy 102.288855 -366.039404) (xy 102.272787 -366.092811) (xy 102.249115 -366.143308)
			(xy 102.218342 -366.189821) (xy 102.181125 -366.231358) (xy 102.138257 -366.267033) (xy 102.130359 -366.271853)
			(xy 104.673087 -366.271853) (xy 104.673087 -366.217347) (xy 104.680845 -366.163397) (xy 104.696202 -366.1111)
			(xy 104.718846 -366.061521) (xy 104.748316 -366.015669) (xy 104.784011 -365.974479) (xy 104.825206 -365.938788)
			(xy 104.871061 -365.909324) (xy 104.920643 -365.886686) (xy 104.972942 -365.871335) (xy 105.026893 -365.863584)
			(xy 105.054146 -365.863124) (xy 105.080526 -365.863544) (xy 105.132786 -365.870804) (xy 105.183547 -365.885191)
			(xy 105.231843 -365.906433) (xy 105.276753 -365.934124) (xy 105.317421 -365.967737) (xy 105.353072 -366.006631)
			(xy 105.383026 -366.050064) (xy 105.395268 -366.073436) (xy 105.40197 -366.085795) (xy 105.420945 -366.106523)
			(xy 105.444859 -366.121285) (xy 105.471895 -366.128957) (xy 105.499997 -366.128957) (xy 105.527033 -366.121285)
			(xy 105.550947 -366.106523) (xy 105.569922 -366.085795) (xy 105.576624 -366.073436) (xy 105.588879 -366.050073)
			(xy 105.618842 -366.006652) (xy 105.654497 -365.967769) (xy 105.695164 -365.934164) (xy 105.740071 -365.906477)
			(xy 105.788361 -365.885234) (xy 105.839116 -365.870842) (xy 105.891368 -365.863572) (xy 105.917746 -365.863124)
			(xy 105.944997 -365.863549) (xy 105.998945 -365.871311) (xy 106.051238 -365.886672) (xy 106.100814 -365.909318)
			(xy 106.146662 -365.938788) (xy 106.187851 -365.974482) (xy 106.22354 -366.015675) (xy 106.253005 -366.061527)
			(xy 106.275644 -366.111105) (xy 106.290998 -366.1634) (xy 106.298754 -366.217349) (xy 106.298754 -366.271851)
			(xy 106.290998 -366.3258) (xy 106.275644 -366.378095) (xy 106.253005 -366.427673) (xy 106.22354 -366.473525)
			(xy 106.187851 -366.514718) (xy 106.146662 -366.550412) (xy 106.100814 -366.579882) (xy 106.051238 -366.602528)
			(xy 105.998945 -366.617889) (xy 105.944997 -366.625651) (xy 105.917746 -366.62614) (xy 105.891367 -366.625691)
			(xy 105.839111 -366.618432) (xy 105.788352 -366.604046) (xy 105.740058 -366.582807) (xy 105.695148 -366.55512)
			(xy 105.65448 -366.521513) (xy 105.618826 -366.482625) (xy 105.588868 -366.439197) (xy 105.576624 -366.415828)
			(xy 105.569922 -366.403469) (xy 105.550947 -366.382741) (xy 105.527033 -366.367979) (xy 105.499997 -366.360307)
			(xy 105.471895 -366.360307) (xy 105.444859 -366.367979) (xy 105.420945 -366.382741) (xy 105.40197 -366.403469)
			(xy 105.395268 -366.415828) (xy 105.383003 -366.439186) (xy 105.353043 -366.482608) (xy 105.317391 -366.521493)
			(xy 105.276725 -366.555099) (xy 105.231819 -366.582787) (xy 105.18353 -366.60403) (xy 105.132776 -366.618423)
			(xy 105.080524 -366.625692) (xy 105.054146 -366.62614) (xy 105.026893 -366.625616) (xy 104.972942 -366.617865)
			(xy 104.920643 -366.602514) (xy 104.871061 -366.579876) (xy 104.825206 -366.550412) (xy 104.784011 -366.514721)
			(xy 104.748316 -366.473531) (xy 104.718846 -366.427679) (xy 104.696202 -366.3781) (xy 104.680845 -366.325803)
			(xy 104.673087 -366.271853) (xy 102.130359 -366.271853) (xy 102.090651 -366.296087) (xy 102.039322 -366.317899)
			(xy 101.985365 -366.332005) (xy 101.929928 -366.338105) (xy 101.874194 -366.336068) (xy 101.819351 -366.325938)
			(xy 101.766567 -366.307931) (xy 101.716967 -366.28243) (xy 101.671609 -366.249979) (xy 101.63146 -366.21127)
			(xy 101.597374 -366.167127) (xy 101.570078 -366.118492) (xy 101.550155 -366.066401) (xy 101.538029 -366.011964)
			(xy 101.533958 -365.956342) (xy 100.906858 -365.956342) (xy 100.862177 -365.968023) (xy 100.80674 -365.974123)
			(xy 100.751006 -365.972086) (xy 100.696163 -365.961956) (xy 100.643379 -365.943949) (xy 100.593779 -365.918448)
			(xy 100.548421 -365.885997) (xy 100.508272 -365.847288) (xy 100.474186 -365.803145) (xy 100.44689 -365.75451)
			(xy 100.426967 -365.702419) (xy 100.414841 -365.647982) (xy 100.41077 -365.59236) (xy 92.646908 -365.59236)
			(xy 95.209252 -366.653651) (xy 107.352072 -366.653651) (xy 107.352072 -366.599149) (xy 107.359828 -366.545202)
			(xy 107.375183 -366.492908) (xy 107.397823 -366.443331) (xy 107.427288 -366.39748) (xy 107.462978 -366.35629)
			(xy 107.504167 -366.320598) (xy 107.550017 -366.291131) (xy 107.599593 -366.268488) (xy 107.651886 -366.253131)
			(xy 107.705833 -366.245373) (xy 107.733084 -366.244886) (xy 107.759465 -366.245296) (xy 107.811723 -366.252559)
			(xy 107.862484 -366.26695) (xy 107.910779 -366.288195) (xy 107.955688 -366.315887) (xy 107.996356 -366.3495)
			(xy 108.032008 -366.388394) (xy 108.061963 -366.431826) (xy 108.074206 -366.455198) (xy 108.080908 -366.467557)
			(xy 108.099883 -366.488285) (xy 108.123797 -366.503047) (xy 108.150833 -366.510719) (xy 108.178935 -366.510719)
			(xy 108.205971 -366.503047) (xy 108.229885 -366.488285) (xy 108.24886 -366.467557) (xy 108.255562 -366.455198)
			(xy 108.267815 -366.431834) (xy 108.297776 -366.38841) (xy 108.333429 -366.349524) (xy 108.374097 -366.315917)
			(xy 108.419004 -366.28823) (xy 108.467296 -366.266988) (xy 108.518052 -366.252598) (xy 108.570306 -366.245332)
			(xy 108.596684 -366.244886) (xy 108.623937 -366.24536) (xy 108.677889 -366.253115) (xy 108.730188 -366.26847)
			(xy 108.779769 -366.291111) (xy 108.825624 -366.320578) (xy 108.866818 -366.356271) (xy 108.902512 -366.397463)
			(xy 108.931981 -366.443317) (xy 108.954625 -366.492897) (xy 108.969981 -366.545195) (xy 108.977739 -366.599147)
			(xy 108.977739 -366.653653) (xy 108.969981 -366.707605) (xy 108.954625 -366.759903) (xy 108.931981 -366.809483)
			(xy 108.902512 -366.855337) (xy 108.866818 -366.896529) (xy 108.825624 -366.932222) (xy 108.779769 -366.961689)
			(xy 108.730188 -366.98433) (xy 108.677889 -366.999685) (xy 108.623937 -367.00744) (xy 108.596684 -367.007902)
			(xy 108.570305 -367.007443) (xy 108.518048 -367.000188) (xy 108.467289 -366.985805) (xy 108.418994 -366.964569)
			(xy 108.374084 -366.936883) (xy 108.333415 -366.903276) (xy 108.297762 -366.864388) (xy 108.267805 -366.82096)
			(xy 108.255562 -366.79759) (xy 108.24886 -366.785231) (xy 108.229885 -366.764503) (xy 108.205971 -366.749741)
			(xy 108.178935 -366.742069) (xy 108.150833 -366.742069) (xy 108.123797 -366.749741) (xy 108.099883 -366.764503)
			(xy 108.080908 -366.785231) (xy 108.074206 -366.79759) (xy 108.061972 -366.820965) (xy 108.032009 -366.86439)
			(xy 107.996354 -366.903276) (xy 107.955683 -366.936882) (xy 107.910773 -366.964569) (xy 107.862479 -366.985808)
			(xy 107.81172 -367.000196) (xy 107.759463 -367.007458) (xy 107.733084 -367.007902) (xy 107.705833 -367.007427)
			(xy 107.651886 -366.999669) (xy 107.599593 -366.984312) (xy 107.550017 -366.961669) (xy 107.504167 -366.932202)
			(xy 107.462978 -366.89651) (xy 107.427288 -366.85532) (xy 107.397823 -366.809469) (xy 107.375183 -366.759892)
			(xy 107.359828 -366.707598) (xy 107.352072 -366.653651) (xy 95.209252 -366.653651) (xy 101.047804 -369.071906)
			(xy 121.675144 -372.131844) (xy 156.315664 -372.131844)
		)
		(stroke
			(width 0)
			(type solid)
		)
		(fill yes)
		(layer "In6.Cu")
		(net "GND")
	)
	(gr_poly
		(pts
			(xy 111.0615 -236.285786) (xy 111.087908 -236.277138) (xy 111.142684 -236.267812) (xy 111.170466 -236.267244)
			(xy 111.198245 -236.26784) (xy 111.253018 -236.277164) (xy 111.279432 -236.285786) (xy 111.28756 -236.28858)
			(xy 111.993172 -236.28858) (xy 112.0013 -236.285786) (xy 112.027708 -236.277138) (xy 112.082484 -236.267812)
			(xy 112.110266 -236.267244) (xy 112.138045 -236.26784) (xy 112.192818 -236.277164) (xy 112.219232 -236.285786)
			(xy 112.22736 -236.28858) (xy 112.932972 -236.28858) (xy 112.9411 -236.285786) (xy 112.967508 -236.277138)
			(xy 113.022284 -236.267812) (xy 113.050066 -236.267244) (xy 113.077845 -236.26784) (xy 113.132618 -236.277164)
			(xy 113.159032 -236.285786) (xy 113.16716 -236.28858) (xy 113.873026 -236.28858) (xy 113.881154 -236.285786)
			(xy 113.907563 -236.277142) (xy 113.962339 -236.267825) (xy 113.99012 -236.267244) (xy 114.0179 -236.267836)
			(xy 114.072675 -236.277153) (xy 114.099086 -236.285786) (xy 114.107214 -236.28858) (xy 115.161314 -236.28858)
			(xy 115.184522 -236.274095) (xy 115.234618 -236.252125) (xy 115.287647 -236.238698) (xy 115.342162 -236.234181)
			(xy 115.396677 -236.238698) (xy 115.449706 -236.252125) (xy 115.499802 -236.274095) (xy 115.52301 -236.28858)
			(xy 120.644412 -236.28858) (xy 120.64619 -236.239558) (xy 120.647605 -236.214249) (xy 120.657227 -236.164483)
			(xy 120.674336 -236.116769) (xy 120.698531 -236.072228) (xy 120.729244 -236.031904) (xy 120.765755 -235.996744)
			(xy 120.807207 -235.967571) (xy 120.852628 -235.945071) (xy 120.900952 -235.929771) (xy 120.951046 -235.92203)
			(xy 121.001734 -235.92203) (xy 121.051828 -235.929771) (xy 121.100152 -235.945071) (xy 121.145573 -235.967571)
			(xy 121.187025 -235.996744) (xy 121.223536 -236.031904) (xy 121.254249 -236.072228) (xy 121.278444 -236.116769)
			(xy 121.295553 -236.164483) (xy 121.305175 -236.214249) (xy 121.30659 -236.239558) (xy 121.308368 -236.28858)
			(xy 121.39168 -236.28858) (xy 121.399554 -236.285786) (xy 121.425851 -236.277247) (xy 121.480369 -236.268053)
			(xy 121.535655 -236.268053) (xy 121.590173 -236.277247) (xy 121.61647 -236.285786) (xy 121.624344 -236.28858)
			(xy 122.331734 -236.28858) (xy 122.339608 -236.285786) (xy 122.365905 -236.277247) (xy 122.420423 -236.268053)
			(xy 122.475709 -236.268053) (xy 122.530227 -236.277247) (xy 122.556524 -236.285786) (xy 122.564398 -236.28858)
			(xy 123.27128 -236.28858) (xy 123.279154 -236.285786) (xy 123.305451 -236.277247) (xy 123.359969 -236.268053)
			(xy 123.415255 -236.268053) (xy 123.469773 -236.277247) (xy 123.49607 -236.285786) (xy 123.503944 -236.28858)
			(xy 124.038106 -236.28858) (xy 124.473462 -235.853224) (xy 124.47016 -235.828332) (xy 124.468745 -235.817274)
			(xy 124.46722 -235.79503) (xy 124.467112 -235.783882) (xy 124.467623 -235.757915) (xy 124.475749 -235.70662)
			(xy 124.491799 -235.657228) (xy 124.515377 -235.610954) (xy 124.545903 -235.568937) (xy 124.582625 -235.532213)
			(xy 124.62464 -235.501685) (xy 124.670913 -235.478105) (xy 124.720304 -235.462053) (xy 124.771599 -235.453924)
			(xy 124.797566 -235.453428) (xy 124.808714 -235.453527) (xy 124.830959 -235.455052) (xy 124.842016 -235.456476)
			(xy 124.866908 -235.459778) (xy 124.956316 -235.37037) (xy 124.956316 -235.081572) (xy 124.953776 -235.073952)
			(xy 124.945956 -235.048696) (xy 124.937537 -234.996502) (xy 124.937542 -234.943634) (xy 124.945972 -234.891442)
			(xy 124.953776 -234.86618) (xy 124.956316 -234.85856) (xy 124.956316 -234.584494) (xy 124.955822 -234.570044)
			(xy 124.947738 -234.5423) (xy 124.932193 -234.517939) (xy 124.910436 -234.498919) (xy 124.884216 -234.486769)
			(xy 124.85564 -234.482465) (xy 124.841254 -234.48391) (xy 124.830382 -234.485246) (xy 124.80852 -234.486648)
			(xy 124.797566 -234.486704) (xy 124.771597 -234.486192) (xy 124.720298 -234.478062) (xy 124.670902 -234.462008)
			(xy 124.624626 -234.438425) (xy 124.582609 -234.407894) (xy 124.545884 -234.371165) (xy 124.515357 -234.329145)
			(xy 124.491779 -234.282866) (xy 124.47573 -234.233469) (xy 124.467605 -234.182169) (xy 124.467605 -234.130231)
			(xy 124.47573 -234.078931) (xy 124.491779 -234.029534) (xy 124.515357 -233.983255) (xy 124.545884 -233.941235)
			(xy 124.582609 -233.904506) (xy 124.624626 -233.873975) (xy 124.670902 -233.850392) (xy 124.720298 -233.834338)
			(xy 124.771597 -233.826208) (xy 124.797566 -233.825796) (xy 124.808519 -233.825862) (xy 124.830381 -233.82726)
			(xy 124.841254 -233.82859) (xy 124.855636 -233.830002) (xy 124.884193 -233.825658) (xy 124.910394 -233.813499)
			(xy 124.932146 -233.794494) (xy 124.947713 -233.770163) (xy 124.955851 -233.742448) (xy 124.956316 -233.728006)
			(xy 124.956316 -233.454448) (xy 124.953776 -233.446574) (xy 124.945863 -233.421202) (xy 124.937308 -233.368751)
			(xy 124.936758 -233.34218) (xy 124.937308 -233.315608) (xy 124.945859 -233.263157) (xy 124.953776 -233.237786)
			(xy 124.956316 -233.229912) (xy 124.956316 -232.956608) (xy 124.955823 -232.942157) (xy 124.947742 -232.914409)
			(xy 124.932197 -232.890044) (xy 124.91044 -232.871021) (xy 124.884218 -232.858869) (xy 124.855639 -232.854565)
			(xy 124.841254 -232.856024) (xy 124.830382 -232.85736) (xy 124.80852 -232.858761) (xy 124.797566 -232.858818)
			(xy 124.771603 -232.858306) (xy 124.720318 -232.850179) (xy 124.670935 -232.834129) (xy 124.624671 -232.810552)
			(xy 124.582665 -232.780028) (xy 124.54595 -232.74331) (xy 124.51543 -232.7013) (xy 124.491858 -232.655033)
			(xy 124.475813 -232.605649) (xy 124.467691 -232.554363) (xy 124.467691 -232.502437) (xy 124.475813 -232.451151)
			(xy 124.491858 -232.401767) (xy 124.51543 -232.3555) (xy 124.54595 -232.31349) (xy 124.582665 -232.276772)
			(xy 124.624671 -232.246248) (xy 124.670935 -232.222671) (xy 124.720318 -232.206621) (xy 124.771603 -232.198494)
			(xy 124.797566 -232.19791) (xy 124.808519 -232.197976) (xy 124.830381 -232.199374) (xy 124.841254 -232.200704)
			(xy 124.855637 -232.202116) (xy 124.884195 -232.197772) (xy 124.910397 -232.185613) (xy 124.932152 -232.166609)
			(xy 124.947722 -232.142278) (xy 124.955863 -232.114562) (xy 124.956316 -232.10012) (xy 124.956316 -231.826816)
			(xy 124.953776 -231.818942) (xy 124.945865 -231.79357) (xy 124.937315 -231.741119) (xy 124.936758 -231.714548)
			(xy 124.937311 -231.687977) (xy 124.945866 -231.635527) (xy 124.953776 -231.610154) (xy 124.956316 -231.60228)
			(xy 124.956316 -231.328722) (xy 124.955825 -231.31427) (xy 124.947746 -231.286518) (xy 124.932202 -231.26215)
			(xy 124.910444 -231.243124) (xy 124.88422 -231.23097) (xy 124.855638 -231.226665) (xy 124.841254 -231.228138)
			(xy 124.830382 -231.229474) (xy 124.80852 -231.230875) (xy 124.797566 -231.230932) (xy 124.771602 -231.23042)
			(xy 124.720315 -231.222292) (xy 124.67093 -231.206242) (xy 124.624664 -231.182664) (xy 124.582655 -231.152139)
			(xy 124.545939 -231.115419) (xy 124.515418 -231.073407) (xy 124.491845 -231.027139) (xy 124.4758 -230.977752)
			(xy 124.467677 -230.926464) (xy 124.467677 -230.874536) (xy 124.4758 -230.823248) (xy 124.491845 -230.773861)
			(xy 124.515418 -230.727593) (xy 124.545939 -230.685581) (xy 124.582655 -230.648861) (xy 124.624664 -230.618336)
			(xy 124.67093 -230.594758) (xy 124.720315 -230.578708) (xy 124.771602 -230.57058) (xy 124.797566 -230.570024)
			(xy 124.808519 -230.57009) (xy 124.830381 -230.571488) (xy 124.841254 -230.572818) (xy 124.855633 -230.57423)
			(xy 124.884182 -230.569886) (xy 124.910375 -230.557725) (xy 124.932117 -230.538718) (xy 124.947669 -230.514386)
			(xy 124.955789 -230.486672) (xy 124.956316 -230.472234) (xy 124.956316 -230.23449) (xy 124.965714 -230.225092)
			(xy 124.9553 -230.19512) (xy 124.946761 -230.168823) (xy 124.93757 -230.114305) (xy 124.937012 -230.086662)
			(xy 124.937524 -230.060696) (xy 124.945653 -230.009403) (xy 124.961704 -229.960014) (xy 124.985284 -229.913743)
			(xy 125.01581 -229.871729) (xy 125.052532 -229.835007) (xy 125.094546 -229.804482) (xy 125.140817 -229.780903)
			(xy 125.190207 -229.764852) (xy 125.2415 -229.756724) (xy 125.267466 -229.756208) (xy 125.29511 -229.756762)
			(xy 125.349629 -229.765948) (xy 125.375924 -229.774496) (xy 125.405896 -229.78491) (xy 125.522736 -229.66807)
			(xy 125.532197 -229.657966) (xy 125.545799 -229.633873) (xy 125.552416 -229.607008) (xy 125.551561 -229.579353)
			(xy 125.543296 -229.552948) (xy 125.528232 -229.529741) (xy 125.518164 -229.520242) (xy 125.497626 -229.501247)
			(xy 125.462614 -229.45762) (xy 125.435441 -229.408725) (xy 125.416881 -229.355955) (xy 125.407463 -229.300815)
			(xy 125.406912 -229.272846) (xy 125.407391 -229.246873) (xy 125.41551 -229.195567) (xy 125.431556 -229.146162)
			(xy 125.455132 -229.099875) (xy 125.48566 -229.057847) (xy 125.522386 -229.021112) (xy 125.564407 -228.990574)
			(xy 125.610688 -228.966986) (xy 125.660089 -228.950929) (xy 125.711393 -228.942798) (xy 125.737366 -228.942392)
			(xy 125.765335 -228.942974) (xy 125.820477 -228.952379) (xy 125.87325 -228.970927) (xy 125.92215 -228.998089)
			(xy 125.965784 -229.033091) (xy 125.984762 -229.053644) (xy 125.994282 -229.063668) (xy 126.0175 -229.078655)
			(xy 126.043884 -229.086873) (xy 126.071505 -229.087721) (xy 126.098344 -229.081136) (xy 126.122436 -229.067601)
			(xy 126.13259 -229.058216) (xy 126.230634 -228.960172) (xy 126.2404 -228.949744) (xy 126.254233 -228.92476)
			(xy 126.260602 -228.896921) (xy 126.25901 -228.868407) (xy 126.24958 -228.841451) (xy 126.233051 -228.818162)
			(xy 126.210717 -228.800365) (xy 126.184326 -228.789451) (xy 126.170182 -228.787452) (xy 126.143614 -228.783933)
			(xy 126.092028 -228.769414) (xy 126.043461 -228.746761) (xy 125.999186 -228.716568) (xy 125.960363 -228.679625)
			(xy 125.928012 -228.636902) (xy 125.902978 -228.589518) (xy 125.885919 -228.538715) (xy 125.877283 -228.485825)
			(xy 125.876812 -228.45903) (xy 125.877319 -228.43306) (xy 125.885439 -228.38176) (xy 125.901485 -228.332361)
			(xy 125.925061 -228.28608) (xy 125.955586 -228.244058) (xy 125.992309 -228.207327) (xy 126.034326 -228.176794)
			(xy 126.080602 -228.153209) (xy 126.129997 -228.137154) (xy 126.181296 -228.129024) (xy 126.207266 -228.128576)
			(xy 126.234054 -228.1291) (xy 126.286928 -228.137752) (xy 126.337714 -228.154819) (xy 126.385082 -228.179853)
			(xy 126.427793 -228.2122) (xy 126.464727 -228.251012) (xy 126.494918 -228.295272) (xy 126.517574 -228.343823)
			(xy 126.532103 -228.395392) (xy 126.535688 -228.421946) (xy 126.537782 -228.436062) (xy 126.548729 -228.462403)
			(xy 126.56653 -228.484692) (xy 126.589798 -228.501193) (xy 126.61672 -228.51062) (xy 126.645199 -228.512238)
			(xy 126.673016 -228.505922) (xy 126.698004 -228.492163) (xy 126.708408 -228.482398) (xy 126.831598 -228.359208)
			(xy 126.835408 -228.34854) (xy 126.844014 -228.325609) (xy 126.867022 -228.282374) (xy 126.896161 -228.243008)
			(xy 126.930791 -228.208376) (xy 126.970154 -228.179234) (xy 127.013388 -228.156223) (xy 127.036322 -228.147626)
			(xy 127.04699 -228.143816) (xy 127.348742 -227.842064) (xy 127.329438 -227.808536) (xy 127.315857 -227.783435)
			(xy 127.296588 -227.72972) (xy 127.286829 -227.673494) (xy 127.286258 -227.64496) (xy 127.28677 -227.618995)
			(xy 127.2949 -227.567706) (xy 127.310952 -227.518319) (xy 127.334532 -227.472052) (xy 127.365059 -227.430042)
			(xy 127.401782 -227.393325) (xy 127.443796 -227.362805) (xy 127.490067 -227.339232) (xy 127.539456 -227.323187)
			(xy 127.590747 -227.315066) (xy 127.616712 -227.314506) (xy 127.645246 -227.315082) (xy 127.701475 -227.324832)
			(xy 127.755194 -227.344091) (xy 127.780288 -227.357686) (xy 127.813816 -227.37699) (xy 127.92456 -227.266246)
			(xy 127.934874 -227.255162) (xy 127.949077 -227.228442) (xy 127.954826 -227.198732) (xy 127.951616 -227.168642)
			(xy 127.939729 -227.140814) (xy 127.920208 -227.117691) (xy 127.907796 -227.10902) (xy 127.884976 -227.093641)
			(xy 127.84432 -227.056561) (xy 127.810364 -227.013261) (xy 127.784043 -226.964939) (xy 127.766085 -226.912925)
			(xy 127.756986 -226.858657) (xy 127.756412 -226.831144) (xy 127.756892 -226.805171) (xy 127.765011 -226.753865)
			(xy 127.781056 -226.70446) (xy 127.804633 -226.658174) (xy 127.835161 -226.616146) (xy 127.871887 -226.579411)
			(xy 127.913908 -226.548874) (xy 127.960188 -226.525286) (xy 128.009589 -226.509229) (xy 128.060894 -226.501098)
			(xy 128.086866 -226.50069) (xy 128.114381 -226.501234) (xy 128.168653 -226.510337) (xy 128.22067 -226.528298)
			(xy 128.268995 -226.554622) (xy 128.312298 -226.588581) (xy 128.349381 -226.62924) (xy 128.364742 -226.652074)
			(xy 128.373413 -226.664475) (xy 128.396545 -226.683958) (xy 128.424365 -226.695819) (xy 128.454439 -226.699019)
			(xy 128.484132 -226.693279) (xy 128.510846 -226.679101) (xy 128.521968 -226.668838) (xy 129.165604 -226.025202)
			(xy 129.166366 -226.005136) (xy 129.167768 -225.979817) (xy 129.177368 -225.930027) (xy 129.194462 -225.882287)
			(xy 129.218647 -225.837719) (xy 129.249357 -225.797369) (xy 129.28587 -225.762183) (xy 129.327329 -225.732988)
			(xy 129.372762 -225.710468) (xy 129.421101 -225.695154) (xy 129.471212 -225.687402) (xy 129.496566 -225.686874)
			(xy 129.522104 -225.687347) (xy 129.572574 -225.695199) (xy 129.621235 -225.710722) (xy 129.666929 -225.733545)
			(xy 129.708567 -225.763126) (xy 129.727198 -225.7806) (xy 130.205734 -225.7806) (xy 130.224366 -225.763129)
			(xy 130.266009 -225.733559) (xy 130.311703 -225.710744) (xy 130.360363 -225.695225) (xy 130.410829 -225.687372)
			(xy 130.461903 -225.687372) (xy 130.512369 -225.695225) (xy 130.561029 -225.710744) (xy 130.606723 -225.733559)
			(xy 130.648366 -225.763129) (xy 130.666998 -225.7806) (xy 131.145534 -225.7806) (xy 131.164166 -225.763129)
			(xy 131.205809 -225.733559) (xy 131.251503 -225.710744) (xy 131.300163 -225.695225) (xy 131.350629 -225.687372)
			(xy 131.401703 -225.687372) (xy 131.452169 -225.695225) (xy 131.500829 -225.710744) (xy 131.546523 -225.733559)
			(xy 131.588166 -225.763129) (xy 131.606798 -225.7806) (xy 132.085334 -225.7806) (xy 132.103966 -225.763129)
			(xy 132.145609 -225.733559) (xy 132.191303 -225.710744) (xy 132.239963 -225.695225) (xy 132.290429 -225.687372)
			(xy 132.341503 -225.687372) (xy 132.391969 -225.695225) (xy 132.440629 -225.710744) (xy 132.486323 -225.733559)
			(xy 132.527966 -225.763129) (xy 132.546598 -225.7806) (xy 133.025134 -225.7806) (xy 133.043766 -225.763127)
			(xy 133.085409 -225.733551) (xy 133.131102 -225.710725) (xy 133.17976 -225.695193) (xy 133.230228 -225.687323)
			(xy 133.255766 -225.686874) (xy 133.27265 -225.687086) (xy 133.306244 -225.690521) (xy 133.322822 -225.693732)
			(xy 133.349746 -225.69932) (xy 133.480556 -225.56851) (xy 133.491152 -225.557068) (xy 133.505465 -225.52938)
			(xy 133.510775 -225.498667) (xy 133.506589 -225.46778) (xy 133.493296 -225.439588) (xy 133.483096 -225.427794)
			(xy 133.466665 -225.409354) (xy 133.438896 -225.368513) (xy 133.417511 -225.323995) (xy 133.402987 -225.276791)
			(xy 133.395646 -225.227952) (xy 133.395212 -225.203258) (xy 133.395724 -225.177292) (xy 133.403854 -225.126)
			(xy 133.419906 -225.076611) (xy 133.443485 -225.03034) (xy 133.474011 -224.988327) (xy 133.510733 -224.951606)
			(xy 133.552747 -224.921081) (xy 133.599018 -224.897503) (xy 133.648408 -224.881452) (xy 133.6997 -224.873324)
			(xy 133.725666 -224.872804) (xy 133.750357 -224.873266) (xy 133.799188 -224.880617) (xy 133.846385 -224.895145)
			(xy 133.890897 -224.916528) (xy 133.931735 -224.944291) (xy 133.950202 -224.960688) (xy 133.962006 -224.97088)
			(xy 133.990185 -224.984206) (xy 134.021072 -224.988402) (xy 134.051784 -224.983076) (xy 134.079454 -224.968725)
			(xy 134.090918 -224.958148) (xy 134.220966 -224.8281) (xy 134.157974 -224.718626) (xy 134.13486 -224.714308)
			(xy 134.109915 -224.709173) (xy 134.061879 -224.692255) (xy 134.017008 -224.668168) (xy 133.976364 -224.637481)
			(xy 133.940909 -224.600921) (xy 133.911484 -224.559354) (xy 133.888786 -224.513765) (xy 133.873351 -224.465232)
			(xy 133.865546 -224.414906) (xy 133.865112 -224.389442) (xy 133.865592 -224.36347) (xy 133.873711 -224.312163)
			(xy 133.889757 -224.262759) (xy 133.913334 -224.216473) (xy 133.943861 -224.174445) (xy 133.980587 -224.137711)
			(xy 134.022608 -224.107174) (xy 134.068889 -224.083586) (xy 134.118289 -224.067529) (xy 134.169594 -224.059398)
			(xy 134.195566 -224.058988) (xy 134.205305 -224.059061) (xy 134.224748 -224.060205) (xy 134.234428 -224.061274)
			(xy 134.248702 -224.062464) (xy 134.276947 -224.057788) (xy 134.302787 -224.045461) (xy 134.324194 -224.026449)
			(xy 134.339487 -224.002246) (xy 134.347465 -223.97475) (xy 134.347966 -223.960436) (xy 134.347966 -223.667574)
			(xy 134.346188 -223.66097) (xy 134.340969 -223.640021) (xy 134.335361 -223.597213) (xy 134.335012 -223.575626)
			(xy 134.335332 -223.554037) (xy 134.340945 -223.511227) (xy 134.346188 -223.490282) (xy 134.347966 -223.483678)
			(xy 134.347966 -223.190562) (xy 134.347486 -223.176241) (xy 134.339538 -223.148723) (xy 134.324253 -223.1245)
			(xy 134.302835 -223.105483) (xy 134.276974 -223.093172) (xy 134.248709 -223.088536) (xy 134.234428 -223.089724)
			(xy 134.224749 -223.0908) (xy 134.205305 -223.091946) (xy 134.195566 -223.09201) (xy 134.169604 -223.091498)
			(xy 134.11832 -223.083371) (xy 134.068938 -223.067321) (xy 134.022675 -223.043745) (xy 133.98067 -223.013222)
			(xy 133.943956 -222.976504) (xy 133.913437 -222.934496) (xy 133.889866 -222.88823) (xy 133.873821 -222.838847)
			(xy 133.865699 -222.787562) (xy 133.865699 -222.735638) (xy 133.873821 -222.684353) (xy 133.889866 -222.63497)
			(xy 133.913437 -222.588704) (xy 133.943956 -222.546696) (xy 133.98067 -222.509978) (xy 134.022675 -222.479455)
			(xy 134.068938 -222.455879) (xy 134.11832 -222.439829) (xy 134.169604 -222.431702) (xy 134.195566 -222.431102)
			(xy 134.205305 -222.431175) (xy 134.224748 -222.432318) (xy 134.234428 -222.433388) (xy 134.248698 -222.434578)
			(xy 134.276935 -222.429903) (xy 134.302765 -222.417573) (xy 134.324159 -222.398559) (xy 134.339434 -222.374354)
			(xy 134.347392 -222.346861) (xy 134.347966 -222.33255) (xy 134.347966 -222.04045) (xy 134.346188 -222.033846)
			(xy 134.340849 -222.012721) (xy 134.335118 -221.969526) (xy 134.334758 -221.94774) (xy 134.335106 -221.925953)
			(xy 134.340842 -221.882758) (xy 134.346188 -221.861634) (xy 134.347966 -221.85503) (xy 134.347966 -221.56293)
			(xy 134.347482 -221.548612) (xy 134.339529 -221.521102) (xy 134.324242 -221.496887) (xy 134.302826 -221.477877)
			(xy 134.276969 -221.46557) (xy 134.24871 -221.460936) (xy 134.234428 -221.462092) (xy 134.224749 -221.463168)
			(xy 134.205305 -221.464314) (xy 134.195566 -221.464378) (xy 134.1696 -221.463866) (xy 134.118308 -221.455738)
			(xy 134.068918 -221.439686) (xy 134.022647 -221.416107) (xy 133.980634 -221.385581) (xy 133.943913 -221.348859)
			(xy 133.913387 -221.306844) (xy 133.88981 -221.260573) (xy 133.87376 -221.211183) (xy 133.865633 -221.15989)
			(xy 133.865112 -221.133924) (xy 133.865723 -221.105944) (xy 133.875171 -221.050785) (xy 133.883908 -221.024196)
			(xy 133.891528 -221.002098) (xy 133.68782 -220.649038) (xy 133.66496 -220.64472) (xy 133.640014 -220.639585)
			(xy 133.591978 -220.622668) (xy 133.547105 -220.598581) (xy 133.50646 -220.567894) (xy 133.471005 -220.531334)
			(xy 133.441578 -220.489767) (xy 133.418878 -220.444178) (xy 133.403442 -220.395645) (xy 133.395635 -220.345318)
			(xy 133.395212 -220.319854) (xy 133.395721 -220.293887) (xy 133.403846 -220.242592) (xy 133.419894 -220.193199)
			(xy 133.443472 -220.146925) (xy 133.473998 -220.104909) (xy 133.510721 -220.068186) (xy 133.552737 -220.03766)
			(xy 133.599011 -220.014082) (xy 133.648404 -219.998034) (xy 133.699699 -219.989909) (xy 133.751633 -219.989909)
			(xy 133.802928 -219.998034) (xy 133.852321 -220.014082) (xy 133.898595 -220.03766) (xy 133.940611 -220.068186)
			(xy 133.977334 -220.104909) (xy 134.00786 -220.146925) (xy 134.031438 -220.193199) (xy 134.047486 -220.242592)
			(xy 134.055611 -220.293887) (xy 134.05612 -220.319854) (xy 134.055511 -220.347835) (xy 134.046067 -220.402995)
			(xy 134.037324 -220.429582) (xy 134.029704 -220.451426) (xy 134.233666 -220.80474) (xy 134.256526 -220.809058)
			(xy 134.283704 -220.815408) (xy 134.290308 -220.817186) (xy 134.347966 -220.817186) (xy 134.347966 -220.412564)
			(xy 134.346188 -220.40596) (xy 134.340848 -220.384835) (xy 134.335115 -220.34164) (xy 134.334758 -220.319854)
			(xy 134.335105 -220.298067) (xy 134.340839 -220.254871) (xy 134.346188 -220.233748) (xy 134.347966 -220.227144)
			(xy 134.347966 -219.935044) (xy 134.347483 -219.920724) (xy 134.339533 -219.893211) (xy 134.324247 -219.868993)
			(xy 134.30283 -219.84998) (xy 134.276971 -219.837671) (xy 134.24871 -219.833036) (xy 134.234428 -219.834206)
			(xy 134.224749 -219.835282) (xy 134.205305 -219.836428) (xy 134.195566 -219.836492) (xy 134.169598 -219.83598)
			(xy 134.118301 -219.827851) (xy 134.068907 -219.811797) (xy 134.022633 -219.788215) (xy 133.980617 -219.757684)
			(xy 133.943893 -219.720958) (xy 133.913367 -219.678938) (xy 133.88979 -219.632662) (xy 133.873741 -219.583266)
			(xy 133.865617 -219.531969) (xy 133.865617 -219.480032) (xy 133.873741 -219.428734) (xy 133.88979 -219.379339)
			(xy 133.913367 -219.333062) (xy 133.943893 -219.291042) (xy 133.980617 -219.254316) (xy 134.022633 -219.223785)
			(xy 134.068907 -219.200203) (xy 134.118301 -219.184149) (xy 134.169598 -219.17602) (xy 134.195566 -219.175584)
			(xy 134.205305 -219.175657) (xy 134.224748 -219.176801) (xy 134.234428 -219.17787) (xy 134.248701 -219.17906)
			(xy 134.276947 -219.174384) (xy 134.302786 -219.162057) (xy 134.324192 -219.143045) (xy 134.339484 -219.118842)
			(xy 134.347462 -219.091346) (xy 134.347966 -219.077032) (xy 134.347966 -218.78417) (xy 134.346188 -218.777566)
			(xy 134.340969 -218.756617) (xy 134.335362 -218.713809) (xy 134.335012 -218.692222) (xy 134.335332 -218.670633)
			(xy 134.340945 -218.627823) (xy 134.346188 -218.606878) (xy 134.347966 -218.600274) (xy 134.347966 -218.307412)
			(xy 134.347479 -218.293095) (xy 134.339524 -218.26559) (xy 134.324236 -218.24138) (xy 134.30282 -218.222374)
			(xy 134.276966 -218.210069) (xy 134.248711 -218.205436) (xy 134.234428 -218.206574) (xy 134.224749 -218.207652)
			(xy 134.205305 -218.208798) (xy 134.195566 -218.20886) (xy 134.1696 -218.208348) (xy 134.118309 -218.20022)
			(xy 134.068921 -218.184168) (xy 134.022651 -218.160589) (xy 133.980639 -218.130062) (xy 133.94392 -218.093339)
			(xy 133.913397 -218.051325) (xy 133.889821 -218.005053) (xy 133.873774 -217.955664) (xy 133.86565 -217.904372)
			(xy 133.865112 -217.878406) (xy 133.865725 -217.850426) (xy 133.875176 -217.795268) (xy 133.883908 -217.768678)
			(xy 133.891528 -217.74658) (xy 133.68782 -217.39352) (xy 133.664706 -217.389202) (xy 133.638008 -217.383651)
			(xy 133.586778 -217.364981) (xy 133.53931 -217.338151) (xy 133.496892 -217.303889) (xy 133.460678 -217.263127)
			(xy 133.43165 -217.21697) (xy 133.410597 -217.166672) (xy 133.39809 -217.1136) (xy 133.39572 -217.086434)
			(xy 133.39445 -217.067384) (xy 133.288532 -216.961466) (xy 133.278498 -216.952119) (xy 133.254618 -216.93866)
			(xy 133.228017 -216.932042) (xy 133.200614 -216.932743) (xy 133.174386 -216.940711) (xy 133.151225 -216.955372)
			(xy 133.1328 -216.975668) (xy 133.120442 -217.000136) (xy 133.115041 -217.02701) (xy 133.115558 -217.040714)
			(xy 133.11632 -217.064336) (xy 133.115808 -217.090299) (xy 133.10768 -217.141586) (xy 133.091629 -217.19097)
			(xy 133.06805 -217.237235) (xy 133.037525 -217.279242) (xy 133.000805 -217.315957) (xy 132.958793 -217.346476)
			(xy 132.912525 -217.370047) (xy 132.863139 -217.386091) (xy 132.811851 -217.394212) (xy 132.759924 -217.39421)
			(xy 132.708637 -217.386085) (xy 132.659252 -217.370038) (xy 132.612985 -217.346463) (xy 132.570976 -217.31594)
			(xy 132.534258 -217.279223) (xy 132.503736 -217.237213) (xy 132.480161 -217.190946) (xy 132.464114 -217.141561)
			(xy 132.45599 -217.090274) (xy 132.455988 -217.038347) (xy 132.464109 -216.987059) (xy 132.480153 -216.937673)
			(xy 132.503725 -216.891405) (xy 132.534244 -216.849394) (xy 132.57096 -216.812673) (xy 132.612967 -216.782148)
			(xy 132.659232 -216.75857) (xy 132.708616 -216.74252) (xy 132.759903 -216.734392) (xy 132.785866 -216.733882)
			(xy 132.809488 -216.734644) (xy 132.823203 -216.735197) (xy 132.850112 -216.729833) (xy 132.874616 -216.71749)
			(xy 132.894944 -216.699062) (xy 132.909624 -216.675881) (xy 132.917593 -216.649626) (xy 132.918275 -216.622197)
			(xy 132.91162 -216.595578) (xy 132.89811 -216.571697) (xy 132.888736 -216.56167) (xy 132.746496 -216.41943)
			(xy 132.735536 -216.409216) (xy 132.709131 -216.395091) (xy 132.679764 -216.389236) (xy 132.649961 -216.392153)
			(xy 132.622287 -216.403591) (xy 132.599122 -216.422568) (xy 132.590286 -216.43467) (xy 132.574815 -216.456798)
			(xy 132.537867 -216.496164) (xy 132.495004 -216.528992) (xy 132.44737 -216.554405) (xy 132.396234 -216.571725)
			(xy 132.342961 -216.580492) (xy 132.315966 -216.580974) (xy 132.29 -216.580462) (xy 132.238708 -216.572334)
			(xy 132.189319 -216.556282) (xy 132.143048 -216.532703) (xy 132.101035 -216.502177) (xy 132.064314 -216.465454)
			(xy 132.033789 -216.42344) (xy 132.010212 -216.377168) (xy 131.994163 -216.327779) (xy 131.986037 -216.276486)
			(xy 131.985512 -216.25052) (xy 131.985981 -216.224825) (xy 131.993889 -216.174048) (xy 132.00126 -216.149428)
			(xy 132.005015 -216.136269) (xy 132.006151 -216.108938) (xy 131.99999 -216.082287) (xy 131.986973 -216.058228)
			(xy 131.968036 -216.038489) (xy 131.944537 -216.024487) (xy 131.918163 -216.017228) (xy 131.904486 -216.01684)
			(xy 131.787646 -216.01684) (xy 131.773976 -216.017288) (xy 131.747618 -216.024555) (xy 131.724133 -216.038554)
			(xy 131.705203 -216.058281) (xy 131.692184 -216.082323) (xy 131.686009 -216.108957) (xy 131.687121 -216.136275)
			(xy 131.690872 -216.149428) (xy 131.698246 -216.174047) (xy 131.706149 -216.224825) (xy 131.70662 -216.25052)
			(xy 131.706136 -216.276487) (xy 131.698008 -216.327782) (xy 131.681956 -216.377174) (xy 131.658375 -216.423446)
			(xy 131.627845 -216.46546) (xy 131.591119 -216.50218) (xy 131.5491 -216.532703) (xy 131.502824 -216.556277)
			(xy 131.453429 -216.572321) (xy 131.402133 -216.58044) (xy 131.376166 -216.580974) (xy 131.349131 -216.580433)
			(xy 131.295782 -216.57163) (xy 131.244576 -216.554266) (xy 131.196877 -216.528802) (xy 131.153956 -216.495918)
			(xy 131.116958 -216.456488) (xy 131.086866 -216.411565) (xy 131.064485 -216.362344) (xy 131.050409 -216.310138)
			(xy 131.047236 -216.283286) (xy 131.045196 -216.267961) (xy 131.033126 -216.239516) (xy 131.013087 -216.215994)
			(xy 130.986922 -216.199556) (xy 130.957033 -216.191712) (xy 130.941572 -216.191846) (xy 130.906012 -216.192608)
			(xy 130.87096 -216.191846) (xy 130.855499 -216.191678) (xy 130.825615 -216.199554) (xy 130.799451 -216.216003)
			(xy 130.779401 -216.23952) (xy 130.767298 -216.267957) (xy 130.765296 -216.283286) (xy 130.762083 -216.310136)
			(xy 130.74804 -216.362352) (xy 130.725681 -216.411584) (xy 130.695601 -216.456517) (xy 130.658605 -216.495951)
			(xy 130.615681 -216.528833) (xy 130.567974 -216.554285) (xy 130.516758 -216.571627) (xy 130.463402 -216.580396)
			(xy 130.436366 -216.580974) (xy 130.4104 -216.580462) (xy 130.359108 -216.572334) (xy 130.309719 -216.556282)
			(xy 130.263448 -216.532703) (xy 130.221435 -216.502177) (xy 130.184714 -216.465454) (xy 130.154189 -216.42344)
			(xy 130.130612 -216.377168) (xy 130.114563 -216.327779) (xy 130.106437 -216.276486) (xy 130.105912 -216.25052)
			(xy 130.106381 -216.224825) (xy 130.114289 -216.174048) (xy 130.12166 -216.149428) (xy 130.125415 -216.136269)
			(xy 130.126551 -216.108938) (xy 130.12039 -216.082287) (xy 130.107373 -216.058228) (xy 130.088436 -216.038489)
			(xy 130.064937 -216.024487) (xy 130.038563 -216.017228) (xy 130.024886 -216.01684) (xy 129.908046 -216.01684)
			(xy 129.894376 -216.017288) (xy 129.868018 -216.024555) (xy 129.844533 -216.038554) (xy 129.825603 -216.058281)
			(xy 129.812584 -216.082323) (xy 129.806409 -216.108957) (xy 129.807521 -216.136275) (xy 129.811272 -216.149428)
			(xy 129.818646 -216.174047) (xy 129.826549 -216.224825) (xy 129.82702 -216.25052) (xy 129.826536 -216.276487)
			(xy 129.818408 -216.327782) (xy 129.802356 -216.377174) (xy 129.778775 -216.423446) (xy 129.748245 -216.46546)
			(xy 129.711519 -216.50218) (xy 129.6695 -216.532703) (xy 129.623224 -216.556277) (xy 129.573829 -216.572321)
			(xy 129.522533 -216.58044) (xy 129.496566 -216.580974) (xy 129.469531 -216.580433) (xy 129.416182 -216.57163)
			(xy 129.364976 -216.554266) (xy 129.317277 -216.528802) (xy 129.274356 -216.495918) (xy 129.237358 -216.456488)
			(xy 129.207266 -216.411565) (xy 129.184885 -216.362344) (xy 129.170809 -216.310138) (xy 129.167636 -216.283286)
			(xy 129.165596 -216.267961) (xy 129.153526 -216.239516) (xy 129.133487 -216.215994) (xy 129.107322 -216.199556)
			(xy 129.077433 -216.191712) (xy 129.061972 -216.191846) (xy 129.026412 -216.192608) (xy 128.99136 -216.191846)
			(xy 128.975899 -216.191678) (xy 128.946015 -216.199554) (xy 128.919851 -216.216003) (xy 128.899801 -216.23952)
			(xy 128.887698 -216.267957) (xy 128.885696 -216.283286) (xy 128.882483 -216.310136) (xy 128.86844 -216.362352)
			(xy 128.846081 -216.411584) (xy 128.816001 -216.456517) (xy 128.779005 -216.495951) (xy 128.736081 -216.528833)
			(xy 128.688374 -216.554285) (xy 128.637158 -216.571627) (xy 128.583802 -216.580396) (xy 128.556766 -216.580974)
			(xy 128.5308 -216.580462) (xy 128.479508 -216.572334) (xy 128.430119 -216.556282) (xy 128.383848 -216.532703)
			(xy 128.341835 -216.502177) (xy 128.305114 -216.465454) (xy 128.274589 -216.42344) (xy 128.251012 -216.377168)
			(xy 128.234963 -216.327779) (xy 128.226837 -216.276486) (xy 128.226312 -216.25052) (xy 128.226781 -216.224825)
			(xy 128.234689 -216.174048) (xy 128.24206 -216.149428) (xy 128.245815 -216.136269) (xy 128.246951 -216.108938)
			(xy 128.24079 -216.082287) (xy 128.227773 -216.058228) (xy 128.208836 -216.038489) (xy 128.185337 -216.024487)
			(xy 128.158963 -216.017228) (xy 128.145286 -216.01684) (xy 128.028446 -216.01684) (xy 128.014776 -216.017288)
			(xy 127.988418 -216.024555) (xy 127.964933 -216.038554) (xy 127.946003 -216.058281) (xy 127.932984 -216.082323)
			(xy 127.926809 -216.108957) (xy 127.927921 -216.136275) (xy 127.931672 -216.149428) (xy 127.939046 -216.174047)
			(xy 127.946949 -216.224825) (xy 127.94742 -216.25052) (xy 127.946936 -216.276487) (xy 127.938808 -216.327782)
			(xy 127.922756 -216.377174) (xy 127.899175 -216.423446) (xy 127.868645 -216.46546) (xy 127.831919 -216.50218)
			(xy 127.7899 -216.532703) (xy 127.743624 -216.556277) (xy 127.694229 -216.572321) (xy 127.642933 -216.58044)
			(xy 127.616966 -216.580974) (xy 127.589931 -216.580433) (xy 127.536582 -216.57163) (xy 127.485376 -216.554266)
			(xy 127.437677 -216.528802) (xy 127.394756 -216.495918) (xy 127.357758 -216.456488) (xy 127.327666 -216.411565)
			(xy 127.305285 -216.362344) (xy 127.291209 -216.310138) (xy 127.288036 -216.283286) (xy 127.285996 -216.267961)
			(xy 127.273926 -216.239516) (xy 127.253887 -216.215994) (xy 127.227722 -216.199556) (xy 127.197833 -216.191712)
			(xy 127.182372 -216.191846) (xy 127.146812 -216.192608) (xy 127.11176 -216.191846) (xy 127.096299 -216.191678)
			(xy 127.066415 -216.199554) (xy 127.040251 -216.216003) (xy 127.020201 -216.23952) (xy 127.008098 -216.267957)
			(xy 127.006096 -216.283286) (xy 127.002883 -216.310136) (xy 126.98884 -216.362352) (xy 126.966481 -216.411584)
			(xy 126.936401 -216.456517) (xy 126.899405 -216.495951) (xy 126.856481 -216.528833) (xy 126.808774 -216.554285)
			(xy 126.757558 -216.571627) (xy 126.704202 -216.580396) (xy 126.677166 -216.580974) (xy 126.6512 -216.580462)
			(xy 126.599908 -216.572334) (xy 126.550519 -216.556282) (xy 126.504248 -216.532703) (xy 126.462235 -216.502177)
			(xy 126.425514 -216.465454) (xy 126.394989 -216.42344) (xy 126.371412 -216.377168) (xy 126.355363 -216.327779)
			(xy 126.347237 -216.276486) (xy 126.346712 -216.25052) (xy 126.347203 -216.224426) (xy 126.355402 -216.172886)
			(xy 126.371599 -216.123275) (xy 126.395392 -216.076827) (xy 126.42619 -216.034695) (xy 126.463226 -215.997927)
			(xy 126.484126 -215.982296) (xy 126.496381 -215.972838) (xy 126.514988 -215.948116) (xy 126.525362 -215.918965)
			(xy 126.526556 -215.888046) (xy 126.51846 -215.858182) (xy 126.510542 -215.844882) (xy 126.491502 -215.8144)
			(xy 126.458621 -215.750488) (xy 126.431953 -215.683744) (xy 126.411738 -215.614771) (xy 126.398159 -215.544191)
			(xy 126.391339 -215.472641) (xy 126.390908 -215.436704) (xy 126.391142 -215.408851) (xy 126.395208 -215.353295)
			(xy 126.399036 -215.325706) (xy 126.371566 -215.314604) (xy 126.318292 -215.288663) (xy 126.29261 -215.27389)
			(xy 126.283866 -215.269239) (xy 126.264294 -215.266333) (xy 126.245081 -215.271062) (xy 126.229094 -215.282721)
			(xy 126.223522 -215.290908) (xy 126.205481 -215.319442) (xy 126.165036 -215.3735) (xy 126.14275 -215.398858)
			(xy 126.130059 -215.43646) (xy 126.097865 -215.509004) (xy 126.078488 -215.543638) (xy 125.922024 -215.814656)
			(xy 125.903736 -215.844628) (xy 125.895853 -215.857936) (xy 125.88771 -215.887761) (xy 125.888843 -215.918657)
			(xy 125.899149 -215.947805) (xy 125.917687 -215.972547) (xy 125.929898 -215.982042) (xy 125.950858 -215.997665)
			(xy 125.988028 -216.034421) (xy 126.01894 -216.076576) (xy 126.042822 -216.123076) (xy 126.059076 -216.172759)
			(xy 126.067297 -216.224383) (xy 126.06782 -216.25052) (xy 126.067336 -216.276487) (xy 126.059208 -216.327782)
			(xy 126.043156 -216.377174) (xy 126.019575 -216.423446) (xy 125.989045 -216.46546) (xy 125.952319 -216.50218)
			(xy 125.9103 -216.532703) (xy 125.864024 -216.556277) (xy 125.814629 -216.572321) (xy 125.763333 -216.58044)
			(xy 125.737366 -216.580974) (xy 125.710331 -216.580433) (xy 125.656982 -216.57163) (xy 125.605776 -216.554266)
			(xy 125.558077 -216.528802) (xy 125.515156 -216.495918) (xy 125.478158 -216.456488) (xy 125.448066 -216.411565)
			(xy 125.425685 -216.362344) (xy 125.411609 -216.310138) (xy 125.408436 -216.283286) (xy 125.406396 -216.267961)
			(xy 125.394326 -216.239516) (xy 125.374287 -216.215994) (xy 125.348122 -216.199556) (xy 125.318233 -216.191712)
			(xy 125.302772 -216.191846) (xy 125.267212 -216.192608) (xy 125.23216 -216.191846) (xy 125.216699 -216.191678)
			(xy 125.186815 -216.199554) (xy 125.160651 -216.216003) (xy 125.140601 -216.23952) (xy 125.128498 -216.267957)
			(xy 125.126496 -216.283286) (xy 125.123283 -216.310136) (xy 125.10924 -216.362352) (xy 125.086881 -216.411584)
			(xy 125.056801 -216.456517) (xy 125.019805 -216.495951) (xy 124.976881 -216.528833) (xy 124.929174 -216.554285)
			(xy 124.877958 -216.571627) (xy 124.824602 -216.580396) (xy 124.797566 -216.580974) (xy 124.7716 -216.580462)
			(xy 124.720308 -216.572334) (xy 124.670919 -216.556282) (xy 124.624648 -216.532703) (xy 124.582635 -216.502177)
			(xy 124.545914 -216.465454) (xy 124.515389 -216.42344) (xy 124.491812 -216.377168) (xy 124.475763 -216.327779)
			(xy 124.467637 -216.276486) (xy 124.467112 -216.25052) (xy 124.467603 -216.224426) (xy 124.475802 -216.172886)
			(xy 124.491999 -216.123275) (xy 124.515792 -216.076827) (xy 124.54659 -216.034695) (xy 124.583626 -215.997927)
			(xy 124.604526 -215.982296) (xy 124.616781 -215.972838) (xy 124.635388 -215.948116) (xy 124.645762 -215.918965)
			(xy 124.646956 -215.888046) (xy 124.63886 -215.858182) (xy 124.630942 -215.844882) (xy 124.611902 -215.8144)
			(xy 124.579021 -215.750488) (xy 124.552353 -215.683744) (xy 124.532138 -215.614771) (xy 124.518559 -215.544191)
			(xy 124.511739 -215.472641) (xy 124.511308 -215.436704) (xy 124.511542 -215.408851) (xy 124.515608 -215.353295)
			(xy 124.519436 -215.325706) (xy 124.491966 -215.314604) (xy 124.438692 -215.288663) (xy 124.41301 -215.27389)
			(xy 124.404266 -215.269239) (xy 124.384694 -215.266333) (xy 124.365481 -215.271062) (xy 124.349494 -215.282721)
			(xy 124.343922 -215.290908) (xy 124.325881 -215.319442) (xy 124.285436 -215.3735) (xy 124.26315 -215.398858)
			(xy 124.250459 -215.43646) (xy 124.218265 -215.509004) (xy 124.198888 -215.543638) (xy 124.042424 -215.814656)
			(xy 124.024136 -215.844628) (xy 124.016253 -215.857936) (xy 124.00811 -215.887761) (xy 124.009243 -215.918657)
			(xy 124.019549 -215.947805) (xy 124.038087 -215.972547) (xy 124.050298 -215.982042) (xy 124.071258 -215.997665)
			(xy 124.108428 -216.034421) (xy 124.13934 -216.076576) (xy 124.163222 -216.123076) (xy 124.179476 -216.172759)
			(xy 124.187697 -216.224383) (xy 124.18822 -216.25052) (xy 124.187736 -216.276487) (xy 124.179608 -216.327782)
			(xy 124.163556 -216.377174) (xy 124.139975 -216.423446) (xy 124.109445 -216.46546) (xy 124.072719 -216.50218)
			(xy 124.0307 -216.532703) (xy 123.984424 -216.556277) (xy 123.935029 -216.572321) (xy 123.883733 -216.58044)
			(xy 123.857766 -216.580974) (xy 123.830731 -216.580433) (xy 123.777382 -216.57163) (xy 123.726176 -216.554266)
			(xy 123.678477 -216.528802) (xy 123.635556 -216.495918) (xy 123.598558 -216.456488) (xy 123.568466 -216.411565)
			(xy 123.546085 -216.362344) (xy 123.532009 -216.310138) (xy 123.528836 -216.283286) (xy 123.526796 -216.267961)
			(xy 123.514726 -216.239516) (xy 123.494687 -216.215994) (xy 123.468522 -216.199556) (xy 123.438633 -216.191712)
			(xy 123.423172 -216.191846) (xy 123.387612 -216.192608) (xy 123.35256 -216.191846) (xy 123.337099 -216.191678)
			(xy 123.307215 -216.199554) (xy 123.281051 -216.216003) (xy 123.261001 -216.23952) (xy 123.248898 -216.267957)
			(xy 123.246896 -216.283286) (xy 123.243683 -216.310136) (xy 123.22964 -216.362352) (xy 123.207281 -216.411584)
			(xy 123.177201 -216.456517) (xy 123.140205 -216.495951) (xy 123.097281 -216.528833) (xy 123.049574 -216.554285)
			(xy 122.998358 -216.571627) (xy 122.945002 -216.580396) (xy 122.917966 -216.580974) (xy 122.892 -216.580462)
			(xy 122.840708 -216.572334) (xy 122.791319 -216.556282) (xy 122.745048 -216.532703) (xy 122.703035 -216.502177)
			(xy 122.666314 -216.465454) (xy 122.635789 -216.42344) (xy 122.612212 -216.377168) (xy 122.596163 -216.327779)
			(xy 122.588037 -216.276486) (xy 122.587512 -216.25052) (xy 122.588003 -216.224426) (xy 122.596202 -216.172886)
			(xy 122.612399 -216.123275) (xy 122.636192 -216.076827) (xy 122.66699 -216.034695) (xy 122.704026 -215.997927)
			(xy 122.724926 -215.982296) (xy 122.737181 -215.972838) (xy 122.755788 -215.948116) (xy 122.766162 -215.918965)
			(xy 122.767356 -215.888046) (xy 122.75926 -215.858182) (xy 122.751342 -215.844882) (xy 122.732302 -215.8144)
			(xy 122.699421 -215.750488) (xy 122.672753 -215.683744) (xy 122.652538 -215.614771) (xy 122.638959 -215.544191)
			(xy 122.632139 -215.472641) (xy 122.631708 -215.436704) (xy 122.631942 -215.408851) (xy 122.636008 -215.353295)
			(xy 122.639836 -215.325706) (xy 122.612366 -215.314604) (xy 122.559092 -215.288663) (xy 122.53341 -215.27389)
			(xy 122.524666 -215.269239) (xy 122.505094 -215.266333) (xy 122.485881 -215.271062) (xy 122.469894 -215.282721)
			(xy 122.464322 -215.290908) (xy 122.446281 -215.319442) (xy 122.405836 -215.3735) (xy 122.38355 -215.398858)
			(xy 122.370859 -215.43646) (xy 122.338665 -215.509004) (xy 122.319288 -215.543638) (xy 122.162824 -215.814656)
			(xy 122.144536 -215.844628) (xy 122.136653 -215.857936) (xy 122.12851 -215.887761) (xy 122.129643 -215.918657)
			(xy 122.139949 -215.947805) (xy 122.158487 -215.972547) (xy 122.170698 -215.982042) (xy 122.191658 -215.997665)
			(xy 122.228828 -216.034421) (xy 122.25974 -216.076576) (xy 122.283622 -216.123076) (xy 122.299876 -216.172759)
			(xy 122.308097 -216.224383) (xy 122.30862 -216.25052) (xy 122.308136 -216.276487) (xy 122.300008 -216.327782)
			(xy 122.283956 -216.377174) (xy 122.260375 -216.423446) (xy 122.229845 -216.46546) (xy 122.193119 -216.50218)
			(xy 122.1511 -216.532703) (xy 122.104824 -216.556277) (xy 122.055429 -216.572321) (xy 122.004133 -216.58044)
			(xy 121.978166 -216.580974) (xy 121.951131 -216.580433) (xy 121.897782 -216.57163) (xy 121.846576 -216.554266)
			(xy 121.798877 -216.528802) (xy 121.755956 -216.495918) (xy 121.718958 -216.456488) (xy 121.688866 -216.411565)
			(xy 121.666485 -216.362344) (xy 121.652409 -216.310138) (xy 121.649236 -216.283286) (xy 121.647196 -216.267961)
			(xy 121.635126 -216.239516) (xy 121.615087 -216.215994) (xy 121.588922 -216.199556) (xy 121.559033 -216.191712)
			(xy 121.543572 -216.191846) (xy 121.508012 -216.192608) (xy 121.47296 -216.191846) (xy 121.457499 -216.191678)
			(xy 121.427615 -216.199554) (xy 121.401451 -216.216003) (xy 121.381401 -216.23952) (xy 121.369298 -216.267957)
			(xy 121.367296 -216.283286) (xy 121.364083 -216.310136) (xy 121.35004 -216.362352) (xy 121.327681 -216.411584)
			(xy 121.297601 -216.456517) (xy 121.260605 -216.495951) (xy 121.217681 -216.528833) (xy 121.169974 -216.554285)
			(xy 121.118758 -216.571627) (xy 121.065402 -216.580396) (xy 121.038366 -216.580974) (xy 121.0124 -216.580462)
			(xy 120.961108 -216.572334) (xy 120.911719 -216.556282) (xy 120.865448 -216.532703) (xy 120.823435 -216.502177)
			(xy 120.786714 -216.465454) (xy 120.756189 -216.42344) (xy 120.732612 -216.377168) (xy 120.716563 -216.327779)
			(xy 120.708437 -216.276486) (xy 120.707912 -216.25052) (xy 120.708403 -216.224426) (xy 120.716602 -216.172886)
			(xy 120.732799 -216.123275) (xy 120.756592 -216.076827) (xy 120.78739 -216.034695) (xy 120.824426 -215.997927)
			(xy 120.845326 -215.982296) (xy 120.857581 -215.972838) (xy 120.876188 -215.948116) (xy 120.886562 -215.918965)
			(xy 120.887756 -215.888046) (xy 120.87966 -215.858182) (xy 120.871742 -215.844882) (xy 120.852702 -215.8144)
			(xy 120.819821 -215.750488) (xy 120.793153 -215.683744) (xy 120.772938 -215.614771) (xy 120.759359 -215.544191)
			(xy 120.752539 -215.472641) (xy 120.752108 -215.436704) (xy 120.752342 -215.408851) (xy 120.756408 -215.353295)
			(xy 120.760236 -215.325706) (xy 120.732766 -215.314604) (xy 120.679492 -215.288663) (xy 120.65381 -215.27389)
			(xy 120.645066 -215.269239) (xy 120.625494 -215.266333) (xy 120.606281 -215.271062) (xy 120.590294 -215.282721)
			(xy 120.584722 -215.290908) (xy 120.566681 -215.319442) (xy 120.526236 -215.3735) (xy 120.50395 -215.398858)
			(xy 120.491259 -215.43646) (xy 120.459065 -215.509004) (xy 120.439688 -215.543638) (xy 120.283224 -215.814656)
			(xy 120.264936 -215.844628) (xy 120.257053 -215.857936) (xy 120.24891 -215.887761) (xy 120.250043 -215.918657)
			(xy 120.260349 -215.947805) (xy 120.278887 -215.972547) (xy 120.291098 -215.982042) (xy 120.312058 -215.997665)
			(xy 120.349228 -216.034421) (xy 120.38014 -216.076576) (xy 120.404022 -216.123076) (xy 120.420276 -216.172759)
			(xy 120.428497 -216.224383) (xy 120.42902 -216.25052) (xy 120.428536 -216.276487) (xy 120.420408 -216.327782)
			(xy 120.404356 -216.377174) (xy 120.380775 -216.423446) (xy 120.350245 -216.46546) (xy 120.313519 -216.50218)
			(xy 120.2715 -216.532703) (xy 120.225224 -216.556277) (xy 120.175829 -216.572321) (xy 120.124533 -216.58044)
			(xy 120.098566 -216.580974) (xy 120.071531 -216.580433) (xy 120.018182 -216.57163) (xy 119.966976 -216.554266)
			(xy 119.919277 -216.528802) (xy 119.876356 -216.495918) (xy 119.839358 -216.456488) (xy 119.809266 -216.411565)
			(xy 119.786885 -216.362344) (xy 119.772809 -216.310138) (xy 119.769636 -216.283286) (xy 119.767596 -216.267961)
			(xy 119.755526 -216.239516) (xy 119.735487 -216.215994) (xy 119.709322 -216.199556) (xy 119.679433 -216.191712)
			(xy 119.663972 -216.191846) (xy 119.628412 -216.192608) (xy 119.59336 -216.191846) (xy 119.577899 -216.191678)
			(xy 119.548015 -216.199554) (xy 119.521851 -216.216003) (xy 119.501801 -216.23952) (xy 119.489698 -216.267957)
			(xy 119.487696 -216.283286) (xy 119.484483 -216.310136) (xy 119.47044 -216.362352) (xy 119.448081 -216.411584)
			(xy 119.418001 -216.456517) (xy 119.381005 -216.495951) (xy 119.338081 -216.528833) (xy 119.290374 -216.554285)
			(xy 119.239158 -216.571627) (xy 119.185802 -216.580396) (xy 119.158766 -216.580974) (xy 119.1328 -216.580462)
			(xy 119.081508 -216.572334) (xy 119.032119 -216.556282) (xy 118.985848 -216.532703) (xy 118.943835 -216.502177)
			(xy 118.907114 -216.465454) (xy 118.876589 -216.42344) (xy 118.853012 -216.377168) (xy 118.836963 -216.327779)
			(xy 118.828837 -216.276486) (xy 118.828312 -216.25052) (xy 118.828803 -216.224426) (xy 118.837002 -216.172886)
			(xy 118.853199 -216.123275) (xy 118.876992 -216.076827) (xy 118.90779 -216.034695) (xy 118.944826 -215.997927)
			(xy 118.965726 -215.982296) (xy 118.977981 -215.972838) (xy 118.996588 -215.948116) (xy 119.006962 -215.918965)
			(xy 119.008156 -215.888046) (xy 119.00006 -215.858182) (xy 118.992142 -215.844882) (xy 118.973102 -215.8144)
			(xy 118.940221 -215.750488) (xy 118.913553 -215.683744) (xy 118.893338 -215.614771) (xy 118.879759 -215.544191)
			(xy 118.872939 -215.472641) (xy 118.872508 -215.436704) (xy 118.872742 -215.408851) (xy 118.876808 -215.353295)
			(xy 118.880636 -215.325706) (xy 118.853166 -215.314604) (xy 118.799892 -215.288663) (xy 118.77421 -215.27389)
			(xy 118.765466 -215.269239) (xy 118.745894 -215.266333) (xy 118.726681 -215.271062) (xy 118.710694 -215.282721)
			(xy 118.705122 -215.290908) (xy 118.687081 -215.319442) (xy 118.646636 -215.3735) (xy 118.62435 -215.398858)
			(xy 118.611659 -215.43646) (xy 118.579465 -215.509004) (xy 118.560088 -215.543638) (xy 118.403624 -215.814656)
			(xy 118.385336 -215.844628) (xy 118.377453 -215.857936) (xy 118.36931 -215.887761) (xy 118.370443 -215.918657)
			(xy 118.380749 -215.947805) (xy 118.399287 -215.972547) (xy 118.411498 -215.982042) (xy 118.432458 -215.997665)
			(xy 118.469628 -216.034421) (xy 118.50054 -216.076576) (xy 118.524422 -216.123076) (xy 118.540676 -216.172759)
			(xy 118.548897 -216.224383) (xy 118.54942 -216.25052) (xy 118.548936 -216.276487) (xy 118.540808 -216.327782)
			(xy 118.524756 -216.377174) (xy 118.501175 -216.423446) (xy 118.470645 -216.46546) (xy 118.433919 -216.50218)
			(xy 118.3919 -216.532703) (xy 118.345624 -216.556277) (xy 118.296229 -216.572321) (xy 118.244933 -216.58044)
			(xy 118.218966 -216.580974) (xy 118.191931 -216.580433) (xy 118.138582 -216.57163) (xy 118.087376 -216.554266)
			(xy 118.039677 -216.528802) (xy 117.996756 -216.495918) (xy 117.959758 -216.456488) (xy 117.929666 -216.411565)
			(xy 117.907285 -216.362344) (xy 117.893209 -216.310138) (xy 117.890036 -216.283286) (xy 117.887996 -216.267961)
			(xy 117.875926 -216.239516) (xy 117.855887 -216.215994) (xy 117.829722 -216.199556) (xy 117.799833 -216.191712)
			(xy 117.784372 -216.191846) (xy 117.748812 -216.192608) (xy 117.71376 -216.191846) (xy 117.698299 -216.191678)
			(xy 117.668415 -216.199554) (xy 117.642251 -216.216003) (xy 117.622201 -216.23952) (xy 117.610098 -216.267957)
			(xy 117.608096 -216.283286) (xy 117.604883 -216.310136) (xy 117.59084 -216.362352) (xy 117.568481 -216.411584)
			(xy 117.538401 -216.456517) (xy 117.501405 -216.495951) (xy 117.458481 -216.528833) (xy 117.410774 -216.554285)
			(xy 117.359558 -216.571627) (xy 117.306202 -216.580396) (xy 117.279166 -216.580974) (xy 117.2532 -216.580462)
			(xy 117.201908 -216.572334) (xy 117.152519 -216.556282) (xy 117.106248 -216.532703) (xy 117.064235 -216.502177)
			(xy 117.027514 -216.465454) (xy 116.996989 -216.42344) (xy 116.973412 -216.377168) (xy 116.957363 -216.327779)
			(xy 116.949237 -216.276486) (xy 116.948712 -216.25052) (xy 116.949203 -216.224426) (xy 116.957402 -216.172886)
			(xy 116.973599 -216.123275) (xy 116.997392 -216.076827) (xy 117.02819 -216.034695) (xy 117.065226 -215.997927)
			(xy 117.086126 -215.982296) (xy 117.098381 -215.972838) (xy 117.116988 -215.948116) (xy 117.127362 -215.918965)
			(xy 117.128556 -215.888046) (xy 117.12046 -215.858182) (xy 117.112542 -215.844882) (xy 117.093502 -215.8144)
			(xy 117.060621 -215.750488) (xy 117.033953 -215.683744) (xy 117.013738 -215.614771) (xy 117.000159 -215.544191)
			(xy 116.993339 -215.472641) (xy 116.992908 -215.436704) (xy 116.993142 -215.408851) (xy 116.997208 -215.353295)
			(xy 117.001036 -215.325706) (xy 116.973566 -215.314604) (xy 116.920292 -215.288663) (xy 116.89461 -215.27389)
			(xy 116.885866 -215.269239) (xy 116.866294 -215.266333) (xy 116.847081 -215.271062) (xy 116.831094 -215.282721)
			(xy 116.825522 -215.290908) (xy 116.807481 -215.319442) (xy 116.767036 -215.3735) (xy 116.74475 -215.398858)
			(xy 116.732059 -215.43646) (xy 116.699865 -215.509004) (xy 116.680488 -215.543638) (xy 116.524024 -215.814656)
			(xy 116.505736 -215.844628) (xy 116.497853 -215.857936) (xy 116.48971 -215.887761) (xy 116.490843 -215.918657)
			(xy 116.501149 -215.947805) (xy 116.519687 -215.972547) (xy 116.531898 -215.982042) (xy 116.552858 -215.997665)
			(xy 116.590028 -216.034421) (xy 116.62094 -216.076576) (xy 116.644822 -216.123076) (xy 116.661076 -216.172759)
			(xy 116.669297 -216.224383) (xy 116.66982 -216.25052) (xy 116.669336 -216.276487) (xy 116.661208 -216.327782)
			(xy 116.645156 -216.377174) (xy 116.621575 -216.423446) (xy 116.591045 -216.46546) (xy 116.554319 -216.50218)
			(xy 116.5123 -216.532703) (xy 116.466024 -216.556277) (xy 116.416629 -216.572321) (xy 116.365333 -216.58044)
			(xy 116.339366 -216.580974) (xy 116.312331 -216.580433) (xy 116.258982 -216.57163) (xy 116.207776 -216.554266)
			(xy 116.160077 -216.528802) (xy 116.117156 -216.495918) (xy 116.080158 -216.456488) (xy 116.050066 -216.411565)
			(xy 116.027685 -216.362344) (xy 116.013609 -216.310138) (xy 116.010436 -216.283286) (xy 116.008396 -216.267961)
			(xy 115.996326 -216.239516) (xy 115.976287 -216.215994) (xy 115.950122 -216.199556) (xy 115.920233 -216.191712)
			(xy 115.904772 -216.191846) (xy 115.869212 -216.192608) (xy 115.833906 -216.191846) (xy 115.81845 -216.191686)
			(xy 115.78858 -216.199572) (xy 115.76243 -216.216024) (xy 115.742393 -216.239539) (xy 115.730298 -216.267967)
			(xy 115.728242 -216.283286) (xy 115.725029 -216.310137) (xy 115.710987 -216.362357) (xy 115.688629 -216.411593)
			(xy 115.65855 -216.45653) (xy 115.621555 -216.495968) (xy 115.578631 -216.528856) (xy 115.530923 -216.554313)
			(xy 115.479707 -216.571662) (xy 115.42635 -216.580438) (xy 115.399312 -216.580974) (xy 115.373344 -216.580466)
			(xy 115.322046 -216.572343) (xy 115.27265 -216.556296) (xy 115.226373 -216.532719) (xy 115.184354 -216.502193)
			(xy 115.147628 -216.46547) (xy 115.117098 -216.423454) (xy 115.093517 -216.377179) (xy 115.077465 -216.327785)
			(xy 115.069337 -216.276488) (xy 115.068858 -216.25052) (xy 115.069351 -216.224396) (xy 115.077568 -216.172798)
			(xy 115.093799 -216.123135) (xy 115.117642 -216.076644) (xy 115.148501 -216.034483) (xy 115.185609 -215.997701)
			(xy 115.206526 -215.982042) (xy 115.218701 -215.972564) (xy 115.237159 -215.947856) (xy 115.247427 -215.918775)
			(xy 115.248574 -215.887956) (xy 115.240495 -215.858192) (xy 115.232688 -215.844882) (xy 115.223302 -215.829943)
			(xy 115.20577 -215.799323) (xy 115.197636 -215.783668) (xy 115.190049 -215.770188) (xy 115.168275 -215.748238)
			(xy 115.14093 -215.73381) (xy 115.110521 -215.728228) (xy 115.079834 -215.732002) (xy 115.065556 -215.737948)
			(xy 115.044066 -215.747201) (xy 114.999131 -215.760233) (xy 114.952806 -215.766788) (xy 114.929412 -215.767158)
			(xy 114.906156 -215.76676) (xy 114.860103 -215.760245) (xy 114.815412 -215.747356) (xy 114.79403 -215.738202)
			(xy 114.780176 -215.732542) (xy 114.750512 -215.728702) (xy 114.721011 -215.733639) (xy 114.694213 -215.746927)
			(xy 114.672428 -215.767424) (xy 114.66449 -215.780112) (xy 114.644424 -215.814656) (xy 114.626136 -215.844628)
			(xy 114.618253 -215.857936) (xy 114.61011 -215.887761) (xy 114.611243 -215.918657) (xy 114.621549 -215.947805)
			(xy 114.640087 -215.972547) (xy 114.652298 -215.982042) (xy 114.673258 -215.997665) (xy 114.710428 -216.034421)
			(xy 114.74134 -216.076576) (xy 114.765222 -216.123076) (xy 114.781476 -216.172759) (xy 114.789697 -216.224383)
			(xy 114.79022 -216.25052) (xy 114.789736 -216.276487) (xy 114.781608 -216.327782) (xy 114.765556 -216.377174)
			(xy 114.741975 -216.423446) (xy 114.711445 -216.46546) (xy 114.674719 -216.50218) (xy 114.6327 -216.532703)
			(xy 114.586424 -216.556277) (xy 114.537029 -216.572321) (xy 114.485733 -216.58044) (xy 114.459766 -216.580974)
			(xy 114.432731 -216.580433) (xy 114.379382 -216.57163) (xy 114.328176 -216.554266) (xy 114.280477 -216.528802)
			(xy 114.237556 -216.495918) (xy 114.200558 -216.456488) (xy 114.170466 -216.411565) (xy 114.148085 -216.362344)
			(xy 114.134009 -216.310138) (xy 114.130836 -216.283286) (xy 114.128796 -216.267961) (xy 114.116726 -216.239516)
			(xy 114.096687 -216.215994) (xy 114.070522 -216.199556) (xy 114.040633 -216.191712) (xy 114.025172 -216.191846)
			(xy 113.989612 -216.192608) (xy 113.95456 -216.191846) (xy 113.939099 -216.191678) (xy 113.909215 -216.199554)
			(xy 113.883051 -216.216003) (xy 113.863001 -216.23952) (xy 113.850898 -216.267957) (xy 113.848896 -216.283286)
			(xy 113.845683 -216.310136) (xy 113.83164 -216.362352) (xy 113.809281 -216.411584) (xy 113.779201 -216.456517)
			(xy 113.742205 -216.495951) (xy 113.699281 -216.528833) (xy 113.651574 -216.554285) (xy 113.600358 -216.571627)
			(xy 113.547002 -216.580396) (xy 113.519966 -216.580974) (xy 113.494 -216.580462) (xy 113.442708 -216.572334)
			(xy 113.393319 -216.556282) (xy 113.347048 -216.532703) (xy 113.305035 -216.502177) (xy 113.268314 -216.465454)
			(xy 113.237789 -216.42344) (xy 113.214212 -216.377168) (xy 113.198163 -216.327779) (xy 113.190037 -216.276486)
			(xy 113.189512 -216.25052) (xy 113.190003 -216.224426) (xy 113.198202 -216.172886) (xy 113.214399 -216.123275)
			(xy 113.238192 -216.076827) (xy 113.26899 -216.034695) (xy 113.306026 -215.997927) (xy 113.326926 -215.982296)
			(xy 113.339181 -215.972838) (xy 113.357788 -215.948116) (xy 113.368162 -215.918965) (xy 113.369356 -215.888046)
			(xy 113.36126 -215.858182) (xy 113.353342 -215.844882) (xy 113.343892 -215.829946) (xy 113.326233 -215.799326)
			(xy 113.318036 -215.783668) (xy 113.310449 -215.770188) (xy 113.288675 -215.748238) (xy 113.26133 -215.73381)
			(xy 113.230921 -215.728228) (xy 113.200234 -215.732002) (xy 113.185956 -215.737948) (xy 113.164466 -215.747201)
			(xy 113.119531 -215.760233) (xy 113.073206 -215.766788) (xy 113.049812 -215.767158) (xy 113.023842 -215.766676)
			(xy 112.972541 -215.758553) (xy 112.923143 -215.742504) (xy 112.876863 -215.718925) (xy 112.834842 -215.688396)
			(xy 112.798114 -215.65167) (xy 112.767584 -215.60965) (xy 112.744002 -215.563372) (xy 112.727951 -215.513974)
			(xy 112.719825 -215.462674) (xy 112.719358 -215.436704) (xy 112.720374 -215.411812) (xy 112.720984 -215.397856)
			(xy 112.715453 -215.370484) (xy 112.702711 -215.345634) (xy 112.683712 -215.325168) (xy 112.659877 -215.310616)
			(xy 112.632991 -215.303068) (xy 112.619028 -215.302592) (xy 112.579658 -215.302592) (xy 112.545368 -215.301576)
			(xy 112.530988 -215.301423) (xy 112.503049 -215.308183) (xy 112.478099 -215.322458) (xy 112.458115 -215.34312)
			(xy 112.444678 -215.368531) (xy 112.438853 -215.39668) (xy 112.43945 -215.41105) (xy 112.440466 -215.436704)
			(xy 112.439956 -215.462671) (xy 112.431832 -215.513967) (xy 112.415783 -215.563359) (xy 112.392205 -215.609634)
			(xy 112.361679 -215.65165) (xy 112.324956 -215.688374) (xy 112.28294 -215.718901) (xy 112.236667 -215.74248)
			(xy 112.187274 -215.75853) (xy 112.135979 -215.766656) (xy 112.110012 -215.767158) (xy 112.086619 -215.766769)
			(xy 112.040297 -215.76021) (xy 111.99536 -215.747193) (xy 111.973868 -215.737948) (xy 111.959574 -215.732075)
			(xy 111.928913 -215.728332) (xy 111.898533 -215.73392) (xy 111.87121 -215.748327) (xy 111.849439 -215.770238)
			(xy 111.841788 -215.783668) (xy 111.833648 -215.799258) (xy 111.816116 -215.829751) (xy 111.806736 -215.844628)
			(xy 111.798853 -215.857936) (xy 111.79071 -215.887761) (xy 111.791843 -215.918657) (xy 111.802149 -215.947805)
			(xy 111.820687 -215.972547) (xy 111.832898 -215.982042) (xy 111.853858 -215.997665) (xy 111.891028 -216.034421)
			(xy 111.92194 -216.076576) (xy 111.945822 -216.123076) (xy 111.962076 -216.172759) (xy 111.970297 -216.224383)
			(xy 111.97082 -216.25052) (xy 111.970336 -216.276487) (xy 112.249967 -216.276487) (xy 112.249967 -216.224553)
			(xy 112.258092 -216.173258) (xy 112.27414 -216.123865) (xy 112.297718 -216.077591) (xy 112.328244 -216.035575)
			(xy 112.364967 -215.998852) (xy 112.406983 -215.968326) (xy 112.453257 -215.944748) (xy 112.50265 -215.9287)
			(xy 112.553945 -215.920575) (xy 112.605879 -215.920575) (xy 112.657174 -215.9287) (xy 112.706567 -215.944748)
			(xy 112.752841 -215.968326) (xy 112.794857 -215.998852) (xy 112.83158 -216.035575) (xy 112.862106 -216.077591)
			(xy 112.885684 -216.123865) (xy 112.901732 -216.173258) (xy 112.909857 -216.224553) (xy 112.910366 -216.25052)
			(xy 112.909857 -216.276487) (xy 112.901732 -216.327782) (xy 112.885684 -216.377175) (xy 112.862106 -216.423449)
			(xy 112.83158 -216.465465) (xy 112.794857 -216.502188) (xy 112.752841 -216.532714) (xy 112.706567 -216.556292)
			(xy 112.657174 -216.57234) (xy 112.605879 -216.580465) (xy 112.553945 -216.580465) (xy 112.50265 -216.57234)
			(xy 112.453257 -216.556292) (xy 112.406983 -216.532714) (xy 112.364967 -216.502188) (xy 112.328244 -216.465465)
			(xy 112.297718 -216.423449) (xy 112.27414 -216.377175) (xy 112.258092 -216.327782) (xy 112.249967 -216.276487)
			(xy 111.970336 -216.276487) (xy 111.962208 -216.327782) (xy 111.946156 -216.377174) (xy 111.922575 -216.423446)
			(xy 111.892045 -216.46546) (xy 111.855319 -216.50218) (xy 111.8133 -216.532703) (xy 111.767024 -216.556277)
			(xy 111.717629 -216.572321) (xy 111.666333 -216.58044) (xy 111.640366 -216.580974) (xy 111.63808 -216.580974)
			(xy 111.62802 -216.581345) (xy 111.609402 -216.588964) (xy 111.595135 -216.603145) (xy 111.587405 -216.621716)
			(xy 111.587026 -216.631774) (xy 111.587026 -217.090303) (xy 111.780321 -217.090303) (xy 111.780321 -217.038369)
			(xy 111.788446 -216.987074) (xy 111.804494 -216.937681) (xy 111.828072 -216.891407) (xy 111.858598 -216.849391)
			(xy 111.895321 -216.812668) (xy 111.937337 -216.782142) (xy 111.983611 -216.758564) (xy 112.033004 -216.742516)
			(xy 112.084299 -216.734391) (xy 112.136233 -216.734391) (xy 112.187528 -216.742516) (xy 112.236921 -216.758564)
			(xy 112.283195 -216.782142) (xy 112.325211 -216.812668) (xy 112.361934 -216.849391) (xy 112.39246 -216.891407)
			(xy 112.416038 -216.937681) (xy 112.432086 -216.987074) (xy 112.440211 -217.038369) (xy 112.44072 -217.064336)
			(xy 112.719358 -217.064336) (xy 112.719867 -217.038369) (xy 112.727992 -216.987074) (xy 112.74404 -216.937681)
			(xy 112.767618 -216.891407) (xy 112.798144 -216.849391) (xy 112.834867 -216.812668) (xy 112.876883 -216.782142)
			(xy 112.923157 -216.758564) (xy 112.97255 -216.742516) (xy 113.023845 -216.734391) (xy 113.075779 -216.734391)
			(xy 113.127074 -216.742516) (xy 113.176467 -216.758564) (xy 113.222741 -216.782142) (xy 113.264757 -216.812668)
			(xy 113.30148 -216.849391) (xy 113.332006 -216.891407) (xy 113.355584 -216.937681) (xy 113.371632 -216.987074)
			(xy 113.379757 -217.038369) (xy 113.380266 -217.064336) (xy 113.379765 -217.090303) (xy 113.659921 -217.090303)
			(xy 113.659921 -217.038369) (xy 113.668046 -216.987074) (xy 113.684094 -216.937681) (xy 113.707672 -216.891407)
			(xy 113.738198 -216.849391) (xy 113.774921 -216.812668) (xy 113.816937 -216.782142) (xy 113.863211 -216.758564)
			(xy 113.912604 -216.742516) (xy 113.963899 -216.734391) (xy 114.015833 -216.734391) (xy 114.067128 -216.742516)
			(xy 114.116521 -216.758564) (xy 114.162795 -216.782142) (xy 114.204811 -216.812668) (xy 114.241534 -216.849391)
			(xy 114.27206 -216.891407) (xy 114.295638 -216.937681) (xy 114.311686 -216.987074) (xy 114.319811 -217.038369)
			(xy 114.32032 -217.064336) (xy 114.598958 -217.064336) (xy 114.599467 -217.038369) (xy 114.607592 -216.987074)
			(xy 114.62364 -216.937681) (xy 114.647218 -216.891407) (xy 114.677744 -216.849391) (xy 114.714467 -216.812668)
			(xy 114.756483 -216.782142) (xy 114.802757 -216.758564) (xy 114.85215 -216.742516) (xy 114.903445 -216.734391)
			(xy 114.955379 -216.734391) (xy 115.006674 -216.742516) (xy 115.056067 -216.758564) (xy 115.102341 -216.782142)
			(xy 115.144357 -216.812668) (xy 115.18108 -216.849391) (xy 115.211606 -216.891407) (xy 115.235184 -216.937681)
			(xy 115.251232 -216.987074) (xy 115.259357 -217.038369) (xy 115.259866 -217.064336) (xy 115.259365 -217.090303)
			(xy 115.539521 -217.090303) (xy 115.539521 -217.038369) (xy 115.547646 -216.987074) (xy 115.563694 -216.937681)
			(xy 115.587272 -216.891407) (xy 115.617798 -216.849391) (xy 115.654521 -216.812668) (xy 115.696537 -216.782142)
			(xy 115.742811 -216.758564) (xy 115.792204 -216.742516) (xy 115.843499 -216.734391) (xy 115.895433 -216.734391)
			(xy 115.946728 -216.742516) (xy 115.996121 -216.758564) (xy 116.042395 -216.782142) (xy 116.084411 -216.812668)
			(xy 116.121134 -216.849391) (xy 116.15166 -216.891407) (xy 116.175238 -216.937681) (xy 116.191286 -216.987074)
			(xy 116.199411 -217.038369) (xy 116.19992 -217.064336) (xy 116.478558 -217.064336) (xy 116.479067 -217.038369)
			(xy 116.487192 -216.987074) (xy 116.50324 -216.937681) (xy 116.526818 -216.891407) (xy 116.557344 -216.849391)
			(xy 116.594067 -216.812668) (xy 116.636083 -216.782142) (xy 116.682357 -216.758564) (xy 116.73175 -216.742516)
			(xy 116.783045 -216.734391) (xy 116.834979 -216.734391) (xy 116.886274 -216.742516) (xy 116.935667 -216.758564)
			(xy 116.981941 -216.782142) (xy 117.023957 -216.812668) (xy 117.06068 -216.849391) (xy 117.091206 -216.891407)
			(xy 117.114784 -216.937681) (xy 117.130832 -216.987074) (xy 117.138957 -217.038369) (xy 117.139466 -217.064336)
			(xy 117.138965 -217.090303) (xy 117.419121 -217.090303) (xy 117.419121 -217.038369) (xy 117.427246 -216.987074)
			(xy 117.443294 -216.937681) (xy 117.466872 -216.891407) (xy 117.497398 -216.849391) (xy 117.534121 -216.812668)
			(xy 117.576137 -216.782142) (xy 117.622411 -216.758564) (xy 117.671804 -216.742516) (xy 117.723099 -216.734391)
			(xy 117.775033 -216.734391) (xy 117.826328 -216.742516) (xy 117.875721 -216.758564) (xy 117.921995 -216.782142)
			(xy 117.964011 -216.812668) (xy 118.000734 -216.849391) (xy 118.03126 -216.891407) (xy 118.054838 -216.937681)
			(xy 118.070886 -216.987074) (xy 118.079011 -217.038369) (xy 118.07952 -217.064336) (xy 118.358158 -217.064336)
			(xy 118.358667 -217.038369) (xy 118.366792 -216.987074) (xy 118.38284 -216.937681) (xy 118.406418 -216.891407)
			(xy 118.436944 -216.849391) (xy 118.473667 -216.812668) (xy 118.515683 -216.782142) (xy 118.561957 -216.758564)
			(xy 118.61135 -216.742516) (xy 118.662645 -216.734391) (xy 118.714579 -216.734391) (xy 118.765874 -216.742516)
			(xy 118.815267 -216.758564) (xy 118.861541 -216.782142) (xy 118.903557 -216.812668) (xy 118.94028 -216.849391)
			(xy 118.970806 -216.891407) (xy 118.994384 -216.937681) (xy 119.010432 -216.987074) (xy 119.018557 -217.038369)
			(xy 119.019066 -217.064336) (xy 119.018565 -217.090303) (xy 119.298721 -217.090303) (xy 119.298721 -217.038369)
			(xy 119.306846 -216.987074) (xy 119.322894 -216.937681) (xy 119.346472 -216.891407) (xy 119.376998 -216.849391)
			(xy 119.413721 -216.812668) (xy 119.455737 -216.782142) (xy 119.502011 -216.758564) (xy 119.551404 -216.742516)
			(xy 119.602699 -216.734391) (xy 119.654633 -216.734391) (xy 119.705928 -216.742516) (xy 119.755321 -216.758564)
			(xy 119.801595 -216.782142) (xy 119.843611 -216.812668) (xy 119.880334 -216.849391) (xy 119.91086 -216.891407)
			(xy 119.934438 -216.937681) (xy 119.950486 -216.987074) (xy 119.958611 -217.038369) (xy 119.95912 -217.064336)
			(xy 120.237758 -217.064336) (xy 120.238267 -217.038369) (xy 120.246392 -216.987074) (xy 120.26244 -216.937681)
			(xy 120.286018 -216.891407) (xy 120.316544 -216.849391) (xy 120.353267 -216.812668) (xy 120.395283 -216.782142)
			(xy 120.441557 -216.758564) (xy 120.49095 -216.742516) (xy 120.542245 -216.734391) (xy 120.594179 -216.734391)
			(xy 120.645474 -216.742516) (xy 120.694867 -216.758564) (xy 120.741141 -216.782142) (xy 120.783157 -216.812668)
			(xy 120.81988 -216.849391) (xy 120.850406 -216.891407) (xy 120.873984 -216.937681) (xy 120.890032 -216.987074)
			(xy 120.898157 -217.038369) (xy 120.898666 -217.064336) (xy 120.898165 -217.090303) (xy 121.178321 -217.090303)
			(xy 121.178321 -217.038369) (xy 121.186446 -216.987074) (xy 121.202494 -216.937681) (xy 121.226072 -216.891407)
			(xy 121.256598 -216.849391) (xy 121.293321 -216.812668) (xy 121.335337 -216.782142) (xy 121.381611 -216.758564)
			(xy 121.431004 -216.742516) (xy 121.482299 -216.734391) (xy 121.534233 -216.734391) (xy 121.585528 -216.742516)
			(xy 121.634921 -216.758564) (xy 121.681195 -216.782142) (xy 121.723211 -216.812668) (xy 121.759934 -216.849391)
			(xy 121.79046 -216.891407) (xy 121.814038 -216.937681) (xy 121.830086 -216.987074) (xy 121.838211 -217.038369)
			(xy 121.83872 -217.064336) (xy 122.117358 -217.064336) (xy 122.117867 -217.038369) (xy 122.125992 -216.987074)
			(xy 122.14204 -216.937681) (xy 122.165618 -216.891407) (xy 122.196144 -216.849391) (xy 122.232867 -216.812668)
			(xy 122.274883 -216.782142) (xy 122.321157 -216.758564) (xy 122.37055 -216.742516) (xy 122.421845 -216.734391)
			(xy 122.473779 -216.734391) (xy 122.525074 -216.742516) (xy 122.574467 -216.758564) (xy 122.620741 -216.782142)
			(xy 122.662757 -216.812668) (xy 122.69948 -216.849391) (xy 122.730006 -216.891407) (xy 122.753584 -216.937681)
			(xy 122.769632 -216.987074) (xy 122.777757 -217.038369) (xy 122.778266 -217.064336) (xy 122.777765 -217.090303)
			(xy 123.057921 -217.090303) (xy 123.057921 -217.038369) (xy 123.066046 -216.987074) (xy 123.082094 -216.937681)
			(xy 123.105672 -216.891407) (xy 123.136198 -216.849391) (xy 123.172921 -216.812668) (xy 123.214937 -216.782142)
			(xy 123.261211 -216.758564) (xy 123.310604 -216.742516) (xy 123.361899 -216.734391) (xy 123.413833 -216.734391)
			(xy 123.465128 -216.742516) (xy 123.514521 -216.758564) (xy 123.560795 -216.782142) (xy 123.602811 -216.812668)
			(xy 123.639534 -216.849391) (xy 123.67006 -216.891407) (xy 123.693638 -216.937681) (xy 123.709686 -216.987074)
			(xy 123.717811 -217.038369) (xy 123.71832 -217.064336) (xy 123.996958 -217.064336) (xy 123.997467 -217.038369)
			(xy 124.005592 -216.987074) (xy 124.02164 -216.937681) (xy 124.045218 -216.891407) (xy 124.075744 -216.849391)
			(xy 124.112467 -216.812668) (xy 124.154483 -216.782142) (xy 124.200757 -216.758564) (xy 124.25015 -216.742516)
			(xy 124.301445 -216.734391) (xy 124.353379 -216.734391) (xy 124.404674 -216.742516) (xy 124.454067 -216.758564)
			(xy 124.500341 -216.782142) (xy 124.542357 -216.812668) (xy 124.57908 -216.849391) (xy 124.609606 -216.891407)
			(xy 124.633184 -216.937681) (xy 124.649232 -216.987074) (xy 124.657357 -217.038369) (xy 124.657866 -217.064336)
			(xy 124.657365 -217.090303) (xy 124.937521 -217.090303) (xy 124.937521 -217.038369) (xy 124.945646 -216.987074)
			(xy 124.961694 -216.937681) (xy 124.985272 -216.891407) (xy 125.015798 -216.849391) (xy 125.052521 -216.812668)
			(xy 125.094537 -216.782142) (xy 125.140811 -216.758564) (xy 125.190204 -216.742516) (xy 125.241499 -216.734391)
			(xy 125.293433 -216.734391) (xy 125.344728 -216.742516) (xy 125.394121 -216.758564) (xy 125.440395 -216.782142)
			(xy 125.482411 -216.812668) (xy 125.519134 -216.849391) (xy 125.54966 -216.891407) (xy 125.573238 -216.937681)
			(xy 125.589286 -216.987074) (xy 125.597411 -217.038369) (xy 125.59792 -217.064336) (xy 125.876558 -217.064336)
			(xy 125.877067 -217.038369) (xy 125.885192 -216.987074) (xy 125.90124 -216.937681) (xy 125.924818 -216.891407)
			(xy 125.955344 -216.849391) (xy 125.992067 -216.812668) (xy 126.034083 -216.782142) (xy 126.080357 -216.758564)
			(xy 126.12975 -216.742516) (xy 126.181045 -216.734391) (xy 126.232979 -216.734391) (xy 126.284274 -216.742516)
			(xy 126.333667 -216.758564) (xy 126.379941 -216.782142) (xy 126.421957 -216.812668) (xy 126.45868 -216.849391)
			(xy 126.489206 -216.891407) (xy 126.512784 -216.937681) (xy 126.528832 -216.987074) (xy 126.536957 -217.038369)
			(xy 126.537466 -217.064336) (xy 126.536965 -217.090303) (xy 126.817121 -217.090303) (xy 126.817121 -217.038369)
			(xy 126.825246 -216.987074) (xy 126.841294 -216.937681) (xy 126.864872 -216.891407) (xy 126.895398 -216.849391)
			(xy 126.932121 -216.812668) (xy 126.974137 -216.782142) (xy 127.020411 -216.758564) (xy 127.069804 -216.742516)
			(xy 127.121099 -216.734391) (xy 127.173033 -216.734391) (xy 127.224328 -216.742516) (xy 127.273721 -216.758564)
			(xy 127.319995 -216.782142) (xy 127.362011 -216.812668) (xy 127.398734 -216.849391) (xy 127.42926 -216.891407)
			(xy 127.452838 -216.937681) (xy 127.468886 -216.987074) (xy 127.477011 -217.038369) (xy 127.47752 -217.064336)
			(xy 127.756158 -217.064336) (xy 127.756667 -217.038369) (xy 127.764792 -216.987074) (xy 127.78084 -216.937681)
			(xy 127.804418 -216.891407) (xy 127.834944 -216.849391) (xy 127.871667 -216.812668) (xy 127.913683 -216.782142)
			(xy 127.959957 -216.758564) (xy 128.00935 -216.742516) (xy 128.060645 -216.734391) (xy 128.112579 -216.734391)
			(xy 128.163874 -216.742516) (xy 128.213267 -216.758564) (xy 128.259541 -216.782142) (xy 128.301557 -216.812668)
			(xy 128.33828 -216.849391) (xy 128.368806 -216.891407) (xy 128.392384 -216.937681) (xy 128.408432 -216.987074)
			(xy 128.416557 -217.038369) (xy 128.417066 -217.064336) (xy 128.416565 -217.090303) (xy 128.696721 -217.090303)
			(xy 128.696721 -217.038369) (xy 128.704846 -216.987074) (xy 128.720894 -216.937681) (xy 128.744472 -216.891407)
			(xy 128.774998 -216.849391) (xy 128.811721 -216.812668) (xy 128.853737 -216.782142) (xy 128.900011 -216.758564)
			(xy 128.949404 -216.742516) (xy 129.000699 -216.734391) (xy 129.052633 -216.734391) (xy 129.103928 -216.742516)
			(xy 129.153321 -216.758564) (xy 129.199595 -216.782142) (xy 129.241611 -216.812668) (xy 129.278334 -216.849391)
			(xy 129.30886 -216.891407) (xy 129.332438 -216.937681) (xy 129.348486 -216.987074) (xy 129.356611 -217.038369)
			(xy 129.35712 -217.064336) (xy 129.635758 -217.064336) (xy 129.636267 -217.038369) (xy 129.644392 -216.987074)
			(xy 129.66044 -216.937681) (xy 129.684018 -216.891407) (xy 129.714544 -216.849391) (xy 129.751267 -216.812668)
			(xy 129.793283 -216.782142) (xy 129.839557 -216.758564) (xy 129.88895 -216.742516) (xy 129.940245 -216.734391)
			(xy 129.992179 -216.734391) (xy 130.043474 -216.742516) (xy 130.092867 -216.758564) (xy 130.139141 -216.782142)
			(xy 130.181157 -216.812668) (xy 130.21788 -216.849391) (xy 130.248406 -216.891407) (xy 130.271984 -216.937681)
			(xy 130.288032 -216.987074) (xy 130.296157 -217.038369) (xy 130.296666 -217.064336) (xy 130.296165 -217.090303)
			(xy 130.576321 -217.090303) (xy 130.576321 -217.038369) (xy 130.584446 -216.987074) (xy 130.600494 -216.937681)
			(xy 130.624072 -216.891407) (xy 130.654598 -216.849391) (xy 130.691321 -216.812668) (xy 130.733337 -216.782142)
			(xy 130.779611 -216.758564) (xy 130.829004 -216.742516) (xy 130.880299 -216.734391) (xy 130.932233 -216.734391)
			(xy 130.983528 -216.742516) (xy 131.032921 -216.758564) (xy 131.079195 -216.782142) (xy 131.121211 -216.812668)
			(xy 131.157934 -216.849391) (xy 131.18846 -216.891407) (xy 131.212038 -216.937681) (xy 131.228086 -216.987074)
			(xy 131.236211 -217.038369) (xy 131.23672 -217.064336) (xy 131.515358 -217.064336) (xy 131.515867 -217.038369)
			(xy 131.523992 -216.987074) (xy 131.54004 -216.937681) (xy 131.563618 -216.891407) (xy 131.594144 -216.849391)
			(xy 131.630867 -216.812668) (xy 131.672883 -216.782142) (xy 131.719157 -216.758564) (xy 131.76855 -216.742516)
			(xy 131.819845 -216.734391) (xy 131.871779 -216.734391) (xy 131.923074 -216.742516) (xy 131.972467 -216.758564)
			(xy 132.018741 -216.782142) (xy 132.060757 -216.812668) (xy 132.09748 -216.849391) (xy 132.128006 -216.891407)
			(xy 132.151584 -216.937681) (xy 132.167632 -216.987074) (xy 132.175757 -217.038369) (xy 132.176266 -217.064336)
			(xy 132.175727 -217.092245) (xy 132.166402 -217.147278) (xy 132.157724 -217.17381) (xy 132.14985 -217.195654)
			(xy 132.354066 -217.549222) (xy 132.376926 -217.55354) (xy 132.40184 -217.558742) (xy 132.449822 -217.575703)
			(xy 132.494638 -217.599816) (xy 132.535231 -217.630512) (xy 132.57064 -217.667066) (xy 132.600029 -217.708614)
			(xy 132.622705 -217.754174) (xy 132.638132 -217.802672) (xy 132.645945 -217.85296) (xy 132.64642 -217.878406)
			(xy 132.645911 -217.904373) (xy 132.637786 -217.955668) (xy 132.621738 -218.005061) (xy 132.59816 -218.051335)
			(xy 132.567634 -218.093351) (xy 132.530911 -218.130074) (xy 132.488895 -218.1606) (xy 132.442621 -218.184178)
			(xy 132.393228 -218.200226) (xy 132.341933 -218.208351) (xy 132.289999 -218.208351) (xy 132.238704 -218.200226)
			(xy 132.189311 -218.184178) (xy 132.143037 -218.1606) (xy 132.101021 -218.130074) (xy 132.064298 -218.093351)
			(xy 132.033772 -218.051335) (xy 132.010194 -218.005061) (xy 131.994146 -217.955668) (xy 131.986021 -217.904373)
			(xy 131.985512 -217.878406) (xy 131.986066 -217.85042) (xy 131.995515 -217.795252) (xy 132.004308 -217.768678)
			(xy 132.011928 -217.74658) (xy 131.80822 -217.39352) (xy 131.785106 -217.389202) (xy 131.760166 -217.384059)
			(xy 131.712142 -217.367128) (xy 131.667282 -217.343032) (xy 131.626649 -217.312342) (xy 131.591203 -217.275784)
			(xy 131.561782 -217.234221) (xy 131.539084 -217.188639) (xy 131.523645 -217.140115) (xy 131.51583 -217.089797)
			(xy 131.515358 -217.064336) (xy 131.23672 -217.064336) (xy 131.236211 -217.090303) (xy 131.228086 -217.141598)
			(xy 131.212038 -217.190991) (xy 131.18846 -217.237265) (xy 131.157934 -217.279281) (xy 131.121211 -217.316004)
			(xy 131.079195 -217.34653) (xy 131.032921 -217.370108) (xy 130.983528 -217.386156) (xy 130.932233 -217.394281)
			(xy 130.880299 -217.394281) (xy 130.829004 -217.386156) (xy 130.779611 -217.370108) (xy 130.733337 -217.34653)
			(xy 130.691321 -217.316004) (xy 130.654598 -217.279281) (xy 130.624072 -217.237265) (xy 130.600494 -217.190991)
			(xy 130.584446 -217.141598) (xy 130.576321 -217.090303) (xy 130.296165 -217.090303) (xy 130.296127 -217.092245)
			(xy 130.286802 -217.147278) (xy 130.278124 -217.17381) (xy 130.27025 -217.195654) (xy 130.474466 -217.549222)
			(xy 130.497326 -217.55354) (xy 130.52224 -217.558742) (xy 130.570222 -217.575703) (xy 130.615038 -217.599816)
			(xy 130.655631 -217.630512) (xy 130.69104 -217.667066) (xy 130.720429 -217.708614) (xy 130.743105 -217.754174)
			(xy 130.758532 -217.802672) (xy 130.766345 -217.85296) (xy 130.76682 -217.878406) (xy 130.766311 -217.904373)
			(xy 130.758186 -217.955668) (xy 130.742138 -218.005061) (xy 130.71856 -218.051335) (xy 130.688034 -218.093351)
			(xy 130.651311 -218.130074) (xy 130.609295 -218.1606) (xy 130.563021 -218.184178) (xy 130.513628 -218.200226)
			(xy 130.462333 -218.208351) (xy 130.410399 -218.208351) (xy 130.359104 -218.200226) (xy 130.309711 -218.184178)
			(xy 130.263437 -218.1606) (xy 130.221421 -218.130074) (xy 130.184698 -218.093351) (xy 130.154172 -218.051335)
			(xy 130.130594 -218.005061) (xy 130.114546 -217.955668) (xy 130.106421 -217.904373) (xy 130.105912 -217.878406)
			(xy 130.106466 -217.85042) (xy 130.115915 -217.795252) (xy 130.124708 -217.768678) (xy 130.132328 -217.74658)
			(xy 129.92862 -217.39352) (xy 129.905506 -217.389202) (xy 129.880566 -217.384059) (xy 129.832542 -217.367128)
			(xy 129.787682 -217.343032) (xy 129.747049 -217.312342) (xy 129.711603 -217.275784) (xy 129.682182 -217.234221)
			(xy 129.659484 -217.188639) (xy 129.644045 -217.140115) (xy 129.63623 -217.089797) (xy 129.635758 -217.064336)
			(xy 129.35712 -217.064336) (xy 129.356611 -217.090303) (xy 129.348486 -217.141598) (xy 129.332438 -217.190991)
			(xy 129.30886 -217.237265) (xy 129.278334 -217.279281) (xy 129.241611 -217.316004) (xy 129.199595 -217.34653)
			(xy 129.153321 -217.370108) (xy 129.103928 -217.386156) (xy 129.052633 -217.394281) (xy 129.000699 -217.394281)
			(xy 128.949404 -217.386156) (xy 128.900011 -217.370108) (xy 128.853737 -217.34653) (xy 128.811721 -217.316004)
			(xy 128.774998 -217.279281) (xy 128.744472 -217.237265) (xy 128.720894 -217.190991) (xy 128.704846 -217.141598)
			(xy 128.696721 -217.090303) (xy 128.416565 -217.090303) (xy 128.416527 -217.092245) (xy 128.407202 -217.147278)
			(xy 128.398524 -217.17381) (xy 128.39065 -217.195654) (xy 128.594866 -217.549222) (xy 128.617726 -217.55354)
			(xy 128.64264 -217.558742) (xy 128.690622 -217.575703) (xy 128.735438 -217.599816) (xy 128.776031 -217.630512)
			(xy 128.81144 -217.667066) (xy 128.840829 -217.708614) (xy 128.863505 -217.754174) (xy 128.878932 -217.802672)
			(xy 128.886745 -217.85296) (xy 128.88722 -217.878406) (xy 128.886711 -217.904373) (xy 128.878586 -217.955668)
			(xy 128.862538 -218.005061) (xy 128.83896 -218.051335) (xy 128.808434 -218.093351) (xy 128.771711 -218.130074)
			(xy 128.729695 -218.1606) (xy 128.683421 -218.184178) (xy 128.634028 -218.200226) (xy 128.582733 -218.208351)
			(xy 128.530799 -218.208351) (xy 128.479504 -218.200226) (xy 128.430111 -218.184178) (xy 128.383837 -218.1606)
			(xy 128.341821 -218.130074) (xy 128.305098 -218.093351) (xy 128.274572 -218.051335) (xy 128.250994 -218.005061)
			(xy 128.234946 -217.955668) (xy 128.226821 -217.904373) (xy 128.226312 -217.878406) (xy 128.226866 -217.85042)
			(xy 128.236315 -217.795252) (xy 128.245108 -217.768678) (xy 128.252728 -217.74658) (xy 128.04902 -217.39352)
			(xy 128.025906 -217.389202) (xy 128.000966 -217.384059) (xy 127.952942 -217.367128) (xy 127.908082 -217.343032)
			(xy 127.867449 -217.312342) (xy 127.832003 -217.275784) (xy 127.802582 -217.234221) (xy 127.779884 -217.188639)
			(xy 127.764445 -217.140115) (xy 127.75663 -217.089797) (xy 127.756158 -217.064336) (xy 127.47752 -217.064336)
			(xy 127.477011 -217.090303) (xy 127.468886 -217.141598) (xy 127.452838 -217.190991) (xy 127.42926 -217.237265)
			(xy 127.398734 -217.279281) (xy 127.362011 -217.316004) (xy 127.319995 -217.34653) (xy 127.273721 -217.370108)
			(xy 127.224328 -217.386156) (xy 127.173033 -217.394281) (xy 127.121099 -217.394281) (xy 127.069804 -217.386156)
			(xy 127.020411 -217.370108) (xy 126.974137 -217.34653) (xy 126.932121 -217.316004) (xy 126.895398 -217.279281)
			(xy 126.864872 -217.237265) (xy 126.841294 -217.190991) (xy 126.825246 -217.141598) (xy 126.817121 -217.090303)
			(xy 126.536965 -217.090303) (xy 126.536927 -217.092245) (xy 126.527602 -217.147278) (xy 126.518924 -217.17381)
			(xy 126.51105 -217.195654) (xy 126.715266 -217.549222) (xy 126.738126 -217.55354) (xy 126.76304 -217.558742)
			(xy 126.811022 -217.575703) (xy 126.855838 -217.599816) (xy 126.896431 -217.630512) (xy 126.93184 -217.667066)
			(xy 126.961229 -217.708614) (xy 126.983905 -217.754174) (xy 126.999332 -217.802672) (xy 127.007145 -217.85296)
			(xy 127.00762 -217.878406) (xy 127.007111 -217.904373) (xy 126.998986 -217.955668) (xy 126.982938 -218.005061)
			(xy 126.95936 -218.051335) (xy 126.928834 -218.093351) (xy 126.892111 -218.130074) (xy 126.850095 -218.1606)
			(xy 126.803821 -218.184178) (xy 126.754428 -218.200226) (xy 126.703133 -218.208351) (xy 126.651199 -218.208351)
			(xy 126.599904 -218.200226) (xy 126.550511 -218.184178) (xy 126.504237 -218.1606) (xy 126.462221 -218.130074)
			(xy 126.425498 -218.093351) (xy 126.394972 -218.051335) (xy 126.371394 -218.005061) (xy 126.355346 -217.955668)
			(xy 126.347221 -217.904373) (xy 126.346712 -217.878406) (xy 126.347266 -217.85042) (xy 126.356715 -217.795252)
			(xy 126.365508 -217.768678) (xy 126.373128 -217.74658) (xy 126.16942 -217.39352) (xy 126.146306 -217.389202)
			(xy 126.121366 -217.384059) (xy 126.073342 -217.367128) (xy 126.028482 -217.343032) (xy 125.987849 -217.312342)
			(xy 125.952403 -217.275784) (xy 125.922982 -217.234221) (xy 125.900284 -217.188639) (xy 125.884845 -217.140115)
			(xy 125.87703 -217.089797) (xy 125.876558 -217.064336) (xy 125.59792 -217.064336) (xy 125.597411 -217.090303)
			(xy 125.589286 -217.141598) (xy 125.573238 -217.190991) (xy 125.54966 -217.237265) (xy 125.519134 -217.279281)
			(xy 125.482411 -217.316004) (xy 125.440395 -217.34653) (xy 125.394121 -217.370108) (xy 125.344728 -217.386156)
			(xy 125.293433 -217.394281) (xy 125.241499 -217.394281) (xy 125.190204 -217.386156) (xy 125.140811 -217.370108)
			(xy 125.094537 -217.34653) (xy 125.052521 -217.316004) (xy 125.015798 -217.279281) (xy 124.985272 -217.237265)
			(xy 124.961694 -217.190991) (xy 124.945646 -217.141598) (xy 124.937521 -217.090303) (xy 124.657365 -217.090303)
			(xy 124.657327 -217.092245) (xy 124.648002 -217.147278) (xy 124.639324 -217.17381) (xy 124.63145 -217.195654)
			(xy 124.835666 -217.549222) (xy 124.858526 -217.55354) (xy 124.88344 -217.558742) (xy 124.931422 -217.575703)
			(xy 124.976238 -217.599816) (xy 125.016831 -217.630512) (xy 125.05224 -217.667066) (xy 125.081629 -217.708614)
			(xy 125.104305 -217.754174) (xy 125.119732 -217.802672) (xy 125.127545 -217.85296) (xy 125.12802 -217.878406)
			(xy 125.127511 -217.904373) (xy 125.119386 -217.955668) (xy 125.103338 -218.005061) (xy 125.07976 -218.051335)
			(xy 125.049234 -218.093351) (xy 125.012511 -218.130074) (xy 124.970495 -218.1606) (xy 124.924221 -218.184178)
			(xy 124.874828 -218.200226) (xy 124.823533 -218.208351) (xy 124.771599 -218.208351) (xy 124.720304 -218.200226)
			(xy 124.670911 -218.184178) (xy 124.624637 -218.1606) (xy 124.582621 -218.130074) (xy 124.545898 -218.093351)
			(xy 124.515372 -218.051335) (xy 124.491794 -218.005061) (xy 124.475746 -217.955668) (xy 124.467621 -217.904373)
			(xy 124.467112 -217.878406) (xy 124.467666 -217.85042) (xy 124.477115 -217.795252) (xy 124.485908 -217.768678)
			(xy 124.493528 -217.74658) (xy 124.28982 -217.39352) (xy 124.266706 -217.389202) (xy 124.241766 -217.384059)
			(xy 124.193742 -217.367128) (xy 124.148882 -217.343032) (xy 124.108249 -217.312342) (xy 124.072803 -217.275784)
			(xy 124.043382 -217.234221) (xy 124.020684 -217.188639) (xy 124.005245 -217.140115) (xy 123.99743 -217.089797)
			(xy 123.996958 -217.064336) (xy 123.71832 -217.064336) (xy 123.717811 -217.090303) (xy 123.709686 -217.141598)
			(xy 123.693638 -217.190991) (xy 123.67006 -217.237265) (xy 123.639534 -217.279281) (xy 123.602811 -217.316004)
			(xy 123.560795 -217.34653) (xy 123.514521 -217.370108) (xy 123.465128 -217.386156) (xy 123.413833 -217.394281)
			(xy 123.361899 -217.394281) (xy 123.310604 -217.386156) (xy 123.261211 -217.370108) (xy 123.214937 -217.34653)
			(xy 123.172921 -217.316004) (xy 123.136198 -217.279281) (xy 123.105672 -217.237265) (xy 123.082094 -217.190991)
			(xy 123.066046 -217.141598) (xy 123.057921 -217.090303) (xy 122.777765 -217.090303) (xy 122.777727 -217.092245)
			(xy 122.768402 -217.147278) (xy 122.759724 -217.17381) (xy 122.75185 -217.195654) (xy 122.956066 -217.549222)
			(xy 122.978926 -217.55354) (xy 123.00384 -217.558742) (xy 123.051822 -217.575703) (xy 123.096638 -217.599816)
			(xy 123.137231 -217.630512) (xy 123.17264 -217.667066) (xy 123.202029 -217.708614) (xy 123.224705 -217.754174)
			(xy 123.240132 -217.802672) (xy 123.247945 -217.85296) (xy 123.24842 -217.878406) (xy 123.247911 -217.904373)
			(xy 123.239786 -217.955668) (xy 123.223738 -218.005061) (xy 123.20016 -218.051335) (xy 123.169634 -218.093351)
			(xy 123.132911 -218.130074) (xy 123.090895 -218.1606) (xy 123.044621 -218.184178) (xy 122.995228 -218.200226)
			(xy 122.943933 -218.208351) (xy 122.891999 -218.208351) (xy 122.840704 -218.200226) (xy 122.791311 -218.184178)
			(xy 122.745037 -218.1606) (xy 122.703021 -218.130074) (xy 122.666298 -218.093351) (xy 122.635772 -218.051335)
			(xy 122.612194 -218.005061) (xy 122.596146 -217.955668) (xy 122.588021 -217.904373) (xy 122.587512 -217.878406)
			(xy 122.588066 -217.85042) (xy 122.597515 -217.795252) (xy 122.606308 -217.768678) (xy 122.613928 -217.74658)
			(xy 122.41022 -217.39352) (xy 122.387106 -217.389202) (xy 122.362166 -217.384059) (xy 122.314142 -217.367128)
			(xy 122.269282 -217.343032) (xy 122.228649 -217.312342) (xy 122.193203 -217.275784) (xy 122.163782 -217.234221)
			(xy 122.141084 -217.188639) (xy 122.125645 -217.140115) (xy 122.11783 -217.089797) (xy 122.117358 -217.064336)
			(xy 121.83872 -217.064336) (xy 121.838211 -217.090303) (xy 121.830086 -217.141598) (xy 121.814038 -217.190991)
			(xy 121.79046 -217.237265) (xy 121.759934 -217.279281) (xy 121.723211 -217.316004) (xy 121.681195 -217.34653)
			(xy 121.634921 -217.370108) (xy 121.585528 -217.386156) (xy 121.534233 -217.394281) (xy 121.482299 -217.394281)
			(xy 121.431004 -217.386156) (xy 121.381611 -217.370108) (xy 121.335337 -217.34653) (xy 121.293321 -217.316004)
			(xy 121.256598 -217.279281) (xy 121.226072 -217.237265) (xy 121.202494 -217.190991) (xy 121.186446 -217.141598)
			(xy 121.178321 -217.090303) (xy 120.898165 -217.090303) (xy 120.898127 -217.092245) (xy 120.888802 -217.147278)
			(xy 120.880124 -217.17381) (xy 120.87225 -217.195654) (xy 121.076466 -217.549222) (xy 121.099326 -217.55354)
			(xy 121.12424 -217.558742) (xy 121.172222 -217.575703) (xy 121.217038 -217.599816) (xy 121.257631 -217.630512)
			(xy 121.29304 -217.667066) (xy 121.322429 -217.708614) (xy 121.345105 -217.754174) (xy 121.360532 -217.802672)
			(xy 121.368345 -217.85296) (xy 121.36882 -217.878406) (xy 121.368311 -217.904373) (xy 121.360186 -217.955668)
			(xy 121.344138 -218.005061) (xy 121.32056 -218.051335) (xy 121.290034 -218.093351) (xy 121.253311 -218.130074)
			(xy 121.211295 -218.1606) (xy 121.165021 -218.184178) (xy 121.115628 -218.200226) (xy 121.064333 -218.208351)
			(xy 121.012399 -218.208351) (xy 120.961104 -218.200226) (xy 120.911711 -218.184178) (xy 120.865437 -218.1606)
			(xy 120.823421 -218.130074) (xy 120.786698 -218.093351) (xy 120.756172 -218.051335) (xy 120.732594 -218.005061)
			(xy 120.716546 -217.955668) (xy 120.708421 -217.904373) (xy 120.707912 -217.878406) (xy 120.708466 -217.85042)
			(xy 120.717915 -217.795252) (xy 120.726708 -217.768678) (xy 120.734328 -217.74658) (xy 120.53062 -217.39352)
			(xy 120.507506 -217.389202) (xy 120.482566 -217.384059) (xy 120.434542 -217.367128) (xy 120.389682 -217.343032)
			(xy 120.349049 -217.312342) (xy 120.313603 -217.275784) (xy 120.284182 -217.234221) (xy 120.261484 -217.188639)
			(xy 120.246045 -217.140115) (xy 120.23823 -217.089797) (xy 120.237758 -217.064336) (xy 119.95912 -217.064336)
			(xy 119.958611 -217.090303) (xy 119.950486 -217.141598) (xy 119.934438 -217.190991) (xy 119.91086 -217.237265)
			(xy 119.880334 -217.279281) (xy 119.843611 -217.316004) (xy 119.801595 -217.34653) (xy 119.755321 -217.370108)
			(xy 119.705928 -217.386156) (xy 119.654633 -217.394281) (xy 119.602699 -217.394281) (xy 119.551404 -217.386156)
			(xy 119.502011 -217.370108) (xy 119.455737 -217.34653) (xy 119.413721 -217.316004) (xy 119.376998 -217.279281)
			(xy 119.346472 -217.237265) (xy 119.322894 -217.190991) (xy 119.306846 -217.141598) (xy 119.298721 -217.090303)
			(xy 119.018565 -217.090303) (xy 119.018527 -217.092245) (xy 119.009202 -217.147278) (xy 119.000524 -217.17381)
			(xy 118.99265 -217.195654) (xy 119.196866 -217.549222) (xy 119.219726 -217.55354) (xy 119.24464 -217.558742)
			(xy 119.292622 -217.575703) (xy 119.337438 -217.599816) (xy 119.378031 -217.630512) (xy 119.41344 -217.667066)
			(xy 119.442829 -217.708614) (xy 119.465505 -217.754174) (xy 119.480932 -217.802672) (xy 119.488745 -217.85296)
			(xy 119.48922 -217.878406) (xy 119.488711 -217.904373) (xy 119.480586 -217.955668) (xy 119.464538 -218.005061)
			(xy 119.44096 -218.051335) (xy 119.410434 -218.093351) (xy 119.373711 -218.130074) (xy 119.331695 -218.1606)
			(xy 119.285421 -218.184178) (xy 119.236028 -218.200226) (xy 119.184733 -218.208351) (xy 119.132799 -218.208351)
			(xy 119.081504 -218.200226) (xy 119.032111 -218.184178) (xy 118.985837 -218.1606) (xy 118.943821 -218.130074)
			(xy 118.907098 -218.093351) (xy 118.876572 -218.051335) (xy 118.852994 -218.005061) (xy 118.836946 -217.955668)
			(xy 118.828821 -217.904373) (xy 118.828312 -217.878406) (xy 118.828866 -217.85042) (xy 118.838315 -217.795252)
			(xy 118.847108 -217.768678) (xy 118.854728 -217.74658) (xy 118.65102 -217.39352) (xy 118.627906 -217.389202)
			(xy 118.602966 -217.384059) (xy 118.554942 -217.367128) (xy 118.510082 -217.343032) (xy 118.469449 -217.312342)
			(xy 118.434003 -217.275784) (xy 118.404582 -217.234221) (xy 118.381884 -217.188639) (xy 118.366445 -217.140115)
			(xy 118.35863 -217.089797) (xy 118.358158 -217.064336) (xy 118.07952 -217.064336) (xy 118.079011 -217.090303)
			(xy 118.070886 -217.141598) (xy 118.054838 -217.190991) (xy 118.03126 -217.237265) (xy 118.000734 -217.279281)
			(xy 117.964011 -217.316004) (xy 117.921995 -217.34653) (xy 117.875721 -217.370108) (xy 117.826328 -217.386156)
			(xy 117.775033 -217.394281) (xy 117.723099 -217.394281) (xy 117.671804 -217.386156) (xy 117.622411 -217.370108)
			(xy 117.576137 -217.34653) (xy 117.534121 -217.316004) (xy 117.497398 -217.279281) (xy 117.466872 -217.237265)
			(xy 117.443294 -217.190991) (xy 117.427246 -217.141598) (xy 117.419121 -217.090303) (xy 117.138965 -217.090303)
			(xy 117.138927 -217.092245) (xy 117.129602 -217.147278) (xy 117.120924 -217.17381) (xy 117.11305 -217.195654)
			(xy 117.317266 -217.549222) (xy 117.340126 -217.55354) (xy 117.36504 -217.558742) (xy 117.413022 -217.575703)
			(xy 117.457838 -217.599816) (xy 117.498431 -217.630512) (xy 117.53384 -217.667066) (xy 117.563229 -217.708614)
			(xy 117.585905 -217.754174) (xy 117.601332 -217.802672) (xy 117.609145 -217.85296) (xy 117.60962 -217.878406)
			(xy 117.609111 -217.904373) (xy 117.600986 -217.955668) (xy 117.584938 -218.005061) (xy 117.56136 -218.051335)
			(xy 117.530834 -218.093351) (xy 117.494111 -218.130074) (xy 117.452095 -218.1606) (xy 117.405821 -218.184178)
			(xy 117.356428 -218.200226) (xy 117.305133 -218.208351) (xy 117.253199 -218.208351) (xy 117.201904 -218.200226)
			(xy 117.152511 -218.184178) (xy 117.106237 -218.1606) (xy 117.064221 -218.130074) (xy 117.027498 -218.093351)
			(xy 116.996972 -218.051335) (xy 116.973394 -218.005061) (xy 116.957346 -217.955668) (xy 116.949221 -217.904373)
			(xy 116.948712 -217.878406) (xy 116.949266 -217.85042) (xy 116.958715 -217.795252) (xy 116.967508 -217.768678)
			(xy 116.975128 -217.74658) (xy 116.77142 -217.39352) (xy 116.748306 -217.389202) (xy 116.723366 -217.384059)
			(xy 116.675342 -217.367128) (xy 116.630482 -217.343032) (xy 116.589849 -217.312342) (xy 116.554403 -217.275784)
			(xy 116.524982 -217.234221) (xy 116.502284 -217.188639) (xy 116.486845 -217.140115) (xy 116.47903 -217.089797)
			(xy 116.478558 -217.064336) (xy 116.19992 -217.064336) (xy 116.199411 -217.090303) (xy 116.191286 -217.141598)
			(xy 116.175238 -217.190991) (xy 116.15166 -217.237265) (xy 116.121134 -217.279281) (xy 116.084411 -217.316004)
			(xy 116.042395 -217.34653) (xy 115.996121 -217.370108) (xy 115.946728 -217.386156) (xy 115.895433 -217.394281)
			(xy 115.843499 -217.394281) (xy 115.792204 -217.386156) (xy 115.742811 -217.370108) (xy 115.696537 -217.34653)
			(xy 115.654521 -217.316004) (xy 115.617798 -217.279281) (xy 115.587272 -217.237265) (xy 115.563694 -217.190991)
			(xy 115.547646 -217.141598) (xy 115.539521 -217.090303) (xy 115.259365 -217.090303) (xy 115.259327 -217.092245)
			(xy 115.250002 -217.147278) (xy 115.241324 -217.17381) (xy 115.23345 -217.195654) (xy 115.437666 -217.549222)
			(xy 115.460526 -217.55354) (xy 115.48544 -217.558742) (xy 115.533422 -217.575703) (xy 115.578238 -217.599816)
			(xy 115.618831 -217.630512) (xy 115.65424 -217.667066) (xy 115.683629 -217.708614) (xy 115.706305 -217.754174)
			(xy 115.721732 -217.802672) (xy 115.729545 -217.85296) (xy 115.73002 -217.878406) (xy 115.729511 -217.904373)
			(xy 115.721386 -217.955668) (xy 115.705338 -218.005061) (xy 115.68176 -218.051335) (xy 115.651234 -218.093351)
			(xy 115.614511 -218.130074) (xy 115.572495 -218.1606) (xy 115.526221 -218.184178) (xy 115.476828 -218.200226)
			(xy 115.425533 -218.208351) (xy 115.373599 -218.208351) (xy 115.322304 -218.200226) (xy 115.272911 -218.184178)
			(xy 115.226637 -218.1606) (xy 115.184621 -218.130074) (xy 115.147898 -218.093351) (xy 115.117372 -218.051335)
			(xy 115.093794 -218.005061) (xy 115.077746 -217.955668) (xy 115.069621 -217.904373) (xy 115.069112 -217.878406)
			(xy 115.069666 -217.85042) (xy 115.079115 -217.795252) (xy 115.087908 -217.768678) (xy 115.095528 -217.74658)
			(xy 114.89182 -217.39352) (xy 114.868706 -217.389202) (xy 114.843766 -217.384059) (xy 114.795742 -217.367128)
			(xy 114.750882 -217.343032) (xy 114.710249 -217.312342) (xy 114.674803 -217.275784) (xy 114.645382 -217.234221)
			(xy 114.622684 -217.188639) (xy 114.607245 -217.140115) (xy 114.59943 -217.089797) (xy 114.598958 -217.064336)
			(xy 114.32032 -217.064336) (xy 114.319811 -217.090303) (xy 114.311686 -217.141598) (xy 114.295638 -217.190991)
			(xy 114.27206 -217.237265) (xy 114.241534 -217.279281) (xy 114.204811 -217.316004) (xy 114.162795 -217.34653)
			(xy 114.116521 -217.370108) (xy 114.067128 -217.386156) (xy 114.015833 -217.394281) (xy 113.963899 -217.394281)
			(xy 113.912604 -217.386156) (xy 113.863211 -217.370108) (xy 113.816937 -217.34653) (xy 113.774921 -217.316004)
			(xy 113.738198 -217.279281) (xy 113.707672 -217.237265) (xy 113.684094 -217.190991) (xy 113.668046 -217.141598)
			(xy 113.659921 -217.090303) (xy 113.379765 -217.090303) (xy 113.379727 -217.092245) (xy 113.370402 -217.147278)
			(xy 113.361724 -217.17381) (xy 113.35385 -217.195654) (xy 113.558066 -217.549222) (xy 113.580926 -217.55354)
			(xy 113.60584 -217.558742) (xy 113.653822 -217.575703) (xy 113.698638 -217.599816) (xy 113.739231 -217.630512)
			(xy 113.77464 -217.667066) (xy 113.804029 -217.708614) (xy 113.826705 -217.754174) (xy 113.842132 -217.802672)
			(xy 113.849945 -217.85296) (xy 113.85042 -217.878406) (xy 113.849911 -217.904373) (xy 113.841786 -217.955668)
			(xy 113.825738 -218.005061) (xy 113.80216 -218.051335) (xy 113.771634 -218.093351) (xy 113.734911 -218.130074)
			(xy 113.692895 -218.1606) (xy 113.646621 -218.184178) (xy 113.597228 -218.200226) (xy 113.545933 -218.208351)
			(xy 113.493999 -218.208351) (xy 113.442704 -218.200226) (xy 113.393311 -218.184178) (xy 113.347037 -218.1606)
			(xy 113.305021 -218.130074) (xy 113.268298 -218.093351) (xy 113.237772 -218.051335) (xy 113.214194 -218.005061)
			(xy 113.198146 -217.955668) (xy 113.190021 -217.904373) (xy 113.189512 -217.878406) (xy 113.190066 -217.85042)
			(xy 113.199515 -217.795252) (xy 113.208308 -217.768678) (xy 113.215928 -217.74658) (xy 113.01222 -217.39352)
			(xy 112.989106 -217.389202) (xy 112.964166 -217.384059) (xy 112.916142 -217.367128) (xy 112.871282 -217.343032)
			(xy 112.830649 -217.312342) (xy 112.795203 -217.275784) (xy 112.765782 -217.234221) (xy 112.743084 -217.188639)
			(xy 112.727645 -217.140115) (xy 112.71983 -217.089797) (xy 112.719358 -217.064336) (xy 112.44072 -217.064336)
			(xy 112.440211 -217.090303) (xy 112.432086 -217.141598) (xy 112.416038 -217.190991) (xy 112.39246 -217.237265)
			(xy 112.361934 -217.279281) (xy 112.325211 -217.316004) (xy 112.283195 -217.34653) (xy 112.236921 -217.370108)
			(xy 112.187528 -217.386156) (xy 112.136233 -217.394281) (xy 112.084299 -217.394281) (xy 112.033004 -217.386156)
			(xy 111.983611 -217.370108) (xy 111.937337 -217.34653) (xy 111.895321 -217.316004) (xy 111.858598 -217.279281)
			(xy 111.828072 -217.237265) (xy 111.804494 -217.190991) (xy 111.788446 -217.141598) (xy 111.780321 -217.090303)
			(xy 111.587026 -217.090303) (xy 111.587026 -217.497152) (xy 111.587444 -217.507209) (xy 111.595154 -217.525787)
			(xy 111.609409 -217.539977) (xy 111.628021 -217.547601) (xy 111.63808 -217.547952) (xy 111.640112 -217.547952)
			(xy 111.666078 -217.548462) (xy 111.717371 -217.556588) (xy 111.766761 -217.572637) (xy 111.813032 -217.596215)
			(xy 111.855046 -217.626741) (xy 111.891767 -217.663463) (xy 111.922291 -217.705478) (xy 111.945867 -217.75175)
			(xy 111.961915 -217.801141) (xy 111.970039 -217.852434) (xy 111.970039 -217.904366) (xy 111.961915 -217.955659)
			(xy 111.945867 -218.00505) (xy 111.922291 -218.051322) (xy 111.891767 -218.093337) (xy 111.855046 -218.130059)
			(xy 111.813032 -218.160585) (xy 111.766761 -218.184163) (xy 111.717371 -218.200212) (xy 111.666078 -218.208338)
			(xy 111.640112 -218.20886) (xy 111.63808 -218.20886) (xy 111.628019 -218.20923) (xy 111.609399 -218.216849)
			(xy 111.595128 -218.23103) (xy 111.587393 -218.249601) (xy 111.587026 -218.25966) (xy 111.587026 -218.692222)
			(xy 111.779558 -218.692222) (xy 111.779965 -218.666768) (xy 111.787754 -218.616461) (xy 111.803169 -218.567943)
			(xy 111.825842 -218.522364) (xy 111.855239 -218.480803) (xy 111.890662 -218.444242) (xy 111.931274 -218.413547)
			(xy 111.976114 -218.389444) (xy 112.02412 -218.372505) (xy 112.049052 -218.367356) (xy 112.071912 -218.363038)
			(xy 112.275874 -218.00947) (xy 112.268254 -217.987626) (xy 112.259617 -217.96115) (xy 112.250292 -217.906249)
			(xy 112.249712 -217.878406) (xy 112.250221 -217.852439) (xy 112.258346 -217.801144) (xy 112.274394 -217.751751)
			(xy 112.297972 -217.705477) (xy 112.328498 -217.663461) (xy 112.365221 -217.626738) (xy 112.407237 -217.596212)
			(xy 112.453511 -217.572634) (xy 112.502904 -217.556586) (xy 112.554199 -217.548461) (xy 112.606133 -217.548461)
			(xy 112.657428 -217.556586) (xy 112.706821 -217.572634) (xy 112.753095 -217.596212) (xy 112.795111 -217.626738)
			(xy 112.831834 -217.663461) (xy 112.86236 -217.705477) (xy 112.885938 -217.751751) (xy 112.901986 -217.801144)
			(xy 112.910111 -217.852439) (xy 112.91062 -217.878406) (xy 112.910171 -217.903881) (xy 112.90235 -217.954227)
			(xy 112.886894 -218.002775) (xy 112.864169 -218.048376) (xy 112.834714 -218.089949) (xy 112.799227 -218.126507)
			(xy 112.758549 -218.157186) (xy 112.713645 -218.181258) (xy 112.665577 -218.198151) (xy 112.640618 -218.203272)
			(xy 112.617504 -218.20759) (xy 112.41405 -218.560396) (xy 112.42167 -218.582494) (xy 112.430405 -218.609083)
			(xy 112.439855 -218.664242) (xy 112.440466 -218.692222) (xy 112.439957 -218.718189) (xy 112.719867 -218.718189)
			(xy 112.719867 -218.666255) (xy 112.727992 -218.61496) (xy 112.74404 -218.565567) (xy 112.767618 -218.519293)
			(xy 112.798144 -218.477277) (xy 112.834867 -218.440554) (xy 112.876883 -218.410028) (xy 112.923157 -218.38645)
			(xy 112.97255 -218.370402) (xy 113.023845 -218.362277) (xy 113.075779 -218.362277) (xy 113.127074 -218.370402)
			(xy 113.176467 -218.38645) (xy 113.222741 -218.410028) (xy 113.264757 -218.440554) (xy 113.30148 -218.477277)
			(xy 113.332006 -218.519293) (xy 113.355584 -218.565567) (xy 113.371632 -218.61496) (xy 113.379757 -218.666255)
			(xy 113.380266 -218.692222) (xy 113.659412 -218.692222) (xy 113.659856 -218.66677) (xy 113.667644 -218.616466)
			(xy 113.683056 -218.567952) (xy 113.705726 -218.522375) (xy 113.735118 -218.480815) (xy 113.770536 -218.444254)
			(xy 113.811142 -218.413557) (xy 113.855976 -218.389452) (xy 113.903977 -218.372508) (xy 113.928906 -218.367356)
			(xy 113.951766 -218.363038) (xy 114.155728 -218.009724) (xy 114.147854 -217.98788) (xy 114.139187 -217.961346)
			(xy 114.129871 -217.906314) (xy 114.129312 -217.878406) (xy 114.129821 -217.852439) (xy 114.137946 -217.801144)
			(xy 114.153994 -217.751751) (xy 114.177572 -217.705477) (xy 114.208098 -217.663461) (xy 114.244821 -217.626738)
			(xy 114.286837 -217.596212) (xy 114.333111 -217.572634) (xy 114.382504 -217.556586) (xy 114.433799 -217.548461)
			(xy 114.485733 -217.548461) (xy 114.537028 -217.556586) (xy 114.586421 -217.572634) (xy 114.632695 -217.596212)
			(xy 114.674711 -217.626738) (xy 114.711434 -217.663461) (xy 114.74196 -217.705477) (xy 114.765538 -217.751751)
			(xy 114.781586 -217.801144) (xy 114.789711 -217.852439) (xy 114.79022 -217.878406) (xy 114.789728 -217.903868)
			(xy 114.781929 -217.95419) (xy 114.766501 -218.00272) (xy 114.743809 -218.048307) (xy 114.714392 -218.089874)
			(xy 114.678945 -218.126434) (xy 114.638308 -218.157123) (xy 114.593444 -218.181213) (xy 114.545414 -218.198134)
			(xy 114.520472 -218.203272) (xy 114.497358 -218.20759) (xy 114.293904 -218.560396) (xy 114.301524 -218.582494)
			(xy 114.310261 -218.609082) (xy 114.319709 -218.664242) (xy 114.32032 -218.692222) (xy 114.319811 -218.718189)
			(xy 114.599721 -218.718189) (xy 114.599721 -218.666255) (xy 114.607846 -218.61496) (xy 114.623894 -218.565567)
			(xy 114.647472 -218.519293) (xy 114.677998 -218.477277) (xy 114.714721 -218.440554) (xy 114.756737 -218.410028)
			(xy 114.803011 -218.38645) (xy 114.852404 -218.370402) (xy 114.903699 -218.362277) (xy 114.955633 -218.362277)
			(xy 115.006928 -218.370402) (xy 115.056321 -218.38645) (xy 115.102595 -218.410028) (xy 115.144611 -218.440554)
			(xy 115.181334 -218.477277) (xy 115.21186 -218.519293) (xy 115.235438 -218.565567) (xy 115.251486 -218.61496)
			(xy 115.259611 -218.666255) (xy 115.26012 -218.692222) (xy 115.538758 -218.692222) (xy 115.539165 -218.666768)
			(xy 115.546954 -218.616461) (xy 115.562369 -218.567943) (xy 115.585042 -218.522364) (xy 115.614439 -218.480803)
			(xy 115.649862 -218.444242) (xy 115.690474 -218.413547) (xy 115.735314 -218.389444) (xy 115.78332 -218.372505)
			(xy 115.808252 -218.367356) (xy 115.831112 -218.363038) (xy 116.035074 -218.00947) (xy 116.027454 -217.987626)
			(xy 116.018817 -217.96115) (xy 116.009492 -217.906249) (xy 116.008912 -217.878406) (xy 116.009421 -217.852439)
			(xy 116.017546 -217.801144) (xy 116.033594 -217.751751) (xy 116.057172 -217.705477) (xy 116.087698 -217.663461)
			(xy 116.124421 -217.626738) (xy 116.166437 -217.596212) (xy 116.212711 -217.572634) (xy 116.262104 -217.556586)
			(xy 116.313399 -217.548461) (xy 116.365333 -217.548461) (xy 116.416628 -217.556586) (xy 116.466021 -217.572634)
			(xy 116.512295 -217.596212) (xy 116.554311 -217.626738) (xy 116.591034 -217.663461) (xy 116.62156 -217.705477)
			(xy 116.645138 -217.751751) (xy 116.661186 -217.801144) (xy 116.669311 -217.852439) (xy 116.66982 -217.878406)
			(xy 116.669371 -217.903881) (xy 116.66155 -217.954227) (xy 116.646094 -218.002775) (xy 116.623369 -218.048376)
			(xy 116.593914 -218.089949) (xy 116.558427 -218.126507) (xy 116.517749 -218.157186) (xy 116.472845 -218.181258)
			(xy 116.424777 -218.198151) (xy 116.399818 -218.203272) (xy 116.376704 -218.20759) (xy 116.17325 -218.560396)
			(xy 116.18087 -218.582494) (xy 116.189605 -218.609083) (xy 116.199055 -218.664242) (xy 116.199666 -218.692222)
			(xy 117.418358 -218.692222) (xy 117.418765 -218.666768) (xy 117.426554 -218.616461) (xy 117.441969 -218.567943)
			(xy 117.464642 -218.522364) (xy 117.494039 -218.480803) (xy 117.529462 -218.444242) (xy 117.570074 -218.413547)
			(xy 117.614914 -218.389444) (xy 117.66292 -218.372505) (xy 117.687852 -218.367356) (xy 117.710712 -218.363038)
			(xy 117.914674 -218.00947) (xy 117.907054 -217.987626) (xy 117.898417 -217.96115) (xy 117.889092 -217.906249)
			(xy 117.888512 -217.878406) (xy 117.889021 -217.852439) (xy 117.897146 -217.801144) (xy 117.913194 -217.751751)
			(xy 117.936772 -217.705477) (xy 117.967298 -217.663461) (xy 118.004021 -217.626738) (xy 118.046037 -217.596212)
			(xy 118.092311 -217.572634) (xy 118.141704 -217.556586) (xy 118.192999 -217.548461) (xy 118.244933 -217.548461)
			(xy 118.296228 -217.556586) (xy 118.345621 -217.572634) (xy 118.391895 -217.596212) (xy 118.433911 -217.626738)
			(xy 118.470634 -217.663461) (xy 118.50116 -217.705477) (xy 118.524738 -217.751751) (xy 118.540786 -217.801144)
			(xy 118.548911 -217.852439) (xy 118.54942 -217.878406) (xy 118.548971 -217.903881) (xy 118.54115 -217.954227)
			(xy 118.525694 -218.002775) (xy 118.502969 -218.048376) (xy 118.473514 -218.089949) (xy 118.438027 -218.126507)
			(xy 118.397349 -218.157186) (xy 118.352445 -218.181258) (xy 118.304377 -218.198151) (xy 118.279418 -218.203272)
			(xy 118.256304 -218.20759) (xy 118.05285 -218.560396) (xy 118.06047 -218.582494) (xy 118.069205 -218.609083)
			(xy 118.078655 -218.664242) (xy 118.079266 -218.692222) (xy 119.297958 -218.692222) (xy 119.298365 -218.666768)
			(xy 119.306154 -218.616461) (xy 119.321569 -218.567943) (xy 119.344242 -218.522364) (xy 119.373639 -218.480803)
			(xy 119.409062 -218.444242) (xy 119.449674 -218.413547) (xy 119.494514 -218.389444) (xy 119.54252 -218.372505)
			(xy 119.567452 -218.367356) (xy 119.590312 -218.363038) (xy 119.794274 -218.00947) (xy 119.786654 -217.987626)
			(xy 119.778017 -217.96115) (xy 119.768692 -217.906249) (xy 119.768112 -217.878406) (xy 119.768621 -217.852439)
			(xy 119.776746 -217.801144) (xy 119.792794 -217.751751) (xy 119.816372 -217.705477) (xy 119.846898 -217.663461)
			(xy 119.883621 -217.626738) (xy 119.925637 -217.596212) (xy 119.971911 -217.572634) (xy 120.021304 -217.556586)
			(xy 120.072599 -217.548461) (xy 120.124533 -217.548461) (xy 120.175828 -217.556586) (xy 120.225221 -217.572634)
			(xy 120.271495 -217.596212) (xy 120.313511 -217.626738) (xy 120.350234 -217.663461) (xy 120.38076 -217.705477)
			(xy 120.404338 -217.751751) (xy 120.420386 -217.801144) (xy 120.428511 -217.852439) (xy 120.42902 -217.878406)
			(xy 120.428571 -217.903881) (xy 120.42075 -217.954227) (xy 120.405294 -218.002775) (xy 120.382569 -218.048376)
			(xy 120.353114 -218.089949) (xy 120.317627 -218.126507) (xy 120.276949 -218.157186) (xy 120.232045 -218.181258)
			(xy 120.183977 -218.198151) (xy 120.159018 -218.203272) (xy 120.135904 -218.20759) (xy 119.93245 -218.560396)
			(xy 119.94007 -218.582494) (xy 119.948805 -218.609083) (xy 119.958255 -218.664242) (xy 119.958866 -218.692222)
			(xy 121.177558 -218.692222) (xy 121.177965 -218.666768) (xy 121.185754 -218.616461) (xy 121.201169 -218.567943)
			(xy 121.223842 -218.522364) (xy 121.253239 -218.480803) (xy 121.288662 -218.444242) (xy 121.329274 -218.413547)
			(xy 121.374114 -218.389444) (xy 121.42212 -218.372505) (xy 121.447052 -218.367356) (xy 121.469912 -218.363038)
			(xy 121.673874 -218.00947) (xy 121.666254 -217.987626) (xy 121.657617 -217.96115) (xy 121.648292 -217.906249)
			(xy 121.647712 -217.878406) (xy 121.648221 -217.852439) (xy 121.656346 -217.801144) (xy 121.672394 -217.751751)
			(xy 121.695972 -217.705477) (xy 121.726498 -217.663461) (xy 121.763221 -217.626738) (xy 121.805237 -217.596212)
			(xy 121.851511 -217.572634) (xy 121.900904 -217.556586) (xy 121.952199 -217.548461) (xy 122.004133 -217.548461)
			(xy 122.055428 -217.556586) (xy 122.104821 -217.572634) (xy 122.151095 -217.596212) (xy 122.193111 -217.626738)
			(xy 122.229834 -217.663461) (xy 122.26036 -217.705477) (xy 122.283938 -217.751751) (xy 122.299986 -217.801144)
			(xy 122.308111 -217.852439) (xy 122.30862 -217.878406) (xy 122.308171 -217.903881) (xy 122.30035 -217.954227)
			(xy 122.284894 -218.002775) (xy 122.262169 -218.048376) (xy 122.232714 -218.089949) (xy 122.197227 -218.126507)
			(xy 122.156549 -218.157186) (xy 122.111645 -218.181258) (xy 122.063577 -218.198151) (xy 122.038618 -218.203272)
			(xy 122.015504 -218.20759) (xy 121.81205 -218.560396) (xy 121.81967 -218.582494) (xy 121.828405 -218.609083)
			(xy 121.837855 -218.664242) (xy 121.838466 -218.692222) (xy 123.057158 -218.692222) (xy 123.057565 -218.666768)
			(xy 123.065354 -218.616461) (xy 123.080769 -218.567943) (xy 123.103442 -218.522364) (xy 123.132839 -218.480803)
			(xy 123.168262 -218.444242) (xy 123.208874 -218.413547) (xy 123.253714 -218.389444) (xy 123.30172 -218.372505)
			(xy 123.326652 -218.367356) (xy 123.349512 -218.363038) (xy 123.553474 -218.00947) (xy 123.545854 -217.987626)
			(xy 123.537217 -217.96115) (xy 123.527892 -217.906249) (xy 123.527312 -217.878406) (xy 123.527821 -217.852439)
			(xy 123.535946 -217.801144) (xy 123.551994 -217.751751) (xy 123.575572 -217.705477) (xy 123.606098 -217.663461)
			(xy 123.642821 -217.626738) (xy 123.684837 -217.596212) (xy 123.731111 -217.572634) (xy 123.780504 -217.556586)
			(xy 123.831799 -217.548461) (xy 123.883733 -217.548461) (xy 123.935028 -217.556586) (xy 123.984421 -217.572634)
			(xy 124.030695 -217.596212) (xy 124.072711 -217.626738) (xy 124.109434 -217.663461) (xy 124.13996 -217.705477)
			(xy 124.163538 -217.751751) (xy 124.179586 -217.801144) (xy 124.187711 -217.852439) (xy 124.18822 -217.878406)
			(xy 124.187771 -217.903881) (xy 124.17995 -217.954227) (xy 124.164494 -218.002775) (xy 124.141769 -218.048376)
			(xy 124.112314 -218.089949) (xy 124.076827 -218.126507) (xy 124.036149 -218.157186) (xy 123.991245 -218.181258)
			(xy 123.943177 -218.198151) (xy 123.918218 -218.203272) (xy 123.895104 -218.20759) (xy 123.69165 -218.560396)
			(xy 123.69927 -218.582494) (xy 123.708005 -218.609083) (xy 123.717455 -218.664242) (xy 123.718066 -218.692222)
			(xy 124.936758 -218.692222) (xy 124.937165 -218.666768) (xy 124.944954 -218.616461) (xy 124.960369 -218.567943)
			(xy 124.983042 -218.522364) (xy 125.012439 -218.480803) (xy 125.047862 -218.444242) (xy 125.088474 -218.413547)
			(xy 125.133314 -218.389444) (xy 125.18132 -218.372505) (xy 125.206252 -218.367356) (xy 125.229112 -218.363038)
			(xy 125.433074 -218.00947) (xy 125.425454 -217.987626) (xy 125.416817 -217.96115) (xy 125.407492 -217.906249)
			(xy 125.406912 -217.878406) (xy 125.407421 -217.852439) (xy 125.415546 -217.801144) (xy 125.431594 -217.751751)
			(xy 125.455172 -217.705477) (xy 125.485698 -217.663461) (xy 125.522421 -217.626738) (xy 125.564437 -217.596212)
			(xy 125.610711 -217.572634) (xy 125.660104 -217.556586) (xy 125.711399 -217.548461) (xy 125.763333 -217.548461)
			(xy 125.814628 -217.556586) (xy 125.864021 -217.572634) (xy 125.910295 -217.596212) (xy 125.952311 -217.626738)
			(xy 125.989034 -217.663461) (xy 126.01956 -217.705477) (xy 126.043138 -217.751751) (xy 126.059186 -217.801144)
			(xy 126.067311 -217.852439) (xy 126.06782 -217.878406) (xy 126.067371 -217.903881) (xy 126.05955 -217.954227)
			(xy 126.044094 -218.002775) (xy 126.021369 -218.048376) (xy 125.991914 -218.089949) (xy 125.956427 -218.126507)
			(xy 125.915749 -218.157186) (xy 125.870845 -218.181258) (xy 125.822777 -218.198151) (xy 125.797818 -218.203272)
			(xy 125.774704 -218.20759) (xy 125.57125 -218.560396) (xy 125.57887 -218.582494) (xy 125.587605 -218.609083)
			(xy 125.597055 -218.664242) (xy 125.597666 -218.692222) (xy 126.816358 -218.692222) (xy 126.816765 -218.666768)
			(xy 126.824554 -218.616461) (xy 126.839969 -218.567943) (xy 126.862642 -218.522364) (xy 126.892039 -218.480803)
			(xy 126.927462 -218.444242) (xy 126.968074 -218.413547) (xy 127.012914 -218.389444) (xy 127.06092 -218.372505)
			(xy 127.085852 -218.367356) (xy 127.108712 -218.363038) (xy 127.312674 -218.00947) (xy 127.305054 -217.987626)
			(xy 127.296417 -217.96115) (xy 127.287092 -217.906249) (xy 127.286512 -217.878406) (xy 127.287021 -217.852439)
			(xy 127.295146 -217.801144) (xy 127.311194 -217.751751) (xy 127.334772 -217.705477) (xy 127.365298 -217.663461)
			(xy 127.402021 -217.626738) (xy 127.444037 -217.596212) (xy 127.490311 -217.572634) (xy 127.539704 -217.556586)
			(xy 127.590999 -217.548461) (xy 127.642933 -217.548461) (xy 127.694228 -217.556586) (xy 127.743621 -217.572634)
			(xy 127.789895 -217.596212) (xy 127.831911 -217.626738) (xy 127.868634 -217.663461) (xy 127.89916 -217.705477)
			(xy 127.922738 -217.751751) (xy 127.938786 -217.801144) (xy 127.946911 -217.852439) (xy 127.94742 -217.878406)
			(xy 127.946971 -217.903881) (xy 127.93915 -217.954227) (xy 127.923694 -218.002775) (xy 127.900969 -218.048376)
			(xy 127.871514 -218.089949) (xy 127.836027 -218.126507) (xy 127.795349 -218.157186) (xy 127.750445 -218.181258)
			(xy 127.702377 -218.198151) (xy 127.677418 -218.203272) (xy 127.654304 -218.20759) (xy 127.45085 -218.560396)
			(xy 127.45847 -218.582494) (xy 127.467205 -218.609083) (xy 127.476655 -218.664242) (xy 127.477266 -218.692222)
			(xy 127.476757 -218.718189) (xy 127.756667 -218.718189) (xy 127.756667 -218.666255) (xy 127.764792 -218.61496)
			(xy 127.78084 -218.565567) (xy 127.804418 -218.519293) (xy 127.834944 -218.477277) (xy 127.871667 -218.440554)
			(xy 127.913683 -218.410028) (xy 127.959957 -218.38645) (xy 128.00935 -218.370402) (xy 128.060645 -218.362277)
			(xy 128.112579 -218.362277) (xy 128.163874 -218.370402) (xy 128.213267 -218.38645) (xy 128.259541 -218.410028)
			(xy 128.301557 -218.440554) (xy 128.33828 -218.477277) (xy 128.368806 -218.519293) (xy 128.392384 -218.565567)
			(xy 128.408432 -218.61496) (xy 128.416557 -218.666255) (xy 128.417066 -218.692222) (xy 128.695958 -218.692222)
			(xy 128.696365 -218.666768) (xy 128.704154 -218.616461) (xy 128.719569 -218.567943) (xy 128.742242 -218.522364)
			(xy 128.771639 -218.480803) (xy 128.807062 -218.444242) (xy 128.847674 -218.413547) (xy 128.892514 -218.389444)
			(xy 128.94052 -218.372505) (xy 128.965452 -218.367356) (xy 128.988312 -218.363038) (xy 129.192274 -218.00947)
			(xy 129.184654 -217.987626) (xy 129.176017 -217.96115) (xy 129.166692 -217.906249) (xy 129.166112 -217.878406)
			(xy 129.166621 -217.852439) (xy 129.174746 -217.801144) (xy 129.190794 -217.751751) (xy 129.214372 -217.705477)
			(xy 129.244898 -217.663461) (xy 129.281621 -217.626738) (xy 129.323637 -217.596212) (xy 129.369911 -217.572634)
			(xy 129.419304 -217.556586) (xy 129.470599 -217.548461) (xy 129.522533 -217.548461) (xy 129.573828 -217.556586)
			(xy 129.623221 -217.572634) (xy 129.669495 -217.596212) (xy 129.711511 -217.626738) (xy 129.748234 -217.663461)
			(xy 129.77876 -217.705477) (xy 129.802338 -217.751751) (xy 129.818386 -217.801144) (xy 129.826511 -217.852439)
			(xy 129.82702 -217.878406) (xy 129.826571 -217.903881) (xy 129.81875 -217.954227) (xy 129.803294 -218.002775)
			(xy 129.780569 -218.048376) (xy 129.751114 -218.089949) (xy 129.715627 -218.126507) (xy 129.674949 -218.157186)
			(xy 129.630045 -218.181258) (xy 129.581977 -218.198151) (xy 129.557018 -218.203272) (xy 129.533904 -218.20759)
			(xy 129.33045 -218.560396) (xy 129.33807 -218.582494) (xy 129.346805 -218.609083) (xy 129.356255 -218.664242)
			(xy 129.356866 -218.692222) (xy 129.356357 -218.718189) (xy 129.636267 -218.718189) (xy 129.636267 -218.666255)
			(xy 129.644392 -218.61496) (xy 129.66044 -218.565567) (xy 129.684018 -218.519293) (xy 129.714544 -218.477277)
			(xy 129.751267 -218.440554) (xy 129.793283 -218.410028) (xy 129.839557 -218.38645) (xy 129.88895 -218.370402)
			(xy 129.940245 -218.362277) (xy 129.992179 -218.362277) (xy 130.043474 -218.370402) (xy 130.092867 -218.38645)
			(xy 130.139141 -218.410028) (xy 130.181157 -218.440554) (xy 130.21788 -218.477277) (xy 130.248406 -218.519293)
			(xy 130.271984 -218.565567) (xy 130.288032 -218.61496) (xy 130.296157 -218.666255) (xy 130.296666 -218.692222)
			(xy 130.575558 -218.692222) (xy 130.575965 -218.666768) (xy 130.583754 -218.616461) (xy 130.599169 -218.567943)
			(xy 130.621842 -218.522364) (xy 130.651239 -218.480803) (xy 130.686662 -218.444242) (xy 130.727274 -218.413547)
			(xy 130.772114 -218.389444) (xy 130.82012 -218.372505) (xy 130.845052 -218.367356) (xy 130.867912 -218.363038)
			(xy 131.071874 -218.00947) (xy 131.064254 -217.987626) (xy 131.055617 -217.96115) (xy 131.046292 -217.906249)
			(xy 131.045712 -217.878406) (xy 131.046221 -217.852439) (xy 131.054346 -217.801144) (xy 131.070394 -217.751751)
			(xy 131.093972 -217.705477) (xy 131.124498 -217.663461) (xy 131.161221 -217.626738) (xy 131.203237 -217.596212)
			(xy 131.249511 -217.572634) (xy 131.298904 -217.556586) (xy 131.350199 -217.548461) (xy 131.402133 -217.548461)
			(xy 131.453428 -217.556586) (xy 131.502821 -217.572634) (xy 131.549095 -217.596212) (xy 131.591111 -217.626738)
			(xy 131.627834 -217.663461) (xy 131.65836 -217.705477) (xy 131.681938 -217.751751) (xy 131.697986 -217.801144)
			(xy 131.706111 -217.852439) (xy 131.70662 -217.878406) (xy 131.706171 -217.903881) (xy 131.69835 -217.954227)
			(xy 131.682894 -218.002775) (xy 131.660169 -218.048376) (xy 131.630714 -218.089949) (xy 131.595227 -218.126507)
			(xy 131.554549 -218.157186) (xy 131.509645 -218.181258) (xy 131.461577 -218.198151) (xy 131.436618 -218.203272)
			(xy 131.413504 -218.20759) (xy 131.21005 -218.560396) (xy 131.21767 -218.582494) (xy 131.226405 -218.609083)
			(xy 131.235855 -218.664242) (xy 131.236466 -218.692222) (xy 131.235957 -218.718189) (xy 131.515867 -218.718189)
			(xy 131.515867 -218.666255) (xy 131.523992 -218.61496) (xy 131.54004 -218.565567) (xy 131.563618 -218.519293)
			(xy 131.594144 -218.477277) (xy 131.630867 -218.440554) (xy 131.672883 -218.410028) (xy 131.719157 -218.38645)
			(xy 131.76855 -218.370402) (xy 131.819845 -218.362277) (xy 131.871779 -218.362277) (xy 131.923074 -218.370402)
			(xy 131.972467 -218.38645) (xy 132.018741 -218.410028) (xy 132.060757 -218.440554) (xy 132.09748 -218.477277)
			(xy 132.128006 -218.519293) (xy 132.151584 -218.565567) (xy 132.167632 -218.61496) (xy 132.175757 -218.666255)
			(xy 132.176266 -218.692222) (xy 132.455158 -218.692222) (xy 132.455565 -218.666768) (xy 132.463354 -218.616461)
			(xy 132.478769 -218.567943) (xy 132.501442 -218.522364) (xy 132.530839 -218.480803) (xy 132.566262 -218.444242)
			(xy 132.606874 -218.413547) (xy 132.651714 -218.389444) (xy 132.69972 -218.372505) (xy 132.724652 -218.367356)
			(xy 132.747512 -218.363038) (xy 132.951474 -218.00947) (xy 132.943854 -217.987626) (xy 132.935217 -217.96115)
			(xy 132.925892 -217.906249) (xy 132.925312 -217.878406) (xy 132.925821 -217.852439) (xy 132.933946 -217.801144)
			(xy 132.949994 -217.751751) (xy 132.973572 -217.705477) (xy 133.004098 -217.663461) (xy 133.040821 -217.626738)
			(xy 133.082837 -217.596212) (xy 133.129111 -217.572634) (xy 133.178504 -217.556586) (xy 133.229799 -217.548461)
			(xy 133.281733 -217.548461) (xy 133.333028 -217.556586) (xy 133.382421 -217.572634) (xy 133.428695 -217.596212)
			(xy 133.470711 -217.626738) (xy 133.507434 -217.663461) (xy 133.53796 -217.705477) (xy 133.561538 -217.751751)
			(xy 133.577586 -217.801144) (xy 133.585711 -217.852439) (xy 133.58622 -217.878406) (xy 133.585771 -217.903881)
			(xy 133.57795 -217.954227) (xy 133.562494 -218.002775) (xy 133.539769 -218.048376) (xy 133.510314 -218.089949)
			(xy 133.474827 -218.126507) (xy 133.434149 -218.157186) (xy 133.389245 -218.181258) (xy 133.341177 -218.198151)
			(xy 133.316218 -218.203272) (xy 133.293104 -218.20759) (xy 133.08965 -218.560396) (xy 133.09727 -218.582494)
			(xy 133.106005 -218.609083) (xy 133.115455 -218.664242) (xy 133.116066 -218.692222) (xy 133.115557 -218.718189)
			(xy 133.395721 -218.718189) (xy 133.395721 -218.666255) (xy 133.403846 -218.61496) (xy 133.419894 -218.565567)
			(xy 133.443472 -218.519293) (xy 133.473998 -218.477277) (xy 133.510721 -218.440554) (xy 133.552737 -218.410028)
			(xy 133.599011 -218.38645) (xy 133.648404 -218.370402) (xy 133.699699 -218.362277) (xy 133.751633 -218.362277)
			(xy 133.802928 -218.370402) (xy 133.852321 -218.38645) (xy 133.898595 -218.410028) (xy 133.940611 -218.440554)
			(xy 133.977334 -218.477277) (xy 134.00786 -218.519293) (xy 134.031438 -218.565567) (xy 134.047486 -218.61496)
			(xy 134.055611 -218.666255) (xy 134.05612 -218.692222) (xy 134.055611 -218.718189) (xy 134.047486 -218.769484)
			(xy 134.031438 -218.818877) (xy 134.00786 -218.865151) (xy 133.977334 -218.907167) (xy 133.940611 -218.94389)
			(xy 133.898595 -218.974416) (xy 133.852321 -218.997994) (xy 133.802928 -219.014042) (xy 133.751633 -219.022167)
			(xy 133.699699 -219.022167) (xy 133.648404 -219.014042) (xy 133.599011 -218.997994) (xy 133.552737 -218.974416)
			(xy 133.510721 -218.94389) (xy 133.473998 -218.907167) (xy 133.443472 -218.865151) (xy 133.419894 -218.818877)
			(xy 133.403846 -218.769484) (xy 133.395721 -218.718189) (xy 133.115557 -218.718189) (xy 133.107432 -218.769484)
			(xy 133.091384 -218.818877) (xy 133.067806 -218.865151) (xy 133.03728 -218.907167) (xy 133.000557 -218.94389)
			(xy 132.958541 -218.974416) (xy 132.912267 -218.997994) (xy 132.862874 -219.014042) (xy 132.811579 -219.022167)
			(xy 132.759645 -219.022167) (xy 132.70835 -219.014042) (xy 132.658957 -218.997994) (xy 132.612683 -218.974416)
			(xy 132.570667 -218.94389) (xy 132.533944 -218.907167) (xy 132.503418 -218.865151) (xy 132.47984 -218.818877)
			(xy 132.463792 -218.769484) (xy 132.455667 -218.718189) (xy 132.455158 -218.692222) (xy 132.176266 -218.692222)
			(xy 132.175757 -218.718189) (xy 132.167632 -218.769484) (xy 132.151584 -218.818877) (xy 132.128006 -218.865151)
			(xy 132.09748 -218.907167) (xy 132.060757 -218.94389) (xy 132.018741 -218.974416) (xy 131.972467 -218.997994)
			(xy 131.923074 -219.014042) (xy 131.871779 -219.022167) (xy 131.819845 -219.022167) (xy 131.76855 -219.014042)
			(xy 131.719157 -218.997994) (xy 131.672883 -218.974416) (xy 131.630867 -218.94389) (xy 131.594144 -218.907167)
			(xy 131.563618 -218.865151) (xy 131.54004 -218.818877) (xy 131.523992 -218.769484) (xy 131.515867 -218.718189)
			(xy 131.235957 -218.718189) (xy 131.227832 -218.769484) (xy 131.211784 -218.818877) (xy 131.188206 -218.865151)
			(xy 131.15768 -218.907167) (xy 131.120957 -218.94389) (xy 131.078941 -218.974416) (xy 131.032667 -218.997994)
			(xy 130.983274 -219.014042) (xy 130.931979 -219.022167) (xy 130.880045 -219.022167) (xy 130.82875 -219.014042)
			(xy 130.779357 -218.997994) (xy 130.733083 -218.974416) (xy 130.691067 -218.94389) (xy 130.654344 -218.907167)
			(xy 130.623818 -218.865151) (xy 130.60024 -218.818877) (xy 130.584192 -218.769484) (xy 130.576067 -218.718189)
			(xy 130.575558 -218.692222) (xy 130.296666 -218.692222) (xy 130.296157 -218.718189) (xy 130.288032 -218.769484)
			(xy 130.271984 -218.818877) (xy 130.248406 -218.865151) (xy 130.21788 -218.907167) (xy 130.181157 -218.94389)
			(xy 130.139141 -218.974416) (xy 130.092867 -218.997994) (xy 130.043474 -219.014042) (xy 129.992179 -219.022167)
			(xy 129.940245 -219.022167) (xy 129.88895 -219.014042) (xy 129.839557 -218.997994) (xy 129.793283 -218.974416)
			(xy 129.751267 -218.94389) (xy 129.714544 -218.907167) (xy 129.684018 -218.865151) (xy 129.66044 -218.818877)
			(xy 129.644392 -218.769484) (xy 129.636267 -218.718189) (xy 129.356357 -218.718189) (xy 129.348232 -218.769484)
			(xy 129.332184 -218.818877) (xy 129.308606 -218.865151) (xy 129.27808 -218.907167) (xy 129.241357 -218.94389)
			(xy 129.199341 -218.974416) (xy 129.153067 -218.997994) (xy 129.103674 -219.014042) (xy 129.052379 -219.022167)
			(xy 129.000445 -219.022167) (xy 128.94915 -219.014042) (xy 128.899757 -218.997994) (xy 128.853483 -218.974416)
			(xy 128.811467 -218.94389) (xy 128.774744 -218.907167) (xy 128.744218 -218.865151) (xy 128.72064 -218.818877)
			(xy 128.704592 -218.769484) (xy 128.696467 -218.718189) (xy 128.695958 -218.692222) (xy 128.417066 -218.692222)
			(xy 128.416557 -218.718189) (xy 128.408432 -218.769484) (xy 128.392384 -218.818877) (xy 128.368806 -218.865151)
			(xy 128.33828 -218.907167) (xy 128.301557 -218.94389) (xy 128.259541 -218.974416) (xy 128.213267 -218.997994)
			(xy 128.163874 -219.014042) (xy 128.112579 -219.022167) (xy 128.060645 -219.022167) (xy 128.00935 -219.014042)
			(xy 127.959957 -218.997994) (xy 127.913683 -218.974416) (xy 127.871667 -218.94389) (xy 127.834944 -218.907167)
			(xy 127.804418 -218.865151) (xy 127.78084 -218.818877) (xy 127.764792 -218.769484) (xy 127.756667 -218.718189)
			(xy 127.476757 -218.718189) (xy 127.468632 -218.769484) (xy 127.452584 -218.818877) (xy 127.429006 -218.865151)
			(xy 127.39848 -218.907167) (xy 127.361757 -218.94389) (xy 127.319741 -218.974416) (xy 127.273467 -218.997994)
			(xy 127.224074 -219.014042) (xy 127.172779 -219.022167) (xy 127.120845 -219.022167) (xy 127.06955 -219.014042)
			(xy 127.020157 -218.997994) (xy 126.973883 -218.974416) (xy 126.931867 -218.94389) (xy 126.895144 -218.907167)
			(xy 126.864618 -218.865151) (xy 126.84104 -218.818877) (xy 126.824992 -218.769484) (xy 126.816867 -218.718189)
			(xy 126.816358 -218.692222) (xy 125.597666 -218.692222) (xy 125.597157 -218.718189) (xy 125.589032 -218.769484)
			(xy 125.572984 -218.818877) (xy 125.549406 -218.865151) (xy 125.51888 -218.907167) (xy 125.482157 -218.94389)
			(xy 125.440141 -218.974416) (xy 125.393867 -218.997994) (xy 125.344474 -219.014042) (xy 125.293179 -219.022167)
			(xy 125.241245 -219.022167) (xy 125.18995 -219.014042) (xy 125.140557 -218.997994) (xy 125.094283 -218.974416)
			(xy 125.052267 -218.94389) (xy 125.015544 -218.907167) (xy 124.985018 -218.865151) (xy 124.96144 -218.818877)
			(xy 124.945392 -218.769484) (xy 124.937267 -218.718189) (xy 124.936758 -218.692222) (xy 123.718066 -218.692222)
			(xy 123.717557 -218.718189) (xy 123.709432 -218.769484) (xy 123.693384 -218.818877) (xy 123.669806 -218.865151)
			(xy 123.63928 -218.907167) (xy 123.602557 -218.94389) (xy 123.560541 -218.974416) (xy 123.514267 -218.997994)
			(xy 123.464874 -219.014042) (xy 123.413579 -219.022167) (xy 123.361645 -219.022167) (xy 123.31035 -219.014042)
			(xy 123.260957 -218.997994) (xy 123.214683 -218.974416) (xy 123.172667 -218.94389) (xy 123.135944 -218.907167)
			(xy 123.105418 -218.865151) (xy 123.08184 -218.818877) (xy 123.065792 -218.769484) (xy 123.057667 -218.718189)
			(xy 123.057158 -218.692222) (xy 121.838466 -218.692222) (xy 121.837957 -218.718189) (xy 121.829832 -218.769484)
			(xy 121.813784 -218.818877) (xy 121.790206 -218.865151) (xy 121.75968 -218.907167) (xy 121.722957 -218.94389)
			(xy 121.680941 -218.974416) (xy 121.634667 -218.997994) (xy 121.585274 -219.014042) (xy 121.533979 -219.022167)
			(xy 121.482045 -219.022167) (xy 121.43075 -219.014042) (xy 121.381357 -218.997994) (xy 121.335083 -218.974416)
			(xy 121.293067 -218.94389) (xy 121.256344 -218.907167) (xy 121.225818 -218.865151) (xy 121.20224 -218.818877)
			(xy 121.186192 -218.769484) (xy 121.178067 -218.718189) (xy 121.177558 -218.692222) (xy 119.958866 -218.692222)
			(xy 119.958357 -218.718189) (xy 119.950232 -218.769484) (xy 119.934184 -218.818877) (xy 119.910606 -218.865151)
			(xy 119.88008 -218.907167) (xy 119.843357 -218.94389) (xy 119.801341 -218.974416) (xy 119.755067 -218.997994)
			(xy 119.705674 -219.014042) (xy 119.654379 -219.022167) (xy 119.602445 -219.022167) (xy 119.55115 -219.014042)
			(xy 119.501757 -218.997994) (xy 119.455483 -218.974416) (xy 119.413467 -218.94389) (xy 119.376744 -218.907167)
			(xy 119.346218 -218.865151) (xy 119.32264 -218.818877) (xy 119.306592 -218.769484) (xy 119.298467 -218.718189)
			(xy 119.297958 -218.692222) (xy 118.079266 -218.692222) (xy 118.078757 -218.718189) (xy 118.070632 -218.769484)
			(xy 118.054584 -218.818877) (xy 118.031006 -218.865151) (xy 118.00048 -218.907167) (xy 117.963757 -218.94389)
			(xy 117.921741 -218.974416) (xy 117.875467 -218.997994) (xy 117.826074 -219.014042) (xy 117.774779 -219.022167)
			(xy 117.722845 -219.022167) (xy 117.67155 -219.014042) (xy 117.622157 -218.997994) (xy 117.575883 -218.974416)
			(xy 117.533867 -218.94389) (xy 117.497144 -218.907167) (xy 117.466618 -218.865151) (xy 117.44304 -218.818877)
			(xy 117.426992 -218.769484) (xy 117.418867 -218.718189) (xy 117.418358 -218.692222) (xy 116.199666 -218.692222)
			(xy 116.199157 -218.718189) (xy 116.191032 -218.769484) (xy 116.174984 -218.818877) (xy 116.151406 -218.865151)
			(xy 116.12088 -218.907167) (xy 116.084157 -218.94389) (xy 116.042141 -218.974416) (xy 115.995867 -218.997994)
			(xy 115.946474 -219.014042) (xy 115.895179 -219.022167) (xy 115.843245 -219.022167) (xy 115.79195 -219.014042)
			(xy 115.742557 -218.997994) (xy 115.696283 -218.974416) (xy 115.654267 -218.94389) (xy 115.617544 -218.907167)
			(xy 115.587018 -218.865151) (xy 115.56344 -218.818877) (xy 115.547392 -218.769484) (xy 115.539267 -218.718189)
			(xy 115.538758 -218.692222) (xy 115.26012 -218.692222) (xy 115.259611 -218.718189) (xy 115.251486 -218.769484)
			(xy 115.235438 -218.818877) (xy 115.21186 -218.865151) (xy 115.181334 -218.907167) (xy 115.144611 -218.94389)
			(xy 115.102595 -218.974416) (xy 115.056321 -218.997994) (xy 115.006928 -219.014042) (xy 114.955633 -219.022167)
			(xy 114.903699 -219.022167) (xy 114.852404 -219.014042) (xy 114.803011 -218.997994) (xy 114.756737 -218.974416)
			(xy 114.714721 -218.94389) (xy 114.677998 -218.907167) (xy 114.647472 -218.865151) (xy 114.623894 -218.818877)
			(xy 114.607846 -218.769484) (xy 114.599721 -218.718189) (xy 114.319811 -218.718189) (xy 114.311686 -218.769484)
			(xy 114.295638 -218.818877) (xy 114.27206 -218.865151) (xy 114.241534 -218.907167) (xy 114.204811 -218.94389)
			(xy 114.162795 -218.974416) (xy 114.116521 -218.997994) (xy 114.067128 -219.014042) (xy 114.015833 -219.022167)
			(xy 113.963899 -219.022167) (xy 113.912604 -219.014042) (xy 113.863211 -218.997994) (xy 113.816937 -218.974416)
			(xy 113.774921 -218.94389) (xy 113.738198 -218.907167) (xy 113.707672 -218.865151) (xy 113.684094 -218.818877)
			(xy 113.668046 -218.769484) (xy 113.659921 -218.718189) (xy 113.659412 -218.692222) (xy 113.380266 -218.692222)
			(xy 113.379757 -218.718189) (xy 113.371632 -218.769484) (xy 113.355584 -218.818877) (xy 113.332006 -218.865151)
			(xy 113.30148 -218.907167) (xy 113.264757 -218.94389) (xy 113.222741 -218.974416) (xy 113.176467 -218.997994)
			(xy 113.127074 -219.014042) (xy 113.075779 -219.022167) (xy 113.023845 -219.022167) (xy 112.97255 -219.014042)
			(xy 112.923157 -218.997994) (xy 112.876883 -218.974416) (xy 112.834867 -218.94389) (xy 112.798144 -218.907167)
			(xy 112.767618 -218.865151) (xy 112.74404 -218.818877) (xy 112.727992 -218.769484) (xy 112.719867 -218.718189)
			(xy 112.439957 -218.718189) (xy 112.431832 -218.769484) (xy 112.415784 -218.818877) (xy 112.392206 -218.865151)
			(xy 112.36168 -218.907167) (xy 112.324957 -218.94389) (xy 112.282941 -218.974416) (xy 112.236667 -218.997994)
			(xy 112.187274 -219.014042) (xy 112.135979 -219.022167) (xy 112.084045 -219.022167) (xy 112.03275 -219.014042)
			(xy 111.983357 -218.997994) (xy 111.937083 -218.974416) (xy 111.895067 -218.94389) (xy 111.858344 -218.907167)
			(xy 111.827818 -218.865151) (xy 111.80424 -218.818877) (xy 111.788192 -218.769484) (xy 111.780067 -218.718189)
			(xy 111.779558 -218.692222) (xy 111.587026 -218.692222) (xy 111.587026 -219.124784) (xy 111.58745 -219.134837)
			(xy 111.595165 -219.153403) (xy 111.609419 -219.167583) (xy 111.628025 -219.175202) (xy 111.63808 -219.175584)
			(xy 111.640366 -219.175584) (xy 111.666334 -219.176064) (xy 111.717631 -219.184184) (xy 111.767027 -219.200229)
			(xy 111.813304 -219.223804) (xy 111.855323 -219.254329) (xy 111.892049 -219.291051) (xy 111.922578 -219.333067)
			(xy 111.946158 -219.379342) (xy 111.962208 -219.428735) (xy 111.970333 -219.480032) (xy 111.970333 -219.531968)
			(xy 111.970327 -219.532005) (xy 112.250221 -219.532005) (xy 112.250221 -219.480071) (xy 112.258346 -219.428776)
			(xy 112.274394 -219.379383) (xy 112.297972 -219.333109) (xy 112.328498 -219.291093) (xy 112.365221 -219.25437)
			(xy 112.407237 -219.223844) (xy 112.453511 -219.200266) (xy 112.502904 -219.184218) (xy 112.554199 -219.176093)
			(xy 112.606133 -219.176093) (xy 112.657428 -219.184218) (xy 112.706821 -219.200266) (xy 112.753095 -219.223844)
			(xy 112.795111 -219.25437) (xy 112.831834 -219.291093) (xy 112.86236 -219.333109) (xy 112.885938 -219.379383)
			(xy 112.901986 -219.428776) (xy 112.910111 -219.480071) (xy 112.91062 -219.506038) (xy 112.910111 -219.532005)
			(xy 113.190021 -219.532005) (xy 113.190021 -219.480071) (xy 113.198146 -219.428776) (xy 113.214194 -219.379383)
			(xy 113.237772 -219.333109) (xy 113.268298 -219.291093) (xy 113.305021 -219.25437) (xy 113.347037 -219.223844)
			(xy 113.393311 -219.200266) (xy 113.442704 -219.184218) (xy 113.493999 -219.176093) (xy 113.545933 -219.176093)
			(xy 113.597228 -219.184218) (xy 113.646621 -219.200266) (xy 113.692895 -219.223844) (xy 113.734911 -219.25437)
			(xy 113.771634 -219.291093) (xy 113.80216 -219.333109) (xy 113.825738 -219.379383) (xy 113.841786 -219.428776)
			(xy 113.849911 -219.480071) (xy 113.85042 -219.506038) (xy 113.849911 -219.532005) (xy 114.129821 -219.532005)
			(xy 114.129821 -219.480071) (xy 114.137946 -219.428776) (xy 114.153994 -219.379383) (xy 114.177572 -219.333109)
			(xy 114.208098 -219.291093) (xy 114.244821 -219.25437) (xy 114.286837 -219.223844) (xy 114.333111 -219.200266)
			(xy 114.382504 -219.184218) (xy 114.433799 -219.176093) (xy 114.485733 -219.176093) (xy 114.537028 -219.184218)
			(xy 114.586421 -219.200266) (xy 114.632695 -219.223844) (xy 114.674711 -219.25437) (xy 114.711434 -219.291093)
			(xy 114.74196 -219.333109) (xy 114.765538 -219.379383) (xy 114.781586 -219.428776) (xy 114.789711 -219.480071)
			(xy 114.79022 -219.506038) (xy 114.789711 -219.532005) (xy 115.069621 -219.532005) (xy 115.069621 -219.480071)
			(xy 115.077746 -219.428776) (xy 115.093794 -219.379383) (xy 115.117372 -219.333109) (xy 115.147898 -219.291093)
			(xy 115.184621 -219.25437) (xy 115.226637 -219.223844) (xy 115.272911 -219.200266) (xy 115.322304 -219.184218)
			(xy 115.373599 -219.176093) (xy 115.425533 -219.176093) (xy 115.476828 -219.184218) (xy 115.526221 -219.200266)
			(xy 115.572495 -219.223844) (xy 115.614511 -219.25437) (xy 115.651234 -219.291093) (xy 115.68176 -219.333109)
			(xy 115.705338 -219.379383) (xy 115.721386 -219.428776) (xy 115.729511 -219.480071) (xy 115.73002 -219.506038)
			(xy 115.729511 -219.532005) (xy 116.009421 -219.532005) (xy 116.009421 -219.480071) (xy 116.017546 -219.428776)
			(xy 116.033594 -219.379383) (xy 116.057172 -219.333109) (xy 116.087698 -219.291093) (xy 116.124421 -219.25437)
			(xy 116.166437 -219.223844) (xy 116.212711 -219.200266) (xy 116.262104 -219.184218) (xy 116.313399 -219.176093)
			(xy 116.365333 -219.176093) (xy 116.416628 -219.184218) (xy 116.466021 -219.200266) (xy 116.512295 -219.223844)
			(xy 116.554311 -219.25437) (xy 116.591034 -219.291093) (xy 116.62156 -219.333109) (xy 116.645138 -219.379383)
			(xy 116.661186 -219.428776) (xy 116.669311 -219.480071) (xy 116.66982 -219.506038) (xy 116.669311 -219.532005)
			(xy 116.949221 -219.532005) (xy 116.949221 -219.480071) (xy 116.957346 -219.428776) (xy 116.973394 -219.379383)
			(xy 116.996972 -219.333109) (xy 117.027498 -219.291093) (xy 117.064221 -219.25437) (xy 117.106237 -219.223844)
			(xy 117.152511 -219.200266) (xy 117.201904 -219.184218) (xy 117.253199 -219.176093) (xy 117.305133 -219.176093)
			(xy 117.356428 -219.184218) (xy 117.405821 -219.200266) (xy 117.452095 -219.223844) (xy 117.494111 -219.25437)
			(xy 117.530834 -219.291093) (xy 117.56136 -219.333109) (xy 117.584938 -219.379383) (xy 117.600986 -219.428776)
			(xy 117.609111 -219.480071) (xy 117.60962 -219.506038) (xy 117.609111 -219.532005) (xy 117.889021 -219.532005)
			(xy 117.889021 -219.480071) (xy 117.897146 -219.428776) (xy 117.913194 -219.379383) (xy 117.936772 -219.333109)
			(xy 117.967298 -219.291093) (xy 118.004021 -219.25437) (xy 118.046037 -219.223844) (xy 118.092311 -219.200266)
			(xy 118.141704 -219.184218) (xy 118.192999 -219.176093) (xy 118.244933 -219.176093) (xy 118.296228 -219.184218)
			(xy 118.345621 -219.200266) (xy 118.391895 -219.223844) (xy 118.433911 -219.25437) (xy 118.470634 -219.291093)
			(xy 118.50116 -219.333109) (xy 118.524738 -219.379383) (xy 118.540786 -219.428776) (xy 118.548911 -219.480071)
			(xy 118.54942 -219.506038) (xy 118.548911 -219.532005) (xy 118.828821 -219.532005) (xy 118.828821 -219.480071)
			(xy 118.836946 -219.428776) (xy 118.852994 -219.379383) (xy 118.876572 -219.333109) (xy 118.907098 -219.291093)
			(xy 118.943821 -219.25437) (xy 118.985837 -219.223844) (xy 119.032111 -219.200266) (xy 119.081504 -219.184218)
			(xy 119.132799 -219.176093) (xy 119.184733 -219.176093) (xy 119.236028 -219.184218) (xy 119.285421 -219.200266)
			(xy 119.331695 -219.223844) (xy 119.373711 -219.25437) (xy 119.410434 -219.291093) (xy 119.44096 -219.333109)
			(xy 119.464538 -219.379383) (xy 119.480586 -219.428776) (xy 119.488711 -219.480071) (xy 119.48922 -219.506038)
			(xy 119.488711 -219.532005) (xy 119.768621 -219.532005) (xy 119.768621 -219.480071) (xy 119.776746 -219.428776)
			(xy 119.792794 -219.379383) (xy 119.816372 -219.333109) (xy 119.846898 -219.291093) (xy 119.883621 -219.25437)
			(xy 119.925637 -219.223844) (xy 119.971911 -219.200266) (xy 120.021304 -219.184218) (xy 120.072599 -219.176093)
			(xy 120.124533 -219.176093) (xy 120.175828 -219.184218) (xy 120.225221 -219.200266) (xy 120.271495 -219.223844)
			(xy 120.313511 -219.25437) (xy 120.350234 -219.291093) (xy 120.38076 -219.333109) (xy 120.404338 -219.379383)
			(xy 120.420386 -219.428776) (xy 120.428511 -219.480071) (xy 120.42902 -219.506038) (xy 120.428511 -219.532005)
			(xy 120.708421 -219.532005) (xy 120.708421 -219.480071) (xy 120.716546 -219.428776) (xy 120.732594 -219.379383)
			(xy 120.756172 -219.333109) (xy 120.786698 -219.291093) (xy 120.823421 -219.25437) (xy 120.865437 -219.223844)
			(xy 120.911711 -219.200266) (xy 120.961104 -219.184218) (xy 121.012399 -219.176093) (xy 121.064333 -219.176093)
			(xy 121.115628 -219.184218) (xy 121.165021 -219.200266) (xy 121.211295 -219.223844) (xy 121.253311 -219.25437)
			(xy 121.290034 -219.291093) (xy 121.32056 -219.333109) (xy 121.344138 -219.379383) (xy 121.360186 -219.428776)
			(xy 121.368311 -219.480071) (xy 121.36882 -219.506038) (xy 121.368311 -219.532005) (xy 121.648221 -219.532005)
			(xy 121.648221 -219.480071) (xy 121.656346 -219.428776) (xy 121.672394 -219.379383) (xy 121.695972 -219.333109)
			(xy 121.726498 -219.291093) (xy 121.763221 -219.25437) (xy 121.805237 -219.223844) (xy 121.851511 -219.200266)
			(xy 121.900904 -219.184218) (xy 121.952199 -219.176093) (xy 122.004133 -219.176093) (xy 122.055428 -219.184218)
			(xy 122.104821 -219.200266) (xy 122.151095 -219.223844) (xy 122.193111 -219.25437) (xy 122.229834 -219.291093)
			(xy 122.26036 -219.333109) (xy 122.283938 -219.379383) (xy 122.299986 -219.428776) (xy 122.308111 -219.480071)
			(xy 122.30862 -219.506038) (xy 122.308111 -219.532005) (xy 122.588021 -219.532005) (xy 122.588021 -219.480071)
			(xy 122.596146 -219.428776) (xy 122.612194 -219.379383) (xy 122.635772 -219.333109) (xy 122.666298 -219.291093)
			(xy 122.703021 -219.25437) (xy 122.745037 -219.223844) (xy 122.791311 -219.200266) (xy 122.840704 -219.184218)
			(xy 122.891999 -219.176093) (xy 122.943933 -219.176093) (xy 122.995228 -219.184218) (xy 123.044621 -219.200266)
			(xy 123.090895 -219.223844) (xy 123.132911 -219.25437) (xy 123.169634 -219.291093) (xy 123.20016 -219.333109)
			(xy 123.223738 -219.379383) (xy 123.239786 -219.428776) (xy 123.247911 -219.480071) (xy 123.24842 -219.506038)
			(xy 123.247911 -219.532005) (xy 123.527821 -219.532005) (xy 123.527821 -219.480071) (xy 123.535946 -219.428776)
			(xy 123.551994 -219.379383) (xy 123.575572 -219.333109) (xy 123.606098 -219.291093) (xy 123.642821 -219.25437)
			(xy 123.684837 -219.223844) (xy 123.731111 -219.200266) (xy 123.780504 -219.184218) (xy 123.831799 -219.176093)
			(xy 123.883733 -219.176093) (xy 123.935028 -219.184218) (xy 123.984421 -219.200266) (xy 124.030695 -219.223844)
			(xy 124.072711 -219.25437) (xy 124.109434 -219.291093) (xy 124.13996 -219.333109) (xy 124.163538 -219.379383)
			(xy 124.179586 -219.428776) (xy 124.187711 -219.480071) (xy 124.18822 -219.506038) (xy 124.187711 -219.532005)
			(xy 124.467621 -219.532005) (xy 124.467621 -219.480071) (xy 124.475746 -219.428776) (xy 124.491794 -219.379383)
			(xy 124.515372 -219.333109) (xy 124.545898 -219.291093) (xy 124.582621 -219.25437) (xy 124.624637 -219.223844)
			(xy 124.670911 -219.200266) (xy 124.720304 -219.184218) (xy 124.771599 -219.176093) (xy 124.823533 -219.176093)
			(xy 124.874828 -219.184218) (xy 124.924221 -219.200266) (xy 124.970495 -219.223844) (xy 125.012511 -219.25437)
			(xy 125.049234 -219.291093) (xy 125.07976 -219.333109) (xy 125.103338 -219.379383) (xy 125.119386 -219.428776)
			(xy 125.127511 -219.480071) (xy 125.12802 -219.506038) (xy 125.127511 -219.532005) (xy 125.407421 -219.532005)
			(xy 125.407421 -219.480071) (xy 125.415546 -219.428776) (xy 125.431594 -219.379383) (xy 125.455172 -219.333109)
			(xy 125.485698 -219.291093) (xy 125.522421 -219.25437) (xy 125.564437 -219.223844) (xy 125.610711 -219.200266)
			(xy 125.660104 -219.184218) (xy 125.711399 -219.176093) (xy 125.763333 -219.176093) (xy 125.814628 -219.184218)
			(xy 125.864021 -219.200266) (xy 125.910295 -219.223844) (xy 125.952311 -219.25437) (xy 125.989034 -219.291093)
			(xy 126.01956 -219.333109) (xy 126.043138 -219.379383) (xy 126.059186 -219.428776) (xy 126.067311 -219.480071)
			(xy 126.06782 -219.506038) (xy 126.067311 -219.532005) (xy 126.347221 -219.532005) (xy 126.347221 -219.480071)
			(xy 126.355346 -219.428776) (xy 126.371394 -219.379383) (xy 126.394972 -219.333109) (xy 126.425498 -219.291093)
			(xy 126.462221 -219.25437) (xy 126.504237 -219.223844) (xy 126.550511 -219.200266) (xy 126.599904 -219.184218)
			(xy 126.651199 -219.176093) (xy 126.703133 -219.176093) (xy 126.754428 -219.184218) (xy 126.803821 -219.200266)
			(xy 126.850095 -219.223844) (xy 126.892111 -219.25437) (xy 126.928834 -219.291093) (xy 126.95936 -219.333109)
			(xy 126.982938 -219.379383) (xy 126.998986 -219.428776) (xy 127.007111 -219.480071) (xy 127.00762 -219.506038)
			(xy 127.007111 -219.532005) (xy 127.287021 -219.532005) (xy 127.287021 -219.480071) (xy 127.295146 -219.428776)
			(xy 127.311194 -219.379383) (xy 127.334772 -219.333109) (xy 127.365298 -219.291093) (xy 127.402021 -219.25437)
			(xy 127.444037 -219.223844) (xy 127.490311 -219.200266) (xy 127.539704 -219.184218) (xy 127.590999 -219.176093)
			(xy 127.642933 -219.176093) (xy 127.694228 -219.184218) (xy 127.743621 -219.200266) (xy 127.789895 -219.223844)
			(xy 127.831911 -219.25437) (xy 127.868634 -219.291093) (xy 127.89916 -219.333109) (xy 127.922738 -219.379383)
			(xy 127.938786 -219.428776) (xy 127.946911 -219.480071) (xy 127.94742 -219.506038) (xy 127.946911 -219.532005)
			(xy 128.226821 -219.532005) (xy 128.226821 -219.480071) (xy 128.234946 -219.428776) (xy 128.250994 -219.379383)
			(xy 128.274572 -219.333109) (xy 128.305098 -219.291093) (xy 128.341821 -219.25437) (xy 128.383837 -219.223844)
			(xy 128.430111 -219.200266) (xy 128.479504 -219.184218) (xy 128.530799 -219.176093) (xy 128.582733 -219.176093)
			(xy 128.634028 -219.184218) (xy 128.683421 -219.200266) (xy 128.729695 -219.223844) (xy 128.771711 -219.25437)
			(xy 128.808434 -219.291093) (xy 128.83896 -219.333109) (xy 128.862538 -219.379383) (xy 128.878586 -219.428776)
			(xy 128.886711 -219.480071) (xy 128.88722 -219.506038) (xy 128.886711 -219.532005) (xy 129.166621 -219.532005)
			(xy 129.166621 -219.480071) (xy 129.174746 -219.428776) (xy 129.190794 -219.379383) (xy 129.214372 -219.333109)
			(xy 129.244898 -219.291093) (xy 129.281621 -219.25437) (xy 129.323637 -219.223844) (xy 129.369911 -219.200266)
			(xy 129.419304 -219.184218) (xy 129.470599 -219.176093) (xy 129.522533 -219.176093) (xy 129.573828 -219.184218)
			(xy 129.623221 -219.200266) (xy 129.669495 -219.223844) (xy 129.711511 -219.25437) (xy 129.748234 -219.291093)
			(xy 129.77876 -219.333109) (xy 129.802338 -219.379383) (xy 129.818386 -219.428776) (xy 129.826511 -219.480071)
			(xy 129.82702 -219.506038) (xy 129.826511 -219.532005) (xy 130.106421 -219.532005) (xy 130.106421 -219.480071)
			(xy 130.114546 -219.428776) (xy 130.130594 -219.379383) (xy 130.154172 -219.333109) (xy 130.184698 -219.291093)
			(xy 130.221421 -219.25437) (xy 130.263437 -219.223844) (xy 130.309711 -219.200266) (xy 130.359104 -219.184218)
			(xy 130.410399 -219.176093) (xy 130.462333 -219.176093) (xy 130.513628 -219.184218) (xy 130.563021 -219.200266)
			(xy 130.609295 -219.223844) (xy 130.651311 -219.25437) (xy 130.688034 -219.291093) (xy 130.71856 -219.333109)
			(xy 130.742138 -219.379383) (xy 130.758186 -219.428776) (xy 130.766311 -219.480071) (xy 130.76682 -219.506038)
			(xy 130.766311 -219.532005) (xy 131.046221 -219.532005) (xy 131.046221 -219.480071) (xy 131.054346 -219.428776)
			(xy 131.070394 -219.379383) (xy 131.093972 -219.333109) (xy 131.124498 -219.291093) (xy 131.161221 -219.25437)
			(xy 131.203237 -219.223844) (xy 131.249511 -219.200266) (xy 131.298904 -219.184218) (xy 131.350199 -219.176093)
			(xy 131.402133 -219.176093) (xy 131.453428 -219.184218) (xy 131.502821 -219.200266) (xy 131.549095 -219.223844)
			(xy 131.591111 -219.25437) (xy 131.627834 -219.291093) (xy 131.65836 -219.333109) (xy 131.681938 -219.379383)
			(xy 131.697986 -219.428776) (xy 131.706111 -219.480071) (xy 131.70662 -219.506038) (xy 131.706111 -219.532005)
			(xy 131.986021 -219.532005) (xy 131.986021 -219.480071) (xy 131.994146 -219.428776) (xy 132.010194 -219.379383)
			(xy 132.033772 -219.333109) (xy 132.064298 -219.291093) (xy 132.101021 -219.25437) (xy 132.143037 -219.223844)
			(xy 132.189311 -219.200266) (xy 132.238704 -219.184218) (xy 132.289999 -219.176093) (xy 132.341933 -219.176093)
			(xy 132.393228 -219.184218) (xy 132.442621 -219.200266) (xy 132.488895 -219.223844) (xy 132.530911 -219.25437)
			(xy 132.567634 -219.291093) (xy 132.59816 -219.333109) (xy 132.621738 -219.379383) (xy 132.637786 -219.428776)
			(xy 132.645911 -219.480071) (xy 132.64642 -219.506038) (xy 132.645911 -219.532005) (xy 132.925821 -219.532005)
			(xy 132.925821 -219.480071) (xy 132.933946 -219.428776) (xy 132.949994 -219.379383) (xy 132.973572 -219.333109)
			(xy 133.004098 -219.291093) (xy 133.040821 -219.25437) (xy 133.082837 -219.223844) (xy 133.129111 -219.200266)
			(xy 133.178504 -219.184218) (xy 133.229799 -219.176093) (xy 133.281733 -219.176093) (xy 133.333028 -219.184218)
			(xy 133.382421 -219.200266) (xy 133.428695 -219.223844) (xy 133.470711 -219.25437) (xy 133.507434 -219.291093)
			(xy 133.53796 -219.333109) (xy 133.561538 -219.379383) (xy 133.577586 -219.428776) (xy 133.585711 -219.480071)
			(xy 133.58622 -219.506038) (xy 133.585711 -219.532005) (xy 133.577586 -219.5833) (xy 133.561538 -219.632693)
			(xy 133.53796 -219.678967) (xy 133.507434 -219.720983) (xy 133.470711 -219.757706) (xy 133.428695 -219.788232)
			(xy 133.382421 -219.81181) (xy 133.333028 -219.827858) (xy 133.281733 -219.835983) (xy 133.229799 -219.835983)
			(xy 133.178504 -219.827858) (xy 133.129111 -219.81181) (xy 133.082837 -219.788232) (xy 133.040821 -219.757706)
			(xy 133.004098 -219.720983) (xy 132.973572 -219.678967) (xy 132.949994 -219.632693) (xy 132.933946 -219.5833)
			(xy 132.925821 -219.532005) (xy 132.645911 -219.532005) (xy 132.637786 -219.5833) (xy 132.621738 -219.632693)
			(xy 132.59816 -219.678967) (xy 132.567634 -219.720983) (xy 132.530911 -219.757706) (xy 132.488895 -219.788232)
			(xy 132.442621 -219.81181) (xy 132.393228 -219.827858) (xy 132.341933 -219.835983) (xy 132.289999 -219.835983)
			(xy 132.238704 -219.827858) (xy 132.189311 -219.81181) (xy 132.143037 -219.788232) (xy 132.101021 -219.757706)
			(xy 132.064298 -219.720983) (xy 132.033772 -219.678967) (xy 132.010194 -219.632693) (xy 131.994146 -219.5833)
			(xy 131.986021 -219.532005) (xy 131.706111 -219.532005) (xy 131.697986 -219.5833) (xy 131.681938 -219.632693)
			(xy 131.65836 -219.678967) (xy 131.627834 -219.720983) (xy 131.591111 -219.757706) (xy 131.549095 -219.788232)
			(xy 131.502821 -219.81181) (xy 131.453428 -219.827858) (xy 131.402133 -219.835983) (xy 131.350199 -219.835983)
			(xy 131.298904 -219.827858) (xy 131.249511 -219.81181) (xy 131.203237 -219.788232) (xy 131.161221 -219.757706)
			(xy 131.124498 -219.720983) (xy 131.093972 -219.678967) (xy 131.070394 -219.632693) (xy 131.054346 -219.5833)
			(xy 131.046221 -219.532005) (xy 130.766311 -219.532005) (xy 130.758186 -219.5833) (xy 130.742138 -219.632693)
			(xy 130.71856 -219.678967) (xy 130.688034 -219.720983) (xy 130.651311 -219.757706) (xy 130.609295 -219.788232)
			(xy 130.563021 -219.81181) (xy 130.513628 -219.827858) (xy 130.462333 -219.835983) (xy 130.410399 -219.835983)
			(xy 130.359104 -219.827858) (xy 130.309711 -219.81181) (xy 130.263437 -219.788232) (xy 130.221421 -219.757706)
			(xy 130.184698 -219.720983) (xy 130.154172 -219.678967) (xy 130.130594 -219.632693) (xy 130.114546 -219.5833)
			(xy 130.106421 -219.532005) (xy 129.826511 -219.532005) (xy 129.818386 -219.5833) (xy 129.802338 -219.632693)
			(xy 129.77876 -219.678967) (xy 129.748234 -219.720983) (xy 129.711511 -219.757706) (xy 129.669495 -219.788232)
			(xy 129.623221 -219.81181) (xy 129.573828 -219.827858) (xy 129.522533 -219.835983) (xy 129.470599 -219.835983)
			(xy 129.419304 -219.827858) (xy 129.369911 -219.81181) (xy 129.323637 -219.788232) (xy 129.281621 -219.757706)
			(xy 129.244898 -219.720983) (xy 129.214372 -219.678967) (xy 129.190794 -219.632693) (xy 129.174746 -219.5833)
			(xy 129.166621 -219.532005) (xy 128.886711 -219.532005) (xy 128.878586 -219.5833) (xy 128.862538 -219.632693)
			(xy 128.83896 -219.678967) (xy 128.808434 -219.720983) (xy 128.771711 -219.757706) (xy 128.729695 -219.788232)
			(xy 128.683421 -219.81181) (xy 128.634028 -219.827858) (xy 128.582733 -219.835983) (xy 128.530799 -219.835983)
			(xy 128.479504 -219.827858) (xy 128.430111 -219.81181) (xy 128.383837 -219.788232) (xy 128.341821 -219.757706)
			(xy 128.305098 -219.720983) (xy 128.274572 -219.678967) (xy 128.250994 -219.632693) (xy 128.234946 -219.5833)
			(xy 128.226821 -219.532005) (xy 127.946911 -219.532005) (xy 127.938786 -219.5833) (xy 127.922738 -219.632693)
			(xy 127.89916 -219.678967) (xy 127.868634 -219.720983) (xy 127.831911 -219.757706) (xy 127.789895 -219.788232)
			(xy 127.743621 -219.81181) (xy 127.694228 -219.827858) (xy 127.642933 -219.835983) (xy 127.590999 -219.835983)
			(xy 127.539704 -219.827858) (xy 127.490311 -219.81181) (xy 127.444037 -219.788232) (xy 127.402021 -219.757706)
			(xy 127.365298 -219.720983) (xy 127.334772 -219.678967) (xy 127.311194 -219.632693) (xy 127.295146 -219.5833)
			(xy 127.287021 -219.532005) (xy 127.007111 -219.532005) (xy 126.998986 -219.5833) (xy 126.982938 -219.632693)
			(xy 126.95936 -219.678967) (xy 126.928834 -219.720983) (xy 126.892111 -219.757706) (xy 126.850095 -219.788232)
			(xy 126.803821 -219.81181) (xy 126.754428 -219.827858) (xy 126.703133 -219.835983) (xy 126.651199 -219.835983)
			(xy 126.599904 -219.827858) (xy 126.550511 -219.81181) (xy 126.504237 -219.788232) (xy 126.462221 -219.757706)
			(xy 126.425498 -219.720983) (xy 126.394972 -219.678967) (xy 126.371394 -219.632693) (xy 126.355346 -219.5833)
			(xy 126.347221 -219.532005) (xy 126.067311 -219.532005) (xy 126.059186 -219.5833) (xy 126.043138 -219.632693)
			(xy 126.01956 -219.678967) (xy 125.989034 -219.720983) (xy 125.952311 -219.757706) (xy 125.910295 -219.788232)
			(xy 125.864021 -219.81181) (xy 125.814628 -219.827858) (xy 125.763333 -219.835983) (xy 125.711399 -219.835983)
			(xy 125.660104 -219.827858) (xy 125.610711 -219.81181) (xy 125.564437 -219.788232) (xy 125.522421 -219.757706)
			(xy 125.485698 -219.720983) (xy 125.455172 -219.678967) (xy 125.431594 -219.632693) (xy 125.415546 -219.5833)
			(xy 125.407421 -219.532005) (xy 125.127511 -219.532005) (xy 125.119386 -219.5833) (xy 125.103338 -219.632693)
			(xy 125.07976 -219.678967) (xy 125.049234 -219.720983) (xy 125.012511 -219.757706) (xy 124.970495 -219.788232)
			(xy 124.924221 -219.81181) (xy 124.874828 -219.827858) (xy 124.823533 -219.835983) (xy 124.771599 -219.835983)
			(xy 124.720304 -219.827858) (xy 124.670911 -219.81181) (xy 124.624637 -219.788232) (xy 124.582621 -219.757706)
			(xy 124.545898 -219.720983) (xy 124.515372 -219.678967) (xy 124.491794 -219.632693) (xy 124.475746 -219.5833)
			(xy 124.467621 -219.532005) (xy 124.187711 -219.532005) (xy 124.179586 -219.5833) (xy 124.163538 -219.632693)
			(xy 124.13996 -219.678967) (xy 124.109434 -219.720983) (xy 124.072711 -219.757706) (xy 124.030695 -219.788232)
			(xy 123.984421 -219.81181) (xy 123.935028 -219.827858) (xy 123.883733 -219.835983) (xy 123.831799 -219.835983)
			(xy 123.780504 -219.827858) (xy 123.731111 -219.81181) (xy 123.684837 -219.788232) (xy 123.642821 -219.757706)
			(xy 123.606098 -219.720983) (xy 123.575572 -219.678967) (xy 123.551994 -219.632693) (xy 123.535946 -219.5833)
			(xy 123.527821 -219.532005) (xy 123.247911 -219.532005) (xy 123.239786 -219.5833) (xy 123.223738 -219.632693)
			(xy 123.20016 -219.678967) (xy 123.169634 -219.720983) (xy 123.132911 -219.757706) (xy 123.090895 -219.788232)
			(xy 123.044621 -219.81181) (xy 122.995228 -219.827858) (xy 122.943933 -219.835983) (xy 122.891999 -219.835983)
			(xy 122.840704 -219.827858) (xy 122.791311 -219.81181) (xy 122.745037 -219.788232) (xy 122.703021 -219.757706)
			(xy 122.666298 -219.720983) (xy 122.635772 -219.678967) (xy 122.612194 -219.632693) (xy 122.596146 -219.5833)
			(xy 122.588021 -219.532005) (xy 122.308111 -219.532005) (xy 122.299986 -219.5833) (xy 122.283938 -219.632693)
			(xy 122.26036 -219.678967) (xy 122.229834 -219.720983) (xy 122.193111 -219.757706) (xy 122.151095 -219.788232)
			(xy 122.104821 -219.81181) (xy 122.055428 -219.827858) (xy 122.004133 -219.835983) (xy 121.952199 -219.835983)
			(xy 121.900904 -219.827858) (xy 121.851511 -219.81181) (xy 121.805237 -219.788232) (xy 121.763221 -219.757706)
			(xy 121.726498 -219.720983) (xy 121.695972 -219.678967) (xy 121.672394 -219.632693) (xy 121.656346 -219.5833)
			(xy 121.648221 -219.532005) (xy 121.368311 -219.532005) (xy 121.360186 -219.5833) (xy 121.344138 -219.632693)
			(xy 121.32056 -219.678967) (xy 121.290034 -219.720983) (xy 121.253311 -219.757706) (xy 121.211295 -219.788232)
			(xy 121.165021 -219.81181) (xy 121.115628 -219.827858) (xy 121.064333 -219.835983) (xy 121.012399 -219.835983)
			(xy 120.961104 -219.827858) (xy 120.911711 -219.81181) (xy 120.865437 -219.788232) (xy 120.823421 -219.757706)
			(xy 120.786698 -219.720983) (xy 120.756172 -219.678967) (xy 120.732594 -219.632693) (xy 120.716546 -219.5833)
			(xy 120.708421 -219.532005) (xy 120.428511 -219.532005) (xy 120.420386 -219.5833) (xy 120.404338 -219.632693)
			(xy 120.38076 -219.678967) (xy 120.350234 -219.720983) (xy 120.313511 -219.757706) (xy 120.271495 -219.788232)
			(xy 120.225221 -219.81181) (xy 120.175828 -219.827858) (xy 120.124533 -219.835983) (xy 120.072599 -219.835983)
			(xy 120.021304 -219.827858) (xy 119.971911 -219.81181) (xy 119.925637 -219.788232) (xy 119.883621 -219.757706)
			(xy 119.846898 -219.720983) (xy 119.816372 -219.678967) (xy 119.792794 -219.632693) (xy 119.776746 -219.5833)
			(xy 119.768621 -219.532005) (xy 119.488711 -219.532005) (xy 119.480586 -219.5833) (xy 119.464538 -219.632693)
			(xy 119.44096 -219.678967) (xy 119.410434 -219.720983) (xy 119.373711 -219.757706) (xy 119.331695 -219.788232)
			(xy 119.285421 -219.81181) (xy 119.236028 -219.827858) (xy 119.184733 -219.835983) (xy 119.132799 -219.835983)
			(xy 119.081504 -219.827858) (xy 119.032111 -219.81181) (xy 118.985837 -219.788232) (xy 118.943821 -219.757706)
			(xy 118.907098 -219.720983) (xy 118.876572 -219.678967) (xy 118.852994 -219.632693) (xy 118.836946 -219.5833)
			(xy 118.828821 -219.532005) (xy 118.548911 -219.532005) (xy 118.540786 -219.5833) (xy 118.524738 -219.632693)
			(xy 118.50116 -219.678967) (xy 118.470634 -219.720983) (xy 118.433911 -219.757706) (xy 118.391895 -219.788232)
			(xy 118.345621 -219.81181) (xy 118.296228 -219.827858) (xy 118.244933 -219.835983) (xy 118.192999 -219.835983)
			(xy 118.141704 -219.827858) (xy 118.092311 -219.81181) (xy 118.046037 -219.788232) (xy 118.004021 -219.757706)
			(xy 117.967298 -219.720983) (xy 117.936772 -219.678967) (xy 117.913194 -219.632693) (xy 117.897146 -219.5833)
			(xy 117.889021 -219.532005) (xy 117.609111 -219.532005) (xy 117.600986 -219.5833) (xy 117.584938 -219.632693)
			(xy 117.56136 -219.678967) (xy 117.530834 -219.720983) (xy 117.494111 -219.757706) (xy 117.452095 -219.788232)
			(xy 117.405821 -219.81181) (xy 117.356428 -219.827858) (xy 117.305133 -219.835983) (xy 117.253199 -219.835983)
			(xy 117.201904 -219.827858) (xy 117.152511 -219.81181) (xy 117.106237 -219.788232) (xy 117.064221 -219.757706)
			(xy 117.027498 -219.720983) (xy 116.996972 -219.678967) (xy 116.973394 -219.632693) (xy 116.957346 -219.5833)
			(xy 116.949221 -219.532005) (xy 116.669311 -219.532005) (xy 116.661186 -219.5833) (xy 116.645138 -219.632693)
			(xy 116.62156 -219.678967) (xy 116.591034 -219.720983) (xy 116.554311 -219.757706) (xy 116.512295 -219.788232)
			(xy 116.466021 -219.81181) (xy 116.416628 -219.827858) (xy 116.365333 -219.835983) (xy 116.313399 -219.835983)
			(xy 116.262104 -219.827858) (xy 116.212711 -219.81181) (xy 116.166437 -219.788232) (xy 116.124421 -219.757706)
			(xy 116.087698 -219.720983) (xy 116.057172 -219.678967) (xy 116.033594 -219.632693) (xy 116.017546 -219.5833)
			(xy 116.009421 -219.532005) (xy 115.729511 -219.532005) (xy 115.721386 -219.5833) (xy 115.705338 -219.632693)
			(xy 115.68176 -219.678967) (xy 115.651234 -219.720983) (xy 115.614511 -219.757706) (xy 115.572495 -219.788232)
			(xy 115.526221 -219.81181) (xy 115.476828 -219.827858) (xy 115.425533 -219.835983) (xy 115.373599 -219.835983)
			(xy 115.322304 -219.827858) (xy 115.272911 -219.81181) (xy 115.226637 -219.788232) (xy 115.184621 -219.757706)
			(xy 115.147898 -219.720983) (xy 115.117372 -219.678967) (xy 115.093794 -219.632693) (xy 115.077746 -219.5833)
			(xy 115.069621 -219.532005) (xy 114.789711 -219.532005) (xy 114.781586 -219.5833) (xy 114.765538 -219.632693)
			(xy 114.74196 -219.678967) (xy 114.711434 -219.720983) (xy 114.674711 -219.757706) (xy 114.632695 -219.788232)
			(xy 114.586421 -219.81181) (xy 114.537028 -219.827858) (xy 114.485733 -219.835983) (xy 114.433799 -219.835983)
			(xy 114.382504 -219.827858) (xy 114.333111 -219.81181) (xy 114.286837 -219.788232) (xy 114.244821 -219.757706)
			(xy 114.208098 -219.720983) (xy 114.177572 -219.678967) (xy 114.153994 -219.632693) (xy 114.137946 -219.5833)
			(xy 114.129821 -219.532005) (xy 113.849911 -219.532005) (xy 113.841786 -219.5833) (xy 113.825738 -219.632693)
			(xy 113.80216 -219.678967) (xy 113.771634 -219.720983) (xy 113.734911 -219.757706) (xy 113.692895 -219.788232)
			(xy 113.646621 -219.81181) (xy 113.597228 -219.827858) (xy 113.545933 -219.835983) (xy 113.493999 -219.835983)
			(xy 113.442704 -219.827858) (xy 113.393311 -219.81181) (xy 113.347037 -219.788232) (xy 113.305021 -219.757706)
			(xy 113.268298 -219.720983) (xy 113.237772 -219.678967) (xy 113.214194 -219.632693) (xy 113.198146 -219.5833)
			(xy 113.190021 -219.532005) (xy 112.910111 -219.532005) (xy 112.901986 -219.5833) (xy 112.885938 -219.632693)
			(xy 112.86236 -219.678967) (xy 112.831834 -219.720983) (xy 112.795111 -219.757706) (xy 112.753095 -219.788232)
			(xy 112.706821 -219.81181) (xy 112.657428 -219.827858) (xy 112.606133 -219.835983) (xy 112.554199 -219.835983)
			(xy 112.502904 -219.827858) (xy 112.453511 -219.81181) (xy 112.407237 -219.788232) (xy 112.365221 -219.757706)
			(xy 112.328498 -219.720983) (xy 112.297972 -219.678967) (xy 112.274394 -219.632693) (xy 112.258346 -219.5833)
			(xy 112.250221 -219.532005) (xy 111.970327 -219.532005) (xy 111.962208 -219.583265) (xy 111.946158 -219.632658)
			(xy 111.922578 -219.678933) (xy 111.892049 -219.720949) (xy 111.855323 -219.757671) (xy 111.813304 -219.788196)
			(xy 111.767027 -219.811771) (xy 111.717631 -219.827816) (xy 111.666334 -219.835936) (xy 111.640366 -219.836492)
			(xy 111.63808 -219.836492) (xy 111.628021 -219.836863) (xy 111.609407 -219.844482) (xy 111.595144 -219.858664)
			(xy 111.587419 -219.877235) (xy 111.587026 -219.887292) (xy 111.587026 -220.345821) (xy 111.780321 -220.345821)
			(xy 111.780321 -220.293887) (xy 111.788446 -220.242592) (xy 111.804494 -220.193199) (xy 111.828072 -220.146925)
			(xy 111.858598 -220.104909) (xy 111.895321 -220.068186) (xy 111.937337 -220.03766) (xy 111.983611 -220.014082)
			(xy 112.033004 -219.998034) (xy 112.084299 -219.989909) (xy 112.136233 -219.989909) (xy 112.187528 -219.998034)
			(xy 112.236921 -220.014082) (xy 112.283195 -220.03766) (xy 112.325211 -220.068186) (xy 112.361934 -220.104909)
			(xy 112.39246 -220.146925) (xy 112.416038 -220.193199) (xy 112.432086 -220.242592) (xy 112.440211 -220.293887)
			(xy 112.44072 -220.319854) (xy 112.719358 -220.319854) (xy 112.719867 -220.293887) (xy 112.727992 -220.242592)
			(xy 112.74404 -220.193199) (xy 112.767618 -220.146925) (xy 112.798144 -220.104909) (xy 112.834867 -220.068186)
			(xy 112.876883 -220.03766) (xy 112.923157 -220.014082) (xy 112.97255 -219.998034) (xy 113.023845 -219.989909)
			(xy 113.075779 -219.989909) (xy 113.127074 -219.998034) (xy 113.176467 -220.014082) (xy 113.222741 -220.03766)
			(xy 113.264757 -220.068186) (xy 113.30148 -220.104909) (xy 113.332006 -220.146925) (xy 113.355584 -220.193199)
			(xy 113.371632 -220.242592) (xy 113.379757 -220.293887) (xy 113.380266 -220.319854) (xy 113.379769 -220.345821)
			(xy 113.659921 -220.345821) (xy 113.659921 -220.293887) (xy 113.668046 -220.242592) (xy 113.684094 -220.193199)
			(xy 113.707672 -220.146925) (xy 113.738198 -220.104909) (xy 113.774921 -220.068186) (xy 113.816937 -220.03766)
			(xy 113.863211 -220.014082) (xy 113.912604 -219.998034) (xy 113.963899 -219.989909) (xy 114.015833 -219.989909)
			(xy 114.067128 -219.998034) (xy 114.116521 -220.014082) (xy 114.162795 -220.03766) (xy 114.204811 -220.068186)
			(xy 114.241534 -220.104909) (xy 114.27206 -220.146925) (xy 114.295638 -220.193199) (xy 114.311686 -220.242592)
			(xy 114.319811 -220.293887) (xy 114.32032 -220.319854) (xy 114.598958 -220.319854) (xy 114.599467 -220.293887)
			(xy 114.607592 -220.242592) (xy 114.62364 -220.193199) (xy 114.647218 -220.146925) (xy 114.677744 -220.104909)
			(xy 114.714467 -220.068186) (xy 114.756483 -220.03766) (xy 114.802757 -220.014082) (xy 114.85215 -219.998034)
			(xy 114.903445 -219.989909) (xy 114.955379 -219.989909) (xy 115.006674 -219.998034) (xy 115.056067 -220.014082)
			(xy 115.102341 -220.03766) (xy 115.144357 -220.068186) (xy 115.18108 -220.104909) (xy 115.211606 -220.146925)
			(xy 115.235184 -220.193199) (xy 115.251232 -220.242592) (xy 115.259357 -220.293887) (xy 115.259866 -220.319854)
			(xy 115.259369 -220.345821) (xy 115.539521 -220.345821) (xy 115.539521 -220.293887) (xy 115.547646 -220.242592)
			(xy 115.563694 -220.193199) (xy 115.587272 -220.146925) (xy 115.617798 -220.104909) (xy 115.654521 -220.068186)
			(xy 115.696537 -220.03766) (xy 115.742811 -220.014082) (xy 115.792204 -219.998034) (xy 115.843499 -219.989909)
			(xy 115.895433 -219.989909) (xy 115.946728 -219.998034) (xy 115.996121 -220.014082) (xy 116.042395 -220.03766)
			(xy 116.084411 -220.068186) (xy 116.121134 -220.104909) (xy 116.15166 -220.146925) (xy 116.175238 -220.193199)
			(xy 116.191286 -220.242592) (xy 116.199411 -220.293887) (xy 116.19992 -220.319854) (xy 116.478558 -220.319854)
			(xy 116.479067 -220.293887) (xy 116.487192 -220.242592) (xy 116.50324 -220.193199) (xy 116.526818 -220.146925)
			(xy 116.557344 -220.104909) (xy 116.594067 -220.068186) (xy 116.636083 -220.03766) (xy 116.682357 -220.014082)
			(xy 116.73175 -219.998034) (xy 116.783045 -219.989909) (xy 116.834979 -219.989909) (xy 116.886274 -219.998034)
			(xy 116.935667 -220.014082) (xy 116.981941 -220.03766) (xy 117.023957 -220.068186) (xy 117.06068 -220.104909)
			(xy 117.091206 -220.146925) (xy 117.114784 -220.193199) (xy 117.130832 -220.242592) (xy 117.138957 -220.293887)
			(xy 117.139466 -220.319854) (xy 117.138969 -220.345821) (xy 117.419121 -220.345821) (xy 117.419121 -220.293887)
			(xy 117.427246 -220.242592) (xy 117.443294 -220.193199) (xy 117.466872 -220.146925) (xy 117.497398 -220.104909)
			(xy 117.534121 -220.068186) (xy 117.576137 -220.03766) (xy 117.622411 -220.014082) (xy 117.671804 -219.998034)
			(xy 117.723099 -219.989909) (xy 117.775033 -219.989909) (xy 117.826328 -219.998034) (xy 117.875721 -220.014082)
			(xy 117.921995 -220.03766) (xy 117.964011 -220.068186) (xy 118.000734 -220.104909) (xy 118.03126 -220.146925)
			(xy 118.054838 -220.193199) (xy 118.070886 -220.242592) (xy 118.079011 -220.293887) (xy 118.07952 -220.319854)
			(xy 118.358158 -220.319854) (xy 118.358667 -220.293887) (xy 118.366792 -220.242592) (xy 118.38284 -220.193199)
			(xy 118.406418 -220.146925) (xy 118.436944 -220.104909) (xy 118.473667 -220.068186) (xy 118.515683 -220.03766)
			(xy 118.561957 -220.014082) (xy 118.61135 -219.998034) (xy 118.662645 -219.989909) (xy 118.714579 -219.989909)
			(xy 118.765874 -219.998034) (xy 118.815267 -220.014082) (xy 118.861541 -220.03766) (xy 118.903557 -220.068186)
			(xy 118.94028 -220.104909) (xy 118.970806 -220.146925) (xy 118.994384 -220.193199) (xy 119.010432 -220.242592)
			(xy 119.018557 -220.293887) (xy 119.019066 -220.319854) (xy 119.018569 -220.345821) (xy 119.298721 -220.345821)
			(xy 119.298721 -220.293887) (xy 119.306846 -220.242592) (xy 119.322894 -220.193199) (xy 119.346472 -220.146925)
			(xy 119.376998 -220.104909) (xy 119.413721 -220.068186) (xy 119.455737 -220.03766) (xy 119.502011 -220.014082)
			(xy 119.551404 -219.998034) (xy 119.602699 -219.989909) (xy 119.654633 -219.989909) (xy 119.705928 -219.998034)
			(xy 119.755321 -220.014082) (xy 119.801595 -220.03766) (xy 119.843611 -220.068186) (xy 119.880334 -220.104909)
			(xy 119.91086 -220.146925) (xy 119.934438 -220.193199) (xy 119.950486 -220.242592) (xy 119.958611 -220.293887)
			(xy 119.95912 -220.319854) (xy 120.237758 -220.319854) (xy 120.238267 -220.293887) (xy 120.246392 -220.242592)
			(xy 120.26244 -220.193199) (xy 120.286018 -220.146925) (xy 120.316544 -220.104909) (xy 120.353267 -220.068186)
			(xy 120.395283 -220.03766) (xy 120.441557 -220.014082) (xy 120.49095 -219.998034) (xy 120.542245 -219.989909)
			(xy 120.594179 -219.989909) (xy 120.645474 -219.998034) (xy 120.694867 -220.014082) (xy 120.741141 -220.03766)
			(xy 120.783157 -220.068186) (xy 120.81988 -220.104909) (xy 120.850406 -220.146925) (xy 120.873984 -220.193199)
			(xy 120.890032 -220.242592) (xy 120.898157 -220.293887) (xy 120.898666 -220.319854) (xy 120.898169 -220.345821)
			(xy 121.178321 -220.345821) (xy 121.178321 -220.293887) (xy 121.186446 -220.242592) (xy 121.202494 -220.193199)
			(xy 121.226072 -220.146925) (xy 121.256598 -220.104909) (xy 121.293321 -220.068186) (xy 121.335337 -220.03766)
			(xy 121.381611 -220.014082) (xy 121.431004 -219.998034) (xy 121.482299 -219.989909) (xy 121.534233 -219.989909)
			(xy 121.585528 -219.998034) (xy 121.634921 -220.014082) (xy 121.681195 -220.03766) (xy 121.723211 -220.068186)
			(xy 121.759934 -220.104909) (xy 121.79046 -220.146925) (xy 121.814038 -220.193199) (xy 121.830086 -220.242592)
			(xy 121.838211 -220.293887) (xy 121.83872 -220.319854) (xy 122.117358 -220.319854) (xy 122.117867 -220.293887)
			(xy 122.125992 -220.242592) (xy 122.14204 -220.193199) (xy 122.165618 -220.146925) (xy 122.196144 -220.104909)
			(xy 122.232867 -220.068186) (xy 122.274883 -220.03766) (xy 122.321157 -220.014082) (xy 122.37055 -219.998034)
			(xy 122.421845 -219.989909) (xy 122.473779 -219.989909) (xy 122.525074 -219.998034) (xy 122.574467 -220.014082)
			(xy 122.620741 -220.03766) (xy 122.662757 -220.068186) (xy 122.69948 -220.104909) (xy 122.730006 -220.146925)
			(xy 122.753584 -220.193199) (xy 122.769632 -220.242592) (xy 122.777757 -220.293887) (xy 122.778266 -220.319854)
			(xy 122.777769 -220.345821) (xy 123.057921 -220.345821) (xy 123.057921 -220.293887) (xy 123.066046 -220.242592)
			(xy 123.082094 -220.193199) (xy 123.105672 -220.146925) (xy 123.136198 -220.104909) (xy 123.172921 -220.068186)
			(xy 123.214937 -220.03766) (xy 123.261211 -220.014082) (xy 123.310604 -219.998034) (xy 123.361899 -219.989909)
			(xy 123.413833 -219.989909) (xy 123.465128 -219.998034) (xy 123.514521 -220.014082) (xy 123.560795 -220.03766)
			(xy 123.602811 -220.068186) (xy 123.639534 -220.104909) (xy 123.67006 -220.146925) (xy 123.693638 -220.193199)
			(xy 123.709686 -220.242592) (xy 123.717811 -220.293887) (xy 123.71832 -220.319854) (xy 123.996958 -220.319854)
			(xy 123.997467 -220.293887) (xy 124.005592 -220.242592) (xy 124.02164 -220.193199) (xy 124.045218 -220.146925)
			(xy 124.075744 -220.104909) (xy 124.112467 -220.068186) (xy 124.154483 -220.03766) (xy 124.200757 -220.014082)
			(xy 124.25015 -219.998034) (xy 124.301445 -219.989909) (xy 124.353379 -219.989909) (xy 124.404674 -219.998034)
			(xy 124.454067 -220.014082) (xy 124.500341 -220.03766) (xy 124.542357 -220.068186) (xy 124.57908 -220.104909)
			(xy 124.609606 -220.146925) (xy 124.633184 -220.193199) (xy 124.649232 -220.242592) (xy 124.657357 -220.293887)
			(xy 124.657866 -220.319854) (xy 124.657369 -220.345821) (xy 124.937521 -220.345821) (xy 124.937521 -220.293887)
			(xy 124.945646 -220.242592) (xy 124.961694 -220.193199) (xy 124.985272 -220.146925) (xy 125.015798 -220.104909)
			(xy 125.052521 -220.068186) (xy 125.094537 -220.03766) (xy 125.140811 -220.014082) (xy 125.190204 -219.998034)
			(xy 125.241499 -219.989909) (xy 125.293433 -219.989909) (xy 125.344728 -219.998034) (xy 125.394121 -220.014082)
			(xy 125.440395 -220.03766) (xy 125.482411 -220.068186) (xy 125.519134 -220.104909) (xy 125.54966 -220.146925)
			(xy 125.573238 -220.193199) (xy 125.589286 -220.242592) (xy 125.597411 -220.293887) (xy 125.59792 -220.319854)
			(xy 125.876558 -220.319854) (xy 125.877067 -220.293887) (xy 125.885192 -220.242592) (xy 125.90124 -220.193199)
			(xy 125.924818 -220.146925) (xy 125.955344 -220.104909) (xy 125.992067 -220.068186) (xy 126.034083 -220.03766)
			(xy 126.080357 -220.014082) (xy 126.12975 -219.998034) (xy 126.181045 -219.989909) (xy 126.232979 -219.989909)
			(xy 126.284274 -219.998034) (xy 126.333667 -220.014082) (xy 126.379941 -220.03766) (xy 126.421957 -220.068186)
			(xy 126.45868 -220.104909) (xy 126.489206 -220.146925) (xy 126.512784 -220.193199) (xy 126.528832 -220.242592)
			(xy 126.536957 -220.293887) (xy 126.537466 -220.319854) (xy 126.536969 -220.345821) (xy 126.817121 -220.345821)
			(xy 126.817121 -220.293887) (xy 126.825246 -220.242592) (xy 126.841294 -220.193199) (xy 126.864872 -220.146925)
			(xy 126.895398 -220.104909) (xy 126.932121 -220.068186) (xy 126.974137 -220.03766) (xy 127.020411 -220.014082)
			(xy 127.069804 -219.998034) (xy 127.121099 -219.989909) (xy 127.173033 -219.989909) (xy 127.224328 -219.998034)
			(xy 127.273721 -220.014082) (xy 127.319995 -220.03766) (xy 127.362011 -220.068186) (xy 127.398734 -220.104909)
			(xy 127.42926 -220.146925) (xy 127.452838 -220.193199) (xy 127.468886 -220.242592) (xy 127.477011 -220.293887)
			(xy 127.47752 -220.319854) (xy 127.756158 -220.319854) (xy 127.756667 -220.293887) (xy 127.764792 -220.242592)
			(xy 127.78084 -220.193199) (xy 127.804418 -220.146925) (xy 127.834944 -220.104909) (xy 127.871667 -220.068186)
			(xy 127.913683 -220.03766) (xy 127.959957 -220.014082) (xy 128.00935 -219.998034) (xy 128.060645 -219.989909)
			(xy 128.112579 -219.989909) (xy 128.163874 -219.998034) (xy 128.213267 -220.014082) (xy 128.259541 -220.03766)
			(xy 128.301557 -220.068186) (xy 128.33828 -220.104909) (xy 128.368806 -220.146925) (xy 128.392384 -220.193199)
			(xy 128.408432 -220.242592) (xy 128.416557 -220.293887) (xy 128.417066 -220.319854) (xy 128.416569 -220.345821)
			(xy 128.696721 -220.345821) (xy 128.696721 -220.293887) (xy 128.704846 -220.242592) (xy 128.720894 -220.193199)
			(xy 128.744472 -220.146925) (xy 128.774998 -220.104909) (xy 128.811721 -220.068186) (xy 128.853737 -220.03766)
			(xy 128.900011 -220.014082) (xy 128.949404 -219.998034) (xy 129.000699 -219.989909) (xy 129.052633 -219.989909)
			(xy 129.103928 -219.998034) (xy 129.153321 -220.014082) (xy 129.199595 -220.03766) (xy 129.241611 -220.068186)
			(xy 129.278334 -220.104909) (xy 129.30886 -220.146925) (xy 129.332438 -220.193199) (xy 129.348486 -220.242592)
			(xy 129.356611 -220.293887) (xy 129.35712 -220.319854) (xy 129.635758 -220.319854) (xy 129.636267 -220.293887)
			(xy 129.644392 -220.242592) (xy 129.66044 -220.193199) (xy 129.684018 -220.146925) (xy 129.714544 -220.104909)
			(xy 129.751267 -220.068186) (xy 129.793283 -220.03766) (xy 129.839557 -220.014082) (xy 129.88895 -219.998034)
			(xy 129.940245 -219.989909) (xy 129.992179 -219.989909) (xy 130.043474 -219.998034) (xy 130.092867 -220.014082)
			(xy 130.139141 -220.03766) (xy 130.181157 -220.068186) (xy 130.21788 -220.104909) (xy 130.248406 -220.146925)
			(xy 130.271984 -220.193199) (xy 130.288032 -220.242592) (xy 130.296157 -220.293887) (xy 130.296666 -220.319854)
			(xy 130.296169 -220.345821) (xy 130.576321 -220.345821) (xy 130.576321 -220.293887) (xy 130.584446 -220.242592)
			(xy 130.600494 -220.193199) (xy 130.624072 -220.146925) (xy 130.654598 -220.104909) (xy 130.691321 -220.068186)
			(xy 130.733337 -220.03766) (xy 130.779611 -220.014082) (xy 130.829004 -219.998034) (xy 130.880299 -219.989909)
			(xy 130.932233 -219.989909) (xy 130.983528 -219.998034) (xy 131.032921 -220.014082) (xy 131.079195 -220.03766)
			(xy 131.121211 -220.068186) (xy 131.157934 -220.104909) (xy 131.18846 -220.146925) (xy 131.212038 -220.193199)
			(xy 131.228086 -220.242592) (xy 131.236211 -220.293887) (xy 131.23672 -220.319854) (xy 131.515358 -220.319854)
			(xy 131.515867 -220.293887) (xy 131.523992 -220.242592) (xy 131.54004 -220.193199) (xy 131.563618 -220.146925)
			(xy 131.594144 -220.104909) (xy 131.630867 -220.068186) (xy 131.672883 -220.03766) (xy 131.719157 -220.014082)
			(xy 131.76855 -219.998034) (xy 131.819845 -219.989909) (xy 131.871779 -219.989909) (xy 131.923074 -219.998034)
			(xy 131.972467 -220.014082) (xy 132.018741 -220.03766) (xy 132.060757 -220.068186) (xy 132.09748 -220.104909)
			(xy 132.128006 -220.146925) (xy 132.151584 -220.193199) (xy 132.167632 -220.242592) (xy 132.175757 -220.293887)
			(xy 132.176266 -220.319854) (xy 132.175769 -220.345821) (xy 132.455921 -220.345821) (xy 132.455921 -220.293887)
			(xy 132.464046 -220.242592) (xy 132.480094 -220.193199) (xy 132.503672 -220.146925) (xy 132.534198 -220.104909)
			(xy 132.570921 -220.068186) (xy 132.612937 -220.03766) (xy 132.659211 -220.014082) (xy 132.708604 -219.998034)
			(xy 132.759899 -219.989909) (xy 132.811833 -219.989909) (xy 132.863128 -219.998034) (xy 132.912521 -220.014082)
			(xy 132.958795 -220.03766) (xy 133.000811 -220.068186) (xy 133.037534 -220.104909) (xy 133.06806 -220.146925)
			(xy 133.091638 -220.193199) (xy 133.107686 -220.242592) (xy 133.115811 -220.293887) (xy 133.11632 -220.319854)
			(xy 133.115811 -220.345821) (xy 133.107686 -220.397116) (xy 133.091638 -220.446509) (xy 133.06806 -220.492783)
			(xy 133.037534 -220.534799) (xy 133.000811 -220.571522) (xy 132.958795 -220.602048) (xy 132.912521 -220.625626)
			(xy 132.863128 -220.641674) (xy 132.811833 -220.649799) (xy 132.759899 -220.649799) (xy 132.708604 -220.641674)
			(xy 132.659211 -220.625626) (xy 132.612937 -220.602048) (xy 132.570921 -220.571522) (xy 132.534198 -220.534799)
			(xy 132.503672 -220.492783) (xy 132.480094 -220.446509) (xy 132.464046 -220.397116) (xy 132.455921 -220.345821)
			(xy 132.175769 -220.345821) (xy 132.175732 -220.347764) (xy 132.166404 -220.402797) (xy 132.157724 -220.429328)
			(xy 132.14985 -220.451172) (xy 132.354066 -220.80474) (xy 132.376926 -220.809058) (xy 132.401844 -220.814243)
			(xy 132.449827 -220.831206) (xy 132.494645 -220.85532) (xy 132.535238 -220.886018) (xy 132.570647 -220.922574)
			(xy 132.600036 -220.964124) (xy 132.622711 -221.009687) (xy 132.638135 -221.058187) (xy 132.645946 -221.108477)
			(xy 132.64642 -221.133924) (xy 132.645911 -221.159891) (xy 132.637786 -221.211186) (xy 132.621738 -221.260579)
			(xy 132.59816 -221.306853) (xy 132.567634 -221.348869) (xy 132.530911 -221.385592) (xy 132.488895 -221.416118)
			(xy 132.442621 -221.439696) (xy 132.393228 -221.455744) (xy 132.341933 -221.463869) (xy 132.289999 -221.463869)
			(xy 132.238704 -221.455744) (xy 132.189311 -221.439696) (xy 132.143037 -221.416118) (xy 132.101021 -221.385592)
			(xy 132.064298 -221.348869) (xy 132.033772 -221.306853) (xy 132.010194 -221.260579) (xy 131.994146 -221.211186)
			(xy 131.986021 -221.159891) (xy 131.985512 -221.133924) (xy 131.98607 -221.105938) (xy 131.995516 -221.050771)
			(xy 132.004308 -221.024196) (xy 132.011928 -221.002098) (xy 131.80822 -220.649038) (xy 131.785106 -220.64472)
			(xy 131.76017 -220.63956) (xy 131.712147 -220.62263) (xy 131.667288 -220.598536) (xy 131.626655 -220.567848)
			(xy 131.591209 -220.531292) (xy 131.561789 -220.489732) (xy 131.539089 -220.444152) (xy 131.523649 -220.39563)
			(xy 131.515832 -220.345314) (xy 131.515358 -220.319854) (xy 131.23672 -220.319854) (xy 131.236211 -220.345821)
			(xy 131.228086 -220.397116) (xy 131.212038 -220.446509) (xy 131.18846 -220.492783) (xy 131.157934 -220.534799)
			(xy 131.121211 -220.571522) (xy 131.079195 -220.602048) (xy 131.032921 -220.625626) (xy 130.983528 -220.641674)
			(xy 130.932233 -220.649799) (xy 130.880299 -220.649799) (xy 130.829004 -220.641674) (xy 130.779611 -220.625626)
			(xy 130.733337 -220.602048) (xy 130.691321 -220.571522) (xy 130.654598 -220.534799) (xy 130.624072 -220.492783)
			(xy 130.600494 -220.446509) (xy 130.584446 -220.397116) (xy 130.576321 -220.345821) (xy 130.296169 -220.345821)
			(xy 130.296132 -220.347764) (xy 130.286804 -220.402797) (xy 130.278124 -220.429328) (xy 130.27025 -220.451172)
			(xy 130.474466 -220.80474) (xy 130.497326 -220.809058) (xy 130.522244 -220.814243) (xy 130.570227 -220.831206)
			(xy 130.615045 -220.85532) (xy 130.655638 -220.886018) (xy 130.691047 -220.922574) (xy 130.720436 -220.964124)
			(xy 130.743111 -221.009687) (xy 130.758535 -221.058187) (xy 130.766346 -221.108477) (xy 130.76682 -221.133924)
			(xy 130.766311 -221.159891) (xy 130.758186 -221.211186) (xy 130.742138 -221.260579) (xy 130.71856 -221.306853)
			(xy 130.688034 -221.348869) (xy 130.651311 -221.385592) (xy 130.609295 -221.416118) (xy 130.563021 -221.439696)
			(xy 130.513628 -221.455744) (xy 130.462333 -221.463869) (xy 130.410399 -221.463869) (xy 130.359104 -221.455744)
			(xy 130.309711 -221.439696) (xy 130.263437 -221.416118) (xy 130.221421 -221.385592) (xy 130.184698 -221.348869)
			(xy 130.154172 -221.306853) (xy 130.130594 -221.260579) (xy 130.114546 -221.211186) (xy 130.106421 -221.159891)
			(xy 130.105912 -221.133924) (xy 130.10647 -221.105938) (xy 130.115916 -221.050771) (xy 130.124708 -221.024196)
			(xy 130.132328 -221.002098) (xy 129.92862 -220.649038) (xy 129.905506 -220.64472) (xy 129.88057 -220.63956)
			(xy 129.832547 -220.62263) (xy 129.787688 -220.598536) (xy 129.747055 -220.567848) (xy 129.711609 -220.531292)
			(xy 129.682189 -220.489732) (xy 129.659489 -220.444152) (xy 129.644049 -220.39563) (xy 129.636232 -220.345314)
			(xy 129.635758 -220.319854) (xy 129.35712 -220.319854) (xy 129.356611 -220.345821) (xy 129.348486 -220.397116)
			(xy 129.332438 -220.446509) (xy 129.30886 -220.492783) (xy 129.278334 -220.534799) (xy 129.241611 -220.571522)
			(xy 129.199595 -220.602048) (xy 129.153321 -220.625626) (xy 129.103928 -220.641674) (xy 129.052633 -220.649799)
			(xy 129.000699 -220.649799) (xy 128.949404 -220.641674) (xy 128.900011 -220.625626) (xy 128.853737 -220.602048)
			(xy 128.811721 -220.571522) (xy 128.774998 -220.534799) (xy 128.744472 -220.492783) (xy 128.720894 -220.446509)
			(xy 128.704846 -220.397116) (xy 128.696721 -220.345821) (xy 128.416569 -220.345821) (xy 128.416532 -220.347764)
			(xy 128.407204 -220.402797) (xy 128.398524 -220.429328) (xy 128.39065 -220.451172) (xy 128.594866 -220.80474)
			(xy 128.617726 -220.809058) (xy 128.642644 -220.814243) (xy 128.690627 -220.831206) (xy 128.735445 -220.85532)
			(xy 128.776038 -220.886018) (xy 128.811447 -220.922574) (xy 128.840836 -220.964124) (xy 128.863511 -221.009687)
			(xy 128.878935 -221.058187) (xy 128.886746 -221.108477) (xy 128.88722 -221.133924) (xy 128.886711 -221.159891)
			(xy 128.878586 -221.211186) (xy 128.862538 -221.260579) (xy 128.83896 -221.306853) (xy 128.808434 -221.348869)
			(xy 128.771711 -221.385592) (xy 128.729695 -221.416118) (xy 128.683421 -221.439696) (xy 128.634028 -221.455744)
			(xy 128.582733 -221.463869) (xy 128.530799 -221.463869) (xy 128.479504 -221.455744) (xy 128.430111 -221.439696)
			(xy 128.383837 -221.416118) (xy 128.341821 -221.385592) (xy 128.305098 -221.348869) (xy 128.274572 -221.306853)
			(xy 128.250994 -221.260579) (xy 128.234946 -221.211186) (xy 128.226821 -221.159891) (xy 128.226312 -221.133924)
			(xy 128.22687 -221.105938) (xy 128.236316 -221.050771) (xy 128.245108 -221.024196) (xy 128.252728 -221.002098)
			(xy 128.04902 -220.649038) (xy 128.025906 -220.64472) (xy 128.00097 -220.63956) (xy 127.952947 -220.62263)
			(xy 127.908088 -220.598536) (xy 127.867455 -220.567848) (xy 127.832009 -220.531292) (xy 127.802589 -220.489732)
			(xy 127.779889 -220.444152) (xy 127.764449 -220.39563) (xy 127.756632 -220.345314) (xy 127.756158 -220.319854)
			(xy 127.47752 -220.319854) (xy 127.477011 -220.345821) (xy 127.468886 -220.397116) (xy 127.452838 -220.446509)
			(xy 127.42926 -220.492783) (xy 127.398734 -220.534799) (xy 127.362011 -220.571522) (xy 127.319995 -220.602048)
			(xy 127.273721 -220.625626) (xy 127.224328 -220.641674) (xy 127.173033 -220.649799) (xy 127.121099 -220.649799)
			(xy 127.069804 -220.641674) (xy 127.020411 -220.625626) (xy 126.974137 -220.602048) (xy 126.932121 -220.571522)
			(xy 126.895398 -220.534799) (xy 126.864872 -220.492783) (xy 126.841294 -220.446509) (xy 126.825246 -220.397116)
			(xy 126.817121 -220.345821) (xy 126.536969 -220.345821) (xy 126.536932 -220.347764) (xy 126.527604 -220.402797)
			(xy 126.518924 -220.429328) (xy 126.51105 -220.451172) (xy 126.715266 -220.80474) (xy 126.738126 -220.809058)
			(xy 126.763044 -220.814243) (xy 126.811027 -220.831206) (xy 126.855845 -220.85532) (xy 126.896438 -220.886018)
			(xy 126.931847 -220.922574) (xy 126.961236 -220.964124) (xy 126.983911 -221.009687) (xy 126.999335 -221.058187)
			(xy 127.007146 -221.108477) (xy 127.00762 -221.133924) (xy 127.007111 -221.159891) (xy 126.998986 -221.211186)
			(xy 126.982938 -221.260579) (xy 126.95936 -221.306853) (xy 126.928834 -221.348869) (xy 126.892111 -221.385592)
			(xy 126.850095 -221.416118) (xy 126.803821 -221.439696) (xy 126.754428 -221.455744) (xy 126.703133 -221.463869)
			(xy 126.651199 -221.463869) (xy 126.599904 -221.455744) (xy 126.550511 -221.439696) (xy 126.504237 -221.416118)
			(xy 126.462221 -221.385592) (xy 126.425498 -221.348869) (xy 126.394972 -221.306853) (xy 126.371394 -221.260579)
			(xy 126.355346 -221.211186) (xy 126.347221 -221.159891) (xy 126.346712 -221.133924) (xy 126.34727 -221.105938)
			(xy 126.356716 -221.050771) (xy 126.365508 -221.024196) (xy 126.373128 -221.002098) (xy 126.16942 -220.649038)
			(xy 126.146306 -220.64472) (xy 126.12137 -220.63956) (xy 126.073347 -220.62263) (xy 126.028488 -220.598536)
			(xy 125.987855 -220.567848) (xy 125.952409 -220.531292) (xy 125.922989 -220.489732) (xy 125.900289 -220.444152)
			(xy 125.884849 -220.39563) (xy 125.877032 -220.345314) (xy 125.876558 -220.319854) (xy 125.59792 -220.319854)
			(xy 125.597411 -220.345821) (xy 125.589286 -220.397116) (xy 125.573238 -220.446509) (xy 125.54966 -220.492783)
			(xy 125.519134 -220.534799) (xy 125.482411 -220.571522) (xy 125.440395 -220.602048) (xy 125.394121 -220.625626)
			(xy 125.344728 -220.641674) (xy 125.293433 -220.649799) (xy 125.241499 -220.649799) (xy 125.190204 -220.641674)
			(xy 125.140811 -220.625626) (xy 125.094537 -220.602048) (xy 125.052521 -220.571522) (xy 125.015798 -220.534799)
			(xy 124.985272 -220.492783) (xy 124.961694 -220.446509) (xy 124.945646 -220.397116) (xy 124.937521 -220.345821)
			(xy 124.657369 -220.345821) (xy 124.657332 -220.347764) (xy 124.648004 -220.402797) (xy 124.639324 -220.429328)
			(xy 124.63145 -220.451172) (xy 124.835666 -220.80474) (xy 124.858526 -220.809058) (xy 124.883444 -220.814243)
			(xy 124.931427 -220.831206) (xy 124.976245 -220.85532) (xy 125.016838 -220.886018) (xy 125.052247 -220.922574)
			(xy 125.081636 -220.964124) (xy 125.104311 -221.009687) (xy 125.119735 -221.058187) (xy 125.127546 -221.108477)
			(xy 125.12802 -221.133924) (xy 125.127511 -221.159891) (xy 125.119386 -221.211186) (xy 125.103338 -221.260579)
			(xy 125.07976 -221.306853) (xy 125.049234 -221.348869) (xy 125.012511 -221.385592) (xy 124.970495 -221.416118)
			(xy 124.924221 -221.439696) (xy 124.874828 -221.455744) (xy 124.823533 -221.463869) (xy 124.771599 -221.463869)
			(xy 124.720304 -221.455744) (xy 124.670911 -221.439696) (xy 124.624637 -221.416118) (xy 124.582621 -221.385592)
			(xy 124.545898 -221.348869) (xy 124.515372 -221.306853) (xy 124.491794 -221.260579) (xy 124.475746 -221.211186)
			(xy 124.467621 -221.159891) (xy 124.467112 -221.133924) (xy 124.46767 -221.105938) (xy 124.477116 -221.050771)
			(xy 124.485908 -221.024196) (xy 124.493528 -221.002098) (xy 124.28982 -220.649038) (xy 124.266706 -220.64472)
			(xy 124.24177 -220.63956) (xy 124.193747 -220.62263) (xy 124.148888 -220.598536) (xy 124.108255 -220.567848)
			(xy 124.072809 -220.531292) (xy 124.043389 -220.489732) (xy 124.020689 -220.444152) (xy 124.005249 -220.39563)
			(xy 123.997432 -220.345314) (xy 123.996958 -220.319854) (xy 123.71832 -220.319854) (xy 123.717811 -220.345821)
			(xy 123.709686 -220.397116) (xy 123.693638 -220.446509) (xy 123.67006 -220.492783) (xy 123.639534 -220.534799)
			(xy 123.602811 -220.571522) (xy 123.560795 -220.602048) (xy 123.514521 -220.625626) (xy 123.465128 -220.641674)
			(xy 123.413833 -220.649799) (xy 123.361899 -220.649799) (xy 123.310604 -220.641674) (xy 123.261211 -220.625626)
			(xy 123.214937 -220.602048) (xy 123.172921 -220.571522) (xy 123.136198 -220.534799) (xy 123.105672 -220.492783)
			(xy 123.082094 -220.446509) (xy 123.066046 -220.397116) (xy 123.057921 -220.345821) (xy 122.777769 -220.345821)
			(xy 122.777732 -220.347764) (xy 122.768404 -220.402797) (xy 122.759724 -220.429328) (xy 122.75185 -220.451172)
			(xy 122.956066 -220.80474) (xy 122.978926 -220.809058) (xy 123.003844 -220.814243) (xy 123.051827 -220.831206)
			(xy 123.096645 -220.85532) (xy 123.137238 -220.886018) (xy 123.172647 -220.922574) (xy 123.202036 -220.964124)
			(xy 123.224711 -221.009687) (xy 123.240135 -221.058187) (xy 123.247946 -221.108477) (xy 123.24842 -221.133924)
			(xy 123.247911 -221.159891) (xy 123.239786 -221.211186) (xy 123.223738 -221.260579) (xy 123.20016 -221.306853)
			(xy 123.169634 -221.348869) (xy 123.132911 -221.385592) (xy 123.090895 -221.416118) (xy 123.044621 -221.439696)
			(xy 122.995228 -221.455744) (xy 122.943933 -221.463869) (xy 122.891999 -221.463869) (xy 122.840704 -221.455744)
			(xy 122.791311 -221.439696) (xy 122.745037 -221.416118) (xy 122.703021 -221.385592) (xy 122.666298 -221.348869)
			(xy 122.635772 -221.306853) (xy 122.612194 -221.260579) (xy 122.596146 -221.211186) (xy 122.588021 -221.159891)
			(xy 122.587512 -221.133924) (xy 122.58807 -221.105938) (xy 122.597516 -221.050771) (xy 122.606308 -221.024196)
			(xy 122.613928 -221.002098) (xy 122.41022 -220.649038) (xy 122.387106 -220.64472) (xy 122.36217 -220.63956)
			(xy 122.314147 -220.62263) (xy 122.269288 -220.598536) (xy 122.228655 -220.567848) (xy 122.193209 -220.531292)
			(xy 122.163789 -220.489732) (xy 122.141089 -220.444152) (xy 122.125649 -220.39563) (xy 122.117832 -220.345314)
			(xy 122.117358 -220.319854) (xy 121.83872 -220.319854) (xy 121.838211 -220.345821) (xy 121.830086 -220.397116)
			(xy 121.814038 -220.446509) (xy 121.79046 -220.492783) (xy 121.759934 -220.534799) (xy 121.723211 -220.571522)
			(xy 121.681195 -220.602048) (xy 121.634921 -220.625626) (xy 121.585528 -220.641674) (xy 121.534233 -220.649799)
			(xy 121.482299 -220.649799) (xy 121.431004 -220.641674) (xy 121.381611 -220.625626) (xy 121.335337 -220.602048)
			(xy 121.293321 -220.571522) (xy 121.256598 -220.534799) (xy 121.226072 -220.492783) (xy 121.202494 -220.446509)
			(xy 121.186446 -220.397116) (xy 121.178321 -220.345821) (xy 120.898169 -220.345821) (xy 120.898132 -220.347764)
			(xy 120.888804 -220.402797) (xy 120.880124 -220.429328) (xy 120.87225 -220.451172) (xy 121.076466 -220.80474)
			(xy 121.099326 -220.809058) (xy 121.124244 -220.814243) (xy 121.172227 -220.831206) (xy 121.217045 -220.85532)
			(xy 121.257638 -220.886018) (xy 121.293047 -220.922574) (xy 121.322436 -220.964124) (xy 121.345111 -221.009687)
			(xy 121.360535 -221.058187) (xy 121.368346 -221.108477) (xy 121.36882 -221.133924) (xy 121.368311 -221.159891)
			(xy 121.360186 -221.211186) (xy 121.344138 -221.260579) (xy 121.32056 -221.306853) (xy 121.290034 -221.348869)
			(xy 121.253311 -221.385592) (xy 121.211295 -221.416118) (xy 121.165021 -221.439696) (xy 121.115628 -221.455744)
			(xy 121.064333 -221.463869) (xy 121.012399 -221.463869) (xy 120.961104 -221.455744) (xy 120.911711 -221.439696)
			(xy 120.865437 -221.416118) (xy 120.823421 -221.385592) (xy 120.786698 -221.348869) (xy 120.756172 -221.306853)
			(xy 120.732594 -221.260579) (xy 120.716546 -221.211186) (xy 120.708421 -221.159891) (xy 120.707912 -221.133924)
			(xy 120.70847 -221.105938) (xy 120.717916 -221.050771) (xy 120.726708 -221.024196) (xy 120.734328 -221.002098)
			(xy 120.53062 -220.649038) (xy 120.507506 -220.64472) (xy 120.48257 -220.63956) (xy 120.434547 -220.62263)
			(xy 120.389688 -220.598536) (xy 120.349055 -220.567848) (xy 120.313609 -220.531292) (xy 120.284189 -220.489732)
			(xy 120.261489 -220.444152) (xy 120.246049 -220.39563) (xy 120.238232 -220.345314) (xy 120.237758 -220.319854)
			(xy 119.95912 -220.319854) (xy 119.958611 -220.345821) (xy 119.950486 -220.397116) (xy 119.934438 -220.446509)
			(xy 119.91086 -220.492783) (xy 119.880334 -220.534799) (xy 119.843611 -220.571522) (xy 119.801595 -220.602048)
			(xy 119.755321 -220.625626) (xy 119.705928 -220.641674) (xy 119.654633 -220.649799) (xy 119.602699 -220.649799)
			(xy 119.551404 -220.641674) (xy 119.502011 -220.625626) (xy 119.455737 -220.602048) (xy 119.413721 -220.571522)
			(xy 119.376998 -220.534799) (xy 119.346472 -220.492783) (xy 119.322894 -220.446509) (xy 119.306846 -220.397116)
			(xy 119.298721 -220.345821) (xy 119.018569 -220.345821) (xy 119.018532 -220.347764) (xy 119.009204 -220.402797)
			(xy 119.000524 -220.429328) (xy 118.99265 -220.451172) (xy 119.196866 -220.80474) (xy 119.219726 -220.809058)
			(xy 119.244644 -220.814243) (xy 119.292627 -220.831206) (xy 119.337445 -220.85532) (xy 119.378038 -220.886018)
			(xy 119.413447 -220.922574) (xy 119.442836 -220.964124) (xy 119.465511 -221.009687) (xy 119.480935 -221.058187)
			(xy 119.488746 -221.108477) (xy 119.48922 -221.133924) (xy 119.488711 -221.159891) (xy 119.768367 -221.159891)
			(xy 119.768367 -221.107957) (xy 119.776492 -221.056662) (xy 119.79254 -221.007269) (xy 119.816118 -220.960995)
			(xy 119.846644 -220.918979) (xy 119.883367 -220.882256) (xy 119.925383 -220.85173) (xy 119.971657 -220.828152)
			(xy 120.02105 -220.812104) (xy 120.072345 -220.803979) (xy 120.124279 -220.803979) (xy 120.175574 -220.812104)
			(xy 120.224967 -220.828152) (xy 120.271241 -220.85173) (xy 120.313257 -220.882256) (xy 120.34998 -220.918979)
			(xy 120.380506 -220.960995) (xy 120.404084 -221.007269) (xy 120.420132 -221.056662) (xy 120.428257 -221.107957)
			(xy 120.428766 -221.133924) (xy 120.428257 -221.159891) (xy 120.420132 -221.211186) (xy 120.404084 -221.260579)
			(xy 120.380506 -221.306853) (xy 120.34998 -221.348869) (xy 120.313257 -221.385592) (xy 120.271241 -221.416118)
			(xy 120.224967 -221.439696) (xy 120.175574 -221.455744) (xy 120.124279 -221.463869) (xy 120.072345 -221.463869)
			(xy 120.02105 -221.455744) (xy 119.971657 -221.439696) (xy 119.925383 -221.416118) (xy 119.883367 -221.385592)
			(xy 119.846644 -221.348869) (xy 119.816118 -221.306853) (xy 119.79254 -221.260579) (xy 119.776492 -221.211186)
			(xy 119.768367 -221.159891) (xy 119.488711 -221.159891) (xy 119.480586 -221.211186) (xy 119.464538 -221.260579)
			(xy 119.44096 -221.306853) (xy 119.410434 -221.348869) (xy 119.373711 -221.385592) (xy 119.331695 -221.416118)
			(xy 119.285421 -221.439696) (xy 119.236028 -221.455744) (xy 119.184733 -221.463869) (xy 119.132799 -221.463869)
			(xy 119.081504 -221.455744) (xy 119.032111 -221.439696) (xy 118.985837 -221.416118) (xy 118.943821 -221.385592)
			(xy 118.907098 -221.348869) (xy 118.876572 -221.306853) (xy 118.852994 -221.260579) (xy 118.836946 -221.211186)
			(xy 118.828821 -221.159891) (xy 118.828312 -221.133924) (xy 118.82887 -221.105938) (xy 118.838316 -221.050771)
			(xy 118.847108 -221.024196) (xy 118.854728 -221.002098) (xy 118.65102 -220.649038) (xy 118.627906 -220.64472)
			(xy 118.60297 -220.63956) (xy 118.554947 -220.62263) (xy 118.510088 -220.598536) (xy 118.469455 -220.567848)
			(xy 118.434009 -220.531292) (xy 118.404589 -220.489732) (xy 118.381889 -220.444152) (xy 118.366449 -220.39563)
			(xy 118.358632 -220.345314) (xy 118.358158 -220.319854) (xy 118.07952 -220.319854) (xy 118.079011 -220.345821)
			(xy 118.070886 -220.397116) (xy 118.054838 -220.446509) (xy 118.03126 -220.492783) (xy 118.000734 -220.534799)
			(xy 117.964011 -220.571522) (xy 117.921995 -220.602048) (xy 117.875721 -220.625626) (xy 117.826328 -220.641674)
			(xy 117.775033 -220.649799) (xy 117.723099 -220.649799) (xy 117.671804 -220.641674) (xy 117.622411 -220.625626)
			(xy 117.576137 -220.602048) (xy 117.534121 -220.571522) (xy 117.497398 -220.534799) (xy 117.466872 -220.492783)
			(xy 117.443294 -220.446509) (xy 117.427246 -220.397116) (xy 117.419121 -220.345821) (xy 117.138969 -220.345821)
			(xy 117.138932 -220.347764) (xy 117.129604 -220.402797) (xy 117.120924 -220.429328) (xy 117.11305 -220.451172)
			(xy 117.317266 -220.80474) (xy 117.340126 -220.809058) (xy 117.365044 -220.814243) (xy 117.413027 -220.831206)
			(xy 117.457845 -220.85532) (xy 117.498438 -220.886018) (xy 117.533847 -220.922574) (xy 117.563236 -220.964124)
			(xy 117.585911 -221.009687) (xy 117.601335 -221.058187) (xy 117.609146 -221.108477) (xy 117.60962 -221.133924)
			(xy 117.609111 -221.159891) (xy 117.600986 -221.211186) (xy 117.584938 -221.260579) (xy 117.56136 -221.306853)
			(xy 117.530834 -221.348869) (xy 117.494111 -221.385592) (xy 117.452095 -221.416118) (xy 117.405821 -221.439696)
			(xy 117.356428 -221.455744) (xy 117.305133 -221.463869) (xy 117.253199 -221.463869) (xy 117.201904 -221.455744)
			(xy 117.152511 -221.439696) (xy 117.106237 -221.416118) (xy 117.064221 -221.385592) (xy 117.027498 -221.348869)
			(xy 116.996972 -221.306853) (xy 116.973394 -221.260579) (xy 116.957346 -221.211186) (xy 116.949221 -221.159891)
			(xy 116.948712 -221.133924) (xy 116.94927 -221.105938) (xy 116.958716 -221.050771) (xy 116.967508 -221.024196)
			(xy 116.975128 -221.002098) (xy 116.77142 -220.649038) (xy 116.748306 -220.64472) (xy 116.72337 -220.63956)
			(xy 116.675347 -220.62263) (xy 116.630488 -220.598536) (xy 116.589855 -220.567848) (xy 116.554409 -220.531292)
			(xy 116.524989 -220.489732) (xy 116.502289 -220.444152) (xy 116.486849 -220.39563) (xy 116.479032 -220.345314)
			(xy 116.478558 -220.319854) (xy 116.19992 -220.319854) (xy 116.199411 -220.345821) (xy 116.191286 -220.397116)
			(xy 116.175238 -220.446509) (xy 116.15166 -220.492783) (xy 116.121134 -220.534799) (xy 116.084411 -220.571522)
			(xy 116.042395 -220.602048) (xy 115.996121 -220.625626) (xy 115.946728 -220.641674) (xy 115.895433 -220.649799)
			(xy 115.843499 -220.649799) (xy 115.792204 -220.641674) (xy 115.742811 -220.625626) (xy 115.696537 -220.602048)
			(xy 115.654521 -220.571522) (xy 115.617798 -220.534799) (xy 115.587272 -220.492783) (xy 115.563694 -220.446509)
			(xy 115.547646 -220.397116) (xy 115.539521 -220.345821) (xy 115.259369 -220.345821) (xy 115.259332 -220.347764)
			(xy 115.250004 -220.402797) (xy 115.241324 -220.429328) (xy 115.23345 -220.451172) (xy 115.437666 -220.80474)
			(xy 115.460526 -220.809058) (xy 115.485444 -220.814243) (xy 115.533427 -220.831206) (xy 115.578245 -220.85532)
			(xy 115.618838 -220.886018) (xy 115.654247 -220.922574) (xy 115.683636 -220.964124) (xy 115.706311 -221.009687)
			(xy 115.721735 -221.058187) (xy 115.729546 -221.108477) (xy 115.73002 -221.133924) (xy 115.729511 -221.159891)
			(xy 115.721386 -221.211186) (xy 115.705338 -221.260579) (xy 115.68176 -221.306853) (xy 115.651234 -221.348869)
			(xy 115.614511 -221.385592) (xy 115.572495 -221.416118) (xy 115.526221 -221.439696) (xy 115.476828 -221.455744)
			(xy 115.425533 -221.463869) (xy 115.373599 -221.463869) (xy 115.322304 -221.455744) (xy 115.272911 -221.439696)
			(xy 115.226637 -221.416118) (xy 115.184621 -221.385592) (xy 115.147898 -221.348869) (xy 115.117372 -221.306853)
			(xy 115.093794 -221.260579) (xy 115.077746 -221.211186) (xy 115.069621 -221.159891) (xy 115.069112 -221.133924)
			(xy 115.06967 -221.105938) (xy 115.079116 -221.050771) (xy 115.087908 -221.024196) (xy 115.095528 -221.002098)
			(xy 114.89182 -220.649038) (xy 114.868706 -220.64472) (xy 114.84377 -220.63956) (xy 114.795747 -220.62263)
			(xy 114.750888 -220.598536) (xy 114.710255 -220.567848) (xy 114.674809 -220.531292) (xy 114.645389 -220.489732)
			(xy 114.622689 -220.444152) (xy 114.607249 -220.39563) (xy 114.599432 -220.345314) (xy 114.598958 -220.319854)
			(xy 114.32032 -220.319854) (xy 114.319811 -220.345821) (xy 114.311686 -220.397116) (xy 114.295638 -220.446509)
			(xy 114.27206 -220.492783) (xy 114.241534 -220.534799) (xy 114.204811 -220.571522) (xy 114.162795 -220.602048)
			(xy 114.116521 -220.625626) (xy 114.067128 -220.641674) (xy 114.015833 -220.649799) (xy 113.963899 -220.649799)
			(xy 113.912604 -220.641674) (xy 113.863211 -220.625626) (xy 113.816937 -220.602048) (xy 113.774921 -220.571522)
			(xy 113.738198 -220.534799) (xy 113.707672 -220.492783) (xy 113.684094 -220.446509) (xy 113.668046 -220.397116)
			(xy 113.659921 -220.345821) (xy 113.379769 -220.345821) (xy 113.379732 -220.347764) (xy 113.370404 -220.402797)
			(xy 113.361724 -220.429328) (xy 113.35385 -220.451172) (xy 113.558066 -220.80474) (xy 113.580926 -220.809058)
			(xy 113.605844 -220.814243) (xy 113.653827 -220.831206) (xy 113.698645 -220.85532) (xy 113.739238 -220.886018)
			(xy 113.774647 -220.922574) (xy 113.804036 -220.964124) (xy 113.826711 -221.009687) (xy 113.842135 -221.058187)
			(xy 113.849946 -221.108477) (xy 113.85042 -221.133924) (xy 113.849911 -221.159891) (xy 113.841786 -221.211186)
			(xy 113.825738 -221.260579) (xy 113.80216 -221.306853) (xy 113.771634 -221.348869) (xy 113.734911 -221.385592)
			(xy 113.692895 -221.416118) (xy 113.646621 -221.439696) (xy 113.597228 -221.455744) (xy 113.545933 -221.463869)
			(xy 113.493999 -221.463869) (xy 113.442704 -221.455744) (xy 113.393311 -221.439696) (xy 113.347037 -221.416118)
			(xy 113.305021 -221.385592) (xy 113.268298 -221.348869) (xy 113.237772 -221.306853) (xy 113.214194 -221.260579)
			(xy 113.198146 -221.211186) (xy 113.190021 -221.159891) (xy 113.189512 -221.133924) (xy 113.19007 -221.105938)
			(xy 113.199516 -221.050771) (xy 113.208308 -221.024196) (xy 113.215928 -221.002098) (xy 113.01222 -220.649038)
			(xy 112.989106 -220.64472) (xy 112.96417 -220.63956) (xy 112.916147 -220.62263) (xy 112.871288 -220.598536)
			(xy 112.830655 -220.567848) (xy 112.795209 -220.531292) (xy 112.765789 -220.489732) (xy 112.743089 -220.444152)
			(xy 112.727649 -220.39563) (xy 112.719832 -220.345314) (xy 112.719358 -220.319854) (xy 112.44072 -220.319854)
			(xy 112.440211 -220.345821) (xy 112.432086 -220.397116) (xy 112.416038 -220.446509) (xy 112.39246 -220.492783)
			(xy 112.361934 -220.534799) (xy 112.325211 -220.571522) (xy 112.283195 -220.602048) (xy 112.236921 -220.625626)
			(xy 112.187528 -220.641674) (xy 112.136233 -220.649799) (xy 112.084299 -220.649799) (xy 112.033004 -220.641674)
			(xy 111.983611 -220.625626) (xy 111.937337 -220.602048) (xy 111.895321 -220.571522) (xy 111.858598 -220.534799)
			(xy 111.828072 -220.492783) (xy 111.804494 -220.446509) (xy 111.788446 -220.397116) (xy 111.780321 -220.345821)
			(xy 111.587026 -220.345821) (xy 111.587026 -220.646498) (xy 111.678466 -220.80474) (xy 111.701326 -220.809058)
			(xy 111.726259 -220.814206) (xy 111.774268 -220.831143) (xy 111.81911 -220.855244) (xy 111.859725 -220.885938)
			(xy 111.895151 -220.922499) (xy 111.924549 -220.964061) (xy 111.947224 -221.009641) (xy 111.962639 -221.05816)
			(xy 111.970429 -221.108469) (xy 111.97082 -221.133924) (xy 111.970335 -221.159891) (xy 111.962207 -221.211185)
			(xy 111.946155 -221.260576) (xy 111.922573 -221.306848) (xy 111.892044 -221.348861) (xy 111.855317 -221.385581)
			(xy 111.813299 -221.416104) (xy 111.767023 -221.439677) (xy 111.717629 -221.455721) (xy 111.666333 -221.46384)
			(xy 111.640366 -221.464378) (xy 111.63808 -221.464378) (xy 111.62802 -221.464749) (xy 111.609403 -221.472368)
			(xy 111.595137 -221.486549) (xy 111.587408 -221.50512) (xy 111.587026 -221.515178) (xy 111.587026 -221.94774)
			(xy 111.779558 -221.94774) (xy 111.779981 -221.922287) (xy 111.787768 -221.87198) (xy 111.80318 -221.823463)
			(xy 111.825851 -221.777884) (xy 111.855245 -221.736322) (xy 111.890667 -221.699761) (xy 111.931278 -221.669066)
			(xy 111.976116 -221.644963) (xy 112.024121 -221.628023) (xy 112.049052 -221.622874) (xy 112.071912 -221.618556)
			(xy 112.275874 -221.264988) (xy 112.268254 -221.243144) (xy 112.259621 -221.216666) (xy 112.250293 -221.161767)
			(xy 112.249712 -221.133924) (xy 112.250221 -221.107957) (xy 112.258346 -221.056662) (xy 112.274394 -221.007269)
			(xy 112.297972 -220.960995) (xy 112.328498 -220.918979) (xy 112.365221 -220.882256) (xy 112.407237 -220.85173)
			(xy 112.453511 -220.828152) (xy 112.502904 -220.812104) (xy 112.554199 -220.803979) (xy 112.606133 -220.803979)
			(xy 112.657428 -220.812104) (xy 112.706821 -220.828152) (xy 112.753095 -220.85173) (xy 112.795111 -220.882256)
			(xy 112.831834 -220.918979) (xy 112.86236 -220.960995) (xy 112.885938 -221.007269) (xy 112.901986 -221.056662)
			(xy 112.910111 -221.107957) (xy 112.91062 -221.133924) (xy 112.910187 -221.159399) (xy 112.902363 -221.209746)
			(xy 112.886905 -221.258295) (xy 112.864178 -221.303896) (xy 112.834721 -221.345468) (xy 112.799232 -221.382027)
			(xy 112.758553 -221.412705) (xy 112.713646 -221.436776) (xy 112.665578 -221.453669) (xy 112.640618 -221.45879)
			(xy 112.617504 -221.463108) (xy 112.41405 -221.815914) (xy 112.42167 -221.838012) (xy 112.43041 -221.8646)
			(xy 112.439856 -221.919759) (xy 112.440466 -221.94774) (xy 112.439957 -221.973707) (xy 112.719867 -221.973707)
			(xy 112.719867 -221.921773) (xy 112.727992 -221.870478) (xy 112.74404 -221.821085) (xy 112.767618 -221.774811)
			(xy 112.798144 -221.732795) (xy 112.834867 -221.696072) (xy 112.876883 -221.665546) (xy 112.923157 -221.641968)
			(xy 112.97255 -221.62592) (xy 113.023845 -221.617795) (xy 113.075779 -221.617795) (xy 113.127074 -221.62592)
			(xy 113.176467 -221.641968) (xy 113.222741 -221.665546) (xy 113.264757 -221.696072) (xy 113.30148 -221.732795)
			(xy 113.332006 -221.774811) (xy 113.355584 -221.821085) (xy 113.371632 -221.870478) (xy 113.379757 -221.921773)
			(xy 113.380266 -221.94774) (xy 113.659412 -221.94774) (xy 113.659872 -221.922289) (xy 113.667658 -221.871985)
			(xy 113.683067 -221.823471) (xy 113.705735 -221.777895) (xy 113.735124 -221.736334) (xy 113.770541 -221.699773)
			(xy 113.811146 -221.669076) (xy 113.855978 -221.64497) (xy 113.903977 -221.628026) (xy 113.928906 -221.622874)
			(xy 113.951766 -221.618556) (xy 114.155728 -221.265242) (xy 114.147854 -221.243398) (xy 114.139191 -221.216863)
			(xy 114.129872 -221.161832) (xy 114.129312 -221.133924) (xy 114.129821 -221.107957) (xy 114.137946 -221.056662)
			(xy 114.153994 -221.007269) (xy 114.177572 -220.960995) (xy 114.208098 -220.918979) (xy 114.244821 -220.882256)
			(xy 114.286837 -220.85173) (xy 114.333111 -220.828152) (xy 114.382504 -220.812104) (xy 114.433799 -220.803979)
			(xy 114.485733 -220.803979) (xy 114.537028 -220.812104) (xy 114.586421 -220.828152) (xy 114.632695 -220.85173)
			(xy 114.674711 -220.882256) (xy 114.711434 -220.918979) (xy 114.74196 -220.960995) (xy 114.765538 -221.007269)
			(xy 114.781586 -221.056662) (xy 114.789711 -221.107957) (xy 114.79022 -221.133924) (xy 114.789744 -221.159386)
			(xy 114.781942 -221.209709) (xy 114.766512 -221.258239) (xy 114.743818 -221.303827) (xy 114.714399 -221.345393)
			(xy 114.67895 -221.381953) (xy 114.638311 -221.412642) (xy 114.593446 -221.436732) (xy 114.545415 -221.453652)
			(xy 114.520472 -221.45879) (xy 114.497358 -221.463108) (xy 114.293904 -221.815914) (xy 114.301524 -221.838012)
			(xy 114.310265 -221.864599) (xy 114.31971 -221.919759) (xy 114.32032 -221.94774) (xy 114.319811 -221.973707)
			(xy 114.599721 -221.973707) (xy 114.599721 -221.921773) (xy 114.607846 -221.870478) (xy 114.623894 -221.821085)
			(xy 114.647472 -221.774811) (xy 114.677998 -221.732795) (xy 114.714721 -221.696072) (xy 114.756737 -221.665546)
			(xy 114.803011 -221.641968) (xy 114.852404 -221.62592) (xy 114.903699 -221.617795) (xy 114.955633 -221.617795)
			(xy 115.006928 -221.62592) (xy 115.056321 -221.641968) (xy 115.102595 -221.665546) (xy 115.144611 -221.696072)
			(xy 115.181334 -221.732795) (xy 115.21186 -221.774811) (xy 115.235438 -221.821085) (xy 115.251486 -221.870478)
			(xy 115.259611 -221.921773) (xy 115.26012 -221.94774) (xy 115.538758 -221.94774) (xy 115.539181 -221.922287)
			(xy 115.546968 -221.87198) (xy 115.56238 -221.823463) (xy 115.585051 -221.777884) (xy 115.614445 -221.736322)
			(xy 115.649867 -221.699761) (xy 115.690478 -221.669066) (xy 115.735316 -221.644963) (xy 115.783321 -221.628023)
			(xy 115.808252 -221.622874) (xy 115.831112 -221.618556) (xy 116.035074 -221.264988) (xy 116.027454 -221.243144)
			(xy 116.018821 -221.216666) (xy 116.009493 -221.161767) (xy 116.008912 -221.133924) (xy 116.009421 -221.107957)
			(xy 116.017546 -221.056662) (xy 116.033594 -221.007269) (xy 116.057172 -220.960995) (xy 116.087698 -220.918979)
			(xy 116.124421 -220.882256) (xy 116.166437 -220.85173) (xy 116.212711 -220.828152) (xy 116.262104 -220.812104)
			(xy 116.313399 -220.803979) (xy 116.365333 -220.803979) (xy 116.416628 -220.812104) (xy 116.466021 -220.828152)
			(xy 116.512295 -220.85173) (xy 116.554311 -220.882256) (xy 116.591034 -220.918979) (xy 116.62156 -220.960995)
			(xy 116.645138 -221.007269) (xy 116.661186 -221.056662) (xy 116.669311 -221.107957) (xy 116.66982 -221.133924)
			(xy 116.669387 -221.159399) (xy 116.661563 -221.209746) (xy 116.646105 -221.258295) (xy 116.623378 -221.303896)
			(xy 116.593921 -221.345468) (xy 116.558432 -221.382027) (xy 116.517753 -221.412705) (xy 116.472846 -221.436776)
			(xy 116.424778 -221.453669) (xy 116.399818 -221.45879) (xy 116.376704 -221.463108) (xy 116.17325 -221.815914)
			(xy 116.18087 -221.838012) (xy 116.18961 -221.8646) (xy 116.199056 -221.919759) (xy 116.199666 -221.94774)
			(xy 117.418358 -221.94774) (xy 117.418781 -221.922287) (xy 117.426568 -221.87198) (xy 117.44198 -221.823463)
			(xy 117.464651 -221.777884) (xy 117.494045 -221.736322) (xy 117.529467 -221.699761) (xy 117.570078 -221.669066)
			(xy 117.614916 -221.644963) (xy 117.662921 -221.628023) (xy 117.687852 -221.622874) (xy 117.710712 -221.618556)
			(xy 117.914674 -221.264988) (xy 117.907054 -221.243144) (xy 117.898421 -221.216666) (xy 117.889093 -221.161767)
			(xy 117.888512 -221.133924) (xy 117.889021 -221.107957) (xy 117.897146 -221.056662) (xy 117.913194 -221.007269)
			(xy 117.936772 -220.960995) (xy 117.967298 -220.918979) (xy 118.004021 -220.882256) (xy 118.046037 -220.85173)
			(xy 118.092311 -220.828152) (xy 118.141704 -220.812104) (xy 118.192999 -220.803979) (xy 118.244933 -220.803979)
			(xy 118.296228 -220.812104) (xy 118.345621 -220.828152) (xy 118.391895 -220.85173) (xy 118.433911 -220.882256)
			(xy 118.470634 -220.918979) (xy 118.50116 -220.960995) (xy 118.524738 -221.007269) (xy 118.540786 -221.056662)
			(xy 118.548911 -221.107957) (xy 118.54942 -221.133924) (xy 118.548987 -221.159399) (xy 118.541163 -221.209746)
			(xy 118.525705 -221.258295) (xy 118.502978 -221.303896) (xy 118.473521 -221.345468) (xy 118.438032 -221.382027)
			(xy 118.397353 -221.412705) (xy 118.352446 -221.436776) (xy 118.304378 -221.453669) (xy 118.279418 -221.45879)
			(xy 118.256304 -221.463108) (xy 118.05285 -221.815914) (xy 118.06047 -221.838012) (xy 118.06921 -221.8646)
			(xy 118.078656 -221.919759) (xy 118.079266 -221.94774) (xy 118.078757 -221.973707) (xy 119.298721 -221.973707)
			(xy 119.298721 -221.921773) (xy 119.306846 -221.870478) (xy 119.322894 -221.821085) (xy 119.346472 -221.774811)
			(xy 119.376998 -221.732795) (xy 119.413721 -221.696072) (xy 119.455737 -221.665546) (xy 119.502011 -221.641968)
			(xy 119.551404 -221.62592) (xy 119.602699 -221.617795) (xy 119.654633 -221.617795) (xy 119.705928 -221.62592)
			(xy 119.755321 -221.641968) (xy 119.801595 -221.665546) (xy 119.843611 -221.696072) (xy 119.880334 -221.732795)
			(xy 119.91086 -221.774811) (xy 119.934438 -221.821085) (xy 119.950486 -221.870478) (xy 119.958611 -221.921773)
			(xy 119.95912 -221.94774) (xy 121.177558 -221.94774) (xy 121.177981 -221.922287) (xy 121.185768 -221.87198)
			(xy 121.20118 -221.823463) (xy 121.223851 -221.777884) (xy 121.253245 -221.736322) (xy 121.288667 -221.699761)
			(xy 121.329278 -221.669066) (xy 121.374116 -221.644963) (xy 121.422121 -221.628023) (xy 121.447052 -221.622874)
			(xy 121.469912 -221.618556) (xy 121.673874 -221.264988) (xy 121.666254 -221.243144) (xy 121.657621 -221.216666)
			(xy 121.648293 -221.161767) (xy 121.647712 -221.133924) (xy 121.648221 -221.107957) (xy 121.656346 -221.056662)
			(xy 121.672394 -221.007269) (xy 121.695972 -220.960995) (xy 121.726498 -220.918979) (xy 121.763221 -220.882256)
			(xy 121.805237 -220.85173) (xy 121.851511 -220.828152) (xy 121.900904 -220.812104) (xy 121.952199 -220.803979)
			(xy 122.004133 -220.803979) (xy 122.055428 -220.812104) (xy 122.104821 -220.828152) (xy 122.151095 -220.85173)
			(xy 122.193111 -220.882256) (xy 122.229834 -220.918979) (xy 122.26036 -220.960995) (xy 122.283938 -221.007269)
			(xy 122.299986 -221.056662) (xy 122.308111 -221.107957) (xy 122.30862 -221.133924) (xy 122.308187 -221.159399)
			(xy 122.300363 -221.209746) (xy 122.284905 -221.258295) (xy 122.262178 -221.303896) (xy 122.232721 -221.345468)
			(xy 122.197232 -221.382027) (xy 122.156553 -221.412705) (xy 122.111646 -221.436776) (xy 122.063578 -221.453669)
			(xy 122.038618 -221.45879) (xy 122.015504 -221.463108) (xy 121.81205 -221.815914) (xy 121.81967 -221.838012)
			(xy 121.82841 -221.8646) (xy 121.837856 -221.919759) (xy 121.838466 -221.94774) (xy 123.057158 -221.94774)
			(xy 123.057581 -221.922287) (xy 123.065368 -221.87198) (xy 123.08078 -221.823463) (xy 123.103451 -221.777884)
			(xy 123.132845 -221.736322) (xy 123.168267 -221.699761) (xy 123.208878 -221.669066) (xy 123.253716 -221.644963)
			(xy 123.301721 -221.628023) (xy 123.326652 -221.622874) (xy 123.349512 -221.618556) (xy 123.553474 -221.264988)
			(xy 123.545854 -221.243144) (xy 123.537221 -221.216666) (xy 123.527893 -221.161767) (xy 123.527312 -221.133924)
			(xy 123.527821 -221.107957) (xy 123.535946 -221.056662) (xy 123.551994 -221.007269) (xy 123.575572 -220.960995)
			(xy 123.606098 -220.918979) (xy 123.642821 -220.882256) (xy 123.684837 -220.85173) (xy 123.731111 -220.828152)
			(xy 123.780504 -220.812104) (xy 123.831799 -220.803979) (xy 123.883733 -220.803979) (xy 123.935028 -220.812104)
			(xy 123.984421 -220.828152) (xy 124.030695 -220.85173) (xy 124.072711 -220.882256) (xy 124.109434 -220.918979)
			(xy 124.13996 -220.960995) (xy 124.163538 -221.007269) (xy 124.179586 -221.056662) (xy 124.187711 -221.107957)
			(xy 124.18822 -221.133924) (xy 124.187787 -221.159399) (xy 124.179963 -221.209746) (xy 124.164505 -221.258295)
			(xy 124.141778 -221.303896) (xy 124.112321 -221.345468) (xy 124.076832 -221.382027) (xy 124.036153 -221.412705)
			(xy 123.991246 -221.436776) (xy 123.943178 -221.453669) (xy 123.918218 -221.45879) (xy 123.895104 -221.463108)
			(xy 123.69165 -221.815914) (xy 123.69927 -221.838012) (xy 123.70801 -221.8646) (xy 123.717456 -221.919759)
			(xy 123.718066 -221.94774) (xy 124.936758 -221.94774) (xy 124.937181 -221.922287) (xy 124.944968 -221.87198)
			(xy 124.96038 -221.823463) (xy 124.983051 -221.777884) (xy 125.012445 -221.736322) (xy 125.047867 -221.699761)
			(xy 125.088478 -221.669066) (xy 125.133316 -221.644963) (xy 125.181321 -221.628023) (xy 125.206252 -221.622874)
			(xy 125.229112 -221.618556) (xy 125.433074 -221.264988) (xy 125.425454 -221.243144) (xy 125.416821 -221.216666)
			(xy 125.407493 -221.161767) (xy 125.406912 -221.133924) (xy 125.407421 -221.107957) (xy 125.415546 -221.056662)
			(xy 125.431594 -221.007269) (xy 125.455172 -220.960995) (xy 125.485698 -220.918979) (xy 125.522421 -220.882256)
			(xy 125.564437 -220.85173) (xy 125.610711 -220.828152) (xy 125.660104 -220.812104) (xy 125.711399 -220.803979)
			(xy 125.763333 -220.803979) (xy 125.814628 -220.812104) (xy 125.864021 -220.828152) (xy 125.910295 -220.85173)
			(xy 125.952311 -220.882256) (xy 125.989034 -220.918979) (xy 126.01956 -220.960995) (xy 126.043138 -221.007269)
			(xy 126.059186 -221.056662) (xy 126.067311 -221.107957) (xy 126.06782 -221.133924) (xy 126.067387 -221.159399)
			(xy 126.059563 -221.209746) (xy 126.044105 -221.258295) (xy 126.021378 -221.303896) (xy 125.991921 -221.345468)
			(xy 125.956432 -221.382027) (xy 125.915753 -221.412705) (xy 125.870846 -221.436776) (xy 125.822778 -221.453669)
			(xy 125.797818 -221.45879) (xy 125.774704 -221.463108) (xy 125.57125 -221.815914) (xy 125.57887 -221.838012)
			(xy 125.58761 -221.8646) (xy 125.597056 -221.919759) (xy 125.597666 -221.94774) (xy 126.816358 -221.94774)
			(xy 126.816781 -221.922287) (xy 126.824568 -221.87198) (xy 126.83998 -221.823463) (xy 126.862651 -221.777884)
			(xy 126.892045 -221.736322) (xy 126.927467 -221.699761) (xy 126.968078 -221.669066) (xy 127.012916 -221.644963)
			(xy 127.060921 -221.628023) (xy 127.085852 -221.622874) (xy 127.108712 -221.618556) (xy 127.312674 -221.264988)
			(xy 127.305054 -221.243144) (xy 127.296421 -221.216666) (xy 127.287093 -221.161767) (xy 127.286512 -221.133924)
			(xy 127.287021 -221.107957) (xy 127.295146 -221.056662) (xy 127.311194 -221.007269) (xy 127.334772 -220.960995)
			(xy 127.365298 -220.918979) (xy 127.402021 -220.882256) (xy 127.444037 -220.85173) (xy 127.490311 -220.828152)
			(xy 127.539704 -220.812104) (xy 127.590999 -220.803979) (xy 127.642933 -220.803979) (xy 127.694228 -220.812104)
			(xy 127.743621 -220.828152) (xy 127.789895 -220.85173) (xy 127.831911 -220.882256) (xy 127.868634 -220.918979)
			(xy 127.89916 -220.960995) (xy 127.922738 -221.007269) (xy 127.938786 -221.056662) (xy 127.946911 -221.107957)
			(xy 127.94742 -221.133924) (xy 127.946987 -221.159399) (xy 127.939163 -221.209746) (xy 127.923705 -221.258295)
			(xy 127.900978 -221.303896) (xy 127.871521 -221.345468) (xy 127.836032 -221.382027) (xy 127.795353 -221.412705)
			(xy 127.750446 -221.436776) (xy 127.702378 -221.453669) (xy 127.677418 -221.45879) (xy 127.654304 -221.463108)
			(xy 127.45085 -221.815914) (xy 127.45847 -221.838012) (xy 127.46721 -221.8646) (xy 127.476656 -221.919759)
			(xy 127.477266 -221.94774) (xy 127.476757 -221.973707) (xy 127.756667 -221.973707) (xy 127.756667 -221.921773)
			(xy 127.764792 -221.870478) (xy 127.78084 -221.821085) (xy 127.804418 -221.774811) (xy 127.834944 -221.732795)
			(xy 127.871667 -221.696072) (xy 127.913683 -221.665546) (xy 127.959957 -221.641968) (xy 128.00935 -221.62592)
			(xy 128.060645 -221.617795) (xy 128.112579 -221.617795) (xy 128.163874 -221.62592) (xy 128.213267 -221.641968)
			(xy 128.259541 -221.665546) (xy 128.301557 -221.696072) (xy 128.33828 -221.732795) (xy 128.368806 -221.774811)
			(xy 128.392384 -221.821085) (xy 128.408432 -221.870478) (xy 128.416557 -221.921773) (xy 128.417066 -221.94774)
			(xy 128.695958 -221.94774) (xy 128.696381 -221.922287) (xy 128.704168 -221.87198) (xy 128.71958 -221.823463)
			(xy 128.742251 -221.777884) (xy 128.771645 -221.736322) (xy 128.807067 -221.699761) (xy 128.847678 -221.669066)
			(xy 128.892516 -221.644963) (xy 128.940521 -221.628023) (xy 128.965452 -221.622874) (xy 128.988312 -221.618556)
			(xy 129.192274 -221.264988) (xy 129.184654 -221.243144) (xy 129.176021 -221.216666) (xy 129.166693 -221.161767)
			(xy 129.166112 -221.133924) (xy 129.166621 -221.107957) (xy 129.174746 -221.056662) (xy 129.190794 -221.007269)
			(xy 129.214372 -220.960995) (xy 129.244898 -220.918979) (xy 129.281621 -220.882256) (xy 129.323637 -220.85173)
			(xy 129.369911 -220.828152) (xy 129.419304 -220.812104) (xy 129.470599 -220.803979) (xy 129.522533 -220.803979)
			(xy 129.573828 -220.812104) (xy 129.623221 -220.828152) (xy 129.669495 -220.85173) (xy 129.711511 -220.882256)
			(xy 129.748234 -220.918979) (xy 129.77876 -220.960995) (xy 129.802338 -221.007269) (xy 129.818386 -221.056662)
			(xy 129.826511 -221.107957) (xy 129.82702 -221.133924) (xy 129.826587 -221.159399) (xy 129.818763 -221.209746)
			(xy 129.803305 -221.258295) (xy 129.780578 -221.303896) (xy 129.751121 -221.345468) (xy 129.715632 -221.382027)
			(xy 129.674953 -221.412705) (xy 129.630046 -221.436776) (xy 129.581978 -221.453669) (xy 129.557018 -221.45879)
			(xy 129.533904 -221.463108) (xy 129.33045 -221.815914) (xy 129.33807 -221.838012) (xy 129.34681 -221.8646)
			(xy 129.356256 -221.919759) (xy 129.356866 -221.94774) (xy 129.356357 -221.973707) (xy 129.636267 -221.973707)
			(xy 129.636267 -221.921773) (xy 129.644392 -221.870478) (xy 129.66044 -221.821085) (xy 129.684018 -221.774811)
			(xy 129.714544 -221.732795) (xy 129.751267 -221.696072) (xy 129.793283 -221.665546) (xy 129.839557 -221.641968)
			(xy 129.88895 -221.62592) (xy 129.940245 -221.617795) (xy 129.992179 -221.617795) (xy 130.043474 -221.62592)
			(xy 130.092867 -221.641968) (xy 130.139141 -221.665546) (xy 130.181157 -221.696072) (xy 130.21788 -221.732795)
			(xy 130.248406 -221.774811) (xy 130.271984 -221.821085) (xy 130.288032 -221.870478) (xy 130.296157 -221.921773)
			(xy 130.296666 -221.94774) (xy 130.575558 -221.94774) (xy 130.575981 -221.922287) (xy 130.583768 -221.87198)
			(xy 130.59918 -221.823463) (xy 130.621851 -221.777884) (xy 130.651245 -221.736322) (xy 130.686667 -221.699761)
			(xy 130.727278 -221.669066) (xy 130.772116 -221.644963) (xy 130.820121 -221.628023) (xy 130.845052 -221.622874)
			(xy 130.867912 -221.618556) (xy 131.071874 -221.264988) (xy 131.064254 -221.243144) (xy 131.055621 -221.216666)
			(xy 131.046293 -221.161767) (xy 131.045712 -221.133924) (xy 131.046221 -221.107957) (xy 131.054346 -221.056662)
			(xy 131.070394 -221.007269) (xy 131.093972 -220.960995) (xy 131.124498 -220.918979) (xy 131.161221 -220.882256)
			(xy 131.203237 -220.85173) (xy 131.249511 -220.828152) (xy 131.298904 -220.812104) (xy 131.350199 -220.803979)
			(xy 131.402133 -220.803979) (xy 131.453428 -220.812104) (xy 131.502821 -220.828152) (xy 131.549095 -220.85173)
			(xy 131.591111 -220.882256) (xy 131.627834 -220.918979) (xy 131.65836 -220.960995) (xy 131.681938 -221.007269)
			(xy 131.697986 -221.056662) (xy 131.706111 -221.107957) (xy 131.70662 -221.133924) (xy 131.706187 -221.159399)
			(xy 131.698363 -221.209746) (xy 131.682905 -221.258295) (xy 131.660178 -221.303896) (xy 131.630721 -221.345468)
			(xy 131.595232 -221.382027) (xy 131.554553 -221.412705) (xy 131.509646 -221.436776) (xy 131.461578 -221.453669)
			(xy 131.436618 -221.45879) (xy 131.413504 -221.463108) (xy 131.21005 -221.815914) (xy 131.21767 -221.838012)
			(xy 131.22641 -221.8646) (xy 131.235856 -221.919759) (xy 131.236466 -221.94774) (xy 131.235957 -221.973707)
			(xy 131.515867 -221.973707) (xy 131.515867 -221.921773) (xy 131.523992 -221.870478) (xy 131.54004 -221.821085)
			(xy 131.563618 -221.774811) (xy 131.594144 -221.732795) (xy 131.630867 -221.696072) (xy 131.672883 -221.665546)
			(xy 131.719157 -221.641968) (xy 131.76855 -221.62592) (xy 131.819845 -221.617795) (xy 131.871779 -221.617795)
			(xy 131.923074 -221.62592) (xy 131.972467 -221.641968) (xy 132.018741 -221.665546) (xy 132.060757 -221.696072)
			(xy 132.09748 -221.732795) (xy 132.128006 -221.774811) (xy 132.151584 -221.821085) (xy 132.167632 -221.870478)
			(xy 132.175757 -221.921773) (xy 132.176266 -221.94774) (xy 132.455158 -221.94774) (xy 132.455581 -221.922287)
			(xy 132.463368 -221.87198) (xy 132.47878 -221.823463) (xy 132.501451 -221.777884) (xy 132.530845 -221.736322)
			(xy 132.566267 -221.699761) (xy 132.606878 -221.669066) (xy 132.651716 -221.644963) (xy 132.699721 -221.628023)
			(xy 132.724652 -221.622874) (xy 132.747766 -221.618556) (xy 132.951474 -221.264988) (xy 132.943854 -221.24289)
			(xy 132.935224 -221.216478) (xy 132.925905 -221.161704) (xy 132.925312 -221.133924) (xy 132.925821 -221.107957)
			(xy 132.933946 -221.056662) (xy 132.949994 -221.007269) (xy 132.973572 -220.960995) (xy 133.004098 -220.918979)
			(xy 133.040821 -220.882256) (xy 133.082837 -220.85173) (xy 133.129111 -220.828152) (xy 133.178504 -220.812104)
			(xy 133.229799 -220.803979) (xy 133.281733 -220.803979) (xy 133.333028 -220.812104) (xy 133.382421 -220.828152)
			(xy 133.428695 -220.85173) (xy 133.470711 -220.882256) (xy 133.507434 -220.918979) (xy 133.53796 -220.960995)
			(xy 133.561538 -221.007269) (xy 133.577586 -221.056662) (xy 133.585711 -221.107957) (xy 133.58622 -221.133924)
			(xy 133.585787 -221.159399) (xy 133.577963 -221.209746) (xy 133.562505 -221.258295) (xy 133.539778 -221.303896)
			(xy 133.510321 -221.345468) (xy 133.474832 -221.382027) (xy 133.434153 -221.412705) (xy 133.389246 -221.436776)
			(xy 133.341178 -221.453669) (xy 133.316218 -221.45879) (xy 133.293104 -221.463108) (xy 133.08965 -221.815914)
			(xy 133.09727 -221.838012) (xy 133.10601 -221.8646) (xy 133.115456 -221.919759) (xy 133.116066 -221.94774)
			(xy 133.115557 -221.973707) (xy 133.395721 -221.973707) (xy 133.395721 -221.921773) (xy 133.403846 -221.870478)
			(xy 133.419894 -221.821085) (xy 133.443472 -221.774811) (xy 133.473998 -221.732795) (xy 133.510721 -221.696072)
			(xy 133.552737 -221.665546) (xy 133.599011 -221.641968) (xy 133.648404 -221.62592) (xy 133.699699 -221.617795)
			(xy 133.751633 -221.617795) (xy 133.802928 -221.62592) (xy 133.852321 -221.641968) (xy 133.898595 -221.665546)
			(xy 133.940611 -221.696072) (xy 133.977334 -221.732795) (xy 134.00786 -221.774811) (xy 134.031438 -221.821085)
			(xy 134.047486 -221.870478) (xy 134.055611 -221.921773) (xy 134.05612 -221.94774) (xy 134.055611 -221.973707)
			(xy 134.047486 -222.025002) (xy 134.031438 -222.074395) (xy 134.00786 -222.120669) (xy 133.977334 -222.162685)
			(xy 133.940611 -222.199408) (xy 133.898595 -222.229934) (xy 133.852321 -222.253512) (xy 133.802928 -222.26956)
			(xy 133.751633 -222.277685) (xy 133.699699 -222.277685) (xy 133.648404 -222.26956) (xy 133.599011 -222.253512)
			(xy 133.552737 -222.229934) (xy 133.510721 -222.199408) (xy 133.473998 -222.162685) (xy 133.443472 -222.120669)
			(xy 133.419894 -222.074395) (xy 133.403846 -222.025002) (xy 133.395721 -221.973707) (xy 133.115557 -221.973707)
			(xy 133.107432 -222.025002) (xy 133.091384 -222.074395) (xy 133.067806 -222.120669) (xy 133.03728 -222.162685)
			(xy 133.000557 -222.199408) (xy 132.958541 -222.229934) (xy 132.912267 -222.253512) (xy 132.862874 -222.26956)
			(xy 132.811579 -222.277685) (xy 132.759645 -222.277685) (xy 132.70835 -222.26956) (xy 132.658957 -222.253512)
			(xy 132.612683 -222.229934) (xy 132.570667 -222.199408) (xy 132.533944 -222.162685) (xy 132.503418 -222.120669)
			(xy 132.47984 -222.074395) (xy 132.463792 -222.025002) (xy 132.455667 -221.973707) (xy 132.455158 -221.94774)
			(xy 132.176266 -221.94774) (xy 132.175757 -221.973707) (xy 132.167632 -222.025002) (xy 132.151584 -222.074395)
			(xy 132.128006 -222.120669) (xy 132.09748 -222.162685) (xy 132.060757 -222.199408) (xy 132.018741 -222.229934)
			(xy 131.972467 -222.253512) (xy 131.923074 -222.26956) (xy 131.871779 -222.277685) (xy 131.819845 -222.277685)
			(xy 131.76855 -222.26956) (xy 131.719157 -222.253512) (xy 131.672883 -222.229934) (xy 131.630867 -222.199408)
			(xy 131.594144 -222.162685) (xy 131.563618 -222.120669) (xy 131.54004 -222.074395) (xy 131.523992 -222.025002)
			(xy 131.515867 -221.973707) (xy 131.235957 -221.973707) (xy 131.227832 -222.025002) (xy 131.211784 -222.074395)
			(xy 131.188206 -222.120669) (xy 131.15768 -222.162685) (xy 131.120957 -222.199408) (xy 131.078941 -222.229934)
			(xy 131.032667 -222.253512) (xy 130.983274 -222.26956) (xy 130.931979 -222.277685) (xy 130.880045 -222.277685)
			(xy 130.82875 -222.26956) (xy 130.779357 -222.253512) (xy 130.733083 -222.229934) (xy 130.691067 -222.199408)
			(xy 130.654344 -222.162685) (xy 130.623818 -222.120669) (xy 130.60024 -222.074395) (xy 130.584192 -222.025002)
			(xy 130.576067 -221.973707) (xy 130.575558 -221.94774) (xy 130.296666 -221.94774) (xy 130.296157 -221.973707)
			(xy 130.288032 -222.025002) (xy 130.271984 -222.074395) (xy 130.248406 -222.120669) (xy 130.21788 -222.162685)
			(xy 130.181157 -222.199408) (xy 130.139141 -222.229934) (xy 130.092867 -222.253512) (xy 130.043474 -222.26956)
			(xy 129.992179 -222.277685) (xy 129.940245 -222.277685) (xy 129.88895 -222.26956) (xy 129.839557 -222.253512)
			(xy 129.793283 -222.229934) (xy 129.751267 -222.199408) (xy 129.714544 -222.162685) (xy 129.684018 -222.120669)
			(xy 129.66044 -222.074395) (xy 129.644392 -222.025002) (xy 129.636267 -221.973707) (xy 129.356357 -221.973707)
			(xy 129.348232 -222.025002) (xy 129.332184 -222.074395) (xy 129.308606 -222.120669) (xy 129.27808 -222.162685)
			(xy 129.241357 -222.199408) (xy 129.199341 -222.229934) (xy 129.153067 -222.253512) (xy 129.103674 -222.26956)
			(xy 129.052379 -222.277685) (xy 129.000445 -222.277685) (xy 128.94915 -222.26956) (xy 128.899757 -222.253512)
			(xy 128.853483 -222.229934) (xy 128.811467 -222.199408) (xy 128.774744 -222.162685) (xy 128.744218 -222.120669)
			(xy 128.72064 -222.074395) (xy 128.704592 -222.025002) (xy 128.696467 -221.973707) (xy 128.695958 -221.94774)
			(xy 128.417066 -221.94774) (xy 128.416557 -221.973707) (xy 128.408432 -222.025002) (xy 128.392384 -222.074395)
			(xy 128.368806 -222.120669) (xy 128.33828 -222.162685) (xy 128.301557 -222.199408) (xy 128.259541 -222.229934)
			(xy 128.213267 -222.253512) (xy 128.163874 -222.26956) (xy 128.112579 -222.277685) (xy 128.060645 -222.277685)
			(xy 128.00935 -222.26956) (xy 127.959957 -222.253512) (xy 127.913683 -222.229934) (xy 127.871667 -222.199408)
			(xy 127.834944 -222.162685) (xy 127.804418 -222.120669) (xy 127.78084 -222.074395) (xy 127.764792 -222.025002)
			(xy 127.756667 -221.973707) (xy 127.476757 -221.973707) (xy 127.468632 -222.025002) (xy 127.452584 -222.074395)
			(xy 127.429006 -222.120669) (xy 127.39848 -222.162685) (xy 127.361757 -222.199408) (xy 127.319741 -222.229934)
			(xy 127.273467 -222.253512) (xy 127.224074 -222.26956) (xy 127.172779 -222.277685) (xy 127.120845 -222.277685)
			(xy 127.06955 -222.26956) (xy 127.020157 -222.253512) (xy 126.973883 -222.229934) (xy 126.931867 -222.199408)
			(xy 126.895144 -222.162685) (xy 126.864618 -222.120669) (xy 126.84104 -222.074395) (xy 126.824992 -222.025002)
			(xy 126.816867 -221.973707) (xy 126.816358 -221.94774) (xy 125.597666 -221.94774) (xy 125.597157 -221.973707)
			(xy 125.589032 -222.025002) (xy 125.572984 -222.074395) (xy 125.549406 -222.120669) (xy 125.51888 -222.162685)
			(xy 125.482157 -222.199408) (xy 125.440141 -222.229934) (xy 125.393867 -222.253512) (xy 125.344474 -222.26956)
			(xy 125.293179 -222.277685) (xy 125.241245 -222.277685) (xy 125.18995 -222.26956) (xy 125.140557 -222.253512)
			(xy 125.094283 -222.229934) (xy 125.052267 -222.199408) (xy 125.015544 -222.162685) (xy 124.985018 -222.120669)
			(xy 124.96144 -222.074395) (xy 124.945392 -222.025002) (xy 124.937267 -221.973707) (xy 124.936758 -221.94774)
			(xy 123.718066 -221.94774) (xy 123.717557 -221.973707) (xy 123.709432 -222.025002) (xy 123.693384 -222.074395)
			(xy 123.669806 -222.120669) (xy 123.63928 -222.162685) (xy 123.602557 -222.199408) (xy 123.560541 -222.229934)
			(xy 123.514267 -222.253512) (xy 123.464874 -222.26956) (xy 123.413579 -222.277685) (xy 123.361645 -222.277685)
			(xy 123.31035 -222.26956) (xy 123.260957 -222.253512) (xy 123.214683 -222.229934) (xy 123.172667 -222.199408)
			(xy 123.135944 -222.162685) (xy 123.105418 -222.120669) (xy 123.08184 -222.074395) (xy 123.065792 -222.025002)
			(xy 123.057667 -221.973707) (xy 123.057158 -221.94774) (xy 121.838466 -221.94774) (xy 121.837957 -221.973707)
			(xy 121.829832 -222.025002) (xy 121.813784 -222.074395) (xy 121.790206 -222.120669) (xy 121.75968 -222.162685)
			(xy 121.722957 -222.199408) (xy 121.680941 -222.229934) (xy 121.634667 -222.253512) (xy 121.585274 -222.26956)
			(xy 121.533979 -222.277685) (xy 121.482045 -222.277685) (xy 121.43075 -222.26956) (xy 121.381357 -222.253512)
			(xy 121.335083 -222.229934) (xy 121.293067 -222.199408) (xy 121.256344 -222.162685) (xy 121.225818 -222.120669)
			(xy 121.20224 -222.074395) (xy 121.186192 -222.025002) (xy 121.178067 -221.973707) (xy 121.177558 -221.94774)
			(xy 119.95912 -221.94774) (xy 119.958611 -221.973707) (xy 119.950486 -222.025002) (xy 119.934438 -222.074395)
			(xy 119.91086 -222.120669) (xy 119.880334 -222.162685) (xy 119.843611 -222.199408) (xy 119.801595 -222.229934)
			(xy 119.755321 -222.253512) (xy 119.705928 -222.26956) (xy 119.654633 -222.277685) (xy 119.602699 -222.277685)
			(xy 119.551404 -222.26956) (xy 119.502011 -222.253512) (xy 119.455737 -222.229934) (xy 119.413721 -222.199408)
			(xy 119.376998 -222.162685) (xy 119.346472 -222.120669) (xy 119.322894 -222.074395) (xy 119.306846 -222.025002)
			(xy 119.298721 -221.973707) (xy 118.078757 -221.973707) (xy 118.070632 -222.025002) (xy 118.054584 -222.074395)
			(xy 118.031006 -222.120669) (xy 118.00048 -222.162685) (xy 117.963757 -222.199408) (xy 117.921741 -222.229934)
			(xy 117.875467 -222.253512) (xy 117.826074 -222.26956) (xy 117.774779 -222.277685) (xy 117.722845 -222.277685)
			(xy 117.67155 -222.26956) (xy 117.622157 -222.253512) (xy 117.575883 -222.229934) (xy 117.533867 -222.199408)
			(xy 117.497144 -222.162685) (xy 117.466618 -222.120669) (xy 117.44304 -222.074395) (xy 117.426992 -222.025002)
			(xy 117.418867 -221.973707) (xy 117.418358 -221.94774) (xy 116.199666 -221.94774) (xy 116.199157 -221.973707)
			(xy 116.191032 -222.025002) (xy 116.174984 -222.074395) (xy 116.151406 -222.120669) (xy 116.12088 -222.162685)
			(xy 116.084157 -222.199408) (xy 116.042141 -222.229934) (xy 115.995867 -222.253512) (xy 115.946474 -222.26956)
			(xy 115.895179 -222.277685) (xy 115.843245 -222.277685) (xy 115.79195 -222.26956) (xy 115.742557 -222.253512)
			(xy 115.696283 -222.229934) (xy 115.654267 -222.199408) (xy 115.617544 -222.162685) (xy 115.587018 -222.120669)
			(xy 115.56344 -222.074395) (xy 115.547392 -222.025002) (xy 115.539267 -221.973707) (xy 115.538758 -221.94774)
			(xy 115.26012 -221.94774) (xy 115.259611 -221.973707) (xy 115.251486 -222.025002) (xy 115.235438 -222.074395)
			(xy 115.21186 -222.120669) (xy 115.181334 -222.162685) (xy 115.144611 -222.199408) (xy 115.102595 -222.229934)
			(xy 115.056321 -222.253512) (xy 115.006928 -222.26956) (xy 114.955633 -222.277685) (xy 114.903699 -222.277685)
			(xy 114.852404 -222.26956) (xy 114.803011 -222.253512) (xy 114.756737 -222.229934) (xy 114.714721 -222.199408)
			(xy 114.677998 -222.162685) (xy 114.647472 -222.120669) (xy 114.623894 -222.074395) (xy 114.607846 -222.025002)
			(xy 114.599721 -221.973707) (xy 114.319811 -221.973707) (xy 114.311686 -222.025002) (xy 114.295638 -222.074395)
			(xy 114.27206 -222.120669) (xy 114.241534 -222.162685) (xy 114.204811 -222.199408) (xy 114.162795 -222.229934)
			(xy 114.116521 -222.253512) (xy 114.067128 -222.26956) (xy 114.015833 -222.277685) (xy 113.963899 -222.277685)
			(xy 113.912604 -222.26956) (xy 113.863211 -222.253512) (xy 113.816937 -222.229934) (xy 113.774921 -222.199408)
			(xy 113.738198 -222.162685) (xy 113.707672 -222.120669) (xy 113.684094 -222.074395) (xy 113.668046 -222.025002)
			(xy 113.659921 -221.973707) (xy 113.659412 -221.94774) (xy 113.380266 -221.94774) (xy 113.379757 -221.973707)
			(xy 113.371632 -222.025002) (xy 113.355584 -222.074395) (xy 113.332006 -222.120669) (xy 113.30148 -222.162685)
			(xy 113.264757 -222.199408) (xy 113.222741 -222.229934) (xy 113.176467 -222.253512) (xy 113.127074 -222.26956)
			(xy 113.075779 -222.277685) (xy 113.023845 -222.277685) (xy 112.97255 -222.26956) (xy 112.923157 -222.253512)
			(xy 112.876883 -222.229934) (xy 112.834867 -222.199408) (xy 112.798144 -222.162685) (xy 112.767618 -222.120669)
			(xy 112.74404 -222.074395) (xy 112.727992 -222.025002) (xy 112.719867 -221.973707) (xy 112.439957 -221.973707)
			(xy 112.431832 -222.025002) (xy 112.415784 -222.074395) (xy 112.392206 -222.120669) (xy 112.36168 -222.162685)
			(xy 112.324957 -222.199408) (xy 112.282941 -222.229934) (xy 112.236667 -222.253512) (xy 112.187274 -222.26956)
			(xy 112.135979 -222.277685) (xy 112.084045 -222.277685) (xy 112.03275 -222.26956) (xy 111.983357 -222.253512)
			(xy 111.937083 -222.229934) (xy 111.895067 -222.199408) (xy 111.858344 -222.162685) (xy 111.827818 -222.120669)
			(xy 111.80424 -222.074395) (xy 111.788192 -222.025002) (xy 111.780067 -221.973707) (xy 111.779558 -221.94774)
			(xy 111.587026 -221.94774) (xy 111.587026 -222.380302) (xy 111.587453 -222.390353) (xy 111.595171 -222.408913)
			(xy 111.609424 -222.423087) (xy 111.628027 -222.430702) (xy 111.63808 -222.431102) (xy 111.640366 -222.431102)
			(xy 111.66634 -222.431582) (xy 111.717651 -222.439704) (xy 111.767058 -222.455753) (xy 111.813347 -222.479334)
			(xy 111.855376 -222.509866) (xy 111.892111 -222.546598) (xy 111.922648 -222.588624) (xy 111.946234 -222.63491)
			(xy 111.962288 -222.684316) (xy 111.970415 -222.735626) (xy 111.970415 -222.787523) (xy 112.250221 -222.787523)
			(xy 112.250221 -222.735589) (xy 112.258346 -222.684294) (xy 112.274394 -222.634901) (xy 112.297972 -222.588627)
			(xy 112.328498 -222.546611) (xy 112.365221 -222.509888) (xy 112.407237 -222.479362) (xy 112.453511 -222.455784)
			(xy 112.502904 -222.439736) (xy 112.554199 -222.431611) (xy 112.606133 -222.431611) (xy 112.657428 -222.439736)
			(xy 112.706821 -222.455784) (xy 112.753095 -222.479362) (xy 112.795111 -222.509888) (xy 112.831834 -222.546611)
			(xy 112.86236 -222.588627) (xy 112.885938 -222.634901) (xy 112.901986 -222.684294) (xy 112.910111 -222.735589)
			(xy 112.91062 -222.761556) (xy 112.910111 -222.787523) (xy 113.190021 -222.787523) (xy 113.190021 -222.735589)
			(xy 113.198146 -222.684294) (xy 113.214194 -222.634901) (xy 113.237772 -222.588627) (xy 113.268298 -222.546611)
			(xy 113.305021 -222.509888) (xy 113.347037 -222.479362) (xy 113.393311 -222.455784) (xy 113.442704 -222.439736)
			(xy 113.493999 -222.431611) (xy 113.545933 -222.431611) (xy 113.597228 -222.439736) (xy 113.646621 -222.455784)
			(xy 113.692895 -222.479362) (xy 113.734911 -222.509888) (xy 113.771634 -222.546611) (xy 113.80216 -222.588627)
			(xy 113.825738 -222.634901) (xy 113.841786 -222.684294) (xy 113.849911 -222.735589) (xy 113.85042 -222.761556)
			(xy 113.849911 -222.787523) (xy 114.129821 -222.787523) (xy 114.129821 -222.735589) (xy 114.137946 -222.684294)
			(xy 114.153994 -222.634901) (xy 114.177572 -222.588627) (xy 114.208098 -222.546611) (xy 114.244821 -222.509888)
			(xy 114.286837 -222.479362) (xy 114.333111 -222.455784) (xy 114.382504 -222.439736) (xy 114.433799 -222.431611)
			(xy 114.485733 -222.431611) (xy 114.537028 -222.439736) (xy 114.586421 -222.455784) (xy 114.632695 -222.479362)
			(xy 114.674711 -222.509888) (xy 114.711434 -222.546611) (xy 114.74196 -222.588627) (xy 114.765538 -222.634901)
			(xy 114.781586 -222.684294) (xy 114.789711 -222.735589) (xy 114.79022 -222.761556) (xy 114.789711 -222.787523)
			(xy 115.069621 -222.787523) (xy 115.069621 -222.735589) (xy 115.077746 -222.684294) (xy 115.093794 -222.634901)
			(xy 115.117372 -222.588627) (xy 115.147898 -222.546611) (xy 115.184621 -222.509888) (xy 115.226637 -222.479362)
			(xy 115.272911 -222.455784) (xy 115.322304 -222.439736) (xy 115.373599 -222.431611) (xy 115.425533 -222.431611)
			(xy 115.476828 -222.439736) (xy 115.526221 -222.455784) (xy 115.572495 -222.479362) (xy 115.614511 -222.509888)
			(xy 115.651234 -222.546611) (xy 115.68176 -222.588627) (xy 115.705338 -222.634901) (xy 115.721386 -222.684294)
			(xy 115.729511 -222.735589) (xy 115.73002 -222.761556) (xy 115.729511 -222.787523) (xy 116.009421 -222.787523)
			(xy 116.009421 -222.735589) (xy 116.017546 -222.684294) (xy 116.033594 -222.634901) (xy 116.057172 -222.588627)
			(xy 116.087698 -222.546611) (xy 116.124421 -222.509888) (xy 116.166437 -222.479362) (xy 116.212711 -222.455784)
			(xy 116.262104 -222.439736) (xy 116.313399 -222.431611) (xy 116.365333 -222.431611) (xy 116.416628 -222.439736)
			(xy 116.466021 -222.455784) (xy 116.512295 -222.479362) (xy 116.554311 -222.509888) (xy 116.591034 -222.546611)
			(xy 116.62156 -222.588627) (xy 116.645138 -222.634901) (xy 116.661186 -222.684294) (xy 116.669311 -222.735589)
			(xy 116.66982 -222.761556) (xy 116.669311 -222.787523) (xy 116.949221 -222.787523) (xy 116.949221 -222.735589)
			(xy 116.957346 -222.684294) (xy 116.973394 -222.634901) (xy 116.996972 -222.588627) (xy 117.027498 -222.546611)
			(xy 117.064221 -222.509888) (xy 117.106237 -222.479362) (xy 117.152511 -222.455784) (xy 117.201904 -222.439736)
			(xy 117.253199 -222.431611) (xy 117.305133 -222.431611) (xy 117.356428 -222.439736) (xy 117.405821 -222.455784)
			(xy 117.452095 -222.479362) (xy 117.494111 -222.509888) (xy 117.530834 -222.546611) (xy 117.56136 -222.588627)
			(xy 117.584938 -222.634901) (xy 117.600986 -222.684294) (xy 117.609111 -222.735589) (xy 117.60962 -222.761556)
			(xy 117.609111 -222.787523) (xy 117.889021 -222.787523) (xy 117.889021 -222.735589) (xy 117.897146 -222.684294)
			(xy 117.913194 -222.634901) (xy 117.936772 -222.588627) (xy 117.967298 -222.546611) (xy 118.004021 -222.509888)
			(xy 118.046037 -222.479362) (xy 118.092311 -222.455784) (xy 118.141704 -222.439736) (xy 118.192999 -222.431611)
			(xy 118.244933 -222.431611) (xy 118.296228 -222.439736) (xy 118.345621 -222.455784) (xy 118.391895 -222.479362)
			(xy 118.433911 -222.509888) (xy 118.470634 -222.546611) (xy 118.50116 -222.588627) (xy 118.524738 -222.634901)
			(xy 118.540786 -222.684294) (xy 118.548911 -222.735589) (xy 118.54942 -222.761556) (xy 118.548911 -222.787523)
			(xy 118.828821 -222.787523) (xy 118.828821 -222.735589) (xy 118.836946 -222.684294) (xy 118.852994 -222.634901)
			(xy 118.876572 -222.588627) (xy 118.907098 -222.546611) (xy 118.943821 -222.509888) (xy 118.985837 -222.479362)
			(xy 119.032111 -222.455784) (xy 119.081504 -222.439736) (xy 119.132799 -222.431611) (xy 119.184733 -222.431611)
			(xy 119.236028 -222.439736) (xy 119.285421 -222.455784) (xy 119.331695 -222.479362) (xy 119.373711 -222.509888)
			(xy 119.410434 -222.546611) (xy 119.44096 -222.588627) (xy 119.464538 -222.634901) (xy 119.480586 -222.684294)
			(xy 119.488711 -222.735589) (xy 119.48922 -222.761556) (xy 119.488711 -222.787523) (xy 119.768621 -222.787523)
			(xy 119.768621 -222.735589) (xy 119.776746 -222.684294) (xy 119.792794 -222.634901) (xy 119.816372 -222.588627)
			(xy 119.846898 -222.546611) (xy 119.883621 -222.509888) (xy 119.925637 -222.479362) (xy 119.971911 -222.455784)
			(xy 120.021304 -222.439736) (xy 120.072599 -222.431611) (xy 120.124533 -222.431611) (xy 120.175828 -222.439736)
			(xy 120.225221 -222.455784) (xy 120.271495 -222.479362) (xy 120.313511 -222.509888) (xy 120.350234 -222.546611)
			(xy 120.38076 -222.588627) (xy 120.404338 -222.634901) (xy 120.420386 -222.684294) (xy 120.428511 -222.735589)
			(xy 120.42902 -222.761556) (xy 120.428511 -222.787523) (xy 120.708421 -222.787523) (xy 120.708421 -222.735589)
			(xy 120.716546 -222.684294) (xy 120.732594 -222.634901) (xy 120.756172 -222.588627) (xy 120.786698 -222.546611)
			(xy 120.823421 -222.509888) (xy 120.865437 -222.479362) (xy 120.911711 -222.455784) (xy 120.961104 -222.439736)
			(xy 121.012399 -222.431611) (xy 121.064333 -222.431611) (xy 121.115628 -222.439736) (xy 121.165021 -222.455784)
			(xy 121.211295 -222.479362) (xy 121.253311 -222.509888) (xy 121.290034 -222.546611) (xy 121.32056 -222.588627)
			(xy 121.344138 -222.634901) (xy 121.360186 -222.684294) (xy 121.368311 -222.735589) (xy 121.36882 -222.761556)
			(xy 121.368311 -222.787523) (xy 121.648221 -222.787523) (xy 121.648221 -222.735589) (xy 121.656346 -222.684294)
			(xy 121.672394 -222.634901) (xy 121.695972 -222.588627) (xy 121.726498 -222.546611) (xy 121.763221 -222.509888)
			(xy 121.805237 -222.479362) (xy 121.851511 -222.455784) (xy 121.900904 -222.439736) (xy 121.952199 -222.431611)
			(xy 122.004133 -222.431611) (xy 122.055428 -222.439736) (xy 122.104821 -222.455784) (xy 122.151095 -222.479362)
			(xy 122.193111 -222.509888) (xy 122.229834 -222.546611) (xy 122.26036 -222.588627) (xy 122.283938 -222.634901)
			(xy 122.299986 -222.684294) (xy 122.308111 -222.735589) (xy 122.30862 -222.761556) (xy 122.308111 -222.787523)
			(xy 122.588021 -222.787523) (xy 122.588021 -222.735589) (xy 122.596146 -222.684294) (xy 122.612194 -222.634901)
			(xy 122.635772 -222.588627) (xy 122.666298 -222.546611) (xy 122.703021 -222.509888) (xy 122.745037 -222.479362)
			(xy 122.791311 -222.455784) (xy 122.840704 -222.439736) (xy 122.891999 -222.431611) (xy 122.943933 -222.431611)
			(xy 122.995228 -222.439736) (xy 123.044621 -222.455784) (xy 123.090895 -222.479362) (xy 123.132911 -222.509888)
			(xy 123.169634 -222.546611) (xy 123.20016 -222.588627) (xy 123.223738 -222.634901) (xy 123.239786 -222.684294)
			(xy 123.247911 -222.735589) (xy 123.24842 -222.761556) (xy 123.247911 -222.787523) (xy 123.527821 -222.787523)
			(xy 123.527821 -222.735589) (xy 123.535946 -222.684294) (xy 123.551994 -222.634901) (xy 123.575572 -222.588627)
			(xy 123.606098 -222.546611) (xy 123.642821 -222.509888) (xy 123.684837 -222.479362) (xy 123.731111 -222.455784)
			(xy 123.780504 -222.439736) (xy 123.831799 -222.431611) (xy 123.883733 -222.431611) (xy 123.935028 -222.439736)
			(xy 123.984421 -222.455784) (xy 124.030695 -222.479362) (xy 124.072711 -222.509888) (xy 124.109434 -222.546611)
			(xy 124.13996 -222.588627) (xy 124.163538 -222.634901) (xy 124.179586 -222.684294) (xy 124.187711 -222.735589)
			(xy 124.18822 -222.761556) (xy 124.187711 -222.787523) (xy 124.467621 -222.787523) (xy 124.467621 -222.735589)
			(xy 124.475746 -222.684294) (xy 124.491794 -222.634901) (xy 124.515372 -222.588627) (xy 124.545898 -222.546611)
			(xy 124.582621 -222.509888) (xy 124.624637 -222.479362) (xy 124.670911 -222.455784) (xy 124.720304 -222.439736)
			(xy 124.771599 -222.431611) (xy 124.823533 -222.431611) (xy 124.874828 -222.439736) (xy 124.924221 -222.455784)
			(xy 124.970495 -222.479362) (xy 125.012511 -222.509888) (xy 125.049234 -222.546611) (xy 125.07976 -222.588627)
			(xy 125.103338 -222.634901) (xy 125.119386 -222.684294) (xy 125.127511 -222.735589) (xy 125.12802 -222.761556)
			(xy 125.127511 -222.787523) (xy 125.407421 -222.787523) (xy 125.407421 -222.735589) (xy 125.415546 -222.684294)
			(xy 125.431594 -222.634901) (xy 125.455172 -222.588627) (xy 125.485698 -222.546611) (xy 125.522421 -222.509888)
			(xy 125.564437 -222.479362) (xy 125.610711 -222.455784) (xy 125.660104 -222.439736) (xy 125.711399 -222.431611)
			(xy 125.763333 -222.431611) (xy 125.814628 -222.439736) (xy 125.864021 -222.455784) (xy 125.910295 -222.479362)
			(xy 125.952311 -222.509888) (xy 125.989034 -222.546611) (xy 126.01956 -222.588627) (xy 126.043138 -222.634901)
			(xy 126.059186 -222.684294) (xy 126.067311 -222.735589) (xy 126.06782 -222.761556) (xy 126.067311 -222.787523)
			(xy 126.347221 -222.787523) (xy 126.347221 -222.735589) (xy 126.355346 -222.684294) (xy 126.371394 -222.634901)
			(xy 126.394972 -222.588627) (xy 126.425498 -222.546611) (xy 126.462221 -222.509888) (xy 126.504237 -222.479362)
			(xy 126.550511 -222.455784) (xy 126.599904 -222.439736) (xy 126.651199 -222.431611) (xy 126.703133 -222.431611)
			(xy 126.754428 -222.439736) (xy 126.803821 -222.455784) (xy 126.850095 -222.479362) (xy 126.892111 -222.509888)
			(xy 126.928834 -222.546611) (xy 126.95936 -222.588627) (xy 126.982938 -222.634901) (xy 126.998986 -222.684294)
			(xy 127.007111 -222.735589) (xy 127.00762 -222.761556) (xy 127.007111 -222.787523) (xy 127.287021 -222.787523)
			(xy 127.287021 -222.735589) (xy 127.295146 -222.684294) (xy 127.311194 -222.634901) (xy 127.334772 -222.588627)
			(xy 127.365298 -222.546611) (xy 127.402021 -222.509888) (xy 127.444037 -222.479362) (xy 127.490311 -222.455784)
			(xy 127.539704 -222.439736) (xy 127.590999 -222.431611) (xy 127.642933 -222.431611) (xy 127.694228 -222.439736)
			(xy 127.743621 -222.455784) (xy 127.789895 -222.479362) (xy 127.831911 -222.509888) (xy 127.868634 -222.546611)
			(xy 127.89916 -222.588627) (xy 127.922738 -222.634901) (xy 127.938786 -222.684294) (xy 127.946911 -222.735589)
			(xy 127.94742 -222.761556) (xy 127.946911 -222.787523) (xy 128.226821 -222.787523) (xy 128.226821 -222.735589)
			(xy 128.234946 -222.684294) (xy 128.250994 -222.634901) (xy 128.274572 -222.588627) (xy 128.305098 -222.546611)
			(xy 128.341821 -222.509888) (xy 128.383837 -222.479362) (xy 128.430111 -222.455784) (xy 128.479504 -222.439736)
			(xy 128.530799 -222.431611) (xy 128.582733 -222.431611) (xy 128.634028 -222.439736) (xy 128.683421 -222.455784)
			(xy 128.729695 -222.479362) (xy 128.771711 -222.509888) (xy 128.808434 -222.546611) (xy 128.83896 -222.588627)
			(xy 128.862538 -222.634901) (xy 128.878586 -222.684294) (xy 128.886711 -222.735589) (xy 128.88722 -222.761556)
			(xy 128.886711 -222.787523) (xy 129.166621 -222.787523) (xy 129.166621 -222.735589) (xy 129.174746 -222.684294)
			(xy 129.190794 -222.634901) (xy 129.214372 -222.588627) (xy 129.244898 -222.546611) (xy 129.281621 -222.509888)
			(xy 129.323637 -222.479362) (xy 129.369911 -222.455784) (xy 129.419304 -222.439736) (xy 129.470599 -222.431611)
			(xy 129.522533 -222.431611) (xy 129.573828 -222.439736) (xy 129.623221 -222.455784) (xy 129.669495 -222.479362)
			(xy 129.711511 -222.509888) (xy 129.748234 -222.546611) (xy 129.77876 -222.588627) (xy 129.802338 -222.634901)
			(xy 129.818386 -222.684294) (xy 129.826511 -222.735589) (xy 129.82702 -222.761556) (xy 129.826511 -222.787523)
			(xy 130.106421 -222.787523) (xy 130.106421 -222.735589) (xy 130.114546 -222.684294) (xy 130.130594 -222.634901)
			(xy 130.154172 -222.588627) (xy 130.184698 -222.546611) (xy 130.221421 -222.509888) (xy 130.263437 -222.479362)
			(xy 130.309711 -222.455784) (xy 130.359104 -222.439736) (xy 130.410399 -222.431611) (xy 130.462333 -222.431611)
			(xy 130.513628 -222.439736) (xy 130.563021 -222.455784) (xy 130.609295 -222.479362) (xy 130.651311 -222.509888)
			(xy 130.688034 -222.546611) (xy 130.71856 -222.588627) (xy 130.742138 -222.634901) (xy 130.758186 -222.684294)
			(xy 130.766311 -222.735589) (xy 130.76682 -222.761556) (xy 130.766311 -222.787523) (xy 131.046221 -222.787523)
			(xy 131.046221 -222.735589) (xy 131.054346 -222.684294) (xy 131.070394 -222.634901) (xy 131.093972 -222.588627)
			(xy 131.124498 -222.546611) (xy 131.161221 -222.509888) (xy 131.203237 -222.479362) (xy 131.249511 -222.455784)
			(xy 131.298904 -222.439736) (xy 131.350199 -222.431611) (xy 131.402133 -222.431611) (xy 131.453428 -222.439736)
			(xy 131.502821 -222.455784) (xy 131.549095 -222.479362) (xy 131.591111 -222.509888) (xy 131.627834 -222.546611)
			(xy 131.65836 -222.588627) (xy 131.681938 -222.634901) (xy 131.697986 -222.684294) (xy 131.706111 -222.735589)
			(xy 131.70662 -222.761556) (xy 131.706111 -222.787523) (xy 131.986021 -222.787523) (xy 131.986021 -222.735589)
			(xy 131.994146 -222.684294) (xy 132.010194 -222.634901) (xy 132.033772 -222.588627) (xy 132.064298 -222.546611)
			(xy 132.101021 -222.509888) (xy 132.143037 -222.479362) (xy 132.189311 -222.455784) (xy 132.238704 -222.439736)
			(xy 132.289999 -222.431611) (xy 132.341933 -222.431611) (xy 132.393228 -222.439736) (xy 132.442621 -222.455784)
			(xy 132.488895 -222.479362) (xy 132.530911 -222.509888) (xy 132.567634 -222.546611) (xy 132.59816 -222.588627)
			(xy 132.621738 -222.634901) (xy 132.637786 -222.684294) (xy 132.645911 -222.735589) (xy 132.64642 -222.761556)
			(xy 132.645911 -222.787523) (xy 132.925821 -222.787523) (xy 132.925821 -222.735589) (xy 132.933946 -222.684294)
			(xy 132.949994 -222.634901) (xy 132.973572 -222.588627) (xy 133.004098 -222.546611) (xy 133.040821 -222.509888)
			(xy 133.082837 -222.479362) (xy 133.129111 -222.455784) (xy 133.178504 -222.439736) (xy 133.229799 -222.431611)
			(xy 133.281733 -222.431611) (xy 133.333028 -222.439736) (xy 133.382421 -222.455784) (xy 133.428695 -222.479362)
			(xy 133.470711 -222.509888) (xy 133.507434 -222.546611) (xy 133.53796 -222.588627) (xy 133.561538 -222.634901)
			(xy 133.577586 -222.684294) (xy 133.585711 -222.735589) (xy 133.58622 -222.761556) (xy 133.585711 -222.787523)
			(xy 133.577586 -222.838818) (xy 133.561538 -222.888211) (xy 133.53796 -222.934485) (xy 133.507434 -222.976501)
			(xy 133.470711 -223.013224) (xy 133.428695 -223.04375) (xy 133.382421 -223.067328) (xy 133.333028 -223.083376)
			(xy 133.281733 -223.091501) (xy 133.229799 -223.091501) (xy 133.178504 -223.083376) (xy 133.129111 -223.067328)
			(xy 133.082837 -223.04375) (xy 133.040821 -223.013224) (xy 133.004098 -222.976501) (xy 132.973572 -222.934485)
			(xy 132.949994 -222.888211) (xy 132.933946 -222.838818) (xy 132.925821 -222.787523) (xy 132.645911 -222.787523)
			(xy 132.637786 -222.838818) (xy 132.621738 -222.888211) (xy 132.59816 -222.934485) (xy 132.567634 -222.976501)
			(xy 132.530911 -223.013224) (xy 132.488895 -223.04375) (xy 132.442621 -223.067328) (xy 132.393228 -223.083376)
			(xy 132.341933 -223.091501) (xy 132.289999 -223.091501) (xy 132.238704 -223.083376) (xy 132.189311 -223.067328)
			(xy 132.143037 -223.04375) (xy 132.101021 -223.013224) (xy 132.064298 -222.976501) (xy 132.033772 -222.934485)
			(xy 132.010194 -222.888211) (xy 131.994146 -222.838818) (xy 131.986021 -222.787523) (xy 131.706111 -222.787523)
			(xy 131.697986 -222.838818) (xy 131.681938 -222.888211) (xy 131.65836 -222.934485) (xy 131.627834 -222.976501)
			(xy 131.591111 -223.013224) (xy 131.549095 -223.04375) (xy 131.502821 -223.067328) (xy 131.453428 -223.083376)
			(xy 131.402133 -223.091501) (xy 131.350199 -223.091501) (xy 131.298904 -223.083376) (xy 131.249511 -223.067328)
			(xy 131.203237 -223.04375) (xy 131.161221 -223.013224) (xy 131.124498 -222.976501) (xy 131.093972 -222.934485)
			(xy 131.070394 -222.888211) (xy 131.054346 -222.838818) (xy 131.046221 -222.787523) (xy 130.766311 -222.787523)
			(xy 130.758186 -222.838818) (xy 130.742138 -222.888211) (xy 130.71856 -222.934485) (xy 130.688034 -222.976501)
			(xy 130.651311 -223.013224) (xy 130.609295 -223.04375) (xy 130.563021 -223.067328) (xy 130.513628 -223.083376)
			(xy 130.462333 -223.091501) (xy 130.410399 -223.091501) (xy 130.359104 -223.083376) (xy 130.309711 -223.067328)
			(xy 130.263437 -223.04375) (xy 130.221421 -223.013224) (xy 130.184698 -222.976501) (xy 130.154172 -222.934485)
			(xy 130.130594 -222.888211) (xy 130.114546 -222.838818) (xy 130.106421 -222.787523) (xy 129.826511 -222.787523)
			(xy 129.818386 -222.838818) (xy 129.802338 -222.888211) (xy 129.77876 -222.934485) (xy 129.748234 -222.976501)
			(xy 129.711511 -223.013224) (xy 129.669495 -223.04375) (xy 129.623221 -223.067328) (xy 129.573828 -223.083376)
			(xy 129.522533 -223.091501) (xy 129.470599 -223.091501) (xy 129.419304 -223.083376) (xy 129.369911 -223.067328)
			(xy 129.323637 -223.04375) (xy 129.281621 -223.013224) (xy 129.244898 -222.976501) (xy 129.214372 -222.934485)
			(xy 129.190794 -222.888211) (xy 129.174746 -222.838818) (xy 129.166621 -222.787523) (xy 128.886711 -222.787523)
			(xy 128.878586 -222.838818) (xy 128.862538 -222.888211) (xy 128.83896 -222.934485) (xy 128.808434 -222.976501)
			(xy 128.771711 -223.013224) (xy 128.729695 -223.04375) (xy 128.683421 -223.067328) (xy 128.634028 -223.083376)
			(xy 128.582733 -223.091501) (xy 128.530799 -223.091501) (xy 128.479504 -223.083376) (xy 128.430111 -223.067328)
			(xy 128.383837 -223.04375) (xy 128.341821 -223.013224) (xy 128.305098 -222.976501) (xy 128.274572 -222.934485)
			(xy 128.250994 -222.888211) (xy 128.234946 -222.838818) (xy 128.226821 -222.787523) (xy 127.946911 -222.787523)
			(xy 127.938786 -222.838818) (xy 127.922738 -222.888211) (xy 127.89916 -222.934485) (xy 127.868634 -222.976501)
			(xy 127.831911 -223.013224) (xy 127.789895 -223.04375) (xy 127.743621 -223.067328) (xy 127.694228 -223.083376)
			(xy 127.642933 -223.091501) (xy 127.590999 -223.091501) (xy 127.539704 -223.083376) (xy 127.490311 -223.067328)
			(xy 127.444037 -223.04375) (xy 127.402021 -223.013224) (xy 127.365298 -222.976501) (xy 127.334772 -222.934485)
			(xy 127.311194 -222.888211) (xy 127.295146 -222.838818) (xy 127.287021 -222.787523) (xy 127.007111 -222.787523)
			(xy 126.998986 -222.838818) (xy 126.982938 -222.888211) (xy 126.95936 -222.934485) (xy 126.928834 -222.976501)
			(xy 126.892111 -223.013224) (xy 126.850095 -223.04375) (xy 126.803821 -223.067328) (xy 126.754428 -223.083376)
			(xy 126.703133 -223.091501) (xy 126.651199 -223.091501) (xy 126.599904 -223.083376) (xy 126.550511 -223.067328)
			(xy 126.504237 -223.04375) (xy 126.462221 -223.013224) (xy 126.425498 -222.976501) (xy 126.394972 -222.934485)
			(xy 126.371394 -222.888211) (xy 126.355346 -222.838818) (xy 126.347221 -222.787523) (xy 126.067311 -222.787523)
			(xy 126.059186 -222.838818) (xy 126.043138 -222.888211) (xy 126.01956 -222.934485) (xy 125.989034 -222.976501)
			(xy 125.952311 -223.013224) (xy 125.910295 -223.04375) (xy 125.864021 -223.067328) (xy 125.814628 -223.083376)
			(xy 125.763333 -223.091501) (xy 125.711399 -223.091501) (xy 125.660104 -223.083376) (xy 125.610711 -223.067328)
			(xy 125.564437 -223.04375) (xy 125.522421 -223.013224) (xy 125.485698 -222.976501) (xy 125.455172 -222.934485)
			(xy 125.431594 -222.888211) (xy 125.415546 -222.838818) (xy 125.407421 -222.787523) (xy 125.127511 -222.787523)
			(xy 125.119386 -222.838818) (xy 125.103338 -222.888211) (xy 125.07976 -222.934485) (xy 125.049234 -222.976501)
			(xy 125.012511 -223.013224) (xy 124.970495 -223.04375) (xy 124.924221 -223.067328) (xy 124.874828 -223.083376)
			(xy 124.823533 -223.091501) (xy 124.771599 -223.091501) (xy 124.720304 -223.083376) (xy 124.670911 -223.067328)
			(xy 124.624637 -223.04375) (xy 124.582621 -223.013224) (xy 124.545898 -222.976501) (xy 124.515372 -222.934485)
			(xy 124.491794 -222.888211) (xy 124.475746 -222.838818) (xy 124.467621 -222.787523) (xy 124.187711 -222.787523)
			(xy 124.179586 -222.838818) (xy 124.163538 -222.888211) (xy 124.13996 -222.934485) (xy 124.109434 -222.976501)
			(xy 124.072711 -223.013224) (xy 124.030695 -223.04375) (xy 123.984421 -223.067328) (xy 123.935028 -223.083376)
			(xy 123.883733 -223.091501) (xy 123.831799 -223.091501) (xy 123.780504 -223.083376) (xy 123.731111 -223.067328)
			(xy 123.684837 -223.04375) (xy 123.642821 -223.013224) (xy 123.606098 -222.976501) (xy 123.575572 -222.934485)
			(xy 123.551994 -222.888211) (xy 123.535946 -222.838818) (xy 123.527821 -222.787523) (xy 123.247911 -222.787523)
			(xy 123.239786 -222.838818) (xy 123.223738 -222.888211) (xy 123.20016 -222.934485) (xy 123.169634 -222.976501)
			(xy 123.132911 -223.013224) (xy 123.090895 -223.04375) (xy 123.044621 -223.067328) (xy 122.995228 -223.083376)
			(xy 122.943933 -223.091501) (xy 122.891999 -223.091501) (xy 122.840704 -223.083376) (xy 122.791311 -223.067328)
			(xy 122.745037 -223.04375) (xy 122.703021 -223.013224) (xy 122.666298 -222.976501) (xy 122.635772 -222.934485)
			(xy 122.612194 -222.888211) (xy 122.596146 -222.838818) (xy 122.588021 -222.787523) (xy 122.308111 -222.787523)
			(xy 122.299986 -222.838818) (xy 122.283938 -222.888211) (xy 122.26036 -222.934485) (xy 122.229834 -222.976501)
			(xy 122.193111 -223.013224) (xy 122.151095 -223.04375) (xy 122.104821 -223.067328) (xy 122.055428 -223.083376)
			(xy 122.004133 -223.091501) (xy 121.952199 -223.091501) (xy 121.900904 -223.083376) (xy 121.851511 -223.067328)
			(xy 121.805237 -223.04375) (xy 121.763221 -223.013224) (xy 121.726498 -222.976501) (xy 121.695972 -222.934485)
			(xy 121.672394 -222.888211) (xy 121.656346 -222.838818) (xy 121.648221 -222.787523) (xy 121.368311 -222.787523)
			(xy 121.360186 -222.838818) (xy 121.344138 -222.888211) (xy 121.32056 -222.934485) (xy 121.290034 -222.976501)
			(xy 121.253311 -223.013224) (xy 121.211295 -223.04375) (xy 121.165021 -223.067328) (xy 121.115628 -223.083376)
			(xy 121.064333 -223.091501) (xy 121.012399 -223.091501) (xy 120.961104 -223.083376) (xy 120.911711 -223.067328)
			(xy 120.865437 -223.04375) (xy 120.823421 -223.013224) (xy 120.786698 -222.976501) (xy 120.756172 -222.934485)
			(xy 120.732594 -222.888211) (xy 120.716546 -222.838818) (xy 120.708421 -222.787523) (xy 120.428511 -222.787523)
			(xy 120.420386 -222.838818) (xy 120.404338 -222.888211) (xy 120.38076 -222.934485) (xy 120.350234 -222.976501)
			(xy 120.313511 -223.013224) (xy 120.271495 -223.04375) (xy 120.225221 -223.067328) (xy 120.175828 -223.083376)
			(xy 120.124533 -223.091501) (xy 120.072599 -223.091501) (xy 120.021304 -223.083376) (xy 119.971911 -223.067328)
			(xy 119.925637 -223.04375) (xy 119.883621 -223.013224) (xy 119.846898 -222.976501) (xy 119.816372 -222.934485)
			(xy 119.792794 -222.888211) (xy 119.776746 -222.838818) (xy 119.768621 -222.787523) (xy 119.488711 -222.787523)
			(xy 119.480586 -222.838818) (xy 119.464538 -222.888211) (xy 119.44096 -222.934485) (xy 119.410434 -222.976501)
			(xy 119.373711 -223.013224) (xy 119.331695 -223.04375) (xy 119.285421 -223.067328) (xy 119.236028 -223.083376)
			(xy 119.184733 -223.091501) (xy 119.132799 -223.091501) (xy 119.081504 -223.083376) (xy 119.032111 -223.067328)
			(xy 118.985837 -223.04375) (xy 118.943821 -223.013224) (xy 118.907098 -222.976501) (xy 118.876572 -222.934485)
			(xy 118.852994 -222.888211) (xy 118.836946 -222.838818) (xy 118.828821 -222.787523) (xy 118.548911 -222.787523)
			(xy 118.540786 -222.838818) (xy 118.524738 -222.888211) (xy 118.50116 -222.934485) (xy 118.470634 -222.976501)
			(xy 118.433911 -223.013224) (xy 118.391895 -223.04375) (xy 118.345621 -223.067328) (xy 118.296228 -223.083376)
			(xy 118.244933 -223.091501) (xy 118.192999 -223.091501) (xy 118.141704 -223.083376) (xy 118.092311 -223.067328)
			(xy 118.046037 -223.04375) (xy 118.004021 -223.013224) (xy 117.967298 -222.976501) (xy 117.936772 -222.934485)
			(xy 117.913194 -222.888211) (xy 117.897146 -222.838818) (xy 117.889021 -222.787523) (xy 117.609111 -222.787523)
			(xy 117.600986 -222.838818) (xy 117.584938 -222.888211) (xy 117.56136 -222.934485) (xy 117.530834 -222.976501)
			(xy 117.494111 -223.013224) (xy 117.452095 -223.04375) (xy 117.405821 -223.067328) (xy 117.356428 -223.083376)
			(xy 117.305133 -223.091501) (xy 117.253199 -223.091501) (xy 117.201904 -223.083376) (xy 117.152511 -223.067328)
			(xy 117.106237 -223.04375) (xy 117.064221 -223.013224) (xy 117.027498 -222.976501) (xy 116.996972 -222.934485)
			(xy 116.973394 -222.888211) (xy 116.957346 -222.838818) (xy 116.949221 -222.787523) (xy 116.669311 -222.787523)
			(xy 116.661186 -222.838818) (xy 116.645138 -222.888211) (xy 116.62156 -222.934485) (xy 116.591034 -222.976501)
			(xy 116.554311 -223.013224) (xy 116.512295 -223.04375) (xy 116.466021 -223.067328) (xy 116.416628 -223.083376)
			(xy 116.365333 -223.091501) (xy 116.313399 -223.091501) (xy 116.262104 -223.083376) (xy 116.212711 -223.067328)
			(xy 116.166437 -223.04375) (xy 116.124421 -223.013224) (xy 116.087698 -222.976501) (xy 116.057172 -222.934485)
			(xy 116.033594 -222.888211) (xy 116.017546 -222.838818) (xy 116.009421 -222.787523) (xy 115.729511 -222.787523)
			(xy 115.721386 -222.838818) (xy 115.705338 -222.888211) (xy 115.68176 -222.934485) (xy 115.651234 -222.976501)
			(xy 115.614511 -223.013224) (xy 115.572495 -223.04375) (xy 115.526221 -223.067328) (xy 115.476828 -223.083376)
			(xy 115.425533 -223.091501) (xy 115.373599 -223.091501) (xy 115.322304 -223.083376) (xy 115.272911 -223.067328)
			(xy 115.226637 -223.04375) (xy 115.184621 -223.013224) (xy 115.147898 -222.976501) (xy 115.117372 -222.934485)
			(xy 115.093794 -222.888211) (xy 115.077746 -222.838818) (xy 115.069621 -222.787523) (xy 114.789711 -222.787523)
			(xy 114.781586 -222.838818) (xy 114.765538 -222.888211) (xy 114.74196 -222.934485) (xy 114.711434 -222.976501)
			(xy 114.674711 -223.013224) (xy 114.632695 -223.04375) (xy 114.586421 -223.067328) (xy 114.537028 -223.083376)
			(xy 114.485733 -223.091501) (xy 114.433799 -223.091501) (xy 114.382504 -223.083376) (xy 114.333111 -223.067328)
			(xy 114.286837 -223.04375) (xy 114.244821 -223.013224) (xy 114.208098 -222.976501) (xy 114.177572 -222.934485)
			(xy 114.153994 -222.888211) (xy 114.137946 -222.838818) (xy 114.129821 -222.787523) (xy 113.849911 -222.787523)
			(xy 113.841786 -222.838818) (xy 113.825738 -222.888211) (xy 113.80216 -222.934485) (xy 113.771634 -222.976501)
			(xy 113.734911 -223.013224) (xy 113.692895 -223.04375) (xy 113.646621 -223.067328) (xy 113.597228 -223.083376)
			(xy 113.545933 -223.091501) (xy 113.493999 -223.091501) (xy 113.442704 -223.083376) (xy 113.393311 -223.067328)
			(xy 113.347037 -223.04375) (xy 113.305021 -223.013224) (xy 113.268298 -222.976501) (xy 113.237772 -222.934485)
			(xy 113.214194 -222.888211) (xy 113.198146 -222.838818) (xy 113.190021 -222.787523) (xy 112.910111 -222.787523)
			(xy 112.901986 -222.838818) (xy 112.885938 -222.888211) (xy 112.86236 -222.934485) (xy 112.831834 -222.976501)
			(xy 112.795111 -223.013224) (xy 112.753095 -223.04375) (xy 112.706821 -223.067328) (xy 112.657428 -223.083376)
			(xy 112.606133 -223.091501) (xy 112.554199 -223.091501) (xy 112.502904 -223.083376) (xy 112.453511 -223.067328)
			(xy 112.407237 -223.04375) (xy 112.365221 -223.013224) (xy 112.328498 -222.976501) (xy 112.297972 -222.934485)
			(xy 112.274394 -222.888211) (xy 112.258346 -222.838818) (xy 112.250221 -222.787523) (xy 111.970415 -222.787523)
			(xy 111.970415 -222.787574) (xy 111.962288 -222.838884) (xy 111.946234 -222.88829) (xy 111.922648 -222.934576)
			(xy 111.892111 -222.976602) (xy 111.855376 -223.013334) (xy 111.813347 -223.043866) (xy 111.767058 -223.067447)
			(xy 111.717651 -223.083496) (xy 111.66634 -223.091618) (xy 111.640366 -223.09201) (xy 111.63808 -223.09201)
			(xy 111.628022 -223.092381) (xy 111.609411 -223.100001) (xy 111.595153 -223.114184) (xy 111.587434 -223.132754)
			(xy 111.587026 -223.14281) (xy 111.587026 -223.601593) (xy 111.780321 -223.601593) (xy 111.780321 -223.549659)
			(xy 111.788446 -223.498364) (xy 111.804494 -223.448971) (xy 111.828072 -223.402697) (xy 111.858598 -223.360681)
			(xy 111.895321 -223.323958) (xy 111.937337 -223.293432) (xy 111.983611 -223.269854) (xy 112.033004 -223.253806)
			(xy 112.084299 -223.245681) (xy 112.136233 -223.245681) (xy 112.187528 -223.253806) (xy 112.236921 -223.269854)
			(xy 112.283195 -223.293432) (xy 112.325211 -223.323958) (xy 112.361934 -223.360681) (xy 112.39246 -223.402697)
			(xy 112.416038 -223.448971) (xy 112.432086 -223.498364) (xy 112.440211 -223.549659) (xy 112.44072 -223.575626)
			(xy 112.440211 -223.601593) (xy 112.432086 -223.652888) (xy 112.416038 -223.702281) (xy 112.39246 -223.748555)
			(xy 112.361934 -223.790571) (xy 112.325211 -223.827294) (xy 112.283195 -223.85782) (xy 112.236921 -223.881398)
			(xy 112.187528 -223.897446) (xy 112.136233 -223.905571) (xy 112.084299 -223.905571) (xy 112.033004 -223.897446)
			(xy 111.983611 -223.881398) (xy 111.937337 -223.85782) (xy 111.895321 -223.827294) (xy 111.858598 -223.790571)
			(xy 111.828072 -223.748555) (xy 111.804494 -223.702281) (xy 111.788446 -223.652888) (xy 111.780321 -223.601593)
			(xy 111.587026 -223.601593) (xy 111.587026 -224.008188) (xy 111.58745 -224.01824) (xy 111.595166 -224.036805)
			(xy 111.60942 -224.050984) (xy 111.628025 -224.058602) (xy 111.63808 -224.058988) (xy 111.640366 -224.058988)
			(xy 111.666336 -224.059468) (xy 111.717637 -224.067589) (xy 111.767035 -224.083637) (xy 111.813314 -224.107215)
			(xy 111.855335 -224.137744) (xy 111.892061 -224.174471) (xy 111.922589 -224.216493) (xy 111.946166 -224.262772)
			(xy 111.962212 -224.312171) (xy 111.970332 -224.363472) (xy 111.97082 -224.389442) (xy 112.249712 -224.389442)
			(xy 112.250174 -224.363991) (xy 112.25796 -224.313687) (xy 112.273368 -224.265174) (xy 112.296036 -224.219597)
			(xy 112.325425 -224.178036) (xy 112.360841 -224.141475) (xy 112.401446 -224.110778) (xy 112.446278 -224.086672)
			(xy 112.494277 -224.069728) (xy 112.519206 -224.064576) (xy 112.542066 -224.060258) (xy 112.745774 -223.707198)
			(xy 112.738154 -223.685354) (xy 112.729431 -223.658761) (xy 112.719974 -223.603606) (xy 112.719358 -223.575626)
			(xy 112.719867 -223.549659) (xy 112.727992 -223.498364) (xy 112.74404 -223.448971) (xy 112.767618 -223.402697)
			(xy 112.798144 -223.360681) (xy 112.834867 -223.323958) (xy 112.876883 -223.293432) (xy 112.923157 -223.269854)
			(xy 112.97255 -223.253806) (xy 113.023845 -223.245681) (xy 113.075779 -223.245681) (xy 113.127074 -223.253806)
			(xy 113.176467 -223.269854) (xy 113.222741 -223.293432) (xy 113.264757 -223.323958) (xy 113.30148 -223.360681)
			(xy 113.332006 -223.402697) (xy 113.355584 -223.448971) (xy 113.371632 -223.498364) (xy 113.379757 -223.549659)
			(xy 113.380266 -223.575626) (xy 113.379793 -223.601077) (xy 113.379713 -223.601593) (xy 113.659921 -223.601593)
			(xy 113.659921 -223.549659) (xy 113.668046 -223.498364) (xy 113.684094 -223.448971) (xy 113.707672 -223.402697)
			(xy 113.738198 -223.360681) (xy 113.774921 -223.323958) (xy 113.816937 -223.293432) (xy 113.863211 -223.269854)
			(xy 113.912604 -223.253806) (xy 113.963899 -223.245681) (xy 114.015833 -223.245681) (xy 114.067128 -223.253806)
			(xy 114.116521 -223.269854) (xy 114.162795 -223.293432) (xy 114.204811 -223.323958) (xy 114.241534 -223.360681)
			(xy 114.27206 -223.402697) (xy 114.295638 -223.448971) (xy 114.311686 -223.498364) (xy 114.319811 -223.549659)
			(xy 114.32032 -223.575626) (xy 114.319811 -223.601593) (xy 114.311686 -223.652888) (xy 114.295638 -223.702281)
			(xy 114.27206 -223.748555) (xy 114.241534 -223.790571) (xy 114.204811 -223.827294) (xy 114.162795 -223.85782)
			(xy 114.116521 -223.881398) (xy 114.067128 -223.897446) (xy 114.015833 -223.905571) (xy 113.963899 -223.905571)
			(xy 113.912604 -223.897446) (xy 113.863211 -223.881398) (xy 113.816937 -223.85782) (xy 113.774921 -223.827294)
			(xy 113.738198 -223.790571) (xy 113.707672 -223.748555) (xy 113.684094 -223.702281) (xy 113.668046 -223.652888)
			(xy 113.659921 -223.601593) (xy 113.379713 -223.601593) (xy 113.372011 -223.651381) (xy 113.356606 -223.699896)
			(xy 113.333941 -223.745473) (xy 113.304553 -223.787035) (xy 113.269137 -223.823597) (xy 113.228533 -223.854293)
			(xy 113.1837 -223.878398) (xy 113.135701 -223.895341) (xy 113.110772 -223.900492) (xy 113.087658 -223.90481)
			(xy 112.884204 -224.257616) (xy 112.891824 -224.279714) (xy 112.900566 -224.306301) (xy 112.91001 -224.361461)
			(xy 112.91062 -224.389442) (xy 113.189512 -224.389442) (xy 113.190021 -224.363475) (xy 113.198146 -224.31218)
			(xy 113.214194 -224.262787) (xy 113.237772 -224.216513) (xy 113.268298 -224.174497) (xy 113.305021 -224.137774)
			(xy 113.347037 -224.107248) (xy 113.393311 -224.08367) (xy 113.442704 -224.067622) (xy 113.493999 -224.059497)
			(xy 113.545933 -224.059497) (xy 113.597228 -224.067622) (xy 113.646621 -224.08367) (xy 113.692895 -224.107248)
			(xy 113.734911 -224.137774) (xy 113.771634 -224.174497) (xy 113.80216 -224.216513) (xy 113.825738 -224.262787)
			(xy 113.841786 -224.31218) (xy 113.849911 -224.363475) (xy 113.85042 -224.389442) (xy 114.129312 -224.389442)
			(xy 114.129774 -224.363991) (xy 114.13756 -224.313687) (xy 114.152968 -224.265174) (xy 114.175636 -224.219597)
			(xy 114.205025 -224.178036) (xy 114.240441 -224.141475) (xy 114.281046 -224.110778) (xy 114.325878 -224.086672)
			(xy 114.373877 -224.069728) (xy 114.398806 -224.064576) (xy 114.421666 -224.060258) (xy 114.625628 -223.706944)
			(xy 114.617754 -223.6851) (xy 114.609091 -223.658565) (xy 114.599773 -223.603534) (xy 114.599212 -223.575626)
			(xy 114.599721 -223.549659) (xy 114.607846 -223.498364) (xy 114.623894 -223.448971) (xy 114.647472 -223.402697)
			(xy 114.677998 -223.360681) (xy 114.714721 -223.323958) (xy 114.756737 -223.293432) (xy 114.803011 -223.269854)
			(xy 114.852404 -223.253806) (xy 114.903699 -223.245681) (xy 114.955633 -223.245681) (xy 115.006928 -223.253806)
			(xy 115.056321 -223.269854) (xy 115.102595 -223.293432) (xy 115.144611 -223.323958) (xy 115.181334 -223.360681)
			(xy 115.21186 -223.402697) (xy 115.235438 -223.448971) (xy 115.251486 -223.498364) (xy 115.259611 -223.549659)
			(xy 115.26012 -223.575626) (xy 115.259646 -223.601088) (xy 115.259568 -223.601593) (xy 115.539521 -223.601593)
			(xy 115.539521 -223.549659) (xy 115.547646 -223.498364) (xy 115.563694 -223.448971) (xy 115.587272 -223.402697)
			(xy 115.617798 -223.360681) (xy 115.654521 -223.323958) (xy 115.696537 -223.293432) (xy 115.742811 -223.269854)
			(xy 115.792204 -223.253806) (xy 115.843499 -223.245681) (xy 115.895433 -223.245681) (xy 115.946728 -223.253806)
			(xy 115.996121 -223.269854) (xy 116.042395 -223.293432) (xy 116.084411 -223.323958) (xy 116.121134 -223.360681)
			(xy 116.15166 -223.402697) (xy 116.175238 -223.448971) (xy 116.191286 -223.498364) (xy 116.199411 -223.549659)
			(xy 116.19992 -223.575626) (xy 116.199411 -223.601593) (xy 116.191286 -223.652888) (xy 116.175238 -223.702281)
			(xy 116.15166 -223.748555) (xy 116.121134 -223.790571) (xy 116.084411 -223.827294) (xy 116.042395 -223.85782)
			(xy 115.996121 -223.881398) (xy 115.946728 -223.897446) (xy 115.895433 -223.905571) (xy 115.843499 -223.905571)
			(xy 115.792204 -223.897446) (xy 115.742811 -223.881398) (xy 115.696537 -223.85782) (xy 115.654521 -223.827294)
			(xy 115.617798 -223.790571) (xy 115.587272 -223.748555) (xy 115.563694 -223.702281) (xy 115.547646 -223.652888)
			(xy 115.539521 -223.601593) (xy 115.259568 -223.601593) (xy 115.251844 -223.651411) (xy 115.236413 -223.699941)
			(xy 115.213719 -223.745529) (xy 115.184299 -223.787095) (xy 115.14885 -223.823656) (xy 115.108212 -223.854344)
			(xy 115.063346 -223.878434) (xy 115.015315 -223.895354) (xy 114.990372 -223.900492) (xy 114.967258 -223.90481)
			(xy 114.763804 -224.257616) (xy 114.771424 -224.279714) (xy 114.780166 -224.306301) (xy 114.78961 -224.361461)
			(xy 114.79022 -224.389442) (xy 115.069112 -224.389442) (xy 115.069621 -224.363475) (xy 115.077746 -224.31218)
			(xy 115.093794 -224.262787) (xy 115.117372 -224.216513) (xy 115.147898 -224.174497) (xy 115.184621 -224.137774)
			(xy 115.226637 -224.107248) (xy 115.272911 -224.08367) (xy 115.322304 -224.067622) (xy 115.373599 -224.059497)
			(xy 115.425533 -224.059497) (xy 115.476828 -224.067622) (xy 115.526221 -224.08367) (xy 115.572495 -224.107248)
			(xy 115.614511 -224.137774) (xy 115.651234 -224.174497) (xy 115.68176 -224.216513) (xy 115.705338 -224.262787)
			(xy 115.721386 -224.31218) (xy 115.729511 -224.363475) (xy 115.73002 -224.389442) (xy 116.008912 -224.389442)
			(xy 116.009374 -224.363991) (xy 116.01716 -224.313687) (xy 116.032568 -224.265174) (xy 116.055236 -224.219597)
			(xy 116.084625 -224.178036) (xy 116.120041 -224.141475) (xy 116.160646 -224.110778) (xy 116.205478 -224.086672)
			(xy 116.253477 -224.069728) (xy 116.278406 -224.064576) (xy 116.301266 -224.060258) (xy 116.504974 -223.707198)
			(xy 116.497354 -223.685354) (xy 116.488631 -223.658761) (xy 116.479174 -223.603606) (xy 116.478558 -223.575626)
			(xy 116.479067 -223.549659) (xy 116.487192 -223.498364) (xy 116.50324 -223.448971) (xy 116.526818 -223.402697)
			(xy 116.557344 -223.360681) (xy 116.594067 -223.323958) (xy 116.636083 -223.293432) (xy 116.682357 -223.269854)
			(xy 116.73175 -223.253806) (xy 116.783045 -223.245681) (xy 116.834979 -223.245681) (xy 116.886274 -223.253806)
			(xy 116.935667 -223.269854) (xy 116.981941 -223.293432) (xy 117.023957 -223.323958) (xy 117.06068 -223.360681)
			(xy 117.091206 -223.402697) (xy 117.114784 -223.448971) (xy 117.130832 -223.498364) (xy 117.138957 -223.549659)
			(xy 117.139466 -223.575626) (xy 117.138993 -223.601077) (xy 117.138913 -223.601593) (xy 117.419121 -223.601593)
			(xy 117.419121 -223.549659) (xy 117.427246 -223.498364) (xy 117.443294 -223.448971) (xy 117.466872 -223.402697)
			(xy 117.497398 -223.360681) (xy 117.534121 -223.323958) (xy 117.576137 -223.293432) (xy 117.622411 -223.269854)
			(xy 117.671804 -223.253806) (xy 117.723099 -223.245681) (xy 117.775033 -223.245681) (xy 117.826328 -223.253806)
			(xy 117.875721 -223.269854) (xy 117.921995 -223.293432) (xy 117.964011 -223.323958) (xy 118.000734 -223.360681)
			(xy 118.03126 -223.402697) (xy 118.054838 -223.448971) (xy 118.070886 -223.498364) (xy 118.079011 -223.549659)
			(xy 118.07952 -223.575626) (xy 118.079011 -223.601593) (xy 118.070886 -223.652888) (xy 118.054838 -223.702281)
			(xy 118.03126 -223.748555) (xy 118.000734 -223.790571) (xy 117.964011 -223.827294) (xy 117.921995 -223.85782)
			(xy 117.875721 -223.881398) (xy 117.826328 -223.897446) (xy 117.775033 -223.905571) (xy 117.723099 -223.905571)
			(xy 117.671804 -223.897446) (xy 117.622411 -223.881398) (xy 117.576137 -223.85782) (xy 117.534121 -223.827294)
			(xy 117.497398 -223.790571) (xy 117.466872 -223.748555) (xy 117.443294 -223.702281) (xy 117.427246 -223.652888)
			(xy 117.419121 -223.601593) (xy 117.138913 -223.601593) (xy 117.131211 -223.651381) (xy 117.115806 -223.699896)
			(xy 117.093141 -223.745473) (xy 117.063753 -223.787035) (xy 117.028337 -223.823597) (xy 116.987733 -223.854293)
			(xy 116.9429 -223.878398) (xy 116.894901 -223.895341) (xy 116.869972 -223.900492) (xy 116.846858 -223.90481)
			(xy 116.643404 -224.257616) (xy 116.651024 -224.279714) (xy 116.659766 -224.306301) (xy 116.66921 -224.361461)
			(xy 116.66982 -224.389442) (xy 116.948712 -224.389442) (xy 116.949221 -224.363475) (xy 116.957346 -224.31218)
			(xy 116.973394 -224.262787) (xy 116.996972 -224.216513) (xy 117.027498 -224.174497) (xy 117.064221 -224.137774)
			(xy 117.106237 -224.107248) (xy 117.152511 -224.08367) (xy 117.201904 -224.067622) (xy 117.253199 -224.059497)
			(xy 117.305133 -224.059497) (xy 117.356428 -224.067622) (xy 117.405821 -224.08367) (xy 117.452095 -224.107248)
			(xy 117.494111 -224.137774) (xy 117.530834 -224.174497) (xy 117.56136 -224.216513) (xy 117.584938 -224.262787)
			(xy 117.600986 -224.31218) (xy 117.609111 -224.363475) (xy 117.60962 -224.389442) (xy 117.888512 -224.389442)
			(xy 117.888974 -224.363991) (xy 117.89676 -224.313687) (xy 117.912168 -224.265174) (xy 117.934836 -224.219597)
			(xy 117.964225 -224.178036) (xy 117.999641 -224.141475) (xy 118.040246 -224.110778) (xy 118.085078 -224.086672)
			(xy 118.133077 -224.069728) (xy 118.158006 -224.064576) (xy 118.180866 -224.060258) (xy 118.384574 -223.707198)
			(xy 118.376954 -223.685354) (xy 118.368231 -223.658761) (xy 118.358774 -223.603606) (xy 118.358158 -223.575626)
			(xy 118.358667 -223.549659) (xy 118.366792 -223.498364) (xy 118.38284 -223.448971) (xy 118.406418 -223.402697)
			(xy 118.436944 -223.360681) (xy 118.473667 -223.323958) (xy 118.515683 -223.293432) (xy 118.561957 -223.269854)
			(xy 118.61135 -223.253806) (xy 118.662645 -223.245681) (xy 118.714579 -223.245681) (xy 118.765874 -223.253806)
			(xy 118.815267 -223.269854) (xy 118.861541 -223.293432) (xy 118.903557 -223.323958) (xy 118.94028 -223.360681)
			(xy 118.970806 -223.402697) (xy 118.994384 -223.448971) (xy 119.010432 -223.498364) (xy 119.018557 -223.549659)
			(xy 119.019066 -223.575626) (xy 119.018593 -223.601077) (xy 119.018513 -223.601593) (xy 119.298721 -223.601593)
			(xy 119.298721 -223.549659) (xy 119.306846 -223.498364) (xy 119.322894 -223.448971) (xy 119.346472 -223.402697)
			(xy 119.376998 -223.360681) (xy 119.413721 -223.323958) (xy 119.455737 -223.293432) (xy 119.502011 -223.269854)
			(xy 119.551404 -223.253806) (xy 119.602699 -223.245681) (xy 119.654633 -223.245681) (xy 119.705928 -223.253806)
			(xy 119.755321 -223.269854) (xy 119.801595 -223.293432) (xy 119.843611 -223.323958) (xy 119.880334 -223.360681)
			(xy 119.91086 -223.402697) (xy 119.934438 -223.448971) (xy 119.950486 -223.498364) (xy 119.958611 -223.549659)
			(xy 119.95912 -223.575626) (xy 119.958611 -223.601593) (xy 119.950486 -223.652888) (xy 119.934438 -223.702281)
			(xy 119.91086 -223.748555) (xy 119.880334 -223.790571) (xy 119.843611 -223.827294) (xy 119.801595 -223.85782)
			(xy 119.755321 -223.881398) (xy 119.705928 -223.897446) (xy 119.654633 -223.905571) (xy 119.602699 -223.905571)
			(xy 119.551404 -223.897446) (xy 119.502011 -223.881398) (xy 119.455737 -223.85782) (xy 119.413721 -223.827294)
			(xy 119.376998 -223.790571) (xy 119.346472 -223.748555) (xy 119.322894 -223.702281) (xy 119.306846 -223.652888)
			(xy 119.298721 -223.601593) (xy 119.018513 -223.601593) (xy 119.010811 -223.651381) (xy 118.995406 -223.699896)
			(xy 118.972741 -223.745473) (xy 118.943353 -223.787035) (xy 118.907937 -223.823597) (xy 118.867333 -223.854293)
			(xy 118.8225 -223.878398) (xy 118.774501 -223.895341) (xy 118.749572 -223.900492) (xy 118.726458 -223.90481)
			(xy 118.523004 -224.257616) (xy 118.530624 -224.279714) (xy 118.539366 -224.306301) (xy 118.54881 -224.361461)
			(xy 118.54942 -224.389442) (xy 118.828312 -224.389442) (xy 118.828821 -224.363475) (xy 118.836946 -224.31218)
			(xy 118.852994 -224.262787) (xy 118.876572 -224.216513) (xy 118.907098 -224.174497) (xy 118.943821 -224.137774)
			(xy 118.985837 -224.107248) (xy 119.032111 -224.08367) (xy 119.081504 -224.067622) (xy 119.132799 -224.059497)
			(xy 119.184733 -224.059497) (xy 119.236028 -224.067622) (xy 119.285421 -224.08367) (xy 119.331695 -224.107248)
			(xy 119.373711 -224.137774) (xy 119.410434 -224.174497) (xy 119.44096 -224.216513) (xy 119.464538 -224.262787)
			(xy 119.480586 -224.31218) (xy 119.488711 -224.363475) (xy 119.48922 -224.389442) (xy 119.768112 -224.389442)
			(xy 119.768574 -224.363991) (xy 119.77636 -224.313687) (xy 119.791768 -224.265174) (xy 119.814436 -224.219597)
			(xy 119.843825 -224.178036) (xy 119.879241 -224.141475) (xy 119.919846 -224.110778) (xy 119.964678 -224.086672)
			(xy 120.012677 -224.069728) (xy 120.037606 -224.064576) (xy 120.060466 -224.060258) (xy 120.264174 -223.707198)
			(xy 120.256554 -223.685354) (xy 120.247831 -223.658761) (xy 120.238374 -223.603606) (xy 120.237758 -223.575626)
			(xy 120.238267 -223.549659) (xy 120.246392 -223.498364) (xy 120.26244 -223.448971) (xy 120.286018 -223.402697)
			(xy 120.316544 -223.360681) (xy 120.353267 -223.323958) (xy 120.395283 -223.293432) (xy 120.441557 -223.269854)
			(xy 120.49095 -223.253806) (xy 120.542245 -223.245681) (xy 120.594179 -223.245681) (xy 120.645474 -223.253806)
			(xy 120.694867 -223.269854) (xy 120.741141 -223.293432) (xy 120.783157 -223.323958) (xy 120.81988 -223.360681)
			(xy 120.850406 -223.402697) (xy 120.873984 -223.448971) (xy 120.890032 -223.498364) (xy 120.898157 -223.549659)
			(xy 120.898666 -223.575626) (xy 120.898193 -223.601077) (xy 120.898113 -223.601593) (xy 121.178321 -223.601593)
			(xy 121.178321 -223.549659) (xy 121.186446 -223.498364) (xy 121.202494 -223.448971) (xy 121.226072 -223.402697)
			(xy 121.256598 -223.360681) (xy 121.293321 -223.323958) (xy 121.335337 -223.293432) (xy 121.381611 -223.269854)
			(xy 121.431004 -223.253806) (xy 121.482299 -223.245681) (xy 121.534233 -223.245681) (xy 121.585528 -223.253806)
			(xy 121.634921 -223.269854) (xy 121.681195 -223.293432) (xy 121.723211 -223.323958) (xy 121.759934 -223.360681)
			(xy 121.79046 -223.402697) (xy 121.814038 -223.448971) (xy 121.830086 -223.498364) (xy 121.838211 -223.549659)
			(xy 121.83872 -223.575626) (xy 121.838211 -223.601593) (xy 121.830086 -223.652888) (xy 121.814038 -223.702281)
			(xy 121.79046 -223.748555) (xy 121.759934 -223.790571) (xy 121.723211 -223.827294) (xy 121.681195 -223.85782)
			(xy 121.634921 -223.881398) (xy 121.585528 -223.897446) (xy 121.534233 -223.905571) (xy 121.482299 -223.905571)
			(xy 121.431004 -223.897446) (xy 121.381611 -223.881398) (xy 121.335337 -223.85782) (xy 121.293321 -223.827294)
			(xy 121.256598 -223.790571) (xy 121.226072 -223.748555) (xy 121.202494 -223.702281) (xy 121.186446 -223.652888)
			(xy 121.178321 -223.601593) (xy 120.898113 -223.601593) (xy 120.890411 -223.651381) (xy 120.875006 -223.699896)
			(xy 120.852341 -223.745473) (xy 120.822953 -223.787035) (xy 120.787537 -223.823597) (xy 120.746933 -223.854293)
			(xy 120.7021 -223.878398) (xy 120.654101 -223.895341) (xy 120.629172 -223.900492) (xy 120.606058 -223.90481)
			(xy 120.402604 -224.257616) (xy 120.410224 -224.279714) (xy 120.418966 -224.306301) (xy 120.42841 -224.361461)
			(xy 120.42902 -224.389442) (xy 120.707912 -224.389442) (xy 120.708421 -224.363475) (xy 120.716546 -224.31218)
			(xy 120.732594 -224.262787) (xy 120.756172 -224.216513) (xy 120.786698 -224.174497) (xy 120.823421 -224.137774)
			(xy 120.865437 -224.107248) (xy 120.911711 -224.08367) (xy 120.961104 -224.067622) (xy 121.012399 -224.059497)
			(xy 121.064333 -224.059497) (xy 121.115628 -224.067622) (xy 121.165021 -224.08367) (xy 121.211295 -224.107248)
			(xy 121.253311 -224.137774) (xy 121.290034 -224.174497) (xy 121.32056 -224.216513) (xy 121.344138 -224.262787)
			(xy 121.360186 -224.31218) (xy 121.368311 -224.363475) (xy 121.36882 -224.389442) (xy 121.647712 -224.389442)
			(xy 121.648174 -224.363991) (xy 121.65596 -224.313687) (xy 121.671368 -224.265174) (xy 121.694036 -224.219597)
			(xy 121.723425 -224.178036) (xy 121.758841 -224.141475) (xy 121.799446 -224.110778) (xy 121.844278 -224.086672)
			(xy 121.892277 -224.069728) (xy 121.917206 -224.064576) (xy 121.940066 -224.060258) (xy 122.143774 -223.707198)
			(xy 122.136154 -223.685354) (xy 122.127431 -223.658761) (xy 122.117974 -223.603606) (xy 122.117358 -223.575626)
			(xy 122.117867 -223.549659) (xy 122.125992 -223.498364) (xy 122.14204 -223.448971) (xy 122.165618 -223.402697)
			(xy 122.196144 -223.360681) (xy 122.232867 -223.323958) (xy 122.274883 -223.293432) (xy 122.321157 -223.269854)
			(xy 122.37055 -223.253806) (xy 122.421845 -223.245681) (xy 122.473779 -223.245681) (xy 122.525074 -223.253806)
			(xy 122.574467 -223.269854) (xy 122.620741 -223.293432) (xy 122.662757 -223.323958) (xy 122.69948 -223.360681)
			(xy 122.730006 -223.402697) (xy 122.753584 -223.448971) (xy 122.769632 -223.498364) (xy 122.777757 -223.549659)
			(xy 122.778266 -223.575626) (xy 122.777793 -223.601077) (xy 122.777713 -223.601593) (xy 123.057921 -223.601593)
			(xy 123.057921 -223.549659) (xy 123.066046 -223.498364) (xy 123.082094 -223.448971) (xy 123.105672 -223.402697)
			(xy 123.136198 -223.360681) (xy 123.172921 -223.323958) (xy 123.214937 -223.293432) (xy 123.261211 -223.269854)
			(xy 123.310604 -223.253806) (xy 123.361899 -223.245681) (xy 123.413833 -223.245681) (xy 123.465128 -223.253806)
			(xy 123.514521 -223.269854) (xy 123.560795 -223.293432) (xy 123.602811 -223.323958) (xy 123.639534 -223.360681)
			(xy 123.67006 -223.402697) (xy 123.693638 -223.448971) (xy 123.709686 -223.498364) (xy 123.717811 -223.549659)
			(xy 123.71832 -223.575626) (xy 123.717811 -223.601593) (xy 123.709686 -223.652888) (xy 123.693638 -223.702281)
			(xy 123.67006 -223.748555) (xy 123.639534 -223.790571) (xy 123.602811 -223.827294) (xy 123.560795 -223.85782)
			(xy 123.514521 -223.881398) (xy 123.465128 -223.897446) (xy 123.413833 -223.905571) (xy 123.361899 -223.905571)
			(xy 123.310604 -223.897446) (xy 123.261211 -223.881398) (xy 123.214937 -223.85782) (xy 123.172921 -223.827294)
			(xy 123.136198 -223.790571) (xy 123.105672 -223.748555) (xy 123.082094 -223.702281) (xy 123.066046 -223.652888)
			(xy 123.057921 -223.601593) (xy 122.777713 -223.601593) (xy 122.770011 -223.651381) (xy 122.754606 -223.699896)
			(xy 122.731941 -223.745473) (xy 122.702553 -223.787035) (xy 122.667137 -223.823597) (xy 122.626533 -223.854293)
			(xy 122.5817 -223.878398) (xy 122.533701 -223.895341) (xy 122.508772 -223.900492) (xy 122.485658 -223.90481)
			(xy 122.282204 -224.257616) (xy 122.289824 -224.279714) (xy 122.298566 -224.306301) (xy 122.30801 -224.361461)
			(xy 122.30862 -224.389442) (xy 122.587512 -224.389442) (xy 122.588021 -224.363475) (xy 122.596146 -224.31218)
			(xy 122.612194 -224.262787) (xy 122.635772 -224.216513) (xy 122.666298 -224.174497) (xy 122.703021 -224.137774)
			(xy 122.745037 -224.107248) (xy 122.791311 -224.08367) (xy 122.840704 -224.067622) (xy 122.891999 -224.059497)
			(xy 122.943933 -224.059497) (xy 122.995228 -224.067622) (xy 123.044621 -224.08367) (xy 123.090895 -224.107248)
			(xy 123.132911 -224.137774) (xy 123.169634 -224.174497) (xy 123.20016 -224.216513) (xy 123.223738 -224.262787)
			(xy 123.239786 -224.31218) (xy 123.247911 -224.363475) (xy 123.24842 -224.389442) (xy 123.527312 -224.389442)
			(xy 123.527774 -224.363991) (xy 123.53556 -224.313687) (xy 123.550968 -224.265174) (xy 123.573636 -224.219597)
			(xy 123.603025 -224.178036) (xy 123.638441 -224.141475) (xy 123.679046 -224.110778) (xy 123.723878 -224.086672)
			(xy 123.771877 -224.069728) (xy 123.796806 -224.064576) (xy 123.819666 -224.060258) (xy 124.023374 -223.707198)
			(xy 124.015754 -223.685354) (xy 124.007031 -223.658761) (xy 123.997574 -223.603606) (xy 123.996958 -223.575626)
			(xy 123.997467 -223.549659) (xy 124.005592 -223.498364) (xy 124.02164 -223.448971) (xy 124.045218 -223.402697)
			(xy 124.075744 -223.360681) (xy 124.112467 -223.323958) (xy 124.154483 -223.293432) (xy 124.200757 -223.269854)
			(xy 124.25015 -223.253806) (xy 124.301445 -223.245681) (xy 124.353379 -223.245681) (xy 124.404674 -223.253806)
			(xy 124.454067 -223.269854) (xy 124.500341 -223.293432) (xy 124.542357 -223.323958) (xy 124.57908 -223.360681)
			(xy 124.609606 -223.402697) (xy 124.633184 -223.448971) (xy 124.649232 -223.498364) (xy 124.657357 -223.549659)
			(xy 124.657866 -223.575626) (xy 124.657393 -223.601077) (xy 124.657313 -223.601593) (xy 124.937521 -223.601593)
			(xy 124.937521 -223.549659) (xy 124.945646 -223.498364) (xy 124.961694 -223.448971) (xy 124.985272 -223.402697)
			(xy 125.015798 -223.360681) (xy 125.052521 -223.323958) (xy 125.094537 -223.293432) (xy 125.140811 -223.269854)
			(xy 125.190204 -223.253806) (xy 125.241499 -223.245681) (xy 125.293433 -223.245681) (xy 125.344728 -223.253806)
			(xy 125.394121 -223.269854) (xy 125.440395 -223.293432) (xy 125.482411 -223.323958) (xy 125.519134 -223.360681)
			(xy 125.54966 -223.402697) (xy 125.573238 -223.448971) (xy 125.589286 -223.498364) (xy 125.597411 -223.549659)
			(xy 125.59792 -223.575626) (xy 125.597411 -223.601593) (xy 125.589286 -223.652888) (xy 125.573238 -223.702281)
			(xy 125.54966 -223.748555) (xy 125.519134 -223.790571) (xy 125.482411 -223.827294) (xy 125.440395 -223.85782)
			(xy 125.394121 -223.881398) (xy 125.344728 -223.897446) (xy 125.293433 -223.905571) (xy 125.241499 -223.905571)
			(xy 125.190204 -223.897446) (xy 125.140811 -223.881398) (xy 125.094537 -223.85782) (xy 125.052521 -223.827294)
			(xy 125.015798 -223.790571) (xy 124.985272 -223.748555) (xy 124.961694 -223.702281) (xy 124.945646 -223.652888)
			(xy 124.937521 -223.601593) (xy 124.657313 -223.601593) (xy 124.649611 -223.651381) (xy 124.634206 -223.699896)
			(xy 124.611541 -223.745473) (xy 124.582153 -223.787035) (xy 124.546737 -223.823597) (xy 124.506133 -223.854293)
			(xy 124.4613 -223.878398) (xy 124.413301 -223.895341) (xy 124.388372 -223.900492) (xy 124.365258 -223.90481)
			(xy 124.161804 -224.257616) (xy 124.169424 -224.279714) (xy 124.178166 -224.306301) (xy 124.18761 -224.361461)
			(xy 124.18822 -224.389442) (xy 124.467112 -224.389442) (xy 124.467621 -224.363475) (xy 124.475746 -224.31218)
			(xy 124.491794 -224.262787) (xy 124.515372 -224.216513) (xy 124.545898 -224.174497) (xy 124.582621 -224.137774)
			(xy 124.624637 -224.107248) (xy 124.670911 -224.08367) (xy 124.720304 -224.067622) (xy 124.771599 -224.059497)
			(xy 124.823533 -224.059497) (xy 124.874828 -224.067622) (xy 124.924221 -224.08367) (xy 124.970495 -224.107248)
			(xy 125.012511 -224.137774) (xy 125.049234 -224.174497) (xy 125.07976 -224.216513) (xy 125.103338 -224.262787)
			(xy 125.119386 -224.31218) (xy 125.127511 -224.363475) (xy 125.12802 -224.389442) (xy 125.406912 -224.389442)
			(xy 125.407374 -224.363991) (xy 125.41516 -224.313687) (xy 125.430568 -224.265174) (xy 125.453236 -224.219597)
			(xy 125.482625 -224.178036) (xy 125.518041 -224.141475) (xy 125.558646 -224.110778) (xy 125.603478 -224.086672)
			(xy 125.651477 -224.069728) (xy 125.676406 -224.064576) (xy 125.699266 -224.060258) (xy 125.902974 -223.707198)
			(xy 125.895354 -223.685354) (xy 125.886631 -223.658761) (xy 125.877174 -223.603606) (xy 125.876558 -223.575626)
			(xy 125.877067 -223.549659) (xy 125.885192 -223.498364) (xy 125.90124 -223.448971) (xy 125.924818 -223.402697)
			(xy 125.955344 -223.360681) (xy 125.992067 -223.323958) (xy 126.034083 -223.293432) (xy 126.080357 -223.269854)
			(xy 126.12975 -223.253806) (xy 126.181045 -223.245681) (xy 126.232979 -223.245681) (xy 126.284274 -223.253806)
			(xy 126.333667 -223.269854) (xy 126.379941 -223.293432) (xy 126.421957 -223.323958) (xy 126.45868 -223.360681)
			(xy 126.489206 -223.402697) (xy 126.512784 -223.448971) (xy 126.528832 -223.498364) (xy 126.536957 -223.549659)
			(xy 126.537466 -223.575626) (xy 126.536993 -223.601077) (xy 126.536913 -223.601593) (xy 126.817121 -223.601593)
			(xy 126.817121 -223.549659) (xy 126.825246 -223.498364) (xy 126.841294 -223.448971) (xy 126.864872 -223.402697)
			(xy 126.895398 -223.360681) (xy 126.932121 -223.323958) (xy 126.974137 -223.293432) (xy 127.020411 -223.269854)
			(xy 127.069804 -223.253806) (xy 127.121099 -223.245681) (xy 127.173033 -223.245681) (xy 127.224328 -223.253806)
			(xy 127.273721 -223.269854) (xy 127.319995 -223.293432) (xy 127.362011 -223.323958) (xy 127.398734 -223.360681)
			(xy 127.42926 -223.402697) (xy 127.452838 -223.448971) (xy 127.468886 -223.498364) (xy 127.477011 -223.549659)
			(xy 127.47752 -223.575626) (xy 127.477011 -223.601593) (xy 127.468886 -223.652888) (xy 127.452838 -223.702281)
			(xy 127.42926 -223.748555) (xy 127.398734 -223.790571) (xy 127.362011 -223.827294) (xy 127.319995 -223.85782)
			(xy 127.273721 -223.881398) (xy 127.224328 -223.897446) (xy 127.173033 -223.905571) (xy 127.121099 -223.905571)
			(xy 127.069804 -223.897446) (xy 127.020411 -223.881398) (xy 126.974137 -223.85782) (xy 126.932121 -223.827294)
			(xy 126.895398 -223.790571) (xy 126.864872 -223.748555) (xy 126.841294 -223.702281) (xy 126.825246 -223.652888)
			(xy 126.817121 -223.601593) (xy 126.536913 -223.601593) (xy 126.529211 -223.651381) (xy 126.513806 -223.699896)
			(xy 126.491141 -223.745473) (xy 126.461753 -223.787035) (xy 126.426337 -223.823597) (xy 126.385733 -223.854293)
			(xy 126.3409 -223.878398) (xy 126.292901 -223.895341) (xy 126.267972 -223.900492) (xy 126.244858 -223.90481)
			(xy 126.041404 -224.257616) (xy 126.049024 -224.279714) (xy 126.057766 -224.306301) (xy 126.06721 -224.361461)
			(xy 126.06782 -224.389442) (xy 126.346712 -224.389442) (xy 126.347221 -224.363475) (xy 126.355346 -224.31218)
			(xy 126.371394 -224.262787) (xy 126.394972 -224.216513) (xy 126.425498 -224.174497) (xy 126.462221 -224.137774)
			(xy 126.504237 -224.107248) (xy 126.550511 -224.08367) (xy 126.599904 -224.067622) (xy 126.651199 -224.059497)
			(xy 126.703133 -224.059497) (xy 126.754428 -224.067622) (xy 126.803821 -224.08367) (xy 126.850095 -224.107248)
			(xy 126.892111 -224.137774) (xy 126.928834 -224.174497) (xy 126.95936 -224.216513) (xy 126.982938 -224.262787)
			(xy 126.998986 -224.31218) (xy 127.007111 -224.363475) (xy 127.00762 -224.389442) (xy 127.286512 -224.389442)
			(xy 127.286974 -224.363991) (xy 127.29476 -224.313687) (xy 127.310168 -224.265174) (xy 127.332836 -224.219597)
			(xy 127.362225 -224.178036) (xy 127.397641 -224.141475) (xy 127.438246 -224.110778) (xy 127.483078 -224.086672)
			(xy 127.531077 -224.069728) (xy 127.556006 -224.064576) (xy 127.578866 -224.060258) (xy 127.782574 -223.707198)
			(xy 127.774954 -223.685354) (xy 127.766231 -223.658761) (xy 127.756774 -223.603606) (xy 127.756158 -223.575626)
			(xy 127.756667 -223.549659) (xy 127.764792 -223.498364) (xy 127.78084 -223.448971) (xy 127.804418 -223.402697)
			(xy 127.834944 -223.360681) (xy 127.871667 -223.323958) (xy 127.913683 -223.293432) (xy 127.959957 -223.269854)
			(xy 128.00935 -223.253806) (xy 128.060645 -223.245681) (xy 128.112579 -223.245681) (xy 128.163874 -223.253806)
			(xy 128.213267 -223.269854) (xy 128.259541 -223.293432) (xy 128.301557 -223.323958) (xy 128.33828 -223.360681)
			(xy 128.368806 -223.402697) (xy 128.392384 -223.448971) (xy 128.408432 -223.498364) (xy 128.416557 -223.549659)
			(xy 128.417066 -223.575626) (xy 128.416593 -223.601077) (xy 128.416513 -223.601593) (xy 128.696721 -223.601593)
			(xy 128.696721 -223.549659) (xy 128.704846 -223.498364) (xy 128.720894 -223.448971) (xy 128.744472 -223.402697)
			(xy 128.774998 -223.360681) (xy 128.811721 -223.323958) (xy 128.853737 -223.293432) (xy 128.900011 -223.269854)
			(xy 128.949404 -223.253806) (xy 129.000699 -223.245681) (xy 129.052633 -223.245681) (xy 129.103928 -223.253806)
			(xy 129.153321 -223.269854) (xy 129.199595 -223.293432) (xy 129.241611 -223.323958) (xy 129.278334 -223.360681)
			(xy 129.30886 -223.402697) (xy 129.332438 -223.448971) (xy 129.348486 -223.498364) (xy 129.356611 -223.549659)
			(xy 129.35712 -223.575626) (xy 129.356611 -223.601593) (xy 129.348486 -223.652888) (xy 129.332438 -223.702281)
			(xy 129.30886 -223.748555) (xy 129.278334 -223.790571) (xy 129.241611 -223.827294) (xy 129.199595 -223.85782)
			(xy 129.153321 -223.881398) (xy 129.103928 -223.897446) (xy 129.052633 -223.905571) (xy 129.000699 -223.905571)
			(xy 128.949404 -223.897446) (xy 128.900011 -223.881398) (xy 128.853737 -223.85782) (xy 128.811721 -223.827294)
			(xy 128.774998 -223.790571) (xy 128.744472 -223.748555) (xy 128.720894 -223.702281) (xy 128.704846 -223.652888)
			(xy 128.696721 -223.601593) (xy 128.416513 -223.601593) (xy 128.408811 -223.651381) (xy 128.393406 -223.699896)
			(xy 128.370741 -223.745473) (xy 128.341353 -223.787035) (xy 128.305937 -223.823597) (xy 128.265333 -223.854293)
			(xy 128.2205 -223.878398) (xy 128.172501 -223.895341) (xy 128.147572 -223.900492) (xy 128.124458 -223.90481)
			(xy 127.921004 -224.257616) (xy 127.928624 -224.279714) (xy 127.937366 -224.306301) (xy 127.94681 -224.361461)
			(xy 127.94742 -224.389442) (xy 128.226312 -224.389442) (xy 128.226821 -224.363475) (xy 128.234946 -224.31218)
			(xy 128.250994 -224.262787) (xy 128.274572 -224.216513) (xy 128.305098 -224.174497) (xy 128.341821 -224.137774)
			(xy 128.383837 -224.107248) (xy 128.430111 -224.08367) (xy 128.479504 -224.067622) (xy 128.530799 -224.059497)
			(xy 128.582733 -224.059497) (xy 128.634028 -224.067622) (xy 128.683421 -224.08367) (xy 128.729695 -224.107248)
			(xy 128.771711 -224.137774) (xy 128.808434 -224.174497) (xy 128.83896 -224.216513) (xy 128.862538 -224.262787)
			(xy 128.878586 -224.31218) (xy 128.886711 -224.363475) (xy 128.88722 -224.389442) (xy 129.166112 -224.389442)
			(xy 129.166574 -224.363991) (xy 129.17436 -224.313687) (xy 129.189768 -224.265174) (xy 129.212436 -224.219597)
			(xy 129.241825 -224.178036) (xy 129.277241 -224.141475) (xy 129.317846 -224.110778) (xy 129.362678 -224.086672)
			(xy 129.410677 -224.069728) (xy 129.435606 -224.064576) (xy 129.458466 -224.060258) (xy 129.662174 -223.707198)
			(xy 129.654554 -223.685354) (xy 129.645831 -223.658761) (xy 129.636374 -223.603606) (xy 129.635758 -223.575626)
			(xy 129.636267 -223.549659) (xy 129.644392 -223.498364) (xy 129.66044 -223.448971) (xy 129.684018 -223.402697)
			(xy 129.714544 -223.360681) (xy 129.751267 -223.323958) (xy 129.793283 -223.293432) (xy 129.839557 -223.269854)
			(xy 129.88895 -223.253806) (xy 129.940245 -223.245681) (xy 129.992179 -223.245681) (xy 130.043474 -223.253806)
			(xy 130.092867 -223.269854) (xy 130.139141 -223.293432) (xy 130.181157 -223.323958) (xy 130.21788 -223.360681)
			(xy 130.248406 -223.402697) (xy 130.271984 -223.448971) (xy 130.288032 -223.498364) (xy 130.296157 -223.549659)
			(xy 130.296666 -223.575626) (xy 130.296193 -223.601077) (xy 130.296113 -223.601593) (xy 130.576321 -223.601593)
			(xy 130.576321 -223.549659) (xy 130.584446 -223.498364) (xy 130.600494 -223.448971) (xy 130.624072 -223.402697)
			(xy 130.654598 -223.360681) (xy 130.691321 -223.323958) (xy 130.733337 -223.293432) (xy 130.779611 -223.269854)
			(xy 130.829004 -223.253806) (xy 130.880299 -223.245681) (xy 130.932233 -223.245681) (xy 130.983528 -223.253806)
			(xy 131.032921 -223.269854) (xy 131.079195 -223.293432) (xy 131.121211 -223.323958) (xy 131.157934 -223.360681)
			(xy 131.18846 -223.402697) (xy 131.212038 -223.448971) (xy 131.228086 -223.498364) (xy 131.236211 -223.549659)
			(xy 131.23672 -223.575626) (xy 131.236211 -223.601593) (xy 131.228086 -223.652888) (xy 131.212038 -223.702281)
			(xy 131.18846 -223.748555) (xy 131.157934 -223.790571) (xy 131.121211 -223.827294) (xy 131.079195 -223.85782)
			(xy 131.032921 -223.881398) (xy 130.983528 -223.897446) (xy 130.932233 -223.905571) (xy 130.880299 -223.905571)
			(xy 130.829004 -223.897446) (xy 130.779611 -223.881398) (xy 130.733337 -223.85782) (xy 130.691321 -223.827294)
			(xy 130.654598 -223.790571) (xy 130.624072 -223.748555) (xy 130.600494 -223.702281) (xy 130.584446 -223.652888)
			(xy 130.576321 -223.601593) (xy 130.296113 -223.601593) (xy 130.288411 -223.651381) (xy 130.273006 -223.699896)
			(xy 130.250341 -223.745473) (xy 130.220953 -223.787035) (xy 130.185537 -223.823597) (xy 130.144933 -223.854293)
			(xy 130.1001 -223.878398) (xy 130.052101 -223.895341) (xy 130.027172 -223.900492) (xy 130.004058 -223.90481)
			(xy 129.800604 -224.257616) (xy 129.808224 -224.279714) (xy 129.816966 -224.306301) (xy 129.82641 -224.361461)
			(xy 129.82702 -224.389442) (xy 130.105912 -224.389442) (xy 130.106421 -224.363475) (xy 130.114546 -224.31218)
			(xy 130.130594 -224.262787) (xy 130.154172 -224.216513) (xy 130.184698 -224.174497) (xy 130.221421 -224.137774)
			(xy 130.263437 -224.107248) (xy 130.309711 -224.08367) (xy 130.359104 -224.067622) (xy 130.410399 -224.059497)
			(xy 130.462333 -224.059497) (xy 130.513628 -224.067622) (xy 130.563021 -224.08367) (xy 130.609295 -224.107248)
			(xy 130.651311 -224.137774) (xy 130.688034 -224.174497) (xy 130.71856 -224.216513) (xy 130.742138 -224.262787)
			(xy 130.758186 -224.31218) (xy 130.766311 -224.363475) (xy 130.76682 -224.389442) (xy 131.045712 -224.389442)
			(xy 131.046174 -224.363991) (xy 131.05396 -224.313687) (xy 131.069368 -224.265174) (xy 131.092036 -224.219597)
			(xy 131.121425 -224.178036) (xy 131.156841 -224.141475) (xy 131.197446 -224.110778) (xy 131.242278 -224.086672)
			(xy 131.290277 -224.069728) (xy 131.315206 -224.064576) (xy 131.33832 -224.060258) (xy 131.541774 -223.707198)
			(xy 131.534154 -223.6851) (xy 131.525408 -223.658579) (xy 131.515959 -223.603545) (xy 131.515358 -223.575626)
			(xy 131.515867 -223.549659) (xy 131.523992 -223.498364) (xy 131.54004 -223.448971) (xy 131.563618 -223.402697)
			(xy 131.594144 -223.360681) (xy 131.630867 -223.323958) (xy 131.672883 -223.293432) (xy 131.719157 -223.269854)
			(xy 131.76855 -223.253806) (xy 131.819845 -223.245681) (xy 131.871779 -223.245681) (xy 131.923074 -223.253806)
			(xy 131.972467 -223.269854) (xy 132.018741 -223.293432) (xy 132.060757 -223.323958) (xy 132.09748 -223.360681)
			(xy 132.128006 -223.402697) (xy 132.151584 -223.448971) (xy 132.167632 -223.498364) (xy 132.175757 -223.549659)
			(xy 132.176266 -223.575626) (xy 132.175793 -223.601077) (xy 132.175713 -223.601593) (xy 132.455921 -223.601593)
			(xy 132.455921 -223.549659) (xy 132.464046 -223.498364) (xy 132.480094 -223.448971) (xy 132.503672 -223.402697)
			(xy 132.534198 -223.360681) (xy 132.570921 -223.323958) (xy 132.612937 -223.293432) (xy 132.659211 -223.269854)
			(xy 132.708604 -223.253806) (xy 132.759899 -223.245681) (xy 132.811833 -223.245681) (xy 132.863128 -223.253806)
			(xy 132.912521 -223.269854) (xy 132.958795 -223.293432) (xy 133.000811 -223.323958) (xy 133.037534 -223.360681)
			(xy 133.06806 -223.402697) (xy 133.091638 -223.448971) (xy 133.107686 -223.498364) (xy 133.115811 -223.549659)
			(xy 133.11632 -223.575626) (xy 133.115811 -223.601593) (xy 133.107686 -223.652888) (xy 133.091638 -223.702281)
			(xy 133.06806 -223.748555) (xy 133.037534 -223.790571) (xy 133.000811 -223.827294) (xy 132.958795 -223.85782)
			(xy 132.912521 -223.881398) (xy 132.863128 -223.897446) (xy 132.811833 -223.905571) (xy 132.759899 -223.905571)
			(xy 132.708604 -223.897446) (xy 132.659211 -223.881398) (xy 132.612937 -223.85782) (xy 132.570921 -223.827294)
			(xy 132.534198 -223.790571) (xy 132.503672 -223.748555) (xy 132.480094 -223.702281) (xy 132.464046 -223.652888)
			(xy 132.455921 -223.601593) (xy 132.175713 -223.601593) (xy 132.168011 -223.651381) (xy 132.152606 -223.699896)
			(xy 132.129941 -223.745473) (xy 132.100553 -223.787035) (xy 132.065137 -223.823597) (xy 132.024533 -223.854293)
			(xy 131.9797 -223.878398) (xy 131.931701 -223.895341) (xy 131.906772 -223.900492) (xy 131.883658 -223.90481)
			(xy 131.680204 -224.257616) (xy 131.687824 -224.279714) (xy 131.696566 -224.306301) (xy 131.70601 -224.361461)
			(xy 131.70662 -224.389442) (xy 131.985512 -224.389442) (xy 131.986021 -224.363475) (xy 131.994146 -224.31218)
			(xy 132.010194 -224.262787) (xy 132.033772 -224.216513) (xy 132.064298 -224.174497) (xy 132.101021 -224.137774)
			(xy 132.143037 -224.107248) (xy 132.189311 -224.08367) (xy 132.238704 -224.067622) (xy 132.289999 -224.059497)
			(xy 132.341933 -224.059497) (xy 132.393228 -224.067622) (xy 132.442621 -224.08367) (xy 132.488895 -224.107248)
			(xy 132.530911 -224.137774) (xy 132.567634 -224.174497) (xy 132.59816 -224.216513) (xy 132.621738 -224.262787)
			(xy 132.637786 -224.31218) (xy 132.645911 -224.363475) (xy 132.64642 -224.389442) (xy 132.925312 -224.389442)
			(xy 132.925774 -224.363991) (xy 132.93356 -224.313687) (xy 132.948968 -224.265174) (xy 132.971636 -224.219597)
			(xy 133.001025 -224.178036) (xy 133.036441 -224.141475) (xy 133.077046 -224.110778) (xy 133.121878 -224.086672)
			(xy 133.169877 -224.069728) (xy 133.194806 -224.064576) (xy 133.21792 -224.060258) (xy 133.421628 -223.706944)
			(xy 133.413754 -223.6851) (xy 133.405091 -223.658565) (xy 133.395773 -223.603534) (xy 133.395212 -223.575626)
			(xy 133.395721 -223.549659) (xy 133.403846 -223.498364) (xy 133.419894 -223.448971) (xy 133.443472 -223.402697)
			(xy 133.473998 -223.360681) (xy 133.510721 -223.323958) (xy 133.552737 -223.293432) (xy 133.599011 -223.269854)
			(xy 133.648404 -223.253806) (xy 133.699699 -223.245681) (xy 133.751633 -223.245681) (xy 133.802928 -223.253806)
			(xy 133.852321 -223.269854) (xy 133.898595 -223.293432) (xy 133.940611 -223.323958) (xy 133.977334 -223.360681)
			(xy 134.00786 -223.402697) (xy 134.031438 -223.448971) (xy 134.047486 -223.498364) (xy 134.055611 -223.549659)
			(xy 134.05612 -223.575626) (xy 134.055646 -223.601088) (xy 134.047844 -223.651411) (xy 134.032413 -223.699941)
			(xy 134.009719 -223.745529) (xy 133.980299 -223.787095) (xy 133.94485 -223.823656) (xy 133.904212 -223.854344)
			(xy 133.859346 -223.878434) (xy 133.811315 -223.895354) (xy 133.786372 -223.900492) (xy 133.763258 -223.90481)
			(xy 133.559804 -224.257616) (xy 133.567424 -224.279714) (xy 133.576166 -224.306301) (xy 133.58561 -224.361461)
			(xy 133.58622 -224.389442) (xy 133.585711 -224.415409) (xy 133.577586 -224.466704) (xy 133.561538 -224.516097)
			(xy 133.53796 -224.562371) (xy 133.507434 -224.604387) (xy 133.470711 -224.64111) (xy 133.428695 -224.671636)
			(xy 133.382421 -224.695214) (xy 133.333028 -224.711262) (xy 133.281733 -224.719387) (xy 133.229799 -224.719387)
			(xy 133.178504 -224.711262) (xy 133.129111 -224.695214) (xy 133.082837 -224.671636) (xy 133.040821 -224.64111)
			(xy 133.004098 -224.604387) (xy 132.973572 -224.562371) (xy 132.949994 -224.516097) (xy 132.933946 -224.466704)
			(xy 132.925821 -224.415409) (xy 132.925312 -224.389442) (xy 132.64642 -224.389442) (xy 132.645877 -224.417428)
			(xy 132.63642 -224.472596) (xy 132.627624 -224.49917) (xy 132.620004 -224.521268) (xy 132.823712 -224.874074)
			(xy 132.846572 -224.878392) (xy 132.871504 -224.883512) (xy 132.91949 -224.900483) (xy 132.964309 -224.924607)
			(xy 133.004902 -224.955314) (xy 133.040309 -224.991878) (xy 133.069696 -225.033436) (xy 133.092368 -225.079006)
			(xy 133.107789 -225.127512) (xy 133.115594 -225.177809) (xy 133.116066 -225.203258) (xy 133.115557 -225.229225)
			(xy 133.107432 -225.28052) (xy 133.091384 -225.329913) (xy 133.067806 -225.376187) (xy 133.03728 -225.418203)
			(xy 133.000557 -225.454926) (xy 132.958541 -225.485452) (xy 132.912267 -225.50903) (xy 132.862874 -225.525078)
			(xy 132.811579 -225.533203) (xy 132.759645 -225.533203) (xy 132.70835 -225.525078) (xy 132.658957 -225.50903)
			(xy 132.612683 -225.485452) (xy 132.570667 -225.454926) (xy 132.533944 -225.418203) (xy 132.503418 -225.376187)
			(xy 132.47984 -225.329913) (xy 132.463792 -225.28052) (xy 132.455667 -225.229225) (xy 132.455158 -225.203258)
			(xy 132.455697 -225.175271) (xy 132.465156 -225.120104) (xy 132.473954 -225.09353) (xy 132.481574 -225.071432)
			(xy 132.277866 -224.718626) (xy 132.255006 -224.714308) (xy 132.230086 -224.709131) (xy 132.1821 -224.692171)
			(xy 132.13728 -224.668057) (xy 132.096685 -224.637359) (xy 132.061275 -224.600802) (xy 132.031886 -224.55925)
			(xy 132.009212 -224.513684) (xy 131.99379 -224.465182) (xy 131.985984 -224.414889) (xy 131.985512 -224.389442)
			(xy 131.70662 -224.389442) (xy 131.706111 -224.415409) (xy 131.697986 -224.466704) (xy 131.681938 -224.516097)
			(xy 131.65836 -224.562371) (xy 131.627834 -224.604387) (xy 131.591111 -224.64111) (xy 131.549095 -224.671636)
			(xy 131.502821 -224.695214) (xy 131.453428 -224.711262) (xy 131.402133 -224.719387) (xy 131.350199 -224.719387)
			(xy 131.298904 -224.711262) (xy 131.249511 -224.695214) (xy 131.203237 -224.671636) (xy 131.161221 -224.64111)
			(xy 131.124498 -224.604387) (xy 131.093972 -224.562371) (xy 131.070394 -224.516097) (xy 131.054346 -224.466704)
			(xy 131.046221 -224.415409) (xy 131.045712 -224.389442) (xy 130.76682 -224.389442) (xy 130.766277 -224.417428)
			(xy 130.75682 -224.472596) (xy 130.748024 -224.49917) (xy 130.740404 -224.521268) (xy 130.944112 -224.874074)
			(xy 130.966972 -224.878392) (xy 130.991904 -224.883512) (xy 131.03989 -224.900483) (xy 131.084709 -224.924607)
			(xy 131.125302 -224.955314) (xy 131.160709 -224.991878) (xy 131.190096 -225.033436) (xy 131.212768 -225.079006)
			(xy 131.228189 -225.127512) (xy 131.235994 -225.177809) (xy 131.236466 -225.203258) (xy 131.235957 -225.229225)
			(xy 131.515867 -225.229225) (xy 131.515867 -225.177291) (xy 131.523992 -225.125996) (xy 131.54004 -225.076603)
			(xy 131.563618 -225.030329) (xy 131.594144 -224.988313) (xy 131.630867 -224.95159) (xy 131.672883 -224.921064)
			(xy 131.719157 -224.897486) (xy 131.76855 -224.881438) (xy 131.819845 -224.873313) (xy 131.871779 -224.873313)
			(xy 131.923074 -224.881438) (xy 131.972467 -224.897486) (xy 132.018741 -224.921064) (xy 132.060757 -224.95159)
			(xy 132.09748 -224.988313) (xy 132.128006 -225.030329) (xy 132.151584 -225.076603) (xy 132.167632 -225.125996)
			(xy 132.175757 -225.177291) (xy 132.176266 -225.203258) (xy 132.175757 -225.229225) (xy 132.167632 -225.28052)
			(xy 132.151584 -225.329913) (xy 132.128006 -225.376187) (xy 132.09748 -225.418203) (xy 132.060757 -225.454926)
			(xy 132.018741 -225.485452) (xy 131.972467 -225.50903) (xy 131.923074 -225.525078) (xy 131.871779 -225.533203)
			(xy 131.819845 -225.533203) (xy 131.76855 -225.525078) (xy 131.719157 -225.50903) (xy 131.672883 -225.485452)
			(xy 131.630867 -225.454926) (xy 131.594144 -225.418203) (xy 131.563618 -225.376187) (xy 131.54004 -225.329913)
			(xy 131.523992 -225.28052) (xy 131.515867 -225.229225) (xy 131.235957 -225.229225) (xy 131.227832 -225.28052)
			(xy 131.211784 -225.329913) (xy 131.188206 -225.376187) (xy 131.15768 -225.418203) (xy 131.120957 -225.454926)
			(xy 131.078941 -225.485452) (xy 131.032667 -225.50903) (xy 130.983274 -225.525078) (xy 130.931979 -225.533203)
			(xy 130.880045 -225.533203) (xy 130.82875 -225.525078) (xy 130.779357 -225.50903) (xy 130.733083 -225.485452)
			(xy 130.691067 -225.454926) (xy 130.654344 -225.418203) (xy 130.623818 -225.376187) (xy 130.60024 -225.329913)
			(xy 130.584192 -225.28052) (xy 130.576067 -225.229225) (xy 130.575558 -225.203258) (xy 130.576097 -225.175271)
			(xy 130.585556 -225.120104) (xy 130.594354 -225.09353) (xy 130.601974 -225.071432) (xy 130.398266 -224.718626)
			(xy 130.375406 -224.714308) (xy 130.350486 -224.709131) (xy 130.3025 -224.692171) (xy 130.25768 -224.668057)
			(xy 130.217085 -224.637359) (xy 130.181675 -224.600802) (xy 130.152286 -224.55925) (xy 130.129612 -224.513684)
			(xy 130.11419 -224.465182) (xy 130.106384 -224.414889) (xy 130.105912 -224.389442) (xy 129.82702 -224.389442)
			(xy 129.826511 -224.415409) (xy 129.818386 -224.466704) (xy 129.802338 -224.516097) (xy 129.77876 -224.562371)
			(xy 129.748234 -224.604387) (xy 129.711511 -224.64111) (xy 129.669495 -224.671636) (xy 129.623221 -224.695214)
			(xy 129.573828 -224.711262) (xy 129.522533 -224.719387) (xy 129.470599 -224.719387) (xy 129.419304 -224.711262)
			(xy 129.369911 -224.695214) (xy 129.323637 -224.671636) (xy 129.281621 -224.64111) (xy 129.244898 -224.604387)
			(xy 129.214372 -224.562371) (xy 129.190794 -224.516097) (xy 129.174746 -224.466704) (xy 129.166621 -224.415409)
			(xy 129.166112 -224.389442) (xy 128.88722 -224.389442) (xy 128.886677 -224.417428) (xy 128.87722 -224.472596)
			(xy 128.868424 -224.49917) (xy 128.860804 -224.521268) (xy 129.064512 -224.874074) (xy 129.087372 -224.878392)
			(xy 129.112304 -224.883512) (xy 129.16029 -224.900483) (xy 129.205109 -224.924607) (xy 129.245702 -224.955314)
			(xy 129.281109 -224.991878) (xy 129.310496 -225.033436) (xy 129.333168 -225.079006) (xy 129.348589 -225.127512)
			(xy 129.356394 -225.177809) (xy 129.356866 -225.203258) (xy 129.356357 -225.229225) (xy 129.636267 -225.229225)
			(xy 129.636267 -225.177291) (xy 129.644392 -225.125996) (xy 129.66044 -225.076603) (xy 129.684018 -225.030329)
			(xy 129.714544 -224.988313) (xy 129.751267 -224.95159) (xy 129.793283 -224.921064) (xy 129.839557 -224.897486)
			(xy 129.88895 -224.881438) (xy 129.940245 -224.873313) (xy 129.992179 -224.873313) (xy 130.043474 -224.881438)
			(xy 130.092867 -224.897486) (xy 130.139141 -224.921064) (xy 130.181157 -224.95159) (xy 130.21788 -224.988313)
			(xy 130.248406 -225.030329) (xy 130.271984 -225.076603) (xy 130.288032 -225.125996) (xy 130.296157 -225.177291)
			(xy 130.296666 -225.203258) (xy 130.296157 -225.229225) (xy 130.288032 -225.28052) (xy 130.271984 -225.329913)
			(xy 130.248406 -225.376187) (xy 130.21788 -225.418203) (xy 130.181157 -225.454926) (xy 130.139141 -225.485452)
			(xy 130.092867 -225.50903) (xy 130.043474 -225.525078) (xy 129.992179 -225.533203) (xy 129.940245 -225.533203)
			(xy 129.88895 -225.525078) (xy 129.839557 -225.50903) (xy 129.793283 -225.485452) (xy 129.751267 -225.454926)
			(xy 129.714544 -225.418203) (xy 129.684018 -225.376187) (xy 129.66044 -225.329913) (xy 129.644392 -225.28052)
			(xy 129.636267 -225.229225) (xy 129.356357 -225.229225) (xy 129.348232 -225.28052) (xy 129.332184 -225.329913)
			(xy 129.308606 -225.376187) (xy 129.27808 -225.418203) (xy 129.241357 -225.454926) (xy 129.199341 -225.485452)
			(xy 129.153067 -225.50903) (xy 129.103674 -225.525078) (xy 129.052379 -225.533203) (xy 129.000445 -225.533203)
			(xy 128.94915 -225.525078) (xy 128.899757 -225.50903) (xy 128.853483 -225.485452) (xy 128.811467 -225.454926)
			(xy 128.774744 -225.418203) (xy 128.744218 -225.376187) (xy 128.72064 -225.329913) (xy 128.704592 -225.28052)
			(xy 128.696467 -225.229225) (xy 128.695958 -225.203258) (xy 128.696497 -225.175271) (xy 128.705956 -225.120104)
			(xy 128.714754 -225.09353) (xy 128.722374 -225.071432) (xy 128.518666 -224.718626) (xy 128.495806 -224.714308)
			(xy 128.470886 -224.709131) (xy 128.4229 -224.692171) (xy 128.37808 -224.668057) (xy 128.337485 -224.637359)
			(xy 128.302075 -224.600802) (xy 128.272686 -224.55925) (xy 128.250012 -224.513684) (xy 128.23459 -224.465182)
			(xy 128.226784 -224.414889) (xy 128.226312 -224.389442) (xy 127.94742 -224.389442) (xy 127.946911 -224.415409)
			(xy 127.938786 -224.466704) (xy 127.922738 -224.516097) (xy 127.89916 -224.562371) (xy 127.868634 -224.604387)
			(xy 127.831911 -224.64111) (xy 127.789895 -224.671636) (xy 127.743621 -224.695214) (xy 127.694228 -224.711262)
			(xy 127.642933 -224.719387) (xy 127.590999 -224.719387) (xy 127.539704 -224.711262) (xy 127.490311 -224.695214)
			(xy 127.444037 -224.671636) (xy 127.402021 -224.64111) (xy 127.365298 -224.604387) (xy 127.334772 -224.562371)
			(xy 127.311194 -224.516097) (xy 127.295146 -224.466704) (xy 127.287021 -224.415409) (xy 127.286512 -224.389442)
			(xy 127.00762 -224.389442) (xy 127.007077 -224.417428) (xy 126.99762 -224.472596) (xy 126.988824 -224.49917)
			(xy 126.981204 -224.521268) (xy 127.184912 -224.874074) (xy 127.207772 -224.878392) (xy 127.232704 -224.883512)
			(xy 127.28069 -224.900483) (xy 127.325509 -224.924607) (xy 127.366102 -224.955314) (xy 127.401509 -224.991878)
			(xy 127.430896 -225.033436) (xy 127.453568 -225.079006) (xy 127.468989 -225.127512) (xy 127.476794 -225.177809)
			(xy 127.477266 -225.203258) (xy 127.476757 -225.229225) (xy 127.756667 -225.229225) (xy 127.756667 -225.177291)
			(xy 127.764792 -225.125996) (xy 127.78084 -225.076603) (xy 127.804418 -225.030329) (xy 127.834944 -224.988313)
			(xy 127.871667 -224.95159) (xy 127.913683 -224.921064) (xy 127.959957 -224.897486) (xy 128.00935 -224.881438)
			(xy 128.060645 -224.873313) (xy 128.112579 -224.873313) (xy 128.163874 -224.881438) (xy 128.213267 -224.897486)
			(xy 128.259541 -224.921064) (xy 128.301557 -224.95159) (xy 128.33828 -224.988313) (xy 128.368806 -225.030329)
			(xy 128.392384 -225.076603) (xy 128.408432 -225.125996) (xy 128.416557 -225.177291) (xy 128.417066 -225.203258)
			(xy 128.416557 -225.229225) (xy 128.408432 -225.28052) (xy 128.392384 -225.329913) (xy 128.368806 -225.376187)
			(xy 128.33828 -225.418203) (xy 128.301557 -225.454926) (xy 128.259541 -225.485452) (xy 128.213267 -225.50903)
			(xy 128.163874 -225.525078) (xy 128.112579 -225.533203) (xy 128.060645 -225.533203) (xy 128.00935 -225.525078)
			(xy 127.959957 -225.50903) (xy 127.913683 -225.485452) (xy 127.871667 -225.454926) (xy 127.834944 -225.418203)
			(xy 127.804418 -225.376187) (xy 127.78084 -225.329913) (xy 127.764792 -225.28052) (xy 127.756667 -225.229225)
			(xy 127.476757 -225.229225) (xy 127.468632 -225.28052) (xy 127.452584 -225.329913) (xy 127.429006 -225.376187)
			(xy 127.39848 -225.418203) (xy 127.361757 -225.454926) (xy 127.319741 -225.485452) (xy 127.273467 -225.50903)
			(xy 127.224074 -225.525078) (xy 127.172779 -225.533203) (xy 127.120845 -225.533203) (xy 127.06955 -225.525078)
			(xy 127.020157 -225.50903) (xy 126.973883 -225.485452) (xy 126.931867 -225.454926) (xy 126.895144 -225.418203)
			(xy 126.864618 -225.376187) (xy 126.84104 -225.329913) (xy 126.824992 -225.28052) (xy 126.816867 -225.229225)
			(xy 126.816358 -225.203258) (xy 126.816897 -225.175271) (xy 126.826356 -225.120104) (xy 126.835154 -225.09353)
			(xy 126.842774 -225.071432) (xy 126.639066 -224.718626) (xy 126.616206 -224.714308) (xy 126.591286 -224.709131)
			(xy 126.5433 -224.692171) (xy 126.49848 -224.668057) (xy 126.457885 -224.637359) (xy 126.422475 -224.600802)
			(xy 126.393086 -224.55925) (xy 126.370412 -224.513684) (xy 126.35499 -224.465182) (xy 126.347184 -224.414889)
			(xy 126.346712 -224.389442) (xy 126.06782 -224.389442) (xy 126.067311 -224.415409) (xy 126.059186 -224.466704)
			(xy 126.043138 -224.516097) (xy 126.01956 -224.562371) (xy 125.989034 -224.604387) (xy 125.952311 -224.64111)
			(xy 125.910295 -224.671636) (xy 125.864021 -224.695214) (xy 125.814628 -224.711262) (xy 125.763333 -224.719387)
			(xy 125.711399 -224.719387) (xy 125.660104 -224.711262) (xy 125.610711 -224.695214) (xy 125.564437 -224.671636)
			(xy 125.522421 -224.64111) (xy 125.485698 -224.604387) (xy 125.455172 -224.562371) (xy 125.431594 -224.516097)
			(xy 125.415546 -224.466704) (xy 125.407421 -224.415409) (xy 125.406912 -224.389442) (xy 125.12802 -224.389442)
			(xy 125.127477 -224.417428) (xy 125.11802 -224.472596) (xy 125.109224 -224.49917) (xy 125.101604 -224.521268)
			(xy 125.305312 -224.874074) (xy 125.328172 -224.878392) (xy 125.353104 -224.883512) (xy 125.40109 -224.900483)
			(xy 125.445909 -224.924607) (xy 125.486502 -224.955314) (xy 125.521909 -224.991878) (xy 125.551296 -225.033436)
			(xy 125.573968 -225.079006) (xy 125.589389 -225.127512) (xy 125.597194 -225.177809) (xy 125.597666 -225.203258)
			(xy 125.597157 -225.229225) (xy 125.589032 -225.28052) (xy 125.572984 -225.329913) (xy 125.549406 -225.376187)
			(xy 125.51888 -225.418203) (xy 125.482157 -225.454926) (xy 125.440141 -225.485452) (xy 125.393867 -225.50903)
			(xy 125.344474 -225.525078) (xy 125.293179 -225.533203) (xy 125.241245 -225.533203) (xy 125.18995 -225.525078)
			(xy 125.140557 -225.50903) (xy 125.094283 -225.485452) (xy 125.052267 -225.454926) (xy 125.015544 -225.418203)
			(xy 124.985018 -225.376187) (xy 124.96144 -225.329913) (xy 124.945392 -225.28052) (xy 124.937267 -225.229225)
			(xy 124.936758 -225.203258) (xy 124.937297 -225.175271) (xy 124.946756 -225.120104) (xy 124.955554 -225.09353)
			(xy 124.963174 -225.071432) (xy 124.759466 -224.718626) (xy 124.736606 -224.714308) (xy 124.711686 -224.709131)
			(xy 124.6637 -224.692171) (xy 124.61888 -224.668057) (xy 124.578285 -224.637359) (xy 124.542875 -224.600802)
			(xy 124.513486 -224.55925) (xy 124.490812 -224.513684) (xy 124.47539 -224.465182) (xy 124.467584 -224.414889)
			(xy 124.467112 -224.389442) (xy 124.18822 -224.389442) (xy 124.187711 -224.415409) (xy 124.179586 -224.466704)
			(xy 124.163538 -224.516097) (xy 124.13996 -224.562371) (xy 124.109434 -224.604387) (xy 124.072711 -224.64111)
			(xy 124.030695 -224.671636) (xy 123.984421 -224.695214) (xy 123.935028 -224.711262) (xy 123.883733 -224.719387)
			(xy 123.831799 -224.719387) (xy 123.780504 -224.711262) (xy 123.731111 -224.695214) (xy 123.684837 -224.671636)
			(xy 123.642821 -224.64111) (xy 123.606098 -224.604387) (xy 123.575572 -224.562371) (xy 123.551994 -224.516097)
			(xy 123.535946 -224.466704) (xy 123.527821 -224.415409) (xy 123.527312 -224.389442) (xy 123.24842 -224.389442)
			(xy 123.247877 -224.417428) (xy 123.23842 -224.472596) (xy 123.229624 -224.49917) (xy 123.222004 -224.521268)
			(xy 123.425712 -224.874074) (xy 123.448572 -224.878392) (xy 123.473504 -224.883512) (xy 123.52149 -224.900483)
			(xy 123.566309 -224.924607) (xy 123.606902 -224.955314) (xy 123.642309 -224.991878) (xy 123.671696 -225.033436)
			(xy 123.694368 -225.079006) (xy 123.709789 -225.127512) (xy 123.717594 -225.177809) (xy 123.718066 -225.203258)
			(xy 123.717557 -225.229225) (xy 123.709432 -225.28052) (xy 123.693384 -225.329913) (xy 123.669806 -225.376187)
			(xy 123.63928 -225.418203) (xy 123.602557 -225.454926) (xy 123.560541 -225.485452) (xy 123.514267 -225.50903)
			(xy 123.464874 -225.525078) (xy 123.413579 -225.533203) (xy 123.361645 -225.533203) (xy 123.31035 -225.525078)
			(xy 123.260957 -225.50903) (xy 123.214683 -225.485452) (xy 123.172667 -225.454926) (xy 123.135944 -225.418203)
			(xy 123.105418 -225.376187) (xy 123.08184 -225.329913) (xy 123.065792 -225.28052) (xy 123.057667 -225.229225)
			(xy 123.057158 -225.203258) (xy 123.057697 -225.175271) (xy 123.067156 -225.120104) (xy 123.075954 -225.09353)
			(xy 123.083574 -225.071432) (xy 122.879866 -224.718626) (xy 122.857006 -224.714308) (xy 122.832086 -224.709131)
			(xy 122.7841 -224.692171) (xy 122.73928 -224.668057) (xy 122.698685 -224.637359) (xy 122.663275 -224.600802)
			(xy 122.633886 -224.55925) (xy 122.611212 -224.513684) (xy 122.59579 -224.465182) (xy 122.587984 -224.414889)
			(xy 122.587512 -224.389442) (xy 122.30862 -224.389442) (xy 122.308111 -224.415409) (xy 122.299986 -224.466704)
			(xy 122.283938 -224.516097) (xy 122.26036 -224.562371) (xy 122.229834 -224.604387) (xy 122.193111 -224.64111)
			(xy 122.151095 -224.671636) (xy 122.104821 -224.695214) (xy 122.055428 -224.711262) (xy 122.004133 -224.719387)
			(xy 121.952199 -224.719387) (xy 121.900904 -224.711262) (xy 121.851511 -224.695214) (xy 121.805237 -224.671636)
			(xy 121.763221 -224.64111) (xy 121.726498 -224.604387) (xy 121.695972 -224.562371) (xy 121.672394 -224.516097)
			(xy 121.656346 -224.466704) (xy 121.648221 -224.415409) (xy 121.647712 -224.389442) (xy 121.36882 -224.389442)
			(xy 121.368277 -224.417428) (xy 121.35882 -224.472596) (xy 121.350024 -224.49917) (xy 121.342404 -224.521268)
			(xy 121.546112 -224.874074) (xy 121.568972 -224.878392) (xy 121.593904 -224.883512) (xy 121.64189 -224.900483)
			(xy 121.686709 -224.924607) (xy 121.727302 -224.955314) (xy 121.762709 -224.991878) (xy 121.792096 -225.033436)
			(xy 121.814768 -225.079006) (xy 121.830189 -225.127512) (xy 121.837994 -225.177809) (xy 121.838466 -225.203258)
			(xy 121.837957 -225.229225) (xy 121.829832 -225.28052) (xy 121.813784 -225.329913) (xy 121.790206 -225.376187)
			(xy 121.75968 -225.418203) (xy 121.722957 -225.454926) (xy 121.680941 -225.485452) (xy 121.634667 -225.50903)
			(xy 121.585274 -225.525078) (xy 121.533979 -225.533203) (xy 121.482045 -225.533203) (xy 121.43075 -225.525078)
			(xy 121.381357 -225.50903) (xy 121.335083 -225.485452) (xy 121.293067 -225.454926) (xy 121.256344 -225.418203)
			(xy 121.225818 -225.376187) (xy 121.20224 -225.329913) (xy 121.186192 -225.28052) (xy 121.178067 -225.229225)
			(xy 121.177558 -225.203258) (xy 121.178097 -225.175271) (xy 121.187556 -225.120104) (xy 121.196354 -225.09353)
			(xy 121.203974 -225.071432) (xy 121.000266 -224.718626) (xy 120.977406 -224.714308) (xy 120.952486 -224.709131)
			(xy 120.9045 -224.692171) (xy 120.85968 -224.668057) (xy 120.819085 -224.637359) (xy 120.783675 -224.600802)
			(xy 120.754286 -224.55925) (xy 120.731612 -224.513684) (xy 120.71619 -224.465182) (xy 120.708384 -224.414889)
			(xy 120.707912 -224.389442) (xy 120.42902 -224.389442) (xy 120.428511 -224.415409) (xy 120.420386 -224.466704)
			(xy 120.404338 -224.516097) (xy 120.38076 -224.562371) (xy 120.350234 -224.604387) (xy 120.313511 -224.64111)
			(xy 120.271495 -224.671636) (xy 120.225221 -224.695214) (xy 120.175828 -224.711262) (xy 120.124533 -224.719387)
			(xy 120.072599 -224.719387) (xy 120.021304 -224.711262) (xy 119.971911 -224.695214) (xy 119.925637 -224.671636)
			(xy 119.883621 -224.64111) (xy 119.846898 -224.604387) (xy 119.816372 -224.562371) (xy 119.792794 -224.516097)
			(xy 119.776746 -224.466704) (xy 119.768621 -224.415409) (xy 119.768112 -224.389442) (xy 119.48922 -224.389442)
			(xy 119.488677 -224.417428) (xy 119.47922 -224.472596) (xy 119.470424 -224.49917) (xy 119.462804 -224.521268)
			(xy 119.666512 -224.874074) (xy 119.689372 -224.878392) (xy 119.714304 -224.883512) (xy 119.76229 -224.900483)
			(xy 119.807109 -224.924607) (xy 119.847702 -224.955314) (xy 119.883109 -224.991878) (xy 119.912496 -225.033436)
			(xy 119.935168 -225.079006) (xy 119.950589 -225.127512) (xy 119.958394 -225.177809) (xy 119.958866 -225.203258)
			(xy 119.958357 -225.229225) (xy 119.950232 -225.28052) (xy 119.934184 -225.329913) (xy 119.910606 -225.376187)
			(xy 119.88008 -225.418203) (xy 119.843357 -225.454926) (xy 119.801341 -225.485452) (xy 119.755067 -225.50903)
			(xy 119.705674 -225.525078) (xy 119.654379 -225.533203) (xy 119.602445 -225.533203) (xy 119.55115 -225.525078)
			(xy 119.501757 -225.50903) (xy 119.455483 -225.485452) (xy 119.413467 -225.454926) (xy 119.376744 -225.418203)
			(xy 119.346218 -225.376187) (xy 119.32264 -225.329913) (xy 119.306592 -225.28052) (xy 119.298467 -225.229225)
			(xy 119.297958 -225.203258) (xy 119.298497 -225.175271) (xy 119.307956 -225.120104) (xy 119.316754 -225.09353)
			(xy 119.324374 -225.071432) (xy 119.120666 -224.718626) (xy 119.097806 -224.714308) (xy 119.072886 -224.709131)
			(xy 119.0249 -224.692171) (xy 118.98008 -224.668057) (xy 118.939485 -224.637359) (xy 118.904075 -224.600802)
			(xy 118.874686 -224.55925) (xy 118.852012 -224.513684) (xy 118.83659 -224.465182) (xy 118.828784 -224.414889)
			(xy 118.828312 -224.389442) (xy 118.54942 -224.389442) (xy 118.548911 -224.415409) (xy 118.540786 -224.466704)
			(xy 118.524738 -224.516097) (xy 118.50116 -224.562371) (xy 118.470634 -224.604387) (xy 118.433911 -224.64111)
			(xy 118.391895 -224.671636) (xy 118.345621 -224.695214) (xy 118.296228 -224.711262) (xy 118.244933 -224.719387)
			(xy 118.192999 -224.719387) (xy 118.141704 -224.711262) (xy 118.092311 -224.695214) (xy 118.046037 -224.671636)
			(xy 118.004021 -224.64111) (xy 117.967298 -224.604387) (xy 117.936772 -224.562371) (xy 117.913194 -224.516097)
			(xy 117.897146 -224.466704) (xy 117.889021 -224.415409) (xy 117.888512 -224.389442) (xy 117.60962 -224.389442)
			(xy 117.609077 -224.417428) (xy 117.59962 -224.472596) (xy 117.590824 -224.49917) (xy 117.583204 -224.521268)
			(xy 117.786912 -224.874074) (xy 117.809772 -224.878392) (xy 117.834704 -224.883512) (xy 117.88269 -224.900483)
			(xy 117.927509 -224.924607) (xy 117.968102 -224.955314) (xy 118.003509 -224.991878) (xy 118.032896 -225.033436)
			(xy 118.055568 -225.079006) (xy 118.070989 -225.127512) (xy 118.078794 -225.177809) (xy 118.079266 -225.203258)
			(xy 118.078757 -225.229225) (xy 118.070632 -225.28052) (xy 118.054584 -225.329913) (xy 118.031006 -225.376187)
			(xy 118.00048 -225.418203) (xy 117.963757 -225.454926) (xy 117.921741 -225.485452) (xy 117.875467 -225.50903)
			(xy 117.826074 -225.525078) (xy 117.774779 -225.533203) (xy 117.722845 -225.533203) (xy 117.67155 -225.525078)
			(xy 117.622157 -225.50903) (xy 117.575883 -225.485452) (xy 117.533867 -225.454926) (xy 117.497144 -225.418203)
			(xy 117.466618 -225.376187) (xy 117.44304 -225.329913) (xy 117.426992 -225.28052) (xy 117.418867 -225.229225)
			(xy 117.418358 -225.203258) (xy 117.418897 -225.175271) (xy 117.428356 -225.120104) (xy 117.437154 -225.09353)
			(xy 117.444774 -225.071432) (xy 117.241066 -224.718626) (xy 117.218206 -224.714308) (xy 117.193286 -224.709131)
			(xy 117.1453 -224.692171) (xy 117.10048 -224.668057) (xy 117.059885 -224.637359) (xy 117.024475 -224.600802)
			(xy 116.995086 -224.55925) (xy 116.972412 -224.513684) (xy 116.95699 -224.465182) (xy 116.949184 -224.414889)
			(xy 116.948712 -224.389442) (xy 116.66982 -224.389442) (xy 116.669311 -224.415409) (xy 116.661186 -224.466704)
			(xy 116.645138 -224.516097) (xy 116.62156 -224.562371) (xy 116.591034 -224.604387) (xy 116.554311 -224.64111)
			(xy 116.512295 -224.671636) (xy 116.466021 -224.695214) (xy 116.416628 -224.711262) (xy 116.365333 -224.719387)
			(xy 116.313399 -224.719387) (xy 116.262104 -224.711262) (xy 116.212711 -224.695214) (xy 116.166437 -224.671636)
			(xy 116.124421 -224.64111) (xy 116.087698 -224.604387) (xy 116.057172 -224.562371) (xy 116.033594 -224.516097)
			(xy 116.017546 -224.466704) (xy 116.009421 -224.415409) (xy 116.008912 -224.389442) (xy 115.73002 -224.389442)
			(xy 115.729477 -224.417428) (xy 115.72002 -224.472596) (xy 115.711224 -224.49917) (xy 115.703604 -224.521268)
			(xy 115.907312 -224.874074) (xy 115.930172 -224.878392) (xy 115.955104 -224.883512) (xy 116.00309 -224.900483)
			(xy 116.047909 -224.924607) (xy 116.088502 -224.955314) (xy 116.123909 -224.991878) (xy 116.153296 -225.033436)
			(xy 116.175968 -225.079006) (xy 116.191389 -225.127512) (xy 116.199194 -225.177809) (xy 116.199666 -225.203258)
			(xy 116.199157 -225.229225) (xy 116.191032 -225.28052) (xy 116.174984 -225.329913) (xy 116.151406 -225.376187)
			(xy 116.12088 -225.418203) (xy 116.084157 -225.454926) (xy 116.042141 -225.485452) (xy 115.995867 -225.50903)
			(xy 115.946474 -225.525078) (xy 115.895179 -225.533203) (xy 115.843245 -225.533203) (xy 115.79195 -225.525078)
			(xy 115.742557 -225.50903) (xy 115.696283 -225.485452) (xy 115.654267 -225.454926) (xy 115.617544 -225.418203)
			(xy 115.587018 -225.376187) (xy 115.56344 -225.329913) (xy 115.547392 -225.28052) (xy 115.539267 -225.229225)
			(xy 115.538758 -225.203258) (xy 115.539297 -225.175271) (xy 115.548756 -225.120104) (xy 115.557554 -225.09353)
			(xy 115.565174 -225.071432) (xy 115.361466 -224.718626) (xy 115.338606 -224.714308) (xy 115.313686 -224.709131)
			(xy 115.2657 -224.692171) (xy 115.22088 -224.668057) (xy 115.180285 -224.637359) (xy 115.144875 -224.600802)
			(xy 115.115486 -224.55925) (xy 115.092812 -224.513684) (xy 115.07739 -224.465182) (xy 115.069584 -224.414889)
			(xy 115.069112 -224.389442) (xy 114.79022 -224.389442) (xy 114.789711 -224.415409) (xy 114.781586 -224.466704)
			(xy 114.765538 -224.516097) (xy 114.74196 -224.562371) (xy 114.711434 -224.604387) (xy 114.674711 -224.64111)
			(xy 114.632695 -224.671636) (xy 114.586421 -224.695214) (xy 114.537028 -224.711262) (xy 114.485733 -224.719387)
			(xy 114.433799 -224.719387) (xy 114.382504 -224.711262) (xy 114.333111 -224.695214) (xy 114.286837 -224.671636)
			(xy 114.244821 -224.64111) (xy 114.208098 -224.604387) (xy 114.177572 -224.562371) (xy 114.153994 -224.516097)
			(xy 114.137946 -224.466704) (xy 114.129821 -224.415409) (xy 114.129312 -224.389442) (xy 113.85042 -224.389442)
			(xy 113.849877 -224.417428) (xy 113.84042 -224.472596) (xy 113.831624 -224.49917) (xy 113.824004 -224.521268)
			(xy 114.027712 -224.874074) (xy 114.050572 -224.878392) (xy 114.075504 -224.883512) (xy 114.12349 -224.900483)
			(xy 114.168309 -224.924607) (xy 114.208902 -224.955314) (xy 114.244309 -224.991878) (xy 114.273696 -225.033436)
			(xy 114.296368 -225.079006) (xy 114.311789 -225.127512) (xy 114.319594 -225.177809) (xy 114.320066 -225.203258)
			(xy 114.319557 -225.229225) (xy 114.311432 -225.28052) (xy 114.295384 -225.329913) (xy 114.271806 -225.376187)
			(xy 114.24128 -225.418203) (xy 114.204557 -225.454926) (xy 114.162541 -225.485452) (xy 114.116267 -225.50903)
			(xy 114.066874 -225.525078) (xy 114.015579 -225.533203) (xy 113.963645 -225.533203) (xy 113.91235 -225.525078)
			(xy 113.862957 -225.50903) (xy 113.816683 -225.485452) (xy 113.774667 -225.454926) (xy 113.737944 -225.418203)
			(xy 113.707418 -225.376187) (xy 113.68384 -225.329913) (xy 113.667792 -225.28052) (xy 113.659667 -225.229225)
			(xy 113.659158 -225.203258) (xy 113.659697 -225.175271) (xy 113.669156 -225.120104) (xy 113.677954 -225.09353)
			(xy 113.685574 -225.071432) (xy 113.481866 -224.718626) (xy 113.459006 -224.714308) (xy 113.434086 -224.709131)
			(xy 113.3861 -224.692171) (xy 113.34128 -224.668057) (xy 113.300685 -224.637359) (xy 113.265275 -224.600802)
			(xy 113.235886 -224.55925) (xy 113.213212 -224.513684) (xy 113.19779 -224.465182) (xy 113.189984 -224.414889)
			(xy 113.189512 -224.389442) (xy 112.91062 -224.389442) (xy 112.910111 -224.415409) (xy 112.901986 -224.466704)
			(xy 112.885938 -224.516097) (xy 112.86236 -224.562371) (xy 112.831834 -224.604387) (xy 112.795111 -224.64111)
			(xy 112.753095 -224.671636) (xy 112.706821 -224.695214) (xy 112.657428 -224.711262) (xy 112.606133 -224.719387)
			(xy 112.554199 -224.719387) (xy 112.502904 -224.711262) (xy 112.453511 -224.695214) (xy 112.407237 -224.671636)
			(xy 112.365221 -224.64111) (xy 112.328498 -224.604387) (xy 112.297972 -224.562371) (xy 112.274394 -224.516097)
			(xy 112.258346 -224.466704) (xy 112.250221 -224.415409) (xy 112.249712 -224.389442) (xy 111.97082 -224.389442)
			(xy 111.970212 -224.417423) (xy 111.96077 -224.472584) (xy 111.952024 -224.49917) (xy 111.944404 -224.521268)
			(xy 112.148112 -224.874074) (xy 112.170972 -224.878392) (xy 112.195901 -224.883543) (xy 112.243902 -224.900485)
			(xy 112.288736 -224.92459) (xy 112.329342 -224.955286) (xy 112.364759 -224.991848) (xy 112.394149 -225.033409)
			(xy 112.416816 -225.078987) (xy 112.432223 -225.127502) (xy 112.440007 -225.177806) (xy 112.440466 -225.203258)
			(xy 112.439957 -225.229225) (xy 112.431832 -225.28052) (xy 112.415784 -225.329913) (xy 112.392206 -225.376187)
			(xy 112.36168 -225.418203) (xy 112.324957 -225.454926) (xy 112.282941 -225.485452) (xy 112.236667 -225.50903)
			(xy 112.187274 -225.525078) (xy 112.135979 -225.533203) (xy 112.084045 -225.533203) (xy 112.03275 -225.525078)
			(xy 111.983357 -225.50903) (xy 111.937083 -225.485452) (xy 111.895067 -225.454926) (xy 111.858344 -225.418203)
			(xy 111.827818 -225.376187) (xy 111.80424 -225.329913) (xy 111.788192 -225.28052) (xy 111.780067 -225.229225)
			(xy 111.779558 -225.203258) (xy 111.780167 -225.175277) (xy 111.789611 -225.120117) (xy 111.798354 -225.09353)
			(xy 111.805974 -225.071432) (xy 111.77651 -225.020378) (xy 111.768669 -225.007821) (xy 111.747135 -224.987525)
			(xy 111.720686 -224.974255) (xy 111.691543 -224.969126) (xy 111.662153 -224.972567) (xy 111.634983 -224.984292)
			(xy 111.612316 -225.003313) (xy 111.596054 -225.028036) (xy 111.587564 -225.056383) (xy 111.587026 -225.071178)
			(xy 111.587026 -225.636074) (xy 111.587448 -225.646128) (xy 111.595161 -225.664698) (xy 111.609416 -225.678881)
			(xy 111.628024 -225.686502) (xy 111.63808 -225.686874) (xy 111.640366 -225.686874) (xy 111.666335 -225.687354)
			(xy 111.717634 -225.695474) (xy 111.767031 -225.71152) (xy 111.813309 -225.735096) (xy 111.855329 -225.765621)
			(xy 111.892057 -225.802345) (xy 111.922587 -225.844362) (xy 111.946167 -225.890638) (xy 111.962218 -225.940033)
			(xy 111.970343 -225.991331) (xy 111.970343 -226.043269) (xy 111.970339 -226.043295) (xy 112.250221 -226.043295)
			(xy 112.250221 -225.991361) (xy 112.258346 -225.940066) (xy 112.274394 -225.890673) (xy 112.297972 -225.844399)
			(xy 112.328498 -225.802383) (xy 112.365221 -225.76566) (xy 112.407237 -225.735134) (xy 112.453511 -225.711556)
			(xy 112.502904 -225.695508) (xy 112.554199 -225.687383) (xy 112.606133 -225.687383) (xy 112.657428 -225.695508)
			(xy 112.706821 -225.711556) (xy 112.753095 -225.735134) (xy 112.795111 -225.76566) (xy 112.831834 -225.802383)
			(xy 112.86236 -225.844399) (xy 112.885938 -225.890673) (xy 112.901986 -225.940066) (xy 112.910111 -225.991361)
			(xy 112.91062 -226.017328) (xy 112.910111 -226.043295) (xy 113.190021 -226.043295) (xy 113.190021 -225.991361)
			(xy 113.198146 -225.940066) (xy 113.214194 -225.890673) (xy 113.237772 -225.844399) (xy 113.268298 -225.802383)
			(xy 113.305021 -225.76566) (xy 113.347037 -225.735134) (xy 113.393311 -225.711556) (xy 113.442704 -225.695508)
			(xy 113.493999 -225.687383) (xy 113.545933 -225.687383) (xy 113.597228 -225.695508) (xy 113.646621 -225.711556)
			(xy 113.692895 -225.735134) (xy 113.734911 -225.76566) (xy 113.771634 -225.802383) (xy 113.80216 -225.844399)
			(xy 113.825738 -225.890673) (xy 113.841786 -225.940066) (xy 113.849911 -225.991361) (xy 113.85042 -226.017328)
			(xy 113.849911 -226.043295) (xy 114.129821 -226.043295) (xy 114.129821 -225.991361) (xy 114.137946 -225.940066)
			(xy 114.153994 -225.890673) (xy 114.177572 -225.844399) (xy 114.208098 -225.802383) (xy 114.244821 -225.76566)
			(xy 114.286837 -225.735134) (xy 114.333111 -225.711556) (xy 114.382504 -225.695508) (xy 114.433799 -225.687383)
			(xy 114.485733 -225.687383) (xy 114.537028 -225.695508) (xy 114.586421 -225.711556) (xy 114.632695 -225.735134)
			(xy 114.674711 -225.76566) (xy 114.711434 -225.802383) (xy 114.74196 -225.844399) (xy 114.765538 -225.890673)
			(xy 114.781586 -225.940066) (xy 114.789711 -225.991361) (xy 114.79022 -226.017328) (xy 114.789711 -226.043295)
			(xy 115.069621 -226.043295) (xy 115.069621 -225.991361) (xy 115.077746 -225.940066) (xy 115.093794 -225.890673)
			(xy 115.117372 -225.844399) (xy 115.147898 -225.802383) (xy 115.184621 -225.76566) (xy 115.226637 -225.735134)
			(xy 115.272911 -225.711556) (xy 115.322304 -225.695508) (xy 115.373599 -225.687383) (xy 115.425533 -225.687383)
			(xy 115.476828 -225.695508) (xy 115.526221 -225.711556) (xy 115.572495 -225.735134) (xy 115.614511 -225.76566)
			(xy 115.651234 -225.802383) (xy 115.68176 -225.844399) (xy 115.705338 -225.890673) (xy 115.721386 -225.940066)
			(xy 115.729511 -225.991361) (xy 115.73002 -226.017328) (xy 115.729511 -226.043295) (xy 116.009421 -226.043295)
			(xy 116.009421 -225.991361) (xy 116.017546 -225.940066) (xy 116.033594 -225.890673) (xy 116.057172 -225.844399)
			(xy 116.087698 -225.802383) (xy 116.124421 -225.76566) (xy 116.166437 -225.735134) (xy 116.212711 -225.711556)
			(xy 116.262104 -225.695508) (xy 116.313399 -225.687383) (xy 116.365333 -225.687383) (xy 116.416628 -225.695508)
			(xy 116.466021 -225.711556) (xy 116.512295 -225.735134) (xy 116.554311 -225.76566) (xy 116.591034 -225.802383)
			(xy 116.62156 -225.844399) (xy 116.645138 -225.890673) (xy 116.661186 -225.940066) (xy 116.669311 -225.991361)
			(xy 116.66982 -226.017328) (xy 116.669311 -226.043295) (xy 116.949221 -226.043295) (xy 116.949221 -225.991361)
			(xy 116.957346 -225.940066) (xy 116.973394 -225.890673) (xy 116.996972 -225.844399) (xy 117.027498 -225.802383)
			(xy 117.064221 -225.76566) (xy 117.106237 -225.735134) (xy 117.152511 -225.711556) (xy 117.201904 -225.695508)
			(xy 117.253199 -225.687383) (xy 117.305133 -225.687383) (xy 117.356428 -225.695508) (xy 117.405821 -225.711556)
			(xy 117.452095 -225.735134) (xy 117.494111 -225.76566) (xy 117.530834 -225.802383) (xy 117.56136 -225.844399)
			(xy 117.584938 -225.890673) (xy 117.600986 -225.940066) (xy 117.609111 -225.991361) (xy 117.60962 -226.017328)
			(xy 117.609111 -226.043295) (xy 117.889021 -226.043295) (xy 117.889021 -225.991361) (xy 117.897146 -225.940066)
			(xy 117.913194 -225.890673) (xy 117.936772 -225.844399) (xy 117.967298 -225.802383) (xy 118.004021 -225.76566)
			(xy 118.046037 -225.735134) (xy 118.092311 -225.711556) (xy 118.141704 -225.695508) (xy 118.192999 -225.687383)
			(xy 118.244933 -225.687383) (xy 118.296228 -225.695508) (xy 118.345621 -225.711556) (xy 118.391895 -225.735134)
			(xy 118.433911 -225.76566) (xy 118.470634 -225.802383) (xy 118.50116 -225.844399) (xy 118.524738 -225.890673)
			(xy 118.540786 -225.940066) (xy 118.548911 -225.991361) (xy 118.54942 -226.017328) (xy 118.548911 -226.043295)
			(xy 118.828821 -226.043295) (xy 118.828821 -225.991361) (xy 118.836946 -225.940066) (xy 118.852994 -225.890673)
			(xy 118.876572 -225.844399) (xy 118.907098 -225.802383) (xy 118.943821 -225.76566) (xy 118.985837 -225.735134)
			(xy 119.032111 -225.711556) (xy 119.081504 -225.695508) (xy 119.132799 -225.687383) (xy 119.184733 -225.687383)
			(xy 119.236028 -225.695508) (xy 119.285421 -225.711556) (xy 119.331695 -225.735134) (xy 119.373711 -225.76566)
			(xy 119.410434 -225.802383) (xy 119.44096 -225.844399) (xy 119.464538 -225.890673) (xy 119.480586 -225.940066)
			(xy 119.488711 -225.991361) (xy 119.48922 -226.017328) (xy 119.488711 -226.043295) (xy 119.768621 -226.043295)
			(xy 119.768621 -225.991361) (xy 119.776746 -225.940066) (xy 119.792794 -225.890673) (xy 119.816372 -225.844399)
			(xy 119.846898 -225.802383) (xy 119.883621 -225.76566) (xy 119.925637 -225.735134) (xy 119.971911 -225.711556)
			(xy 120.021304 -225.695508) (xy 120.072599 -225.687383) (xy 120.124533 -225.687383) (xy 120.175828 -225.695508)
			(xy 120.225221 -225.711556) (xy 120.271495 -225.735134) (xy 120.313511 -225.76566) (xy 120.350234 -225.802383)
			(xy 120.38076 -225.844399) (xy 120.404338 -225.890673) (xy 120.420386 -225.940066) (xy 120.428511 -225.991361)
			(xy 120.42902 -226.017328) (xy 120.428511 -226.043295) (xy 120.708421 -226.043295) (xy 120.708421 -225.991361)
			(xy 120.716546 -225.940066) (xy 120.732594 -225.890673) (xy 120.756172 -225.844399) (xy 120.786698 -225.802383)
			(xy 120.823421 -225.76566) (xy 120.865437 -225.735134) (xy 120.911711 -225.711556) (xy 120.961104 -225.695508)
			(xy 121.012399 -225.687383) (xy 121.064333 -225.687383) (xy 121.115628 -225.695508) (xy 121.165021 -225.711556)
			(xy 121.211295 -225.735134) (xy 121.253311 -225.76566) (xy 121.290034 -225.802383) (xy 121.32056 -225.844399)
			(xy 121.344138 -225.890673) (xy 121.360186 -225.940066) (xy 121.368311 -225.991361) (xy 121.36882 -226.017328)
			(xy 121.368311 -226.043295) (xy 121.648221 -226.043295) (xy 121.648221 -225.991361) (xy 121.656346 -225.940066)
			(xy 121.672394 -225.890673) (xy 121.695972 -225.844399) (xy 121.726498 -225.802383) (xy 121.763221 -225.76566)
			(xy 121.805237 -225.735134) (xy 121.851511 -225.711556) (xy 121.900904 -225.695508) (xy 121.952199 -225.687383)
			(xy 122.004133 -225.687383) (xy 122.055428 -225.695508) (xy 122.104821 -225.711556) (xy 122.151095 -225.735134)
			(xy 122.193111 -225.76566) (xy 122.229834 -225.802383) (xy 122.26036 -225.844399) (xy 122.283938 -225.890673)
			(xy 122.299986 -225.940066) (xy 122.308111 -225.991361) (xy 122.30862 -226.017328) (xy 122.308111 -226.043295)
			(xy 122.588021 -226.043295) (xy 122.588021 -225.991361) (xy 122.596146 -225.940066) (xy 122.612194 -225.890673)
			(xy 122.635772 -225.844399) (xy 122.666298 -225.802383) (xy 122.703021 -225.76566) (xy 122.745037 -225.735134)
			(xy 122.791311 -225.711556) (xy 122.840704 -225.695508) (xy 122.891999 -225.687383) (xy 122.943933 -225.687383)
			(xy 122.995228 -225.695508) (xy 123.044621 -225.711556) (xy 123.090895 -225.735134) (xy 123.132911 -225.76566)
			(xy 123.169634 -225.802383) (xy 123.20016 -225.844399) (xy 123.223738 -225.890673) (xy 123.239786 -225.940066)
			(xy 123.247911 -225.991361) (xy 123.24842 -226.017328) (xy 123.247911 -226.043295) (xy 123.527821 -226.043295)
			(xy 123.527821 -225.991361) (xy 123.535946 -225.940066) (xy 123.551994 -225.890673) (xy 123.575572 -225.844399)
			(xy 123.606098 -225.802383) (xy 123.642821 -225.76566) (xy 123.684837 -225.735134) (xy 123.731111 -225.711556)
			(xy 123.780504 -225.695508) (xy 123.831799 -225.687383) (xy 123.883733 -225.687383) (xy 123.935028 -225.695508)
			(xy 123.984421 -225.711556) (xy 124.030695 -225.735134) (xy 124.072711 -225.76566) (xy 124.109434 -225.802383)
			(xy 124.13996 -225.844399) (xy 124.163538 -225.890673) (xy 124.179586 -225.940066) (xy 124.187711 -225.991361)
			(xy 124.18822 -226.017328) (xy 124.187711 -226.043295) (xy 124.467621 -226.043295) (xy 124.467621 -225.991361)
			(xy 124.475746 -225.940066) (xy 124.491794 -225.890673) (xy 124.515372 -225.844399) (xy 124.545898 -225.802383)
			(xy 124.582621 -225.76566) (xy 124.624637 -225.735134) (xy 124.670911 -225.711556) (xy 124.720304 -225.695508)
			(xy 124.771599 -225.687383) (xy 124.823533 -225.687383) (xy 124.874828 -225.695508) (xy 124.924221 -225.711556)
			(xy 124.970495 -225.735134) (xy 125.012511 -225.76566) (xy 125.049234 -225.802383) (xy 125.07976 -225.844399)
			(xy 125.103338 -225.890673) (xy 125.119386 -225.940066) (xy 125.127511 -225.991361) (xy 125.12802 -226.017328)
			(xy 125.127511 -226.043295) (xy 125.407421 -226.043295) (xy 125.407421 -225.991361) (xy 125.415546 -225.940066)
			(xy 125.431594 -225.890673) (xy 125.455172 -225.844399) (xy 125.485698 -225.802383) (xy 125.522421 -225.76566)
			(xy 125.564437 -225.735134) (xy 125.610711 -225.711556) (xy 125.660104 -225.695508) (xy 125.711399 -225.687383)
			(xy 125.763333 -225.687383) (xy 125.814628 -225.695508) (xy 125.864021 -225.711556) (xy 125.910295 -225.735134)
			(xy 125.952311 -225.76566) (xy 125.989034 -225.802383) (xy 126.01956 -225.844399) (xy 126.043138 -225.890673)
			(xy 126.059186 -225.940066) (xy 126.067311 -225.991361) (xy 126.06782 -226.017328) (xy 126.067311 -226.043295)
			(xy 126.347221 -226.043295) (xy 126.347221 -225.991361) (xy 126.355346 -225.940066) (xy 126.371394 -225.890673)
			(xy 126.394972 -225.844399) (xy 126.425498 -225.802383) (xy 126.462221 -225.76566) (xy 126.504237 -225.735134)
			(xy 126.550511 -225.711556) (xy 126.599904 -225.695508) (xy 126.651199 -225.687383) (xy 126.703133 -225.687383)
			(xy 126.754428 -225.695508) (xy 126.803821 -225.711556) (xy 126.850095 -225.735134) (xy 126.892111 -225.76566)
			(xy 126.928834 -225.802383) (xy 126.95936 -225.844399) (xy 126.982938 -225.890673) (xy 126.998986 -225.940066)
			(xy 127.007111 -225.991361) (xy 127.00762 -226.017328) (xy 127.007111 -226.043295) (xy 127.287021 -226.043295)
			(xy 127.287021 -225.991361) (xy 127.295146 -225.940066) (xy 127.311194 -225.890673) (xy 127.334772 -225.844399)
			(xy 127.365298 -225.802383) (xy 127.402021 -225.76566) (xy 127.444037 -225.735134) (xy 127.490311 -225.711556)
			(xy 127.539704 -225.695508) (xy 127.590999 -225.687383) (xy 127.642933 -225.687383) (xy 127.694228 -225.695508)
			(xy 127.743621 -225.711556) (xy 127.789895 -225.735134) (xy 127.831911 -225.76566) (xy 127.868634 -225.802383)
			(xy 127.89916 -225.844399) (xy 127.922738 -225.890673) (xy 127.938786 -225.940066) (xy 127.946911 -225.991361)
			(xy 127.94742 -226.017328) (xy 127.946911 -226.043295) (xy 128.226821 -226.043295) (xy 128.226821 -225.991361)
			(xy 128.234946 -225.940066) (xy 128.250994 -225.890673) (xy 128.274572 -225.844399) (xy 128.305098 -225.802383)
			(xy 128.341821 -225.76566) (xy 128.383837 -225.735134) (xy 128.430111 -225.711556) (xy 128.479504 -225.695508)
			(xy 128.530799 -225.687383) (xy 128.582733 -225.687383) (xy 128.634028 -225.695508) (xy 128.683421 -225.711556)
			(xy 128.729695 -225.735134) (xy 128.771711 -225.76566) (xy 128.808434 -225.802383) (xy 128.83896 -225.844399)
			(xy 128.862538 -225.890673) (xy 128.878586 -225.940066) (xy 128.886711 -225.991361) (xy 128.88722 -226.017328)
			(xy 128.886711 -226.043295) (xy 128.878586 -226.09459) (xy 128.862538 -226.143983) (xy 128.83896 -226.190257)
			(xy 128.808434 -226.232273) (xy 128.771711 -226.268996) (xy 128.729695 -226.299522) (xy 128.683421 -226.3231)
			(xy 128.634028 -226.339148) (xy 128.582733 -226.347273) (xy 128.530799 -226.347273) (xy 128.479504 -226.339148)
			(xy 128.430111 -226.3231) (xy 128.383837 -226.299522) (xy 128.341821 -226.268996) (xy 128.305098 -226.232273)
			(xy 128.274572 -226.190257) (xy 128.250994 -226.143983) (xy 128.234946 -226.09459) (xy 128.226821 -226.043295)
			(xy 127.946911 -226.043295) (xy 127.938786 -226.09459) (xy 127.922738 -226.143983) (xy 127.89916 -226.190257)
			(xy 127.868634 -226.232273) (xy 127.831911 -226.268996) (xy 127.789895 -226.299522) (xy 127.743621 -226.3231)
			(xy 127.694228 -226.339148) (xy 127.642933 -226.347273) (xy 127.590999 -226.347273) (xy 127.539704 -226.339148)
			(xy 127.490311 -226.3231) (xy 127.444037 -226.299522) (xy 127.402021 -226.268996) (xy 127.365298 -226.232273)
			(xy 127.334772 -226.190257) (xy 127.311194 -226.143983) (xy 127.295146 -226.09459) (xy 127.287021 -226.043295)
			(xy 127.007111 -226.043295) (xy 126.998986 -226.09459) (xy 126.982938 -226.143983) (xy 126.95936 -226.190257)
			(xy 126.928834 -226.232273) (xy 126.892111 -226.268996) (xy 126.850095 -226.299522) (xy 126.803821 -226.3231)
			(xy 126.754428 -226.339148) (xy 126.703133 -226.347273) (xy 126.651199 -226.347273) (xy 126.599904 -226.339148)
			(xy 126.550511 -226.3231) (xy 126.504237 -226.299522) (xy 126.462221 -226.268996) (xy 126.425498 -226.232273)
			(xy 126.394972 -226.190257) (xy 126.371394 -226.143983) (xy 126.355346 -226.09459) (xy 126.347221 -226.043295)
			(xy 126.067311 -226.043295) (xy 126.059186 -226.09459) (xy 126.043138 -226.143983) (xy 126.01956 -226.190257)
			(xy 125.989034 -226.232273) (xy 125.952311 -226.268996) (xy 125.910295 -226.299522) (xy 125.864021 -226.3231)
			(xy 125.814628 -226.339148) (xy 125.763333 -226.347273) (xy 125.711399 -226.347273) (xy 125.660104 -226.339148)
			(xy 125.610711 -226.3231) (xy 125.564437 -226.299522) (xy 125.522421 -226.268996) (xy 125.485698 -226.232273)
			(xy 125.455172 -226.190257) (xy 125.431594 -226.143983) (xy 125.415546 -226.09459) (xy 125.407421 -226.043295)
			(xy 125.127511 -226.043295) (xy 125.119386 -226.09459) (xy 125.103338 -226.143983) (xy 125.07976 -226.190257)
			(xy 125.049234 -226.232273) (xy 125.012511 -226.268996) (xy 124.970495 -226.299522) (xy 124.924221 -226.3231)
			(xy 124.874828 -226.339148) (xy 124.823533 -226.347273) (xy 124.771599 -226.347273) (xy 124.720304 -226.339148)
			(xy 124.670911 -226.3231) (xy 124.624637 -226.299522) (xy 124.582621 -226.268996) (xy 124.545898 -226.232273)
			(xy 124.515372 -226.190257) (xy 124.491794 -226.143983) (xy 124.475746 -226.09459) (xy 124.467621 -226.043295)
			(xy 124.187711 -226.043295) (xy 124.179586 -226.09459) (xy 124.163538 -226.143983) (xy 124.13996 -226.190257)
			(xy 124.109434 -226.232273) (xy 124.072711 -226.268996) (xy 124.030695 -226.299522) (xy 123.984421 -226.3231)
			(xy 123.935028 -226.339148) (xy 123.883733 -226.347273) (xy 123.831799 -226.347273) (xy 123.780504 -226.339148)
			(xy 123.731111 -226.3231) (xy 123.684837 -226.299522) (xy 123.642821 -226.268996) (xy 123.606098 -226.232273)
			(xy 123.575572 -226.190257) (xy 123.551994 -226.143983) (xy 123.535946 -226.09459) (xy 123.527821 -226.043295)
			(xy 123.247911 -226.043295) (xy 123.239786 -226.09459) (xy 123.223738 -226.143983) (xy 123.20016 -226.190257)
			(xy 123.169634 -226.232273) (xy 123.132911 -226.268996) (xy 123.090895 -226.299522) (xy 123.044621 -226.3231)
			(xy 122.995228 -226.339148) (xy 122.943933 -226.347273) (xy 122.891999 -226.347273) (xy 122.840704 -226.339148)
			(xy 122.791311 -226.3231) (xy 122.745037 -226.299522) (xy 122.703021 -226.268996) (xy 122.666298 -226.232273)
			(xy 122.635772 -226.190257) (xy 122.612194 -226.143983) (xy 122.596146 -226.09459) (xy 122.588021 -226.043295)
			(xy 122.308111 -226.043295) (xy 122.299986 -226.09459) (xy 122.283938 -226.143983) (xy 122.26036 -226.190257)
			(xy 122.229834 -226.232273) (xy 122.193111 -226.268996) (xy 122.151095 -226.299522) (xy 122.104821 -226.3231)
			(xy 122.055428 -226.339148) (xy 122.004133 -226.347273) (xy 121.952199 -226.347273) (xy 121.900904 -226.339148)
			(xy 121.851511 -226.3231) (xy 121.805237 -226.299522) (xy 121.763221 -226.268996) (xy 121.726498 -226.232273)
			(xy 121.695972 -226.190257) (xy 121.672394 -226.143983) (xy 121.656346 -226.09459) (xy 121.648221 -226.043295)
			(xy 121.368311 -226.043295) (xy 121.360186 -226.09459) (xy 121.344138 -226.143983) (xy 121.32056 -226.190257)
			(xy 121.290034 -226.232273) (xy 121.253311 -226.268996) (xy 121.211295 -226.299522) (xy 121.165021 -226.3231)
			(xy 121.115628 -226.339148) (xy 121.064333 -226.347273) (xy 121.012399 -226.347273) (xy 120.961104 -226.339148)
			(xy 120.911711 -226.3231) (xy 120.865437 -226.299522) (xy 120.823421 -226.268996) (xy 120.786698 -226.232273)
			(xy 120.756172 -226.190257) (xy 120.732594 -226.143983) (xy 120.716546 -226.09459) (xy 120.708421 -226.043295)
			(xy 120.428511 -226.043295) (xy 120.420386 -226.09459) (xy 120.404338 -226.143983) (xy 120.38076 -226.190257)
			(xy 120.350234 -226.232273) (xy 120.313511 -226.268996) (xy 120.271495 -226.299522) (xy 120.225221 -226.3231)
			(xy 120.175828 -226.339148) (xy 120.124533 -226.347273) (xy 120.072599 -226.347273) (xy 120.021304 -226.339148)
			(xy 119.971911 -226.3231) (xy 119.925637 -226.299522) (xy 119.883621 -226.268996) (xy 119.846898 -226.232273)
			(xy 119.816372 -226.190257) (xy 119.792794 -226.143983) (xy 119.776746 -226.09459) (xy 119.768621 -226.043295)
			(xy 119.488711 -226.043295) (xy 119.480586 -226.09459) (xy 119.464538 -226.143983) (xy 119.44096 -226.190257)
			(xy 119.410434 -226.232273) (xy 119.373711 -226.268996) (xy 119.331695 -226.299522) (xy 119.285421 -226.3231)
			(xy 119.236028 -226.339148) (xy 119.184733 -226.347273) (xy 119.132799 -226.347273) (xy 119.081504 -226.339148)
			(xy 119.032111 -226.3231) (xy 118.985837 -226.299522) (xy 118.943821 -226.268996) (xy 118.907098 -226.232273)
			(xy 118.876572 -226.190257) (xy 118.852994 -226.143983) (xy 118.836946 -226.09459) (xy 118.828821 -226.043295)
			(xy 118.548911 -226.043295) (xy 118.540786 -226.09459) (xy 118.524738 -226.143983) (xy 118.50116 -226.190257)
			(xy 118.470634 -226.232273) (xy 118.433911 -226.268996) (xy 118.391895 -226.299522) (xy 118.345621 -226.3231)
			(xy 118.296228 -226.339148) (xy 118.244933 -226.347273) (xy 118.192999 -226.347273) (xy 118.141704 -226.339148)
			(xy 118.092311 -226.3231) (xy 118.046037 -226.299522) (xy 118.004021 -226.268996) (xy 117.967298 -226.232273)
			(xy 117.936772 -226.190257) (xy 117.913194 -226.143983) (xy 117.897146 -226.09459) (xy 117.889021 -226.043295)
			(xy 117.609111 -226.043295) (xy 117.600986 -226.09459) (xy 117.584938 -226.143983) (xy 117.56136 -226.190257)
			(xy 117.530834 -226.232273) (xy 117.494111 -226.268996) (xy 117.452095 -226.299522) (xy 117.405821 -226.3231)
			(xy 117.356428 -226.339148) (xy 117.305133 -226.347273) (xy 117.253199 -226.347273) (xy 117.201904 -226.339148)
			(xy 117.152511 -226.3231) (xy 117.106237 -226.299522) (xy 117.064221 -226.268996) (xy 117.027498 -226.232273)
			(xy 116.996972 -226.190257) (xy 116.973394 -226.143983) (xy 116.957346 -226.09459) (xy 116.949221 -226.043295)
			(xy 116.669311 -226.043295) (xy 116.661186 -226.09459) (xy 116.645138 -226.143983) (xy 116.62156 -226.190257)
			(xy 116.591034 -226.232273) (xy 116.554311 -226.268996) (xy 116.512295 -226.299522) (xy 116.466021 -226.3231)
			(xy 116.416628 -226.339148) (xy 116.365333 -226.347273) (xy 116.313399 -226.347273) (xy 116.262104 -226.339148)
			(xy 116.212711 -226.3231) (xy 116.166437 -226.299522) (xy 116.124421 -226.268996) (xy 116.087698 -226.232273)
			(xy 116.057172 -226.190257) (xy 116.033594 -226.143983) (xy 116.017546 -226.09459) (xy 116.009421 -226.043295)
			(xy 115.729511 -226.043295) (xy 115.721386 -226.09459) (xy 115.705338 -226.143983) (xy 115.68176 -226.190257)
			(xy 115.651234 -226.232273) (xy 115.614511 -226.268996) (xy 115.572495 -226.299522) (xy 115.526221 -226.3231)
			(xy 115.476828 -226.339148) (xy 115.425533 -226.347273) (xy 115.373599 -226.347273) (xy 115.322304 -226.339148)
			(xy 115.272911 -226.3231) (xy 115.226637 -226.299522) (xy 115.184621 -226.268996) (xy 115.147898 -226.232273)
			(xy 115.117372 -226.190257) (xy 115.093794 -226.143983) (xy 115.077746 -226.09459) (xy 115.069621 -226.043295)
			(xy 114.789711 -226.043295) (xy 114.781586 -226.09459) (xy 114.765538 -226.143983) (xy 114.74196 -226.190257)
			(xy 114.711434 -226.232273) (xy 114.674711 -226.268996) (xy 114.632695 -226.299522) (xy 114.586421 -226.3231)
			(xy 114.537028 -226.339148) (xy 114.485733 -226.347273) (xy 114.433799 -226.347273) (xy 114.382504 -226.339148)
			(xy 114.333111 -226.3231) (xy 114.286837 -226.299522) (xy 114.244821 -226.268996) (xy 114.208098 -226.232273)
			(xy 114.177572 -226.190257) (xy 114.153994 -226.143983) (xy 114.137946 -226.09459) (xy 114.129821 -226.043295)
			(xy 113.849911 -226.043295) (xy 113.841786 -226.09459) (xy 113.825738 -226.143983) (xy 113.80216 -226.190257)
			(xy 113.771634 -226.232273) (xy 113.734911 -226.268996) (xy 113.692895 -226.299522) (xy 113.646621 -226.3231)
			(xy 113.597228 -226.339148) (xy 113.545933 -226.347273) (xy 113.493999 -226.347273) (xy 113.442704 -226.339148)
			(xy 113.393311 -226.3231) (xy 113.347037 -226.299522) (xy 113.305021 -226.268996) (xy 113.268298 -226.232273)
			(xy 113.237772 -226.190257) (xy 113.214194 -226.143983) (xy 113.198146 -226.09459) (xy 113.190021 -226.043295)
			(xy 112.910111 -226.043295) (xy 112.901986 -226.09459) (xy 112.885938 -226.143983) (xy 112.86236 -226.190257)
			(xy 112.831834 -226.232273) (xy 112.795111 -226.268996) (xy 112.753095 -226.299522) (xy 112.706821 -226.3231)
			(xy 112.657428 -226.339148) (xy 112.606133 -226.347273) (xy 112.554199 -226.347273) (xy 112.502904 -226.339148)
			(xy 112.453511 -226.3231) (xy 112.407237 -226.299522) (xy 112.365221 -226.268996) (xy 112.328498 -226.232273)
			(xy 112.297972 -226.190257) (xy 112.274394 -226.143983) (xy 112.258346 -226.09459) (xy 112.250221 -226.043295)
			(xy 111.970339 -226.043295) (xy 111.962218 -226.094567) (xy 111.946167 -226.143962) (xy 111.922587 -226.190238)
			(xy 111.892057 -226.232255) (xy 111.855329 -226.268979) (xy 111.813309 -226.299504) (xy 111.767031 -226.32308)
			(xy 111.717634 -226.339126) (xy 111.666335 -226.347246) (xy 111.640366 -226.347782) (xy 111.63808 -226.347782)
			(xy 111.62802 -226.348153) (xy 111.609404 -226.355772) (xy 111.595139 -226.369954) (xy 111.587411 -226.388525)
			(xy 111.587026 -226.398582) (xy 111.587026 -226.857111) (xy 111.780321 -226.857111) (xy 111.780321 -226.805177)
			(xy 111.788446 -226.753882) (xy 111.804494 -226.704489) (xy 111.828072 -226.658215) (xy 111.858598 -226.616199)
			(xy 111.895321 -226.579476) (xy 111.937337 -226.54895) (xy 111.983611 -226.525372) (xy 112.033004 -226.509324)
			(xy 112.084299 -226.501199) (xy 112.136233 -226.501199) (xy 112.187528 -226.509324) (xy 112.236921 -226.525372)
			(xy 112.283195 -226.54895) (xy 112.325211 -226.579476) (xy 112.361934 -226.616199) (xy 112.39246 -226.658215)
			(xy 112.416038 -226.704489) (xy 112.432086 -226.753882) (xy 112.440211 -226.805177) (xy 112.44072 -226.831144)
			(xy 112.440211 -226.857111) (xy 112.719867 -226.857111) (xy 112.719867 -226.805177) (xy 112.727992 -226.753882)
			(xy 112.74404 -226.704489) (xy 112.767618 -226.658215) (xy 112.798144 -226.616199) (xy 112.834867 -226.579476)
			(xy 112.876883 -226.54895) (xy 112.923157 -226.525372) (xy 112.97255 -226.509324) (xy 113.023845 -226.501199)
			(xy 113.075779 -226.501199) (xy 113.127074 -226.509324) (xy 113.176467 -226.525372) (xy 113.222741 -226.54895)
			(xy 113.264757 -226.579476) (xy 113.30148 -226.616199) (xy 113.332006 -226.658215) (xy 113.355584 -226.704489)
			(xy 113.371632 -226.753882) (xy 113.379757 -226.805177) (xy 113.380266 -226.831144) (xy 113.379757 -226.857111)
			(xy 113.659921 -226.857111) (xy 113.659921 -226.805177) (xy 113.668046 -226.753882) (xy 113.684094 -226.704489)
			(xy 113.707672 -226.658215) (xy 113.738198 -226.616199) (xy 113.774921 -226.579476) (xy 113.816937 -226.54895)
			(xy 113.863211 -226.525372) (xy 113.912604 -226.509324) (xy 113.963899 -226.501199) (xy 114.015833 -226.501199)
			(xy 114.067128 -226.509324) (xy 114.116521 -226.525372) (xy 114.162795 -226.54895) (xy 114.204811 -226.579476)
			(xy 114.241534 -226.616199) (xy 114.27206 -226.658215) (xy 114.295638 -226.704489) (xy 114.311686 -226.753882)
			(xy 114.319811 -226.805177) (xy 114.32032 -226.831144) (xy 114.319811 -226.857111) (xy 114.599721 -226.857111)
			(xy 114.599721 -226.805177) (xy 114.607846 -226.753882) (xy 114.623894 -226.704489) (xy 114.647472 -226.658215)
			(xy 114.677998 -226.616199) (xy 114.714721 -226.579476) (xy 114.756737 -226.54895) (xy 114.803011 -226.525372)
			(xy 114.852404 -226.509324) (xy 114.903699 -226.501199) (xy 114.955633 -226.501199) (xy 115.006928 -226.509324)
			(xy 115.056321 -226.525372) (xy 115.102595 -226.54895) (xy 115.144611 -226.579476) (xy 115.181334 -226.616199)
			(xy 115.21186 -226.658215) (xy 115.235438 -226.704489) (xy 115.251486 -226.753882) (xy 115.259611 -226.805177)
			(xy 115.26012 -226.831144) (xy 115.259611 -226.857111) (xy 115.539521 -226.857111) (xy 115.539521 -226.805177)
			(xy 115.547646 -226.753882) (xy 115.563694 -226.704489) (xy 115.587272 -226.658215) (xy 115.617798 -226.616199)
			(xy 115.654521 -226.579476) (xy 115.696537 -226.54895) (xy 115.742811 -226.525372) (xy 115.792204 -226.509324)
			(xy 115.843499 -226.501199) (xy 115.895433 -226.501199) (xy 115.946728 -226.509324) (xy 115.996121 -226.525372)
			(xy 116.042395 -226.54895) (xy 116.084411 -226.579476) (xy 116.121134 -226.616199) (xy 116.15166 -226.658215)
			(xy 116.175238 -226.704489) (xy 116.191286 -226.753882) (xy 116.199411 -226.805177) (xy 116.19992 -226.831144)
			(xy 116.199411 -226.857111) (xy 116.479067 -226.857111) (xy 116.479067 -226.805177) (xy 116.487192 -226.753882)
			(xy 116.50324 -226.704489) (xy 116.526818 -226.658215) (xy 116.557344 -226.616199) (xy 116.594067 -226.579476)
			(xy 116.636083 -226.54895) (xy 116.682357 -226.525372) (xy 116.73175 -226.509324) (xy 116.783045 -226.501199)
			(xy 116.834979 -226.501199) (xy 116.886274 -226.509324) (xy 116.935667 -226.525372) (xy 116.981941 -226.54895)
			(xy 117.023957 -226.579476) (xy 117.06068 -226.616199) (xy 117.091206 -226.658215) (xy 117.114784 -226.704489)
			(xy 117.130832 -226.753882) (xy 117.138957 -226.805177) (xy 117.139466 -226.831144) (xy 117.138957 -226.857111)
			(xy 117.419121 -226.857111) (xy 117.419121 -226.805177) (xy 117.427246 -226.753882) (xy 117.443294 -226.704489)
			(xy 117.466872 -226.658215) (xy 117.497398 -226.616199) (xy 117.534121 -226.579476) (xy 117.576137 -226.54895)
			(xy 117.622411 -226.525372) (xy 117.671804 -226.509324) (xy 117.723099 -226.501199) (xy 117.775033 -226.501199)
			(xy 117.826328 -226.509324) (xy 117.875721 -226.525372) (xy 117.921995 -226.54895) (xy 117.964011 -226.579476)
			(xy 118.000734 -226.616199) (xy 118.03126 -226.658215) (xy 118.054838 -226.704489) (xy 118.070886 -226.753882)
			(xy 118.079011 -226.805177) (xy 118.07952 -226.831144) (xy 118.079011 -226.857111) (xy 118.358667 -226.857111)
			(xy 118.358667 -226.805177) (xy 118.366792 -226.753882) (xy 118.38284 -226.704489) (xy 118.406418 -226.658215)
			(xy 118.436944 -226.616199) (xy 118.473667 -226.579476) (xy 118.515683 -226.54895) (xy 118.561957 -226.525372)
			(xy 118.61135 -226.509324) (xy 118.662645 -226.501199) (xy 118.714579 -226.501199) (xy 118.765874 -226.509324)
			(xy 118.815267 -226.525372) (xy 118.861541 -226.54895) (xy 118.903557 -226.579476) (xy 118.94028 -226.616199)
			(xy 118.970806 -226.658215) (xy 118.994384 -226.704489) (xy 119.010432 -226.753882) (xy 119.018557 -226.805177)
			(xy 119.019066 -226.831144) (xy 119.018557 -226.857111) (xy 119.298721 -226.857111) (xy 119.298721 -226.805177)
			(xy 119.306846 -226.753882) (xy 119.322894 -226.704489) (xy 119.346472 -226.658215) (xy 119.376998 -226.616199)
			(xy 119.413721 -226.579476) (xy 119.455737 -226.54895) (xy 119.502011 -226.525372) (xy 119.551404 -226.509324)
			(xy 119.602699 -226.501199) (xy 119.654633 -226.501199) (xy 119.705928 -226.509324) (xy 119.755321 -226.525372)
			(xy 119.801595 -226.54895) (xy 119.843611 -226.579476) (xy 119.880334 -226.616199) (xy 119.91086 -226.658215)
			(xy 119.934438 -226.704489) (xy 119.950486 -226.753882) (xy 119.958611 -226.805177) (xy 119.95912 -226.831144)
			(xy 119.958611 -226.857111) (xy 120.238267 -226.857111) (xy 120.238267 -226.805177) (xy 120.246392 -226.753882)
			(xy 120.26244 -226.704489) (xy 120.286018 -226.658215) (xy 120.316544 -226.616199) (xy 120.353267 -226.579476)
			(xy 120.395283 -226.54895) (xy 120.441557 -226.525372) (xy 120.49095 -226.509324) (xy 120.542245 -226.501199)
			(xy 120.594179 -226.501199) (xy 120.645474 -226.509324) (xy 120.694867 -226.525372) (xy 120.741141 -226.54895)
			(xy 120.783157 -226.579476) (xy 120.81988 -226.616199) (xy 120.850406 -226.658215) (xy 120.873984 -226.704489)
			(xy 120.890032 -226.753882) (xy 120.898157 -226.805177) (xy 120.898666 -226.831144) (xy 120.898157 -226.857111)
			(xy 121.178321 -226.857111) (xy 121.178321 -226.805177) (xy 121.186446 -226.753882) (xy 121.202494 -226.704489)
			(xy 121.226072 -226.658215) (xy 121.256598 -226.616199) (xy 121.293321 -226.579476) (xy 121.335337 -226.54895)
			(xy 121.381611 -226.525372) (xy 121.431004 -226.509324) (xy 121.482299 -226.501199) (xy 121.534233 -226.501199)
			(xy 121.585528 -226.509324) (xy 121.634921 -226.525372) (xy 121.681195 -226.54895) (xy 121.723211 -226.579476)
			(xy 121.759934 -226.616199) (xy 121.79046 -226.658215) (xy 121.814038 -226.704489) (xy 121.830086 -226.753882)
			(xy 121.838211 -226.805177) (xy 121.83872 -226.831144) (xy 121.838211 -226.857111) (xy 122.117867 -226.857111)
			(xy 122.117867 -226.805177) (xy 122.125992 -226.753882) (xy 122.14204 -226.704489) (xy 122.165618 -226.658215)
			(xy 122.196144 -226.616199) (xy 122.232867 -226.579476) (xy 122.274883 -226.54895) (xy 122.321157 -226.525372)
			(xy 122.37055 -226.509324) (xy 122.421845 -226.501199) (xy 122.473779 -226.501199) (xy 122.525074 -226.509324)
			(xy 122.574467 -226.525372) (xy 122.620741 -226.54895) (xy 122.662757 -226.579476) (xy 122.69948 -226.616199)
			(xy 122.730006 -226.658215) (xy 122.753584 -226.704489) (xy 122.769632 -226.753882) (xy 122.777757 -226.805177)
			(xy 122.778266 -226.831144) (xy 122.777757 -226.857111) (xy 123.057667 -226.857111) (xy 123.057667 -226.805177)
			(xy 123.065792 -226.753882) (xy 123.08184 -226.704489) (xy 123.105418 -226.658215) (xy 123.135944 -226.616199)
			(xy 123.172667 -226.579476) (xy 123.214683 -226.54895) (xy 123.260957 -226.525372) (xy 123.31035 -226.509324)
			(xy 123.361645 -226.501199) (xy 123.413579 -226.501199) (xy 123.464874 -226.509324) (xy 123.514267 -226.525372)
			(xy 123.560541 -226.54895) (xy 123.602557 -226.579476) (xy 123.63928 -226.616199) (xy 123.669806 -226.658215)
			(xy 123.693384 -226.704489) (xy 123.709432 -226.753882) (xy 123.717557 -226.805177) (xy 123.718066 -226.831144)
			(xy 123.717557 -226.857111) (xy 123.997721 -226.857111) (xy 123.997721 -226.805177) (xy 124.005846 -226.753882)
			(xy 124.021894 -226.704489) (xy 124.045472 -226.658215) (xy 124.075998 -226.616199) (xy 124.112721 -226.579476)
			(xy 124.154737 -226.54895) (xy 124.201011 -226.525372) (xy 124.250404 -226.509324) (xy 124.301699 -226.501199)
			(xy 124.353633 -226.501199) (xy 124.404928 -226.509324) (xy 124.454321 -226.525372) (xy 124.500595 -226.54895)
			(xy 124.542611 -226.579476) (xy 124.579334 -226.616199) (xy 124.60986 -226.658215) (xy 124.633438 -226.704489)
			(xy 124.649486 -226.753882) (xy 124.657611 -226.805177) (xy 124.65812 -226.831144) (xy 124.657611 -226.857111)
			(xy 124.937267 -226.857111) (xy 124.937267 -226.805177) (xy 124.945392 -226.753882) (xy 124.96144 -226.704489)
			(xy 124.985018 -226.658215) (xy 125.015544 -226.616199) (xy 125.052267 -226.579476) (xy 125.094283 -226.54895)
			(xy 125.140557 -226.525372) (xy 125.18995 -226.509324) (xy 125.241245 -226.501199) (xy 125.293179 -226.501199)
			(xy 125.344474 -226.509324) (xy 125.393867 -226.525372) (xy 125.440141 -226.54895) (xy 125.482157 -226.579476)
			(xy 125.51888 -226.616199) (xy 125.549406 -226.658215) (xy 125.572984 -226.704489) (xy 125.589032 -226.753882)
			(xy 125.597157 -226.805177) (xy 125.597666 -226.831144) (xy 125.597157 -226.857111) (xy 125.877067 -226.857111)
			(xy 125.877067 -226.805177) (xy 125.885192 -226.753882) (xy 125.90124 -226.704489) (xy 125.924818 -226.658215)
			(xy 125.955344 -226.616199) (xy 125.992067 -226.579476) (xy 126.034083 -226.54895) (xy 126.080357 -226.525372)
			(xy 126.12975 -226.509324) (xy 126.181045 -226.501199) (xy 126.232979 -226.501199) (xy 126.284274 -226.509324)
			(xy 126.333667 -226.525372) (xy 126.379941 -226.54895) (xy 126.421957 -226.579476) (xy 126.45868 -226.616199)
			(xy 126.489206 -226.658215) (xy 126.512784 -226.704489) (xy 126.528832 -226.753882) (xy 126.536957 -226.805177)
			(xy 126.537466 -226.831144) (xy 126.536957 -226.857111) (xy 126.817121 -226.857111) (xy 126.817121 -226.805177)
			(xy 126.825246 -226.753882) (xy 126.841294 -226.704489) (xy 126.864872 -226.658215) (xy 126.895398 -226.616199)
			(xy 126.932121 -226.579476) (xy 126.974137 -226.54895) (xy 127.020411 -226.525372) (xy 127.069804 -226.509324)
			(xy 127.121099 -226.501199) (xy 127.173033 -226.501199) (xy 127.224328 -226.509324) (xy 127.273721 -226.525372)
			(xy 127.319995 -226.54895) (xy 127.362011 -226.579476) (xy 127.398734 -226.616199) (xy 127.42926 -226.658215)
			(xy 127.452838 -226.704489) (xy 127.468886 -226.753882) (xy 127.477011 -226.805177) (xy 127.47752 -226.831144)
			(xy 127.477011 -226.857111) (xy 127.468886 -226.908406) (xy 127.452838 -226.957799) (xy 127.42926 -227.004073)
			(xy 127.398734 -227.046089) (xy 127.362011 -227.082812) (xy 127.319995 -227.113338) (xy 127.273721 -227.136916)
			(xy 127.224328 -227.152964) (xy 127.173033 -227.161089) (xy 127.121099 -227.161089) (xy 127.069804 -227.152964)
			(xy 127.020411 -227.136916) (xy 126.974137 -227.113338) (xy 126.932121 -227.082812) (xy 126.895398 -227.046089)
			(xy 126.864872 -227.004073) (xy 126.841294 -226.957799) (xy 126.825246 -226.908406) (xy 126.817121 -226.857111)
			(xy 126.536957 -226.857111) (xy 126.528832 -226.908406) (xy 126.512784 -226.957799) (xy 126.489206 -227.004073)
			(xy 126.45868 -227.046089) (xy 126.421957 -227.082812) (xy 126.379941 -227.113338) (xy 126.333667 -227.136916)
			(xy 126.284274 -227.152964) (xy 126.232979 -227.161089) (xy 126.181045 -227.161089) (xy 126.12975 -227.152964)
			(xy 126.080357 -227.136916) (xy 126.034083 -227.113338) (xy 125.992067 -227.082812) (xy 125.955344 -227.046089)
			(xy 125.924818 -227.004073) (xy 125.90124 -226.957799) (xy 125.885192 -226.908406) (xy 125.877067 -226.857111)
			(xy 125.597157 -226.857111) (xy 125.589032 -226.908406) (xy 125.572984 -226.957799) (xy 125.549406 -227.004073)
			(xy 125.51888 -227.046089) (xy 125.482157 -227.082812) (xy 125.440141 -227.113338) (xy 125.393867 -227.136916)
			(xy 125.344474 -227.152964) (xy 125.293179 -227.161089) (xy 125.241245 -227.161089) (xy 125.18995 -227.152964)
			(xy 125.140557 -227.136916) (xy 125.094283 -227.113338) (xy 125.052267 -227.082812) (xy 125.015544 -227.046089)
			(xy 124.985018 -227.004073) (xy 124.96144 -226.957799) (xy 124.945392 -226.908406) (xy 124.937267 -226.857111)
			(xy 124.657611 -226.857111) (xy 124.649486 -226.908406) (xy 124.633438 -226.957799) (xy 124.60986 -227.004073)
			(xy 124.579334 -227.046089) (xy 124.542611 -227.082812) (xy 124.500595 -227.113338) (xy 124.454321 -227.136916)
			(xy 124.404928 -227.152964) (xy 124.353633 -227.161089) (xy 124.301699 -227.161089) (xy 124.250404 -227.152964)
			(xy 124.201011 -227.136916) (xy 124.154737 -227.113338) (xy 124.112721 -227.082812) (xy 124.075998 -227.046089)
			(xy 124.045472 -227.004073) (xy 124.021894 -226.957799) (xy 124.005846 -226.908406) (xy 123.997721 -226.857111)
			(xy 123.717557 -226.857111) (xy 123.709432 -226.908406) (xy 123.693384 -226.957799) (xy 123.669806 -227.004073)
			(xy 123.63928 -227.046089) (xy 123.602557 -227.082812) (xy 123.560541 -227.113338) (xy 123.514267 -227.136916)
			(xy 123.464874 -227.152964) (xy 123.413579 -227.161089) (xy 123.361645 -227.161089) (xy 123.31035 -227.152964)
			(xy 123.260957 -227.136916) (xy 123.214683 -227.113338) (xy 123.172667 -227.082812) (xy 123.135944 -227.046089)
			(xy 123.105418 -227.004073) (xy 123.08184 -226.957799) (xy 123.065792 -226.908406) (xy 123.057667 -226.857111)
			(xy 122.777757 -226.857111) (xy 122.769632 -226.908406) (xy 122.753584 -226.957799) (xy 122.730006 -227.004073)
			(xy 122.69948 -227.046089) (xy 122.662757 -227.082812) (xy 122.620741 -227.113338) (xy 122.574467 -227.136916)
			(xy 122.525074 -227.152964) (xy 122.473779 -227.161089) (xy 122.421845 -227.161089) (xy 122.37055 -227.152964)
			(xy 122.321157 -227.136916) (xy 122.274883 -227.113338) (xy 122.232867 -227.082812) (xy 122.196144 -227.046089)
			(xy 122.165618 -227.004073) (xy 122.14204 -226.957799) (xy 122.125992 -226.908406) (xy 122.117867 -226.857111)
			(xy 121.838211 -226.857111) (xy 121.830086 -226.908406) (xy 121.814038 -226.957799) (xy 121.79046 -227.004073)
			(xy 121.759934 -227.046089) (xy 121.723211 -227.082812) (xy 121.681195 -227.113338) (xy 121.634921 -227.136916)
			(xy 121.585528 -227.152964) (xy 121.534233 -227.161089) (xy 121.482299 -227.161089) (xy 121.431004 -227.152964)
			(xy 121.381611 -227.136916) (xy 121.335337 -227.113338) (xy 121.293321 -227.082812) (xy 121.256598 -227.046089)
			(xy 121.226072 -227.004073) (xy 121.202494 -226.957799) (xy 121.186446 -226.908406) (xy 121.178321 -226.857111)
			(xy 120.898157 -226.857111) (xy 120.890032 -226.908406) (xy 120.873984 -226.957799) (xy 120.850406 -227.004073)
			(xy 120.81988 -227.046089) (xy 120.783157 -227.082812) (xy 120.741141 -227.113338) (xy 120.694867 -227.136916)
			(xy 120.645474 -227.152964) (xy 120.594179 -227.161089) (xy 120.542245 -227.161089) (xy 120.49095 -227.152964)
			(xy 120.441557 -227.136916) (xy 120.395283 -227.113338) (xy 120.353267 -227.082812) (xy 120.316544 -227.046089)
			(xy 120.286018 -227.004073) (xy 120.26244 -226.957799) (xy 120.246392 -226.908406) (xy 120.238267 -226.857111)
			(xy 119.958611 -226.857111) (xy 119.950486 -226.908406) (xy 119.934438 -226.957799) (xy 119.91086 -227.004073)
			(xy 119.880334 -227.046089) (xy 119.843611 -227.082812) (xy 119.801595 -227.113338) (xy 119.755321 -227.136916)
			(xy 119.705928 -227.152964) (xy 119.654633 -227.161089) (xy 119.602699 -227.161089) (xy 119.551404 -227.152964)
			(xy 119.502011 -227.136916) (xy 119.455737 -227.113338) (xy 119.413721 -227.082812) (xy 119.376998 -227.046089)
			(xy 119.346472 -227.004073) (xy 119.322894 -226.957799) (xy 119.306846 -226.908406) (xy 119.298721 -226.857111)
			(xy 119.018557 -226.857111) (xy 119.010432 -226.908406) (xy 118.994384 -226.957799) (xy 118.970806 -227.004073)
			(xy 118.94028 -227.046089) (xy 118.903557 -227.082812) (xy 118.861541 -227.113338) (xy 118.815267 -227.136916)
			(xy 118.765874 -227.152964) (xy 118.714579 -227.161089) (xy 118.662645 -227.161089) (xy 118.61135 -227.152964)
			(xy 118.561957 -227.136916) (xy 118.515683 -227.113338) (xy 118.473667 -227.082812) (xy 118.436944 -227.046089)
			(xy 118.406418 -227.004073) (xy 118.38284 -226.957799) (xy 118.366792 -226.908406) (xy 118.358667 -226.857111)
			(xy 118.079011 -226.857111) (xy 118.070886 -226.908406) (xy 118.054838 -226.957799) (xy 118.03126 -227.004073)
			(xy 118.000734 -227.046089) (xy 117.964011 -227.082812) (xy 117.921995 -227.113338) (xy 117.875721 -227.136916)
			(xy 117.826328 -227.152964) (xy 117.775033 -227.161089) (xy 117.723099 -227.161089) (xy 117.671804 -227.152964)
			(xy 117.622411 -227.136916) (xy 117.576137 -227.113338) (xy 117.534121 -227.082812) (xy 117.497398 -227.046089)
			(xy 117.466872 -227.004073) (xy 117.443294 -226.957799) (xy 117.427246 -226.908406) (xy 117.419121 -226.857111)
			(xy 117.138957 -226.857111) (xy 117.130832 -226.908406) (xy 117.114784 -226.957799) (xy 117.091206 -227.004073)
			(xy 117.06068 -227.046089) (xy 117.023957 -227.082812) (xy 116.981941 -227.113338) (xy 116.935667 -227.136916)
			(xy 116.886274 -227.152964) (xy 116.834979 -227.161089) (xy 116.783045 -227.161089) (xy 116.73175 -227.152964)
			(xy 116.682357 -227.136916) (xy 116.636083 -227.113338) (xy 116.594067 -227.082812) (xy 116.557344 -227.046089)
			(xy 116.526818 -227.004073) (xy 116.50324 -226.957799) (xy 116.487192 -226.908406) (xy 116.479067 -226.857111)
			(xy 116.199411 -226.857111) (xy 116.191286 -226.908406) (xy 116.175238 -226.957799) (xy 116.15166 -227.004073)
			(xy 116.121134 -227.046089) (xy 116.084411 -227.082812) (xy 116.042395 -227.113338) (xy 115.996121 -227.136916)
			(xy 115.946728 -227.152964) (xy 115.895433 -227.161089) (xy 115.843499 -227.161089) (xy 115.792204 -227.152964)
			(xy 115.742811 -227.136916) (xy 115.696537 -227.113338) (xy 115.654521 -227.082812) (xy 115.617798 -227.046089)
			(xy 115.587272 -227.004073) (xy 115.563694 -226.957799) (xy 115.547646 -226.908406) (xy 115.539521 -226.857111)
			(xy 115.259611 -226.857111) (xy 115.251486 -226.908406) (xy 115.235438 -226.957799) (xy 115.21186 -227.004073)
			(xy 115.181334 -227.046089) (xy 115.144611 -227.082812) (xy 115.102595 -227.113338) (xy 115.056321 -227.136916)
			(xy 115.006928 -227.152964) (xy 114.955633 -227.161089) (xy 114.903699 -227.161089) (xy 114.852404 -227.152964)
			(xy 114.803011 -227.136916) (xy 114.756737 -227.113338) (xy 114.714721 -227.082812) (xy 114.677998 -227.046089)
			(xy 114.647472 -227.004073) (xy 114.623894 -226.957799) (xy 114.607846 -226.908406) (xy 114.599721 -226.857111)
			(xy 114.319811 -226.857111) (xy 114.311686 -226.908406) (xy 114.295638 -226.957799) (xy 114.27206 -227.004073)
			(xy 114.241534 -227.046089) (xy 114.204811 -227.082812) (xy 114.162795 -227.113338) (xy 114.116521 -227.136916)
			(xy 114.067128 -227.152964) (xy 114.015833 -227.161089) (xy 113.963899 -227.161089) (xy 113.912604 -227.152964)
			(xy 113.863211 -227.136916) (xy 113.816937 -227.113338) (xy 113.774921 -227.082812) (xy 113.738198 -227.046089)
			(xy 113.707672 -227.004073) (xy 113.684094 -226.957799) (xy 113.668046 -226.908406) (xy 113.659921 -226.857111)
			(xy 113.379757 -226.857111) (xy 113.371632 -226.908406) (xy 113.355584 -226.957799) (xy 113.332006 -227.004073)
			(xy 113.30148 -227.046089) (xy 113.264757 -227.082812) (xy 113.222741 -227.113338) (xy 113.176467 -227.136916)
			(xy 113.127074 -227.152964) (xy 113.075779 -227.161089) (xy 113.023845 -227.161089) (xy 112.97255 -227.152964)
			(xy 112.923157 -227.136916) (xy 112.876883 -227.113338) (xy 112.834867 -227.082812) (xy 112.798144 -227.046089)
			(xy 112.767618 -227.004073) (xy 112.74404 -226.957799) (xy 112.727992 -226.908406) (xy 112.719867 -226.857111)
			(xy 112.440211 -226.857111) (xy 112.432086 -226.908406) (xy 112.416038 -226.957799) (xy 112.39246 -227.004073)
			(xy 112.361934 -227.046089) (xy 112.325211 -227.082812) (xy 112.283195 -227.113338) (xy 112.236921 -227.136916)
			(xy 112.187528 -227.152964) (xy 112.136233 -227.161089) (xy 112.084299 -227.161089) (xy 112.033004 -227.152964)
			(xy 111.983611 -227.136916) (xy 111.937337 -227.113338) (xy 111.895321 -227.082812) (xy 111.858598 -227.046089)
			(xy 111.828072 -227.004073) (xy 111.804494 -226.957799) (xy 111.788446 -226.908406) (xy 111.780321 -226.857111)
			(xy 111.587026 -226.857111) (xy 111.587026 -227.263706) (xy 111.587453 -227.273756) (xy 111.595173 -227.292315)
			(xy 111.609426 -227.306488) (xy 111.628028 -227.314102) (xy 111.63808 -227.314506) (xy 111.640366 -227.314506)
			(xy 111.66634 -227.314986) (xy 111.71765 -227.323108) (xy 111.767057 -227.339157) (xy 111.813345 -227.362738)
			(xy 111.855374 -227.39327) (xy 111.892108 -227.430001) (xy 111.922645 -227.472026) (xy 111.94623 -227.518312)
			(xy 111.962284 -227.567717) (xy 111.970411 -227.619026) (xy 111.970411 -227.670927) (xy 112.250221 -227.670927)
			(xy 112.250221 -227.618993) (xy 112.258346 -227.567698) (xy 112.274394 -227.518305) (xy 112.297972 -227.472031)
			(xy 112.328498 -227.430015) (xy 112.365221 -227.393292) (xy 112.407237 -227.362766) (xy 112.453511 -227.339188)
			(xy 112.502904 -227.32314) (xy 112.554199 -227.315015) (xy 112.606133 -227.315015) (xy 112.657428 -227.32314)
			(xy 112.706821 -227.339188) (xy 112.753095 -227.362766) (xy 112.795111 -227.393292) (xy 112.831834 -227.430015)
			(xy 112.86236 -227.472031) (xy 112.885938 -227.518305) (xy 112.901986 -227.567698) (xy 112.910111 -227.618993)
			(xy 112.91062 -227.64496) (xy 112.910111 -227.670927) (xy 113.190021 -227.670927) (xy 113.190021 -227.618993)
			(xy 113.198146 -227.567698) (xy 113.214194 -227.518305) (xy 113.237772 -227.472031) (xy 113.268298 -227.430015)
			(xy 113.305021 -227.393292) (xy 113.347037 -227.362766) (xy 113.393311 -227.339188) (xy 113.442704 -227.32314)
			(xy 113.493999 -227.315015) (xy 113.545933 -227.315015) (xy 113.597228 -227.32314) (xy 113.646621 -227.339188)
			(xy 113.692895 -227.362766) (xy 113.734911 -227.393292) (xy 113.771634 -227.430015) (xy 113.80216 -227.472031)
			(xy 113.825738 -227.518305) (xy 113.841786 -227.567698) (xy 113.849911 -227.618993) (xy 113.85042 -227.64496)
			(xy 113.849911 -227.670927) (xy 114.130075 -227.670927) (xy 114.130075 -227.618993) (xy 114.1382 -227.567698)
			(xy 114.154248 -227.518305) (xy 114.177826 -227.472031) (xy 114.208352 -227.430015) (xy 114.245075 -227.393292)
			(xy 114.287091 -227.362766) (xy 114.333365 -227.339188) (xy 114.382758 -227.32314) (xy 114.434053 -227.315015)
			(xy 114.485987 -227.315015) (xy 114.537282 -227.32314) (xy 114.586675 -227.339188) (xy 114.632949 -227.362766)
			(xy 114.674965 -227.393292) (xy 114.711688 -227.430015) (xy 114.742214 -227.472031) (xy 114.765792 -227.518305)
			(xy 114.78184 -227.567698) (xy 114.789965 -227.618993) (xy 114.790474 -227.64496) (xy 114.789965 -227.670927)
			(xy 115.069621 -227.670927) (xy 115.069621 -227.618993) (xy 115.077746 -227.567698) (xy 115.093794 -227.518305)
			(xy 115.117372 -227.472031) (xy 115.147898 -227.430015) (xy 115.184621 -227.393292) (xy 115.226637 -227.362766)
			(xy 115.272911 -227.339188) (xy 115.322304 -227.32314) (xy 115.373599 -227.315015) (xy 115.425533 -227.315015)
			(xy 115.476828 -227.32314) (xy 115.526221 -227.339188) (xy 115.572495 -227.362766) (xy 115.614511 -227.393292)
			(xy 115.651234 -227.430015) (xy 115.68176 -227.472031) (xy 115.705338 -227.518305) (xy 115.721386 -227.567698)
			(xy 115.729511 -227.618993) (xy 115.73002 -227.64496) (xy 115.729511 -227.670927) (xy 116.009421 -227.670927)
			(xy 116.009421 -227.618993) (xy 116.017546 -227.567698) (xy 116.033594 -227.518305) (xy 116.057172 -227.472031)
			(xy 116.087698 -227.430015) (xy 116.124421 -227.393292) (xy 116.166437 -227.362766) (xy 116.212711 -227.339188)
			(xy 116.262104 -227.32314) (xy 116.313399 -227.315015) (xy 116.365333 -227.315015) (xy 116.416628 -227.32314)
			(xy 116.466021 -227.339188) (xy 116.512295 -227.362766) (xy 116.554311 -227.393292) (xy 116.591034 -227.430015)
			(xy 116.62156 -227.472031) (xy 116.645138 -227.518305) (xy 116.661186 -227.567698) (xy 116.669311 -227.618993)
			(xy 116.66982 -227.64496) (xy 116.669311 -227.670927) (xy 116.949221 -227.670927) (xy 116.949221 -227.618993)
			(xy 116.957346 -227.567698) (xy 116.973394 -227.518305) (xy 116.996972 -227.472031) (xy 117.027498 -227.430015)
			(xy 117.064221 -227.393292) (xy 117.106237 -227.362766) (xy 117.152511 -227.339188) (xy 117.201904 -227.32314)
			(xy 117.253199 -227.315015) (xy 117.305133 -227.315015) (xy 117.356428 -227.32314) (xy 117.405821 -227.339188)
			(xy 117.452095 -227.362766) (xy 117.494111 -227.393292) (xy 117.530834 -227.430015) (xy 117.56136 -227.472031)
			(xy 117.584938 -227.518305) (xy 117.600986 -227.567698) (xy 117.609111 -227.618993) (xy 117.60962 -227.64496)
			(xy 117.609111 -227.670927) (xy 117.889021 -227.670927) (xy 117.889021 -227.618993) (xy 117.897146 -227.567698)
			(xy 117.913194 -227.518305) (xy 117.936772 -227.472031) (xy 117.967298 -227.430015) (xy 118.004021 -227.393292)
			(xy 118.046037 -227.362766) (xy 118.092311 -227.339188) (xy 118.141704 -227.32314) (xy 118.192999 -227.315015)
			(xy 118.244933 -227.315015) (xy 118.296228 -227.32314) (xy 118.345621 -227.339188) (xy 118.391895 -227.362766)
			(xy 118.433911 -227.393292) (xy 118.470634 -227.430015) (xy 118.50116 -227.472031) (xy 118.524738 -227.518305)
			(xy 118.540786 -227.567698) (xy 118.548911 -227.618993) (xy 118.54942 -227.64496) (xy 118.548911 -227.670927)
			(xy 118.828821 -227.670927) (xy 118.828821 -227.618993) (xy 118.836946 -227.567698) (xy 118.852994 -227.518305)
			(xy 118.876572 -227.472031) (xy 118.907098 -227.430015) (xy 118.943821 -227.393292) (xy 118.985837 -227.362766)
			(xy 119.032111 -227.339188) (xy 119.081504 -227.32314) (xy 119.132799 -227.315015) (xy 119.184733 -227.315015)
			(xy 119.236028 -227.32314) (xy 119.285421 -227.339188) (xy 119.331695 -227.362766) (xy 119.373711 -227.393292)
			(xy 119.410434 -227.430015) (xy 119.44096 -227.472031) (xy 119.464538 -227.518305) (xy 119.480586 -227.567698)
			(xy 119.488711 -227.618993) (xy 119.48922 -227.64496) (xy 119.488711 -227.670927) (xy 119.768621 -227.670927)
			(xy 119.768621 -227.618993) (xy 119.776746 -227.567698) (xy 119.792794 -227.518305) (xy 119.816372 -227.472031)
			(xy 119.846898 -227.430015) (xy 119.883621 -227.393292) (xy 119.925637 -227.362766) (xy 119.971911 -227.339188)
			(xy 120.021304 -227.32314) (xy 120.072599 -227.315015) (xy 120.124533 -227.315015) (xy 120.175828 -227.32314)
			(xy 120.225221 -227.339188) (xy 120.271495 -227.362766) (xy 120.313511 -227.393292) (xy 120.350234 -227.430015)
			(xy 120.38076 -227.472031) (xy 120.404338 -227.518305) (xy 120.420386 -227.567698) (xy 120.428511 -227.618993)
			(xy 120.42902 -227.64496) (xy 120.428511 -227.670927) (xy 120.708421 -227.670927) (xy 120.708421 -227.618993)
			(xy 120.716546 -227.567698) (xy 120.732594 -227.518305) (xy 120.756172 -227.472031) (xy 120.786698 -227.430015)
			(xy 120.823421 -227.393292) (xy 120.865437 -227.362766) (xy 120.911711 -227.339188) (xy 120.961104 -227.32314)
			(xy 121.012399 -227.315015) (xy 121.064333 -227.315015) (xy 121.115628 -227.32314) (xy 121.165021 -227.339188)
			(xy 121.211295 -227.362766) (xy 121.253311 -227.393292) (xy 121.290034 -227.430015) (xy 121.32056 -227.472031)
			(xy 121.344138 -227.518305) (xy 121.360186 -227.567698) (xy 121.368311 -227.618993) (xy 121.36882 -227.64496)
			(xy 121.368311 -227.670927) (xy 121.647967 -227.670927) (xy 121.647967 -227.618993) (xy 121.656092 -227.567698)
			(xy 121.67214 -227.518305) (xy 121.695718 -227.472031) (xy 121.726244 -227.430015) (xy 121.762967 -227.393292)
			(xy 121.804983 -227.362766) (xy 121.851257 -227.339188) (xy 121.90065 -227.32314) (xy 121.951945 -227.315015)
			(xy 122.003879 -227.315015) (xy 122.055174 -227.32314) (xy 122.104567 -227.339188) (xy 122.150841 -227.362766)
			(xy 122.192857 -227.393292) (xy 122.22958 -227.430015) (xy 122.260106 -227.472031) (xy 122.283684 -227.518305)
			(xy 122.299732 -227.567698) (xy 122.307857 -227.618993) (xy 122.308366 -227.64496) (xy 122.307857 -227.670927)
			(xy 122.588021 -227.670927) (xy 122.588021 -227.618993) (xy 122.596146 -227.567698) (xy 122.612194 -227.518305)
			(xy 122.635772 -227.472031) (xy 122.666298 -227.430015) (xy 122.703021 -227.393292) (xy 122.745037 -227.362766)
			(xy 122.791311 -227.339188) (xy 122.840704 -227.32314) (xy 122.891999 -227.315015) (xy 122.943933 -227.315015)
			(xy 122.995228 -227.32314) (xy 123.044621 -227.339188) (xy 123.090895 -227.362766) (xy 123.132911 -227.393292)
			(xy 123.169634 -227.430015) (xy 123.20016 -227.472031) (xy 123.223738 -227.518305) (xy 123.239786 -227.567698)
			(xy 123.247911 -227.618993) (xy 123.24842 -227.64496) (xy 123.247911 -227.670927) (xy 123.527821 -227.670927)
			(xy 123.527821 -227.618993) (xy 123.535946 -227.567698) (xy 123.551994 -227.518305) (xy 123.575572 -227.472031)
			(xy 123.606098 -227.430015) (xy 123.642821 -227.393292) (xy 123.684837 -227.362766) (xy 123.731111 -227.339188)
			(xy 123.780504 -227.32314) (xy 123.831799 -227.315015) (xy 123.883733 -227.315015) (xy 123.935028 -227.32314)
			(xy 123.984421 -227.339188) (xy 124.030695 -227.362766) (xy 124.072711 -227.393292) (xy 124.109434 -227.430015)
			(xy 124.13996 -227.472031) (xy 124.163538 -227.518305) (xy 124.179586 -227.567698) (xy 124.187711 -227.618993)
			(xy 124.18822 -227.64496) (xy 124.187711 -227.670927) (xy 124.467621 -227.670927) (xy 124.467621 -227.618993)
			(xy 124.475746 -227.567698) (xy 124.491794 -227.518305) (xy 124.515372 -227.472031) (xy 124.545898 -227.430015)
			(xy 124.582621 -227.393292) (xy 124.624637 -227.362766) (xy 124.670911 -227.339188) (xy 124.720304 -227.32314)
			(xy 124.771599 -227.315015) (xy 124.823533 -227.315015) (xy 124.874828 -227.32314) (xy 124.924221 -227.339188)
			(xy 124.970495 -227.362766) (xy 125.012511 -227.393292) (xy 125.049234 -227.430015) (xy 125.07976 -227.472031)
			(xy 125.103338 -227.518305) (xy 125.119386 -227.567698) (xy 125.127511 -227.618993) (xy 125.12802 -227.64496)
			(xy 125.127511 -227.670927) (xy 125.407421 -227.670927) (xy 125.407421 -227.618993) (xy 125.415546 -227.567698)
			(xy 125.431594 -227.518305) (xy 125.455172 -227.472031) (xy 125.485698 -227.430015) (xy 125.522421 -227.393292)
			(xy 125.564437 -227.362766) (xy 125.610711 -227.339188) (xy 125.660104 -227.32314) (xy 125.711399 -227.315015)
			(xy 125.763333 -227.315015) (xy 125.814628 -227.32314) (xy 125.864021 -227.339188) (xy 125.910295 -227.362766)
			(xy 125.952311 -227.393292) (xy 125.989034 -227.430015) (xy 126.01956 -227.472031) (xy 126.043138 -227.518305)
			(xy 126.059186 -227.567698) (xy 126.067311 -227.618993) (xy 126.06782 -227.64496) (xy 126.067311 -227.670927)
			(xy 126.347221 -227.670927) (xy 126.347221 -227.618993) (xy 126.355346 -227.567698) (xy 126.371394 -227.518305)
			(xy 126.394972 -227.472031) (xy 126.425498 -227.430015) (xy 126.462221 -227.393292) (xy 126.504237 -227.362766)
			(xy 126.550511 -227.339188) (xy 126.599904 -227.32314) (xy 126.651199 -227.315015) (xy 126.703133 -227.315015)
			(xy 126.754428 -227.32314) (xy 126.803821 -227.339188) (xy 126.850095 -227.362766) (xy 126.892111 -227.393292)
			(xy 126.928834 -227.430015) (xy 126.95936 -227.472031) (xy 126.982938 -227.518305) (xy 126.998986 -227.567698)
			(xy 127.007111 -227.618993) (xy 127.00762 -227.64496) (xy 127.007111 -227.670927) (xy 126.998986 -227.722222)
			(xy 126.982938 -227.771615) (xy 126.95936 -227.817889) (xy 126.928834 -227.859905) (xy 126.892111 -227.896628)
			(xy 126.850095 -227.927154) (xy 126.803821 -227.950732) (xy 126.754428 -227.96678) (xy 126.703133 -227.974905)
			(xy 126.651199 -227.974905) (xy 126.599904 -227.96678) (xy 126.550511 -227.950732) (xy 126.504237 -227.927154)
			(xy 126.462221 -227.896628) (xy 126.425498 -227.859905) (xy 126.394972 -227.817889) (xy 126.371394 -227.771615)
			(xy 126.355346 -227.722222) (xy 126.347221 -227.670927) (xy 126.067311 -227.670927) (xy 126.059186 -227.722222)
			(xy 126.043138 -227.771615) (xy 126.01956 -227.817889) (xy 125.989034 -227.859905) (xy 125.952311 -227.896628)
			(xy 125.910295 -227.927154) (xy 125.864021 -227.950732) (xy 125.814628 -227.96678) (xy 125.763333 -227.974905)
			(xy 125.711399 -227.974905) (xy 125.660104 -227.96678) (xy 125.610711 -227.950732) (xy 125.564437 -227.927154)
			(xy 125.522421 -227.896628) (xy 125.485698 -227.859905) (xy 125.455172 -227.817889) (xy 125.431594 -227.771615)
			(xy 125.415546 -227.722222) (xy 125.407421 -227.670927) (xy 125.127511 -227.670927) (xy 125.119386 -227.722222)
			(xy 125.103338 -227.771615) (xy 125.07976 -227.817889) (xy 125.049234 -227.859905) (xy 125.012511 -227.896628)
			(xy 124.970495 -227.927154) (xy 124.924221 -227.950732) (xy 124.874828 -227.96678) (xy 124.823533 -227.974905)
			(xy 124.771599 -227.974905) (xy 124.720304 -227.96678) (xy 124.670911 -227.950732) (xy 124.624637 -227.927154)
			(xy 124.582621 -227.896628) (xy 124.545898 -227.859905) (xy 124.515372 -227.817889) (xy 124.491794 -227.771615)
			(xy 124.475746 -227.722222) (xy 124.467621 -227.670927) (xy 124.187711 -227.670927) (xy 124.179586 -227.722222)
			(xy 124.163538 -227.771615) (xy 124.13996 -227.817889) (xy 124.109434 -227.859905) (xy 124.072711 -227.896628)
			(xy 124.030695 -227.927154) (xy 123.984421 -227.950732) (xy 123.935028 -227.96678) (xy 123.883733 -227.974905)
			(xy 123.831799 -227.974905) (xy 123.780504 -227.96678) (xy 123.731111 -227.950732) (xy 123.684837 -227.927154)
			(xy 123.642821 -227.896628) (xy 123.606098 -227.859905) (xy 123.575572 -227.817889) (xy 123.551994 -227.771615)
			(xy 123.535946 -227.722222) (xy 123.527821 -227.670927) (xy 123.247911 -227.670927) (xy 123.239786 -227.722222)
			(xy 123.223738 -227.771615) (xy 123.20016 -227.817889) (xy 123.169634 -227.859905) (xy 123.132911 -227.896628)
			(xy 123.090895 -227.927154) (xy 123.044621 -227.950732) (xy 122.995228 -227.96678) (xy 122.943933 -227.974905)
			(xy 122.891999 -227.974905) (xy 122.840704 -227.96678) (xy 122.791311 -227.950732) (xy 122.745037 -227.927154)
			(xy 122.703021 -227.896628) (xy 122.666298 -227.859905) (xy 122.635772 -227.817889) (xy 122.612194 -227.771615)
			(xy 122.596146 -227.722222) (xy 122.588021 -227.670927) (xy 122.307857 -227.670927) (xy 122.299732 -227.722222)
			(xy 122.283684 -227.771615) (xy 122.260106 -227.817889) (xy 122.22958 -227.859905) (xy 122.192857 -227.896628)
			(xy 122.150841 -227.927154) (xy 122.104567 -227.950732) (xy 122.055174 -227.96678) (xy 122.003879 -227.974905)
			(xy 121.951945 -227.974905) (xy 121.90065 -227.96678) (xy 121.851257 -227.950732) (xy 121.804983 -227.927154)
			(xy 121.762967 -227.896628) (xy 121.726244 -227.859905) (xy 121.695718 -227.817889) (xy 121.67214 -227.771615)
			(xy 121.656092 -227.722222) (xy 121.647967 -227.670927) (xy 121.368311 -227.670927) (xy 121.360186 -227.722222)
			(xy 121.344138 -227.771615) (xy 121.32056 -227.817889) (xy 121.290034 -227.859905) (xy 121.253311 -227.896628)
			(xy 121.211295 -227.927154) (xy 121.165021 -227.950732) (xy 121.115628 -227.96678) (xy 121.064333 -227.974905)
			(xy 121.012399 -227.974905) (xy 120.961104 -227.96678) (xy 120.911711 -227.950732) (xy 120.865437 -227.927154)
			(xy 120.823421 -227.896628) (xy 120.786698 -227.859905) (xy 120.756172 -227.817889) (xy 120.732594 -227.771615)
			(xy 120.716546 -227.722222) (xy 120.708421 -227.670927) (xy 120.428511 -227.670927) (xy 120.420386 -227.722222)
			(xy 120.404338 -227.771615) (xy 120.38076 -227.817889) (xy 120.350234 -227.859905) (xy 120.313511 -227.896628)
			(xy 120.271495 -227.927154) (xy 120.225221 -227.950732) (xy 120.175828 -227.96678) (xy 120.124533 -227.974905)
			(xy 120.072599 -227.974905) (xy 120.021304 -227.96678) (xy 119.971911 -227.950732) (xy 119.925637 -227.927154)
			(xy 119.883621 -227.896628) (xy 119.846898 -227.859905) (xy 119.816372 -227.817889) (xy 119.792794 -227.771615)
			(xy 119.776746 -227.722222) (xy 119.768621 -227.670927) (xy 119.488711 -227.670927) (xy 119.480586 -227.722222)
			(xy 119.464538 -227.771615) (xy 119.44096 -227.817889) (xy 119.410434 -227.859905) (xy 119.373711 -227.896628)
			(xy 119.331695 -227.927154) (xy 119.285421 -227.950732) (xy 119.236028 -227.96678) (xy 119.184733 -227.974905)
			(xy 119.132799 -227.974905) (xy 119.081504 -227.96678) (xy 119.032111 -227.950732) (xy 118.985837 -227.927154)
			(xy 118.943821 -227.896628) (xy 118.907098 -227.859905) (xy 118.876572 -227.817889) (xy 118.852994 -227.771615)
			(xy 118.836946 -227.722222) (xy 118.828821 -227.670927) (xy 118.548911 -227.670927) (xy 118.540786 -227.722222)
			(xy 118.524738 -227.771615) (xy 118.50116 -227.817889) (xy 118.470634 -227.859905) (xy 118.433911 -227.896628)
			(xy 118.391895 -227.927154) (xy 118.345621 -227.950732) (xy 118.296228 -227.96678) (xy 118.244933 -227.974905)
			(xy 118.192999 -227.974905) (xy 118.141704 -227.96678) (xy 118.092311 -227.950732) (xy 118.046037 -227.927154)
			(xy 118.004021 -227.896628) (xy 117.967298 -227.859905) (xy 117.936772 -227.817889) (xy 117.913194 -227.771615)
			(xy 117.897146 -227.722222) (xy 117.889021 -227.670927) (xy 117.609111 -227.670927) (xy 117.600986 -227.722222)
			(xy 117.584938 -227.771615) (xy 117.56136 -227.817889) (xy 117.530834 -227.859905) (xy 117.494111 -227.896628)
			(xy 117.452095 -227.927154) (xy 117.405821 -227.950732) (xy 117.356428 -227.96678) (xy 117.305133 -227.974905)
			(xy 117.253199 -227.974905) (xy 117.201904 -227.96678) (xy 117.152511 -227.950732) (xy 117.106237 -227.927154)
			(xy 117.064221 -227.896628) (xy 117.027498 -227.859905) (xy 116.996972 -227.817889) (xy 116.973394 -227.771615)
			(xy 116.957346 -227.722222) (xy 116.949221 -227.670927) (xy 116.669311 -227.670927) (xy 116.661186 -227.722222)
			(xy 116.645138 -227.771615) (xy 116.62156 -227.817889) (xy 116.591034 -227.859905) (xy 116.554311 -227.896628)
			(xy 116.512295 -227.927154) (xy 116.466021 -227.950732) (xy 116.416628 -227.96678) (xy 116.365333 -227.974905)
			(xy 116.313399 -227.974905) (xy 116.262104 -227.96678) (xy 116.212711 -227.950732) (xy 116.166437 -227.927154)
			(xy 116.124421 -227.896628) (xy 116.087698 -227.859905) (xy 116.057172 -227.817889) (xy 116.033594 -227.771615)
			(xy 116.017546 -227.722222) (xy 116.009421 -227.670927) (xy 115.729511 -227.670927) (xy 115.721386 -227.722222)
			(xy 115.705338 -227.771615) (xy 115.68176 -227.817889) (xy 115.651234 -227.859905) (xy 115.614511 -227.896628)
			(xy 115.572495 -227.927154) (xy 115.526221 -227.950732) (xy 115.476828 -227.96678) (xy 115.425533 -227.974905)
			(xy 115.373599 -227.974905) (xy 115.322304 -227.96678) (xy 115.272911 -227.950732) (xy 115.226637 -227.927154)
			(xy 115.184621 -227.896628) (xy 115.147898 -227.859905) (xy 115.117372 -227.817889) (xy 115.093794 -227.771615)
			(xy 115.077746 -227.722222) (xy 115.069621 -227.670927) (xy 114.789965 -227.670927) (xy 114.78184 -227.722222)
			(xy 114.765792 -227.771615) (xy 114.742214 -227.817889) (xy 114.711688 -227.859905) (xy 114.674965 -227.896628)
			(xy 114.632949 -227.927154) (xy 114.586675 -227.950732) (xy 114.537282 -227.96678) (xy 114.485987 -227.974905)
			(xy 114.434053 -227.974905) (xy 114.382758 -227.96678) (xy 114.333365 -227.950732) (xy 114.287091 -227.927154)
			(xy 114.245075 -227.896628) (xy 114.208352 -227.859905) (xy 114.177826 -227.817889) (xy 114.154248 -227.771615)
			(xy 114.1382 -227.722222) (xy 114.130075 -227.670927) (xy 113.849911 -227.670927) (xy 113.841786 -227.722222)
			(xy 113.825738 -227.771615) (xy 113.80216 -227.817889) (xy 113.771634 -227.859905) (xy 113.734911 -227.896628)
			(xy 113.692895 -227.927154) (xy 113.646621 -227.950732) (xy 113.597228 -227.96678) (xy 113.545933 -227.974905)
			(xy 113.493999 -227.974905) (xy 113.442704 -227.96678) (xy 113.393311 -227.950732) (xy 113.347037 -227.927154)
			(xy 113.305021 -227.896628) (xy 113.268298 -227.859905) (xy 113.237772 -227.817889) (xy 113.214194 -227.771615)
			(xy 113.198146 -227.722222) (xy 113.190021 -227.670927) (xy 112.910111 -227.670927) (xy 112.901986 -227.722222)
			(xy 112.885938 -227.771615) (xy 112.86236 -227.817889) (xy 112.831834 -227.859905) (xy 112.795111 -227.896628)
			(xy 112.753095 -227.927154) (xy 112.706821 -227.950732) (xy 112.657428 -227.96678) (xy 112.606133 -227.974905)
			(xy 112.554199 -227.974905) (xy 112.502904 -227.96678) (xy 112.453511 -227.950732) (xy 112.407237 -227.927154)
			(xy 112.365221 -227.896628) (xy 112.328498 -227.859905) (xy 112.297972 -227.817889) (xy 112.274394 -227.771615)
			(xy 112.258346 -227.722222) (xy 112.250221 -227.670927) (xy 111.970411 -227.670927) (xy 111.970411 -227.670974)
			(xy 111.962284 -227.722283) (xy 111.94623 -227.771688) (xy 111.922645 -227.817974) (xy 111.892108 -227.859999)
			(xy 111.855374 -227.89673) (xy 111.813345 -227.927262) (xy 111.767057 -227.950843) (xy 111.71765 -227.966892)
			(xy 111.66634 -227.975014) (xy 111.640366 -227.975414) (xy 111.63808 -227.975414) (xy 111.628023 -227.975785)
			(xy 111.609412 -227.983405) (xy 111.595155 -227.997588) (xy 111.587437 -228.016159) (xy 111.587026 -228.026214)
			(xy 111.587026 -228.484997) (xy 111.780067 -228.484997) (xy 111.780067 -228.433063) (xy 111.788192 -228.381768)
			(xy 111.80424 -228.332375) (xy 111.827818 -228.286101) (xy 111.858344 -228.244085) (xy 111.895067 -228.207362)
			(xy 111.937083 -228.176836) (xy 111.983357 -228.153258) (xy 112.03275 -228.13721) (xy 112.084045 -228.129085)
			(xy 112.135979 -228.129085) (xy 112.187274 -228.13721) (xy 112.236667 -228.153258) (xy 112.282941 -228.176836)
			(xy 112.324957 -228.207362) (xy 112.36168 -228.244085) (xy 112.392206 -228.286101) (xy 112.415784 -228.332375)
			(xy 112.431832 -228.381768) (xy 112.439957 -228.433063) (xy 112.440466 -228.45903) (xy 112.439957 -228.484997)
			(xy 112.719867 -228.484997) (xy 112.719867 -228.433063) (xy 112.727992 -228.381768) (xy 112.74404 -228.332375)
			(xy 112.767618 -228.286101) (xy 112.798144 -228.244085) (xy 112.834867 -228.207362) (xy 112.876883 -228.176836)
			(xy 112.923157 -228.153258) (xy 112.97255 -228.13721) (xy 113.023845 -228.129085) (xy 113.075779 -228.129085)
			(xy 113.127074 -228.13721) (xy 113.176467 -228.153258) (xy 113.222741 -228.176836) (xy 113.264757 -228.207362)
			(xy 113.30148 -228.244085) (xy 113.332006 -228.286101) (xy 113.355584 -228.332375) (xy 113.371632 -228.381768)
			(xy 113.379757 -228.433063) (xy 113.380266 -228.45903) (xy 113.379757 -228.484997) (xy 113.659667 -228.484997)
			(xy 113.659667 -228.433063) (xy 113.667792 -228.381768) (xy 113.68384 -228.332375) (xy 113.707418 -228.286101)
			(xy 113.737944 -228.244085) (xy 113.774667 -228.207362) (xy 113.816683 -228.176836) (xy 113.862957 -228.153258)
			(xy 113.91235 -228.13721) (xy 113.963645 -228.129085) (xy 114.015579 -228.129085) (xy 114.066874 -228.13721)
			(xy 114.116267 -228.153258) (xy 114.162541 -228.176836) (xy 114.204557 -228.207362) (xy 114.24128 -228.244085)
			(xy 114.271806 -228.286101) (xy 114.295384 -228.332375) (xy 114.311432 -228.381768) (xy 114.319557 -228.433063)
			(xy 114.320066 -228.45903) (xy 114.319557 -228.484997) (xy 115.539267 -228.484997) (xy 115.539267 -228.433063)
			(xy 115.547392 -228.381768) (xy 115.56344 -228.332375) (xy 115.587018 -228.286101) (xy 115.617544 -228.244085)
			(xy 115.654267 -228.207362) (xy 115.696283 -228.176836) (xy 115.742557 -228.153258) (xy 115.79195 -228.13721)
			(xy 115.843245 -228.129085) (xy 115.895179 -228.129085) (xy 115.946474 -228.13721) (xy 115.995867 -228.153258)
			(xy 116.042141 -228.176836) (xy 116.084157 -228.207362) (xy 116.12088 -228.244085) (xy 116.151406 -228.286101)
			(xy 116.174984 -228.332375) (xy 116.191032 -228.381768) (xy 116.199157 -228.433063) (xy 116.199666 -228.45903)
			(xy 116.199157 -228.484997) (xy 117.418867 -228.484997) (xy 117.418867 -228.433063) (xy 117.426992 -228.381768)
			(xy 117.44304 -228.332375) (xy 117.466618 -228.286101) (xy 117.497144 -228.244085) (xy 117.533867 -228.207362)
			(xy 117.575883 -228.176836) (xy 117.622157 -228.153258) (xy 117.67155 -228.13721) (xy 117.722845 -228.129085)
			(xy 117.774779 -228.129085) (xy 117.826074 -228.13721) (xy 117.875467 -228.153258) (xy 117.921741 -228.176836)
			(xy 117.963757 -228.207362) (xy 118.00048 -228.244085) (xy 118.031006 -228.286101) (xy 118.054584 -228.332375)
			(xy 118.070632 -228.381768) (xy 118.078757 -228.433063) (xy 118.079266 -228.45903) (xy 118.078757 -228.484997)
			(xy 119.298467 -228.484997) (xy 119.298467 -228.433063) (xy 119.306592 -228.381768) (xy 119.32264 -228.332375)
			(xy 119.346218 -228.286101) (xy 119.376744 -228.244085) (xy 119.413467 -228.207362) (xy 119.455483 -228.176836)
			(xy 119.501757 -228.153258) (xy 119.55115 -228.13721) (xy 119.602445 -228.129085) (xy 119.654379 -228.129085)
			(xy 119.705674 -228.13721) (xy 119.755067 -228.153258) (xy 119.801341 -228.176836) (xy 119.843357 -228.207362)
			(xy 119.88008 -228.244085) (xy 119.910606 -228.286101) (xy 119.934184 -228.332375) (xy 119.950232 -228.381768)
			(xy 119.958357 -228.433063) (xy 119.958866 -228.45903) (xy 119.958357 -228.484997) (xy 120.238267 -228.484997)
			(xy 120.238267 -228.433063) (xy 120.246392 -228.381768) (xy 120.26244 -228.332375) (xy 120.286018 -228.286101)
			(xy 120.316544 -228.244085) (xy 120.353267 -228.207362) (xy 120.395283 -228.176836) (xy 120.441557 -228.153258)
			(xy 120.49095 -228.13721) (xy 120.542245 -228.129085) (xy 120.594179 -228.129085) (xy 120.645474 -228.13721)
			(xy 120.694867 -228.153258) (xy 120.741141 -228.176836) (xy 120.783157 -228.207362) (xy 120.81988 -228.244085)
			(xy 120.850406 -228.286101) (xy 120.873984 -228.332375) (xy 120.890032 -228.381768) (xy 120.898157 -228.433063)
			(xy 120.898666 -228.45903) (xy 120.898157 -228.484997) (xy 121.178067 -228.484997) (xy 121.178067 -228.433063)
			(xy 121.186192 -228.381768) (xy 121.20224 -228.332375) (xy 121.225818 -228.286101) (xy 121.256344 -228.244085)
			(xy 121.293067 -228.207362) (xy 121.335083 -228.176836) (xy 121.381357 -228.153258) (xy 121.43075 -228.13721)
			(xy 121.482045 -228.129085) (xy 121.533979 -228.129085) (xy 121.585274 -228.13721) (xy 121.634667 -228.153258)
			(xy 121.680941 -228.176836) (xy 121.722957 -228.207362) (xy 121.75968 -228.244085) (xy 121.790206 -228.286101)
			(xy 121.813784 -228.332375) (xy 121.829832 -228.381768) (xy 121.837957 -228.433063) (xy 121.838466 -228.45903)
			(xy 121.837957 -228.484997) (xy 122.117867 -228.484997) (xy 122.117867 -228.433063) (xy 122.125992 -228.381768)
			(xy 122.14204 -228.332375) (xy 122.165618 -228.286101) (xy 122.196144 -228.244085) (xy 122.232867 -228.207362)
			(xy 122.274883 -228.176836) (xy 122.321157 -228.153258) (xy 122.37055 -228.13721) (xy 122.421845 -228.129085)
			(xy 122.473779 -228.129085) (xy 122.525074 -228.13721) (xy 122.574467 -228.153258) (xy 122.620741 -228.176836)
			(xy 122.662757 -228.207362) (xy 122.69948 -228.244085) (xy 122.730006 -228.286101) (xy 122.753584 -228.332375)
			(xy 122.769632 -228.381768) (xy 122.777757 -228.433063) (xy 122.778266 -228.45903) (xy 122.777757 -228.484997)
			(xy 123.057667 -228.484997) (xy 123.057667 -228.433063) (xy 123.065792 -228.381768) (xy 123.08184 -228.332375)
			(xy 123.105418 -228.286101) (xy 123.135944 -228.244085) (xy 123.172667 -228.207362) (xy 123.214683 -228.176836)
			(xy 123.260957 -228.153258) (xy 123.31035 -228.13721) (xy 123.361645 -228.129085) (xy 123.413579 -228.129085)
			(xy 123.464874 -228.13721) (xy 123.514267 -228.153258) (xy 123.560541 -228.176836) (xy 123.602557 -228.207362)
			(xy 123.63928 -228.244085) (xy 123.669806 -228.286101) (xy 123.693384 -228.332375) (xy 123.709432 -228.381768)
			(xy 123.717557 -228.433063) (xy 123.718066 -228.45903) (xy 123.717557 -228.484997) (xy 123.997467 -228.484997)
			(xy 123.997467 -228.433063) (xy 124.005592 -228.381768) (xy 124.02164 -228.332375) (xy 124.045218 -228.286101)
			(xy 124.075744 -228.244085) (xy 124.112467 -228.207362) (xy 124.154483 -228.176836) (xy 124.200757 -228.153258)
			(xy 124.25015 -228.13721) (xy 124.301445 -228.129085) (xy 124.353379 -228.129085) (xy 124.404674 -228.13721)
			(xy 124.454067 -228.153258) (xy 124.500341 -228.176836) (xy 124.542357 -228.207362) (xy 124.57908 -228.244085)
			(xy 124.609606 -228.286101) (xy 124.633184 -228.332375) (xy 124.649232 -228.381768) (xy 124.657357 -228.433063)
			(xy 124.657866 -228.45903) (xy 124.657357 -228.484997) (xy 124.937267 -228.484997) (xy 124.937267 -228.433063)
			(xy 124.945392 -228.381768) (xy 124.96144 -228.332375) (xy 124.985018 -228.286101) (xy 125.015544 -228.244085)
			(xy 125.052267 -228.207362) (xy 125.094283 -228.176836) (xy 125.140557 -228.153258) (xy 125.18995 -228.13721)
			(xy 125.241245 -228.129085) (xy 125.293179 -228.129085) (xy 125.344474 -228.13721) (xy 125.393867 -228.153258)
			(xy 125.440141 -228.176836) (xy 125.482157 -228.207362) (xy 125.51888 -228.244085) (xy 125.549406 -228.286101)
			(xy 125.572984 -228.332375) (xy 125.589032 -228.381768) (xy 125.597157 -228.433063) (xy 125.597666 -228.45903)
			(xy 125.597157 -228.484997) (xy 125.589032 -228.536292) (xy 125.572984 -228.585685) (xy 125.549406 -228.631959)
			(xy 125.51888 -228.673975) (xy 125.482157 -228.710698) (xy 125.440141 -228.741224) (xy 125.393867 -228.764802)
			(xy 125.344474 -228.78085) (xy 125.293179 -228.788975) (xy 125.241245 -228.788975) (xy 125.18995 -228.78085)
			(xy 125.140557 -228.764802) (xy 125.094283 -228.741224) (xy 125.052267 -228.710698) (xy 125.015544 -228.673975)
			(xy 124.985018 -228.631959) (xy 124.96144 -228.585685) (xy 124.945392 -228.536292) (xy 124.937267 -228.484997)
			(xy 124.657357 -228.484997) (xy 124.649232 -228.536292) (xy 124.633184 -228.585685) (xy 124.609606 -228.631959)
			(xy 124.57908 -228.673975) (xy 124.542357 -228.710698) (xy 124.500341 -228.741224) (xy 124.454067 -228.764802)
			(xy 124.404674 -228.78085) (xy 124.353379 -228.788975) (xy 124.301445 -228.788975) (xy 124.25015 -228.78085)
			(xy 124.200757 -228.764802) (xy 124.154483 -228.741224) (xy 124.112467 -228.710698) (xy 124.075744 -228.673975)
			(xy 124.045218 -228.631959) (xy 124.02164 -228.585685) (xy 124.005592 -228.536292) (xy 123.997467 -228.484997)
			(xy 123.717557 -228.484997) (xy 123.709432 -228.536292) (xy 123.693384 -228.585685) (xy 123.669806 -228.631959)
			(xy 123.63928 -228.673975) (xy 123.602557 -228.710698) (xy 123.560541 -228.741224) (xy 123.514267 -228.764802)
			(xy 123.464874 -228.78085) (xy 123.413579 -228.788975) (xy 123.361645 -228.788975) (xy 123.31035 -228.78085)
			(xy 123.260957 -228.764802) (xy 123.214683 -228.741224) (xy 123.172667 -228.710698) (xy 123.135944 -228.673975)
			(xy 123.105418 -228.631959) (xy 123.08184 -228.585685) (xy 123.065792 -228.536292) (xy 123.057667 -228.484997)
			(xy 122.777757 -228.484997) (xy 122.769632 -228.536292) (xy 122.753584 -228.585685) (xy 122.730006 -228.631959)
			(xy 122.69948 -228.673975) (xy 122.662757 -228.710698) (xy 122.620741 -228.741224) (xy 122.574467 -228.764802)
			(xy 122.525074 -228.78085) (xy 122.473779 -228.788975) (xy 122.421845 -228.788975) (xy 122.37055 -228.78085)
			(xy 122.321157 -228.764802) (xy 122.274883 -228.741224) (xy 122.232867 -228.710698) (xy 122.196144 -228.673975)
			(xy 122.165618 -228.631959) (xy 122.14204 -228.585685) (xy 122.125992 -228.536292) (xy 122.117867 -228.484997)
			(xy 121.837957 -228.484997) (xy 121.829832 -228.536292) (xy 121.813784 -228.585685) (xy 121.790206 -228.631959)
			(xy 121.75968 -228.673975) (xy 121.722957 -228.710698) (xy 121.680941 -228.741224) (xy 121.634667 -228.764802)
			(xy 121.585274 -228.78085) (xy 121.533979 -228.788975) (xy 121.482045 -228.788975) (xy 121.43075 -228.78085)
			(xy 121.381357 -228.764802) (xy 121.335083 -228.741224) (xy 121.293067 -228.710698) (xy 121.256344 -228.673975)
			(xy 121.225818 -228.631959) (xy 121.20224 -228.585685) (xy 121.186192 -228.536292) (xy 121.178067 -228.484997)
			(xy 120.898157 -228.484997) (xy 120.890032 -228.536292) (xy 120.873984 -228.585685) (xy 120.850406 -228.631959)
			(xy 120.81988 -228.673975) (xy 120.783157 -228.710698) (xy 120.741141 -228.741224) (xy 120.694867 -228.764802)
			(xy 120.645474 -228.78085) (xy 120.594179 -228.788975) (xy 120.542245 -228.788975) (xy 120.49095 -228.78085)
			(xy 120.441557 -228.764802) (xy 120.395283 -228.741224) (xy 120.353267 -228.710698) (xy 120.316544 -228.673975)
			(xy 120.286018 -228.631959) (xy 120.26244 -228.585685) (xy 120.246392 -228.536292) (xy 120.238267 -228.484997)
			(xy 119.958357 -228.484997) (xy 119.950232 -228.536292) (xy 119.934184 -228.585685) (xy 119.910606 -228.631959)
			(xy 119.88008 -228.673975) (xy 119.843357 -228.710698) (xy 119.801341 -228.741224) (xy 119.755067 -228.764802)
			(xy 119.705674 -228.78085) (xy 119.654379 -228.788975) (xy 119.602445 -228.788975) (xy 119.55115 -228.78085)
			(xy 119.501757 -228.764802) (xy 119.455483 -228.741224) (xy 119.413467 -228.710698) (xy 119.376744 -228.673975)
			(xy 119.346218 -228.631959) (xy 119.32264 -228.585685) (xy 119.306592 -228.536292) (xy 119.298467 -228.484997)
			(xy 118.078757 -228.484997) (xy 118.070632 -228.536292) (xy 118.054584 -228.585685) (xy 118.031006 -228.631959)
			(xy 118.00048 -228.673975) (xy 117.963757 -228.710698) (xy 117.921741 -228.741224) (xy 117.875467 -228.764802)
			(xy 117.826074 -228.78085) (xy 117.774779 -228.788975) (xy 117.722845 -228.788975) (xy 117.67155 -228.78085)
			(xy 117.622157 -228.764802) (xy 117.575883 -228.741224) (xy 117.533867 -228.710698) (xy 117.497144 -228.673975)
			(xy 117.466618 -228.631959) (xy 117.44304 -228.585685) (xy 117.426992 -228.536292) (xy 117.418867 -228.484997)
			(xy 116.199157 -228.484997) (xy 116.191032 -228.536292) (xy 116.174984 -228.585685) (xy 116.151406 -228.631959)
			(xy 116.12088 -228.673975) (xy 116.084157 -228.710698) (xy 116.042141 -228.741224) (xy 115.995867 -228.764802)
			(xy 115.946474 -228.78085) (xy 115.895179 -228.788975) (xy 115.843245 -228.788975) (xy 115.79195 -228.78085)
			(xy 115.742557 -228.764802) (xy 115.696283 -228.741224) (xy 115.654267 -228.710698) (xy 115.617544 -228.673975)
			(xy 115.587018 -228.631959) (xy 115.56344 -228.585685) (xy 115.547392 -228.536292) (xy 115.539267 -228.484997)
			(xy 114.319557 -228.484997) (xy 114.311432 -228.536292) (xy 114.295384 -228.585685) (xy 114.271806 -228.631959)
			(xy 114.24128 -228.673975) (xy 114.204557 -228.710698) (xy 114.162541 -228.741224) (xy 114.116267 -228.764802)
			(xy 114.066874 -228.78085) (xy 114.015579 -228.788975) (xy 113.963645 -228.788975) (xy 113.91235 -228.78085)
			(xy 113.862957 -228.764802) (xy 113.816683 -228.741224) (xy 113.774667 -228.710698) (xy 113.737944 -228.673975)
			(xy 113.707418 -228.631959) (xy 113.68384 -228.585685) (xy 113.667792 -228.536292) (xy 113.659667 -228.484997)
			(xy 113.379757 -228.484997) (xy 113.371632 -228.536292) (xy 113.355584 -228.585685) (xy 113.332006 -228.631959)
			(xy 113.30148 -228.673975) (xy 113.264757 -228.710698) (xy 113.222741 -228.741224) (xy 113.176467 -228.764802)
			(xy 113.127074 -228.78085) (xy 113.075779 -228.788975) (xy 113.023845 -228.788975) (xy 112.97255 -228.78085)
			(xy 112.923157 -228.764802) (xy 112.876883 -228.741224) (xy 112.834867 -228.710698) (xy 112.798144 -228.673975)
			(xy 112.767618 -228.631959) (xy 112.74404 -228.585685) (xy 112.727992 -228.536292) (xy 112.719867 -228.484997)
			(xy 112.439957 -228.484997) (xy 112.431832 -228.536292) (xy 112.415784 -228.585685) (xy 112.392206 -228.631959)
			(xy 112.36168 -228.673975) (xy 112.324957 -228.710698) (xy 112.282941 -228.741224) (xy 112.236667 -228.764802)
			(xy 112.187274 -228.78085) (xy 112.135979 -228.788975) (xy 112.084045 -228.788975) (xy 112.03275 -228.78085)
			(xy 111.983357 -228.764802) (xy 111.937083 -228.741224) (xy 111.895067 -228.710698) (xy 111.858344 -228.673975)
			(xy 111.827818 -228.631959) (xy 111.80424 -228.585685) (xy 111.788192 -228.536292) (xy 111.780067 -228.484997)
			(xy 111.587026 -228.484997) (xy 111.587026 -228.891592) (xy 111.587451 -228.901644) (xy 111.595168 -228.920208)
			(xy 111.609421 -228.934385) (xy 111.628026 -228.942002) (xy 111.63808 -228.942392) (xy 111.640112 -228.942392)
			(xy 111.666075 -228.942902) (xy 111.717361 -228.951027) (xy 111.766746 -228.967074) (xy 111.813011 -228.990649)
			(xy 111.85502 -229.021172) (xy 111.891736 -229.057889) (xy 111.922257 -229.099899) (xy 111.94583 -229.146166)
			(xy 111.961876 -229.19555) (xy 111.969999 -229.246837) (xy 111.969999 -229.298763) (xy 111.969991 -229.298813)
			(xy 112.250221 -229.298813) (xy 112.250221 -229.246879) (xy 112.258346 -229.195584) (xy 112.274394 -229.146191)
			(xy 112.297972 -229.099917) (xy 112.328498 -229.057901) (xy 112.365221 -229.021178) (xy 112.407237 -228.990652)
			(xy 112.453511 -228.967074) (xy 112.502904 -228.951026) (xy 112.554199 -228.942901) (xy 112.606133 -228.942901)
			(xy 112.657428 -228.951026) (xy 112.706821 -228.967074) (xy 112.753095 -228.990652) (xy 112.795111 -229.021178)
			(xy 112.831834 -229.057901) (xy 112.86236 -229.099917) (xy 112.885938 -229.146191) (xy 112.901986 -229.195584)
			(xy 112.910111 -229.246879) (xy 112.91062 -229.272846) (xy 112.910111 -229.298813) (xy 113.190021 -229.298813)
			(xy 113.190021 -229.246879) (xy 113.198146 -229.195584) (xy 113.214194 -229.146191) (xy 113.237772 -229.099917)
			(xy 113.268298 -229.057901) (xy 113.305021 -229.021178) (xy 113.347037 -228.990652) (xy 113.393311 -228.967074)
			(xy 113.442704 -228.951026) (xy 113.493999 -228.942901) (xy 113.545933 -228.942901) (xy 113.597228 -228.951026)
			(xy 113.646621 -228.967074) (xy 113.692895 -228.990652) (xy 113.734911 -229.021178) (xy 113.771634 -229.057901)
			(xy 113.80216 -229.099917) (xy 113.825738 -229.146191) (xy 113.841786 -229.195584) (xy 113.849911 -229.246879)
			(xy 113.85042 -229.272846) (xy 113.849911 -229.298813) (xy 114.129821 -229.298813) (xy 114.129821 -229.246879)
			(xy 114.137946 -229.195584) (xy 114.153994 -229.146191) (xy 114.177572 -229.099917) (xy 114.208098 -229.057901)
			(xy 114.244821 -229.021178) (xy 114.286837 -228.990652) (xy 114.333111 -228.967074) (xy 114.382504 -228.951026)
			(xy 114.433799 -228.942901) (xy 114.485733 -228.942901) (xy 114.537028 -228.951026) (xy 114.586421 -228.967074)
			(xy 114.632695 -228.990652) (xy 114.674711 -229.021178) (xy 114.711434 -229.057901) (xy 114.74196 -229.099917)
			(xy 114.765538 -229.146191) (xy 114.781586 -229.195584) (xy 114.789711 -229.246879) (xy 114.79022 -229.272846)
			(xy 114.789711 -229.298813) (xy 115.069621 -229.298813) (xy 115.069621 -229.246879) (xy 115.077746 -229.195584)
			(xy 115.093794 -229.146191) (xy 115.117372 -229.099917) (xy 115.147898 -229.057901) (xy 115.184621 -229.021178)
			(xy 115.226637 -228.990652) (xy 115.272911 -228.967074) (xy 115.322304 -228.951026) (xy 115.373599 -228.942901)
			(xy 115.425533 -228.942901) (xy 115.476828 -228.951026) (xy 115.526221 -228.967074) (xy 115.572495 -228.990652)
			(xy 115.614511 -229.021178) (xy 115.651234 -229.057901) (xy 115.68176 -229.099917) (xy 115.705338 -229.146191)
			(xy 115.721386 -229.195584) (xy 115.729511 -229.246879) (xy 115.73002 -229.272846) (xy 115.729511 -229.298813)
			(xy 116.009421 -229.298813) (xy 116.009421 -229.246879) (xy 116.017546 -229.195584) (xy 116.033594 -229.146191)
			(xy 116.057172 -229.099917) (xy 116.087698 -229.057901) (xy 116.124421 -229.021178) (xy 116.166437 -228.990652)
			(xy 116.212711 -228.967074) (xy 116.262104 -228.951026) (xy 116.313399 -228.942901) (xy 116.365333 -228.942901)
			(xy 116.416628 -228.951026) (xy 116.466021 -228.967074) (xy 116.512295 -228.990652) (xy 116.554311 -229.021178)
			(xy 116.591034 -229.057901) (xy 116.62156 -229.099917) (xy 116.645138 -229.146191) (xy 116.661186 -229.195584)
			(xy 116.669311 -229.246879) (xy 116.66982 -229.272846) (xy 116.669311 -229.298813) (xy 116.949221 -229.298813)
			(xy 116.949221 -229.246879) (xy 116.957346 -229.195584) (xy 116.973394 -229.146191) (xy 116.996972 -229.099917)
			(xy 117.027498 -229.057901) (xy 117.064221 -229.021178) (xy 117.106237 -228.990652) (xy 117.152511 -228.967074)
			(xy 117.201904 -228.951026) (xy 117.253199 -228.942901) (xy 117.305133 -228.942901) (xy 117.356428 -228.951026)
			(xy 117.405821 -228.967074) (xy 117.452095 -228.990652) (xy 117.494111 -229.021178) (xy 117.530834 -229.057901)
			(xy 117.56136 -229.099917) (xy 117.584938 -229.146191) (xy 117.600986 -229.195584) (xy 117.609111 -229.246879)
			(xy 117.60962 -229.272846) (xy 117.609111 -229.298813) (xy 117.889021 -229.298813) (xy 117.889021 -229.246879)
			(xy 117.897146 -229.195584) (xy 117.913194 -229.146191) (xy 117.936772 -229.099917) (xy 117.967298 -229.057901)
			(xy 118.004021 -229.021178) (xy 118.046037 -228.990652) (xy 118.092311 -228.967074) (xy 118.141704 -228.951026)
			(xy 118.192999 -228.942901) (xy 118.244933 -228.942901) (xy 118.296228 -228.951026) (xy 118.345621 -228.967074)
			(xy 118.391895 -228.990652) (xy 118.433911 -229.021178) (xy 118.470634 -229.057901) (xy 118.50116 -229.099917)
			(xy 118.524738 -229.146191) (xy 118.540786 -229.195584) (xy 118.548911 -229.246879) (xy 118.54942 -229.272846)
			(xy 118.548911 -229.298813) (xy 118.828821 -229.298813) (xy 118.828821 -229.246879) (xy 118.836946 -229.195584)
			(xy 118.852994 -229.146191) (xy 118.876572 -229.099917) (xy 118.907098 -229.057901) (xy 118.943821 -229.021178)
			(xy 118.985837 -228.990652) (xy 119.032111 -228.967074) (xy 119.081504 -228.951026) (xy 119.132799 -228.942901)
			(xy 119.184733 -228.942901) (xy 119.236028 -228.951026) (xy 119.285421 -228.967074) (xy 119.331695 -228.990652)
			(xy 119.373711 -229.021178) (xy 119.410434 -229.057901) (xy 119.44096 -229.099917) (xy 119.464538 -229.146191)
			(xy 119.480586 -229.195584) (xy 119.488711 -229.246879) (xy 119.48922 -229.272846) (xy 119.488711 -229.298813)
			(xy 119.768621 -229.298813) (xy 119.768621 -229.246879) (xy 119.776746 -229.195584) (xy 119.792794 -229.146191)
			(xy 119.816372 -229.099917) (xy 119.846898 -229.057901) (xy 119.883621 -229.021178) (xy 119.925637 -228.990652)
			(xy 119.971911 -228.967074) (xy 120.021304 -228.951026) (xy 120.072599 -228.942901) (xy 120.124533 -228.942901)
			(xy 120.175828 -228.951026) (xy 120.225221 -228.967074) (xy 120.271495 -228.990652) (xy 120.313511 -229.021178)
			(xy 120.350234 -229.057901) (xy 120.38076 -229.099917) (xy 120.404338 -229.146191) (xy 120.420386 -229.195584)
			(xy 120.428511 -229.246879) (xy 120.42902 -229.272846) (xy 120.428511 -229.298813) (xy 120.708421 -229.298813)
			(xy 120.708421 -229.246879) (xy 120.716546 -229.195584) (xy 120.732594 -229.146191) (xy 120.756172 -229.099917)
			(xy 120.786698 -229.057901) (xy 120.823421 -229.021178) (xy 120.865437 -228.990652) (xy 120.911711 -228.967074)
			(xy 120.961104 -228.951026) (xy 121.012399 -228.942901) (xy 121.064333 -228.942901) (xy 121.115628 -228.951026)
			(xy 121.165021 -228.967074) (xy 121.211295 -228.990652) (xy 121.253311 -229.021178) (xy 121.290034 -229.057901)
			(xy 121.32056 -229.099917) (xy 121.344138 -229.146191) (xy 121.360186 -229.195584) (xy 121.368311 -229.246879)
			(xy 121.36882 -229.272846) (xy 121.368311 -229.298813) (xy 121.648221 -229.298813) (xy 121.648221 -229.246879)
			(xy 121.656346 -229.195584) (xy 121.672394 -229.146191) (xy 121.695972 -229.099917) (xy 121.726498 -229.057901)
			(xy 121.763221 -229.021178) (xy 121.805237 -228.990652) (xy 121.851511 -228.967074) (xy 121.900904 -228.951026)
			(xy 121.952199 -228.942901) (xy 122.004133 -228.942901) (xy 122.055428 -228.951026) (xy 122.104821 -228.967074)
			(xy 122.151095 -228.990652) (xy 122.193111 -229.021178) (xy 122.229834 -229.057901) (xy 122.26036 -229.099917)
			(xy 122.283938 -229.146191) (xy 122.299986 -229.195584) (xy 122.308111 -229.246879) (xy 122.30862 -229.272846)
			(xy 122.308111 -229.298813) (xy 122.587767 -229.298813) (xy 122.587767 -229.246879) (xy 122.595892 -229.195584)
			(xy 122.61194 -229.146191) (xy 122.635518 -229.099917) (xy 122.666044 -229.057901) (xy 122.702767 -229.021178)
			(xy 122.744783 -228.990652) (xy 122.791057 -228.967074) (xy 122.84045 -228.951026) (xy 122.891745 -228.942901)
			(xy 122.943679 -228.942901) (xy 122.994974 -228.951026) (xy 123.044367 -228.967074) (xy 123.090641 -228.990652)
			(xy 123.132657 -229.021178) (xy 123.16938 -229.057901) (xy 123.199906 -229.099917) (xy 123.223484 -229.146191)
			(xy 123.239532 -229.195584) (xy 123.247657 -229.246879) (xy 123.248166 -229.272846) (xy 123.247657 -229.298813)
			(xy 123.527821 -229.298813) (xy 123.527821 -229.246879) (xy 123.535946 -229.195584) (xy 123.551994 -229.146191)
			(xy 123.575572 -229.099917) (xy 123.606098 -229.057901) (xy 123.642821 -229.021178) (xy 123.684837 -228.990652)
			(xy 123.731111 -228.967074) (xy 123.780504 -228.951026) (xy 123.831799 -228.942901) (xy 123.883733 -228.942901)
			(xy 123.935028 -228.951026) (xy 123.984421 -228.967074) (xy 124.030695 -228.990652) (xy 124.072711 -229.021178)
			(xy 124.109434 -229.057901) (xy 124.13996 -229.099917) (xy 124.163538 -229.146191) (xy 124.179586 -229.195584)
			(xy 124.187711 -229.246879) (xy 124.18822 -229.272846) (xy 124.187711 -229.298813) (xy 124.467621 -229.298813)
			(xy 124.467621 -229.246879) (xy 124.475746 -229.195584) (xy 124.491794 -229.146191) (xy 124.515372 -229.099917)
			(xy 124.545898 -229.057901) (xy 124.582621 -229.021178) (xy 124.624637 -228.990652) (xy 124.670911 -228.967074)
			(xy 124.720304 -228.951026) (xy 124.771599 -228.942901) (xy 124.823533 -228.942901) (xy 124.874828 -228.951026)
			(xy 124.924221 -228.967074) (xy 124.970495 -228.990652) (xy 125.012511 -229.021178) (xy 125.049234 -229.057901)
			(xy 125.07976 -229.099917) (xy 125.103338 -229.146191) (xy 125.119386 -229.195584) (xy 125.127511 -229.246879)
			(xy 125.12802 -229.272846) (xy 125.127511 -229.298813) (xy 125.119386 -229.350108) (xy 125.103338 -229.399501)
			(xy 125.07976 -229.445775) (xy 125.049234 -229.487791) (xy 125.012511 -229.524514) (xy 124.970495 -229.55504)
			(xy 124.924221 -229.578618) (xy 124.874828 -229.594666) (xy 124.823533 -229.602791) (xy 124.771599 -229.602791)
			(xy 124.720304 -229.594666) (xy 124.670911 -229.578618) (xy 124.624637 -229.55504) (xy 124.582621 -229.524514)
			(xy 124.545898 -229.487791) (xy 124.515372 -229.445775) (xy 124.491794 -229.399501) (xy 124.475746 -229.350108)
			(xy 124.467621 -229.298813) (xy 124.187711 -229.298813) (xy 124.179586 -229.350108) (xy 124.163538 -229.399501)
			(xy 124.13996 -229.445775) (xy 124.109434 -229.487791) (xy 124.072711 -229.524514) (xy 124.030695 -229.55504)
			(xy 123.984421 -229.578618) (xy 123.935028 -229.594666) (xy 123.883733 -229.602791) (xy 123.831799 -229.602791)
			(xy 123.780504 -229.594666) (xy 123.731111 -229.578618) (xy 123.684837 -229.55504) (xy 123.642821 -229.524514)
			(xy 123.606098 -229.487791) (xy 123.575572 -229.445775) (xy 123.551994 -229.399501) (xy 123.535946 -229.350108)
			(xy 123.527821 -229.298813) (xy 123.247657 -229.298813) (xy 123.239532 -229.350108) (xy 123.223484 -229.399501)
			(xy 123.199906 -229.445775) (xy 123.16938 -229.487791) (xy 123.132657 -229.524514) (xy 123.090641 -229.55504)
			(xy 123.044367 -229.578618) (xy 122.994974 -229.594666) (xy 122.943679 -229.602791) (xy 122.891745 -229.602791)
			(xy 122.84045 -229.594666) (xy 122.791057 -229.578618) (xy 122.744783 -229.55504) (xy 122.702767 -229.524514)
			(xy 122.666044 -229.487791) (xy 122.635518 -229.445775) (xy 122.61194 -229.399501) (xy 122.595892 -229.350108)
			(xy 122.587767 -229.298813) (xy 122.308111 -229.298813) (xy 122.299986 -229.350108) (xy 122.283938 -229.399501)
			(xy 122.26036 -229.445775) (xy 122.229834 -229.487791) (xy 122.193111 -229.524514) (xy 122.151095 -229.55504)
			(xy 122.104821 -229.578618) (xy 122.055428 -229.594666) (xy 122.004133 -229.602791) (xy 121.952199 -229.602791)
			(xy 121.900904 -229.594666) (xy 121.851511 -229.578618) (xy 121.805237 -229.55504) (xy 121.763221 -229.524514)
			(xy 121.726498 -229.487791) (xy 121.695972 -229.445775) (xy 121.672394 -229.399501) (xy 121.656346 -229.350108)
			(xy 121.648221 -229.298813) (xy 121.368311 -229.298813) (xy 121.360186 -229.350108) (xy 121.344138 -229.399501)
			(xy 121.32056 -229.445775) (xy 121.290034 -229.487791) (xy 121.253311 -229.524514) (xy 121.211295 -229.55504)
			(xy 121.165021 -229.578618) (xy 121.115628 -229.594666) (xy 121.064333 -229.602791) (xy 121.012399 -229.602791)
			(xy 120.961104 -229.594666) (xy 120.911711 -229.578618) (xy 120.865437 -229.55504) (xy 120.823421 -229.524514)
			(xy 120.786698 -229.487791) (xy 120.756172 -229.445775) (xy 120.732594 -229.399501) (xy 120.716546 -229.350108)
			(xy 120.708421 -229.298813) (xy 120.428511 -229.298813) (xy 120.420386 -229.350108) (xy 120.404338 -229.399501)
			(xy 120.38076 -229.445775) (xy 120.350234 -229.487791) (xy 120.313511 -229.524514) (xy 120.271495 -229.55504)
			(xy 120.225221 -229.578618) (xy 120.175828 -229.594666) (xy 120.124533 -229.602791) (xy 120.072599 -229.602791)
			(xy 120.021304 -229.594666) (xy 119.971911 -229.578618) (xy 119.925637 -229.55504) (xy 119.883621 -229.524514)
			(xy 119.846898 -229.487791) (xy 119.816372 -229.445775) (xy 119.792794 -229.399501) (xy 119.776746 -229.350108)
			(xy 119.768621 -229.298813) (xy 119.488711 -229.298813) (xy 119.480586 -229.350108) (xy 119.464538 -229.399501)
			(xy 119.44096 -229.445775) (xy 119.410434 -229.487791) (xy 119.373711 -229.524514) (xy 119.331695 -229.55504)
			(xy 119.285421 -229.578618) (xy 119.236028 -229.594666) (xy 119.184733 -229.602791) (xy 119.132799 -229.602791)
			(xy 119.081504 -229.594666) (xy 119.032111 -229.578618) (xy 118.985837 -229.55504) (xy 118.943821 -229.524514)
			(xy 118.907098 -229.487791) (xy 118.876572 -229.445775) (xy 118.852994 -229.399501) (xy 118.836946 -229.350108)
			(xy 118.828821 -229.298813) (xy 118.548911 -229.298813) (xy 118.540786 -229.350108) (xy 118.524738 -229.399501)
			(xy 118.50116 -229.445775) (xy 118.470634 -229.487791) (xy 118.433911 -229.524514) (xy 118.391895 -229.55504)
			(xy 118.345621 -229.578618) (xy 118.296228 -229.594666) (xy 118.244933 -229.602791) (xy 118.192999 -229.602791)
			(xy 118.141704 -229.594666) (xy 118.092311 -229.578618) (xy 118.046037 -229.55504) (xy 118.004021 -229.524514)
			(xy 117.967298 -229.487791) (xy 117.936772 -229.445775) (xy 117.913194 -229.399501) (xy 117.897146 -229.350108)
			(xy 117.889021 -229.298813) (xy 117.609111 -229.298813) (xy 117.600986 -229.350108) (xy 117.584938 -229.399501)
			(xy 117.56136 -229.445775) (xy 117.530834 -229.487791) (xy 117.494111 -229.524514) (xy 117.452095 -229.55504)
			(xy 117.405821 -229.578618) (xy 117.356428 -229.594666) (xy 117.305133 -229.602791) (xy 117.253199 -229.602791)
			(xy 117.201904 -229.594666) (xy 117.152511 -229.578618) (xy 117.106237 -229.55504) (xy 117.064221 -229.524514)
			(xy 117.027498 -229.487791) (xy 116.996972 -229.445775) (xy 116.973394 -229.399501) (xy 116.957346 -229.350108)
			(xy 116.949221 -229.298813) (xy 116.669311 -229.298813) (xy 116.661186 -229.350108) (xy 116.645138 -229.399501)
			(xy 116.62156 -229.445775) (xy 116.591034 -229.487791) (xy 116.554311 -229.524514) (xy 116.512295 -229.55504)
			(xy 116.466021 -229.578618) (xy 116.416628 -229.594666) (xy 116.365333 -229.602791) (xy 116.313399 -229.602791)
			(xy 116.262104 -229.594666) (xy 116.212711 -229.578618) (xy 116.166437 -229.55504) (xy 116.124421 -229.524514)
			(xy 116.087698 -229.487791) (xy 116.057172 -229.445775) (xy 116.033594 -229.399501) (xy 116.017546 -229.350108)
			(xy 116.009421 -229.298813) (xy 115.729511 -229.298813) (xy 115.721386 -229.350108) (xy 115.705338 -229.399501)
			(xy 115.68176 -229.445775) (xy 115.651234 -229.487791) (xy 115.614511 -229.524514) (xy 115.572495 -229.55504)
			(xy 115.526221 -229.578618) (xy 115.476828 -229.594666) (xy 115.425533 -229.602791) (xy 115.373599 -229.602791)
			(xy 115.322304 -229.594666) (xy 115.272911 -229.578618) (xy 115.226637 -229.55504) (xy 115.184621 -229.524514)
			(xy 115.147898 -229.487791) (xy 115.117372 -229.445775) (xy 115.093794 -229.399501) (xy 115.077746 -229.350108)
			(xy 115.069621 -229.298813) (xy 114.789711 -229.298813) (xy 114.781586 -229.350108) (xy 114.765538 -229.399501)
			(xy 114.74196 -229.445775) (xy 114.711434 -229.487791) (xy 114.674711 -229.524514) (xy 114.632695 -229.55504)
			(xy 114.586421 -229.578618) (xy 114.537028 -229.594666) (xy 114.485733 -229.602791) (xy 114.433799 -229.602791)
			(xy 114.382504 -229.594666) (xy 114.333111 -229.578618) (xy 114.286837 -229.55504) (xy 114.244821 -229.524514)
			(xy 114.208098 -229.487791) (xy 114.177572 -229.445775) (xy 114.153994 -229.399501) (xy 114.137946 -229.350108)
			(xy 114.129821 -229.298813) (xy 113.849911 -229.298813) (xy 113.841786 -229.350108) (xy 113.825738 -229.399501)
			(xy 113.80216 -229.445775) (xy 113.771634 -229.487791) (xy 113.734911 -229.524514) (xy 113.692895 -229.55504)
			(xy 113.646621 -229.578618) (xy 113.597228 -229.594666) (xy 113.545933 -229.602791) (xy 113.493999 -229.602791)
			(xy 113.442704 -229.594666) (xy 113.393311 -229.578618) (xy 113.347037 -229.55504) (xy 113.305021 -229.524514)
			(xy 113.268298 -229.487791) (xy 113.237772 -229.445775) (xy 113.214194 -229.399501) (xy 113.198146 -229.350108)
			(xy 113.190021 -229.298813) (xy 112.910111 -229.298813) (xy 112.901986 -229.350108) (xy 112.885938 -229.399501)
			(xy 112.86236 -229.445775) (xy 112.831834 -229.487791) (xy 112.795111 -229.524514) (xy 112.753095 -229.55504)
			(xy 112.706821 -229.578618) (xy 112.657428 -229.594666) (xy 112.606133 -229.602791) (xy 112.554199 -229.602791)
			(xy 112.502904 -229.594666) (xy 112.453511 -229.578618) (xy 112.407237 -229.55504) (xy 112.365221 -229.524514)
			(xy 112.328498 -229.487791) (xy 112.297972 -229.445775) (xy 112.274394 -229.399501) (xy 112.258346 -229.350108)
			(xy 112.250221 -229.298813) (xy 111.969991 -229.298813) (xy 111.961876 -229.35005) (xy 111.94583 -229.399434)
			(xy 111.922257 -229.445701) (xy 111.891736 -229.487711) (xy 111.85502 -229.524428) (xy 111.813011 -229.554951)
			(xy 111.766746 -229.578526) (xy 111.717361 -229.594573) (xy 111.666075 -229.602698) (xy 111.640112 -229.6033)
			(xy 111.63808 -229.6033) (xy 111.628022 -229.603671) (xy 111.609409 -229.611291) (xy 111.595148 -229.625473)
			(xy 111.587426 -229.644044) (xy 111.587026 -229.6541) (xy 111.587026 -230.112629) (xy 111.780321 -230.112629)
			(xy 111.780321 -230.060695) (xy 111.788446 -230.0094) (xy 111.804494 -229.960007) (xy 111.828072 -229.913733)
			(xy 111.858598 -229.871717) (xy 111.895321 -229.834994) (xy 111.937337 -229.804468) (xy 111.983611 -229.78089)
			(xy 112.033004 -229.764842) (xy 112.084299 -229.756717) (xy 112.136233 -229.756717) (xy 112.187528 -229.764842)
			(xy 112.236921 -229.78089) (xy 112.283195 -229.804468) (xy 112.325211 -229.834994) (xy 112.361934 -229.871717)
			(xy 112.39246 -229.913733) (xy 112.416038 -229.960007) (xy 112.432086 -230.0094) (xy 112.440211 -230.060695)
			(xy 112.44072 -230.086662) (xy 112.440211 -230.112629) (xy 112.720121 -230.112629) (xy 112.720121 -230.060695)
			(xy 112.728246 -230.0094) (xy 112.744294 -229.960007) (xy 112.767872 -229.913733) (xy 112.798398 -229.871717)
			(xy 112.835121 -229.834994) (xy 112.877137 -229.804468) (xy 112.923411 -229.78089) (xy 112.972804 -229.764842)
			(xy 113.024099 -229.756717) (xy 113.076033 -229.756717) (xy 113.127328 -229.764842) (xy 113.176721 -229.78089)
			(xy 113.222995 -229.804468) (xy 113.265011 -229.834994) (xy 113.301734 -229.871717) (xy 113.33226 -229.913733)
			(xy 113.355838 -229.960007) (xy 113.371886 -230.0094) (xy 113.380011 -230.060695) (xy 113.38052 -230.086662)
			(xy 113.380011 -230.112629) (xy 113.659921 -230.112629) (xy 113.659921 -230.060695) (xy 113.668046 -230.0094)
			(xy 113.684094 -229.960007) (xy 113.707672 -229.913733) (xy 113.738198 -229.871717) (xy 113.774921 -229.834994)
			(xy 113.816937 -229.804468) (xy 113.863211 -229.78089) (xy 113.912604 -229.764842) (xy 113.963899 -229.756717)
			(xy 114.015833 -229.756717) (xy 114.067128 -229.764842) (xy 114.116521 -229.78089) (xy 114.162795 -229.804468)
			(xy 114.204811 -229.834994) (xy 114.241534 -229.871717) (xy 114.27206 -229.913733) (xy 114.295638 -229.960007)
			(xy 114.311686 -230.0094) (xy 114.319811 -230.060695) (xy 114.32032 -230.086662) (xy 114.319811 -230.112629)
			(xy 114.599721 -230.112629) (xy 114.599721 -230.060695) (xy 114.607846 -230.0094) (xy 114.623894 -229.960007)
			(xy 114.647472 -229.913733) (xy 114.677998 -229.871717) (xy 114.714721 -229.834994) (xy 114.756737 -229.804468)
			(xy 114.803011 -229.78089) (xy 114.852404 -229.764842) (xy 114.903699 -229.756717) (xy 114.955633 -229.756717)
			(xy 115.006928 -229.764842) (xy 115.056321 -229.78089) (xy 115.102595 -229.804468) (xy 115.144611 -229.834994)
			(xy 115.181334 -229.871717) (xy 115.21186 -229.913733) (xy 115.235438 -229.960007) (xy 115.251486 -230.0094)
			(xy 115.259611 -230.060695) (xy 115.26012 -230.086662) (xy 115.259611 -230.112629) (xy 115.539267 -230.112629)
			(xy 115.539267 -230.060695) (xy 115.547392 -230.0094) (xy 115.56344 -229.960007) (xy 115.587018 -229.913733)
			(xy 115.617544 -229.871717) (xy 115.654267 -229.834994) (xy 115.696283 -229.804468) (xy 115.742557 -229.78089)
			(xy 115.79195 -229.764842) (xy 115.843245 -229.756717) (xy 115.895179 -229.756717) (xy 115.946474 -229.764842)
			(xy 115.995867 -229.78089) (xy 116.042141 -229.804468) (xy 116.084157 -229.834994) (xy 116.12088 -229.871717)
			(xy 116.151406 -229.913733) (xy 116.174984 -229.960007) (xy 116.191032 -230.0094) (xy 116.199157 -230.060695)
			(xy 116.199666 -230.086662) (xy 116.199157 -230.112629) (xy 116.479067 -230.112629) (xy 116.479067 -230.060695)
			(xy 116.487192 -230.0094) (xy 116.50324 -229.960007) (xy 116.526818 -229.913733) (xy 116.557344 -229.871717)
			(xy 116.594067 -229.834994) (xy 116.636083 -229.804468) (xy 116.682357 -229.78089) (xy 116.73175 -229.764842)
			(xy 116.783045 -229.756717) (xy 116.834979 -229.756717) (xy 116.886274 -229.764842) (xy 116.935667 -229.78089)
			(xy 116.981941 -229.804468) (xy 117.023957 -229.834994) (xy 117.06068 -229.871717) (xy 117.091206 -229.913733)
			(xy 117.114784 -229.960007) (xy 117.130832 -230.0094) (xy 117.138957 -230.060695) (xy 117.139466 -230.086662)
			(xy 117.138957 -230.112629) (xy 117.418867 -230.112629) (xy 117.418867 -230.060695) (xy 117.426992 -230.0094)
			(xy 117.44304 -229.960007) (xy 117.466618 -229.913733) (xy 117.497144 -229.871717) (xy 117.533867 -229.834994)
			(xy 117.575883 -229.804468) (xy 117.622157 -229.78089) (xy 117.67155 -229.764842) (xy 117.722845 -229.756717)
			(xy 117.774779 -229.756717) (xy 117.826074 -229.764842) (xy 117.875467 -229.78089) (xy 117.921741 -229.804468)
			(xy 117.963757 -229.834994) (xy 118.00048 -229.871717) (xy 118.031006 -229.913733) (xy 118.054584 -229.960007)
			(xy 118.070632 -230.0094) (xy 118.078757 -230.060695) (xy 118.079266 -230.086662) (xy 118.078757 -230.112629)
			(xy 118.358667 -230.112629) (xy 118.358667 -230.060695) (xy 118.366792 -230.0094) (xy 118.38284 -229.960007)
			(xy 118.406418 -229.913733) (xy 118.436944 -229.871717) (xy 118.473667 -229.834994) (xy 118.515683 -229.804468)
			(xy 118.561957 -229.78089) (xy 118.61135 -229.764842) (xy 118.662645 -229.756717) (xy 118.714579 -229.756717)
			(xy 118.765874 -229.764842) (xy 118.815267 -229.78089) (xy 118.861541 -229.804468) (xy 118.903557 -229.834994)
			(xy 118.94028 -229.871717) (xy 118.970806 -229.913733) (xy 118.994384 -229.960007) (xy 119.010432 -230.0094)
			(xy 119.018557 -230.060695) (xy 119.019066 -230.086662) (xy 119.018557 -230.112629) (xy 119.298467 -230.112629)
			(xy 119.298467 -230.060695) (xy 119.306592 -230.0094) (xy 119.32264 -229.960007) (xy 119.346218 -229.913733)
			(xy 119.376744 -229.871717) (xy 119.413467 -229.834994) (xy 119.455483 -229.804468) (xy 119.501757 -229.78089)
			(xy 119.55115 -229.764842) (xy 119.602445 -229.756717) (xy 119.654379 -229.756717) (xy 119.705674 -229.764842)
			(xy 119.755067 -229.78089) (xy 119.801341 -229.804468) (xy 119.843357 -229.834994) (xy 119.88008 -229.871717)
			(xy 119.910606 -229.913733) (xy 119.934184 -229.960007) (xy 119.950232 -230.0094) (xy 119.958357 -230.060695)
			(xy 119.958866 -230.086662) (xy 119.958357 -230.112629) (xy 120.238267 -230.112629) (xy 120.238267 -230.060695)
			(xy 120.246392 -230.0094) (xy 120.26244 -229.960007) (xy 120.286018 -229.913733) (xy 120.316544 -229.871717)
			(xy 120.353267 -229.834994) (xy 120.395283 -229.804468) (xy 120.441557 -229.78089) (xy 120.49095 -229.764842)
			(xy 120.542245 -229.756717) (xy 120.594179 -229.756717) (xy 120.645474 -229.764842) (xy 120.694867 -229.78089)
			(xy 120.741141 -229.804468) (xy 120.783157 -229.834994) (xy 120.81988 -229.871717) (xy 120.850406 -229.913733)
			(xy 120.873984 -229.960007) (xy 120.890032 -230.0094) (xy 120.898157 -230.060695) (xy 120.898666 -230.086662)
			(xy 120.898157 -230.112629) (xy 121.178067 -230.112629) (xy 121.178067 -230.060695) (xy 121.186192 -230.0094)
			(xy 121.20224 -229.960007) (xy 121.225818 -229.913733) (xy 121.256344 -229.871717) (xy 121.293067 -229.834994)
			(xy 121.335083 -229.804468) (xy 121.381357 -229.78089) (xy 121.43075 -229.764842) (xy 121.482045 -229.756717)
			(xy 121.533979 -229.756717) (xy 121.585274 -229.764842) (xy 121.634667 -229.78089) (xy 121.680941 -229.804468)
			(xy 121.722957 -229.834994) (xy 121.75968 -229.871717) (xy 121.790206 -229.913733) (xy 121.813784 -229.960007)
			(xy 121.829832 -230.0094) (xy 121.837957 -230.060695) (xy 121.838466 -230.086662) (xy 121.837957 -230.112629)
			(xy 123.057667 -230.112629) (xy 123.057667 -230.060695) (xy 123.065792 -230.0094) (xy 123.08184 -229.960007)
			(xy 123.105418 -229.913733) (xy 123.135944 -229.871717) (xy 123.172667 -229.834994) (xy 123.214683 -229.804468)
			(xy 123.260957 -229.78089) (xy 123.31035 -229.764842) (xy 123.361645 -229.756717) (xy 123.413579 -229.756717)
			(xy 123.464874 -229.764842) (xy 123.514267 -229.78089) (xy 123.560541 -229.804468) (xy 123.602557 -229.834994)
			(xy 123.63928 -229.871717) (xy 123.669806 -229.913733) (xy 123.693384 -229.960007) (xy 123.709432 -230.0094)
			(xy 123.717557 -230.060695) (xy 123.718066 -230.086662) (xy 123.717557 -230.112629) (xy 123.997467 -230.112629)
			(xy 123.997467 -230.060695) (xy 124.005592 -230.0094) (xy 124.02164 -229.960007) (xy 124.045218 -229.913733)
			(xy 124.075744 -229.871717) (xy 124.112467 -229.834994) (xy 124.154483 -229.804468) (xy 124.200757 -229.78089)
			(xy 124.25015 -229.764842) (xy 124.301445 -229.756717) (xy 124.353379 -229.756717) (xy 124.404674 -229.764842)
			(xy 124.454067 -229.78089) (xy 124.500341 -229.804468) (xy 124.542357 -229.834994) (xy 124.57908 -229.871717)
			(xy 124.609606 -229.913733) (xy 124.633184 -229.960007) (xy 124.649232 -230.0094) (xy 124.657357 -230.060695)
			(xy 124.657866 -230.086662) (xy 124.657357 -230.112629) (xy 124.649232 -230.163924) (xy 124.633184 -230.213317)
			(xy 124.609606 -230.259591) (xy 124.57908 -230.301607) (xy 124.542357 -230.33833) (xy 124.500341 -230.368856)
			(xy 124.454067 -230.392434) (xy 124.404674 -230.408482) (xy 124.353379 -230.416607) (xy 124.301445 -230.416607)
			(xy 124.25015 -230.408482) (xy 124.200757 -230.392434) (xy 124.154483 -230.368856) (xy 124.112467 -230.33833)
			(xy 124.075744 -230.301607) (xy 124.045218 -230.259591) (xy 124.02164 -230.213317) (xy 124.005592 -230.163924)
			(xy 123.997467 -230.112629) (xy 123.717557 -230.112629) (xy 123.709432 -230.163924) (xy 123.693384 -230.213317)
			(xy 123.669806 -230.259591) (xy 123.63928 -230.301607) (xy 123.602557 -230.33833) (xy 123.560541 -230.368856)
			(xy 123.514267 -230.392434) (xy 123.464874 -230.408482) (xy 123.413579 -230.416607) (xy 123.361645 -230.416607)
			(xy 123.31035 -230.408482) (xy 123.260957 -230.392434) (xy 123.214683 -230.368856) (xy 123.172667 -230.33833)
			(xy 123.135944 -230.301607) (xy 123.105418 -230.259591) (xy 123.08184 -230.213317) (xy 123.065792 -230.163924)
			(xy 123.057667 -230.112629) (xy 121.837957 -230.112629) (xy 121.829832 -230.163924) (xy 121.813784 -230.213317)
			(xy 121.790206 -230.259591) (xy 121.75968 -230.301607) (xy 121.722957 -230.33833) (xy 121.680941 -230.368856)
			(xy 121.634667 -230.392434) (xy 121.585274 -230.408482) (xy 121.533979 -230.416607) (xy 121.482045 -230.416607)
			(xy 121.43075 -230.408482) (xy 121.381357 -230.392434) (xy 121.335083 -230.368856) (xy 121.293067 -230.33833)
			(xy 121.256344 -230.301607) (xy 121.225818 -230.259591) (xy 121.20224 -230.213317) (xy 121.186192 -230.163924)
			(xy 121.178067 -230.112629) (xy 120.898157 -230.112629) (xy 120.890032 -230.163924) (xy 120.873984 -230.213317)
			(xy 120.850406 -230.259591) (xy 120.81988 -230.301607) (xy 120.783157 -230.33833) (xy 120.741141 -230.368856)
			(xy 120.694867 -230.392434) (xy 120.645474 -230.408482) (xy 120.594179 -230.416607) (xy 120.542245 -230.416607)
			(xy 120.49095 -230.408482) (xy 120.441557 -230.392434) (xy 120.395283 -230.368856) (xy 120.353267 -230.33833)
			(xy 120.316544 -230.301607) (xy 120.286018 -230.259591) (xy 120.26244 -230.213317) (xy 120.246392 -230.163924)
			(xy 120.238267 -230.112629) (xy 119.958357 -230.112629) (xy 119.950232 -230.163924) (xy 119.934184 -230.213317)
			(xy 119.910606 -230.259591) (xy 119.88008 -230.301607) (xy 119.843357 -230.33833) (xy 119.801341 -230.368856)
			(xy 119.755067 -230.392434) (xy 119.705674 -230.408482) (xy 119.654379 -230.416607) (xy 119.602445 -230.416607)
			(xy 119.55115 -230.408482) (xy 119.501757 -230.392434) (xy 119.455483 -230.368856) (xy 119.413467 -230.33833)
			(xy 119.376744 -230.301607) (xy 119.346218 -230.259591) (xy 119.32264 -230.213317) (xy 119.306592 -230.163924)
			(xy 119.298467 -230.112629) (xy 119.018557 -230.112629) (xy 119.010432 -230.163924) (xy 118.994384 -230.213317)
			(xy 118.970806 -230.259591) (xy 118.94028 -230.301607) (xy 118.903557 -230.33833) (xy 118.861541 -230.368856)
			(xy 118.815267 -230.392434) (xy 118.765874 -230.408482) (xy 118.714579 -230.416607) (xy 118.662645 -230.416607)
			(xy 118.61135 -230.408482) (xy 118.561957 -230.392434) (xy 118.515683 -230.368856) (xy 118.473667 -230.33833)
			(xy 118.436944 -230.301607) (xy 118.406418 -230.259591) (xy 118.38284 -230.213317) (xy 118.366792 -230.163924)
			(xy 118.358667 -230.112629) (xy 118.078757 -230.112629) (xy 118.070632 -230.163924) (xy 118.054584 -230.213317)
			(xy 118.031006 -230.259591) (xy 118.00048 -230.301607) (xy 117.963757 -230.33833) (xy 117.921741 -230.368856)
			(xy 117.875467 -230.392434) (xy 117.826074 -230.408482) (xy 117.774779 -230.416607) (xy 117.722845 -230.416607)
			(xy 117.67155 -230.408482) (xy 117.622157 -230.392434) (xy 117.575883 -230.368856) (xy 117.533867 -230.33833)
			(xy 117.497144 -230.301607) (xy 117.466618 -230.259591) (xy 117.44304 -230.213317) (xy 117.426992 -230.163924)
			(xy 117.418867 -230.112629) (xy 117.138957 -230.112629) (xy 117.130832 -230.163924) (xy 117.114784 -230.213317)
			(xy 117.091206 -230.259591) (xy 117.06068 -230.301607) (xy 117.023957 -230.33833) (xy 116.981941 -230.368856)
			(xy 116.935667 -230.392434) (xy 116.886274 -230.408482) (xy 116.834979 -230.416607) (xy 116.783045 -230.416607)
			(xy 116.73175 -230.408482) (xy 116.682357 -230.392434) (xy 116.636083 -230.368856) (xy 116.594067 -230.33833)
			(xy 116.557344 -230.301607) (xy 116.526818 -230.259591) (xy 116.50324 -230.213317) (xy 116.487192 -230.163924)
			(xy 116.479067 -230.112629) (xy 116.199157 -230.112629) (xy 116.191032 -230.163924) (xy 116.174984 -230.213317)
			(xy 116.151406 -230.259591) (xy 116.12088 -230.301607) (xy 116.084157 -230.33833) (xy 116.042141 -230.368856)
			(xy 115.995867 -230.392434) (xy 115.946474 -230.408482) (xy 115.895179 -230.416607) (xy 115.843245 -230.416607)
			(xy 115.79195 -230.408482) (xy 115.742557 -230.392434) (xy 115.696283 -230.368856) (xy 115.654267 -230.33833)
			(xy 115.617544 -230.301607) (xy 115.587018 -230.259591) (xy 115.56344 -230.213317) (xy 115.547392 -230.163924)
			(xy 115.539267 -230.112629) (xy 115.259611 -230.112629) (xy 115.251486 -230.163924) (xy 115.235438 -230.213317)
			(xy 115.21186 -230.259591) (xy 115.181334 -230.301607) (xy 115.144611 -230.33833) (xy 115.102595 -230.368856)
			(xy 115.056321 -230.392434) (xy 115.006928 -230.408482) (xy 114.955633 -230.416607) (xy 114.903699 -230.416607)
			(xy 114.852404 -230.408482) (xy 114.803011 -230.392434) (xy 114.756737 -230.368856) (xy 114.714721 -230.33833)
			(xy 114.677998 -230.301607) (xy 114.647472 -230.259591) (xy 114.623894 -230.213317) (xy 114.607846 -230.163924)
			(xy 114.599721 -230.112629) (xy 114.319811 -230.112629) (xy 114.311686 -230.163924) (xy 114.295638 -230.213317)
			(xy 114.27206 -230.259591) (xy 114.241534 -230.301607) (xy 114.204811 -230.33833) (xy 114.162795 -230.368856)
			(xy 114.116521 -230.392434) (xy 114.067128 -230.408482) (xy 114.015833 -230.416607) (xy 113.963899 -230.416607)
			(xy 113.912604 -230.408482) (xy 113.863211 -230.392434) (xy 113.816937 -230.368856) (xy 113.774921 -230.33833)
			(xy 113.738198 -230.301607) (xy 113.707672 -230.259591) (xy 113.684094 -230.213317) (xy 113.668046 -230.163924)
			(xy 113.659921 -230.112629) (xy 113.380011 -230.112629) (xy 113.371886 -230.163924) (xy 113.355838 -230.213317)
			(xy 113.33226 -230.259591) (xy 113.301734 -230.301607) (xy 113.265011 -230.33833) (xy 113.222995 -230.368856)
			(xy 113.176721 -230.392434) (xy 113.127328 -230.408482) (xy 113.076033 -230.416607) (xy 113.024099 -230.416607)
			(xy 112.972804 -230.408482) (xy 112.923411 -230.392434) (xy 112.877137 -230.368856) (xy 112.835121 -230.33833)
			(xy 112.798398 -230.301607) (xy 112.767872 -230.259591) (xy 112.744294 -230.213317) (xy 112.728246 -230.163924)
			(xy 112.720121 -230.112629) (xy 112.440211 -230.112629) (xy 112.432086 -230.163924) (xy 112.416038 -230.213317)
			(xy 112.39246 -230.259591) (xy 112.361934 -230.301607) (xy 112.325211 -230.33833) (xy 112.283195 -230.368856)
			(xy 112.236921 -230.392434) (xy 112.187528 -230.408482) (xy 112.136233 -230.416607) (xy 112.084299 -230.416607)
			(xy 112.033004 -230.408482) (xy 111.983611 -230.392434) (xy 111.937337 -230.368856) (xy 111.895321 -230.33833)
			(xy 111.858598 -230.301607) (xy 111.828072 -230.259591) (xy 111.804494 -230.213317) (xy 111.788446 -230.163924)
			(xy 111.780321 -230.112629) (xy 111.587026 -230.112629) (xy 111.587026 -230.519224) (xy 111.587457 -230.529272)
			(xy 111.595179 -230.547824) (xy 111.609431 -230.561991) (xy 111.62803 -230.569603) (xy 111.63808 -230.570024)
			(xy 111.640366 -230.570024) (xy 111.666339 -230.570504) (xy 111.717645 -230.578626) (xy 111.76705 -230.594674)
			(xy 111.813335 -230.618253) (xy 111.855362 -230.648783) (xy 111.892095 -230.685512) (xy 111.922629 -230.727536)
			(xy 111.946213 -230.773819) (xy 111.962266 -230.823221) (xy 111.970393 -230.874527) (xy 111.970393 -230.926445)
			(xy 112.250221 -230.926445) (xy 112.250221 -230.874511) (xy 112.258346 -230.823216) (xy 112.274394 -230.773823)
			(xy 112.297972 -230.727549) (xy 112.328498 -230.685533) (xy 112.365221 -230.64881) (xy 112.407237 -230.618284)
			(xy 112.453511 -230.594706) (xy 112.502904 -230.578658) (xy 112.554199 -230.570533) (xy 112.606133 -230.570533)
			(xy 112.657428 -230.578658) (xy 112.706821 -230.594706) (xy 112.753095 -230.618284) (xy 112.795111 -230.64881)
			(xy 112.831834 -230.685533) (xy 112.86236 -230.727549) (xy 112.885938 -230.773823) (xy 112.901986 -230.823216)
			(xy 112.910111 -230.874511) (xy 112.91062 -230.900478) (xy 112.910111 -230.926445) (xy 113.190021 -230.926445)
			(xy 113.190021 -230.874511) (xy 113.198146 -230.823216) (xy 113.214194 -230.773823) (xy 113.237772 -230.727549)
			(xy 113.268298 -230.685533) (xy 113.305021 -230.64881) (xy 113.347037 -230.618284) (xy 113.393311 -230.594706)
			(xy 113.442704 -230.578658) (xy 113.493999 -230.570533) (xy 113.545933 -230.570533) (xy 113.597228 -230.578658)
			(xy 113.646621 -230.594706) (xy 113.692895 -230.618284) (xy 113.734911 -230.64881) (xy 113.771634 -230.685533)
			(xy 113.80216 -230.727549) (xy 113.825738 -230.773823) (xy 113.841786 -230.823216) (xy 113.849911 -230.874511)
			(xy 113.85042 -230.900478) (xy 113.849911 -230.926445) (xy 114.130075 -230.926445) (xy 114.130075 -230.874511)
			(xy 114.1382 -230.823216) (xy 114.154248 -230.773823) (xy 114.177826 -230.727549) (xy 114.208352 -230.685533)
			(xy 114.245075 -230.64881) (xy 114.287091 -230.618284) (xy 114.333365 -230.594706) (xy 114.382758 -230.578658)
			(xy 114.434053 -230.570533) (xy 114.485987 -230.570533) (xy 114.537282 -230.578658) (xy 114.586675 -230.594706)
			(xy 114.632949 -230.618284) (xy 114.674965 -230.64881) (xy 114.711688 -230.685533) (xy 114.742214 -230.727549)
			(xy 114.765792 -230.773823) (xy 114.78184 -230.823216) (xy 114.789965 -230.874511) (xy 114.790474 -230.900478)
			(xy 114.789965 -230.926445) (xy 115.069621 -230.926445) (xy 115.069621 -230.874511) (xy 115.077746 -230.823216)
			(xy 115.093794 -230.773823) (xy 115.117372 -230.727549) (xy 115.147898 -230.685533) (xy 115.184621 -230.64881)
			(xy 115.226637 -230.618284) (xy 115.272911 -230.594706) (xy 115.322304 -230.578658) (xy 115.373599 -230.570533)
			(xy 115.425533 -230.570533) (xy 115.476828 -230.578658) (xy 115.526221 -230.594706) (xy 115.572495 -230.618284)
			(xy 115.614511 -230.64881) (xy 115.651234 -230.685533) (xy 115.68176 -230.727549) (xy 115.705338 -230.773823)
			(xy 115.721386 -230.823216) (xy 115.729511 -230.874511) (xy 115.73002 -230.900478) (xy 115.729511 -230.926445)
			(xy 116.009421 -230.926445) (xy 116.009421 -230.874511) (xy 116.017546 -230.823216) (xy 116.033594 -230.773823)
			(xy 116.057172 -230.727549) (xy 116.087698 -230.685533) (xy 116.124421 -230.64881) (xy 116.166437 -230.618284)
			(xy 116.212711 -230.594706) (xy 116.262104 -230.578658) (xy 116.313399 -230.570533) (xy 116.365333 -230.570533)
			(xy 116.416628 -230.578658) (xy 116.466021 -230.594706) (xy 116.512295 -230.618284) (xy 116.554311 -230.64881)
			(xy 116.591034 -230.685533) (xy 116.62156 -230.727549) (xy 116.645138 -230.773823) (xy 116.661186 -230.823216)
			(xy 116.669311 -230.874511) (xy 116.66982 -230.900478) (xy 116.669311 -230.926445) (xy 116.949221 -230.926445)
			(xy 116.949221 -230.874511) (xy 116.957346 -230.823216) (xy 116.973394 -230.773823) (xy 116.996972 -230.727549)
			(xy 117.027498 -230.685533) (xy 117.064221 -230.64881) (xy 117.106237 -230.618284) (xy 117.152511 -230.594706)
			(xy 117.201904 -230.578658) (xy 117.253199 -230.570533) (xy 117.305133 -230.570533) (xy 117.356428 -230.578658)
			(xy 117.405821 -230.594706) (xy 117.452095 -230.618284) (xy 117.494111 -230.64881) (xy 117.530834 -230.685533)
			(xy 117.56136 -230.727549) (xy 117.584938 -230.773823) (xy 117.600986 -230.823216) (xy 117.609111 -230.874511)
			(xy 117.60962 -230.900478) (xy 117.609111 -230.926445) (xy 117.889021 -230.926445) (xy 117.889021 -230.874511)
			(xy 117.897146 -230.823216) (xy 117.913194 -230.773823) (xy 117.936772 -230.727549) (xy 117.967298 -230.685533)
			(xy 118.004021 -230.64881) (xy 118.046037 -230.618284) (xy 118.092311 -230.594706) (xy 118.141704 -230.578658)
			(xy 118.192999 -230.570533) (xy 118.244933 -230.570533) (xy 118.296228 -230.578658) (xy 118.345621 -230.594706)
			(xy 118.391895 -230.618284) (xy 118.433911 -230.64881) (xy 118.470634 -230.685533) (xy 118.50116 -230.727549)
			(xy 118.524738 -230.773823) (xy 118.540786 -230.823216) (xy 118.548911 -230.874511) (xy 118.54942 -230.900478)
			(xy 118.548911 -230.926445) (xy 118.828821 -230.926445) (xy 118.828821 -230.874511) (xy 118.836946 -230.823216)
			(xy 118.852994 -230.773823) (xy 118.876572 -230.727549) (xy 118.907098 -230.685533) (xy 118.943821 -230.64881)
			(xy 118.985837 -230.618284) (xy 119.032111 -230.594706) (xy 119.081504 -230.578658) (xy 119.132799 -230.570533)
			(xy 119.184733 -230.570533) (xy 119.236028 -230.578658) (xy 119.285421 -230.594706) (xy 119.331695 -230.618284)
			(xy 119.373711 -230.64881) (xy 119.410434 -230.685533) (xy 119.44096 -230.727549) (xy 119.464538 -230.773823)
			(xy 119.480586 -230.823216) (xy 119.488711 -230.874511) (xy 119.48922 -230.900478) (xy 119.488711 -230.926445)
			(xy 119.768621 -230.926445) (xy 119.768621 -230.874511) (xy 119.776746 -230.823216) (xy 119.792794 -230.773823)
			(xy 119.816372 -230.727549) (xy 119.846898 -230.685533) (xy 119.883621 -230.64881) (xy 119.925637 -230.618284)
			(xy 119.971911 -230.594706) (xy 120.021304 -230.578658) (xy 120.072599 -230.570533) (xy 120.124533 -230.570533)
			(xy 120.175828 -230.578658) (xy 120.225221 -230.594706) (xy 120.271495 -230.618284) (xy 120.313511 -230.64881)
			(xy 120.350234 -230.685533) (xy 120.38076 -230.727549) (xy 120.404338 -230.773823) (xy 120.420386 -230.823216)
			(xy 120.428511 -230.874511) (xy 120.42902 -230.900478) (xy 120.428511 -230.926445) (xy 120.708421 -230.926445)
			(xy 120.708421 -230.874511) (xy 120.716546 -230.823216) (xy 120.732594 -230.773823) (xy 120.756172 -230.727549)
			(xy 120.786698 -230.685533) (xy 120.823421 -230.64881) (xy 120.865437 -230.618284) (xy 120.911711 -230.594706)
			(xy 120.961104 -230.578658) (xy 121.012399 -230.570533) (xy 121.064333 -230.570533) (xy 121.115628 -230.578658)
			(xy 121.165021 -230.594706) (xy 121.211295 -230.618284) (xy 121.253311 -230.64881) (xy 121.290034 -230.685533)
			(xy 121.32056 -230.727549) (xy 121.344138 -230.773823) (xy 121.360186 -230.823216) (xy 121.368311 -230.874511)
			(xy 121.36882 -230.900478) (xy 121.368311 -230.926445) (xy 121.647967 -230.926445) (xy 121.647967 -230.874511)
			(xy 121.656092 -230.823216) (xy 121.67214 -230.773823) (xy 121.695718 -230.727549) (xy 121.726244 -230.685533)
			(xy 121.762967 -230.64881) (xy 121.804983 -230.618284) (xy 121.851257 -230.594706) (xy 121.90065 -230.578658)
			(xy 121.951945 -230.570533) (xy 122.003879 -230.570533) (xy 122.055174 -230.578658) (xy 122.104567 -230.594706)
			(xy 122.150841 -230.618284) (xy 122.192857 -230.64881) (xy 122.22958 -230.685533) (xy 122.260106 -230.727549)
			(xy 122.283684 -230.773823) (xy 122.299732 -230.823216) (xy 122.307857 -230.874511) (xy 122.308366 -230.900478)
			(xy 122.307857 -230.926445) (xy 122.588021 -230.926445) (xy 122.588021 -230.874511) (xy 122.596146 -230.823216)
			(xy 122.612194 -230.773823) (xy 122.635772 -230.727549) (xy 122.666298 -230.685533) (xy 122.703021 -230.64881)
			(xy 122.745037 -230.618284) (xy 122.791311 -230.594706) (xy 122.840704 -230.578658) (xy 122.891999 -230.570533)
			(xy 122.943933 -230.570533) (xy 122.995228 -230.578658) (xy 123.044621 -230.594706) (xy 123.090895 -230.618284)
			(xy 123.132911 -230.64881) (xy 123.169634 -230.685533) (xy 123.20016 -230.727549) (xy 123.223738 -230.773823)
			(xy 123.239786 -230.823216) (xy 123.247911 -230.874511) (xy 123.24842 -230.900478) (xy 123.247911 -230.926445)
			(xy 123.527821 -230.926445) (xy 123.527821 -230.874511) (xy 123.535946 -230.823216) (xy 123.551994 -230.773823)
			(xy 123.575572 -230.727549) (xy 123.606098 -230.685533) (xy 123.642821 -230.64881) (xy 123.684837 -230.618284)
			(xy 123.731111 -230.594706) (xy 123.780504 -230.578658) (xy 123.831799 -230.570533) (xy 123.883733 -230.570533)
			(xy 123.935028 -230.578658) (xy 123.984421 -230.594706) (xy 124.030695 -230.618284) (xy 124.072711 -230.64881)
			(xy 124.109434 -230.685533) (xy 124.13996 -230.727549) (xy 124.163538 -230.773823) (xy 124.179586 -230.823216)
			(xy 124.187711 -230.874511) (xy 124.18822 -230.900478) (xy 124.187711 -230.926445) (xy 124.179586 -230.97774)
			(xy 124.163538 -231.027133) (xy 124.13996 -231.073407) (xy 124.109434 -231.115423) (xy 124.072711 -231.152146)
			(xy 124.030695 -231.182672) (xy 123.984421 -231.20625) (xy 123.935028 -231.222298) (xy 123.883733 -231.230423)
			(xy 123.831799 -231.230423) (xy 123.780504 -231.222298) (xy 123.731111 -231.20625) (xy 123.684837 -231.182672)
			(xy 123.642821 -231.152146) (xy 123.606098 -231.115423) (xy 123.575572 -231.073407) (xy 123.551994 -231.027133)
			(xy 123.535946 -230.97774) (xy 123.527821 -230.926445) (xy 123.247911 -230.926445) (xy 123.239786 -230.97774)
			(xy 123.223738 -231.027133) (xy 123.20016 -231.073407) (xy 123.169634 -231.115423) (xy 123.132911 -231.152146)
			(xy 123.090895 -231.182672) (xy 123.044621 -231.20625) (xy 122.995228 -231.222298) (xy 122.943933 -231.230423)
			(xy 122.891999 -231.230423) (xy 122.840704 -231.222298) (xy 122.791311 -231.20625) (xy 122.745037 -231.182672)
			(xy 122.703021 -231.152146) (xy 122.666298 -231.115423) (xy 122.635772 -231.073407) (xy 122.612194 -231.027133)
			(xy 122.596146 -230.97774) (xy 122.588021 -230.926445) (xy 122.307857 -230.926445) (xy 122.299732 -230.97774)
			(xy 122.283684 -231.027133) (xy 122.260106 -231.073407) (xy 122.22958 -231.115423) (xy 122.192857 -231.152146)
			(xy 122.150841 -231.182672) (xy 122.104567 -231.20625) (xy 122.055174 -231.222298) (xy 122.003879 -231.230423)
			(xy 121.951945 -231.230423) (xy 121.90065 -231.222298) (xy 121.851257 -231.20625) (xy 121.804983 -231.182672)
			(xy 121.762967 -231.152146) (xy 121.726244 -231.115423) (xy 121.695718 -231.073407) (xy 121.67214 -231.027133)
			(xy 121.656092 -230.97774) (xy 121.647967 -230.926445) (xy 121.368311 -230.926445) (xy 121.360186 -230.97774)
			(xy 121.344138 -231.027133) (xy 121.32056 -231.073407) (xy 121.290034 -231.115423) (xy 121.253311 -231.152146)
			(xy 121.211295 -231.182672) (xy 121.165021 -231.20625) (xy 121.115628 -231.222298) (xy 121.064333 -231.230423)
			(xy 121.012399 -231.230423) (xy 120.961104 -231.222298) (xy 120.911711 -231.20625) (xy 120.865437 -231.182672)
			(xy 120.823421 -231.152146) (xy 120.786698 -231.115423) (xy 120.756172 -231.073407) (xy 120.732594 -231.027133)
			(xy 120.716546 -230.97774) (xy 120.708421 -230.926445) (xy 120.428511 -230.926445) (xy 120.420386 -230.97774)
			(xy 120.404338 -231.027133) (xy 120.38076 -231.073407) (xy 120.350234 -231.115423) (xy 120.313511 -231.152146)
			(xy 120.271495 -231.182672) (xy 120.225221 -231.20625) (xy 120.175828 -231.222298) (xy 120.124533 -231.230423)
			(xy 120.072599 -231.230423) (xy 120.021304 -231.222298) (xy 119.971911 -231.20625) (xy 119.925637 -231.182672)
			(xy 119.883621 -231.152146) (xy 119.846898 -231.115423) (xy 119.816372 -231.073407) (xy 119.792794 -231.027133)
			(xy 119.776746 -230.97774) (xy 119.768621 -230.926445) (xy 119.488711 -230.926445) (xy 119.480586 -230.97774)
			(xy 119.464538 -231.027133) (xy 119.44096 -231.073407) (xy 119.410434 -231.115423) (xy 119.373711 -231.152146)
			(xy 119.331695 -231.182672) (xy 119.285421 -231.20625) (xy 119.236028 -231.222298) (xy 119.184733 -231.230423)
			(xy 119.132799 -231.230423) (xy 119.081504 -231.222298) (xy 119.032111 -231.20625) (xy 118.985837 -231.182672)
			(xy 118.943821 -231.152146) (xy 118.907098 -231.115423) (xy 118.876572 -231.073407) (xy 118.852994 -231.027133)
			(xy 118.836946 -230.97774) (xy 118.828821 -230.926445) (xy 118.548911 -230.926445) (xy 118.540786 -230.97774)
			(xy 118.524738 -231.027133) (xy 118.50116 -231.073407) (xy 118.470634 -231.115423) (xy 118.433911 -231.152146)
			(xy 118.391895 -231.182672) (xy 118.345621 -231.20625) (xy 118.296228 -231.222298) (xy 118.244933 -231.230423)
			(xy 118.192999 -231.230423) (xy 118.141704 -231.222298) (xy 118.092311 -231.20625) (xy 118.046037 -231.182672)
			(xy 118.004021 -231.152146) (xy 117.967298 -231.115423) (xy 117.936772 -231.073407) (xy 117.913194 -231.027133)
			(xy 117.897146 -230.97774) (xy 117.889021 -230.926445) (xy 117.609111 -230.926445) (xy 117.600986 -230.97774)
			(xy 117.584938 -231.027133) (xy 117.56136 -231.073407) (xy 117.530834 -231.115423) (xy 117.494111 -231.152146)
			(xy 117.452095 -231.182672) (xy 117.405821 -231.20625) (xy 117.356428 -231.222298) (xy 117.305133 -231.230423)
			(xy 117.253199 -231.230423) (xy 117.201904 -231.222298) (xy 117.152511 -231.20625) (xy 117.106237 -231.182672)
			(xy 117.064221 -231.152146) (xy 117.027498 -231.115423) (xy 116.996972 -231.073407) (xy 116.973394 -231.027133)
			(xy 116.957346 -230.97774) (xy 116.949221 -230.926445) (xy 116.669311 -230.926445) (xy 116.661186 -230.97774)
			(xy 116.645138 -231.027133) (xy 116.62156 -231.073407) (xy 116.591034 -231.115423) (xy 116.554311 -231.152146)
			(xy 116.512295 -231.182672) (xy 116.466021 -231.20625) (xy 116.416628 -231.222298) (xy 116.365333 -231.230423)
			(xy 116.313399 -231.230423) (xy 116.262104 -231.222298) (xy 116.212711 -231.20625) (xy 116.166437 -231.182672)
			(xy 116.124421 -231.152146) (xy 116.087698 -231.115423) (xy 116.057172 -231.073407) (xy 116.033594 -231.027133)
			(xy 116.017546 -230.97774) (xy 116.009421 -230.926445) (xy 115.729511 -230.926445) (xy 115.721386 -230.97774)
			(xy 115.705338 -231.027133) (xy 115.68176 -231.073407) (xy 115.651234 -231.115423) (xy 115.614511 -231.152146)
			(xy 115.572495 -231.182672) (xy 115.526221 -231.20625) (xy 115.476828 -231.222298) (xy 115.425533 -231.230423)
			(xy 115.373599 -231.230423) (xy 115.322304 -231.222298) (xy 115.272911 -231.20625) (xy 115.226637 -231.182672)
			(xy 115.184621 -231.152146) (xy 115.147898 -231.115423) (xy 115.117372 -231.073407) (xy 115.093794 -231.027133)
			(xy 115.077746 -230.97774) (xy 115.069621 -230.926445) (xy 114.789965 -230.926445) (xy 114.78184 -230.97774)
			(xy 114.765792 -231.027133) (xy 114.742214 -231.073407) (xy 114.711688 -231.115423) (xy 114.674965 -231.152146)
			(xy 114.632949 -231.182672) (xy 114.586675 -231.20625) (xy 114.537282 -231.222298) (xy 114.485987 -231.230423)
			(xy 114.434053 -231.230423) (xy 114.382758 -231.222298) (xy 114.333365 -231.20625) (xy 114.287091 -231.182672)
			(xy 114.245075 -231.152146) (xy 114.208352 -231.115423) (xy 114.177826 -231.073407) (xy 114.154248 -231.027133)
			(xy 114.1382 -230.97774) (xy 114.130075 -230.926445) (xy 113.849911 -230.926445) (xy 113.841786 -230.97774)
			(xy 113.825738 -231.027133) (xy 113.80216 -231.073407) (xy 113.771634 -231.115423) (xy 113.734911 -231.152146)
			(xy 113.692895 -231.182672) (xy 113.646621 -231.20625) (xy 113.597228 -231.222298) (xy 113.545933 -231.230423)
			(xy 113.493999 -231.230423) (xy 113.442704 -231.222298) (xy 113.393311 -231.20625) (xy 113.347037 -231.182672)
			(xy 113.305021 -231.152146) (xy 113.268298 -231.115423) (xy 113.237772 -231.073407) (xy 113.214194 -231.027133)
			(xy 113.198146 -230.97774) (xy 113.190021 -230.926445) (xy 112.910111 -230.926445) (xy 112.901986 -230.97774)
			(xy 112.885938 -231.027133) (xy 112.86236 -231.073407) (xy 112.831834 -231.115423) (xy 112.795111 -231.152146)
			(xy 112.753095 -231.182672) (xy 112.706821 -231.20625) (xy 112.657428 -231.222298) (xy 112.606133 -231.230423)
			(xy 112.554199 -231.230423) (xy 112.502904 -231.222298) (xy 112.453511 -231.20625) (xy 112.407237 -231.182672)
			(xy 112.365221 -231.152146) (xy 112.328498 -231.115423) (xy 112.297972 -231.073407) (xy 112.274394 -231.027133)
			(xy 112.258346 -230.97774) (xy 112.250221 -230.926445) (xy 111.970393 -230.926445) (xy 111.970393 -230.926473)
			(xy 111.962266 -230.977779) (xy 111.946213 -231.027181) (xy 111.922629 -231.073464) (xy 111.892095 -231.115488)
			(xy 111.855362 -231.152217) (xy 111.813335 -231.182747) (xy 111.76705 -231.206326) (xy 111.717645 -231.222374)
			(xy 111.666339 -231.230496) (xy 111.640366 -231.230932) (xy 111.63808 -231.230932) (xy 111.628024 -231.231304)
			(xy 111.609417 -231.238925) (xy 111.595164 -231.253108) (xy 111.587452 -231.271678) (xy 111.587026 -231.281732)
			(xy 111.587026 -231.740515) (xy 111.780575 -231.740515) (xy 111.780575 -231.688581) (xy 111.7887 -231.637286)
			(xy 111.804748 -231.587893) (xy 111.828326 -231.541619) (xy 111.858852 -231.499603) (xy 111.895575 -231.46288)
			(xy 111.937591 -231.432354) (xy 111.983865 -231.408776) (xy 112.033258 -231.392728) (xy 112.084553 -231.384603)
			(xy 112.136487 -231.384603) (xy 112.187782 -231.392728) (xy 112.237175 -231.408776) (xy 112.283449 -231.432354)
			(xy 112.325465 -231.46288) (xy 112.362188 -231.499603) (xy 112.392714 -231.541619) (xy 112.416292 -231.587893)
			(xy 112.43234 -231.637286) (xy 112.440465 -231.688581) (xy 112.440974 -231.714548) (xy 112.440465 -231.740515)
			(xy 112.720375 -231.740515) (xy 112.720375 -231.688581) (xy 112.7285 -231.637286) (xy 112.744548 -231.587893)
			(xy 112.768126 -231.541619) (xy 112.798652 -231.499603) (xy 112.835375 -231.46288) (xy 112.877391 -231.432354)
			(xy 112.923665 -231.408776) (xy 112.973058 -231.392728) (xy 113.024353 -231.384603) (xy 113.076287 -231.384603)
			(xy 113.127582 -231.392728) (xy 113.176975 -231.408776) (xy 113.223249 -231.432354) (xy 113.265265 -231.46288)
			(xy 113.301988 -231.499603) (xy 113.332514 -231.541619) (xy 113.356092 -231.587893) (xy 113.37214 -231.637286)
			(xy 113.380265 -231.688581) (xy 113.380774 -231.714548) (xy 113.380265 -231.740515) (xy 113.660175 -231.740515)
			(xy 113.660175 -231.688581) (xy 113.6683 -231.637286) (xy 113.684348 -231.587893) (xy 113.707926 -231.541619)
			(xy 113.738452 -231.499603) (xy 113.775175 -231.46288) (xy 113.817191 -231.432354) (xy 113.863465 -231.408776)
			(xy 113.912858 -231.392728) (xy 113.964153 -231.384603) (xy 114.016087 -231.384603) (xy 114.067382 -231.392728)
			(xy 114.116775 -231.408776) (xy 114.163049 -231.432354) (xy 114.205065 -231.46288) (xy 114.241788 -231.499603)
			(xy 114.272314 -231.541619) (xy 114.295892 -231.587893) (xy 114.31194 -231.637286) (xy 114.320065 -231.688581)
			(xy 114.320574 -231.714548) (xy 114.320065 -231.740515) (xy 114.599467 -231.740515) (xy 114.599467 -231.688581)
			(xy 114.607592 -231.637286) (xy 114.62364 -231.587893) (xy 114.647218 -231.541619) (xy 114.677744 -231.499603)
			(xy 114.714467 -231.46288) (xy 114.756483 -231.432354) (xy 114.802757 -231.408776) (xy 114.85215 -231.392728)
			(xy 114.903445 -231.384603) (xy 114.955379 -231.384603) (xy 115.006674 -231.392728) (xy 115.056067 -231.408776)
			(xy 115.102341 -231.432354) (xy 115.144357 -231.46288) (xy 115.18108 -231.499603) (xy 115.211606 -231.541619)
			(xy 115.235184 -231.587893) (xy 115.251232 -231.637286) (xy 115.259357 -231.688581) (xy 115.259866 -231.714548)
			(xy 115.259357 -231.740515) (xy 115.539267 -231.740515) (xy 115.539267 -231.688581) (xy 115.547392 -231.637286)
			(xy 115.56344 -231.587893) (xy 115.587018 -231.541619) (xy 115.617544 -231.499603) (xy 115.654267 -231.46288)
			(xy 115.696283 -231.432354) (xy 115.742557 -231.408776) (xy 115.79195 -231.392728) (xy 115.843245 -231.384603)
			(xy 115.895179 -231.384603) (xy 115.946474 -231.392728) (xy 115.995867 -231.408776) (xy 116.042141 -231.432354)
			(xy 116.084157 -231.46288) (xy 116.12088 -231.499603) (xy 116.151406 -231.541619) (xy 116.174984 -231.587893)
			(xy 116.191032 -231.637286) (xy 116.199157 -231.688581) (xy 116.199666 -231.714548) (xy 116.199157 -231.740515)
			(xy 116.479067 -231.740515) (xy 116.479067 -231.688581) (xy 116.487192 -231.637286) (xy 116.50324 -231.587893)
			(xy 116.526818 -231.541619) (xy 116.557344 -231.499603) (xy 116.594067 -231.46288) (xy 116.636083 -231.432354)
			(xy 116.682357 -231.408776) (xy 116.73175 -231.392728) (xy 116.783045 -231.384603) (xy 116.834979 -231.384603)
			(xy 116.886274 -231.392728) (xy 116.935667 -231.408776) (xy 116.981941 -231.432354) (xy 117.023957 -231.46288)
			(xy 117.06068 -231.499603) (xy 117.091206 -231.541619) (xy 117.114784 -231.587893) (xy 117.130832 -231.637286)
			(xy 117.138957 -231.688581) (xy 117.139466 -231.714548) (xy 117.138957 -231.740515) (xy 117.418867 -231.740515)
			(xy 117.418867 -231.688581) (xy 117.426992 -231.637286) (xy 117.44304 -231.587893) (xy 117.466618 -231.541619)
			(xy 117.497144 -231.499603) (xy 117.533867 -231.46288) (xy 117.575883 -231.432354) (xy 117.622157 -231.408776)
			(xy 117.67155 -231.392728) (xy 117.722845 -231.384603) (xy 117.774779 -231.384603) (xy 117.826074 -231.392728)
			(xy 117.875467 -231.408776) (xy 117.921741 -231.432354) (xy 117.963757 -231.46288) (xy 118.00048 -231.499603)
			(xy 118.031006 -231.541619) (xy 118.054584 -231.587893) (xy 118.070632 -231.637286) (xy 118.078757 -231.688581)
			(xy 118.079266 -231.714548) (xy 118.078757 -231.740515) (xy 118.358667 -231.740515) (xy 118.358667 -231.688581)
			(xy 118.366792 -231.637286) (xy 118.38284 -231.587893) (xy 118.406418 -231.541619) (xy 118.436944 -231.499603)
			(xy 118.473667 -231.46288) (xy 118.515683 -231.432354) (xy 118.561957 -231.408776) (xy 118.61135 -231.392728)
			(xy 118.662645 -231.384603) (xy 118.714579 -231.384603) (xy 118.765874 -231.392728) (xy 118.815267 -231.408776)
			(xy 118.861541 -231.432354) (xy 118.903557 -231.46288) (xy 118.94028 -231.499603) (xy 118.970806 -231.541619)
			(xy 118.994384 -231.587893) (xy 119.010432 -231.637286) (xy 119.018557 -231.688581) (xy 119.019066 -231.714548)
			(xy 119.018557 -231.740515) (xy 119.298975 -231.740515) (xy 119.298975 -231.688581) (xy 119.3071 -231.637286)
			(xy 119.323148 -231.587893) (xy 119.346726 -231.541619) (xy 119.377252 -231.499603) (xy 119.413975 -231.46288)
			(xy 119.455991 -231.432354) (xy 119.502265 -231.408776) (xy 119.551658 -231.392728) (xy 119.602953 -231.384603)
			(xy 119.654887 -231.384603) (xy 119.706182 -231.392728) (xy 119.755575 -231.408776) (xy 119.801849 -231.432354)
			(xy 119.843865 -231.46288) (xy 119.880588 -231.499603) (xy 119.911114 -231.541619) (xy 119.934692 -231.587893)
			(xy 119.95074 -231.637286) (xy 119.958865 -231.688581) (xy 119.959374 -231.714548) (xy 119.958865 -231.740515)
			(xy 120.238267 -231.740515) (xy 120.238267 -231.688581) (xy 120.246392 -231.637286) (xy 120.26244 -231.587893)
			(xy 120.286018 -231.541619) (xy 120.316544 -231.499603) (xy 120.353267 -231.46288) (xy 120.395283 -231.432354)
			(xy 120.441557 -231.408776) (xy 120.49095 -231.392728) (xy 120.542245 -231.384603) (xy 120.594179 -231.384603)
			(xy 120.645474 -231.392728) (xy 120.694867 -231.408776) (xy 120.741141 -231.432354) (xy 120.783157 -231.46288)
			(xy 120.81988 -231.499603) (xy 120.850406 -231.541619) (xy 120.873984 -231.587893) (xy 120.890032 -231.637286)
			(xy 120.898157 -231.688581) (xy 120.898666 -231.714548) (xy 120.898157 -231.740515) (xy 121.178575 -231.740515)
			(xy 121.178575 -231.688581) (xy 121.1867 -231.637286) (xy 121.202748 -231.587893) (xy 121.226326 -231.541619)
			(xy 121.256852 -231.499603) (xy 121.293575 -231.46288) (xy 121.335591 -231.432354) (xy 121.381865 -231.408776)
			(xy 121.431258 -231.392728) (xy 121.482553 -231.384603) (xy 121.534487 -231.384603) (xy 121.585782 -231.392728)
			(xy 121.635175 -231.408776) (xy 121.681449 -231.432354) (xy 121.723465 -231.46288) (xy 121.760188 -231.499603)
			(xy 121.790714 -231.541619) (xy 121.814292 -231.587893) (xy 121.83034 -231.637286) (xy 121.838465 -231.688581)
			(xy 121.838974 -231.714548) (xy 121.838465 -231.740515) (xy 122.118121 -231.740515) (xy 122.118121 -231.688581)
			(xy 122.126246 -231.637286) (xy 122.142294 -231.587893) (xy 122.165872 -231.541619) (xy 122.196398 -231.499603)
			(xy 122.233121 -231.46288) (xy 122.275137 -231.432354) (xy 122.321411 -231.408776) (xy 122.370804 -231.392728)
			(xy 122.422099 -231.384603) (xy 122.474033 -231.384603) (xy 122.525328 -231.392728) (xy 122.574721 -231.408776)
			(xy 122.620995 -231.432354) (xy 122.663011 -231.46288) (xy 122.699734 -231.499603) (xy 122.73026 -231.541619)
			(xy 122.753838 -231.587893) (xy 122.769886 -231.637286) (xy 122.778011 -231.688581) (xy 122.77852 -231.714548)
			(xy 122.778011 -231.740515) (xy 123.057667 -231.740515) (xy 123.057667 -231.688581) (xy 123.065792 -231.637286)
			(xy 123.08184 -231.587893) (xy 123.105418 -231.541619) (xy 123.135944 -231.499603) (xy 123.172667 -231.46288)
			(xy 123.214683 -231.432354) (xy 123.260957 -231.408776) (xy 123.31035 -231.392728) (xy 123.361645 -231.384603)
			(xy 123.413579 -231.384603) (xy 123.464874 -231.392728) (xy 123.514267 -231.408776) (xy 123.560541 -231.432354)
			(xy 123.602557 -231.46288) (xy 123.63928 -231.499603) (xy 123.669806 -231.541619) (xy 123.693384 -231.587893)
			(xy 123.709432 -231.637286) (xy 123.717557 -231.688581) (xy 123.718066 -231.714548) (xy 123.717557 -231.740515)
			(xy 123.997467 -231.740515) (xy 123.997467 -231.688581) (xy 124.005592 -231.637286) (xy 124.02164 -231.587893)
			(xy 124.045218 -231.541619) (xy 124.075744 -231.499603) (xy 124.112467 -231.46288) (xy 124.154483 -231.432354)
			(xy 124.200757 -231.408776) (xy 124.25015 -231.392728) (xy 124.301445 -231.384603) (xy 124.353379 -231.384603)
			(xy 124.404674 -231.392728) (xy 124.454067 -231.408776) (xy 124.500341 -231.432354) (xy 124.542357 -231.46288)
			(xy 124.57908 -231.499603) (xy 124.609606 -231.541619) (xy 124.633184 -231.587893) (xy 124.649232 -231.637286)
			(xy 124.657357 -231.688581) (xy 124.657866 -231.714548) (xy 124.657357 -231.740515) (xy 124.649232 -231.79181)
			(xy 124.633184 -231.841203) (xy 124.609606 -231.887477) (xy 124.57908 -231.929493) (xy 124.542357 -231.966216)
			(xy 124.500341 -231.996742) (xy 124.454067 -232.02032) (xy 124.404674 -232.036368) (xy 124.353379 -232.044493)
			(xy 124.301445 -232.044493) (xy 124.25015 -232.036368) (xy 124.200757 -232.02032) (xy 124.154483 -231.996742)
			(xy 124.112467 -231.966216) (xy 124.075744 -231.929493) (xy 124.045218 -231.887477) (xy 124.02164 -231.841203)
			(xy 124.005592 -231.79181) (xy 123.997467 -231.740515) (xy 123.717557 -231.740515) (xy 123.709432 -231.79181)
			(xy 123.693384 -231.841203) (xy 123.669806 -231.887477) (xy 123.63928 -231.929493) (xy 123.602557 -231.966216)
			(xy 123.560541 -231.996742) (xy 123.514267 -232.02032) (xy 123.464874 -232.036368) (xy 123.413579 -232.044493)
			(xy 123.361645 -232.044493) (xy 123.31035 -232.036368) (xy 123.260957 -232.02032) (xy 123.214683 -231.996742)
			(xy 123.172667 -231.966216) (xy 123.135944 -231.929493) (xy 123.105418 -231.887477) (xy 123.08184 -231.841203)
			(xy 123.065792 -231.79181) (xy 123.057667 -231.740515) (xy 122.778011 -231.740515) (xy 122.769886 -231.79181)
			(xy 122.753838 -231.841203) (xy 122.73026 -231.887477) (xy 122.699734 -231.929493) (xy 122.663011 -231.966216)
			(xy 122.620995 -231.996742) (xy 122.574721 -232.02032) (xy 122.525328 -232.036368) (xy 122.474033 -232.044493)
			(xy 122.422099 -232.044493) (xy 122.370804 -232.036368) (xy 122.321411 -232.02032) (xy 122.275137 -231.996742)
			(xy 122.233121 -231.966216) (xy 122.196398 -231.929493) (xy 122.165872 -231.887477) (xy 122.142294 -231.841203)
			(xy 122.126246 -231.79181) (xy 122.118121 -231.740515) (xy 121.838465 -231.740515) (xy 121.83034 -231.79181)
			(xy 121.814292 -231.841203) (xy 121.790714 -231.887477) (xy 121.760188 -231.929493) (xy 121.723465 -231.966216)
			(xy 121.681449 -231.996742) (xy 121.635175 -232.02032) (xy 121.585782 -232.036368) (xy 121.534487 -232.044493)
			(xy 121.482553 -232.044493) (xy 121.431258 -232.036368) (xy 121.381865 -232.02032) (xy 121.335591 -231.996742)
			(xy 121.293575 -231.966216) (xy 121.256852 -231.929493) (xy 121.226326 -231.887477) (xy 121.202748 -231.841203)
			(xy 121.1867 -231.79181) (xy 121.178575 -231.740515) (xy 120.898157 -231.740515) (xy 120.890032 -231.79181)
			(xy 120.873984 -231.841203) (xy 120.850406 -231.887477) (xy 120.81988 -231.929493) (xy 120.783157 -231.966216)
			(xy 120.741141 -231.996742) (xy 120.694867 -232.02032) (xy 120.645474 -232.036368) (xy 120.594179 -232.044493)
			(xy 120.542245 -232.044493) (xy 120.49095 -232.036368) (xy 120.441557 -232.02032) (xy 120.395283 -231.996742)
			(xy 120.353267 -231.966216) (xy 120.316544 -231.929493) (xy 120.286018 -231.887477) (xy 120.26244 -231.841203)
			(xy 120.246392 -231.79181) (xy 120.238267 -231.740515) (xy 119.958865 -231.740515) (xy 119.95074 -231.79181)
			(xy 119.934692 -231.841203) (xy 119.911114 -231.887477) (xy 119.880588 -231.929493) (xy 119.843865 -231.966216)
			(xy 119.801849 -231.996742) (xy 119.755575 -232.02032) (xy 119.706182 -232.036368) (xy 119.654887 -232.044493)
			(xy 119.602953 -232.044493) (xy 119.551658 -232.036368) (xy 119.502265 -232.02032) (xy 119.455991 -231.996742)
			(xy 119.413975 -231.966216) (xy 119.377252 -231.929493) (xy 119.346726 -231.887477) (xy 119.323148 -231.841203)
			(xy 119.3071 -231.79181) (xy 119.298975 -231.740515) (xy 119.018557 -231.740515) (xy 119.010432 -231.79181)
			(xy 118.994384 -231.841203) (xy 118.970806 -231.887477) (xy 118.94028 -231.929493) (xy 118.903557 -231.966216)
			(xy 118.861541 -231.996742) (xy 118.815267 -232.02032) (xy 118.765874 -232.036368) (xy 118.714579 -232.044493)
			(xy 118.662645 -232.044493) (xy 118.61135 -232.036368) (xy 118.561957 -232.02032) (xy 118.515683 -231.996742)
			(xy 118.473667 -231.966216) (xy 118.436944 -231.929493) (xy 118.406418 -231.887477) (xy 118.38284 -231.841203)
			(xy 118.366792 -231.79181) (xy 118.358667 -231.740515) (xy 118.078757 -231.740515) (xy 118.070632 -231.79181)
			(xy 118.054584 -231.841203) (xy 118.031006 -231.887477) (xy 118.00048 -231.929493) (xy 117.963757 -231.966216)
			(xy 117.921741 -231.996742) (xy 117.875467 -232.02032) (xy 117.826074 -232.036368) (xy 117.774779 -232.044493)
			(xy 117.722845 -232.044493) (xy 117.67155 -232.036368) (xy 117.622157 -232.02032) (xy 117.575883 -231.996742)
			(xy 117.533867 -231.966216) (xy 117.497144 -231.929493) (xy 117.466618 -231.887477) (xy 117.44304 -231.841203)
			(xy 117.426992 -231.79181) (xy 117.418867 -231.740515) (xy 117.138957 -231.740515) (xy 117.130832 -231.79181)
			(xy 117.114784 -231.841203) (xy 117.091206 -231.887477) (xy 117.06068 -231.929493) (xy 117.023957 -231.966216)
			(xy 116.981941 -231.996742) (xy 116.935667 -232.02032) (xy 116.886274 -232.036368) (xy 116.834979 -232.044493)
			(xy 116.783045 -232.044493) (xy 116.73175 -232.036368) (xy 116.682357 -232.02032) (xy 116.636083 -231.996742)
			(xy 116.594067 -231.966216) (xy 116.557344 -231.929493) (xy 116.526818 -231.887477) (xy 116.50324 -231.841203)
			(xy 116.487192 -231.79181) (xy 116.479067 -231.740515) (xy 116.199157 -231.740515) (xy 116.191032 -231.79181)
			(xy 116.174984 -231.841203) (xy 116.151406 -231.887477) (xy 116.12088 -231.929493) (xy 116.084157 -231.966216)
			(xy 116.042141 -231.996742) (xy 115.995867 -232.02032) (xy 115.946474 -232.036368) (xy 115.895179 -232.044493)
			(xy 115.843245 -232.044493) (xy 115.79195 -232.036368) (xy 115.742557 -232.02032) (xy 115.696283 -231.996742)
			(xy 115.654267 -231.966216) (xy 115.617544 -231.929493) (xy 115.587018 -231.887477) (xy 115.56344 -231.841203)
			(xy 115.547392 -231.79181) (xy 115.539267 -231.740515) (xy 115.259357 -231.740515) (xy 115.251232 -231.79181)
			(xy 115.235184 -231.841203) (xy 115.211606 -231.887477) (xy 115.18108 -231.929493) (xy 115.144357 -231.966216)
			(xy 115.102341 -231.996742) (xy 115.056067 -232.02032) (xy 115.006674 -232.036368) (xy 114.955379 -232.044493)
			(xy 114.903445 -232.044493) (xy 114.85215 -232.036368) (xy 114.802757 -232.02032) (xy 114.756483 -231.996742)
			(xy 114.714467 -231.966216) (xy 114.677744 -231.929493) (xy 114.647218 -231.887477) (xy 114.62364 -231.841203)
			(xy 114.607592 -231.79181) (xy 114.599467 -231.740515) (xy 114.320065 -231.740515) (xy 114.31194 -231.79181)
			(xy 114.295892 -231.841203) (xy 114.272314 -231.887477) (xy 114.241788 -231.929493) (xy 114.205065 -231.966216)
			(xy 114.163049 -231.996742) (xy 114.116775 -232.02032) (xy 114.067382 -232.036368) (xy 114.016087 -232.044493)
			(xy 113.964153 -232.044493) (xy 113.912858 -232.036368) (xy 113.863465 -232.02032) (xy 113.817191 -231.996742)
			(xy 113.775175 -231.966216) (xy 113.738452 -231.929493) (xy 113.707926 -231.887477) (xy 113.684348 -231.841203)
			(xy 113.6683 -231.79181) (xy 113.660175 -231.740515) (xy 113.380265 -231.740515) (xy 113.37214 -231.79181)
			(xy 113.356092 -231.841203) (xy 113.332514 -231.887477) (xy 113.301988 -231.929493) (xy 113.265265 -231.966216)
			(xy 113.223249 -231.996742) (xy 113.176975 -232.02032) (xy 113.127582 -232.036368) (xy 113.076287 -232.044493)
			(xy 113.024353 -232.044493) (xy 112.973058 -232.036368) (xy 112.923665 -232.02032) (xy 112.877391 -231.996742)
			(xy 112.835375 -231.966216) (xy 112.798652 -231.929493) (xy 112.768126 -231.887477) (xy 112.744548 -231.841203)
			(xy 112.7285 -231.79181) (xy 112.720375 -231.740515) (xy 112.440465 -231.740515) (xy 112.43234 -231.79181)
			(xy 112.416292 -231.841203) (xy 112.392714 -231.887477) (xy 112.362188 -231.929493) (xy 112.325465 -231.966216)
			(xy 112.283449 -231.996742) (xy 112.237175 -232.02032) (xy 112.187782 -232.036368) (xy 112.136487 -232.044493)
			(xy 112.084553 -232.044493) (xy 112.033258 -232.036368) (xy 111.983865 -232.02032) (xy 111.937591 -231.996742)
			(xy 111.895575 -231.966216) (xy 111.858852 -231.929493) (xy 111.828326 -231.887477) (xy 111.804748 -231.841203)
			(xy 111.7887 -231.79181) (xy 111.780575 -231.740515) (xy 111.587026 -231.740515) (xy 111.587026 -232.14711)
			(xy 111.587454 -232.157159) (xy 111.595174 -232.175717) (xy 111.609427 -232.189889) (xy 111.628028 -232.197502)
			(xy 111.63808 -232.19791) (xy 111.640366 -232.19791) (xy 111.66634 -232.19839) (xy 111.717649 -232.206512)
			(xy 111.767055 -232.222561) (xy 111.813343 -232.246141) (xy 111.855371 -232.276673) (xy 111.892105 -232.313403)
			(xy 111.922641 -232.355428) (xy 111.946226 -232.401713) (xy 111.96228 -232.451118) (xy 111.970407 -232.502426)
			(xy 111.970407 -232.554331) (xy 112.250221 -232.554331) (xy 112.250221 -232.502397) (xy 112.258346 -232.451102)
			(xy 112.274394 -232.401709) (xy 112.297972 -232.355435) (xy 112.328498 -232.313419) (xy 112.365221 -232.276696)
			(xy 112.407237 -232.24617) (xy 112.453511 -232.222592) (xy 112.502904 -232.206544) (xy 112.554199 -232.198419)
			(xy 112.606133 -232.198419) (xy 112.657428 -232.206544) (xy 112.706821 -232.222592) (xy 112.753095 -232.24617)
			(xy 112.795111 -232.276696) (xy 112.831834 -232.313419) (xy 112.86236 -232.355435) (xy 112.885938 -232.401709)
			(xy 112.901986 -232.451102) (xy 112.910111 -232.502397) (xy 112.91062 -232.528364) (xy 112.910111 -232.554331)
			(xy 113.190021 -232.554331) (xy 113.190021 -232.502397) (xy 113.198146 -232.451102) (xy 113.214194 -232.401709)
			(xy 113.237772 -232.355435) (xy 113.268298 -232.313419) (xy 113.305021 -232.276696) (xy 113.347037 -232.24617)
			(xy 113.393311 -232.222592) (xy 113.442704 -232.206544) (xy 113.493999 -232.198419) (xy 113.545933 -232.198419)
			(xy 113.597228 -232.206544) (xy 113.646621 -232.222592) (xy 113.692895 -232.24617) (xy 113.734911 -232.276696)
			(xy 113.771634 -232.313419) (xy 113.80216 -232.355435) (xy 113.825738 -232.401709) (xy 113.841786 -232.451102)
			(xy 113.849911 -232.502397) (xy 113.85042 -232.528364) (xy 113.849911 -232.554331) (xy 114.129821 -232.554331)
			(xy 114.129821 -232.502397) (xy 114.137946 -232.451102) (xy 114.153994 -232.401709) (xy 114.177572 -232.355435)
			(xy 114.208098 -232.313419) (xy 114.244821 -232.276696) (xy 114.286837 -232.24617) (xy 114.333111 -232.222592)
			(xy 114.382504 -232.206544) (xy 114.433799 -232.198419) (xy 114.485733 -232.198419) (xy 114.537028 -232.206544)
			(xy 114.586421 -232.222592) (xy 114.632695 -232.24617) (xy 114.674711 -232.276696) (xy 114.711434 -232.313419)
			(xy 114.74196 -232.355435) (xy 114.765538 -232.401709) (xy 114.781586 -232.451102) (xy 114.789711 -232.502397)
			(xy 114.79022 -232.528364) (xy 114.789711 -232.554331) (xy 115.069621 -232.554331) (xy 115.069621 -232.502397)
			(xy 115.077746 -232.451102) (xy 115.093794 -232.401709) (xy 115.117372 -232.355435) (xy 115.147898 -232.313419)
			(xy 115.184621 -232.276696) (xy 115.226637 -232.24617) (xy 115.272911 -232.222592) (xy 115.322304 -232.206544)
			(xy 115.373599 -232.198419) (xy 115.425533 -232.198419) (xy 115.476828 -232.206544) (xy 115.526221 -232.222592)
			(xy 115.572495 -232.24617) (xy 115.614511 -232.276696) (xy 115.651234 -232.313419) (xy 115.68176 -232.355435)
			(xy 115.705338 -232.401709) (xy 115.721386 -232.451102) (xy 115.729511 -232.502397) (xy 115.73002 -232.528364)
			(xy 115.729511 -232.554331) (xy 116.009421 -232.554331) (xy 116.009421 -232.502397) (xy 116.017546 -232.451102)
			(xy 116.033594 -232.401709) (xy 116.057172 -232.355435) (xy 116.087698 -232.313419) (xy 116.124421 -232.276696)
			(xy 116.166437 -232.24617) (xy 116.212711 -232.222592) (xy 116.262104 -232.206544) (xy 116.313399 -232.198419)
			(xy 116.365333 -232.198419) (xy 116.416628 -232.206544) (xy 116.466021 -232.222592) (xy 116.512295 -232.24617)
			(xy 116.554311 -232.276696) (xy 116.591034 -232.313419) (xy 116.62156 -232.355435) (xy 116.645138 -232.401709)
			(xy 116.661186 -232.451102) (xy 116.669311 -232.502397) (xy 116.66982 -232.528364) (xy 116.669311 -232.554331)
			(xy 116.949221 -232.554331) (xy 116.949221 -232.502397) (xy 116.957346 -232.451102) (xy 116.973394 -232.401709)
			(xy 116.996972 -232.355435) (xy 117.027498 -232.313419) (xy 117.064221 -232.276696) (xy 117.106237 -232.24617)
			(xy 117.152511 -232.222592) (xy 117.201904 -232.206544) (xy 117.253199 -232.198419) (xy 117.305133 -232.198419)
			(xy 117.356428 -232.206544) (xy 117.405821 -232.222592) (xy 117.452095 -232.24617) (xy 117.494111 -232.276696)
			(xy 117.530834 -232.313419) (xy 117.56136 -232.355435) (xy 117.584938 -232.401709) (xy 117.600986 -232.451102)
			(xy 117.609111 -232.502397) (xy 117.60962 -232.528364) (xy 117.609111 -232.554331) (xy 117.889021 -232.554331)
			(xy 117.889021 -232.502397) (xy 117.897146 -232.451102) (xy 117.913194 -232.401709) (xy 117.936772 -232.355435)
			(xy 117.967298 -232.313419) (xy 118.004021 -232.276696) (xy 118.046037 -232.24617) (xy 118.092311 -232.222592)
			(xy 118.141704 -232.206544) (xy 118.192999 -232.198419) (xy 118.244933 -232.198419) (xy 118.296228 -232.206544)
			(xy 118.345621 -232.222592) (xy 118.391895 -232.24617) (xy 118.433911 -232.276696) (xy 118.470634 -232.313419)
			(xy 118.50116 -232.355435) (xy 118.524738 -232.401709) (xy 118.540786 -232.451102) (xy 118.548911 -232.502397)
			(xy 118.54942 -232.528364) (xy 118.548911 -232.554331) (xy 118.828821 -232.554331) (xy 118.828821 -232.502397)
			(xy 118.836946 -232.451102) (xy 118.852994 -232.401709) (xy 118.876572 -232.355435) (xy 118.907098 -232.313419)
			(xy 118.943821 -232.276696) (xy 118.985837 -232.24617) (xy 119.032111 -232.222592) (xy 119.081504 -232.206544)
			(xy 119.132799 -232.198419) (xy 119.184733 -232.198419) (xy 119.236028 -232.206544) (xy 119.285421 -232.222592)
			(xy 119.331695 -232.24617) (xy 119.373711 -232.276696) (xy 119.410434 -232.313419) (xy 119.44096 -232.355435)
			(xy 119.464538 -232.401709) (xy 119.480586 -232.451102) (xy 119.488711 -232.502397) (xy 119.48922 -232.528364)
			(xy 119.488711 -232.554331) (xy 119.768367 -232.554331) (xy 119.768367 -232.502397) (xy 119.776492 -232.451102)
			(xy 119.79254 -232.401709) (xy 119.816118 -232.355435) (xy 119.846644 -232.313419) (xy 119.883367 -232.276696)
			(xy 119.925383 -232.24617) (xy 119.971657 -232.222592) (xy 120.02105 -232.206544) (xy 120.072345 -232.198419)
			(xy 120.124279 -232.198419) (xy 120.175574 -232.206544) (xy 120.224967 -232.222592) (xy 120.271241 -232.24617)
			(xy 120.313257 -232.276696) (xy 120.34998 -232.313419) (xy 120.380506 -232.355435) (xy 120.404084 -232.401709)
			(xy 120.420132 -232.451102) (xy 120.428257 -232.502397) (xy 120.428766 -232.528364) (xy 120.428257 -232.554331)
			(xy 120.708421 -232.554331) (xy 120.708421 -232.502397) (xy 120.716546 -232.451102) (xy 120.732594 -232.401709)
			(xy 120.756172 -232.355435) (xy 120.786698 -232.313419) (xy 120.823421 -232.276696) (xy 120.865437 -232.24617)
			(xy 120.911711 -232.222592) (xy 120.961104 -232.206544) (xy 121.012399 -232.198419) (xy 121.064333 -232.198419)
			(xy 121.115628 -232.206544) (xy 121.165021 -232.222592) (xy 121.211295 -232.24617) (xy 121.253311 -232.276696)
			(xy 121.290034 -232.313419) (xy 121.32056 -232.355435) (xy 121.344138 -232.401709) (xy 121.360186 -232.451102)
			(xy 121.368311 -232.502397) (xy 121.36882 -232.528364) (xy 121.368311 -232.554331) (xy 121.648221 -232.554331)
			(xy 121.648221 -232.502397) (xy 121.656346 -232.451102) (xy 121.672394 -232.401709) (xy 121.695972 -232.355435)
			(xy 121.726498 -232.313419) (xy 121.763221 -232.276696) (xy 121.805237 -232.24617) (xy 121.851511 -232.222592)
			(xy 121.900904 -232.206544) (xy 121.952199 -232.198419) (xy 122.004133 -232.198419) (xy 122.055428 -232.206544)
			(xy 122.104821 -232.222592) (xy 122.151095 -232.24617) (xy 122.193111 -232.276696) (xy 122.229834 -232.313419)
			(xy 122.26036 -232.355435) (xy 122.283938 -232.401709) (xy 122.299986 -232.451102) (xy 122.308111 -232.502397)
			(xy 122.30862 -232.528364) (xy 122.308111 -232.554331) (xy 122.588021 -232.554331) (xy 122.588021 -232.502397)
			(xy 122.596146 -232.451102) (xy 122.612194 -232.401709) (xy 122.635772 -232.355435) (xy 122.666298 -232.313419)
			(xy 122.703021 -232.276696) (xy 122.745037 -232.24617) (xy 122.791311 -232.222592) (xy 122.840704 -232.206544)
			(xy 122.891999 -232.198419) (xy 122.943933 -232.198419) (xy 122.995228 -232.206544) (xy 123.044621 -232.222592)
			(xy 123.090895 -232.24617) (xy 123.132911 -232.276696) (xy 123.169634 -232.313419) (xy 123.20016 -232.355435)
			(xy 123.223738 -232.401709) (xy 123.239786 -232.451102) (xy 123.247911 -232.502397) (xy 123.24842 -232.528364)
			(xy 123.247911 -232.554331) (xy 123.527821 -232.554331) (xy 123.527821 -232.502397) (xy 123.535946 -232.451102)
			(xy 123.551994 -232.401709) (xy 123.575572 -232.355435) (xy 123.606098 -232.313419) (xy 123.642821 -232.276696)
			(xy 123.684837 -232.24617) (xy 123.731111 -232.222592) (xy 123.780504 -232.206544) (xy 123.831799 -232.198419)
			(xy 123.883733 -232.198419) (xy 123.935028 -232.206544) (xy 123.984421 -232.222592) (xy 124.030695 -232.24617)
			(xy 124.072711 -232.276696) (xy 124.109434 -232.313419) (xy 124.13996 -232.355435) (xy 124.163538 -232.401709)
			(xy 124.179586 -232.451102) (xy 124.187711 -232.502397) (xy 124.18822 -232.528364) (xy 124.187711 -232.554331)
			(xy 124.179586 -232.605626) (xy 124.163538 -232.655019) (xy 124.13996 -232.701293) (xy 124.109434 -232.743309)
			(xy 124.072711 -232.780032) (xy 124.030695 -232.810558) (xy 123.984421 -232.834136) (xy 123.935028 -232.850184)
			(xy 123.883733 -232.858309) (xy 123.831799 -232.858309) (xy 123.780504 -232.850184) (xy 123.731111 -232.834136)
			(xy 123.684837 -232.810558) (xy 123.642821 -232.780032) (xy 123.606098 -232.743309) (xy 123.575572 -232.701293)
			(xy 123.551994 -232.655019) (xy 123.535946 -232.605626) (xy 123.527821 -232.554331) (xy 123.247911 -232.554331)
			(xy 123.239786 -232.605626) (xy 123.223738 -232.655019) (xy 123.20016 -232.701293) (xy 123.169634 -232.743309)
			(xy 123.132911 -232.780032) (xy 123.090895 -232.810558) (xy 123.044621 -232.834136) (xy 122.995228 -232.850184)
			(xy 122.943933 -232.858309) (xy 122.891999 -232.858309) (xy 122.840704 -232.850184) (xy 122.791311 -232.834136)
			(xy 122.745037 -232.810558) (xy 122.703021 -232.780032) (xy 122.666298 -232.743309) (xy 122.635772 -232.701293)
			(xy 122.612194 -232.655019) (xy 122.596146 -232.605626) (xy 122.588021 -232.554331) (xy 122.308111 -232.554331)
			(xy 122.299986 -232.605626) (xy 122.283938 -232.655019) (xy 122.26036 -232.701293) (xy 122.229834 -232.743309)
			(xy 122.193111 -232.780032) (xy 122.151095 -232.810558) (xy 122.104821 -232.834136) (xy 122.055428 -232.850184)
			(xy 122.004133 -232.858309) (xy 121.952199 -232.858309) (xy 121.900904 -232.850184) (xy 121.851511 -232.834136)
			(xy 121.805237 -232.810558) (xy 121.763221 -232.780032) (xy 121.726498 -232.743309) (xy 121.695972 -232.701293)
			(xy 121.672394 -232.655019) (xy 121.656346 -232.605626) (xy 121.648221 -232.554331) (xy 121.368311 -232.554331)
			(xy 121.360186 -232.605626) (xy 121.344138 -232.655019) (xy 121.32056 -232.701293) (xy 121.290034 -232.743309)
			(xy 121.253311 -232.780032) (xy 121.211295 -232.810558) (xy 121.165021 -232.834136) (xy 121.115628 -232.850184)
			(xy 121.064333 -232.858309) (xy 121.012399 -232.858309) (xy 120.961104 -232.850184) (xy 120.911711 -232.834136)
			(xy 120.865437 -232.810558) (xy 120.823421 -232.780032) (xy 120.786698 -232.743309) (xy 120.756172 -232.701293)
			(xy 120.732594 -232.655019) (xy 120.716546 -232.605626) (xy 120.708421 -232.554331) (xy 120.428257 -232.554331)
			(xy 120.420132 -232.605626) (xy 120.404084 -232.655019) (xy 120.380506 -232.701293) (xy 120.34998 -232.743309)
			(xy 120.313257 -232.780032) (xy 120.271241 -232.810558) (xy 120.224967 -232.834136) (xy 120.175574 -232.850184)
			(xy 120.124279 -232.858309) (xy 120.072345 -232.858309) (xy 120.02105 -232.850184) (xy 119.971657 -232.834136)
			(xy 119.925383 -232.810558) (xy 119.883367 -232.780032) (xy 119.846644 -232.743309) (xy 119.816118 -232.701293)
			(xy 119.79254 -232.655019) (xy 119.776492 -232.605626) (xy 119.768367 -232.554331) (xy 119.488711 -232.554331)
			(xy 119.480586 -232.605626) (xy 119.464538 -232.655019) (xy 119.44096 -232.701293) (xy 119.410434 -232.743309)
			(xy 119.373711 -232.780032) (xy 119.331695 -232.810558) (xy 119.285421 -232.834136) (xy 119.236028 -232.850184)
			(xy 119.184733 -232.858309) (xy 119.132799 -232.858309) (xy 119.081504 -232.850184) (xy 119.032111 -232.834136)
			(xy 118.985837 -232.810558) (xy 118.943821 -232.780032) (xy 118.907098 -232.743309) (xy 118.876572 -232.701293)
			(xy 118.852994 -232.655019) (xy 118.836946 -232.605626) (xy 118.828821 -232.554331) (xy 118.548911 -232.554331)
			(xy 118.540786 -232.605626) (xy 118.524738 -232.655019) (xy 118.50116 -232.701293) (xy 118.470634 -232.743309)
			(xy 118.433911 -232.780032) (xy 118.391895 -232.810558) (xy 118.345621 -232.834136) (xy 118.296228 -232.850184)
			(xy 118.244933 -232.858309) (xy 118.192999 -232.858309) (xy 118.141704 -232.850184) (xy 118.092311 -232.834136)
			(xy 118.046037 -232.810558) (xy 118.004021 -232.780032) (xy 117.967298 -232.743309) (xy 117.936772 -232.701293)
			(xy 117.913194 -232.655019) (xy 117.897146 -232.605626) (xy 117.889021 -232.554331) (xy 117.609111 -232.554331)
			(xy 117.600986 -232.605626) (xy 117.584938 -232.655019) (xy 117.56136 -232.701293) (xy 117.530834 -232.743309)
			(xy 117.494111 -232.780032) (xy 117.452095 -232.810558) (xy 117.405821 -232.834136) (xy 117.356428 -232.850184)
			(xy 117.305133 -232.858309) (xy 117.253199 -232.858309) (xy 117.201904 -232.850184) (xy 117.152511 -232.834136)
			(xy 117.106237 -232.810558) (xy 117.064221 -232.780032) (xy 117.027498 -232.743309) (xy 116.996972 -232.701293)
			(xy 116.973394 -232.655019) (xy 116.957346 -232.605626) (xy 116.949221 -232.554331) (xy 116.669311 -232.554331)
			(xy 116.661186 -232.605626) (xy 116.645138 -232.655019) (xy 116.62156 -232.701293) (xy 116.591034 -232.743309)
			(xy 116.554311 -232.780032) (xy 116.512295 -232.810558) (xy 116.466021 -232.834136) (xy 116.416628 -232.850184)
			(xy 116.365333 -232.858309) (xy 116.313399 -232.858309) (xy 116.262104 -232.850184) (xy 116.212711 -232.834136)
			(xy 116.166437 -232.810558) (xy 116.124421 -232.780032) (xy 116.087698 -232.743309) (xy 116.057172 -232.701293)
			(xy 116.033594 -232.655019) (xy 116.017546 -232.605626) (xy 116.009421 -232.554331) (xy 115.729511 -232.554331)
			(xy 115.721386 -232.605626) (xy 115.705338 -232.655019) (xy 115.68176 -232.701293) (xy 115.651234 -232.743309)
			(xy 115.614511 -232.780032) (xy 115.572495 -232.810558) (xy 115.526221 -232.834136) (xy 115.476828 -232.850184)
			(xy 115.425533 -232.858309) (xy 115.373599 -232.858309) (xy 115.322304 -232.850184) (xy 115.272911 -232.834136)
			(xy 115.226637 -232.810558) (xy 115.184621 -232.780032) (xy 115.147898 -232.743309) (xy 115.117372 -232.701293)
			(xy 115.093794 -232.655019) (xy 115.077746 -232.605626) (xy 115.069621 -232.554331) (xy 114.789711 -232.554331)
			(xy 114.781586 -232.605626) (xy 114.765538 -232.655019) (xy 114.74196 -232.701293) (xy 114.711434 -232.743309)
			(xy 114.674711 -232.780032) (xy 114.632695 -232.810558) (xy 114.586421 -232.834136) (xy 114.537028 -232.850184)
			(xy 114.485733 -232.858309) (xy 114.433799 -232.858309) (xy 114.382504 -232.850184) (xy 114.333111 -232.834136)
			(xy 114.286837 -232.810558) (xy 114.244821 -232.780032) (xy 114.208098 -232.743309) (xy 114.177572 -232.701293)
			(xy 114.153994 -232.655019) (xy 114.137946 -232.605626) (xy 114.129821 -232.554331) (xy 113.849911 -232.554331)
			(xy 113.841786 -232.605626) (xy 113.825738 -232.655019) (xy 113.80216 -232.701293) (xy 113.771634 -232.743309)
			(xy 113.734911 -232.780032) (xy 113.692895 -232.810558) (xy 113.646621 -232.834136) (xy 113.597228 -232.850184)
			(xy 113.545933 -232.858309) (xy 113.493999 -232.858309) (xy 113.442704 -232.850184) (xy 113.393311 -232.834136)
			(xy 113.347037 -232.810558) (xy 113.305021 -232.780032) (xy 113.268298 -232.743309) (xy 113.237772 -232.701293)
			(xy 113.214194 -232.655019) (xy 113.198146 -232.605626) (xy 113.190021 -232.554331) (xy 112.910111 -232.554331)
			(xy 112.901986 -232.605626) (xy 112.885938 -232.655019) (xy 112.86236 -232.701293) (xy 112.831834 -232.743309)
			(xy 112.795111 -232.780032) (xy 112.753095 -232.810558) (xy 112.706821 -232.834136) (xy 112.657428 -232.850184)
			(xy 112.606133 -232.858309) (xy 112.554199 -232.858309) (xy 112.502904 -232.850184) (xy 112.453511 -232.834136)
			(xy 112.407237 -232.810558) (xy 112.365221 -232.780032) (xy 112.328498 -232.743309) (xy 112.297972 -232.701293)
			(xy 112.274394 -232.655019) (xy 112.258346 -232.605626) (xy 112.250221 -232.554331) (xy 111.970407 -232.554331)
			(xy 111.970407 -232.554374) (xy 111.96228 -232.605682) (xy 111.946226 -232.655087) (xy 111.922641 -232.701372)
			(xy 111.892105 -232.743397) (xy 111.855371 -232.780127) (xy 111.813343 -232.810659) (xy 111.767055 -232.834239)
			(xy 111.717649 -232.850288) (xy 111.66634 -232.85841) (xy 111.640366 -232.858818) (xy 111.63808 -232.858818)
			(xy 111.628023 -232.859189) (xy 111.609413 -232.86681) (xy 111.595157 -232.880993) (xy 111.58744 -232.899563)
			(xy 111.587026 -232.909618) (xy 111.587026 -233.368147) (xy 111.780067 -233.368147) (xy 111.780067 -233.316213)
			(xy 111.788192 -233.264918) (xy 111.80424 -233.215525) (xy 111.827818 -233.169251) (xy 111.858344 -233.127235)
			(xy 111.895067 -233.090512) (xy 111.937083 -233.059986) (xy 111.983357 -233.036408) (xy 112.03275 -233.02036)
			(xy 112.084045 -233.012235) (xy 112.135979 -233.012235) (xy 112.187274 -233.02036) (xy 112.236667 -233.036408)
			(xy 112.282941 -233.059986) (xy 112.324957 -233.090512) (xy 112.36168 -233.127235) (xy 112.392206 -233.169251)
			(xy 112.415784 -233.215525) (xy 112.431832 -233.264918) (xy 112.439957 -233.316213) (xy 112.440466 -233.34218)
			(xy 112.439957 -233.368147) (xy 112.719867 -233.368147) (xy 112.719867 -233.316213) (xy 112.727992 -233.264918)
			(xy 112.74404 -233.215525) (xy 112.767618 -233.169251) (xy 112.798144 -233.127235) (xy 112.834867 -233.090512)
			(xy 112.876883 -233.059986) (xy 112.923157 -233.036408) (xy 112.97255 -233.02036) (xy 113.023845 -233.012235)
			(xy 113.075779 -233.012235) (xy 113.127074 -233.02036) (xy 113.176467 -233.036408) (xy 113.222741 -233.059986)
			(xy 113.264757 -233.090512) (xy 113.30148 -233.127235) (xy 113.332006 -233.169251) (xy 113.355584 -233.215525)
			(xy 113.371632 -233.264918) (xy 113.379757 -233.316213) (xy 113.380266 -233.34218) (xy 113.379757 -233.368147)
			(xy 113.659921 -233.368147) (xy 113.659921 -233.316213) (xy 113.668046 -233.264918) (xy 113.684094 -233.215525)
			(xy 113.707672 -233.169251) (xy 113.738198 -233.127235) (xy 113.774921 -233.090512) (xy 113.816937 -233.059986)
			(xy 113.863211 -233.036408) (xy 113.912604 -233.02036) (xy 113.963899 -233.012235) (xy 114.015833 -233.012235)
			(xy 114.067128 -233.02036) (xy 114.116521 -233.036408) (xy 114.162795 -233.059986) (xy 114.204811 -233.090512)
			(xy 114.241534 -233.127235) (xy 114.27206 -233.169251) (xy 114.295638 -233.215525) (xy 114.311686 -233.264918)
			(xy 114.319811 -233.316213) (xy 114.32032 -233.34218) (xy 114.319811 -233.368147) (xy 114.599467 -233.368147)
			(xy 114.599467 -233.316213) (xy 114.607592 -233.264918) (xy 114.62364 -233.215525) (xy 114.647218 -233.169251)
			(xy 114.677744 -233.127235) (xy 114.714467 -233.090512) (xy 114.756483 -233.059986) (xy 114.802757 -233.036408)
			(xy 114.85215 -233.02036) (xy 114.903445 -233.012235) (xy 114.955379 -233.012235) (xy 115.006674 -233.02036)
			(xy 115.056067 -233.036408) (xy 115.102341 -233.059986) (xy 115.144357 -233.090512) (xy 115.18108 -233.127235)
			(xy 115.211606 -233.169251) (xy 115.235184 -233.215525) (xy 115.251232 -233.264918) (xy 115.259357 -233.316213)
			(xy 115.259866 -233.34218) (xy 115.259357 -233.368147) (xy 115.539267 -233.368147) (xy 115.539267 -233.316213)
			(xy 115.547392 -233.264918) (xy 115.56344 -233.215525) (xy 115.587018 -233.169251) (xy 115.617544 -233.127235)
			(xy 115.654267 -233.090512) (xy 115.696283 -233.059986) (xy 115.742557 -233.036408) (xy 115.79195 -233.02036)
			(xy 115.843245 -233.012235) (xy 115.895179 -233.012235) (xy 115.946474 -233.02036) (xy 115.995867 -233.036408)
			(xy 116.042141 -233.059986) (xy 116.084157 -233.090512) (xy 116.12088 -233.127235) (xy 116.151406 -233.169251)
			(xy 116.174984 -233.215525) (xy 116.191032 -233.264918) (xy 116.199157 -233.316213) (xy 116.199666 -233.34218)
			(xy 116.199157 -233.368147) (xy 116.479067 -233.368147) (xy 116.479067 -233.316213) (xy 116.487192 -233.264918)
			(xy 116.50324 -233.215525) (xy 116.526818 -233.169251) (xy 116.557344 -233.127235) (xy 116.594067 -233.090512)
			(xy 116.636083 -233.059986) (xy 116.682357 -233.036408) (xy 116.73175 -233.02036) (xy 116.783045 -233.012235)
			(xy 116.834979 -233.012235) (xy 116.886274 -233.02036) (xy 116.935667 -233.036408) (xy 116.981941 -233.059986)
			(xy 117.023957 -233.090512) (xy 117.06068 -233.127235) (xy 117.091206 -233.169251) (xy 117.114784 -233.215525)
			(xy 117.130832 -233.264918) (xy 117.138957 -233.316213) (xy 117.139466 -233.34218) (xy 117.138957 -233.368147)
			(xy 117.418867 -233.368147) (xy 117.418867 -233.316213) (xy 117.426992 -233.264918) (xy 117.44304 -233.215525)
			(xy 117.466618 -233.169251) (xy 117.497144 -233.127235) (xy 117.533867 -233.090512) (xy 117.575883 -233.059986)
			(xy 117.622157 -233.036408) (xy 117.67155 -233.02036) (xy 117.722845 -233.012235) (xy 117.774779 -233.012235)
			(xy 117.826074 -233.02036) (xy 117.875467 -233.036408) (xy 117.921741 -233.059986) (xy 117.963757 -233.090512)
			(xy 118.00048 -233.127235) (xy 118.031006 -233.169251) (xy 118.054584 -233.215525) (xy 118.070632 -233.264918)
			(xy 118.078757 -233.316213) (xy 118.079266 -233.34218) (xy 118.078757 -233.368147) (xy 118.358667 -233.368147)
			(xy 118.358667 -233.316213) (xy 118.366792 -233.264918) (xy 118.38284 -233.215525) (xy 118.406418 -233.169251)
			(xy 118.436944 -233.127235) (xy 118.473667 -233.090512) (xy 118.515683 -233.059986) (xy 118.561957 -233.036408)
			(xy 118.61135 -233.02036) (xy 118.662645 -233.012235) (xy 118.714579 -233.012235) (xy 118.765874 -233.02036)
			(xy 118.815267 -233.036408) (xy 118.861541 -233.059986) (xy 118.903557 -233.090512) (xy 118.94028 -233.127235)
			(xy 118.970806 -233.169251) (xy 118.994384 -233.215525) (xy 119.010432 -233.264918) (xy 119.018557 -233.316213)
			(xy 119.019066 -233.34218) (xy 119.018557 -233.368147) (xy 119.298467 -233.368147) (xy 119.298467 -233.316213)
			(xy 119.306592 -233.264918) (xy 119.32264 -233.215525) (xy 119.346218 -233.169251) (xy 119.376744 -233.127235)
			(xy 119.413467 -233.090512) (xy 119.455483 -233.059986) (xy 119.501757 -233.036408) (xy 119.55115 -233.02036)
			(xy 119.602445 -233.012235) (xy 119.654379 -233.012235) (xy 119.705674 -233.02036) (xy 119.755067 -233.036408)
			(xy 119.801341 -233.059986) (xy 119.843357 -233.090512) (xy 119.88008 -233.127235) (xy 119.910606 -233.169251)
			(xy 119.934184 -233.215525) (xy 119.950232 -233.264918) (xy 119.958357 -233.316213) (xy 119.958866 -233.34218)
			(xy 119.958357 -233.368147) (xy 120.238267 -233.368147) (xy 120.238267 -233.316213) (xy 120.246392 -233.264918)
			(xy 120.26244 -233.215525) (xy 120.286018 -233.169251) (xy 120.316544 -233.127235) (xy 120.353267 -233.090512)
			(xy 120.395283 -233.059986) (xy 120.441557 -233.036408) (xy 120.49095 -233.02036) (xy 120.542245 -233.012235)
			(xy 120.594179 -233.012235) (xy 120.645474 -233.02036) (xy 120.694867 -233.036408) (xy 120.741141 -233.059986)
			(xy 120.783157 -233.090512) (xy 120.81988 -233.127235) (xy 120.850406 -233.169251) (xy 120.873984 -233.215525)
			(xy 120.890032 -233.264918) (xy 120.898157 -233.316213) (xy 120.898666 -233.34218) (xy 120.898157 -233.368147)
			(xy 121.178321 -233.368147) (xy 121.178321 -233.316213) (xy 121.186446 -233.264918) (xy 121.202494 -233.215525)
			(xy 121.226072 -233.169251) (xy 121.256598 -233.127235) (xy 121.293321 -233.090512) (xy 121.335337 -233.059986)
			(xy 121.381611 -233.036408) (xy 121.431004 -233.02036) (xy 121.482299 -233.012235) (xy 121.534233 -233.012235)
			(xy 121.585528 -233.02036) (xy 121.634921 -233.036408) (xy 121.681195 -233.059986) (xy 121.723211 -233.090512)
			(xy 121.759934 -233.127235) (xy 121.79046 -233.169251) (xy 121.814038 -233.215525) (xy 121.830086 -233.264918)
			(xy 121.838211 -233.316213) (xy 121.83872 -233.34218) (xy 121.838211 -233.368147) (xy 122.117867 -233.368147)
			(xy 122.117867 -233.316213) (xy 122.125992 -233.264918) (xy 122.14204 -233.215525) (xy 122.165618 -233.169251)
			(xy 122.196144 -233.127235) (xy 122.232867 -233.090512) (xy 122.274883 -233.059986) (xy 122.321157 -233.036408)
			(xy 122.37055 -233.02036) (xy 122.421845 -233.012235) (xy 122.473779 -233.012235) (xy 122.525074 -233.02036)
			(xy 122.574467 -233.036408) (xy 122.620741 -233.059986) (xy 122.662757 -233.090512) (xy 122.69948 -233.127235)
			(xy 122.730006 -233.169251) (xy 122.753584 -233.215525) (xy 122.769632 -233.264918) (xy 122.777757 -233.316213)
			(xy 122.778266 -233.34218) (xy 122.777757 -233.368147) (xy 123.057667 -233.368147) (xy 123.057667 -233.316213)
			(xy 123.065792 -233.264918) (xy 123.08184 -233.215525) (xy 123.105418 -233.169251) (xy 123.135944 -233.127235)
			(xy 123.172667 -233.090512) (xy 123.214683 -233.059986) (xy 123.260957 -233.036408) (xy 123.31035 -233.02036)
			(xy 123.361645 -233.012235) (xy 123.413579 -233.012235) (xy 123.464874 -233.02036) (xy 123.514267 -233.036408)
			(xy 123.560541 -233.059986) (xy 123.602557 -233.090512) (xy 123.63928 -233.127235) (xy 123.669806 -233.169251)
			(xy 123.693384 -233.215525) (xy 123.709432 -233.264918) (xy 123.717557 -233.316213) (xy 123.718066 -233.34218)
			(xy 123.717557 -233.368147) (xy 123.997467 -233.368147) (xy 123.997467 -233.316213) (xy 124.005592 -233.264918)
			(xy 124.02164 -233.215525) (xy 124.045218 -233.169251) (xy 124.075744 -233.127235) (xy 124.112467 -233.090512)
			(xy 124.154483 -233.059986) (xy 124.200757 -233.036408) (xy 124.25015 -233.02036) (xy 124.301445 -233.012235)
			(xy 124.353379 -233.012235) (xy 124.404674 -233.02036) (xy 124.454067 -233.036408) (xy 124.500341 -233.059986)
			(xy 124.542357 -233.090512) (xy 124.57908 -233.127235) (xy 124.609606 -233.169251) (xy 124.633184 -233.215525)
			(xy 124.649232 -233.264918) (xy 124.657357 -233.316213) (xy 124.657866 -233.34218) (xy 124.657357 -233.368147)
			(xy 124.649232 -233.419442) (xy 124.633184 -233.468835) (xy 124.609606 -233.515109) (xy 124.57908 -233.557125)
			(xy 124.542357 -233.593848) (xy 124.500341 -233.624374) (xy 124.454067 -233.647952) (xy 124.404674 -233.664)
			(xy 124.353379 -233.672125) (xy 124.301445 -233.672125) (xy 124.25015 -233.664) (xy 124.200757 -233.647952)
			(xy 124.154483 -233.624374) (xy 124.112467 -233.593848) (xy 124.075744 -233.557125) (xy 124.045218 -233.515109)
			(xy 124.02164 -233.468835) (xy 124.005592 -233.419442) (xy 123.997467 -233.368147) (xy 123.717557 -233.368147)
			(xy 123.709432 -233.419442) (xy 123.693384 -233.468835) (xy 123.669806 -233.515109) (xy 123.63928 -233.557125)
			(xy 123.602557 -233.593848) (xy 123.560541 -233.624374) (xy 123.514267 -233.647952) (xy 123.464874 -233.664)
			(xy 123.413579 -233.672125) (xy 123.361645 -233.672125) (xy 123.31035 -233.664) (xy 123.260957 -233.647952)
			(xy 123.214683 -233.624374) (xy 123.172667 -233.593848) (xy 123.135944 -233.557125) (xy 123.105418 -233.515109)
			(xy 123.08184 -233.468835) (xy 123.065792 -233.419442) (xy 123.057667 -233.368147) (xy 122.777757 -233.368147)
			(xy 122.769632 -233.419442) (xy 122.753584 -233.468835) (xy 122.730006 -233.515109) (xy 122.69948 -233.557125)
			(xy 122.662757 -233.593848) (xy 122.620741 -233.624374) (xy 122.574467 -233.647952) (xy 122.525074 -233.664)
			(xy 122.473779 -233.672125) (xy 122.421845 -233.672125) (xy 122.37055 -233.664) (xy 122.321157 -233.647952)
			(xy 122.274883 -233.624374) (xy 122.232867 -233.593848) (xy 122.196144 -233.557125) (xy 122.165618 -233.515109)
			(xy 122.14204 -233.468835) (xy 122.125992 -233.419442) (xy 122.117867 -233.368147) (xy 121.838211 -233.368147)
			(xy 121.830086 -233.419442) (xy 121.814038 -233.468835) (xy 121.79046 -233.515109) (xy 121.759934 -233.557125)
			(xy 121.723211 -233.593848) (xy 121.681195 -233.624374) (xy 121.634921 -233.647952) (xy 121.585528 -233.664)
			(xy 121.534233 -233.672125) (xy 121.482299 -233.672125) (xy 121.431004 -233.664) (xy 121.381611 -233.647952)
			(xy 121.335337 -233.624374) (xy 121.293321 -233.593848) (xy 121.256598 -233.557125) (xy 121.226072 -233.515109)
			(xy 121.202494 -233.468835) (xy 121.186446 -233.419442) (xy 121.178321 -233.368147) (xy 120.898157 -233.368147)
			(xy 120.890032 -233.419442) (xy 120.873984 -233.468835) (xy 120.850406 -233.515109) (xy 120.81988 -233.557125)
			(xy 120.783157 -233.593848) (xy 120.741141 -233.624374) (xy 120.694867 -233.647952) (xy 120.645474 -233.664)
			(xy 120.594179 -233.672125) (xy 120.542245 -233.672125) (xy 120.49095 -233.664) (xy 120.441557 -233.647952)
			(xy 120.395283 -233.624374) (xy 120.353267 -233.593848) (xy 120.316544 -233.557125) (xy 120.286018 -233.515109)
			(xy 120.26244 -233.468835) (xy 120.246392 -233.419442) (xy 120.238267 -233.368147) (xy 119.958357 -233.368147)
			(xy 119.950232 -233.419442) (xy 119.934184 -233.468835) (xy 119.910606 -233.515109) (xy 119.88008 -233.557125)
			(xy 119.843357 -233.593848) (xy 119.801341 -233.624374) (xy 119.755067 -233.647952) (xy 119.705674 -233.664)
			(xy 119.654379 -233.672125) (xy 119.602445 -233.672125) (xy 119.55115 -233.664) (xy 119.501757 -233.647952)
			(xy 119.455483 -233.624374) (xy 119.413467 -233.593848) (xy 119.376744 -233.557125) (xy 119.346218 -233.515109)
			(xy 119.32264 -233.468835) (xy 119.306592 -233.419442) (xy 119.298467 -233.368147) (xy 119.018557 -233.368147)
			(xy 119.010432 -233.419442) (xy 118.994384 -233.468835) (xy 118.970806 -233.515109) (xy 118.94028 -233.557125)
			(xy 118.903557 -233.593848) (xy 118.861541 -233.624374) (xy 118.815267 -233.647952) (xy 118.765874 -233.664)
			(xy 118.714579 -233.672125) (xy 118.662645 -233.672125) (xy 118.61135 -233.664) (xy 118.561957 -233.647952)
			(xy 118.515683 -233.624374) (xy 118.473667 -233.593848) (xy 118.436944 -233.557125) (xy 118.406418 -233.515109)
			(xy 118.38284 -233.468835) (xy 118.366792 -233.419442) (xy 118.358667 -233.368147) (xy 118.078757 -233.368147)
			(xy 118.070632 -233.419442) (xy 118.054584 -233.468835) (xy 118.031006 -233.515109) (xy 118.00048 -233.557125)
			(xy 117.963757 -233.593848) (xy 117.921741 -233.624374) (xy 117.875467 -233.647952) (xy 117.826074 -233.664)
			(xy 117.774779 -233.672125) (xy 117.722845 -233.672125) (xy 117.67155 -233.664) (xy 117.622157 -233.647952)
			(xy 117.575883 -233.624374) (xy 117.533867 -233.593848) (xy 117.497144 -233.557125) (xy 117.466618 -233.515109)
			(xy 117.44304 -233.468835) (xy 117.426992 -233.419442) (xy 117.418867 -233.368147) (xy 117.138957 -233.368147)
			(xy 117.130832 -233.419442) (xy 117.114784 -233.468835) (xy 117.091206 -233.515109) (xy 117.06068 -233.557125)
			(xy 117.023957 -233.593848) (xy 116.981941 -233.624374) (xy 116.935667 -233.647952) (xy 116.886274 -233.664)
			(xy 116.834979 -233.672125) (xy 116.783045 -233.672125) (xy 116.73175 -233.664) (xy 116.682357 -233.647952)
			(xy 116.636083 -233.624374) (xy 116.594067 -233.593848) (xy 116.557344 -233.557125) (xy 116.526818 -233.515109)
			(xy 116.50324 -233.468835) (xy 116.487192 -233.419442) (xy 116.479067 -233.368147) (xy 116.199157 -233.368147)
			(xy 116.191032 -233.419442) (xy 116.174984 -233.468835) (xy 116.151406 -233.515109) (xy 116.12088 -233.557125)
			(xy 116.084157 -233.593848) (xy 116.042141 -233.624374) (xy 115.995867 -233.647952) (xy 115.946474 -233.664)
			(xy 115.895179 -233.672125) (xy 115.843245 -233.672125) (xy 115.79195 -233.664) (xy 115.742557 -233.647952)
			(xy 115.696283 -233.624374) (xy 115.654267 -233.593848) (xy 115.617544 -233.557125) (xy 115.587018 -233.515109)
			(xy 115.56344 -233.468835) (xy 115.547392 -233.419442) (xy 115.539267 -233.368147) (xy 115.259357 -233.368147)
			(xy 115.251232 -233.419442) (xy 115.235184 -233.468835) (xy 115.211606 -233.515109) (xy 115.18108 -233.557125)
			(xy 115.144357 -233.593848) (xy 115.102341 -233.624374) (xy 115.056067 -233.647952) (xy 115.006674 -233.664)
			(xy 114.955379 -233.672125) (xy 114.903445 -233.672125) (xy 114.85215 -233.664) (xy 114.802757 -233.647952)
			(xy 114.756483 -233.624374) (xy 114.714467 -233.593848) (xy 114.677744 -233.557125) (xy 114.647218 -233.515109)
			(xy 114.62364 -233.468835) (xy 114.607592 -233.419442) (xy 114.599467 -233.368147) (xy 114.319811 -233.368147)
			(xy 114.311686 -233.419442) (xy 114.295638 -233.468835) (xy 114.27206 -233.515109) (xy 114.241534 -233.557125)
			(xy 114.204811 -233.593848) (xy 114.162795 -233.624374) (xy 114.116521 -233.647952) (xy 114.067128 -233.664)
			(xy 114.015833 -233.672125) (xy 113.963899 -233.672125) (xy 113.912604 -233.664) (xy 113.863211 -233.647952)
			(xy 113.816937 -233.624374) (xy 113.774921 -233.593848) (xy 113.738198 -233.557125) (xy 113.707672 -233.515109)
			(xy 113.684094 -233.468835) (xy 113.668046 -233.419442) (xy 113.659921 -233.368147) (xy 113.379757 -233.368147)
			(xy 113.371632 -233.419442) (xy 113.355584 -233.468835) (xy 113.332006 -233.515109) (xy 113.30148 -233.557125)
			(xy 113.264757 -233.593848) (xy 113.222741 -233.624374) (xy 113.176467 -233.647952) (xy 113.127074 -233.664)
			(xy 113.075779 -233.672125) (xy 113.023845 -233.672125) (xy 112.97255 -233.664) (xy 112.923157 -233.647952)
			(xy 112.876883 -233.624374) (xy 112.834867 -233.593848) (xy 112.798144 -233.557125) (xy 112.767618 -233.515109)
			(xy 112.74404 -233.468835) (xy 112.727992 -233.419442) (xy 112.719867 -233.368147) (xy 112.439957 -233.368147)
			(xy 112.431832 -233.419442) (xy 112.415784 -233.468835) (xy 112.392206 -233.515109) (xy 112.36168 -233.557125)
			(xy 112.324957 -233.593848) (xy 112.282941 -233.624374) (xy 112.236667 -233.647952) (xy 112.187274 -233.664)
			(xy 112.135979 -233.672125) (xy 112.084045 -233.672125) (xy 112.03275 -233.664) (xy 111.983357 -233.647952)
			(xy 111.937083 -233.624374) (xy 111.895067 -233.593848) (xy 111.858344 -233.557125) (xy 111.827818 -233.515109)
			(xy 111.80424 -233.468835) (xy 111.788192 -233.419442) (xy 111.780067 -233.368147) (xy 111.587026 -233.368147)
			(xy 111.587026 -233.774996) (xy 111.587452 -233.785047) (xy 111.595169 -233.80361) (xy 111.609422 -233.817786)
			(xy 111.628026 -233.825402) (xy 111.63808 -233.825796) (xy 111.640366 -233.825796) (xy 111.666333 -233.826276)
			(xy 111.717629 -233.834396) (xy 111.767022 -233.85044) (xy 111.813298 -233.874014) (xy 111.855315 -233.904538)
			(xy 111.89204 -233.941259) (xy 111.922568 -233.983273) (xy 111.946147 -234.029546) (xy 111.962196 -234.078938)
			(xy 111.970321 -234.130233) (xy 111.970321 -234.182167) (xy 111.970313 -234.182217) (xy 112.250221 -234.182217)
			(xy 112.250221 -234.130283) (xy 112.258346 -234.078988) (xy 112.274394 -234.029595) (xy 112.297972 -233.983321)
			(xy 112.328498 -233.941305) (xy 112.365221 -233.904582) (xy 112.407237 -233.874056) (xy 112.453511 -233.850478)
			(xy 112.502904 -233.83443) (xy 112.554199 -233.826305) (xy 112.606133 -233.826305) (xy 112.657428 -233.83443)
			(xy 112.706821 -233.850478) (xy 112.753095 -233.874056) (xy 112.795111 -233.904582) (xy 112.831834 -233.941305)
			(xy 112.86236 -233.983321) (xy 112.885938 -234.029595) (xy 112.901986 -234.078988) (xy 112.910111 -234.130283)
			(xy 112.91062 -234.15625) (xy 112.910111 -234.182217) (xy 113.190021 -234.182217) (xy 113.190021 -234.130283)
			(xy 113.198146 -234.078988) (xy 113.214194 -234.029595) (xy 113.237772 -233.983321) (xy 113.268298 -233.941305)
			(xy 113.305021 -233.904582) (xy 113.347037 -233.874056) (xy 113.393311 -233.850478) (xy 113.442704 -233.83443)
			(xy 113.493999 -233.826305) (xy 113.545933 -233.826305) (xy 113.597228 -233.83443) (xy 113.646621 -233.850478)
			(xy 113.692895 -233.874056) (xy 113.734911 -233.904582) (xy 113.771634 -233.941305) (xy 113.80216 -233.983321)
			(xy 113.825738 -234.029595) (xy 113.841786 -234.078988) (xy 113.849911 -234.130283) (xy 113.85042 -234.15625)
			(xy 113.849911 -234.182217) (xy 114.129821 -234.182217) (xy 114.129821 -234.130283) (xy 114.137946 -234.078988)
			(xy 114.153994 -234.029595) (xy 114.177572 -233.983321) (xy 114.208098 -233.941305) (xy 114.244821 -233.904582)
			(xy 114.286837 -233.874056) (xy 114.333111 -233.850478) (xy 114.382504 -233.83443) (xy 114.433799 -233.826305)
			(xy 114.485733 -233.826305) (xy 114.537028 -233.83443) (xy 114.586421 -233.850478) (xy 114.632695 -233.874056)
			(xy 114.674711 -233.904582) (xy 114.711434 -233.941305) (xy 114.74196 -233.983321) (xy 114.765538 -234.029595)
			(xy 114.781586 -234.078988) (xy 114.789711 -234.130283) (xy 114.79022 -234.15625) (xy 114.789711 -234.182217)
			(xy 115.069621 -234.182217) (xy 115.069621 -234.130283) (xy 115.077746 -234.078988) (xy 115.093794 -234.029595)
			(xy 115.117372 -233.983321) (xy 115.147898 -233.941305) (xy 115.184621 -233.904582) (xy 115.226637 -233.874056)
			(xy 115.272911 -233.850478) (xy 115.322304 -233.83443) (xy 115.373599 -233.826305) (xy 115.425533 -233.826305)
			(xy 115.476828 -233.83443) (xy 115.526221 -233.850478) (xy 115.572495 -233.874056) (xy 115.614511 -233.904582)
			(xy 115.651234 -233.941305) (xy 115.68176 -233.983321) (xy 115.705338 -234.029595) (xy 115.721386 -234.078988)
			(xy 115.729511 -234.130283) (xy 115.73002 -234.15625) (xy 115.729511 -234.182217) (xy 116.009421 -234.182217)
			(xy 116.009421 -234.130283) (xy 116.017546 -234.078988) (xy 116.033594 -234.029595) (xy 116.057172 -233.983321)
			(xy 116.087698 -233.941305) (xy 116.124421 -233.904582) (xy 116.166437 -233.874056) (xy 116.212711 -233.850478)
			(xy 116.262104 -233.83443) (xy 116.313399 -233.826305) (xy 116.365333 -233.826305) (xy 116.416628 -233.83443)
			(xy 116.466021 -233.850478) (xy 116.512295 -233.874056) (xy 116.554311 -233.904582) (xy 116.591034 -233.941305)
			(xy 116.62156 -233.983321) (xy 116.645138 -234.029595) (xy 116.661186 -234.078988) (xy 116.669311 -234.130283)
			(xy 116.66982 -234.15625) (xy 116.669311 -234.182217) (xy 116.949221 -234.182217) (xy 116.949221 -234.130283)
			(xy 116.957346 -234.078988) (xy 116.973394 -234.029595) (xy 116.996972 -233.983321) (xy 117.027498 -233.941305)
			(xy 117.064221 -233.904582) (xy 117.106237 -233.874056) (xy 117.152511 -233.850478) (xy 117.201904 -233.83443)
			(xy 117.253199 -233.826305) (xy 117.305133 -233.826305) (xy 117.356428 -233.83443) (xy 117.405821 -233.850478)
			(xy 117.452095 -233.874056) (xy 117.494111 -233.904582) (xy 117.530834 -233.941305) (xy 117.56136 -233.983321)
			(xy 117.584938 -234.029595) (xy 117.600986 -234.078988) (xy 117.609111 -234.130283) (xy 117.60962 -234.15625)
			(xy 117.609111 -234.182217) (xy 117.889021 -234.182217) (xy 117.889021 -234.130283) (xy 117.897146 -234.078988)
			(xy 117.913194 -234.029595) (xy 117.936772 -233.983321) (xy 117.967298 -233.941305) (xy 118.004021 -233.904582)
			(xy 118.046037 -233.874056) (xy 118.092311 -233.850478) (xy 118.141704 -233.83443) (xy 118.192999 -233.826305)
			(xy 118.244933 -233.826305) (xy 118.296228 -233.83443) (xy 118.345621 -233.850478) (xy 118.391895 -233.874056)
			(xy 118.433911 -233.904582) (xy 118.470634 -233.941305) (xy 118.50116 -233.983321) (xy 118.524738 -234.029595)
			(xy 118.540786 -234.078988) (xy 118.548911 -234.130283) (xy 118.54942 -234.15625) (xy 118.548911 -234.182217)
			(xy 118.828821 -234.182217) (xy 118.828821 -234.130283) (xy 118.836946 -234.078988) (xy 118.852994 -234.029595)
			(xy 118.876572 -233.983321) (xy 118.907098 -233.941305) (xy 118.943821 -233.904582) (xy 118.985837 -233.874056)
			(xy 119.032111 -233.850478) (xy 119.081504 -233.83443) (xy 119.132799 -233.826305) (xy 119.184733 -233.826305)
			(xy 119.236028 -233.83443) (xy 119.285421 -233.850478) (xy 119.331695 -233.874056) (xy 119.373711 -233.904582)
			(xy 119.410434 -233.941305) (xy 119.44096 -233.983321) (xy 119.464538 -234.029595) (xy 119.480586 -234.078988)
			(xy 119.488711 -234.130283) (xy 119.48922 -234.15625) (xy 119.488711 -234.182217) (xy 119.768621 -234.182217)
			(xy 119.768621 -234.130283) (xy 119.776746 -234.078988) (xy 119.792794 -234.029595) (xy 119.816372 -233.983321)
			(xy 119.846898 -233.941305) (xy 119.883621 -233.904582) (xy 119.925637 -233.874056) (xy 119.971911 -233.850478)
			(xy 120.021304 -233.83443) (xy 120.072599 -233.826305) (xy 120.124533 -233.826305) (xy 120.175828 -233.83443)
			(xy 120.225221 -233.850478) (xy 120.271495 -233.874056) (xy 120.313511 -233.904582) (xy 120.350234 -233.941305)
			(xy 120.38076 -233.983321) (xy 120.404338 -234.029595) (xy 120.420386 -234.078988) (xy 120.428511 -234.130283)
			(xy 120.42902 -234.15625) (xy 120.428511 -234.182217) (xy 120.708167 -234.182217) (xy 120.708167 -234.130283)
			(xy 120.716292 -234.078988) (xy 120.73234 -234.029595) (xy 120.755918 -233.983321) (xy 120.786444 -233.941305)
			(xy 120.823167 -233.904582) (xy 120.865183 -233.874056) (xy 120.911457 -233.850478) (xy 120.96085 -233.83443)
			(xy 121.012145 -233.826305) (xy 121.064079 -233.826305) (xy 121.115374 -233.83443) (xy 121.164767 -233.850478)
			(xy 121.211041 -233.874056) (xy 121.253057 -233.904582) (xy 121.28978 -233.941305) (xy 121.320306 -233.983321)
			(xy 121.343884 -234.029595) (xy 121.359932 -234.078988) (xy 121.368057 -234.130283) (xy 121.368566 -234.15625)
			(xy 121.368057 -234.182217) (xy 121.648221 -234.182217) (xy 121.648221 -234.130283) (xy 121.656346 -234.078988)
			(xy 121.672394 -234.029595) (xy 121.695972 -233.983321) (xy 121.726498 -233.941305) (xy 121.763221 -233.904582)
			(xy 121.805237 -233.874056) (xy 121.851511 -233.850478) (xy 121.900904 -233.83443) (xy 121.952199 -233.826305)
			(xy 122.004133 -233.826305) (xy 122.055428 -233.83443) (xy 122.104821 -233.850478) (xy 122.151095 -233.874056)
			(xy 122.193111 -233.904582) (xy 122.229834 -233.941305) (xy 122.26036 -233.983321) (xy 122.283938 -234.029595)
			(xy 122.299986 -234.078988) (xy 122.308111 -234.130283) (xy 122.30862 -234.15625) (xy 122.308111 -234.182217)
			(xy 122.587767 -234.182217) (xy 122.587767 -234.130283) (xy 122.595892 -234.078988) (xy 122.61194 -234.029595)
			(xy 122.635518 -233.983321) (xy 122.666044 -233.941305) (xy 122.702767 -233.904582) (xy 122.744783 -233.874056)
			(xy 122.791057 -233.850478) (xy 122.84045 -233.83443) (xy 122.891745 -233.826305) (xy 122.943679 -233.826305)
			(xy 122.994974 -233.83443) (xy 123.044367 -233.850478) (xy 123.090641 -233.874056) (xy 123.132657 -233.904582)
			(xy 123.16938 -233.941305) (xy 123.199906 -233.983321) (xy 123.223484 -234.029595) (xy 123.239532 -234.078988)
			(xy 123.247657 -234.130283) (xy 123.248166 -234.15625) (xy 123.247657 -234.182217) (xy 123.527821 -234.182217)
			(xy 123.527821 -234.130283) (xy 123.535946 -234.078988) (xy 123.551994 -234.029595) (xy 123.575572 -233.983321)
			(xy 123.606098 -233.941305) (xy 123.642821 -233.904582) (xy 123.684837 -233.874056) (xy 123.731111 -233.850478)
			(xy 123.780504 -233.83443) (xy 123.831799 -233.826305) (xy 123.883733 -233.826305) (xy 123.935028 -233.83443)
			(xy 123.984421 -233.850478) (xy 124.030695 -233.874056) (xy 124.072711 -233.904582) (xy 124.109434 -233.941305)
			(xy 124.13996 -233.983321) (xy 124.163538 -234.029595) (xy 124.179586 -234.078988) (xy 124.187711 -234.130283)
			(xy 124.18822 -234.15625) (xy 124.187711 -234.182217) (xy 124.179586 -234.233512) (xy 124.163538 -234.282905)
			(xy 124.13996 -234.329179) (xy 124.109434 -234.371195) (xy 124.072711 -234.407918) (xy 124.030695 -234.438444)
			(xy 123.984421 -234.462022) (xy 123.935028 -234.47807) (xy 123.883733 -234.486195) (xy 123.831799 -234.486195)
			(xy 123.780504 -234.47807) (xy 123.731111 -234.462022) (xy 123.684837 -234.438444) (xy 123.642821 -234.407918)
			(xy 123.606098 -234.371195) (xy 123.575572 -234.329179) (xy 123.551994 -234.282905) (xy 123.535946 -234.233512)
			(xy 123.527821 -234.182217) (xy 123.247657 -234.182217) (xy 123.239532 -234.233512) (xy 123.223484 -234.282905)
			(xy 123.199906 -234.329179) (xy 123.16938 -234.371195) (xy 123.132657 -234.407918) (xy 123.090641 -234.438444)
			(xy 123.044367 -234.462022) (xy 122.994974 -234.47807) (xy 122.943679 -234.486195) (xy 122.891745 -234.486195)
			(xy 122.84045 -234.47807) (xy 122.791057 -234.462022) (xy 122.744783 -234.438444) (xy 122.702767 -234.407918)
			(xy 122.666044 -234.371195) (xy 122.635518 -234.329179) (xy 122.61194 -234.282905) (xy 122.595892 -234.233512)
			(xy 122.587767 -234.182217) (xy 122.308111 -234.182217) (xy 122.299986 -234.233512) (xy 122.283938 -234.282905)
			(xy 122.26036 -234.329179) (xy 122.229834 -234.371195) (xy 122.193111 -234.407918) (xy 122.151095 -234.438444)
			(xy 122.104821 -234.462022) (xy 122.055428 -234.47807) (xy 122.004133 -234.486195) (xy 121.952199 -234.486195)
			(xy 121.900904 -234.47807) (xy 121.851511 -234.462022) (xy 121.805237 -234.438444) (xy 121.763221 -234.407918)
			(xy 121.726498 -234.371195) (xy 121.695972 -234.329179) (xy 121.672394 -234.282905) (xy 121.656346 -234.233512)
			(xy 121.648221 -234.182217) (xy 121.368057 -234.182217) (xy 121.359932 -234.233512) (xy 121.343884 -234.282905)
			(xy 121.320306 -234.329179) (xy 121.28978 -234.371195) (xy 121.253057 -234.407918) (xy 121.211041 -234.438444)
			(xy 121.164767 -234.462022) (xy 121.115374 -234.47807) (xy 121.064079 -234.486195) (xy 121.012145 -234.486195)
			(xy 120.96085 -234.47807) (xy 120.911457 -234.462022) (xy 120.865183 -234.438444) (xy 120.823167 -234.407918)
			(xy 120.786444 -234.371195) (xy 120.755918 -234.329179) (xy 120.73234 -234.282905) (xy 120.716292 -234.233512)
			(xy 120.708167 -234.182217) (xy 120.428511 -234.182217) (xy 120.420386 -234.233512) (xy 120.404338 -234.282905)
			(xy 120.38076 -234.329179) (xy 120.350234 -234.371195) (xy 120.313511 -234.407918) (xy 120.271495 -234.438444)
			(xy 120.225221 -234.462022) (xy 120.175828 -234.47807) (xy 120.124533 -234.486195) (xy 120.072599 -234.486195)
			(xy 120.021304 -234.47807) (xy 119.971911 -234.462022) (xy 119.925637 -234.438444) (xy 119.883621 -234.407918)
			(xy 119.846898 -234.371195) (xy 119.816372 -234.329179) (xy 119.792794 -234.282905) (xy 119.776746 -234.233512)
			(xy 119.768621 -234.182217) (xy 119.488711 -234.182217) (xy 119.480586 -234.233512) (xy 119.464538 -234.282905)
			(xy 119.44096 -234.329179) (xy 119.410434 -234.371195) (xy 119.373711 -234.407918) (xy 119.331695 -234.438444)
			(xy 119.285421 -234.462022) (xy 119.236028 -234.47807) (xy 119.184733 -234.486195) (xy 119.132799 -234.486195)
			(xy 119.081504 -234.47807) (xy 119.032111 -234.462022) (xy 118.985837 -234.438444) (xy 118.943821 -234.407918)
			(xy 118.907098 -234.371195) (xy 118.876572 -234.329179) (xy 118.852994 -234.282905) (xy 118.836946 -234.233512)
			(xy 118.828821 -234.182217) (xy 118.548911 -234.182217) (xy 118.540786 -234.233512) (xy 118.524738 -234.282905)
			(xy 118.50116 -234.329179) (xy 118.470634 -234.371195) (xy 118.433911 -234.407918) (xy 118.391895 -234.438444)
			(xy 118.345621 -234.462022) (xy 118.296228 -234.47807) (xy 118.244933 -234.486195) (xy 118.192999 -234.486195)
			(xy 118.141704 -234.47807) (xy 118.092311 -234.462022) (xy 118.046037 -234.438444) (xy 118.004021 -234.407918)
			(xy 117.967298 -234.371195) (xy 117.936772 -234.329179) (xy 117.913194 -234.282905) (xy 117.897146 -234.233512)
			(xy 117.889021 -234.182217) (xy 117.609111 -234.182217) (xy 117.600986 -234.233512) (xy 117.584938 -234.282905)
			(xy 117.56136 -234.329179) (xy 117.530834 -234.371195) (xy 117.494111 -234.407918) (xy 117.452095 -234.438444)
			(xy 117.405821 -234.462022) (xy 117.356428 -234.47807) (xy 117.305133 -234.486195) (xy 117.253199 -234.486195)
			(xy 117.201904 -234.47807) (xy 117.152511 -234.462022) (xy 117.106237 -234.438444) (xy 117.064221 -234.407918)
			(xy 117.027498 -234.371195) (xy 116.996972 -234.329179) (xy 116.973394 -234.282905) (xy 116.957346 -234.233512)
			(xy 116.949221 -234.182217) (xy 116.669311 -234.182217) (xy 116.661186 -234.233512) (xy 116.645138 -234.282905)
			(xy 116.62156 -234.329179) (xy 116.591034 -234.371195) (xy 116.554311 -234.407918) (xy 116.512295 -234.438444)
			(xy 116.466021 -234.462022) (xy 116.416628 -234.47807) (xy 116.365333 -234.486195) (xy 116.313399 -234.486195)
			(xy 116.262104 -234.47807) (xy 116.212711 -234.462022) (xy 116.166437 -234.438444) (xy 116.124421 -234.407918)
			(xy 116.087698 -234.371195) (xy 116.057172 -234.329179) (xy 116.033594 -234.282905) (xy 116.017546 -234.233512)
			(xy 116.009421 -234.182217) (xy 115.729511 -234.182217) (xy 115.721386 -234.233512) (xy 115.705338 -234.282905)
			(xy 115.68176 -234.329179) (xy 115.651234 -234.371195) (xy 115.614511 -234.407918) (xy 115.572495 -234.438444)
			(xy 115.526221 -234.462022) (xy 115.476828 -234.47807) (xy 115.425533 -234.486195) (xy 115.373599 -234.486195)
			(xy 115.322304 -234.47807) (xy 115.272911 -234.462022) (xy 115.226637 -234.438444) (xy 115.184621 -234.407918)
			(xy 115.147898 -234.371195) (xy 115.117372 -234.329179) (xy 115.093794 -234.282905) (xy 115.077746 -234.233512)
			(xy 115.069621 -234.182217) (xy 114.789711 -234.182217) (xy 114.781586 -234.233512) (xy 114.765538 -234.282905)
			(xy 114.74196 -234.329179) (xy 114.711434 -234.371195) (xy 114.674711 -234.407918) (xy 114.632695 -234.438444)
			(xy 114.586421 -234.462022) (xy 114.537028 -234.47807) (xy 114.485733 -234.486195) (xy 114.433799 -234.486195)
			(xy 114.382504 -234.47807) (xy 114.333111 -234.462022) (xy 114.286837 -234.438444) (xy 114.244821 -234.407918)
			(xy 114.208098 -234.371195) (xy 114.177572 -234.329179) (xy 114.153994 -234.282905) (xy 114.137946 -234.233512)
			(xy 114.129821 -234.182217) (xy 113.849911 -234.182217) (xy 113.841786 -234.233512) (xy 113.825738 -234.282905)
			(xy 113.80216 -234.329179) (xy 113.771634 -234.371195) (xy 113.734911 -234.407918) (xy 113.692895 -234.438444)
			(xy 113.646621 -234.462022) (xy 113.597228 -234.47807) (xy 113.545933 -234.486195) (xy 113.493999 -234.486195)
			(xy 113.442704 -234.47807) (xy 113.393311 -234.462022) (xy 113.347037 -234.438444) (xy 113.305021 -234.407918)
			(xy 113.268298 -234.371195) (xy 113.237772 -234.329179) (xy 113.214194 -234.282905) (xy 113.198146 -234.233512)
			(xy 113.190021 -234.182217) (xy 112.910111 -234.182217) (xy 112.901986 -234.233512) (xy 112.885938 -234.282905)
			(xy 112.86236 -234.329179) (xy 112.831834 -234.371195) (xy 112.795111 -234.407918) (xy 112.753095 -234.438444)
			(xy 112.706821 -234.462022) (xy 112.657428 -234.47807) (xy 112.606133 -234.486195) (xy 112.554199 -234.486195)
			(xy 112.502904 -234.47807) (xy 112.453511 -234.462022) (xy 112.407237 -234.438444) (xy 112.365221 -234.407918)
			(xy 112.328498 -234.371195) (xy 112.297972 -234.329179) (xy 112.274394 -234.282905) (xy 112.258346 -234.233512)
			(xy 112.250221 -234.182217) (xy 111.970313 -234.182217) (xy 111.962196 -234.233462) (xy 111.946147 -234.282854)
			(xy 111.922568 -234.329127) (xy 111.89204 -234.371141) (xy 111.855315 -234.407862) (xy 111.813298 -234.438386)
			(xy 111.767022 -234.46196) (xy 111.717629 -234.478004) (xy 111.666333 -234.486124) (xy 111.640366 -234.486704)
			(xy 111.614834 -234.486234) (xy 111.564376 -234.478387) (xy 111.515726 -234.462872) (xy 111.470043 -234.440056)
			(xy 111.428413 -234.410483) (xy 111.39183 -234.374857) (xy 111.361162 -234.334027) (xy 111.348774 -234.311698)
			(xy 111.342014 -234.299926) (xy 111.323392 -234.280189) (xy 111.300228 -234.266054) (xy 111.274159 -234.25852)
			(xy 111.247027 -234.25812) (xy 111.220747 -234.264881) (xy 111.197176 -234.278326) (xy 111.18723 -234.287568)
			(xy 110.557818 -234.91698) (xy 110.560104 -234.940602) (xy 110.561374 -234.970066) (xy 110.560914 -234.994709)
			(xy 110.560715 -234.996033) (xy 110.840521 -234.996033) (xy 110.840521 -234.944099) (xy 110.848646 -234.892804)
			(xy 110.864694 -234.843411) (xy 110.888272 -234.797137) (xy 110.918798 -234.755121) (xy 110.955521 -234.718398)
			(xy 110.997537 -234.687872) (xy 111.043811 -234.664294) (xy 111.093204 -234.648246) (xy 111.144499 -234.640121)
			(xy 111.196433 -234.640121) (xy 111.247728 -234.648246) (xy 111.297121 -234.664294) (xy 111.343395 -234.687872)
			(xy 111.385411 -234.718398) (xy 111.422134 -234.755121) (xy 111.45266 -234.797137) (xy 111.476238 -234.843411)
			(xy 111.492286 -234.892804) (xy 111.500411 -234.944099) (xy 111.50092 -234.970066) (xy 111.500411 -234.996033)
			(xy 111.780321 -234.996033) (xy 111.780321 -234.944099) (xy 111.788446 -234.892804) (xy 111.804494 -234.843411)
			(xy 111.828072 -234.797137) (xy 111.858598 -234.755121) (xy 111.895321 -234.718398) (xy 111.937337 -234.687872)
			(xy 111.983611 -234.664294) (xy 112.033004 -234.648246) (xy 112.084299 -234.640121) (xy 112.136233 -234.640121)
			(xy 112.187528 -234.648246) (xy 112.236921 -234.664294) (xy 112.283195 -234.687872) (xy 112.325211 -234.718398)
			(xy 112.361934 -234.755121) (xy 112.39246 -234.797137) (xy 112.416038 -234.843411) (xy 112.432086 -234.892804)
			(xy 112.440211 -234.944099) (xy 112.44072 -234.970066) (xy 112.440211 -234.996033) (xy 112.720121 -234.996033)
			(xy 112.720121 -234.944099) (xy 112.728246 -234.892804) (xy 112.744294 -234.843411) (xy 112.767872 -234.797137)
			(xy 112.798398 -234.755121) (xy 112.835121 -234.718398) (xy 112.877137 -234.687872) (xy 112.923411 -234.664294)
			(xy 112.972804 -234.648246) (xy 113.024099 -234.640121) (xy 113.076033 -234.640121) (xy 113.127328 -234.648246)
			(xy 113.176721 -234.664294) (xy 113.222995 -234.687872) (xy 113.265011 -234.718398) (xy 113.301734 -234.755121)
			(xy 113.33226 -234.797137) (xy 113.355838 -234.843411) (xy 113.371886 -234.892804) (xy 113.380011 -234.944099)
			(xy 113.38052 -234.970066) (xy 113.380011 -234.996033) (xy 113.660175 -234.996033) (xy 113.660175 -234.944099)
			(xy 113.6683 -234.892804) (xy 113.684348 -234.843411) (xy 113.707926 -234.797137) (xy 113.738452 -234.755121)
			(xy 113.775175 -234.718398) (xy 113.817191 -234.687872) (xy 113.863465 -234.664294) (xy 113.912858 -234.648246)
			(xy 113.964153 -234.640121) (xy 114.016087 -234.640121) (xy 114.067382 -234.648246) (xy 114.116775 -234.664294)
			(xy 114.163049 -234.687872) (xy 114.205065 -234.718398) (xy 114.241788 -234.755121) (xy 114.272314 -234.797137)
			(xy 114.295892 -234.843411) (xy 114.31194 -234.892804) (xy 114.320065 -234.944099) (xy 114.320574 -234.970066)
			(xy 114.320065 -234.996033) (xy 121.178067 -234.996033) (xy 121.178067 -234.944099) (xy 121.186192 -234.892804)
			(xy 121.20224 -234.843411) (xy 121.225818 -234.797137) (xy 121.256344 -234.755121) (xy 121.293067 -234.718398)
			(xy 121.335083 -234.687872) (xy 121.381357 -234.664294) (xy 121.43075 -234.648246) (xy 121.482045 -234.640121)
			(xy 121.533979 -234.640121) (xy 121.585274 -234.648246) (xy 121.634667 -234.664294) (xy 121.680941 -234.687872)
			(xy 121.722957 -234.718398) (xy 121.75968 -234.755121) (xy 121.790206 -234.797137) (xy 121.813784 -234.843411)
			(xy 121.829832 -234.892804) (xy 121.837957 -234.944099) (xy 121.838466 -234.970066) (xy 121.837957 -234.996033)
			(xy 122.117867 -234.996033) (xy 122.117867 -234.944099) (xy 122.125992 -234.892804) (xy 122.14204 -234.843411)
			(xy 122.165618 -234.797137) (xy 122.196144 -234.755121) (xy 122.232867 -234.718398) (xy 122.274883 -234.687872)
			(xy 122.321157 -234.664294) (xy 122.37055 -234.648246) (xy 122.421845 -234.640121) (xy 122.473779 -234.640121)
			(xy 122.525074 -234.648246) (xy 122.574467 -234.664294) (xy 122.620741 -234.687872) (xy 122.662757 -234.718398)
			(xy 122.69948 -234.755121) (xy 122.730006 -234.797137) (xy 122.753584 -234.843411) (xy 122.769632 -234.892804)
			(xy 122.777757 -234.944099) (xy 122.778266 -234.970066) (xy 122.777757 -234.996033) (xy 123.057667 -234.996033)
			(xy 123.057667 -234.944099) (xy 123.065792 -234.892804) (xy 123.08184 -234.843411) (xy 123.105418 -234.797137)
			(xy 123.135944 -234.755121) (xy 123.172667 -234.718398) (xy 123.214683 -234.687872) (xy 123.260957 -234.664294)
			(xy 123.31035 -234.648246) (xy 123.361645 -234.640121) (xy 123.413579 -234.640121) (xy 123.464874 -234.648246)
			(xy 123.514267 -234.664294) (xy 123.560541 -234.687872) (xy 123.602557 -234.718398) (xy 123.63928 -234.755121)
			(xy 123.669806 -234.797137) (xy 123.693384 -234.843411) (xy 123.709432 -234.892804) (xy 123.717557 -234.944099)
			(xy 123.718066 -234.970066) (xy 123.717557 -234.996033) (xy 123.997467 -234.996033) (xy 123.997467 -234.944099)
			(xy 124.005592 -234.892804) (xy 124.02164 -234.843411) (xy 124.045218 -234.797137) (xy 124.075744 -234.755121)
			(xy 124.112467 -234.718398) (xy 124.154483 -234.687872) (xy 124.200757 -234.664294) (xy 124.25015 -234.648246)
			(xy 124.301445 -234.640121) (xy 124.353379 -234.640121) (xy 124.404674 -234.648246) (xy 124.454067 -234.664294)
			(xy 124.500341 -234.687872) (xy 124.542357 -234.718398) (xy 124.57908 -234.755121) (xy 124.609606 -234.797137)
			(xy 124.633184 -234.843411) (xy 124.649232 -234.892804) (xy 124.657357 -234.944099) (xy 124.657866 -234.970066)
			(xy 124.657357 -234.996033) (xy 124.649232 -235.047328) (xy 124.633184 -235.096721) (xy 124.609606 -235.142995)
			(xy 124.57908 -235.185011) (xy 124.542357 -235.221734) (xy 124.500341 -235.25226) (xy 124.454067 -235.275838)
			(xy 124.404674 -235.291886) (xy 124.353379 -235.300011) (xy 124.301445 -235.300011) (xy 124.25015 -235.291886)
			(xy 124.200757 -235.275838) (xy 124.154483 -235.25226) (xy 124.112467 -235.221734) (xy 124.075744 -235.185011)
			(xy 124.045218 -235.142995) (xy 124.02164 -235.096721) (xy 124.005592 -235.047328) (xy 123.997467 -234.996033)
			(xy 123.717557 -234.996033) (xy 123.709432 -235.047328) (xy 123.693384 -235.096721) (xy 123.669806 -235.142995)
			(xy 123.63928 -235.185011) (xy 123.602557 -235.221734) (xy 123.560541 -235.25226) (xy 123.514267 -235.275838)
			(xy 123.464874 -235.291886) (xy 123.413579 -235.300011) (xy 123.361645 -235.300011) (xy 123.31035 -235.291886)
			(xy 123.260957 -235.275838) (xy 123.214683 -235.25226) (xy 123.172667 -235.221734) (xy 123.135944 -235.185011)
			(xy 123.105418 -235.142995) (xy 123.08184 -235.096721) (xy 123.065792 -235.047328) (xy 123.057667 -234.996033)
			(xy 122.777757 -234.996033) (xy 122.769632 -235.047328) (xy 122.753584 -235.096721) (xy 122.730006 -235.142995)
			(xy 122.69948 -235.185011) (xy 122.662757 -235.221734) (xy 122.620741 -235.25226) (xy 122.574467 -235.275838)
			(xy 122.525074 -235.291886) (xy 122.473779 -235.300011) (xy 122.421845 -235.300011) (xy 122.37055 -235.291886)
			(xy 122.321157 -235.275838) (xy 122.274883 -235.25226) (xy 122.232867 -235.221734) (xy 122.196144 -235.185011)
			(xy 122.165618 -235.142995) (xy 122.14204 -235.096721) (xy 122.125992 -235.047328) (xy 122.117867 -234.996033)
			(xy 121.837957 -234.996033) (xy 121.829832 -235.047328) (xy 121.813784 -235.096721) (xy 121.790206 -235.142995)
			(xy 121.75968 -235.185011) (xy 121.722957 -235.221734) (xy 121.680941 -235.25226) (xy 121.634667 -235.275838)
			(xy 121.585274 -235.291886) (xy 121.533979 -235.300011) (xy 121.482045 -235.300011) (xy 121.43075 -235.291886)
			(xy 121.381357 -235.275838) (xy 121.335083 -235.25226) (xy 121.293067 -235.221734) (xy 121.256344 -235.185011)
			(xy 121.225818 -235.142995) (xy 121.20224 -235.096721) (xy 121.186192 -235.047328) (xy 121.178067 -234.996033)
			(xy 114.320065 -234.996033) (xy 114.31194 -235.047328) (xy 114.295892 -235.096721) (xy 114.272314 -235.142995)
			(xy 114.241788 -235.185011) (xy 114.205065 -235.221734) (xy 114.163049 -235.25226) (xy 114.116775 -235.275838)
			(xy 114.067382 -235.291886) (xy 114.016087 -235.300011) (xy 113.964153 -235.300011) (xy 113.912858 -235.291886)
			(xy 113.863465 -235.275838) (xy 113.817191 -235.25226) (xy 113.775175 -235.221734) (xy 113.738452 -235.185011)
			(xy 113.707926 -235.142995) (xy 113.684348 -235.096721) (xy 113.6683 -235.047328) (xy 113.660175 -234.996033)
			(xy 113.380011 -234.996033) (xy 113.371886 -235.047328) (xy 113.355838 -235.096721) (xy 113.33226 -235.142995)
			(xy 113.301734 -235.185011) (xy 113.265011 -235.221734) (xy 113.222995 -235.25226) (xy 113.176721 -235.275838)
			(xy 113.127328 -235.291886) (xy 113.076033 -235.300011) (xy 113.024099 -235.300011) (xy 112.972804 -235.291886)
			(xy 112.923411 -235.275838) (xy 112.877137 -235.25226) (xy 112.835121 -235.221734) (xy 112.798398 -235.185011)
			(xy 112.767872 -235.142995) (xy 112.744294 -235.096721) (xy 112.728246 -235.047328) (xy 112.720121 -234.996033)
			(xy 112.440211 -234.996033) (xy 112.432086 -235.047328) (xy 112.416038 -235.096721) (xy 112.39246 -235.142995)
			(xy 112.361934 -235.185011) (xy 112.325211 -235.221734) (xy 112.283195 -235.25226) (xy 112.236921 -235.275838)
			(xy 112.187528 -235.291886) (xy 112.136233 -235.300011) (xy 112.084299 -235.300011) (xy 112.033004 -235.291886)
			(xy 111.983611 -235.275838) (xy 111.937337 -235.25226) (xy 111.895321 -235.221734) (xy 111.858598 -235.185011)
			(xy 111.828072 -235.142995) (xy 111.804494 -235.096721) (xy 111.788446 -235.047328) (xy 111.780321 -234.996033)
			(xy 111.500411 -234.996033) (xy 111.492286 -235.047328) (xy 111.476238 -235.096721) (xy 111.45266 -235.142995)
			(xy 111.422134 -235.185011) (xy 111.385411 -235.221734) (xy 111.343395 -235.25226) (xy 111.297121 -235.275838)
			(xy 111.247728 -235.291886) (xy 111.196433 -235.300011) (xy 111.144499 -235.300011) (xy 111.093204 -235.291886)
			(xy 111.043811 -235.275838) (xy 110.997537 -235.25226) (xy 110.955521 -235.221734) (xy 110.918798 -235.185011)
			(xy 110.888272 -235.142995) (xy 110.864694 -235.096721) (xy 110.848646 -235.047328) (xy 110.840521 -234.996033)
			(xy 110.560715 -234.996033) (xy 110.553587 -235.043448) (xy 110.539104 -235.090559) (xy 110.517787 -235.134998)
			(xy 110.490109 -235.175779) (xy 110.456682 -235.211998) (xy 110.418248 -235.242853) (xy 110.375659 -235.26766)
			(xy 110.329859 -235.285869) (xy 110.281864 -235.297075) (xy 110.257336 -235.299504) (xy 110.242246 -235.30127)
			(xy 110.214024 -235.312479) (xy 110.190348 -235.331493) (xy 110.173312 -235.35663) (xy 110.164423 -235.385666)
			(xy 110.163864 -235.40085) (xy 110.163864 -235.809849) (xy 110.370875 -235.809849) (xy 110.370875 -235.757915)
			(xy 110.379 -235.70662) (xy 110.395048 -235.657227) (xy 110.418626 -235.610953) (xy 110.449152 -235.568937)
			(xy 110.485875 -235.532214) (xy 110.527891 -235.501688) (xy 110.574165 -235.47811) (xy 110.623558 -235.462062)
			(xy 110.674853 -235.453937) (xy 110.726787 -235.453937) (xy 110.778082 -235.462062) (xy 110.827475 -235.47811)
			(xy 110.873749 -235.501688) (xy 110.915765 -235.532214) (xy 110.952488 -235.568937) (xy 110.983014 -235.610953)
			(xy 111.006592 -235.657227) (xy 111.02264 -235.70662) (xy 111.030765 -235.757915) (xy 111.031274 -235.783882)
			(xy 111.030765 -235.809849) (xy 111.310675 -235.809849) (xy 111.310675 -235.757915) (xy 111.3188 -235.70662)
			(xy 111.334848 -235.657227) (xy 111.358426 -235.610953) (xy 111.388952 -235.568937) (xy 111.425675 -235.532214)
			(xy 111.467691 -235.501688) (xy 111.513965 -235.47811) (xy 111.563358 -235.462062) (xy 111.614653 -235.453937)
			(xy 111.666587 -235.453937) (xy 111.717882 -235.462062) (xy 111.767275 -235.47811) (xy 111.813549 -235.501688)
			(xy 111.855565 -235.532214) (xy 111.892288 -235.568937) (xy 111.922814 -235.610953) (xy 111.946392 -235.657227)
			(xy 111.96244 -235.70662) (xy 111.970565 -235.757915) (xy 111.971074 -235.783882) (xy 111.970565 -235.809849)
			(xy 112.250475 -235.809849) (xy 112.250475 -235.757915) (xy 112.2586 -235.70662) (xy 112.274648 -235.657227)
			(xy 112.298226 -235.610953) (xy 112.328752 -235.568937) (xy 112.365475 -235.532214) (xy 112.407491 -235.501688)
			(xy 112.453765 -235.47811) (xy 112.503158 -235.462062) (xy 112.554453 -235.453937) (xy 112.606387 -235.453937)
			(xy 112.657682 -235.462062) (xy 112.707075 -235.47811) (xy 112.753349 -235.501688) (xy 112.795365 -235.532214)
			(xy 112.832088 -235.568937) (xy 112.862614 -235.610953) (xy 112.886192 -235.657227) (xy 112.90224 -235.70662)
			(xy 112.910365 -235.757915) (xy 112.910874 -235.783882) (xy 112.910365 -235.809849) (xy 113.190275 -235.809849)
			(xy 113.190275 -235.757915) (xy 113.1984 -235.70662) (xy 113.214448 -235.657227) (xy 113.238026 -235.610953)
			(xy 113.268552 -235.568937) (xy 113.305275 -235.532214) (xy 113.347291 -235.501688) (xy 113.393565 -235.47811)
			(xy 113.442958 -235.462062) (xy 113.494253 -235.453937) (xy 113.546187 -235.453937) (xy 113.597482 -235.462062)
			(xy 113.646875 -235.47811) (xy 113.693149 -235.501688) (xy 113.735165 -235.532214) (xy 113.771888 -235.568937)
			(xy 113.802414 -235.610953) (xy 113.825992 -235.657227) (xy 113.84204 -235.70662) (xy 113.850165 -235.757915)
			(xy 113.850674 -235.783882) (xy 113.850165 -235.809849) (xy 114.130075 -235.809849) (xy 114.130075 -235.757915)
			(xy 114.1382 -235.70662) (xy 114.154248 -235.657227) (xy 114.177826 -235.610953) (xy 114.208352 -235.568937)
			(xy 114.245075 -235.532214) (xy 114.287091 -235.501688) (xy 114.333365 -235.47811) (xy 114.382758 -235.462062)
			(xy 114.434053 -235.453937) (xy 114.485987 -235.453937) (xy 114.537282 -235.462062) (xy 114.586675 -235.47811)
			(xy 114.632949 -235.501688) (xy 114.674965 -235.532214) (xy 114.711688 -235.568937) (xy 114.742214 -235.610953)
			(xy 114.765792 -235.657227) (xy 114.78184 -235.70662) (xy 114.789965 -235.757915) (xy 114.790474 -235.783882)
			(xy 114.789965 -235.809849) (xy 121.648221 -235.809849) (xy 121.648221 -235.757915) (xy 121.656346 -235.70662)
			(xy 121.672394 -235.657227) (xy 121.695972 -235.610953) (xy 121.726498 -235.568937) (xy 121.763221 -235.532214)
			(xy 121.805237 -235.501688) (xy 121.851511 -235.47811) (xy 121.900904 -235.462062) (xy 121.952199 -235.453937)
			(xy 122.004133 -235.453937) (xy 122.055428 -235.462062) (xy 122.104821 -235.47811) (xy 122.151095 -235.501688)
			(xy 122.193111 -235.532214) (xy 122.229834 -235.568937) (xy 122.26036 -235.610953) (xy 122.283938 -235.657227)
			(xy 122.299986 -235.70662) (xy 122.308111 -235.757915) (xy 122.30862 -235.783882) (xy 122.308111 -235.809849)
			(xy 122.588021 -235.809849) (xy 122.588021 -235.757915) (xy 122.596146 -235.70662) (xy 122.612194 -235.657227)
			(xy 122.635772 -235.610953) (xy 122.666298 -235.568937) (xy 122.703021 -235.532214) (xy 122.745037 -235.501688)
			(xy 122.791311 -235.47811) (xy 122.840704 -235.462062) (xy 122.891999 -235.453937) (xy 122.943933 -235.453937)
			(xy 122.995228 -235.462062) (xy 123.044621 -235.47811) (xy 123.090895 -235.501688) (xy 123.132911 -235.532214)
			(xy 123.169634 -235.568937) (xy 123.20016 -235.610953) (xy 123.223738 -235.657227) (xy 123.239786 -235.70662)
			(xy 123.247911 -235.757915) (xy 123.24842 -235.783882) (xy 123.247911 -235.809849) (xy 123.527821 -235.809849)
			(xy 123.527821 -235.757915) (xy 123.535946 -235.70662) (xy 123.551994 -235.657227) (xy 123.575572 -235.610953)
			(xy 123.606098 -235.568937) (xy 123.642821 -235.532214) (xy 123.684837 -235.501688) (xy 123.731111 -235.47811)
			(xy 123.780504 -235.462062) (xy 123.831799 -235.453937) (xy 123.883733 -235.453937) (xy 123.935028 -235.462062)
			(xy 123.984421 -235.47811) (xy 124.030695 -235.501688) (xy 124.072711 -235.532214) (xy 124.109434 -235.568937)
			(xy 124.13996 -235.610953) (xy 124.163538 -235.657227) (xy 124.179586 -235.70662) (xy 124.187711 -235.757915)
			(xy 124.18822 -235.783882) (xy 124.187711 -235.809849) (xy 124.179586 -235.861144) (xy 124.163538 -235.910537)
			(xy 124.13996 -235.956811) (xy 124.109434 -235.998827) (xy 124.072711 -236.03555) (xy 124.030695 -236.066076)
			(xy 123.984421 -236.089654) (xy 123.935028 -236.105702) (xy 123.883733 -236.113827) (xy 123.831799 -236.113827)
			(xy 123.780504 -236.105702) (xy 123.731111 -236.089654) (xy 123.684837 -236.066076) (xy 123.642821 -236.03555)
			(xy 123.606098 -235.998827) (xy 123.575572 -235.956811) (xy 123.551994 -235.910537) (xy 123.535946 -235.861144)
			(xy 123.527821 -235.809849) (xy 123.247911 -235.809849) (xy 123.239786 -235.861144) (xy 123.223738 -235.910537)
			(xy 123.20016 -235.956811) (xy 123.169634 -235.998827) (xy 123.132911 -236.03555) (xy 123.090895 -236.066076)
			(xy 123.044621 -236.089654) (xy 122.995228 -236.105702) (xy 122.943933 -236.113827) (xy 122.891999 -236.113827)
			(xy 122.840704 -236.105702) (xy 122.791311 -236.089654) (xy 122.745037 -236.066076) (xy 122.703021 -236.03555)
			(xy 122.666298 -235.998827) (xy 122.635772 -235.956811) (xy 122.612194 -235.910537) (xy 122.596146 -235.861144)
			(xy 122.588021 -235.809849) (xy 122.308111 -235.809849) (xy 122.299986 -235.861144) (xy 122.283938 -235.910537)
			(xy 122.26036 -235.956811) (xy 122.229834 -235.998827) (xy 122.193111 -236.03555) (xy 122.151095 -236.066076)
			(xy 122.104821 -236.089654) (xy 122.055428 -236.105702) (xy 122.004133 -236.113827) (xy 121.952199 -236.113827)
			(xy 121.900904 -236.105702) (xy 121.851511 -236.089654) (xy 121.805237 -236.066076) (xy 121.763221 -236.03555)
			(xy 121.726498 -235.998827) (xy 121.695972 -235.956811) (xy 121.672394 -235.910537) (xy 121.656346 -235.861144)
			(xy 121.648221 -235.809849) (xy 114.789965 -235.809849) (xy 114.78184 -235.861144) (xy 114.765792 -235.910537)
			(xy 114.742214 -235.956811) (xy 114.711688 -235.998827) (xy 114.674965 -236.03555) (xy 114.632949 -236.066076)
			(xy 114.586675 -236.089654) (xy 114.537282 -236.105702) (xy 114.485987 -236.113827) (xy 114.434053 -236.113827)
			(xy 114.382758 -236.105702) (xy 114.333365 -236.089654) (xy 114.287091 -236.066076) (xy 114.245075 -236.03555)
			(xy 114.208352 -235.998827) (xy 114.177826 -235.956811) (xy 114.154248 -235.910537) (xy 114.1382 -235.861144)
			(xy 114.130075 -235.809849) (xy 113.850165 -235.809849) (xy 113.84204 -235.861144) (xy 113.825992 -235.910537)
			(xy 113.802414 -235.956811) (xy 113.771888 -235.998827) (xy 113.735165 -236.03555) (xy 113.693149 -236.066076)
			(xy 113.646875 -236.089654) (xy 113.597482 -236.105702) (xy 113.546187 -236.113827) (xy 113.494253 -236.113827)
			(xy 113.442958 -236.105702) (xy 113.393565 -236.089654) (xy 113.347291 -236.066076) (xy 113.305275 -236.03555)
			(xy 113.268552 -235.998827) (xy 113.238026 -235.956811) (xy 113.214448 -235.910537) (xy 113.1984 -235.861144)
			(xy 113.190275 -235.809849) (xy 112.910365 -235.809849) (xy 112.90224 -235.861144) (xy 112.886192 -235.910537)
			(xy 112.862614 -235.956811) (xy 112.832088 -235.998827) (xy 112.795365 -236.03555) (xy 112.753349 -236.066076)
			(xy 112.707075 -236.089654) (xy 112.657682 -236.105702) (xy 112.606387 -236.113827) (xy 112.554453 -236.113827)
			(xy 112.503158 -236.105702) (xy 112.453765 -236.089654) (xy 112.407491 -236.066076) (xy 112.365475 -236.03555)
			(xy 112.328752 -235.998827) (xy 112.298226 -235.956811) (xy 112.274648 -235.910537) (xy 112.2586 -235.861144)
			(xy 112.250475 -235.809849) (xy 111.970565 -235.809849) (xy 111.96244 -235.861144) (xy 111.946392 -235.910537)
			(xy 111.922814 -235.956811) (xy 111.892288 -235.998827) (xy 111.855565 -236.03555) (xy 111.813549 -236.066076)
			(xy 111.767275 -236.089654) (xy 111.717882 -236.105702) (xy 111.666587 -236.113827) (xy 111.614653 -236.113827)
			(xy 111.563358 -236.105702) (xy 111.513965 -236.089654) (xy 111.467691 -236.066076) (xy 111.425675 -236.03555)
			(xy 111.388952 -235.998827) (xy 111.358426 -235.956811) (xy 111.334848 -235.910537) (xy 111.3188 -235.861144)
			(xy 111.310675 -235.809849) (xy 111.030765 -235.809849) (xy 111.02264 -235.861144) (xy 111.006592 -235.910537)
			(xy 110.983014 -235.956811) (xy 110.952488 -235.998827) (xy 110.915765 -236.03555) (xy 110.873749 -236.066076)
			(xy 110.827475 -236.089654) (xy 110.778082 -236.105702) (xy 110.726787 -236.113827) (xy 110.674853 -236.113827)
			(xy 110.623558 -236.105702) (xy 110.574165 -236.089654) (xy 110.527891 -236.066076) (xy 110.485875 -236.03555)
			(xy 110.449152 -235.998827) (xy 110.418626 -235.956811) (xy 110.395048 -235.910537) (xy 110.379 -235.861144)
			(xy 110.370875 -235.809849) (xy 110.163864 -235.809849) (xy 110.163864 -236.050328) (xy 110.402116 -236.28858)
			(xy 111.053372 -236.28858)
		)
		(stroke
			(width 0)
			(type solid)
		)
		(fill yes)
		(layer "In6.Cu")
		(net "PVCCINFAON_CPU1")
	)
	(gr_poly
		(pts
			(xy 330.047854 -372.326154) (xy 330.06586 -372.308825) (xy 330.106274 -372.279434) (xy 330.150789 -372.256727)
			(xy 330.198307 -372.241263) (xy 330.247659 -372.233422) (xy 330.272644 -372.232936) (xy 342.850978 -372.232936)
			(xy 346.210636 -368.873278) (xy 346.228627 -368.855933) (xy 346.269046 -368.826549) (xy 346.313564 -368.80385)
			(xy 346.361086 -368.788395) (xy 346.41044 -368.780565) (xy 346.435426 -368.78006) (xy 347.05036 -368.78006)
			(xy 347.073994 -368.764983) (xy 347.124746 -368.741179) (xy 347.178439 -368.725066) (xy 347.233912 -368.716992)
			(xy 347.261942 -368.71656) (xy 347.27007 -368.71656) (xy 347.296908 -368.717636) (xy 347.349902 -368.726391)
			(xy 347.401142 -368.742495) (xy 347.449618 -368.765627) (xy 347.494368 -368.795331) (xy 347.53451 -368.831019)
			(xy 347.569247 -368.871985) (xy 347.597894 -368.91742) (xy 347.619885 -368.966424) (xy 347.634783 -369.018028)
			(xy 347.642294 -369.071212) (xy 347.642688 -369.098068) (xy 347.642227 -369.125322) (xy 347.634473 -369.179275)
			(xy 347.61912 -369.231576) (xy 347.596479 -369.281159) (xy 347.567012 -369.327014) (xy 347.531318 -369.368209)
			(xy 347.490124 -369.403904) (xy 347.444269 -369.433373) (xy 347.394687 -369.456016) (xy 347.342387 -369.471371)
			(xy 347.288434 -369.479126) (xy 347.26118 -369.479576) (xy 347.240115 -369.479312) (xy 347.198237 -369.474732)
			(xy 347.177614 -369.470432) (xy 347.16417 -369.467886) (xy 347.136852 -369.469236) (xy 347.110875 -369.477799)
			(xy 347.088108 -369.492957) (xy 347.070188 -369.513621) (xy 347.058405 -369.538304) (xy 347.053606 -369.565231)
			(xy 347.054424 -369.57889) (xy 347.055948 -369.613688) (xy 347.055451 -369.641751) (xy 347.047226 -369.69727)
			(xy 347.030952 -369.750985) (xy 347.006981 -369.801734) (xy 346.975831 -369.848422) (xy 346.938174 -369.890039)
			(xy 346.894823 -369.925687) (xy 346.871036 -369.940586) (xy 346.865702 -369.943888) (xy 346.700589 -370.108988)
			(xy 347.338902 -370.108988) (xy 347.342973 -370.053366) (xy 347.355099 -369.998929) (xy 347.375022 -369.946838)
			(xy 347.402318 -369.898203) (xy 347.436404 -369.85406) (xy 347.476553 -369.815351) (xy 347.521911 -369.7829)
			(xy 347.571511 -369.757399) (xy 347.624295 -369.739392) (xy 347.679138 -369.729262) (xy 347.734872 -369.727225)
			(xy 347.790309 -369.733325) (xy 347.844266 -369.747431) (xy 347.895595 -369.769243) (xy 347.943201 -369.798297)
			(xy 347.986069 -369.833972) (xy 348.023286 -369.875509) (xy 348.054059 -369.922022) (xy 348.077731 -369.972519)
			(xy 348.093799 -370.025926) (xy 348.101919 -370.081102) (xy 348.102428 -370.108988) (xy 348.101919 -370.136874)
			(xy 348.093799 -370.19205) (xy 348.077731 -370.245457) (xy 348.054059 -370.295954) (xy 348.023286 -370.342467)
			(xy 347.986069 -370.384004) (xy 347.943201 -370.419679) (xy 347.895595 -370.448733) (xy 347.844266 -370.470545)
			(xy 347.790309 -370.484651) (xy 347.734872 -370.490751) (xy 347.679138 -370.488714) (xy 347.624295 -370.478584)
			(xy 347.571511 -370.460577) (xy 347.521911 -370.435076) (xy 347.476553 -370.402625) (xy 347.436404 -370.363916)
			(xy 347.402318 -370.319773) (xy 347.375022 -370.271138) (xy 347.355099 -370.219047) (xy 347.342973 -370.16461)
			(xy 347.338902 -370.108988) (xy 346.700589 -370.108988) (xy 343.565988 -373.243348) (xy 343.552018 -373.25681)
			(xy 343.533222 -373.272812) (xy 343.506298 -373.294148) (xy 343.533222 -373.385588) (xy 345.926918 -373.385588)
			(xy 346.44838 -372.86438) (xy 347.868494 -371.444012) (xy 347.877344 -371.433547) (xy 347.889631 -371.40906)
			(xy 347.894953 -371.382185) (xy 347.892925 -371.354864) (xy 347.883695 -371.329069) (xy 347.867929 -371.306664)
			(xy 347.846765 -371.289267) (xy 347.834458 -371.28323) (xy 347.809615 -371.271587) (xy 347.763269 -371.242228)
			(xy 347.721607 -371.206531) (xy 347.68549 -371.165233) (xy 347.655662 -371.119187) (xy 347.632739 -371.069342)
			(xy 347.617195 -371.016727) (xy 347.609349 -370.962428) (xy 347.608906 -370.934996) (xy 347.60937 -370.907744)
			(xy 347.617127 -370.853794) (xy 347.632484 -370.801497) (xy 347.655127 -370.751919) (xy 347.684595 -370.706067)
			(xy 347.720289 -370.664876) (xy 347.761481 -370.629184) (xy 347.807334 -370.599718) (xy 347.856914 -370.577077)
			(xy 347.909212 -370.561723) (xy 347.963162 -370.553968) (xy 347.990414 -370.553488) (xy 348.014358 -370.553861)
			(xy 348.06187 -370.559843) (xy 348.085156 -370.565426) (xy 348.088204 -370.566188) (xy 348.101152 -370.569156)
			(xy 348.127705 -370.56907) (xy 348.153337 -370.562139) (xy 348.176315 -370.548831) (xy 348.195083 -370.530047)
			(xy 348.208372 -370.507058) (xy 348.215281 -370.48142) (xy 348.215712 -370.468144) (xy 348.215712 -367.444782)
			(xy 345.090496 -364.319312) (xy 345.070369 -364.298463) (xy 345.036263 -364.251614) (xy 345.009908 -364.200005)
			(xy 344.991952 -364.144909) (xy 344.982837 -364.087682) (xy 344.982292 -364.058708) (xy 344.982292 -361.729528)
			(xy 344.982853 -361.700555) (xy 344.991964 -361.64333) (xy 345.009919 -361.588236) (xy 345.036275 -361.53663)
			(xy 345.070383 -361.489786) (xy 345.090496 -361.468924) (xy 346.117672 -360.441494) (xy 346.117672 -355.056948)
			(xy 346.118231 -355.027975) (xy 346.127339 -354.970747) (xy 346.145291 -354.91565) (xy 346.171645 -354.864042)
			(xy 346.20575 -354.817194) (xy 346.225876 -354.796344) (xy 347.199712 -353.822508) (xy 347.220562 -353.802382)
			(xy 347.267411 -353.768278) (xy 347.31902 -353.741925) (xy 347.374116 -353.723972) (xy 347.431343 -353.714861)
			(xy 347.460316 -353.714304) (xy 349.673926 -353.714304) (xy 349.680022 -353.71278) (xy 349.702583 -353.707549)
			(xy 349.748558 -353.701948) (xy 349.771716 -353.701604) (xy 349.798966 -353.702091) (xy 349.85291 -353.709849)
			(xy 349.905201 -353.725205) (xy 349.954775 -353.747847) (xy 350.000621 -353.777313) (xy 350.041808 -353.813003)
			(xy 350.077497 -353.854191) (xy 350.106961 -353.90004) (xy 350.1296 -353.949614) (xy 350.144954 -354.001906)
			(xy 350.15271 -354.05585) (xy 350.15271 -354.11035) (xy 350.144954 -354.164294) (xy 350.1296 -354.216586)
			(xy 350.106961 -354.26616) (xy 350.077497 -354.312009) (xy 350.041808 -354.353197) (xy 350.000621 -354.388887)
			(xy 349.954775 -354.418353) (xy 349.905201 -354.440995) (xy 349.892217 -354.444808) (xy 352.808284 -354.444808)
			(xy 352.812355 -354.389186) (xy 352.824481 -354.334749) (xy 352.844404 -354.282658) (xy 352.8717 -354.234023)
			(xy 352.905786 -354.18988) (xy 352.945935 -354.151171) (xy 352.991293 -354.11872) (xy 353.040893 -354.093219)
			(xy 353.093677 -354.075212) (xy 353.14852 -354.065082) (xy 353.204254 -354.063045) (xy 353.259691 -354.069145)
			(xy 353.313648 -354.083251) (xy 353.364977 -354.105063) (xy 353.412583 -354.134117) (xy 353.455451 -354.169792)
			(xy 353.492668 -354.211329) (xy 353.523441 -354.257842) (xy 353.547113 -354.308339) (xy 353.563181 -354.361746)
			(xy 353.571301 -354.416922) (xy 353.57181 -354.444808) (xy 353.571301 -354.472694) (xy 353.563181 -354.52787)
			(xy 353.547113 -354.581277) (xy 353.523441 -354.631774) (xy 353.492668 -354.678287) (xy 353.455451 -354.719824)
			(xy 353.412583 -354.755499) (xy 353.364977 -354.784553) (xy 353.313648 -354.806365) (xy 353.259691 -354.820471)
			(xy 353.204254 -354.826571) (xy 353.14852 -354.824534) (xy 353.093677 -354.814404) (xy 353.040893 -354.796397)
			(xy 352.991293 -354.770896) (xy 352.945935 -354.738445) (xy 352.905786 -354.699736) (xy 352.8717 -354.655593)
			(xy 352.844404 -354.606958) (xy 352.824481 -354.554867) (xy 352.812355 -354.50043) (xy 352.808284 -354.444808)
			(xy 349.892217 -354.444808) (xy 349.85291 -354.456351) (xy 349.798966 -354.464109) (xy 349.771716 -354.46462)
			(xy 349.748558 -354.464281) (xy 349.702583 -354.458679) (xy 349.680022 -354.453444) (xy 349.673926 -354.45192)
			(xy 347.61297 -354.45192) (xy 347.259148 -354.805742) (xy 347.249218 -354.816374) (xy 347.235337 -354.841928)
			(xy 347.229222 -354.870358) (xy 347.231367 -354.899359) (xy 347.2416 -354.926579) (xy 347.259091 -354.949812)
			(xy 347.282421 -354.967172) (xy 347.309698 -354.977253) (xy 347.324172 -354.978716) (xy 347.352751 -354.981203)
			(xy 347.408745 -354.993665) (xy 347.462246 -355.014361) (xy 347.512049 -355.042827) (xy 347.557035 -355.078421)
			(xy 347.59619 -355.120344) (xy 347.628635 -355.167651) (xy 347.65364 -355.219279) (xy 347.67064 -355.274066)
			(xy 347.679256 -355.33078) (xy 347.679772 -355.359462) (xy 347.679311 -355.386716) (xy 347.671558 -355.440669)
			(xy 347.656205 -355.492969) (xy 347.633565 -355.542552) (xy 347.604097 -355.588407) (xy 347.568403 -355.629601)
			(xy 347.527209 -355.665296) (xy 347.481354 -355.694764) (xy 347.431771 -355.717405) (xy 347.379471 -355.732758)
			(xy 347.325518 -355.740511) (xy 347.298264 -355.74097) (xy 347.268102 -355.740403) (xy 347.20853 -355.730917)
			(xy 347.151193 -355.71217) (xy 347.097523 -355.684631) (xy 347.048857 -355.648987) (xy 347.027246 -355.62794)
			(xy 347.016178 -355.618023) (xy 346.989739 -355.604484) (xy 346.960522 -355.599125) (xy 346.930999 -355.602399)
			(xy 346.903667 -355.61403) (xy 346.880836 -355.633033) (xy 346.864439 -355.657802) (xy 346.855862 -355.686241)
			(xy 346.855288 -355.701092) (xy 346.855288 -356.040436) (xy 351.932746 -356.040436) (xy 351.936817 -355.984814)
			(xy 351.948943 -355.930377) (xy 351.968866 -355.878286) (xy 351.996162 -355.829651) (xy 352.030248 -355.785508)
			(xy 352.070397 -355.746799) (xy 352.115755 -355.714348) (xy 352.165355 -355.688847) (xy 352.218139 -355.67084)
			(xy 352.272982 -355.66071) (xy 352.328716 -355.658673) (xy 352.384153 -355.664773) (xy 352.43811 -355.678879)
			(xy 352.489439 -355.700691) (xy 352.537045 -355.729745) (xy 352.579913 -355.76542) (xy 352.61713 -355.806957)
			(xy 352.647903 -355.85347) (xy 352.671575 -355.903967) (xy 352.687643 -355.957374) (xy 352.695763 -356.01255)
			(xy 352.696272 -356.040436) (xy 352.695763 -356.068322) (xy 352.687643 -356.123498) (xy 352.671575 -356.176905)
			(xy 352.647903 -356.227402) (xy 352.61713 -356.273915) (xy 352.579913 -356.315452) (xy 352.537045 -356.351127)
			(xy 352.489439 -356.380181) (xy 352.43811 -356.401993) (xy 352.384153 -356.416099) (xy 352.328716 -356.422199)
			(xy 352.272982 -356.420162) (xy 352.218139 -356.410032) (xy 352.165355 -356.392025) (xy 352.115755 -356.366524)
			(xy 352.070397 -356.334073) (xy 352.030248 -356.295364) (xy 351.996162 -356.251221) (xy 351.968866 -356.202586)
			(xy 351.948943 -356.150495) (xy 351.936817 -356.096058) (xy 351.932746 -356.040436) (xy 346.855288 -356.040436)
			(xy 346.855288 -356.136702) (xy 346.855789 -356.151573) (xy 346.864334 -356.18006) (xy 346.880726 -356.204875)
			(xy 346.903576 -356.223913) (xy 346.930943 -356.235557) (xy 346.960504 -356.238818) (xy 346.989751 -356.233421)
			(xy 347.016202 -356.219824) (xy 347.027246 -356.209854) (xy 347.04888 -356.188836) (xy 347.097549 -356.153209)
			(xy 347.151215 -356.125681) (xy 347.208543 -356.106937) (xy 347.268107 -356.097444) (xy 347.298264 -356.096824)
			(xy 347.325516 -356.097285) (xy 347.379467 -356.105037) (xy 347.431764 -356.120389) (xy 347.481345 -356.143027)
			(xy 347.527199 -356.172492) (xy 347.568392 -356.208182) (xy 347.604087 -356.249373) (xy 347.633556 -356.295224)
			(xy 347.656199 -356.344802) (xy 347.671555 -356.397098) (xy 347.679313 -356.451048) (xy 347.679313 -356.505552)
			(xy 347.671555 -356.559502) (xy 347.656199 -356.611798) (xy 347.633556 -356.661376) (xy 347.604087 -356.707227)
			(xy 347.568392 -356.748418) (xy 347.527199 -356.784108) (xy 347.481345 -356.813573) (xy 347.431764 -356.836211)
			(xy 347.379467 -356.851563) (xy 347.325516 -356.859315) (xy 347.298264 -356.85984) (xy 347.268103 -356.859273)
			(xy 347.208531 -356.849786) (xy 347.151195 -356.831038) (xy 347.097526 -356.803498) (xy 347.048862 -356.767852)
			(xy 347.027246 -356.74681) (xy 347.016177 -356.736895) (xy 346.989735 -356.72336) (xy 346.960518 -356.718003)
			(xy 346.930995 -356.721278) (xy 346.903662 -356.732907) (xy 346.88083 -356.751908) (xy 346.864428 -356.776674)
			(xy 346.855845 -356.805111) (xy 346.855288 -356.819962) (xy 346.855288 -357.152702) (xy 346.855789 -357.167573)
			(xy 346.864334 -357.19606) (xy 346.880726 -357.220875) (xy 346.903576 -357.239913) (xy 346.930943 -357.251557)
			(xy 346.960504 -357.254818) (xy 346.989751 -357.249421) (xy 347.016202 -357.235824) (xy 347.027246 -357.225854)
			(xy 347.04888 -357.204836) (xy 347.097549 -357.169209) (xy 347.151215 -357.141681) (xy 347.208543 -357.122937)
			(xy 347.268107 -357.113444) (xy 347.298264 -357.112824) (xy 347.325516 -357.113285) (xy 347.379467 -357.121037)
			(xy 347.431764 -357.136389) (xy 347.481345 -357.159027) (xy 347.527199 -357.188492) (xy 347.568392 -357.224182)
			(xy 347.604087 -357.265373) (xy 347.633556 -357.311224) (xy 347.656199 -357.360802) (xy 347.671555 -357.413098)
			(xy 347.679313 -357.467048) (xy 347.679313 -357.521552) (xy 347.671555 -357.575502) (xy 347.656199 -357.627798)
			(xy 347.633556 -357.677376) (xy 347.604087 -357.723227) (xy 347.568392 -357.764418) (xy 347.527199 -357.800108)
			(xy 347.481345 -357.829573) (xy 347.431764 -357.852211) (xy 347.379467 -357.867563) (xy 347.325516 -357.875315)
			(xy 347.298264 -357.87584) (xy 347.268103 -357.875273) (xy 347.208531 -357.865786) (xy 347.151195 -357.847038)
			(xy 347.097526 -357.819498) (xy 347.048862 -357.783852) (xy 347.027246 -357.76281) (xy 347.016177 -357.752895)
			(xy 346.989735 -357.73936) (xy 346.960518 -357.734003) (xy 346.930995 -357.737278) (xy 346.903662 -357.748907)
			(xy 346.88083 -357.767908) (xy 346.864428 -357.792674) (xy 346.855845 -357.821111) (xy 346.855288 -357.835962)
			(xy 346.855288 -358.217724) (xy 347.824296 -358.217724) (xy 347.828367 -358.162102) (xy 347.840493 -358.107665)
			(xy 347.860416 -358.055574) (xy 347.887712 -358.006939) (xy 347.921798 -357.962796) (xy 347.961947 -357.924087)
			(xy 348.007305 -357.891636) (xy 348.056905 -357.866135) (xy 348.109689 -357.848128) (xy 348.164532 -357.837998)
			(xy 348.220266 -357.835961) (xy 348.275703 -357.842061) (xy 348.32966 -357.856167) (xy 348.380989 -357.877979)
			(xy 348.428595 -357.907033) (xy 348.471463 -357.942708) (xy 348.50868 -357.984245) (xy 348.539453 -358.030758)
			(xy 348.563125 -358.081255) (xy 348.579193 -358.134662) (xy 348.587313 -358.189838) (xy 348.587822 -358.217724)
			(xy 348.587757 -358.221267) (xy 351.436611 -358.221267) (xy 351.444366 -358.167309) (xy 351.459721 -358.115003)
			(xy 351.482364 -358.065416) (xy 351.511833 -358.019555) (xy 351.547529 -357.978356) (xy 351.588725 -357.942656)
			(xy 351.634583 -357.913182) (xy 351.684168 -357.890534) (xy 351.736472 -357.875174) (xy 351.79043 -357.867414)
			(xy 351.817686 -357.86695) (xy 351.833829 -357.867091) (xy 351.866003 -357.869764) (xy 351.881948 -357.872284)
			(xy 351.89597 -357.874265) (xy 351.924113 -357.871202) (xy 351.950334 -357.86053) (xy 351.972617 -357.843069)
			(xy 351.989249 -357.82016) (xy 351.998953 -357.793566) (xy 352.000981 -357.765329) (xy 351.998534 -357.75138)
			(xy 351.994727 -357.732111) (xy 351.990659 -357.693042) (xy 351.990406 -357.673402) (xy 351.990876 -357.646151)
			(xy 351.998632 -357.592203) (xy 352.013987 -357.539908) (xy 352.036627 -357.490331) (xy 352.066093 -357.44448)
			(xy 352.101784 -357.40329) (xy 352.142974 -357.367598) (xy 352.188824 -357.338131) (xy 352.238401 -357.315489)
			(xy 352.290695 -357.300134) (xy 352.344643 -357.292376) (xy 352.399145 -357.292375) (xy 352.453093 -357.300131)
			(xy 352.505388 -357.315485) (xy 352.554966 -357.338125) (xy 352.600816 -357.367591) (xy 352.642007 -357.403281)
			(xy 352.6777 -357.444471) (xy 352.707167 -357.49032) (xy 352.729809 -357.539897) (xy 352.745166 -357.592191)
			(xy 352.752924 -357.646139) (xy 352.752925 -357.700641) (xy 352.74517 -357.754589) (xy 352.729816 -357.806884)
			(xy 352.707177 -357.856462) (xy 352.677712 -357.902313) (xy 352.642022 -357.943505) (xy 352.600832 -357.979197)
			(xy 352.554983 -358.008665) (xy 352.505407 -358.031308) (xy 352.453113 -358.046665) (xy 352.399165 -358.054423)
			(xy 352.371914 -358.05491) (xy 352.355771 -358.05477) (xy 352.323597 -358.052097) (xy 352.307652 -358.049576)
			(xy 352.293627 -358.047643) (xy 352.265492 -358.050705) (xy 352.239279 -358.061372) (xy 352.217001 -358.078825)
			(xy 352.200369 -358.101723) (xy 352.190662 -358.128307) (xy 352.188624 -358.156534) (xy 352.191066 -358.17048)
			(xy 352.194867 -358.18975) (xy 352.198939 -358.228818) (xy 352.199194 -358.248458) (xy 352.19879 -358.275714)
			(xy 352.191038 -358.329673) (xy 352.175685 -358.381979) (xy 352.153045 -358.431568) (xy 352.123578 -358.47743)
			(xy 352.087884 -358.518631) (xy 352.04669 -358.554333) (xy 352.000833 -358.583809) (xy 351.951249 -358.606459)
			(xy 351.898946 -358.621822) (xy 351.844989 -358.629585) (xy 351.790476 -358.629589) (xy 351.736518 -358.621836)
			(xy 351.684212 -358.606482) (xy 351.634624 -358.583841) (xy 351.588763 -358.554372) (xy 351.547562 -358.518677)
			(xy 351.511861 -358.477482) (xy 351.482386 -358.431625) (xy 351.459737 -358.38204) (xy 351.444376 -358.329737)
			(xy 351.436615 -358.27578) (xy 351.436611 -358.221267) (xy 348.587757 -358.221267) (xy 348.587313 -358.24561)
			(xy 348.579193 -358.300786) (xy 348.563125 -358.354193) (xy 348.539453 -358.40469) (xy 348.50868 -358.451203)
			(xy 348.471463 -358.49274) (xy 348.428595 -358.528415) (xy 348.380989 -358.557469) (xy 348.32966 -358.579281)
			(xy 348.275703 -358.593387) (xy 348.220266 -358.599487) (xy 348.164532 -358.59745) (xy 348.109689 -358.58732)
			(xy 348.056905 -358.569313) (xy 348.007305 -358.543812) (xy 347.961947 -358.511361) (xy 347.921798 -358.472652)
			(xy 347.887712 -358.428509) (xy 347.860416 -358.379874) (xy 347.840493 -358.327783) (xy 347.828367 -358.273346)
			(xy 347.824296 -358.217724) (xy 346.855288 -358.217724) (xy 346.855288 -359.182924) (xy 346.855777 -359.192915)
			(xy 346.863419 -359.211378) (xy 346.877534 -359.225522) (xy 346.895982 -359.233202) (xy 346.915964 -359.233252)
			(xy 346.93445 -359.225666) (xy 346.941902 -359.218992) (xy 346.998798 -359.16235) (xy 347.013536 -359.137952)
			(xy 347.049119 -359.093424) (xy 347.090933 -359.054688) (xy 347.138047 -359.022609) (xy 347.189412 -358.9979)
			(xy 347.243882 -358.981112) (xy 347.300245 -358.972619) (xy 347.328744 -358.972104) (xy 347.355993 -358.972593)
			(xy 347.409935 -358.980355) (xy 347.462224 -358.995714) (xy 347.511795 -359.018358) (xy 347.557639 -359.047825)
			(xy 347.598823 -359.083517) (xy 347.634508 -359.124706) (xy 347.663969 -359.170555) (xy 347.686606 -359.220129)
			(xy 347.701957 -359.27242) (xy 347.709711 -359.326363) (xy 347.710252 -359.353612) (xy 347.70972 -359.382111)
			(xy 347.701233 -359.438473) (xy 347.687153 -359.484168) (xy 349.7359 -359.484168) (xy 349.739971 -359.428546)
			(xy 349.752097 -359.374109) (xy 349.77202 -359.322018) (xy 349.799316 -359.273383) (xy 349.833402 -359.22924)
			(xy 349.873551 -359.190531) (xy 349.918909 -359.15808) (xy 349.968509 -359.132579) (xy 350.021293 -359.114572)
			(xy 350.076136 -359.104442) (xy 350.13187 -359.102405) (xy 350.187307 -359.108505) (xy 350.241264 -359.122611)
			(xy 350.292593 -359.144423) (xy 350.340199 -359.173477) (xy 350.383067 -359.209152) (xy 350.420284 -359.250689)
			(xy 350.451057 -359.297202) (xy 350.474729 -359.347699) (xy 350.490797 -359.401106) (xy 350.498917 -359.456282)
			(xy 350.499426 -359.484168) (xy 350.498917 -359.512054) (xy 350.490797 -359.56723) (xy 350.474729 -359.620637)
			(xy 350.451057 -359.671134) (xy 350.420284 -359.717647) (xy 350.383067 -359.759184) (xy 350.340199 -359.794859)
			(xy 350.292593 -359.823913) (xy 350.241264 -359.845725) (xy 350.187307 -359.859831) (xy 350.13187 -359.865931)
			(xy 350.076136 -359.863894) (xy 350.021293 -359.853764) (xy 349.968509 -359.835757) (xy 349.918909 -359.810256)
			(xy 349.873551 -359.777805) (xy 349.833402 -359.739096) (xy 349.799316 -359.694953) (xy 349.77202 -359.646318)
			(xy 349.752097 -359.594227) (xy 349.739971 -359.53979) (xy 349.7359 -359.484168) (xy 347.687153 -359.484168)
			(xy 347.684449 -359.492944) (xy 347.659743 -359.544309) (xy 347.627665 -359.591423) (xy 347.588931 -359.633237)
			(xy 347.544403 -359.668818) (xy 347.520006 -359.683558) (xy 347.299788 -359.903776) (xy 347.299788 -360.00944)
			(xy 347.300871 -360.022828) (xy 347.309156 -360.048369) (xy 347.323801 -360.070875) (xy 347.343796 -360.088797)
			(xy 347.367766 -360.100899) (xy 347.394058 -360.106349) (xy 347.407484 -360.10596) (xy 347.443806 -360.104182)
			(xy 347.471542 -360.104687) (xy 347.526429 -360.112732) (xy 347.579573 -360.128637) (xy 347.629856 -360.152067)
			(xy 347.676217 -360.182528) (xy 347.717681 -360.219379) (xy 347.742333 -360.248708) (xy 352.035362 -360.248708)
			(xy 352.039433 -360.193086) (xy 352.051559 -360.138649) (xy 352.071482 -360.086558) (xy 352.098778 -360.037923)
			(xy 352.132864 -359.99378) (xy 352.173013 -359.955071) (xy 352.218371 -359.92262) (xy 352.267971 -359.897119)
			(xy 352.320755 -359.879112) (xy 352.375598 -359.868982) (xy 352.431332 -359.866945) (xy 352.486769 -359.873045)
			(xy 352.540726 -359.887151) (xy 352.592055 -359.908963) (xy 352.639661 -359.938017) (xy 352.682529 -359.973692)
			(xy 352.719746 -360.015229) (xy 352.750519 -360.061742) (xy 352.774191 -360.112239) (xy 352.790259 -360.165646)
			(xy 352.798379 -360.220822) (xy 352.798888 -360.248708) (xy 352.798379 -360.276594) (xy 352.790259 -360.33177)
			(xy 352.774191 -360.385177) (xy 352.750519 -360.435674) (xy 352.719746 -360.482187) (xy 352.682529 -360.523724)
			(xy 352.639661 -360.559399) (xy 352.592055 -360.588453) (xy 352.540726 -360.610265) (xy 352.486769 -360.624371)
			(xy 352.431332 -360.630471) (xy 352.375598 -360.628434) (xy 352.320755 -360.618304) (xy 352.267971 -360.600297)
			(xy 352.218371 -360.574796) (xy 352.173013 -360.542345) (xy 352.132864 -360.503636) (xy 352.098778 -360.459493)
			(xy 352.071482 -360.410858) (xy 352.051559 -360.358767) (xy 352.039433 -360.30433) (xy 352.035362 -360.248708)
			(xy 347.742333 -360.248708) (xy 347.753374 -360.261844) (xy 347.782544 -360.309029) (xy 347.804577 -360.359939)
			(xy 347.819009 -360.413501) (xy 347.822774 -360.440986) (xy 347.824298 -360.455464) (xy 347.825568 -360.48569)
			(xy 347.825017 -360.514865) (xy 347.816146 -360.572538) (xy 347.798609 -360.62819) (xy 347.786198 -360.6546)
			(xy 347.781517 -360.667612) (xy 347.778556 -360.695095) (xy 347.783069 -360.722366) (xy 347.794726 -360.747429)
			(xy 347.812674 -360.768452) (xy 347.8356 -360.783894) (xy 347.861826 -360.792627) (xy 347.875606 -360.793792)
			(xy 348.02826 -360.793792) (xy 348.034356 -360.792268) (xy 348.057035 -360.786946) (xy 348.103266 -360.781215)
			(xy 348.126558 -360.780838) (xy 348.15381 -360.781298) (xy 348.207758 -360.78905) (xy 348.260055 -360.8044)
			(xy 348.309635 -360.827037) (xy 348.355487 -360.856501) (xy 348.39668 -360.89219) (xy 348.432374 -360.933379)
			(xy 348.461842 -360.979229) (xy 348.484485 -361.028806) (xy 348.499842 -361.0811) (xy 348.507599 -361.135049)
			(xy 348.507599 -361.189551) (xy 348.499842 -361.2435) (xy 348.484485 -361.295794) (xy 348.461842 -361.345371)
			(xy 348.432374 -361.391221) (xy 348.39668 -361.43241) (xy 348.355487 -361.468099) (xy 348.309635 -361.497563)
			(xy 348.260055 -361.5202) (xy 348.207759 -361.53555) (xy 348.15381 -361.543302) (xy 348.126558 -361.543854)
			(xy 348.103266 -361.543474) (xy 348.057036 -361.537742) (xy 348.034356 -361.532424) (xy 348.02826 -361.5309)
			(xy 347.559376 -361.5309) (xy 347.029786 -362.060744) (xy 346.834968 -362.255562) (xy 346.824922 -362.266294)
			(xy 346.810906 -362.292121) (xy 346.804809 -362.320866) (xy 346.807135 -362.350159) (xy 346.817691 -362.377582)
			(xy 346.835606 -362.400873) (xy 346.859403 -362.418112) (xy 346.887118 -362.427875) (xy 346.90177 -362.429044)
			(xy 349.47606 -362.429044) (xy 349.489645 -362.427932) (xy 349.515531 -362.41943) (xy 349.538249 -362.404388)
			(xy 349.556182 -362.383875) (xy 349.568055 -362.359351) (xy 349.573023 -362.332561) (xy 349.570731 -362.305411)
			(xy 349.561344 -362.279833) (xy 349.545529 -362.257646) (xy 349.535242 -362.248704) (xy 349.513797 -362.230487)
			(xy 349.475982 -362.188821) (xy 349.444699 -362.142052) (xy 349.420628 -362.091193) (xy 349.404292 -362.037349)
			(xy 349.396045 -361.98169) (xy 349.395542 -361.953556) (xy 349.396028 -361.926305) (xy 349.403784 -361.872357)
			(xy 349.419139 -361.820062) (xy 349.441781 -361.770485) (xy 349.471247 -361.724635) (xy 349.506938 -361.683444)
			(xy 349.548129 -361.647753) (xy 349.593979 -361.618287) (xy 349.643556 -361.595645) (xy 349.695851 -361.58029)
			(xy 349.749799 -361.572534) (xy 349.804301 -361.572534) (xy 349.858249 -361.58029) (xy 349.910544 -361.595645)
			(xy 349.960121 -361.618287) (xy 350.005971 -361.647753) (xy 350.047162 -361.683444) (xy 350.082853 -361.724635)
			(xy 350.112319 -361.770485) (xy 350.134961 -361.820062) (xy 350.150316 -361.872357) (xy 350.158072 -361.926305)
			(xy 350.158531 -361.952032) (xy 350.408746 -361.952032) (xy 350.412817 -361.89641) (xy 350.424943 -361.841973)
			(xy 350.444866 -361.789882) (xy 350.472162 -361.741247) (xy 350.506248 -361.697104) (xy 350.546397 -361.658395)
			(xy 350.591755 -361.625944) (xy 350.641355 -361.600443) (xy 350.694139 -361.582436) (xy 350.748982 -361.572306)
			(xy 350.804716 -361.570269) (xy 350.860153 -361.576369) (xy 350.91411 -361.590475) (xy 350.965439 -361.612287)
			(xy 351.013045 -361.641341) (xy 351.055913 -361.677016) (xy 351.09313 -361.718553) (xy 351.123903 -361.765066)
			(xy 351.147575 -361.815563) (xy 351.163643 -361.86897) (xy 351.171763 -361.924146) (xy 351.172272 -361.952032)
			(xy 351.171763 -361.979918) (xy 351.163643 -362.035094) (xy 351.147575 -362.088501) (xy 351.123903 -362.138998)
			(xy 351.09313 -362.185511) (xy 351.055913 -362.227048) (xy 351.013045 -362.262723) (xy 350.965439 -362.291777)
			(xy 350.91411 -362.313589) (xy 350.860153 -362.327695) (xy 350.804716 -362.333795) (xy 350.748982 -362.331758)
			(xy 350.694139 -362.321628) (xy 350.641355 -362.303621) (xy 350.591755 -362.27812) (xy 350.546397 -362.245669)
			(xy 350.506248 -362.20696) (xy 350.472162 -362.162817) (xy 350.444866 -362.114182) (xy 350.424943 -362.062091)
			(xy 350.412817 -362.007654) (xy 350.408746 -361.952032) (xy 350.158531 -361.952032) (xy 350.158558 -361.953556)
			(xy 350.158052 -361.981688) (xy 350.149786 -362.037341) (xy 350.13344 -362.091179) (xy 350.10937 -362.142034)
			(xy 350.078096 -362.188806) (xy 350.040295 -362.23048) (xy 350.018858 -362.248704) (xy 350.008582 -362.257655)
			(xy 349.992782 -362.279848) (xy 349.983406 -362.305426) (xy 349.981119 -362.332573) (xy 349.986086 -362.359359)
			(xy 349.997952 -362.383882) (xy 350.015874 -362.404399) (xy 350.03858 -362.419452) (xy 350.064456 -362.427973)
			(xy 350.07804 -362.429044) (xy 350.27489 -362.429044) (xy 350.30401 -362.429499) (xy 350.361753 -362.437102)
			(xy 350.418009 -362.452177) (xy 350.471815 -362.474468) (xy 350.522251 -362.503593) (xy 350.568452 -362.539053)
			(xy 350.589342 -362.559346) (xy 350.653604 -362.623608) (xy 351.008948 -362.623608) (xy 351.013019 -362.567986)
			(xy 351.025145 -362.513549) (xy 351.045068 -362.461458) (xy 351.072364 -362.412823) (xy 351.10645 -362.36868)
			(xy 351.146599 -362.329971) (xy 351.191957 -362.29752) (xy 351.241557 -362.272019) (xy 351.294341 -362.254012)
			(xy 351.349184 -362.243882) (xy 351.404918 -362.241845) (xy 351.460355 -362.247945) (xy 351.514312 -362.262051)
			(xy 351.565641 -362.283863) (xy 351.613247 -362.312917) (xy 351.656115 -362.348592) (xy 351.693332 -362.390129)
			(xy 351.724105 -362.436642) (xy 351.747777 -362.487139) (xy 351.763845 -362.540546) (xy 351.771965 -362.595722)
			(xy 351.772474 -362.623608) (xy 351.771965 -362.651494) (xy 351.763845 -362.70667) (xy 351.747777 -362.760077)
			(xy 351.724105 -362.810574) (xy 351.693332 -362.857087) (xy 351.656115 -362.898624) (xy 351.613247 -362.934299)
			(xy 351.565641 -362.963353) (xy 351.514312 -362.985165) (xy 351.460355 -362.999271) (xy 351.404918 -363.005371)
			(xy 351.349184 -363.003334) (xy 351.294341 -362.993204) (xy 351.241557 -362.975197) (xy 351.191957 -362.949696)
			(xy 351.146599 -362.917245) (xy 351.10645 -362.878536) (xy 351.072364 -362.834393) (xy 351.045068 -362.785758)
			(xy 351.025145 -362.733667) (xy 351.013019 -362.67923) (xy 351.008948 -362.623608) (xy 350.653604 -362.623608)
			(xy 351.667826 -363.63783) (xy 352.31146 -363.63783) (xy 352.315531 -363.582208) (xy 352.327657 -363.527771)
			(xy 352.34758 -363.47568) (xy 352.374876 -363.427045) (xy 352.408962 -363.382902) (xy 352.449111 -363.344193)
			(xy 352.494469 -363.311742) (xy 352.544069 -363.286241) (xy 352.596853 -363.268234) (xy 352.651696 -363.258104)
			(xy 352.70743 -363.256067) (xy 352.762867 -363.262167) (xy 352.816824 -363.276273) (xy 352.868153 -363.298085)
			(xy 352.915759 -363.327139) (xy 352.958627 -363.362814) (xy 352.995844 -363.404351) (xy 353.026617 -363.450864)
			(xy 353.050289 -363.501361) (xy 353.066357 -363.554768) (xy 353.074477 -363.609944) (xy 353.074986 -363.63783)
			(xy 353.074477 -363.665716) (xy 353.066357 -363.720892) (xy 353.050289 -363.774299) (xy 353.026617 -363.824796)
			(xy 352.995844 -363.871309) (xy 352.958627 -363.912846) (xy 352.915759 -363.948521) (xy 352.868153 -363.977575)
			(xy 352.816824 -363.999387) (xy 352.762867 -364.013493) (xy 352.70743 -364.019593) (xy 352.651696 -364.017556)
			(xy 352.596853 -364.007426) (xy 352.544069 -363.989419) (xy 352.494469 -363.963918) (xy 352.449111 -363.931467)
			(xy 352.408962 -363.892758) (xy 352.374876 -363.848615) (xy 352.34758 -363.79998) (xy 352.327657 -363.747889)
			(xy 352.315531 -363.693452) (xy 352.31146 -363.63783) (xy 351.667826 -363.63783) (xy 352.098356 -364.06836)
			(xy 352.121901 -364.092799) (xy 352.162059 -364.147499) (xy 352.193456 -364.207657) (xy 352.205036 -364.239556)
			(xy 352.216136 -364.274327) (xy 352.228133 -364.34632) (xy 352.228912 -364.382812) (xy 352.228912 -367.491048)
			(xy 352.48091 -367.491048) (xy 352.48091 -367.436552) (xy 352.488665 -367.382611) (xy 352.504018 -367.330322)
			(xy 352.526656 -367.28075) (xy 352.556118 -367.234905) (xy 352.591804 -367.193718) (xy 352.632989 -367.15803)
			(xy 352.678833 -367.128566) (xy 352.728403 -367.105925) (xy 352.780691 -367.09057) (xy 352.834632 -367.082812)
			(xy 352.86188 -367.082324) (xy 352.888261 -367.082716) (xy 352.940522 -367.08998) (xy 352.991284 -367.104372)
			(xy 353.03958 -367.125618) (xy 353.084489 -367.153313) (xy 353.125157 -367.18693) (xy 353.160807 -367.225826)
			(xy 353.190761 -367.269262) (xy 353.203002 -367.292636) (xy 353.209704 -367.304995) (xy 353.228679 -367.325723)
			(xy 353.252593 -367.340485) (xy 353.279629 -367.348157) (xy 353.307731 -367.348157) (xy 353.334767 -367.340485)
			(xy 353.358681 -367.325723) (xy 353.377656 -367.304995) (xy 353.384358 -367.292636) (xy 353.396587 -367.269259)
			(xy 353.426553 -367.225837) (xy 353.462212 -367.186954) (xy 353.502883 -367.15335) (xy 353.547794 -367.125665)
			(xy 353.596088 -367.104425) (xy 353.646845 -367.090035) (xy 353.699101 -367.08277) (xy 353.72548 -367.082324)
			(xy 353.752736 -367.082722) (xy 353.806694 -367.090477) (xy 353.858998 -367.105832) (xy 353.908585 -367.128476)
			(xy 353.954445 -367.157946) (xy 353.995643 -367.193642) (xy 354.031342 -367.234839) (xy 354.060815 -367.280697)
			(xy 354.083461 -367.330283) (xy 354.098819 -367.382587) (xy 354.106577 -367.436544) (xy 354.106577 -367.491056)
			(xy 354.098819 -367.545013) (xy 354.083461 -367.597317) (xy 354.060815 -367.646903) (xy 354.031342 -367.692761)
			(xy 353.995643 -367.733958) (xy 353.954445 -367.769654) (xy 353.908585 -367.799124) (xy 353.858998 -367.821768)
			(xy 353.806694 -367.837123) (xy 353.752736 -367.844878) (xy 353.72548 -367.84534) (xy 353.699102 -367.844863)
			(xy 353.646847 -367.837609) (xy 353.596089 -367.823227) (xy 353.547795 -367.801992) (xy 353.502885 -367.774309)
			(xy 353.462216 -367.740705) (xy 353.426562 -367.70182) (xy 353.396603 -367.658396) (xy 353.384358 -367.635028)
			(xy 353.377656 -367.622669) (xy 353.358681 -367.601941) (xy 353.334767 -367.587179) (xy 353.307731 -367.579507)
			(xy 353.279629 -367.579507) (xy 353.252593 -367.587179) (xy 353.228679 -367.601941) (xy 353.209704 -367.622669)
			(xy 353.203002 -367.635028) (xy 353.190787 -367.658413) (xy 353.160821 -367.701837) (xy 353.125161 -367.740721)
			(xy 353.084488 -367.774326) (xy 353.039575 -367.802011) (xy 352.991278 -367.823249) (xy 352.940518 -367.837635)
			(xy 352.88826 -367.844896) (xy 352.86188 -367.84534) (xy 352.834632 -367.844788) (xy 352.780691 -367.83703)
			(xy 352.728403 -367.821675) (xy 352.678833 -367.799034) (xy 352.632989 -367.76957) (xy 352.591804 -367.733882)
			(xy 352.556118 -367.692695) (xy 352.526656 -367.64685) (xy 352.504018 -367.597278) (xy 352.488665 -367.544989)
			(xy 352.48091 -367.491048) (xy 352.228912 -367.491048) (xy 352.228912 -380.834392) (xy 365.608108 -380.834392)
			(xy 365.62311 -380.83387) (xy 365.651825 -380.825172) (xy 365.67677 -380.8085) (xy 365.69579 -380.785295)
			(xy 365.70724 -380.757563) (xy 365.710132 -380.727699) (xy 365.704216 -380.698285) (xy 365.690002 -380.671862)
			(xy 365.679736 -380.66091) (xy 354.386134 -369.367054) (xy 354.366057 -369.346174) (xy 354.332011 -369.299314)
			(xy 354.305713 -369.247706) (xy 354.28781 -369.192619) (xy 354.278743 -369.135411) (xy 354.278184 -369.10645)
			(xy 354.278184 -367.011204) (xy 353.321874 -366.054894) (xy 353.301799 -366.034013) (xy 353.267757 -365.987153)
			(xy 353.241464 -365.935544) (xy 353.223568 -365.880458) (xy 353.214509 -365.82325) (xy 353.213924 -365.79429)
			(xy 353.213924 -363.45114) (xy 352.235516 -362.472732) (xy 352.215393 -362.451881) (xy 352.181296 -362.405031)
			(xy 352.15495 -362.353422) (xy 352.137004 -362.298325) (xy 352.127902 -362.2411) (xy 352.127312 -362.212128)
			(xy 352.127312 -361.488228) (xy 352.127873 -361.459255) (xy 352.136984 -361.402031) (xy 352.15494 -361.346937)
			(xy 352.181297 -361.295332) (xy 352.215407 -361.248489) (xy 352.235516 -361.227624) (xy 352.962464 -360.500676)
			(xy 352.962464 -359.522268) (xy 352.41357 -359.522268) (xy 352.407474 -359.523792) (xy 352.384795 -359.529116)
			(xy 352.338564 -359.534852) (xy 352.315272 -359.535222) (xy 352.288021 -359.534734) (xy 352.234074 -359.526974)
			(xy 352.181781 -359.511616) (xy 352.132206 -359.488973) (xy 352.086357 -359.459504) (xy 352.045169 -359.423812)
			(xy 352.009479 -359.382621) (xy 351.980014 -359.33677) (xy 351.957374 -359.287193) (xy 351.94202 -359.234898)
			(xy 351.934264 -359.180951) (xy 351.934264 -359.126449) (xy 351.94202 -359.072502) (xy 351.957374 -359.020207)
			(xy 351.980014 -358.97063) (xy 352.009479 -358.924779) (xy 352.045169 -358.883588) (xy 352.086357 -358.847896)
			(xy 352.132206 -358.818427) (xy 352.181781 -358.795784) (xy 352.234074 -358.780426) (xy 352.288021 -358.772666)
			(xy 352.315272 -358.772206) (xy 352.338563 -358.772588) (xy 352.384793 -358.778324) (xy 352.407474 -358.783636)
			(xy 352.41357 -358.78516) (xy 353.147122 -358.78516) (xy 353.176085 -358.7857) (xy 353.233296 -358.794765)
			(xy 353.288386 -358.812669) (xy 353.339996 -358.83897) (xy 353.386856 -358.87302) (xy 353.407726 -358.89311)
			(xy 353.591622 -359.077006) (xy 353.611697 -359.097887) (xy 353.64574 -359.144747) (xy 353.672033 -359.196356)
			(xy 353.689929 -359.251442) (xy 353.698988 -359.30865) (xy 353.699572 -359.33761) (xy 353.699572 -360.65333)
			(xy 353.699002 -360.68229) (xy 353.689937 -360.739497) (xy 353.672035 -360.794582) (xy 353.645737 -360.846189)
			(xy 353.611691 -360.893047) (xy 353.591622 -360.913934) (xy 353.3775 -361.12831) (xy 353.29876 -361.20705)
			(xy 353.288646 -361.217887) (xy 353.274588 -361.243969) (xy 353.268586 -361.272984) (xy 353.271143 -361.302503)
			(xy 353.282045 -361.330054) (xy 353.30038 -361.35333) (xy 353.312222 -361.362244) (xy 353.334564 -361.377426)
			(xy 353.375134 -361.413088) (xy 353.410264 -361.45412) (xy 353.439249 -361.499701) (xy 353.461509 -361.548917)
			(xy 353.476598 -361.600783) (xy 353.484215 -361.65426) (xy 353.484688 -361.681268) (xy 353.484224 -361.708152)
			(xy 353.476669 -361.761386) (xy 353.461717 -361.813033) (xy 353.439666 -361.86207) (xy 353.410951 -361.907528)
			(xy 353.37614 -361.948506) (xy 353.335924 -361.984193) (xy 353.291097 -362.013883) (xy 353.242547 -362.036988)
			(xy 353.191234 -362.053051) (xy 353.138176 -362.061753) (xy 353.111308 -362.062776) (xy 353.096467 -362.06358)
			(xy 353.06819 -362.072687) (xy 353.043731 -362.089547) (xy 353.025159 -362.112734) (xy 353.014047 -362.140285)
			(xy 353.011335 -362.169868) (xy 353.017252 -362.198981) (xy 353.031299 -362.225158) (xy 353.041458 -362.236004)
			(xy 353.152202 -362.346748) (xy 353.600002 -362.346748) (xy 353.604073 -362.291126) (xy 353.616199 -362.236689)
			(xy 353.636122 -362.184598) (xy 353.663418 -362.135963) (xy 353.697504 -362.09182) (xy 353.737653 -362.053111)
			(xy 353.783011 -362.02066) (xy 353.832611 -361.995159) (xy 353.885395 -361.977152) (xy 353.940238 -361.967022)
			(xy 353.995972 -361.964985) (xy 354.051409 -361.971085) (xy 354.105366 -361.985191) (xy 354.156695 -362.007003)
			(xy 354.204301 -362.036057) (xy 354.247169 -362.071732) (xy 354.284386 -362.113269) (xy 354.315159 -362.159782)
			(xy 354.338831 -362.210279) (xy 354.354899 -362.263686) (xy 354.363019 -362.318862) (xy 354.363528 -362.346748)
			(xy 354.363019 -362.374634) (xy 354.354899 -362.42981) (xy 354.338831 -362.483217) (xy 354.315159 -362.533714)
			(xy 354.284386 -362.580227) (xy 354.247169 -362.621764) (xy 354.204301 -362.657439) (xy 354.156695 -362.686493)
			(xy 354.105366 -362.708305) (xy 354.051409 -362.722411) (xy 353.995972 -362.728511) (xy 353.940238 -362.726474)
			(xy 353.885395 -362.716344) (xy 353.832611 -362.698337) (xy 353.783011 -362.672836) (xy 353.737653 -362.640385)
			(xy 353.697504 -362.601676) (xy 353.663418 -362.557533) (xy 353.636122 -362.508898) (xy 353.616199 -362.456807)
			(xy 353.604073 -362.40237) (xy 353.600002 -362.346748) (xy 353.152202 -362.346748) (xy 353.257104 -362.45165)
			(xy 353.843082 -363.037882) (xy 353.863183 -363.058742) (xy 353.897235 -363.105604) (xy 353.923537 -363.157217)
			(xy 353.94144 -363.212308) (xy 353.950504 -363.269522) (xy 353.950652 -363.277658) (xy 354.17836 -363.277658)
			(xy 354.182431 -363.222036) (xy 354.194557 -363.167599) (xy 354.21448 -363.115508) (xy 354.241776 -363.066873)
			(xy 354.275862 -363.02273) (xy 354.316011 -362.984021) (xy 354.361369 -362.95157) (xy 354.410969 -362.926069)
			(xy 354.463753 -362.908062) (xy 354.518596 -362.897932) (xy 354.57433 -362.895895) (xy 354.629767 -362.901995)
			(xy 354.683724 -362.916101) (xy 354.735053 -362.937913) (xy 354.782659 -362.966967) (xy 354.825527 -363.002642)
			(xy 354.862744 -363.044179) (xy 354.893517 -363.090692) (xy 354.917189 -363.141189) (xy 354.933257 -363.194596)
			(xy 354.941377 -363.249772) (xy 354.941886 -363.277658) (xy 354.941377 -363.305544) (xy 354.933257 -363.36072)
			(xy 354.917189 -363.414127) (xy 354.893517 -363.464624) (xy 354.862744 -363.511137) (xy 354.825527 -363.552674)
			(xy 354.782659 -363.588349) (xy 354.735053 -363.617403) (xy 354.683724 -363.639215) (xy 354.629767 -363.653321)
			(xy 354.57433 -363.659421) (xy 354.518596 -363.657384) (xy 354.463753 -363.647254) (xy 354.410969 -363.629247)
			(xy 354.361369 -363.603746) (xy 354.316011 -363.571295) (xy 354.275862 -363.532586) (xy 354.241776 -363.488443)
			(xy 354.21448 -363.439808) (xy 354.194557 -363.387717) (xy 354.182431 -363.33328) (xy 354.17836 -363.277658)
			(xy 353.950652 -363.277658) (xy 353.951032 -363.298486) (xy 353.951032 -364.4138) (xy 354.060504 -364.4138)
			(xy 354.064575 -364.358178) (xy 354.076701 -364.303741) (xy 354.096624 -364.25165) (xy 354.12392 -364.203015)
			(xy 354.158006 -364.158872) (xy 354.198155 -364.120163) (xy 354.243513 -364.087712) (xy 354.293113 -364.062211)
			(xy 354.345897 -364.044204) (xy 354.40074 -364.034074) (xy 354.456474 -364.032037) (xy 354.511911 -364.038137)
			(xy 354.565868 -364.052243) (xy 354.617197 -364.074055) (xy 354.664803 -364.103109) (xy 354.707671 -364.138784)
			(xy 354.744888 -364.180321) (xy 354.775661 -364.226834) (xy 354.799333 -364.277331) (xy 354.815401 -364.330738)
			(xy 354.823521 -364.385914) (xy 354.823529 -364.386368) (xy 355.566216 -364.386368) (xy 355.570287 -364.330746)
			(xy 355.582413 -364.276309) (xy 355.602336 -364.224218) (xy 355.629632 -364.175583) (xy 355.663718 -364.13144)
			(xy 355.703867 -364.092731) (xy 355.749225 -364.06028) (xy 355.798825 -364.034779) (xy 355.851609 -364.016772)
			(xy 355.906452 -364.006642) (xy 355.962186 -364.004605) (xy 356.017623 -364.010705) (xy 356.07158 -364.024811)
			(xy 356.122909 -364.046623) (xy 356.170515 -364.075677) (xy 356.213383 -364.111352) (xy 356.2506 -364.152889)
			(xy 356.281373 -364.199402) (xy 356.305045 -364.249899) (xy 356.321113 -364.303306) (xy 356.329233 -364.358482)
			(xy 356.329742 -364.386368) (xy 356.329233 -364.414254) (xy 356.321113 -364.46943) (xy 356.305045 -364.522837)
			(xy 356.281373 -364.573334) (xy 356.2506 -364.619847) (xy 356.213383 -364.661384) (xy 356.170515 -364.697059)
			(xy 356.122909 -364.726113) (xy 356.07158 -364.747925) (xy 356.017623 -364.762031) (xy 355.962186 -364.768131)
			(xy 355.906452 -364.766094) (xy 355.851609 -364.755964) (xy 355.798825 -364.737957) (xy 355.749225 -364.712456)
			(xy 355.703867 -364.680005) (xy 355.663718 -364.641296) (xy 355.629632 -364.597153) (xy 355.602336 -364.548518)
			(xy 355.582413 -364.496427) (xy 355.570287 -364.44199) (xy 355.566216 -364.386368) (xy 354.823529 -364.386368)
			(xy 354.82403 -364.4138) (xy 354.823521 -364.441686) (xy 354.815401 -364.496862) (xy 354.799333 -364.550269)
			(xy 354.775661 -364.600766) (xy 354.744888 -364.647279) (xy 354.707671 -364.688816) (xy 354.664803 -364.724491)
			(xy 354.617197 -364.753545) (xy 354.565868 -364.775357) (xy 354.511911 -364.789463) (xy 354.456474 -364.795563)
			(xy 354.40074 -364.793526) (xy 354.345897 -364.783396) (xy 354.293113 -364.765389) (xy 354.243513 -364.739888)
			(xy 354.198155 -364.707437) (xy 354.158006 -364.668728) (xy 354.12392 -364.624585) (xy 354.096624 -364.57595)
			(xy 354.076701 -364.523859) (xy 354.064575 -364.469422) (xy 354.060504 -364.4138) (xy 353.951032 -364.4138)
			(xy 353.951032 -365.21644) (xy 354.854508 -365.21644) (xy 354.858579 -365.160818) (xy 354.870705 -365.106381)
			(xy 354.890628 -365.05429) (xy 354.917924 -365.005655) (xy 354.95201 -364.961512) (xy 354.992159 -364.922803)
			(xy 355.037517 -364.890352) (xy 355.087117 -364.864851) (xy 355.139901 -364.846844) (xy 355.194744 -364.836714)
			(xy 355.250478 -364.834677) (xy 355.305915 -364.840777) (xy 355.359872 -364.854883) (xy 355.411201 -364.876695)
			(xy 355.458807 -364.905749) (xy 355.501675 -364.941424) (xy 355.538892 -364.982961) (xy 355.569665 -365.029474)
			(xy 355.593337 -365.079971) (xy 355.609405 -365.133378) (xy 355.617525 -365.188554) (xy 355.618034 -365.21644)
			(xy 355.617525 -365.244326) (xy 355.609405 -365.299502) (xy 355.593337 -365.352909) (xy 355.569665 -365.403406)
			(xy 355.538892 -365.449919) (xy 355.501675 -365.491456) (xy 355.458807 -365.527131) (xy 355.411201 -365.556185)
			(xy 355.359872 -365.577997) (xy 355.305915 -365.592103) (xy 355.250478 -365.598203) (xy 355.194744 -365.596166)
			(xy 355.139901 -365.586036) (xy 355.087117 -365.568029) (xy 355.037517 -365.542528) (xy 354.992159 -365.510077)
			(xy 354.95201 -365.471368) (xy 354.917924 -365.427225) (xy 354.890628 -365.37859) (xy 354.870705 -365.326499)
			(xy 354.858579 -365.272062) (xy 354.854508 -365.21644) (xy 353.951032 -365.21644) (xy 353.951032 -365.641636)
			(xy 354.907342 -366.597946) (xy 354.92742 -366.618826) (xy 354.961468 -366.665685) (xy 354.987768 -366.717293)
			(xy 355.005673 -366.77238) (xy 355.01474 -366.829589) (xy 355.015292 -366.85855) (xy 355.015292 -368.953796)
			(xy 355.596444 -369.534948) (xy 364.036862 -369.534948) (xy 364.040933 -369.479326) (xy 364.053059 -369.424889)
			(xy 364.072982 -369.372798) (xy 364.100278 -369.324163) (xy 364.134364 -369.28002) (xy 364.174513 -369.241311)
			(xy 364.219871 -369.20886) (xy 364.269471 -369.183359) (xy 364.322255 -369.165352) (xy 364.377098 -369.155222)
			(xy 364.432832 -369.153185) (xy 364.488269 -369.159285) (xy 364.542226 -369.173391) (xy 364.593555 -369.195203)
			(xy 364.641161 -369.224257) (xy 364.684029 -369.259932) (xy 364.721246 -369.301469) (xy 364.752019 -369.347982)
			(xy 364.775691 -369.398479) (xy 364.791759 -369.451886) (xy 364.799879 -369.507062) (xy 364.800388 -369.534948)
			(xy 364.800249 -369.542568) (xy 365.489742 -369.542568) (xy 365.493813 -369.486946) (xy 365.505939 -369.432509)
			(xy 365.525862 -369.380418) (xy 365.553158 -369.331783) (xy 365.587244 -369.28764) (xy 365.627393 -369.248931)
			(xy 365.672751 -369.21648) (xy 365.722351 -369.190979) (xy 365.775135 -369.172972) (xy 365.829978 -369.162842)
			(xy 365.885712 -369.160805) (xy 365.941149 -369.166905) (xy 365.995106 -369.181011) (xy 366.046435 -369.202823)
			(xy 366.094041 -369.231877) (xy 366.136909 -369.267552) (xy 366.174126 -369.309089) (xy 366.204899 -369.355602)
			(xy 366.228571 -369.406099) (xy 366.244639 -369.459506) (xy 366.252759 -369.514682) (xy 366.253268 -369.542568)
			(xy 366.252759 -369.570454) (xy 366.244639 -369.62563) (xy 366.228571 -369.679037) (xy 366.204899 -369.729534)
			(xy 366.174126 -369.776047) (xy 366.136909 -369.817584) (xy 366.094041 -369.853259) (xy 366.046435 -369.882313)
			(xy 365.995106 -369.904125) (xy 365.941149 -369.918231) (xy 365.885712 -369.924331) (xy 365.829978 -369.922294)
			(xy 365.775135 -369.912164) (xy 365.722351 -369.894157) (xy 365.672751 -369.868656) (xy 365.627393 -369.836205)
			(xy 365.587244 -369.797496) (xy 365.553158 -369.753353) (xy 365.525862 -369.704718) (xy 365.505939 -369.652627)
			(xy 365.493813 -369.59819) (xy 365.489742 -369.542568) (xy 364.800249 -369.542568) (xy 364.799879 -369.562834)
			(xy 364.791759 -369.61801) (xy 364.775691 -369.671417) (xy 364.752019 -369.721914) (xy 364.721246 -369.768427)
			(xy 364.684029 -369.809964) (xy 364.641161 -369.845639) (xy 364.593555 -369.874693) (xy 364.542226 -369.896505)
			(xy 364.488269 -369.910611) (xy 364.432832 -369.916711) (xy 364.377098 -369.914674) (xy 364.322255 -369.904544)
			(xy 364.269471 -369.886537) (xy 364.219871 -369.861036) (xy 364.174513 -369.828585) (xy 364.134364 -369.789876)
			(xy 364.100278 -369.745733) (xy 364.072982 -369.697098) (xy 364.053059 -369.645007) (xy 364.040933 -369.59057)
			(xy 364.036862 -369.534948) (xy 355.596444 -369.534948) (xy 366.798352 -380.736856) (xy 392.535918 -380.736856)
			(xy 392.563392 -380.737344) (xy 392.617734 -380.745469) (xy 392.670265 -380.761581) (xy 392.719818 -380.785321)
			(xy 392.765293 -380.816163) (xy 392.785854 -380.834392) (xy 407.150316 -380.834392) (xy 409.680918 -378.304044)
			(xy 409.701767 -378.283916) (xy 409.748615 -378.24981) (xy 409.800224 -378.223456) (xy 409.855321 -378.205501)
			(xy 409.912548 -378.19639) (xy 409.941522 -378.19584) (xy 410.286962 -378.19584) (xy 410.73705 -377.746006)
			(xy 410.747089 -377.735274) (xy 410.761093 -377.709452) (xy 410.767182 -377.680714) (xy 410.764853 -377.651431)
			(xy 410.754298 -377.624018) (xy 410.736387 -377.600734) (xy 410.712599 -377.5835) (xy 410.684893 -377.573737)
			(xy 410.670248 -377.572524) (xy 375.184924 -377.572524) (xy 375.16086 -377.571318) (xy 375.113806 -377.560989)
			(xy 375.069538 -377.541983) (xy 375.029642 -377.514982) (xy 375.012204 -377.498356) (xy 365.411766 -367.897664)
			(xy 358.112822 -367.897664) (xy 358.088758 -367.896458) (xy 358.041703 -367.88613) (xy 357.997434 -367.867126)
			(xy 357.957534 -367.840128) (xy 357.940102 -367.823496) (xy 357.403146 -367.286286) (xy 357.081836 -366.964976)
			(xy 357.071535 -366.95597) (xy 357.0473 -366.94329) (xy 357.02057 -366.937497) (xy 356.99326 -366.939007)
			(xy 356.967331 -366.94771) (xy 356.944642 -366.962984) (xy 356.92682 -366.983731) (xy 356.915144 -367.008465)
			(xy 356.912418 -367.021872) (xy 356.907409 -367.048098) (xy 356.891026 -367.098915) (xy 356.867717 -367.14695)
			(xy 356.837936 -367.191266) (xy 356.802266 -367.230995) (xy 356.761405 -367.265362) (xy 356.71615 -367.293695)
			(xy 356.667387 -367.31544) (xy 356.616067 -367.330172) (xy 356.563194 -367.337604) (xy 356.536498 -367.338102)
			(xy 356.510119 -367.337657) (xy 356.457864 -367.330393) (xy 356.407107 -367.316003) (xy 356.358815 -367.294762)
			(xy 356.313907 -367.267075) (xy 356.273238 -367.233468) (xy 356.237584 -367.194582) (xy 356.207624 -367.151157)
			(xy 356.195376 -367.12779) (xy 356.188674 -367.115431) (xy 356.169699 -367.094703) (xy 356.145785 -367.079941)
			(xy 356.118749 -367.072269) (xy 356.090647 -367.072269) (xy 356.063611 -367.079941) (xy 356.039697 -367.094703)
			(xy 356.020722 -367.115431) (xy 356.01402 -367.12779) (xy 356.001776 -367.151159) (xy 355.971819 -367.194585)
			(xy 355.936166 -367.233472) (xy 355.895497 -367.267077) (xy 355.850587 -367.294761) (xy 355.802292 -367.315995)
			(xy 355.751533 -367.330376) (xy 355.699277 -367.337628) (xy 355.672898 -367.338102) (xy 355.645647 -367.337616)
			(xy 355.591701 -367.329859) (xy 355.539407 -367.314504) (xy 355.489831 -367.291864) (xy 355.443981 -367.262398)
			(xy 355.402792 -367.226707) (xy 355.367101 -367.185517) (xy 355.337636 -367.139668) (xy 355.314995 -367.090091)
			(xy 355.29964 -367.037797) (xy 355.291884 -366.983851) (xy 355.291884 -366.929349) (xy 355.29964 -366.875403)
			(xy 355.314995 -366.823109) (xy 355.337636 -366.773532) (xy 355.367101 -366.727683) (xy 355.402792 -366.686493)
			(xy 355.443981 -366.650802) (xy 355.489831 -366.621336) (xy 355.539407 -366.598696) (xy 355.591701 -366.583341)
			(xy 355.645647 -366.575584) (xy 355.672898 -366.575086) (xy 355.699277 -366.575531) (xy 355.751533 -366.582795)
			(xy 355.80229 -366.597183) (xy 355.850584 -366.618423) (xy 355.895493 -366.64611) (xy 355.936163 -366.679716)
			(xy 355.971818 -366.718602) (xy 356.00178 -366.762026) (xy 356.01402 -366.785398) (xy 356.020722 -366.797757)
			(xy 356.039697 -366.818485) (xy 356.063611 -366.833247) (xy 356.090647 -366.840919) (xy 356.118749 -366.840919)
			(xy 356.145785 -366.833247) (xy 356.169699 -366.818485) (xy 356.188674 -366.797757) (xy 356.195376 -366.785398)
			(xy 356.20886 -366.759723) (xy 356.242407 -366.712421) (xy 356.282728 -366.670742) (xy 356.328894 -366.635648)
			(xy 356.37984 -366.607947) (xy 356.434393 -366.588278) (xy 356.491295 -366.577093) (xy 356.520242 -366.57534)
			(xy 356.535139 -366.574165) (xy 356.563327 -366.564289) (xy 356.587457 -366.546687) (xy 356.605467 -366.52286)
			(xy 356.615821 -366.494844) (xy 356.617634 -366.465031) (xy 356.61473 -366.450372) (xy 356.610582 -366.434113)
			(xy 356.606119 -366.400856) (xy 356.60584 -366.384078) (xy 356.60584 -363.324394) (xy 355.333808 -362.052362)
			(xy 355.31655 -362.034267) (xy 355.288737 -361.992721) (xy 355.269558 -361.946551) (xy 355.259747 -361.897527)
			(xy 355.259132 -361.87253) (xy 355.259132 -355.993192) (xy 355.259765 -355.968194) (xy 355.269557 -355.919165)
			(xy 355.288725 -355.872989) (xy 355.316532 -355.831438) (xy 355.333808 -355.81336) (xy 356.694232 -354.452936)
			(xy 356.712329 -354.435684) (xy 356.753877 -354.407884) (xy 356.800048 -354.388718) (xy 356.849069 -354.378925)
			(xy 356.874064 -354.37826) (xy 357.986584 -354.37826) (xy 357.986584 -353.954588) (xy 358.28224 -353.658932)
			(xy 358.347518 -353.658932) (xy 358.428036 -353.565968) (xy 358.424734 -353.542854) (xy 358.422944 -353.529464)
			(xy 358.421037 -353.502515) (xy 358.420924 -353.489006) (xy 358.420924 -353.488498) (xy 358.421387 -353.461246)
			(xy 358.429145 -353.407297) (xy 358.444501 -353.355001) (xy 358.467144 -353.305423) (xy 358.496613 -353.259573)
			(xy 358.532307 -353.218383) (xy 358.5735 -353.182693) (xy 358.619353 -353.153228) (xy 358.668933 -353.13059)
			(xy 358.72123 -353.115238) (xy 358.77518 -353.107485) (xy 358.802432 -353.10699) (xy 358.829993 -353.107477)
			(xy 358.88454 -353.11541) (xy 358.937379 -353.131106) (xy 358.987411 -353.15424) (xy 359.033595 -353.184329)
			(xy 359.074971 -353.220749) (xy 359.110678 -353.262741) (xy 359.125774 -353.285806) (xy 359.134581 -353.297891)
			(xy 359.157778 -353.316736) (xy 359.185442 -353.328048) (xy 359.215197 -353.330856) (xy 359.244489 -353.324919)
			(xy 359.270803 -353.310747) (xy 359.28173 -353.300538) (xy 359.434638 -353.14763) (xy 361.254802 -353.14763)
			(xy 361.255056 -353.162108) (xy 361.287369 -353.170661) (xy 361.35005 -353.193884) (xy 361.409815 -353.223823)
			(xy 361.465948 -353.260118) (xy 361.517775 -353.302334) (xy 361.564674 -353.349965) (xy 361.606082 -353.40244)
			(xy 361.641504 -353.459128) (xy 361.670513 -353.51935) (xy 361.68203 -353.550728) (xy 361.68711 -353.565714)
			(xy 361.736894 -353.602036) (xy 361.760516 -353.595432) (xy 361.795138 -353.586342) (xy 361.865878 -353.575381)
			(xy 361.937415 -353.572777) (xy 362.008764 -353.578569) (xy 362.078945 -353.592675) (xy 362.14699 -353.614903)
			(xy 362.211965 -353.644945) (xy 362.272975 -353.682389) (xy 362.329181 -353.726719) (xy 362.354876 -353.751642)
			(xy 362.7882 -354.184966) (xy 362.7882 -354.687886) (xy 364.22584 -354.687886) (xy 364.226278 -354.661506)
			(xy 364.233533 -354.609247) (xy 364.247918 -354.558486) (xy 364.269157 -354.51019) (xy 364.296845 -354.46528)
			(xy 364.330456 -354.424611) (xy 364.369348 -354.38896) (xy 364.41278 -354.359006) (xy 364.436152 -354.346764)
			(xy 364.448524 -354.340084) (xy 364.469257 -354.321106) (xy 364.484021 -354.297188) (xy 364.491693 -354.270148)
			(xy 364.491692 -354.24204) (xy 364.484016 -354.215001) (xy 364.469249 -354.191084) (xy 364.448514 -354.172109)
			(xy 364.436152 -354.165408) (xy 364.412765 -354.153197) (xy 364.369342 -354.123229) (xy 364.330458 -354.087569)
			(xy 364.296855 -354.046894) (xy 364.26917 -354.001981) (xy 364.247932 -353.953685) (xy 364.233546 -353.902924)
			(xy 364.226284 -353.850666) (xy 364.22584 -353.824286) (xy 364.226326 -353.797035) (xy 364.234082 -353.743087)
			(xy 364.249437 -353.690792) (xy 364.272079 -353.641215) (xy 364.301545 -353.595365) (xy 364.337236 -353.554174)
			(xy 364.378427 -353.518483) (xy 364.424277 -353.489017) (xy 364.473854 -353.466375) (xy 364.526149 -353.45102)
			(xy 364.580097 -353.443264) (xy 364.634599 -353.443264) (xy 364.688547 -353.45102) (xy 364.740842 -353.466375)
			(xy 364.790419 -353.489017) (xy 364.836269 -353.518483) (xy 364.87746 -353.554174) (xy 364.913151 -353.595365)
			(xy 364.942617 -353.641215) (xy 364.965259 -353.690792) (xy 364.980614 -353.743087) (xy 364.98776 -353.79279)
			(xy 366.64722 -353.79279) (xy 366.651291 -353.737168) (xy 366.663417 -353.682731) (xy 366.68334 -353.63064)
			(xy 366.710636 -353.582005) (xy 366.744722 -353.537862) (xy 366.784871 -353.499153) (xy 366.830229 -353.466702)
			(xy 366.879829 -353.441201) (xy 366.932613 -353.423194) (xy 366.987456 -353.413064) (xy 367.04319 -353.411027)
			(xy 367.098627 -353.417127) (xy 367.152584 -353.431233) (xy 367.203913 -353.453045) (xy 367.251519 -353.482099)
			(xy 367.294387 -353.517774) (xy 367.331604 -353.559311) (xy 367.362377 -353.605824) (xy 367.386049 -353.656321)
			(xy 367.402117 -353.709728) (xy 367.410237 -353.764904) (xy 367.410746 -353.79279) (xy 367.410237 -353.820676)
			(xy 367.402117 -353.875852) (xy 367.386049 -353.929259) (xy 367.362377 -353.979756) (xy 367.331604 -354.026269)
			(xy 367.294387 -354.067806) (xy 367.251519 -354.103481) (xy 367.203913 -354.132535) (xy 367.152584 -354.154347)
			(xy 367.098627 -354.168453) (xy 367.04319 -354.174553) (xy 366.987456 -354.172516) (xy 366.932613 -354.162386)
			(xy 366.879829 -354.144379) (xy 366.830229 -354.118878) (xy 366.784871 -354.086427) (xy 366.744722 -354.047718)
			(xy 366.710636 -354.003575) (xy 366.68334 -353.95494) (xy 366.663417 -353.902849) (xy 366.651291 -353.848412)
			(xy 366.64722 -353.79279) (xy 364.98776 -353.79279) (xy 364.98837 -353.797035) (xy 364.988856 -353.824286)
			(xy 364.988425 -353.850666) (xy 364.981162 -353.902922) (xy 364.966772 -353.953681) (xy 364.945531 -354.001975)
			(xy 364.917841 -354.046884) (xy 364.884232 -354.087552) (xy 364.845342 -354.123205) (xy 364.801914 -354.153164)
			(xy 364.778544 -354.165408) (xy 364.766197 -354.17213) (xy 364.745467 -354.191101) (xy 364.730705 -354.215011)
			(xy 364.723031 -354.242044) (xy 364.72303 -354.270144) (xy 364.7307 -354.297177) (xy 364.745459 -354.321089)
			(xy 364.766186 -354.340063) (xy 364.778544 -354.346764) (xy 364.801919 -354.358998) (xy 364.845341 -354.388962)
			(xy 364.884225 -354.42462) (xy 364.91783 -354.465291) (xy 364.945516 -354.5102) (xy 364.966756 -354.558494)
			(xy 364.981145 -354.609252) (xy 364.98841 -354.661507) (xy 364.988856 -354.687886) (xy 364.98837 -354.715137)
			(xy 364.980614 -354.769085) (xy 364.965259 -354.82138) (xy 364.942617 -354.870957) (xy 364.913151 -354.916807)
			(xy 364.87746 -354.957998) (xy 364.836269 -354.993689) (xy 364.790419 -355.023155) (xy 364.740842 -355.045797)
			(xy 364.688547 -355.061152) (xy 364.634599 -355.068908) (xy 364.580097 -355.068908) (xy 364.526149 -355.061152)
			(xy 364.473854 -355.045797) (xy 364.424277 -355.023155) (xy 364.378427 -354.993689) (xy 364.337236 -354.957998)
			(xy 364.301545 -354.916807) (xy 364.272079 -354.870957) (xy 364.249437 -354.82138) (xy 364.234082 -354.769085)
			(xy 364.226326 -354.715137) (xy 364.22584 -354.687886) (xy 362.7882 -354.687886) (xy 362.7882 -355.288596)
			(xy 362.821728 -355.292152) (xy 362.828078 -355.292152) (xy 362.828078 -355.668072) (xy 366.060736 -355.668072)
			(xy 367.879884 -353.848924) (xy 367.89798 -353.831669) (xy 367.939526 -353.803862) (xy 367.985697 -353.784689)
			(xy 368.03472 -353.774887) (xy 368.059716 -353.774248) (xy 371.303804 -353.774248) (xy 371.328802 -353.774881)
			(xy 371.377831 -353.784673) (xy 371.424007 -353.803841) (xy 371.465558 -353.831649) (xy 371.483636 -353.848924)
			(xy 372.150132 -354.51542) (xy 373.549418 -354.51542) (xy 373.574401 -354.516033) (xy 373.623408 -354.525776)
			(xy 373.669576 -354.544886) (xy 373.711133 -354.572628) (xy 373.72925 -354.589842) (xy 374.788176 -355.648768)
			(xy 379.182122 -355.648768) (xy 379.207104 -355.649381) (xy 379.25611 -355.659127) (xy 379.302275 -355.67824)
			(xy 379.343828 -355.705986) (xy 379.361954 -355.72319) (xy 383.218764 -359.579926) (xy 409.33192 -359.579926)
			(xy 409.335991 -359.524304) (xy 409.348117 -359.469867) (xy 409.36804 -359.417776) (xy 409.395336 -359.369141)
			(xy 409.429422 -359.324998) (xy 409.469571 -359.286289) (xy 409.514929 -359.253838) (xy 409.564529 -359.228337)
			(xy 409.617313 -359.21033) (xy 409.672156 -359.2002) (xy 409.72789 -359.198163) (xy 409.783327 -359.204263)
			(xy 409.837284 -359.218369) (xy 409.888613 -359.240181) (xy 409.936219 -359.269235) (xy 409.979087 -359.30491)
			(xy 410.016304 -359.346447) (xy 410.047077 -359.39296) (xy 410.070749 -359.443457) (xy 410.086817 -359.496864)
			(xy 410.094937 -359.55204) (xy 410.095446 -359.579926) (xy 410.094937 -359.607812) (xy 410.086817 -359.662988)
			(xy 410.070749 -359.716395) (xy 410.047077 -359.766892) (xy 410.016304 -359.813405) (xy 409.979087 -359.854942)
			(xy 409.936219 -359.890617) (xy 409.888613 -359.919671) (xy 409.837284 -359.941483) (xy 409.783327 -359.955589)
			(xy 409.72789 -359.961689) (xy 409.672156 -359.959652) (xy 409.617313 -359.949522) (xy 409.564529 -359.931515)
			(xy 409.514929 -359.906014) (xy 409.469571 -359.873563) (xy 409.429422 -359.834854) (xy 409.395336 -359.790711)
			(xy 409.36804 -359.742076) (xy 409.348117 -359.689985) (xy 409.335991 -359.635548) (xy 409.33192 -359.579926)
			(xy 383.218764 -359.579926) (xy 384.661302 -361.022436) (xy 409.844923 -361.022436) (xy 409.844923 -360.967964)
			(xy 409.852676 -360.914047) (xy 409.868023 -360.861782) (xy 409.890653 -360.812233) (xy 409.920105 -360.76641)
			(xy 409.955779 -360.725245) (xy 409.996948 -360.689576) (xy 410.042775 -360.66013) (xy 410.092327 -360.637506)
			(xy 410.144594 -360.622165) (xy 410.198512 -360.614419) (xy 410.225748 -360.61396) (xy 410.565346 -360.61396)
			(xy 410.595319 -360.614486) (xy 410.654534 -360.623804) (xy 410.71156 -360.642281) (xy 410.764988 -360.669461)
			(xy 410.813499 -360.704674) (xy 410.835094 -360.725466) (xy 411.46603 -361.356402) (xy 411.486759 -361.37805)
			(xy 411.521951 -361.426561) (xy 411.549126 -361.479977) (xy 411.567614 -361.536986) (xy 411.576961 -361.596184)
			(xy 411.577536 -361.62615) (xy 411.577536 -363.554264) (xy 412.204154 -363.554264) (xy 412.204632 -363.526223)
			(xy 412.212837 -363.470745) (xy 412.229067 -363.417063) (xy 412.252972 -363.366331) (xy 412.284039 -363.31964)
			(xy 412.302452 -363.298486) (xy 412.312086 -363.287035) (xy 412.324872 -363.259996) (xy 412.329261 -363.23041)
			(xy 412.324878 -363.200824) (xy 412.312097 -363.173783) (xy 412.302452 -363.162342) (xy 412.284023 -363.141199)
			(xy 412.252931 -363.094519) (xy 412.229018 -363.043786) (xy 412.2128 -362.990095) (xy 412.204627 -362.934608)
			(xy 412.204154 -362.906564) (xy 412.20464 -362.879313) (xy 412.212396 -362.825365) (xy 412.227751 -362.77307)
			(xy 412.250393 -362.723493) (xy 412.279859 -362.677643) (xy 412.31555 -362.636452) (xy 412.356741 -362.600761)
			(xy 412.402591 -362.571295) (xy 412.452168 -362.548653) (xy 412.504463 -362.533298) (xy 412.558411 -362.525542)
			(xy 412.612913 -362.525542) (xy 412.666861 -362.533298) (xy 412.719156 -362.548653) (xy 412.768733 -362.571295)
			(xy 412.814583 -362.600761) (xy 412.855774 -362.636452) (xy 412.891465 -362.677643) (xy 412.920931 -362.723493)
			(xy 412.943573 -362.77307) (xy 412.958928 -362.825365) (xy 412.966684 -362.879313) (xy 412.96717 -362.906564)
			(xy 412.966669 -362.934604) (xy 412.958472 -362.990082) (xy 412.942248 -363.043765) (xy 412.918348 -363.094497)
			(xy 412.887284 -363.141188) (xy 412.868872 -363.162342) (xy 412.864368 -363.167676) (xy 420.18153 -363.167676)
			(xy 420.185601 -363.112054) (xy 420.197727 -363.057617) (xy 420.21765 -363.005526) (xy 420.244946 -362.956891)
			(xy 420.279032 -362.912748) (xy 420.319181 -362.874039) (xy 420.364539 -362.841588) (xy 420.414139 -362.816087)
			(xy 420.466923 -362.79808) (xy 420.521766 -362.78795) (xy 420.5775 -362.785913) (xy 420.632937 -362.792013)
			(xy 420.686894 -362.806119) (xy 420.738223 -362.827931) (xy 420.785829 -362.856985) (xy 420.828697 -362.89266)
			(xy 420.865914 -362.934197) (xy 420.896687 -362.98071) (xy 420.920359 -363.031207) (xy 420.936427 -363.084614)
			(xy 420.944547 -363.13979) (xy 420.945056 -363.167676) (xy 420.944547 -363.195562) (xy 420.936427 -363.250738)
			(xy 420.920359 -363.304145) (xy 420.896687 -363.354642) (xy 420.865914 -363.401155) (xy 420.828697 -363.442692)
			(xy 420.785829 -363.478367) (xy 420.738223 -363.507421) (xy 420.686894 -363.529233) (xy 420.632937 -363.543339)
			(xy 420.591359 -363.547914) (xy 421.892476 -363.547914) (xy 421.892932 -363.520543) (xy 421.900749 -363.466363)
			(xy 421.91624 -363.413859) (xy 421.939084 -363.364112) (xy 421.968813 -363.318147) (xy 421.986456 -363.297216)
			(xy 421.995675 -363.285877) (xy 422.007847 -363.259322) (xy 422.01202 -363.230411) (xy 422.007853 -363.201498)
			(xy 421.995686 -363.174941) (xy 421.986456 -363.163612) (xy 421.968802 -363.142692) (xy 421.939094 -363.096715)
			(xy 421.916261 -363.046965) (xy 421.900773 -362.994462) (xy 421.892948 -362.940284) (xy 421.892476 -362.912914)
			(xy 421.892962 -362.885663) (xy 421.900718 -362.831715) (xy 421.916073 -362.77942) (xy 421.938715 -362.729843)
			(xy 421.968181 -362.683993) (xy 422.003872 -362.642802) (xy 422.045063 -362.607111) (xy 422.090913 -362.577645)
			(xy 422.14049 -362.555003) (xy 422.192785 -362.539648) (xy 422.246733 -362.531892) (xy 422.301235 -362.531892)
			(xy 422.355183 -362.539648) (xy 422.407478 -362.555003) (xy 422.457055 -362.577645) (xy 422.502905 -362.607111)
			(xy 422.544096 -362.642802) (xy 422.579787 -362.683993) (xy 422.609253 -362.729843) (xy 422.631895 -362.77942)
			(xy 422.64725 -362.831715) (xy 422.655006 -362.885663) (xy 422.655492 -362.912914) (xy 422.655036 -362.940285)
			(xy 422.647216 -362.994464) (xy 422.631725 -363.046968) (xy 422.608881 -363.096714) (xy 422.579154 -363.142681)
			(xy 422.561512 -363.163612) (xy 422.555283 -363.171232) (xy 429.73955 -363.171232) (xy 429.743621 -363.11561)
			(xy 429.755747 -363.061173) (xy 429.77567 -363.009082) (xy 429.802966 -362.960447) (xy 429.837052 -362.916304)
			(xy 429.877201 -362.877595) (xy 429.922559 -362.845144) (xy 429.972159 -362.819643) (xy 430.024943 -362.801636)
			(xy 430.079786 -362.791506) (xy 430.13552 -362.789469) (xy 430.190957 -362.795569) (xy 430.244914 -362.809675)
			(xy 430.296243 -362.831487) (xy 430.343849 -362.860541) (xy 430.386717 -362.896216) (xy 430.423934 -362.937753)
			(xy 430.454707 -362.984266) (xy 430.478379 -363.034763) (xy 430.494447 -363.08817) (xy 430.502567 -363.143346)
			(xy 430.503076 -363.171232) (xy 430.502567 -363.199118) (xy 430.494447 -363.254294) (xy 430.478379 -363.307701)
			(xy 430.454707 -363.358198) (xy 430.423934 -363.404711) (xy 430.386717 -363.446248) (xy 430.343849 -363.481923)
			(xy 430.296243 -363.510977) (xy 430.244914 -363.532789) (xy 430.190957 -363.546895) (xy 430.13552 -363.552995)
			(xy 430.079786 -363.550958) (xy 430.024943 -363.540828) (xy 429.972159 -363.522821) (xy 429.922559 -363.49732)
			(xy 429.877201 -363.464869) (xy 429.837052 -363.42616) (xy 429.802966 -363.382017) (xy 429.77567 -363.333382)
			(xy 429.755747 -363.281291) (xy 429.743621 -363.226854) (xy 429.73955 -363.171232) (xy 422.555283 -363.171232)
			(xy 422.552261 -363.174929) (xy 422.540084 -363.20149) (xy 422.535913 -363.230411) (xy 422.54009 -363.25933)
			(xy 422.552272 -363.285889) (xy 422.561512 -363.297216) (xy 422.579127 -363.318167) (xy 422.608842 -363.364135)
			(xy 422.631682 -363.413878) (xy 422.647179 -363.466374) (xy 422.655014 -363.520546) (xy 422.655492 -363.547914)
			(xy 422.655006 -363.575165) (xy 422.64725 -363.629113) (xy 422.631895 -363.681408) (xy 422.609253 -363.730985)
			(xy 422.579787 -363.776835) (xy 422.544096 -363.818026) (xy 422.502905 -363.853717) (xy 422.457055 -363.883183)
			(xy 422.407478 -363.905825) (xy 422.355183 -363.92118) (xy 422.301235 -363.928936) (xy 422.246733 -363.928936)
			(xy 422.192785 -363.92118) (xy 422.14049 -363.905825) (xy 422.090913 -363.883183) (xy 422.045063 -363.853717)
			(xy 422.003872 -363.818026) (xy 421.968181 -363.776835) (xy 421.938715 -363.730985) (xy 421.916073 -363.681408)
			(xy 421.900718 -363.629113) (xy 421.892962 -363.575165) (xy 421.892476 -363.547914) (xy 420.591359 -363.547914)
			(xy 420.5775 -363.549439) (xy 420.521766 -363.547402) (xy 420.466923 -363.537272) (xy 420.414139 -363.519265)
			(xy 420.364539 -363.493764) (xy 420.319181 -363.461313) (xy 420.279032 -363.422604) (xy 420.244946 -363.378461)
			(xy 420.21765 -363.329826) (xy 420.197727 -363.277735) (xy 420.185601 -363.223298) (xy 420.18153 -363.167676)
			(xy 412.864368 -363.167676) (xy 412.859217 -363.173775) (xy 412.846444 -363.200822) (xy 412.842063 -363.23041)
			(xy 412.84645 -363.259998) (xy 412.859228 -363.287043) (xy 412.868872 -363.298486) (xy 412.887318 -363.319615)
			(xy 412.918407 -363.366299) (xy 412.942317 -363.417036) (xy 412.958531 -363.470729) (xy 412.966699 -363.526219)
			(xy 412.96717 -363.554264) (xy 412.966684 -363.581515) (xy 412.958928 -363.635463) (xy 412.943573 -363.687758)
			(xy 412.920931 -363.737335) (xy 412.891465 -363.783185) (xy 412.855774 -363.824376) (xy 412.814583 -363.860067)
			(xy 412.768733 -363.889533) (xy 412.719156 -363.912175) (xy 412.666861 -363.92753) (xy 412.612913 -363.935286)
			(xy 412.558411 -363.935286) (xy 412.504463 -363.92753) (xy 412.452168 -363.912175) (xy 412.402591 -363.889533)
			(xy 412.356741 -363.860067) (xy 412.31555 -363.824376) (xy 412.279859 -363.783185) (xy 412.250393 -363.737335)
			(xy 412.227751 -363.687758) (xy 412.212396 -363.635463) (xy 412.20464 -363.581515) (xy 412.204154 -363.554264)
			(xy 411.577536 -363.554264) (xy 411.577536 -363.9505) (xy 416.452737 -363.9505) (xy 416.456906 -363.894879)
			(xy 416.469318 -363.840501) (xy 416.489697 -363.788581) (xy 416.517587 -363.740278) (xy 416.552365 -363.696672)
			(xy 416.593254 -363.658736) (xy 416.639341 -363.627319) (xy 416.689595 -363.603122) (xy 416.742895 -363.586686)
			(xy 416.79805 -363.578378) (xy 416.825938 -363.577886) (xy 416.853268 -363.578397) (xy 416.907345 -363.586362)
			(xy 416.959677 -363.602145) (xy 417.009141 -363.625407) (xy 417.054673 -363.655648) (xy 417.095297 -363.692219)
			(xy 417.13014 -363.734335) (xy 417.144708 -363.757464) (xy 417.152655 -363.769672) (xy 417.174117 -363.789348)
			(xy 417.200265 -363.802157) (xy 417.228966 -363.807056) (xy 417.257882 -363.803645) (xy 417.271454 -363.798358)
			(xy 417.29466 -363.788857) (xy 417.342995 -363.775511) (xy 417.392686 -363.768787) (xy 417.417758 -363.768386)
			(xy 417.442827 -363.768806) (xy 417.49251 -363.775558) (xy 417.540845 -363.788892) (xy 417.564062 -363.798358)
			(xy 417.577647 -363.803579) (xy 417.606542 -363.806943) (xy 417.635215 -363.802036) (xy 417.661347 -363.789254)
			(xy 417.682824 -363.769633) (xy 417.690808 -363.757464) (xy 417.705377 -363.734333) (xy 417.74022 -363.692212)
			(xy 417.780843 -363.655633) (xy 417.826374 -363.625382) (xy 417.875836 -363.602106) (xy 417.928167 -363.586306)
			(xy 417.982246 -363.57832) (xy 418.03691 -363.57832) (xy 418.090989 -363.586306) (xy 418.14332 -363.602106)
			(xy 418.192782 -363.625382) (xy 418.238313 -363.655633) (xy 418.278936 -363.692212) (xy 418.313779 -363.734333)
			(xy 418.328348 -363.757464) (xy 418.336257 -363.7697) (xy 418.35773 -363.789375) (xy 418.383887 -363.802181)
			(xy 418.412598 -363.807072) (xy 418.44152 -363.803652) (xy 418.455094 -363.798358) (xy 418.478307 -363.788876)
			(xy 418.526638 -363.775523) (xy 418.576327 -363.768791) (xy 418.601398 -363.768386) (xy 418.627622 -363.768832)
			(xy 418.679552 -363.776174) (xy 418.72994 -363.790728) (xy 418.777787 -363.812206) (xy 418.822149 -363.840183)
			(xy 418.862149 -363.874105) (xy 418.896994 -363.913303) (xy 418.925997 -363.957001) (xy 418.937694 -363.980476)
			(xy 418.9441 -363.992667) (xy 418.962164 -364.013433) (xy 418.985123 -364.028613) (xy 419.011303 -364.037104)
			(xy 419.038801 -364.038288) (xy 419.065615 -364.032078) (xy 419.089792 -364.018927) (xy 419.1 -364.009686)
			(xy 419.121475 -363.98975) (xy 419.169373 -363.956) (xy 419.221866 -363.929965) (xy 419.277721 -363.912257)
			(xy 419.335625 -363.903292) (xy 419.364922 -363.902752) (xy 419.382941 -363.902975) (xy 419.418816 -363.906408)
			(xy 419.43655 -363.90961) (xy 419.451762 -363.911934) (xy 419.482317 -363.908418) (xy 419.510438 -363.895963)
			(xy 419.533574 -363.875698) (xy 419.549626 -363.849463) (xy 419.553898 -363.83468) (xy 419.561329 -363.807646)
			(xy 419.582954 -363.75592) (xy 419.611913 -363.707915) (xy 419.647584 -363.664662) (xy 419.689199 -363.627094)
			(xy 419.735863 -363.596019) (xy 419.78657 -363.572104) (xy 419.840231 -363.555866) (xy 419.89569 -363.547652)
			(xy 419.923722 -363.547152) (xy 419.950972 -363.547657) (xy 420.004917 -363.555416) (xy 420.057209 -363.570772)
			(xy 420.106783 -363.593412) (xy 420.152632 -363.622877) (xy 420.193821 -363.658566) (xy 420.229512 -363.699754)
			(xy 420.258979 -363.745601) (xy 420.281622 -363.795174) (xy 420.29698 -363.847465) (xy 420.304742 -363.90141)
			(xy 420.30523 -363.92866) (xy 420.304831 -363.9505) (xy 426.141163 -363.9505) (xy 426.145331 -363.894891)
			(xy 426.157739 -363.840523) (xy 426.178111 -363.788612) (xy 426.205992 -363.740317) (xy 426.240759 -363.696717)
			(xy 426.281635 -363.658784) (xy 426.327709 -363.627368) (xy 426.37795 -363.603168) (xy 426.431236 -363.586726)
			(xy 426.486377 -363.57841) (xy 426.51426 -363.577886) (xy 426.541591 -363.57838) (xy 426.595669 -363.586348)
			(xy 426.648001 -363.602134) (xy 426.697465 -363.625399) (xy 426.742997 -363.655643) (xy 426.78362 -363.692216)
			(xy 426.818463 -363.734334) (xy 426.83303 -363.757464) (xy 426.840956 -363.769687) (xy 426.862424 -363.789363)
			(xy 426.888577 -363.80217) (xy 426.917283 -363.807065) (xy 426.946203 -363.803649) (xy 426.959776 -363.798358)
			(xy 426.982991 -363.788881) (xy 427.031321 -363.775526) (xy 427.081009 -363.768793) (xy 427.10608 -363.768386)
			(xy 427.131148 -363.768832) (xy 427.180831 -363.775573) (xy 427.229166 -363.788896) (xy 427.252384 -363.798358)
			(xy 427.265997 -363.803497) (xy 427.294878 -363.806878) (xy 427.323541 -363.801989) (xy 427.349668 -363.789227)
			(xy 427.371145 -363.769625) (xy 427.37913 -363.757464) (xy 427.393699 -363.734333) (xy 427.428542 -363.692212)
			(xy 427.469165 -363.655633) (xy 427.514696 -363.625382) (xy 427.564158 -363.602106) (xy 427.616489 -363.586306)
			(xy 427.670568 -363.57832) (xy 427.725232 -363.57832) (xy 427.779311 -363.586306) (xy 427.831642 -363.602106)
			(xy 427.881104 -363.625382) (xy 427.926635 -363.655633) (xy 427.967258 -363.692212) (xy 428.002101 -363.734333)
			(xy 428.01667 -363.757464) (xy 428.024558 -363.769715) (xy 428.046036 -363.78939) (xy 428.0722 -363.802194)
			(xy 428.100915 -363.807082) (xy 428.129841 -363.803655) (xy 428.143416 -363.798358) (xy 428.166626 -363.788869)
			(xy 428.214959 -363.775518) (xy 428.264648 -363.76879) (xy 428.28972 -363.768386) (xy 428.316563 -363.768828)
			(xy 428.369694 -363.776536) (xy 428.421169 -363.791788) (xy 428.469922 -363.814269) (xy 428.514944 -363.843513)
			(xy 428.555304 -363.878916) (xy 428.590165 -363.919745) (xy 428.618807 -363.965153) (xy 428.640635 -364.014202)
			(xy 428.648368 -364.039912) (xy 428.653106 -364.054383) (xy 428.669606 -364.079945) (xy 428.692905 -364.099513)
			(xy 428.720934 -364.111348) (xy 428.751206 -364.1144) (xy 428.781034 -364.108398) (xy 428.794672 -364.101634)
			(xy 428.822813 -364.086991) (xy 428.882767 -364.066268) (xy 428.945327 -364.055774) (xy 428.977044 -364.055152)
			(xy 428.995063 -364.055372) (xy 429.030938 -364.058807) (xy 429.048672 -364.06201) (xy 429.063881 -364.064356)
			(xy 429.094438 -364.060834) (xy 429.122561 -364.048373) (xy 429.145697 -364.028104) (xy 429.161749 -364.001864)
			(xy 429.16602 -363.98708) (xy 429.173431 -363.960039) (xy 429.195057 -363.908313) (xy 429.224019 -363.860306)
			(xy 429.259692 -363.817054) (xy 429.30131 -363.779486) (xy 429.347976 -363.748411) (xy 429.398687 -363.724498)
			(xy 429.45235 -363.708261) (xy 429.507811 -363.700051) (xy 429.535844 -363.699552) (xy 429.563095 -363.700037)
			(xy 429.61704 -363.707798) (xy 429.669332 -363.723157) (xy 429.718907 -363.7458) (xy 429.764755 -363.775267)
			(xy 429.805944 -363.810959) (xy 429.841635 -363.852148) (xy 429.871102 -363.897996) (xy 429.893744 -363.947571)
			(xy 429.909103 -363.999864) (xy 429.916864 -364.053809) (xy 429.917352 -364.08106) (xy 429.916876 -364.108634)
			(xy 429.908928 -364.163207) (xy 429.893206 -364.216068) (xy 429.870038 -364.266114) (xy 429.839906 -364.312304)
			(xy 429.803439 -364.353675) (xy 429.782732 -364.37189) (xy 429.771872 -364.381828) (xy 429.755794 -364.406466)
			(xy 429.747403 -364.434664) (xy 429.747395 -364.464084) (xy 429.755772 -364.492287) (xy 429.771838 -364.516933)
			(xy 429.782732 -364.52683) (xy 429.803396 -364.54509) (xy 429.839856 -364.586457) (xy 429.869981 -364.632642)
			(xy 429.893143 -364.682683) (xy 429.908859 -364.735537) (xy 429.916801 -364.790103) (xy 429.916805 -364.845245)
			(xy 429.90887 -364.899812) (xy 429.893161 -364.952669) (xy 429.870006 -365.002713) (xy 429.839888 -365.048902)
			(xy 429.803433 -365.090273) (xy 429.782732 -365.10849) (xy 429.771872 -365.118428) (xy 429.755794 -365.143066)
			(xy 429.747403 -365.171264) (xy 429.747395 -365.200684) (xy 429.755772 -365.228887) (xy 429.771838 -365.253533)
			(xy 429.782732 -365.26343) (xy 429.803467 -365.281615) (xy 429.839934 -365.32299) (xy 429.870063 -365.369186)
			(xy 429.893224 -365.419239) (xy 429.908935 -365.472105) (xy 429.91687 -365.526684) (xy 429.917352 -365.55426)
			(xy 429.916785 -365.581508) (xy 429.909035 -365.635451) (xy 429.893687 -365.687741) (xy 429.871054 -365.737315)
			(xy 429.841596 -365.783164) (xy 429.805913 -365.824353) (xy 429.764731 -365.860045) (xy 429.718889 -365.889513)
			(xy 429.66932 -365.912158) (xy 429.617033 -365.927517) (xy 429.563092 -365.935279) (xy 429.535844 -365.935768)
			(xy 429.507989 -365.935229) (xy 429.452873 -365.927111) (xy 429.399522 -365.91107) (xy 429.349068 -365.887446)
			(xy 429.302582 -365.856741) (xy 429.261052 -365.819607) (xy 429.225359 -365.776832) (xy 429.196261 -365.729325)
			(xy 429.174375 -365.678093) (xy 429.166782 -365.651288) (xy 429.162503 -365.637174) (xy 429.147112 -365.612032)
			(xy 429.125194 -365.592318) (xy 429.098568 -365.579666) (xy 429.069441 -365.575125) (xy 429.054768 -365.576612)
			(xy 429.041752 -365.578282) (xy 429.015567 -365.580061) (xy 429.002444 -365.580168) (xy 428.988295 -365.58007)
			(xy 428.960072 -365.578039) (xy 428.946056 -365.576104) (xy 428.932707 -365.574531) (xy 428.906016 -365.577627)
			(xy 428.881063 -365.587594) (xy 428.859584 -365.603737) (xy 428.843071 -365.624934) (xy 428.832675 -365.64971)
			(xy 428.830486 -365.662972) (xy 428.826449 -365.690134) (xy 428.811471 -365.742967) (xy 428.789074 -365.793107)
			(xy 428.75972 -365.839519) (xy 428.724017 -365.881243) (xy 428.682701 -365.917419) (xy 428.636627 -365.947298)
			(xy 428.586745 -365.970264) (xy 428.534086 -365.985843) (xy 428.479738 -365.993712) (xy 428.45228 -365.994188)
			(xy 428.425027 -365.993741) (xy 428.371077 -365.985981) (xy 428.318781 -365.970622) (xy 428.269202 -365.947977)
			(xy 428.223351 -365.918507) (xy 428.18216 -365.882812) (xy 428.146469 -365.841617) (xy 428.117003 -365.795763)
			(xy 428.094364 -365.746182) (xy 428.07901 -365.693884) (xy 428.071256 -365.639933) (xy 428.070772 -365.61268)
			(xy 428.071303 -365.585108) (xy 428.079243 -365.530538) (xy 428.094956 -365.47768) (xy 428.118114 -365.427634)
			(xy 428.148235 -365.381443) (xy 428.18469 -365.340068) (xy 428.205392 -365.32185) (xy 428.21631 -365.311972)
			(xy 428.232382 -365.287316) (xy 428.240764 -365.259103) (xy 428.24076 -365.229671) (xy 428.232371 -365.20146)
			(xy 428.216292 -365.176809) (xy 428.205392 -365.16691) (xy 428.184681 -365.148699) (xy 428.148211 -365.10733)
			(xy 428.118079 -365.06114) (xy 428.094913 -365.011092) (xy 428.079197 -364.95823) (xy 428.071257 -364.903655)
			(xy 428.070772 -364.87608) (xy 428.071239 -364.849579) (xy 428.078582 -364.797089) (xy 428.093124 -364.746122)
			(xy 428.114584 -364.697659) (xy 428.142548 -364.652636) (xy 428.159164 -364.631986) (xy 428.168558 -364.619807)
			(xy 428.180349 -364.591418) (xy 428.183178 -364.560808) (xy 428.17679 -364.530739) (xy 428.161762 -364.503922)
			(xy 428.13945 -364.482778) (xy 428.12589 -364.475522) (xy 428.102212 -364.463399) (xy 428.058228 -364.433483)
			(xy 428.018943 -364.397619) (xy 427.985156 -364.356534) (xy 427.97095 -364.334044) (xy 427.963041 -364.321808)
			(xy 427.941569 -364.302132) (xy 427.915411 -364.289326) (xy 427.8867 -364.284434) (xy 427.857778 -364.287856)
			(xy 427.844204 -364.29315) (xy 427.820992 -364.302633) (xy 427.77266 -364.315986) (xy 427.722971 -364.322717)
			(xy 427.6979 -364.323122) (xy 427.672831 -364.32269) (xy 427.623148 -364.315945) (xy 427.574814 -364.302615)
			(xy 427.551596 -364.29315) (xy 427.537991 -364.287986) (xy 427.509106 -364.28461) (xy 427.480439 -364.289503)
			(xy 427.45431 -364.302271) (xy 427.432834 -364.32188) (xy 427.42485 -364.334044) (xy 427.410281 -364.357175)
			(xy 427.375438 -364.399296) (xy 427.334815 -364.435875) (xy 427.289284 -364.466126) (xy 427.239822 -364.489402)
			(xy 427.187491 -364.505202) (xy 427.133412 -364.513188) (xy 427.078748 -364.513188) (xy 427.024669 -364.505202)
			(xy 426.972338 -364.489402) (xy 426.922876 -364.466126) (xy 426.877345 -364.435875) (xy 426.836722 -364.399296)
			(xy 426.801879 -364.357175) (xy 426.78731 -364.334044) (xy 426.779344 -364.321849) (xy 426.757887 -364.302173)
			(xy 426.731745 -364.289362) (xy 426.703048 -364.284459) (xy 426.674135 -364.287865) (xy 426.660564 -364.29315)
			(xy 426.637357 -364.302646) (xy 426.589022 -364.315994) (xy 426.539332 -364.32272) (xy 426.51426 -364.323122)
			(xy 426.486377 -364.32259) (xy 426.431236 -364.314274) (xy 426.37795 -364.297832) (xy 426.327709 -364.273632)
			(xy 426.281635 -364.242216) (xy 426.240759 -364.204283) (xy 426.205992 -364.160683) (xy 426.178111 -364.112388)
			(xy 426.157739 -364.060477) (xy 426.145331 -364.006109) (xy 426.141163 -363.9505) (xy 420.304831 -363.9505)
			(xy 420.304726 -363.956233) (xy 420.29678 -364.010804) (xy 420.281062 -364.063662) (xy 420.257899 -364.113708)
			(xy 420.227774 -364.159899) (xy 420.191314 -364.201273) (xy 420.17061 -364.21949) (xy 420.159752 -364.229429)
			(xy 420.143677 -364.254067) (xy 420.135288 -364.282265) (xy 420.135281 -364.311684) (xy 420.143655 -364.339885)
			(xy 420.159718 -364.364532) (xy 420.17061 -364.37443) (xy 420.191275 -364.39269) (xy 420.227737 -364.434056)
			(xy 420.257864 -364.48024) (xy 420.281027 -364.530281) (xy 420.296744 -364.583136) (xy 420.304687 -364.637703)
			(xy 420.304691 -364.692845) (xy 420.296755 -364.747413) (xy 420.281046 -364.80027) (xy 420.257889 -364.850314)
			(xy 420.227769 -364.896503) (xy 420.191312 -364.937874) (xy 420.17061 -364.95609) (xy 420.159752 -364.966029)
			(xy 420.143677 -364.990667) (xy 420.136055 -365.016288) (xy 422.68343 -365.016288) (xy 422.687501 -364.960666)
			(xy 422.699627 -364.906229) (xy 422.71955 -364.854138) (xy 422.746846 -364.805503) (xy 422.780932 -364.76136)
			(xy 422.821081 -364.722651) (xy 422.866439 -364.6902) (xy 422.916039 -364.664699) (xy 422.968823 -364.646692)
			(xy 423.023666 -364.636562) (xy 423.0794 -364.634525) (xy 423.134837 -364.640625) (xy 423.188794 -364.654731)
			(xy 423.240123 -364.676543) (xy 423.287729 -364.705597) (xy 423.330597 -364.741272) (xy 423.367814 -364.782809)
			(xy 423.398587 -364.829322) (xy 423.422259 -364.879819) (xy 423.438327 -364.933226) (xy 423.446447 -364.988402)
			(xy 423.446956 -365.016288) (xy 423.446447 -365.044174) (xy 423.438327 -365.09935) (xy 423.422259 -365.152757)
			(xy 423.398587 -365.203254) (xy 423.367814 -365.249767) (xy 423.330597 -365.291304) (xy 423.287729 -365.326979)
			(xy 423.240123 -365.356033) (xy 423.188794 -365.377845) (xy 423.134837 -365.391951) (xy 423.0794 -365.398051)
			(xy 423.023666 -365.396014) (xy 422.968823 -365.385884) (xy 422.916039 -365.367877) (xy 422.866439 -365.342376)
			(xy 422.821081 -365.309925) (xy 422.780932 -365.271216) (xy 422.746846 -365.227073) (xy 422.71955 -365.178438)
			(xy 422.699627 -365.126347) (xy 422.687501 -365.07191) (xy 422.68343 -365.016288) (xy 420.136055 -365.016288)
			(xy 420.135288 -365.018865) (xy 420.135281 -365.048284) (xy 420.143655 -365.076485) (xy 420.159718 -365.101132)
			(xy 420.17061 -365.11103) (xy 420.191341 -365.12922) (xy 420.227809 -365.170593) (xy 420.257939 -365.216788)
			(xy 420.281101 -365.26684) (xy 420.296813 -365.319706) (xy 420.304748 -365.374284) (xy 420.30523 -365.40186)
			(xy 420.304708 -365.429111) (xy 420.296957 -365.483059) (xy 420.281607 -365.535354) (xy 420.258971 -365.584932)
			(xy 420.229509 -365.630785) (xy 420.193821 -365.671977) (xy 420.152634 -365.707672) (xy 420.106787 -365.737141)
			(xy 420.057212 -365.759785) (xy 420.004919 -365.775143) (xy 419.950973 -365.782903) (xy 419.923722 -365.783368)
			(xy 419.895866 -365.782849) (xy 419.840749 -365.774727) (xy 419.787398 -365.758683) (xy 419.736944 -365.735057)
			(xy 419.690459 -365.704349) (xy 419.648929 -365.667213) (xy 419.613236 -365.624437) (xy 419.584138 -365.576927)
			(xy 419.562253 -365.525694) (xy 419.55466 -365.498888) (xy 419.550403 -365.484766) (xy 419.535007 -365.459622)
			(xy 419.513085 -365.439908) (xy 419.486453 -365.427258) (xy 419.45732 -365.422722) (xy 419.442646 -365.424212)
			(xy 419.42963 -365.425885) (xy 419.403445 -365.427662) (xy 419.390322 -365.427768) (xy 419.361422 -365.427257)
			(xy 419.304278 -365.418587) (xy 419.27653 -365.410496) (xy 419.262999 -365.40669) (xy 419.234907 -365.405954)
			(xy 419.207676 -365.412891) (xy 419.183359 -365.426976) (xy 419.163794 -365.447148) (xy 419.150457 -365.471882)
			(xy 419.144354 -365.499313) (xy 419.144704 -365.513366) (xy 419.145466 -365.53648) (xy 419.14498 -365.563731)
			(xy 419.137224 -365.617679) (xy 419.121869 -365.669974) (xy 419.099227 -365.719551) (xy 419.069761 -365.765401)
			(xy 419.03407 -365.806592) (xy 418.992879 -365.842283) (xy 418.947029 -365.871749) (xy 418.897452 -365.894391)
			(xy 418.845157 -365.909746) (xy 418.791209 -365.917502) (xy 418.736707 -365.917502) (xy 418.682759 -365.909746)
			(xy 418.630464 -365.894391) (xy 418.580887 -365.871749) (xy 418.535037 -365.842283) (xy 418.493846 -365.806592)
			(xy 418.458155 -365.765401) (xy 418.428689 -365.719551) (xy 418.406047 -365.669974) (xy 418.390692 -365.617679)
			(xy 418.382936 -365.563731) (xy 418.38245 -365.53648) (xy 418.382953 -365.508907) (xy 418.390896 -365.454335)
			(xy 418.406612 -365.401475) (xy 418.429775 -365.351428) (xy 418.459902 -365.305238) (xy 418.496365 -365.263866)
			(xy 418.51707 -365.24565) (xy 418.52799 -365.235773) (xy 418.544066 -365.211118) (xy 418.552449 -365.182904)
			(xy 418.552446 -365.15347) (xy 418.544055 -365.125259) (xy 418.527972 -365.100607) (xy 418.51707 -365.09071)
			(xy 418.496354 -365.072504) (xy 418.459886 -365.031133) (xy 418.429755 -364.984942) (xy 418.40659 -364.934893)
			(xy 418.390874 -364.88203) (xy 418.382935 -364.827455) (xy 418.38245 -364.79988) (xy 418.38292 -364.77338)
			(xy 418.390262 -364.720892) (xy 418.404802 -364.669925) (xy 418.42626 -364.621464) (xy 418.439854 -364.598712)
			(xy 418.446578 -364.587148) (xy 418.454271 -364.561535) (xy 418.455055 -364.534802) (xy 418.448875 -364.508782)
			(xy 418.436156 -364.485257) (xy 418.417769 -364.465837) (xy 418.40658 -364.458504) (xy 418.381664 -364.442569)
			(xy 418.336742 -364.404103) (xy 418.298456 -364.359028) (xy 418.282628 -364.334044) (xy 418.27474 -364.321793)
			(xy 418.253262 -364.302117) (xy 418.227099 -364.289313) (xy 418.198383 -364.284425) (xy 418.169457 -364.287852)
			(xy 418.155882 -364.29315) (xy 418.132672 -364.30264) (xy 418.084339 -364.31599) (xy 418.03465 -364.322718)
			(xy 418.009578 -364.323122) (xy 417.984509 -364.322697) (xy 417.934826 -364.315949) (xy 417.886491 -364.302616)
			(xy 417.863274 -364.29315) (xy 417.849677 -364.287963) (xy 417.820788 -364.284591) (xy 417.792118 -364.28949)
			(xy 417.765988 -364.302264) (xy 417.744512 -364.321878) (xy 417.736528 -364.334044) (xy 417.721959 -364.357175)
			(xy 417.687116 -364.399296) (xy 417.646493 -364.435875) (xy 417.600962 -364.466126) (xy 417.5515 -364.489402)
			(xy 417.499169 -364.505202) (xy 417.44509 -364.513188) (xy 417.390426 -364.513188) (xy 417.336347 -364.505202)
			(xy 417.284016 -364.489402) (xy 417.234554 -364.466126) (xy 417.189023 -364.435875) (xy 417.1484 -364.399296)
			(xy 417.113557 -364.357175) (xy 417.098988 -364.334044) (xy 417.091043 -364.321834) (xy 417.06958 -364.302158)
			(xy 417.043432 -364.289349) (xy 417.014731 -364.28445) (xy 416.985814 -364.287862) (xy 416.972242 -364.29315)
			(xy 416.949037 -364.302652) (xy 416.900702 -364.315998) (xy 416.85101 -364.322721) (xy 416.825938 -364.323122)
			(xy 416.79805 -364.322622) (xy 416.742895 -364.314314) (xy 416.689595 -364.297878) (xy 416.639341 -364.273681)
			(xy 416.593254 -364.242264) (xy 416.552365 -364.204328) (xy 416.517587 -364.160722) (xy 416.489697 -364.112419)
			(xy 416.469318 -364.060499) (xy 416.456906 -364.006121) (xy 416.452737 -363.9505) (xy 411.577536 -363.9505)
			(xy 411.577536 -365.016288) (xy 412.995108 -365.016288) (xy 412.999179 -364.960666) (xy 413.011305 -364.906229)
			(xy 413.031228 -364.854138) (xy 413.058524 -364.805503) (xy 413.09261 -364.76136) (xy 413.132759 -364.722651)
			(xy 413.178117 -364.6902) (xy 413.227717 -364.664699) (xy 413.280501 -364.646692) (xy 413.335344 -364.636562)
			(xy 413.391078 -364.634525) (xy 413.446515 -364.640625) (xy 413.500472 -364.654731) (xy 413.551801 -364.676543)
			(xy 413.599407 -364.705597) (xy 413.642275 -364.741272) (xy 413.679492 -364.782809) (xy 413.710265 -364.829322)
			(xy 413.733937 -364.879819) (xy 413.750005 -364.933226) (xy 413.758125 -364.988402) (xy 413.758634 -365.016288)
			(xy 413.758125 -365.044174) (xy 413.750005 -365.09935) (xy 413.733937 -365.152757) (xy 413.710265 -365.203254)
			(xy 413.679492 -365.249767) (xy 413.642275 -365.291304) (xy 413.599407 -365.326979) (xy 413.551801 -365.356033)
			(xy 413.500472 -365.377845) (xy 413.446515 -365.391951) (xy 413.391078 -365.398051) (xy 413.335344 -365.396014)
			(xy 413.280501 -365.385884) (xy 413.227717 -365.367877) (xy 413.178117 -365.342376) (xy 413.132759 -365.309925)
			(xy 413.09261 -365.271216) (xy 413.058524 -365.227073) (xy 413.031228 -365.178438) (xy 413.011305 -365.126347)
			(xy 412.999179 -365.07191) (xy 412.995108 -365.016288) (xy 411.577536 -365.016288) (xy 411.577536 -365.545116)
			(xy 411.577055 -365.575091) (xy 411.567727 -365.634308) (xy 411.549239 -365.691334) (xy 411.522049 -365.744761)
			(xy 411.486827 -365.793271) (xy 411.46603 -365.814864) (xy 411.298644 -365.98225) (xy 412.330644 -365.98225)
			(xy 412.334715 -365.926628) (xy 412.346841 -365.872191) (xy 412.366764 -365.8201) (xy 412.39406 -365.771465)
			(xy 412.428146 -365.727322) (xy 412.468295 -365.688613) (xy 412.513653 -365.656162) (xy 412.563253 -365.630661)
			(xy 412.616037 -365.612654) (xy 412.67088 -365.602524) (xy 412.726614 -365.600487) (xy 412.782051 -365.606587)
			(xy 412.836008 -365.620693) (xy 412.887337 -365.642505) (xy 412.934943 -365.671559) (xy 412.977811 -365.707234)
			(xy 413.015028 -365.748771) (xy 413.045801 -365.795284) (xy 413.069473 -365.845781) (xy 413.085541 -365.899188)
			(xy 413.093661 -365.954364) (xy 413.09417 -365.98225) (xy 413.093661 -366.010136) (xy 413.085541 -366.065312)
			(xy 413.069473 -366.118719) (xy 413.045801 -366.169216) (xy 413.015028 -366.215729) (xy 412.977811 -366.257266)
			(xy 412.934943 -366.292941) (xy 412.887337 -366.321995) (xy 412.836008 -366.343807) (xy 412.782051 -366.357913)
			(xy 412.726614 -366.364013) (xy 412.67088 -366.361976) (xy 412.616037 -366.351846) (xy 412.563253 -366.333839)
			(xy 412.513653 -366.308338) (xy 412.468295 -366.275887) (xy 412.428146 -366.237178) (xy 412.39406 -366.193035)
			(xy 412.366764 -366.1444) (xy 412.346841 -366.092309) (xy 412.334715 -366.037872) (xy 412.330644 -365.98225)
			(xy 411.298644 -365.98225) (xy 411.042358 -366.238536) (xy 411.020743 -366.259319) (xy 410.972247 -366.294578)
			(xy 410.91883 -366.321812) (xy 410.861809 -366.340351) (xy 410.802589 -366.349737) (xy 410.77261 -366.350296)
			(xy 410.745366 -366.349781) (xy 410.691433 -366.342025) (xy 410.639153 -366.32667) (xy 410.589591 -366.304028)
			(xy 410.543759 -366.274561) (xy 410.502588 -366.238869) (xy 410.466917 -366.19768) (xy 410.437475 -366.151831)
			(xy 410.414859 -366.102258) (xy 410.399532 -366.04997) (xy 410.391804 -365.996032) (xy 410.391356 -365.968788)
			(xy 410.391841 -365.938814) (xy 410.401169 -365.879596) (xy 410.419656 -365.82257) (xy 410.446845 -365.769143)
			(xy 410.482066 -365.720633) (xy 410.502862 -365.69904) (xy 410.815028 -365.387128) (xy 410.815028 -361.784138)
			(xy 410.407358 -361.376468) (xy 410.225748 -361.376468) (xy 410.198512 -361.375981) (xy 410.144594 -361.368235)
			(xy 410.092327 -361.352894) (xy 410.042775 -361.33027) (xy 409.996948 -361.300824) (xy 409.955779 -361.265155)
			(xy 409.920105 -361.22399) (xy 409.890653 -361.178167) (xy 409.868023 -361.128618) (xy 409.852676 -361.076353)
			(xy 409.844923 -361.022436) (xy 384.661302 -361.022436) (xy 385.862193 -362.223304) (xy 409.80944 -362.223304)
			(xy 409.813511 -362.167682) (xy 409.825637 -362.113245) (xy 409.84556 -362.061154) (xy 409.872856 -362.012519)
			(xy 409.906942 -361.968376) (xy 409.947091 -361.929667) (xy 409.992449 -361.897216) (xy 410.042049 -361.871715)
			(xy 410.094833 -361.853708) (xy 410.149676 -361.843578) (xy 410.20541 -361.841541) (xy 410.260847 -361.847641)
			(xy 410.314804 -361.861747) (xy 410.366133 -361.883559) (xy 410.413739 -361.912613) (xy 410.456607 -361.948288)
			(xy 410.493824 -361.989825) (xy 410.524597 -362.036338) (xy 410.548269 -362.086835) (xy 410.564337 -362.140242)
			(xy 410.572457 -362.195418) (xy 410.572966 -362.223304) (xy 410.572457 -362.25119) (xy 410.564337 -362.306366)
			(xy 410.548269 -362.359773) (xy 410.524597 -362.41027) (xy 410.493824 -362.456783) (xy 410.456607 -362.49832)
			(xy 410.413739 -362.533995) (xy 410.366133 -362.563049) (xy 410.314804 -362.584861) (xy 410.260847 -362.598967)
			(xy 410.20541 -362.605067) (xy 410.149676 -362.60303) (xy 410.094833 -362.5929) (xy 410.042049 -362.574893)
			(xy 409.992449 -362.549392) (xy 409.947091 -362.516941) (xy 409.906942 -362.478232) (xy 409.872856 -362.434089)
			(xy 409.84556 -362.385454) (xy 409.825637 -362.333363) (xy 409.813511 -362.278926) (xy 409.80944 -362.223304)
			(xy 385.862193 -362.223304) (xy 386.832492 -363.193584) (xy 409.80944 -363.193584) (xy 409.813511 -363.137962)
			(xy 409.825637 -363.083525) (xy 409.84556 -363.031434) (xy 409.872856 -362.982799) (xy 409.906942 -362.938656)
			(xy 409.947091 -362.899947) (xy 409.992449 -362.867496) (xy 410.042049 -362.841995) (xy 410.094833 -362.823988)
			(xy 410.149676 -362.813858) (xy 410.20541 -362.811821) (xy 410.260847 -362.817921) (xy 410.314804 -362.832027)
			(xy 410.366133 -362.853839) (xy 410.413739 -362.882893) (xy 410.456607 -362.918568) (xy 410.493824 -362.960105)
			(xy 410.524597 -363.006618) (xy 410.548269 -363.057115) (xy 410.564337 -363.110522) (xy 410.572457 -363.165698)
			(xy 410.572966 -363.193584) (xy 410.572457 -363.22147) (xy 410.564337 -363.276646) (xy 410.548269 -363.330053)
			(xy 410.524597 -363.38055) (xy 410.493824 -363.427063) (xy 410.456607 -363.4686) (xy 410.413739 -363.504275)
			(xy 410.366133 -363.533329) (xy 410.314804 -363.555141) (xy 410.260847 -363.569247) (xy 410.20541 -363.575347)
			(xy 410.149676 -363.57331) (xy 410.094833 -363.56318) (xy 410.042049 -363.545173) (xy 409.992449 -363.519672)
			(xy 409.947091 -363.487221) (xy 409.906942 -363.448512) (xy 409.872856 -363.404369) (xy 409.84556 -363.355734)
			(xy 409.825637 -363.303643) (xy 409.813511 -363.249206) (xy 409.80944 -363.193584) (xy 386.832492 -363.193584)
			(xy 392.517122 -368.878104) (xy 410.563314 -368.878104) (xy 413.63519 -365.806482) (xy 413.653268 -365.789203)
			(xy 413.694847 -365.761427) (xy 413.71774 -365.751364) (xy 413.822642 -365.70793) (xy 413.830516 -365.688372)
			(xy 413.841703 -365.66253) (xy 413.870566 -365.614179) (xy 413.906224 -365.570598) (xy 413.947903 -365.532733)
			(xy 413.994695 -365.501408) (xy 414.045585 -365.477303) (xy 414.099466 -365.460942) (xy 414.155167 -365.45268)
			(xy 414.183322 -365.452152) (xy 414.210573 -365.452639) (xy 414.264521 -365.460398) (xy 414.316815 -365.475755)
			(xy 414.366392 -365.498397) (xy 414.412243 -365.527863) (xy 414.453434 -365.563554) (xy 414.489126 -365.604743)
			(xy 414.518595 -365.650592) (xy 414.541239 -365.700168) (xy 414.556598 -365.752462) (xy 414.564359 -365.806409)
			(xy 414.564501 -365.81461) (xy 415.42716 -365.81461) (xy 415.427646 -365.787359) (xy 415.435402 -365.733411)
			(xy 415.450757 -365.681116) (xy 415.473399 -365.631539) (xy 415.502865 -365.585689) (xy 415.538556 -365.544498)
			(xy 415.579747 -365.508807) (xy 415.625597 -365.479341) (xy 415.675174 -365.456699) (xy 415.727469 -365.441344)
			(xy 415.781417 -365.433588) (xy 415.835919 -365.433588) (xy 415.889867 -365.441344) (xy 415.942162 -365.456699)
			(xy 415.991739 -365.479341) (xy 416.037589 -365.508807) (xy 416.07878 -365.544498) (xy 416.114471 -365.585689)
			(xy 416.143937 -365.631539) (xy 416.166579 -365.681116) (xy 416.181934 -365.733411) (xy 416.18969 -365.787359)
			(xy 416.190176 -365.81461) (xy 416.189939 -365.833277) (xy 416.18625 -365.870429) (xy 416.18281 -365.888778)
			(xy 416.180493 -365.903048) (xy 416.183021 -365.931832) (xy 416.193516 -365.958754) (xy 416.211135 -365.981656)
			(xy 416.228289 -365.994188) (xy 422.018966 -365.994188) (xy 422.023037 -365.938566) (xy 422.035163 -365.884129)
			(xy 422.055086 -365.832038) (xy 422.082382 -365.783403) (xy 422.116468 -365.73926) (xy 422.156617 -365.700551)
			(xy 422.201975 -365.6681) (xy 422.251575 -365.642599) (xy 422.304359 -365.624592) (xy 422.359202 -365.614462)
			(xy 422.414936 -365.612425) (xy 422.470373 -365.618525) (xy 422.52433 -365.632631) (xy 422.575659 -365.654443)
			(xy 422.623265 -365.683497) (xy 422.666133 -365.719172) (xy 422.70335 -365.760709) (xy 422.734123 -365.807222)
			(xy 422.757795 -365.857719) (xy 422.773863 -365.911126) (xy 422.781983 -365.966302) (xy 422.782492 -365.994188)
			(xy 422.781983 -366.022074) (xy 422.773863 -366.07725) (xy 422.757795 -366.130657) (xy 422.734123 -366.181154)
			(xy 422.70335 -366.227667) (xy 422.666133 -366.269204) (xy 422.623265 -366.304879) (xy 422.575659 -366.333933)
			(xy 422.52433 -366.355745) (xy 422.470373 -366.369851) (xy 422.414936 -366.375951) (xy 422.359202 -366.373914)
			(xy 422.304359 -366.363784) (xy 422.251575 -366.345777) (xy 422.201975 -366.320276) (xy 422.156617 -366.287825)
			(xy 422.116468 -366.249116) (xy 422.082382 -366.204973) (xy 422.055086 -366.156338) (xy 422.035163 -366.104247)
			(xy 422.023037 -366.04981) (xy 422.018966 -365.994188) (xy 416.228289 -365.994188) (xy 416.234467 -365.998701)
			(xy 416.261641 -366.008525) (xy 416.276028 -366.009936) (xy 416.304683 -366.012287) (xy 416.360849 -366.024579)
			(xy 416.414535 -366.045157) (xy 416.464527 -366.073556) (xy 416.509692 -366.109134) (xy 416.549008 -366.151085)
			(xy 416.581587 -366.198459) (xy 416.606689 -366.250185) (xy 416.623747 -366.305091) (xy 416.632375 -366.361935)
			(xy 416.632898 -366.390682) (xy 416.632412 -366.417933) (xy 416.624656 -366.471881) (xy 416.609301 -366.524176)
			(xy 416.586659 -366.573753) (xy 416.557193 -366.619603) (xy 416.521502 -366.660794) (xy 416.480311 -366.696485)
			(xy 416.434461 -366.725951) (xy 416.384884 -366.748593) (xy 416.332589 -366.763948) (xy 416.278641 -366.771704)
			(xy 416.224139 -366.771704) (xy 416.170191 -366.763948) (xy 416.117896 -366.748593) (xy 416.068319 -366.725951)
			(xy 416.022469 -366.696485) (xy 415.981278 -366.660794) (xy 415.945587 -366.619603) (xy 415.916121 -366.573753)
			(xy 415.893479 -366.524176) (xy 415.878124 -366.471881) (xy 415.870368 -366.417933) (xy 415.869882 -366.390682)
			(xy 415.870116 -366.372015) (xy 415.873808 -366.334863) (xy 415.877248 -366.316514) (xy 415.879613 -366.302249)
			(xy 415.877082 -366.273457) (xy 415.86658 -366.246528) (xy 415.848951 -366.223623) (xy 415.825608 -366.206579)
			(xy 415.798422 -366.196762) (xy 415.78403 -366.195356) (xy 415.755378 -366.192963) (xy 415.699213 -366.180679)
			(xy 415.645527 -366.160108) (xy 415.595534 -366.131715) (xy 415.550368 -366.096142) (xy 415.51105 -366.054196)
			(xy 415.478471 -366.006825) (xy 415.453368 -365.955102) (xy 415.43631 -365.900198) (xy 415.427682 -365.843356)
			(xy 415.42716 -365.81461) (xy 414.564501 -365.81461) (xy 414.56483 -365.83366) (xy 414.56441 -365.85998)
			(xy 414.557213 -365.912124) (xy 414.542908 -365.962781) (xy 414.521769 -366.010988) (xy 414.494196 -366.055827)
			(xy 414.460716 -366.096445) (xy 414.44164 -366.114584) (xy 414.431611 -366.124394) (xy 414.416897 -366.148269)
			(xy 414.409247 -366.175251) (xy 414.409239 -366.203295) (xy 414.416875 -366.230281) (xy 414.431576 -366.254164)
			(xy 414.44164 -366.263936) (xy 414.460699 -366.282087) (xy 414.494152 -366.322719) (xy 414.521706 -366.367561)
			(xy 414.54284 -366.415763) (xy 414.557153 -366.466411) (xy 414.564374 -366.518544) (xy 414.56483 -366.54486)
			(xy 414.56437 -366.572115) (xy 414.556618 -366.626072) (xy 414.541265 -366.678376) (xy 414.518625 -366.727962)
			(xy 414.489159 -366.773822) (xy 414.453465 -366.815021) (xy 414.412272 -366.850722) (xy 414.366417 -366.880196)
			(xy 414.316834 -366.902844) (xy 414.264532 -366.918204) (xy 414.210577 -366.925965) (xy 414.183322 -366.926368)
			(xy 414.156085 -366.925864) (xy 414.102169 -366.918084) (xy 414.049906 -366.90272) (xy 414.000356 -366.880085)
			(xy 413.954526 -366.850639) (xy 413.93364 -366.83315) (xy 413.926133 -366.827175) (xy 413.908054 -366.820798)
			(xy 413.888895 -366.821491) (xy 413.871323 -366.829158) (xy 413.864298 -366.83569) (xy 411.006544 -369.693444)
			(xy 410.98845 -369.710703) (xy 410.946905 -369.738518) (xy 410.900734 -369.757699) (xy 410.851709 -369.767508)
			(xy 410.826712 -369.76812) (xy 392.253724 -369.76812) (xy 392.228729 -369.767481) (xy 392.179709 -369.757675)
			(xy 392.133543 -369.738496) (xy 392.092006 -369.71068) (xy 392.073892 -369.693444) (xy 378.952506 -356.572312)
			(xy 374.516904 -356.572312) (xy 374.491902 -356.57172) (xy 374.442866 -356.561927) (xy 374.396683 -356.542754)
			(xy 374.355128 -356.51494) (xy 374.337072 -356.497636) (xy 373.244364 -355.404928) (xy 371.886734 -355.404928)
			(xy 371.861749 -355.40432) (xy 371.812738 -355.394584) (xy 371.766566 -355.375478) (xy 371.725005 -355.347736)
			(xy 371.706902 -355.330506) (xy 371.040406 -354.664264) (xy 368.323114 -354.664264) (xy 367.634606 -355.352604)
			(xy 368.216686 -355.352604) (xy 368.220757 -355.296982) (xy 368.232883 -355.242545) (xy 368.252806 -355.190454)
			(xy 368.280102 -355.141819) (xy 368.314188 -355.097676) (xy 368.354337 -355.058967) (xy 368.399695 -355.026516)
			(xy 368.449295 -355.001015) (xy 368.502079 -354.983008) (xy 368.556922 -354.972878) (xy 368.612656 -354.970841)
			(xy 368.668093 -354.976941) (xy 368.72205 -354.991047) (xy 368.773379 -355.012859) (xy 368.820985 -355.041913)
			(xy 368.863853 -355.077588) (xy 368.90107 -355.119125) (xy 368.931843 -355.165638) (xy 368.955515 -355.216135)
			(xy 368.971583 -355.269542) (xy 368.979703 -355.324718) (xy 368.980212 -355.352604) (xy 368.979703 -355.38049)
			(xy 368.971583 -355.435666) (xy 368.955515 -355.489073) (xy 368.931843 -355.53957) (xy 368.90107 -355.586083)
			(xy 368.863853 -355.62762) (xy 368.820985 -355.663295) (xy 368.773379 -355.692349) (xy 368.72205 -355.714161)
			(xy 368.668093 -355.728267) (xy 368.612656 -355.734367) (xy 368.556922 -355.73233) (xy 368.502079 -355.7222)
			(xy 368.449295 -355.704193) (xy 368.399695 -355.678692) (xy 368.354337 -355.646241) (xy 368.314188 -355.607532)
			(xy 368.280102 -355.563389) (xy 368.252806 -355.514754) (xy 368.232883 -355.462663) (xy 368.220757 -355.408226)
			(xy 368.216686 -355.352604) (xy 367.634606 -355.352604) (xy 367.284762 -355.702362) (xy 366.613403 -356.373938)
			(xy 368.222274 -356.373938) (xy 368.226345 -356.318316) (xy 368.238471 -356.263879) (xy 368.258394 -356.211788)
			(xy 368.28569 -356.163153) (xy 368.319776 -356.11901) (xy 368.359925 -356.080301) (xy 368.405283 -356.04785)
			(xy 368.454883 -356.022349) (xy 368.507667 -356.004342) (xy 368.56251 -355.994212) (xy 368.618244 -355.992175)
			(xy 368.673681 -355.998275) (xy 368.727638 -356.012381) (xy 368.778967 -356.034193) (xy 368.826573 -356.063247)
			(xy 368.869441 -356.098922) (xy 368.906658 -356.140459) (xy 368.937431 -356.186972) (xy 368.961103 -356.237469)
			(xy 368.977171 -356.290876) (xy 368.978854 -356.30231) (xy 370.449854 -356.30231) (xy 370.453925 -356.246688)
			(xy 370.466051 -356.192251) (xy 370.485974 -356.14016) (xy 370.51327 -356.091525) (xy 370.547356 -356.047382)
			(xy 370.587505 -356.008673) (xy 370.632863 -355.976222) (xy 370.682463 -355.950721) (xy 370.735247 -355.932714)
			(xy 370.79009 -355.922584) (xy 370.845824 -355.920547) (xy 370.901261 -355.926647) (xy 370.955218 -355.940753)
			(xy 371.006547 -355.962565) (xy 371.054153 -355.991619) (xy 371.097021 -356.027294) (xy 371.134238 -356.068831)
			(xy 371.165011 -356.115344) (xy 371.188683 -356.165841) (xy 371.204751 -356.219248) (xy 371.212871 -356.274424)
			(xy 371.21338 -356.30231) (xy 371.212871 -356.330196) (xy 371.204751 -356.385372) (xy 371.188683 -356.438779)
			(xy 371.165011 -356.489276) (xy 371.134238 -356.535789) (xy 371.097021 -356.577326) (xy 371.054153 -356.613001)
			(xy 371.006547 -356.642055) (xy 370.955218 -356.663867) (xy 370.901261 -356.677973) (xy 370.845824 -356.684073)
			(xy 370.79009 -356.682036) (xy 370.735247 -356.671906) (xy 370.682463 -356.653899) (xy 370.632863 -356.628398)
			(xy 370.587505 -356.595947) (xy 370.547356 -356.557238) (xy 370.51327 -356.513095) (xy 370.485974 -356.46446)
			(xy 370.466051 -356.412369) (xy 370.453925 -356.357932) (xy 370.449854 -356.30231) (xy 368.978854 -356.30231)
			(xy 368.985291 -356.346052) (xy 368.9858 -356.373938) (xy 368.985291 -356.401824) (xy 368.977171 -356.457)
			(xy 368.961103 -356.510407) (xy 368.937431 -356.560904) (xy 368.906658 -356.607417) (xy 368.869441 -356.648954)
			(xy 368.826573 -356.684629) (xy 368.778967 -356.713683) (xy 368.727638 -356.735495) (xy 368.673681 -356.749601)
			(xy 368.618244 -356.755701) (xy 368.56251 -356.753664) (xy 368.507667 -356.743534) (xy 368.454883 -356.725527)
			(xy 368.405283 -356.700026) (xy 368.359925 -356.667575) (xy 368.319776 -356.628866) (xy 368.28569 -356.584723)
			(xy 368.258394 -356.536088) (xy 368.238471 -356.483997) (xy 368.226345 -356.42956) (xy 368.222274 -356.373938)
			(xy 366.613403 -356.373938) (xy 366.498886 -356.488492) (xy 366.480778 -356.505717) (xy 366.439219 -356.533464)
			(xy 366.393049 -356.552578) (xy 366.344039 -356.562327) (xy 366.319054 -356.562914) (xy 364.812834 -356.56266)
			(xy 362.926884 -356.56266) (xy 362.926884 -356.640638) (xy 362.950252 -356.664006) (xy 362.950252 -357.197406)
			(xy 364.728504 -357.197406) (xy 364.732575 -357.141784) (xy 364.744701 -357.087347) (xy 364.764624 -357.035256)
			(xy 364.79192 -356.986621) (xy 364.826006 -356.942478) (xy 364.866155 -356.903769) (xy 364.911513 -356.871318)
			(xy 364.961113 -356.845817) (xy 365.013897 -356.82781) (xy 365.06874 -356.81768) (xy 365.124474 -356.815643)
			(xy 365.179911 -356.821743) (xy 365.233868 -356.835849) (xy 365.285197 -356.857661) (xy 365.332803 -356.886715)
			(xy 365.375671 -356.92239) (xy 365.412888 -356.963927) (xy 365.443661 -357.01044) (xy 365.467333 -357.060937)
			(xy 365.483401 -357.114344) (xy 365.491521 -357.16952) (xy 365.49203 -357.197406) (xy 365.491521 -357.225292)
			(xy 365.483401 -357.280468) (xy 365.467333 -357.333875) (xy 365.443661 -357.384372) (xy 365.412888 -357.430885)
			(xy 365.375671 -357.472422) (xy 365.332803 -357.508097) (xy 365.285197 -357.537151) (xy 365.233868 -357.558963)
			(xy 365.179911 -357.573069) (xy 365.124474 -357.579169) (xy 365.06874 -357.577132) (xy 365.013897 -357.567002)
			(xy 364.961113 -357.548995) (xy 364.911513 -357.523494) (xy 364.866155 -357.491043) (xy 364.826006 -357.452334)
			(xy 364.79192 -357.408191) (xy 364.764624 -357.359556) (xy 364.744701 -357.307465) (xy 364.732575 -357.253028)
			(xy 364.728504 -357.197406) (xy 362.950252 -357.197406) (xy 362.950252 -357.592376) (xy 362.7882 -357.754428)
			(xy 362.7882 -357.82758) (xy 362.715048 -357.82758) (xy 362.668058 -357.874824) (xy 362.238544 -357.874824)
			(xy 362.011979 -358.101389) (xy 369.986045 -358.101389) (xy 369.993796 -358.047437) (xy 370.009146 -357.995136)
			(xy 370.031783 -357.945553) (xy 370.061246 -357.899696) (xy 370.096935 -357.858499) (xy 370.138124 -357.8228)
			(xy 370.183974 -357.793326) (xy 370.233552 -357.770678) (xy 370.285848 -357.755315) (xy 370.339799 -357.747551)
			(xy 370.367052 -357.747062) (xy 370.380048 -357.747169) (xy 370.405979 -357.748949) (xy 370.418868 -357.750618)
			(xy 370.433246 -357.752024) (xy 370.461801 -357.747758) (xy 370.488017 -357.735664) (xy 370.509796 -357.71671)
			(xy 370.525393 -357.692414) (xy 370.533559 -357.664721) (xy 370.53364 -357.635849) (xy 370.53012 -357.62184)
			(xy 370.523198 -357.59604) (xy 370.5158 -357.543139) (xy 370.515388 -357.51643) (xy 370.515823 -357.489174)
			(xy 370.523576 -357.435218) (xy 370.53893 -357.382913) (xy 370.561571 -357.333327) (xy 370.591039 -357.287467)
			(xy 370.626734 -357.246268) (xy 370.667928 -357.210568) (xy 370.713784 -357.181095) (xy 370.763368 -357.158447)
			(xy 370.81567 -357.143087) (xy 370.869626 -357.135326) (xy 370.924137 -357.135324) (xy 370.978093 -357.143079)
			(xy 371.030397 -357.158434) (xy 371.079983 -357.181077) (xy 371.125842 -357.210546) (xy 371.16704 -357.246242)
			(xy 371.202738 -357.287437) (xy 371.232211 -357.333294) (xy 371.254857 -357.382878) (xy 371.270216 -357.435181)
			(xy 371.277975 -357.489137) (xy 371.277976 -357.543648) (xy 371.270219 -357.597605) (xy 371.254862 -357.649908)
			(xy 371.232218 -357.699493) (xy 371.202747 -357.745351) (xy 371.16705 -357.786548) (xy 371.125854 -357.822245)
			(xy 371.079996 -357.851716) (xy 371.030411 -357.874361) (xy 370.978108 -357.889718) (xy 370.924152 -357.897475)
			(xy 370.896896 -357.897938) (xy 370.8839 -357.897826) (xy 370.857969 -357.896049) (xy 370.84508 -357.894382)
			(xy 370.830698 -357.893022) (xy 370.802146 -357.897276) (xy 370.77593 -357.909361) (xy 370.754151 -357.928308)
			(xy 370.738553 -357.952598) (xy 370.730387 -357.980286) (xy 370.730307 -358.009153) (xy 370.733828 -358.02316)
			(xy 370.740749 -358.04896) (xy 370.748147 -358.101861) (xy 370.74856 -358.12857) (xy 370.748154 -358.155823)
			(xy 370.740402 -358.209775) (xy 370.72505 -358.262075) (xy 370.702411 -358.311657) (xy 370.672947 -358.357513)
			(xy 370.637256 -358.398709) (xy 370.596066 -358.434407) (xy 370.550215 -358.463879) (xy 370.500637 -358.486527)
			(xy 370.44834 -358.501888) (xy 370.394389 -358.50965) (xy 370.339883 -358.509655) (xy 370.285931 -358.501903)
			(xy 370.233631 -358.486552) (xy 370.184048 -358.463914) (xy 370.138191 -358.43445) (xy 370.096995 -358.39876)
			(xy 370.061297 -358.357571) (xy 370.031823 -358.311721) (xy 370.009176 -358.262142) (xy 369.993814 -358.209846)
			(xy 369.986051 -358.155895) (xy 369.986045 -358.101389) (xy 362.011979 -358.101389) (xy 361.749848 -358.36352)
			(xy 361.51058 -358.36352) (xy 361.435396 -358.484678) (xy 361.447842 -358.510078) (xy 361.46015 -358.536384)
			(xy 361.477558 -358.591789) (xy 361.486392 -358.649189) (xy 361.486958 -358.678226) (xy 361.486493 -358.705476)
			(xy 361.478733 -358.759422) (xy 361.463374 -358.811714) (xy 361.460188 -358.818688) (xy 366.653062 -358.818688)
			(xy 366.657133 -358.763066) (xy 366.669259 -358.708629) (xy 366.689182 -358.656538) (xy 366.716478 -358.607903)
			(xy 366.750564 -358.56376) (xy 366.790713 -358.525051) (xy 366.836071 -358.4926) (xy 366.885671 -358.467099)
			(xy 366.938455 -358.449092) (xy 366.993298 -358.438962) (xy 367.049032 -358.436925) (xy 367.104469 -358.443025)
			(xy 367.158426 -358.457131) (xy 367.209755 -358.478943) (xy 367.257361 -358.507997) (xy 367.300229 -358.543672)
			(xy 367.337446 -358.585209) (xy 367.368219 -358.631722) (xy 367.391891 -358.682219) (xy 367.407959 -358.735626)
			(xy 367.416079 -358.790802) (xy 367.416588 -358.818688) (xy 367.416079 -358.846574) (xy 367.407959 -358.90175)
			(xy 367.391891 -358.955157) (xy 367.387519 -358.964484) (xy 370.72773 -358.964484) (xy 370.731801 -358.908862)
			(xy 370.743927 -358.854425) (xy 370.76385 -358.802334) (xy 370.791146 -358.753699) (xy 370.825232 -358.709556)
			(xy 370.865381 -358.670847) (xy 370.910739 -358.638396) (xy 370.960339 -358.612895) (xy 371.013123 -358.594888)
			(xy 371.067966 -358.584758) (xy 371.1237 -358.582721) (xy 371.179137 -358.588821) (xy 371.233094 -358.602927)
			(xy 371.284423 -358.624739) (xy 371.332029 -358.653793) (xy 371.374897 -358.689468) (xy 371.412114 -358.731005)
			(xy 371.442887 -358.777518) (xy 371.466559 -358.828015) (xy 371.482627 -358.881422) (xy 371.490747 -358.936598)
			(xy 371.491256 -358.964484) (xy 371.490747 -358.99237) (xy 371.482627 -359.047546) (xy 371.466559 -359.100953)
			(xy 371.442887 -359.15145) (xy 371.412114 -359.197963) (xy 371.374897 -359.2395) (xy 371.332029 -359.275175)
			(xy 371.284423 -359.304229) (xy 371.233094 -359.326041) (xy 371.179137 -359.340147) (xy 371.1237 -359.346247)
			(xy 371.067966 -359.34421) (xy 371.013123 -359.33408) (xy 370.960339 -359.316073) (xy 370.910739 -359.290572)
			(xy 370.865381 -359.258121) (xy 370.825232 -359.219412) (xy 370.791146 -359.175269) (xy 370.76385 -359.126634)
			(xy 370.743927 -359.074543) (xy 370.731801 -359.020106) (xy 370.72773 -358.964484) (xy 367.387519 -358.964484)
			(xy 367.368219 -359.005654) (xy 367.337446 -359.052167) (xy 367.300229 -359.093704) (xy 367.257361 -359.129379)
			(xy 367.209755 -359.158433) (xy 367.158426 -359.180245) (xy 367.104469 -359.194351) (xy 367.049032 -359.200451)
			(xy 366.993298 -359.198414) (xy 366.938455 -359.188284) (xy 366.885671 -359.170277) (xy 366.836071 -359.144776)
			(xy 366.790713 -359.112325) (xy 366.750564 -359.073616) (xy 366.716478 -359.029473) (xy 366.689182 -358.980838)
			(xy 366.669259 -358.928747) (xy 366.657133 -358.87431) (xy 366.653062 -358.818688) (xy 361.460188 -358.818688)
			(xy 361.440729 -358.861287) (xy 361.41126 -358.907134) (xy 361.375565 -358.948319) (xy 361.334373 -358.984005)
			(xy 361.288521 -359.013466) (xy 361.238942 -359.0361) (xy 361.186647 -359.051449) (xy 361.1327 -359.059198)
			(xy 361.10545 -359.059734) (xy 361.0751 -359.059127) (xy 361.015172 -359.049474) (xy 360.95753 -359.030452)
			(xy 360.903627 -359.002541) (xy 360.854825 -358.966445) (xy 360.833162 -358.94518) (xy 360.155244 -359.622956)
			(xy 360.674829 -359.622956) (xy 360.674829 -359.568444) (xy 360.682587 -359.514488) (xy 360.697945 -359.462185)
			(xy 360.720591 -359.4126) (xy 360.750063 -359.366743) (xy 360.785761 -359.325547) (xy 360.826959 -359.289851)
			(xy 360.872818 -359.260381) (xy 360.922404 -359.237738) (xy 360.974708 -359.222383) (xy 361.028664 -359.214628)
			(xy 361.05592 -359.214166) (xy 361.085972 -359.214716) (xy 361.145331 -359.224155) (xy 361.202477 -359.242782)
			(xy 361.255997 -359.270136) (xy 361.304567 -359.305541) (xy 361.326176 -359.326434) (xy 361.340908 -359.34142)
			(xy 361.404662 -359.34142) (xy 361.429646 -359.342021) (xy 361.478654 -359.351769) (xy 361.524823 -359.37088)
			(xy 361.566384 -359.39862) (xy 361.584494 -359.415842) (xy 361.62869 -359.460038) (xy 363.93323 -359.460038)
			(xy 363.937301 -359.404416) (xy 363.949427 -359.349979) (xy 363.96935 -359.297888) (xy 363.996646 -359.249253)
			(xy 364.030732 -359.20511) (xy 364.070881 -359.166401) (xy 364.116239 -359.13395) (xy 364.165839 -359.108449)
			(xy 364.218623 -359.090442) (xy 364.273466 -359.080312) (xy 364.3292 -359.078275) (xy 364.384637 -359.084375)
			(xy 364.438594 -359.098481) (xy 364.489923 -359.120293) (xy 364.537529 -359.149347) (xy 364.580397 -359.185022)
			(xy 364.617614 -359.226559) (xy 364.648387 -359.273072) (xy 364.672059 -359.323569) (xy 364.688127 -359.376976)
			(xy 364.696247 -359.432152) (xy 364.696756 -359.460038) (xy 364.696247 -359.487924) (xy 364.688127 -359.5431)
			(xy 364.672059 -359.596507) (xy 364.648387 -359.647004) (xy 364.617614 -359.693517) (xy 364.580397 -359.735054)
			(xy 364.537529 -359.770729) (xy 364.489923 -359.799783) (xy 364.438594 -359.821595) (xy 364.384637 -359.835701)
			(xy 364.3292 -359.841801) (xy 364.273466 -359.839764) (xy 364.218623 -359.829634) (xy 364.165839 -359.811627)
			(xy 364.116239 -359.786126) (xy 364.070881 -359.753675) (xy 364.030732 -359.714966) (xy 363.996646 -359.670823)
			(xy 363.96935 -359.622188) (xy 363.949427 -359.570097) (xy 363.937301 -359.51566) (xy 363.93323 -359.460038)
			(xy 361.62869 -359.460038) (xy 362.322618 -360.153966) (xy 366.16843 -360.153966) (xy 366.172501 -360.098344)
			(xy 366.184627 -360.043907) (xy 366.20455 -359.991816) (xy 366.231846 -359.943181) (xy 366.265932 -359.899038)
			(xy 366.306081 -359.860329) (xy 366.351439 -359.827878) (xy 366.401039 -359.802377) (xy 366.453823 -359.78437)
			(xy 366.508666 -359.77424) (xy 366.5644 -359.772203) (xy 366.619837 -359.778303) (xy 366.673794 -359.792409)
			(xy 366.725123 -359.814221) (xy 366.772729 -359.843275) (xy 366.815597 -359.87895) (xy 366.852814 -359.920487)
			(xy 366.883587 -359.967) (xy 366.907259 -360.017497) (xy 366.923327 -360.070904) (xy 366.931447 -360.12608)
			(xy 366.931956 -360.153966) (xy 366.931447 -360.181852) (xy 366.923327 -360.237028) (xy 366.907259 -360.290435)
			(xy 366.883587 -360.340932) (xy 366.852814 -360.387445) (xy 366.815597 -360.428982) (xy 366.772729 -360.464657)
			(xy 366.725123 -360.493711) (xy 366.673794 -360.515523) (xy 366.619837 -360.529629) (xy 366.5644 -360.535729)
			(xy 366.508666 -360.533692) (xy 366.453823 -360.523562) (xy 366.401039 -360.505555) (xy 366.351439 -360.480054)
			(xy 366.306081 -360.447603) (xy 366.265932 -360.408894) (xy 366.231846 -360.364751) (xy 366.20455 -360.316116)
			(xy 366.184627 -360.264025) (xy 366.172501 -360.209588) (xy 366.16843 -360.153966) (xy 362.322618 -360.153966)
			(xy 362.84916 -360.680508) (xy 376.90628 -360.680508) (xy 376.910351 -360.624886) (xy 376.922477 -360.570449)
			(xy 376.9424 -360.518358) (xy 376.969696 -360.469723) (xy 377.003782 -360.42558) (xy 377.043931 -360.386871)
			(xy 377.089289 -360.35442) (xy 377.138889 -360.328919) (xy 377.191673 -360.310912) (xy 377.246516 -360.300782)
			(xy 377.30225 -360.298745) (xy 377.357687 -360.304845) (xy 377.411644 -360.318951) (xy 377.462973 -360.340763)
			(xy 377.510579 -360.369817) (xy 377.553447 -360.405492) (xy 377.590664 -360.447029) (xy 377.621437 -360.493542)
			(xy 377.645109 -360.544039) (xy 377.661177 -360.597446) (xy 377.669297 -360.652622) (xy 377.669806 -360.680508)
			(xy 377.669297 -360.708394) (xy 377.661177 -360.76357) (xy 377.645109 -360.816977) (xy 377.621437 -360.867474)
			(xy 377.590664 -360.913987) (xy 377.553447 -360.955524) (xy 377.510579 -360.991199) (xy 377.462973 -361.020253)
			(xy 377.411644 -361.042065) (xy 377.357687 -361.056171) (xy 377.30225 -361.062271) (xy 377.246516 -361.060234)
			(xy 377.191673 -361.050104) (xy 377.138889 -361.032097) (xy 377.089289 -361.006596) (xy 377.043931 -360.974145)
			(xy 377.003782 -360.935436) (xy 376.969696 -360.891293) (xy 376.9424 -360.842658) (xy 376.922477 -360.790567)
			(xy 376.910351 -360.73613) (xy 376.90628 -360.680508) (xy 362.84916 -360.680508) (xy 363.183932 -361.01528)
			(xy 363.20116 -361.033401) (xy 363.228979 -361.074936) (xy 363.24816 -361.121099) (xy 363.250568 -361.133136)
			(xy 369.3861 -361.133136) (xy 369.390189 -361.077254) (xy 369.402372 -361.022564) (xy 369.422388 -360.97023)
			(xy 369.449811 -360.921368) (xy 369.484056 -360.87702) (xy 369.524392 -360.83813) (xy 369.569962 -360.805528)
			(xy 369.619793 -360.779909) (xy 369.672823 -360.761817) (xy 369.727921 -360.75164) (xy 369.783915 -360.749594)
			(xy 369.83961 -360.755722) (xy 369.893819 -360.769894) (xy 369.945387 -360.791808) (xy 369.993215 -360.820997)
			(xy 370.036283 -360.856838) (xy 370.073673 -360.898568) (xy 370.104589 -360.945298) (xy 370.128372 -360.996031)
			(xy 370.144514 -361.049687) (xy 370.152673 -361.105121) (xy 370.153184 -361.133136) (xy 370.152673 -361.161151)
			(xy 370.144514 -361.216585) (xy 370.128372 -361.270241) (xy 370.104589 -361.320974) (xy 370.073673 -361.367704)
			(xy 370.036283 -361.409434) (xy 369.993215 -361.445275) (xy 369.945387 -361.474464) (xy 369.893819 -361.496378)
			(xy 369.83961 -361.51055) (xy 369.783915 -361.516678) (xy 369.727921 -361.514632) (xy 369.672823 -361.504455)
			(xy 369.619793 -361.486363) (xy 369.569962 -361.460744) (xy 369.524392 -361.428142) (xy 369.484056 -361.389252)
			(xy 369.449811 -361.344904) (xy 369.422388 -361.296042) (xy 369.402372 -361.243708) (xy 369.390189 -361.189018)
			(xy 369.3861 -361.133136) (xy 363.250568 -361.133136) (xy 363.257967 -361.170118) (xy 363.258608 -361.195112)
			(xy 363.258608 -362.097066) (xy 376.025154 -362.097066) (xy 376.029225 -362.041444) (xy 376.041351 -361.987007)
			(xy 376.061274 -361.934916) (xy 376.08857 -361.886281) (xy 376.122656 -361.842138) (xy 376.162805 -361.803429)
			(xy 376.208163 -361.770978) (xy 376.257763 -361.745477) (xy 376.310547 -361.72747) (xy 376.36539 -361.71734)
			(xy 376.421124 -361.715303) (xy 376.476561 -361.721403) (xy 376.52724 -361.734652) (xy 382.553685 -361.734652)
			(xy 382.553685 -361.680148) (xy 382.561442 -361.6262) (xy 382.576798 -361.573905) (xy 382.59944 -361.524328)
			(xy 382.628907 -361.478477) (xy 382.6646 -361.437287) (xy 382.705792 -361.401596) (xy 382.751643 -361.372131)
			(xy 382.801222 -361.349492) (xy 382.853518 -361.334138) (xy 382.907466 -361.326384) (xy 382.934718 -361.325922)
			(xy 382.96148 -361.326343) (xy 383.014474 -361.333852) (xy 383.0659 -361.348693) (xy 383.114747 -361.370573)
			(xy 383.160058 -361.399065) (xy 383.200943 -361.433608) (xy 383.2366 -361.473525) (xy 383.26633 -361.518033)
			(xy 383.289549 -361.566259) (xy 383.305801 -361.617256) (xy 383.314768 -361.670023) (xy 383.315972 -361.696762)
			(xy 383.316841 -361.712162) (xy 383.3268 -361.741345) (xy 383.345005 -361.766232) (xy 383.369801 -361.784562)
			(xy 383.398933 -361.794667) (xy 383.429753 -361.79563) (xy 383.44475 -361.792012) (xy 383.469775 -361.785504)
			(xy 383.521005 -361.778492) (xy 383.546858 -361.778042) (xy 383.574112 -361.778495) (xy 383.628066 -361.786247)
			(xy 383.680367 -361.8016) (xy 383.72995 -361.824242) (xy 383.775806 -361.85371) (xy 383.817001 -361.889405)
			(xy 383.852695 -361.9306) (xy 383.882162 -361.976457) (xy 383.904802 -362.02604) (xy 383.920155 -362.078342)
			(xy 383.927906 -362.132296) (xy 383.928366 -362.15955) (xy 383.928112 -362.176568) (xy 383.927909 -362.191398)
			(xy 383.935129 -362.220154) (xy 383.950314 -362.245619) (xy 383.97218 -362.265641) (xy 383.998881 -362.278529)
			(xy 384.02816 -362.283195) (xy 384.04292 -362.281724) (xy 384.055371 -362.280175) (xy 384.080411 -362.278523)
			(xy 384.092958 -362.278422) (xy 384.120211 -362.278894) (xy 384.174163 -362.286646) (xy 384.226463 -362.301999)
			(xy 384.276045 -362.324639) (xy 384.3219 -362.354105) (xy 384.363094 -362.389798) (xy 384.398788 -362.430991)
			(xy 384.428256 -362.476845) (xy 384.450897 -362.526426) (xy 384.466251 -362.578725) (xy 384.474005 -362.632677)
			(xy 384.474466 -362.65993) (xy 384.474274 -362.676528) (xy 384.471345 -362.709595) (xy 384.468624 -362.72597)
			(xy 384.466495 -362.741477) (xy 384.470727 -362.772475) (xy 384.484126 -362.800745) (xy 384.505442 -362.823645)
			(xy 384.532681 -362.839034) (xy 384.547872 -362.84281) (xy 384.576032 -362.849306) (xy 384.630114 -362.869669)
			(xy 384.680507 -362.897954) (xy 384.726059 -362.933515) (xy 384.765729 -362.975538) (xy 384.798607 -363.023062)
			(xy 384.823944 -363.075) (xy 384.84116 -363.130165) (xy 384.84986 -363.187295) (xy 384.850386 -363.21619)
			(xy 384.850207 -363.233753) (xy 384.84703 -363.268734) (xy 384.844036 -363.28604) (xy 384.841779 -363.301008)
			(xy 384.845177 -363.331074) (xy 384.857239 -363.358822) (xy 384.876904 -363.381817) (xy 384.902446 -363.398037)
			(xy 384.93162 -363.406059) (xy 384.961864 -363.405177) (xy 384.97637 -363.400848) (xy 385.006102 -363.391462)
			(xy 385.067626 -363.381381) (xy 385.098798 -363.380782) (xy 385.126051 -363.381253) (xy 385.180003 -363.38901)
			(xy 385.232301 -363.404366) (xy 385.281882 -363.427009) (xy 385.327736 -363.456477) (xy 385.368929 -363.492171)
			(xy 385.404623 -363.533364) (xy 385.434091 -363.579218) (xy 385.456734 -363.628799) (xy 385.47209 -363.681097)
			(xy 385.479847 -363.735049) (xy 385.479847 -363.789555) (xy 385.472089 -363.843507) (xy 385.456733 -363.895805)
			(xy 385.434089 -363.945386) (xy 385.404621 -363.991239) (xy 385.368926 -364.032432) (xy 385.327733 -364.068125)
			(xy 385.281879 -364.097593) (xy 385.232298 -364.120235) (xy 385.179999 -364.135591) (xy 385.126047 -364.143347)
			(xy 385.071541 -364.143346) (xy 385.017589 -364.135588) (xy 384.965291 -364.120231) (xy 384.915711 -364.097587)
			(xy 384.869858 -364.068118) (xy 384.828665 -364.032423) (xy 384.792972 -363.991229) (xy 384.763505 -363.945375)
			(xy 384.740863 -363.895794) (xy 384.725508 -363.843495) (xy 384.717753 -363.789543) (xy 384.71729 -363.76229)
			(xy 384.717465 -363.744727) (xy 384.720645 -363.709746) (xy 384.72364 -363.69244) (xy 384.725817 -363.677466)
			(xy 384.722415 -363.647418) (xy 384.71036 -363.619686) (xy 384.690709 -363.596702) (xy 384.665187 -363.580483)
			(xy 384.636034 -363.572453) (xy 384.605807 -363.573315) (xy 384.591306 -363.577632) (xy 384.561576 -363.587023)
			(xy 384.500051 -363.597101) (xy 384.468878 -363.597698) (xy 384.441626 -363.597243) (xy 384.387676 -363.589483)
			(xy 384.33538 -363.574124) (xy 384.285803 -363.55148) (xy 384.239952 -363.522011) (xy 384.198762 -363.486316)
			(xy 384.16307 -363.445123) (xy 384.133605 -363.399269) (xy 384.110964 -363.349689) (xy 384.09561 -363.297392)
			(xy 384.087855 -363.243442) (xy 384.08737 -363.21619) (xy 384.087564 -363.199592) (xy 384.090491 -363.166525)
			(xy 384.093212 -363.15015) (xy 384.095292 -363.134639) (xy 384.091067 -363.103649) (xy 384.077678 -363.075384)
			(xy 384.056375 -363.052484) (xy 384.029149 -363.037091) (xy 384.013964 -363.03331) (xy 383.985798 -363.026841)
			(xy 383.931718 -363.00647) (xy 383.881327 -362.978179) (xy 383.835777 -362.942614) (xy 383.79611 -362.900588)
			(xy 383.763232 -362.853061) (xy 383.737895 -362.801122) (xy 383.720679 -362.745956) (xy 383.711977 -362.688825)
			(xy 383.71145 -362.65993) (xy 383.711704 -362.642912) (xy 383.711907 -362.628082) (xy 383.704683 -362.599329)
			(xy 383.689497 -362.573866) (xy 383.667631 -362.553845) (xy 383.640933 -362.540956) (xy 383.611655 -362.536288)
			(xy 383.596896 -362.537756) (xy 383.584444 -362.539304) (xy 383.559405 -362.540956) (xy 383.546858 -362.541058)
			(xy 383.520097 -362.540586) (xy 383.467103 -362.533086) (xy 383.415678 -362.518254) (xy 383.36683 -362.496381)
			(xy 383.321518 -362.467896) (xy 383.280631 -362.433357) (xy 383.244973 -362.393444) (xy 383.215243 -362.348939)
			(xy 383.192024 -362.300716) (xy 383.175772 -362.249721) (xy 383.166806 -362.196956) (xy 383.165604 -362.170218)
			(xy 383.164656 -362.154828) (xy 383.154702 -362.125661) (xy 383.13651 -362.100785) (xy 383.111733 -362.082457)
			(xy 383.08262 -362.072344) (xy 383.051817 -362.071363) (xy 383.036826 -362.074968) (xy 383.011802 -362.08148)
			(xy 382.960572 -362.08849) (xy 382.934718 -362.088938) (xy 382.907466 -362.088416) (xy 382.853518 -362.080662)
			(xy 382.801222 -362.065308) (xy 382.751643 -362.042669) (xy 382.705792 -362.013204) (xy 382.6646 -361.977513)
			(xy 382.628907 -361.936323) (xy 382.59944 -361.890472) (xy 382.576798 -361.840895) (xy 382.561442 -361.7886)
			(xy 382.553685 -361.734652) (xy 376.52724 -361.734652) (xy 376.530518 -361.735509) (xy 376.581847 -361.757321)
			(xy 376.629453 -361.786375) (xy 376.672321 -361.82205) (xy 376.709538 -361.863587) (xy 376.740311 -361.9101)
			(xy 376.763983 -361.960597) (xy 376.780051 -362.014004) (xy 376.788171 -362.06918) (xy 376.78868 -362.097066)
			(xy 376.788171 -362.124952) (xy 376.780051 -362.180128) (xy 376.763983 -362.233535) (xy 376.740311 -362.284032)
			(xy 376.709538 -362.330545) (xy 376.672321 -362.372082) (xy 376.629453 -362.407757) (xy 376.581847 -362.436811)
			(xy 376.530518 -362.458623) (xy 376.476561 -362.472729) (xy 376.421124 -362.478829) (xy 376.36539 -362.476792)
			(xy 376.310547 -362.466662) (xy 376.257763 -362.448655) (xy 376.208163 -362.423154) (xy 376.162805 -362.390703)
			(xy 376.122656 -362.351994) (xy 376.08857 -362.307851) (xy 376.061274 -362.259216) (xy 376.041351 -362.207125)
			(xy 376.029225 -362.152688) (xy 376.025154 -362.097066) (xy 363.258608 -362.097066) (xy 363.258608 -363.018832)
			(xy 363.790482 -363.018832) (xy 363.794553 -362.96321) (xy 363.806679 -362.908773) (xy 363.826602 -362.856682)
			(xy 363.853898 -362.808047) (xy 363.887984 -362.763904) (xy 363.928133 -362.725195) (xy 363.973491 -362.692744)
			(xy 364.023091 -362.667243) (xy 364.075875 -362.649236) (xy 364.130718 -362.639106) (xy 364.186452 -362.637069)
			(xy 364.241889 -362.643169) (xy 364.295846 -362.657275) (xy 364.347175 -362.679087) (xy 364.394781 -362.708141)
			(xy 364.437649 -362.743816) (xy 364.474866 -362.785353) (xy 364.505639 -362.831866) (xy 364.529311 -362.882363)
			(xy 364.545379 -362.93577) (xy 364.553499 -362.990946) (xy 364.554008 -363.018832) (xy 364.553499 -363.046718)
			(xy 364.545379 -363.101894) (xy 364.529311 -363.155301) (xy 364.505639 -363.205798) (xy 364.474866 -363.252311)
			(xy 364.437649 -363.293848) (xy 364.394781 -363.329523) (xy 364.347175 -363.358577) (xy 364.295846 -363.380389)
			(xy 364.241889 -363.394495) (xy 364.186452 -363.400595) (xy 364.130718 -363.398558) (xy 364.075875 -363.388428)
			(xy 364.023091 -363.370421) (xy 363.973491 -363.34492) (xy 363.928133 -363.312469) (xy 363.887984 -363.27376)
			(xy 363.853898 -363.229617) (xy 363.826602 -363.180982) (xy 363.806679 -363.128891) (xy 363.794553 -363.074454)
			(xy 363.790482 -363.018832) (xy 363.258608 -363.018832) (xy 363.258608 -363.095286) (xy 363.90199 -363.738668)
			(xy 364.62589 -363.738668) (xy 365.566452 -362.79836) (xy 365.584515 -362.781065) (xy 365.626068 -362.753249)
			(xy 365.672249 -362.734074) (xy 365.721283 -362.724277) (xy 365.746284 -362.723684) (xy 368.110516 -362.723684)
			(xy 368.135514 -362.724293) (xy 368.184539 -362.734103) (xy 368.230709 -362.753284) (xy 368.272254 -362.7811)
			(xy 368.290348 -362.79836) (xy 368.540284 -363.048296) (xy 383.191258 -363.048296) (xy 383.216243 -363.048877)
			(xy 383.265253 -363.058628) (xy 383.311423 -363.077744) (xy 383.352982 -363.105492) (xy 383.37109 -363.122718)
			(xy 390.271508 -370.023136) (xy 411.051248 -370.023136) (xy 412.975806 -368.098578) (xy 412.993905 -368.081344)
			(xy 413.035467 -368.053603) (xy 413.081641 -368.034499) (xy 413.130653 -368.024763) (xy 413.155638 -368.024156)
			(xy 413.652208 -368.024156) (xy 414.910016 -366.766094) (xy 414.892682 -366.745258) (xy 414.863525 -366.699569)
			(xy 414.84113 -366.650213) (xy 414.825948 -366.598183) (xy 414.818285 -366.544528) (xy 414.817814 -366.517428)
			(xy 414.8183 -366.490177) (xy 414.826056 -366.436229) (xy 414.841411 -366.383934) (xy 414.864053 -366.334357)
			(xy 414.893519 -366.288507) (xy 414.92921 -366.247316) (xy 414.970401 -366.211625) (xy 415.016251 -366.182159)
			(xy 415.065828 -366.159517) (xy 415.118123 -366.144162) (xy 415.172071 -366.136406) (xy 415.226573 -366.136406)
			(xy 415.280521 -366.144162) (xy 415.332816 -366.159517) (xy 415.382393 -366.182159) (xy 415.428243 -366.211625)
			(xy 415.469434 -366.247316) (xy 415.505125 -366.288507) (xy 415.534591 -366.334357) (xy 415.557233 -366.383934)
			(xy 415.572588 -366.436229) (xy 415.580344 -366.490177) (xy 415.58083 -366.517428) (xy 415.580287 -366.547481)
			(xy 415.570846 -366.60684) (xy 415.552217 -366.663986) (xy 415.524862 -366.717505) (xy 415.489456 -366.766076)
			(xy 415.468562 -366.787684) (xy 415.453576 -366.802416) (xy 415.453576 -366.836706) (xy 415.452942 -366.861688)
			(xy 415.443205 -366.910695) (xy 415.424104 -366.956864) (xy 415.396372 -366.998426) (xy 415.379154 -367.016538)
			(xy 413.93745 -368.458242) (xy 413.91933 -368.475453) (xy 413.877775 -368.503197) (xy 413.831608 -368.522307)
			(xy 413.782601 -368.532051) (xy 413.757618 -368.532664) (xy 413.261048 -368.532664) (xy 411.33649 -370.457222)
			(xy 411.318393 -370.474458) (xy 411.27683 -370.502198) (xy 411.230656 -370.521302) (xy 411.181643 -370.531037)
			(xy 411.156658 -370.531644) (xy 390.166098 -370.531644) (xy 390.141115 -370.531017) (xy 390.092108 -370.521279)
			(xy 390.045938 -370.502176) (xy 390.004377 -370.474442) (xy 389.986266 -370.457222) (xy 383.085848 -363.556804)
			(xy 368.434874 -363.556804) (xy 368.40989 -363.556203) (xy 368.360881 -363.546458) (xy 368.314711 -363.527348)
			(xy 368.273151 -363.499605) (xy 368.255042 -363.482382) (xy 368.005106 -363.2327) (xy 365.851694 -363.2327)
			(xy 365.197721 -363.886496) (xy 366.311686 -363.886496) (xy 366.315757 -363.830874) (xy 366.327883 -363.776437)
			(xy 366.347806 -363.724346) (xy 366.375102 -363.675711) (xy 366.409188 -363.631568) (xy 366.449337 -363.592859)
			(xy 366.494695 -363.560408) (xy 366.544295 -363.534907) (xy 366.597079 -363.5169) (xy 366.651922 -363.50677)
			(xy 366.707656 -363.504733) (xy 366.763093 -363.510833) (xy 366.81705 -363.524939) (xy 366.868379 -363.546751)
			(xy 366.915985 -363.575805) (xy 366.958853 -363.61148) (xy 366.99607 -363.653017) (xy 367.026843 -363.69953)
			(xy 367.050515 -363.750027) (xy 367.066583 -363.803434) (xy 367.074703 -363.85861) (xy 367.075212 -363.886496)
			(xy 367.074703 -363.914382) (xy 367.066583 -363.969558) (xy 367.050515 -364.022965) (xy 367.026843 -364.073462)
			(xy 366.99607 -364.119975) (xy 366.958853 -364.161512) (xy 366.915985 -364.197187) (xy 366.868379 -364.226241)
			(xy 366.81705 -364.248053) (xy 366.763093 -364.262159) (xy 366.707656 -364.268259) (xy 366.651922 -364.266222)
			(xy 366.597079 -364.256092) (xy 366.544295 -364.238085) (xy 366.494695 -364.212584) (xy 366.449337 -364.180133)
			(xy 366.409188 -364.141424) (xy 366.375102 -364.097281) (xy 366.347806 -364.048646) (xy 366.327883 -363.996555)
			(xy 366.315757 -363.942118) (xy 366.311686 -363.886496) (xy 365.197721 -363.886496) (xy 364.911132 -364.173008)
			(xy 364.89306 -364.190291) (xy 364.851507 -364.218095) (xy 364.805328 -364.237261) (xy 364.756298 -364.247052)
			(xy 364.7313 -364.247684) (xy 363.79658 -364.247684) (xy 363.771584 -364.247058) (xy 363.722561 -364.23725)
			(xy 363.67639 -364.218073) (xy 363.634844 -364.190264) (xy 363.616748 -364.173008) (xy 362.824268 -363.380528)
			(xy 362.806965 -363.362472) (xy 362.77915 -363.320917) (xy 362.759977 -363.274734) (xy 362.750184 -363.225698)
			(xy 362.749592 -363.200696) (xy 362.749592 -361.300522) (xy 361.321858 -359.872788) (xy 361.286552 -359.899458)
			(xy 361.261519 -359.917721) (xy 361.206762 -359.946721) (xy 361.148043 -359.966505) (xy 361.086901 -359.976555)
			(xy 361.05592 -359.977182) (xy 361.028664 -359.976772) (xy 360.974708 -359.969017) (xy 360.922404 -359.953662)
			(xy 360.872818 -359.931019) (xy 360.826959 -359.901549) (xy 360.785761 -359.865853) (xy 360.750063 -359.824657)
			(xy 360.720591 -359.7788) (xy 360.697945 -359.729215) (xy 360.682587 -359.676912) (xy 360.674829 -359.622956)
			(xy 360.155244 -359.622956) (xy 359.617772 -360.160316) (xy 359.617772 -360.579162) (xy 359.600496 -360.61142)
			(xy 360.771438 -360.61142) (xy 360.775509 -360.555798) (xy 360.787635 -360.501361) (xy 360.807558 -360.44927)
			(xy 360.834854 -360.400635) (xy 360.86894 -360.356492) (xy 360.909089 -360.317783) (xy 360.954447 -360.285332)
			(xy 361.004047 -360.259831) (xy 361.056831 -360.241824) (xy 361.111674 -360.231694) (xy 361.167408 -360.229657)
			(xy 361.222845 -360.235757) (xy 361.276802 -360.249863) (xy 361.328131 -360.271675) (xy 361.375737 -360.300729)
			(xy 361.418605 -360.336404) (xy 361.455822 -360.377941) (xy 361.486595 -360.424454) (xy 361.510267 -360.474951)
			(xy 361.526335 -360.528358) (xy 361.534455 -360.583534) (xy 361.534964 -360.61142) (xy 361.534455 -360.639306)
			(xy 361.526335 -360.694482) (xy 361.510267 -360.747889) (xy 361.486595 -360.798386) (xy 361.455822 -360.844899)
			(xy 361.418605 -360.886436) (xy 361.375737 -360.922111) (xy 361.328131 -360.951165) (xy 361.276802 -360.972977)
			(xy 361.222845 -360.987083) (xy 361.167408 -360.993183) (xy 361.111674 -360.991146) (xy 361.056831 -360.981016)
			(xy 361.004047 -360.963009) (xy 360.954447 -360.937508) (xy 360.909089 -360.905057) (xy 360.86894 -360.866348)
			(xy 360.834854 -360.822205) (xy 360.807558 -360.77357) (xy 360.787635 -360.721479) (xy 360.775509 -360.667042)
			(xy 360.771438 -360.61142) (xy 359.600496 -360.61142) (xy 359.552748 -360.700574) (xy 359.529471 -360.746089)
			(xy 359.489437 -360.840164) (xy 359.45709 -360.93715) (xy 359.432638 -361.036422) (xy 359.416239 -361.137337)
			(xy 359.407999 -361.239243) (xy 359.40746 -361.290362) (xy 359.40746 -361.290616) (xy 359.407991 -361.342626)
			(xy 359.416519 -361.446295) (xy 359.433501 -361.548918) (xy 359.458822 -361.649809) (xy 359.492313 -361.748289)
			(xy 359.533749 -361.843699) (xy 359.557828 -361.889802) (xy 359.617772 -362.00207) (xy 359.617772 -362.097066)
			(xy 359.661206 -362.122974) (xy 360.152188 -362.613956) (xy 360.236008 -362.613956) (xy 360.250944 -362.61343)
			(xy 360.279538 -362.604784) (xy 360.304407 -362.588235) (xy 360.323424 -362.565197) (xy 360.334961 -362.537642)
			(xy 360.338032 -362.507928) (xy 360.332373 -362.478596) (xy 360.325924 -362.465112) (xy 360.312086 -362.43754)
			(xy 360.292512 -362.379041) (xy 360.282595 -362.318156) (xy 360.281982 -362.287312) (xy 360.282511 -362.258805)
			(xy 360.290997 -362.202425) (xy 360.307779 -362.147937) (xy 360.332486 -362.096554) (xy 360.364566 -362.049421)
			(xy 360.403305 -362.007588) (xy 360.425238 -361.98937) (xy 360.436329 -361.979918) (xy 360.453047 -361.956064)
			(xy 360.462361 -361.928464) (xy 360.463515 -361.899357) (xy 360.456415 -361.871106) (xy 360.441639 -361.846003)
			(xy 360.431334 -361.8357) (xy 360.41056 -361.817497) (xy 360.373965 -361.776127) (xy 360.343722 -361.72991)
			(xy 360.320464 -361.679813) (xy 360.304677 -361.626885) (xy 360.296691 -361.572232) (xy 360.296206 -361.544616)
			(xy 360.296692 -361.517365) (xy 360.304448 -361.463417) (xy 360.319803 -361.411122) (xy 360.342445 -361.361545)
			(xy 360.371911 -361.315695) (xy 360.407602 -361.274504) (xy 360.448793 -361.238813) (xy 360.494643 -361.209347)
			(xy 360.54422 -361.186705) (xy 360.596515 -361.17135) (xy 360.650463 -361.163594) (xy 360.704965 -361.163594)
			(xy 360.758913 -361.17135) (xy 360.811208 -361.186705) (xy 360.860785 -361.209347) (xy 360.906635 -361.238813)
			(xy 360.947826 -361.274504) (xy 360.983517 -361.315695) (xy 361.012983 -361.361545) (xy 361.035625 -361.411122)
			(xy 361.05098 -361.463417) (xy 361.058736 -361.517365) (xy 361.059222 -361.544616) (xy 361.058706 -361.57326)
			(xy 361.050137 -361.629902) (xy 361.033192 -361.684627) (xy 361.008254 -361.736201) (xy 360.975884 -361.783466)
			(xy 360.936809 -361.825359) (xy 360.914696 -361.843574) (xy 360.90367 -361.853363) (xy 360.887294 -361.877867)
			(xy 360.878578 -361.906021) (xy 360.878245 -361.935492) (xy 360.886323 -361.963835) (xy 360.902142 -361.988703)
			(xy 360.912918 -361.998768) (xy 360.933268 -362.016955) (xy 360.969071 -362.058149) (xy 360.998635 -362.104026)
			(xy 361.021356 -362.153649) (xy 361.036771 -362.206005) (xy 361.044565 -362.260023) (xy 361.044998 -362.287312)
			(xy 361.044487 -362.315908) (xy 361.03595 -362.372459) (xy 361.01907 -362.427104) (xy 360.994223 -362.478617)
			(xy 360.961967 -362.525845) (xy 360.94289 -362.547154) (xy 360.932692 -362.558987) (xy 360.91936 -362.587219)
			(xy 360.915159 -362.618157) (xy 360.920479 -362.648922) (xy 360.934827 -362.676652) (xy 360.94543 -362.688124)
			(xy 361.294934 -363.037628) (xy 361.302554 -363.044486) (xy 361.309789 -363.051154) (xy 361.323639 -363.065131)
			(xy 361.33024 -363.072426) (xy 361.331256 -363.073696) (xy 361.50042 -363.24286) (xy 361.50042 -363.878368)
			(xy 361.646978 -363.941868) (xy 361.671362 -363.919008) (xy 361.692689 -363.899795) (xy 361.740029 -363.86733)
			(xy 361.791691 -363.842311) (xy 361.846515 -363.8253) (xy 361.903265 -363.81668) (xy 361.931966 -363.816138)
			(xy 361.93222 -363.816138) (xy 361.959488 -363.816626) (xy 362.01347 -363.82439) (xy 362.065797 -363.839757)
			(xy 362.115405 -363.862414) (xy 362.161283 -363.891901) (xy 362.202498 -363.927616) (xy 362.238211 -363.968833)
			(xy 362.267695 -364.014713) (xy 362.29035 -364.064322) (xy 362.305714 -364.11665) (xy 362.313476 -364.170632)
			(xy 362.313476 -364.225168) (xy 362.305714 -364.27915) (xy 362.29035 -364.331478) (xy 362.267695 -364.381087)
			(xy 362.238211 -364.426967) (xy 362.202498 -364.468184) (xy 362.161283 -364.503899) (xy 362.115405 -364.533386)
			(xy 362.065797 -364.556043) (xy 362.01347 -364.57141) (xy 361.959488 -364.579174) (xy 361.93222 -364.579662)
			(xy 361.90458 -364.579173) (xy 361.849879 -364.571199) (xy 361.796902 -364.555415) (xy 361.746756 -364.532151)
			(xy 361.700493 -364.501894) (xy 361.659079 -364.465279) (xy 361.623383 -364.42307) (xy 361.594151 -364.376152)
			(xy 361.571996 -364.325507) (xy 361.564174 -364.298992) (xy 361.424474 -364.267496) (xy 361.249468 -364.442756)
			(xy 361.249468 -364.978696) (xy 365.31245 -364.978696) (xy 365.316521 -364.923074) (xy 365.328647 -364.868637)
			(xy 365.34857 -364.816546) (xy 365.375866 -364.767911) (xy 365.409952 -364.723768) (xy 365.450101 -364.685059)
			(xy 365.495459 -364.652608) (xy 365.545059 -364.627107) (xy 365.597843 -364.6091) (xy 365.652686 -364.59897)
			(xy 365.70842 -364.596933) (xy 365.763857 -364.603033) (xy 365.817814 -364.617139) (xy 365.869143 -364.638951)
			(xy 365.916749 -364.668005) (xy 365.959617 -364.70368) (xy 365.996834 -364.745217) (xy 366.027607 -364.79173)
			(xy 366.051279 -364.842227) (xy 366.067347 -364.895634) (xy 366.075467 -364.95081) (xy 366.075976 -364.978696)
			(xy 366.075467 -365.006582) (xy 366.067347 -365.061758) (xy 366.051279 -365.115165) (xy 366.027607 -365.165662)
			(xy 365.996834 -365.212175) (xy 365.959617 -365.253712) (xy 365.916749 -365.289387) (xy 365.869143 -365.318441)
			(xy 365.817814 -365.340253) (xy 365.763857 -365.354359) (xy 365.70842 -365.360459) (xy 365.652686 -365.358422)
			(xy 365.597843 -365.348292) (xy 365.545059 -365.330285) (xy 365.495459 -365.304784) (xy 365.450101 -365.272333)
			(xy 365.409952 -365.233624) (xy 365.375866 -365.189481) (xy 365.34857 -365.140846) (xy 365.328647 -365.088755)
			(xy 365.316521 -365.034318) (xy 365.31245 -364.978696) (xy 361.249468 -364.978696) (xy 361.249468 -365.005874)
			(xy 360.948986 -365.306356) (xy 360.29138 -365.306356) (xy 360.000804 -365.015526) (xy 360.000804 -364.831884)
			(xy 359.496868 -364.831884) (xy 359.48342 -364.8323) (xy 359.457459 -364.839333) (xy 359.434235 -364.852901)
			(xy 359.415361 -364.872063) (xy 359.402146 -364.89549) (xy 359.395508 -364.921555) (xy 359.395268 -364.935008)
			(xy 359.395268 -364.940596) (xy 359.394782 -364.967847) (xy 359.387026 -365.021795) (xy 359.371671 -365.07409)
			(xy 359.349029 -365.123667) (xy 359.319563 -365.169517) (xy 359.283872 -365.210708) (xy 359.242681 -365.246399)
			(xy 359.196831 -365.275865) (xy 359.147254 -365.298507) (xy 359.094959 -365.313862) (xy 359.041011 -365.321618)
			(xy 358.986509 -365.321618) (xy 358.932561 -365.313862) (xy 358.880266 -365.298507) (xy 358.830689 -365.275865)
			(xy 358.784839 -365.246399) (xy 358.743648 -365.210708) (xy 358.707957 -365.169517) (xy 358.678491 -365.123667)
			(xy 358.655849 -365.07409) (xy 358.640494 -365.021795) (xy 358.632738 -364.967847) (xy 358.632252 -364.940596)
			(xy 358.632252 -364.939834) (xy 358.632869 -364.910062) (xy 358.642189 -364.851249) (xy 358.650794 -364.82274)
			(xy 358.621698 -364.808995) (xy 358.568205 -364.773237) (xy 358.544368 -364.75162) (xy 358.507714 -364.756815)
			(xy 358.433724 -364.759344) (xy 358.359971 -364.7529) (xy 358.323642 -364.745778) (xy 358.296563 -364.75899)
			(xy 358.23928 -364.777665) (xy 358.179777 -364.787124) (xy 358.149652 -364.787688) (xy 358.119525 -364.787143)
			(xy 358.060015 -364.777704) (xy 358.002736 -364.759006) (xy 357.975662 -364.745778) (xy 357.962521 -364.747475)
			(xy 357.93608 -364.749252) (xy 357.92283 -364.749334) (xy 357.894614 -364.748821) (xy 357.8388 -364.740501)
			(xy 357.784819 -364.724052) (xy 357.733848 -364.699833) (xy 357.687 -364.668373) (xy 357.665782 -364.649766)
			(xy 357.654596 -364.640267) (xy 357.628167 -364.627537) (xy 357.599211 -364.62284) (xy 357.570114 -364.626565)
			(xy 357.543274 -364.638403) (xy 357.520904 -364.657379) (xy 357.504847 -364.68193) (xy 357.496428 -364.71003)
			(xy 357.495856 -364.724696) (xy 357.495856 -365.789718) (xy 357.87914 -365.789718) (xy 357.883211 -365.734096)
			(xy 357.895337 -365.679659) (xy 357.91526 -365.627568) (xy 357.942556 -365.578933) (xy 357.976642 -365.53479)
			(xy 358.016791 -365.496081) (xy 358.062149 -365.46363) (xy 358.111749 -365.438129) (xy 358.164533 -365.420122)
			(xy 358.219376 -365.409992) (xy 358.27511 -365.407955) (xy 358.330547 -365.414055) (xy 358.384504 -365.428161)
			(xy 358.435833 -365.449973) (xy 358.483439 -365.479027) (xy 358.526307 -365.514702) (xy 358.563524 -365.556239)
			(xy 358.594297 -365.602752) (xy 358.612049 -365.64062) (xy 380.886211 -365.64062) (xy 380.890247 -365.557173)
			(xy 380.902319 -365.474505) (xy 380.922312 -365.393388) (xy 380.950041 -365.314579) (xy 380.985247 -365.238814)
			(xy 381.027601 -365.166801) (xy 381.076707 -365.099212) (xy 381.132108 -365.036678) (xy 381.193285 -364.979783)
			(xy 381.259668 -364.929057) (xy 381.330636 -364.884976) (xy 381.405528 -364.84795) (xy 381.483644 -364.818324)
			(xy 381.564254 -364.796376) (xy 381.646606 -364.782311) (xy 381.729932 -364.776259) (xy 381.813452 -364.778278)
			(xy 381.896388 -364.788348) (xy 381.977964 -364.806376) (xy 382.05742 -364.832193) (xy 382.134013 -364.865558)
			(xy 382.207029 -364.906159) (xy 382.275785 -364.953618) (xy 382.339639 -365.007491) (xy 382.397996 -365.067276)
			(xy 382.450311 -365.132413) (xy 382.496094 -365.202296) (xy 382.534919 -365.276271) (xy 382.566424 -365.353648)
			(xy 382.590313 -365.433705) (xy 382.606364 -365.515693) (xy 382.614427 -365.598848) (xy 382.614932 -365.64062)
			(xy 382.614427 -365.682392) (xy 382.606364 -365.765547) (xy 382.590313 -365.847535) (xy 382.566424 -365.927592)
			(xy 382.534919 -366.004969) (xy 382.496094 -366.078944) (xy 382.450311 -366.148827) (xy 382.397996 -366.213964)
			(xy 382.339639 -366.273749) (xy 382.275785 -366.327622) (xy 382.207029 -366.375081) (xy 382.134013 -366.415682)
			(xy 382.05742 -366.449047) (xy 381.977964 -366.474864) (xy 381.896388 -366.492892) (xy 381.813452 -366.502962)
			(xy 381.729932 -366.504981) (xy 381.646606 -366.498929) (xy 381.564254 -366.484864) (xy 381.483644 -366.462916)
			(xy 381.405528 -366.43329) (xy 381.330636 -366.396264) (xy 381.259668 -366.352183) (xy 381.193285 -366.301457)
			(xy 381.132108 -366.244562) (xy 381.076707 -366.182028) (xy 381.027601 -366.114439) (xy 380.985247 -366.042426)
			(xy 380.950041 -365.966661) (xy 380.922312 -365.887852) (xy 380.902319 -365.806735) (xy 380.890247 -365.724067)
			(xy 380.886211 -365.64062) (xy 358.612049 -365.64062) (xy 358.617969 -365.653249) (xy 358.634037 -365.706656)
			(xy 358.642157 -365.761832) (xy 358.642666 -365.789718) (xy 358.642157 -365.817604) (xy 358.634037 -365.87278)
			(xy 358.617969 -365.926187) (xy 358.594297 -365.976684) (xy 358.563524 -366.023197) (xy 358.526307 -366.064734)
			(xy 358.483439 -366.100409) (xy 358.435833 -366.129463) (xy 358.384504 -366.151275) (xy 358.330547 -366.165381)
			(xy 358.27511 -366.171481) (xy 358.219376 -366.169444) (xy 358.164533 -366.159314) (xy 358.111749 -366.141307)
			(xy 358.062149 -366.115806) (xy 358.016791 -366.083355) (xy 357.976642 -366.044646) (xy 357.942556 -366.000503)
			(xy 357.91526 -365.951868) (xy 357.895337 -365.899777) (xy 357.883211 -365.84534) (xy 357.87914 -365.789718)
			(xy 357.495856 -365.789718) (xy 357.495856 -365.98733) (xy 358.174544 -366.666272) (xy 358.516428 -367.008156)
			(xy 365.682276 -367.008156) (xy 365.70634 -367.009362) (xy 365.753395 -367.019691) (xy 365.797663 -367.038695)
			(xy 365.837561 -367.065694) (xy 365.854996 -367.082324) (xy 366.548906 -367.776252) (xy 369.189506 -367.776252)
			(xy 369.193577 -367.72063) (xy 369.205703 -367.666193) (xy 369.225626 -367.614102) (xy 369.252922 -367.565467)
			(xy 369.287008 -367.521324) (xy 369.327157 -367.482615) (xy 369.372515 -367.450164) (xy 369.422115 -367.424663)
			(xy 369.474899 -367.406656) (xy 369.529742 -367.396526) (xy 369.585476 -367.394489) (xy 369.640913 -367.400589)
			(xy 369.69487 -367.414695) (xy 369.746199 -367.436507) (xy 369.793805 -367.465561) (xy 369.836673 -367.501236)
			(xy 369.87389 -367.542773) (xy 369.904663 -367.589286) (xy 369.928335 -367.639783) (xy 369.944403 -367.69319)
			(xy 369.952523 -367.748366) (xy 369.953032 -367.776252) (xy 369.952523 -367.804138) (xy 369.944403 -367.859314)
			(xy 369.928335 -367.912721) (xy 369.905269 -367.961926) (xy 370.232686 -367.961926) (xy 370.23319 -367.933008)
			(xy 370.241918 -367.875835) (xy 370.259176 -367.820634) (xy 370.28457 -367.768672) (xy 370.317518 -367.721139)
			(xy 370.357264 -367.679124) (xy 370.379752 -367.660936) (xy 370.391535 -367.651012) (xy 370.409059 -367.625697)
			(xy 370.418241 -367.59631) (xy 370.418245 -367.565522) (xy 370.409073 -367.536131) (xy 370.391557 -367.510811)
			(xy 370.379752 -367.500916) (xy 370.357266 -367.482728) (xy 370.317533 -367.440706) (xy 370.284596 -367.39317)
			(xy 370.259208 -367.341209) (xy 370.241952 -367.286011) (xy 370.233222 -367.228842) (xy 370.232686 -367.199926)
			(xy 370.233172 -367.172675) (xy 370.240928 -367.118727) (xy 370.256283 -367.066432) (xy 370.278925 -367.016855)
			(xy 370.308391 -366.971005) (xy 370.344082 -366.929814) (xy 370.385273 -366.894123) (xy 370.431123 -366.864657)
			(xy 370.4807 -366.842015) (xy 370.532995 -366.82666) (xy 370.586943 -366.818904) (xy 370.641445 -366.818904)
			(xy 370.695393 -366.82666) (xy 370.747688 -366.842015) (xy 370.797265 -366.864657) (xy 370.843115 -366.894123)
			(xy 370.884306 -366.929814) (xy 370.919997 -366.971005) (xy 370.949463 -367.016855) (xy 370.972105 -367.066432)
			(xy 370.98746 -367.118727) (xy 370.995216 -367.172675) (xy 370.995702 -367.199926) (xy 370.99513 -367.228841)
			(xy 370.986412 -367.28601) (xy 370.969165 -367.341207) (xy 370.943783 -367.393169) (xy 370.910849 -367.440705)
			(xy 370.871117 -367.482724) (xy 370.848636 -367.500916) (xy 370.836802 -367.510784) (xy 370.819281 -367.536114)
			(xy 370.810106 -367.565516) (xy 370.810111 -367.596316) (xy 370.819295 -367.625715) (xy 370.836825 -367.65104)
			(xy 370.848636 -367.660936) (xy 370.871144 -367.679098) (xy 370.910876 -367.721125) (xy 370.943811 -367.768666)
			(xy 370.969195 -367.820633) (xy 370.986446 -367.875835) (xy 370.99517 -367.933008) (xy 370.995702 -367.961926)
			(xy 372.38051 -367.961926) (xy 372.381043 -367.93301) (xy 372.389769 -367.875839) (xy 372.407023 -367.82064)
			(xy 372.432412 -367.768678) (xy 372.465353 -367.721144) (xy 372.505092 -367.679127) (xy 372.527576 -367.660936)
			(xy 372.539356 -367.651011) (xy 372.556876 -367.625695) (xy 372.566056 -367.596309) (xy 372.56606 -367.565523)
			(xy 372.55689 -367.536134) (xy 372.539378 -367.510813) (xy 372.527576 -367.500916) (xy 372.505095 -367.482722)
			(xy 372.465361 -367.440702) (xy 372.432422 -367.393168) (xy 372.407034 -367.341207) (xy 372.389777 -367.28601)
			(xy 372.381046 -367.228842) (xy 372.38051 -367.199926) (xy 372.380996 -367.172675) (xy 372.388752 -367.118727)
			(xy 372.404107 -367.066432) (xy 372.426749 -367.016855) (xy 372.456215 -366.971005) (xy 372.491906 -366.929814)
			(xy 372.533097 -366.894123) (xy 372.578947 -366.864657) (xy 372.628524 -366.842015) (xy 372.680819 -366.82666)
			(xy 372.734767 -366.818904) (xy 372.789269 -366.818904) (xy 372.843217 -366.82666) (xy 372.895512 -366.842015)
			(xy 372.945089 -366.864657) (xy 372.990939 -366.894123) (xy 373.03213 -366.929814) (xy 373.067821 -366.971005)
			(xy 373.097287 -367.016855) (xy 373.119929 -367.066432) (xy 373.135284 -367.118727) (xy 373.14304 -367.172675)
			(xy 373.143526 -367.199926) (xy 373.142982 -367.228842) (xy 373.134263 -367.286014) (xy 373.117011 -367.341213)
			(xy 373.091625 -367.393176) (xy 373.058684 -367.44071) (xy 373.018945 -367.482726) (xy 372.99646 -367.500916)
			(xy 372.984624 -367.510783) (xy 372.967099 -367.536112) (xy 372.957922 -367.565515) (xy 372.957926 -367.596317)
			(xy 372.967113 -367.625716) (xy 372.984647 -367.651041) (xy 372.99646 -367.660936) (xy 373.018952 -367.679117)
			(xy 373.058689 -367.721137) (xy 373.091628 -367.768674) (xy 373.117015 -367.820638) (xy 373.134269 -367.875838)
			(xy 373.142994 -367.933009) (xy 373.143526 -367.961926) (xy 374.51411 -367.961926) (xy 374.514643 -367.93301)
			(xy 374.523369 -367.875839) (xy 374.540623 -367.82064) (xy 374.566012 -367.768678) (xy 374.598953 -367.721144)
			(xy 374.638692 -367.679127) (xy 374.661176 -367.660936) (xy 374.672956 -367.651011) (xy 374.690476 -367.625695)
			(xy 374.699656 -367.596309) (xy 374.69966 -367.565523) (xy 374.69049 -367.536134) (xy 374.672978 -367.510813)
			(xy 374.661176 -367.500916) (xy 374.638695 -367.482722) (xy 374.598961 -367.440702) (xy 374.566022 -367.393168)
			(xy 374.540634 -367.341207) (xy 374.523377 -367.28601) (xy 374.514646 -367.228842) (xy 374.51411 -367.199926)
			(xy 374.514596 -367.172675) (xy 374.522352 -367.118727) (xy 374.537707 -367.066432) (xy 374.560349 -367.016855)
			(xy 374.589815 -366.971005) (xy 374.625506 -366.929814) (xy 374.666697 -366.894123) (xy 374.712547 -366.864657)
			(xy 374.762124 -366.842015) (xy 374.814419 -366.82666) (xy 374.868367 -366.818904) (xy 374.922869 -366.818904)
			(xy 374.976817 -366.82666) (xy 375.029112 -366.842015) (xy 375.078689 -366.864657) (xy 375.124539 -366.894123)
			(xy 375.16573 -366.929814) (xy 375.201421 -366.971005) (xy 375.230887 -367.016855) (xy 375.253529 -367.066432)
			(xy 375.268884 -367.118727) (xy 375.27664 -367.172675) (xy 375.277126 -367.199926) (xy 375.276582 -367.228842)
			(xy 375.267863 -367.286014) (xy 375.250611 -367.341213) (xy 375.225225 -367.393176) (xy 375.192284 -367.44071)
			(xy 375.152545 -367.482726) (xy 375.13006 -367.500916) (xy 375.118224 -367.510783) (xy 375.100699 -367.536112)
			(xy 375.091522 -367.565515) (xy 375.091526 -367.596317) (xy 375.100713 -367.625716) (xy 375.118247 -367.651041)
			(xy 375.13006 -367.660936) (xy 375.152552 -367.679117) (xy 375.192289 -367.721137) (xy 375.225228 -367.768674)
			(xy 375.250615 -367.820638) (xy 375.267869 -367.875838) (xy 375.276594 -367.933009) (xy 375.276603 -367.933478)
			(xy 376.66676 -367.933478) (xy 376.667312 -367.904562) (xy 376.676031 -367.847391) (xy 376.693281 -367.792192)
			(xy 376.718666 -367.74023) (xy 376.751605 -367.692695) (xy 376.791342 -367.650678) (xy 376.813826 -367.632488)
			(xy 376.825649 -367.622612) (xy 376.84316 -367.597281) (xy 376.852329 -367.567884) (xy 376.852325 -367.537089)
			(xy 376.843148 -367.507694) (xy 376.825631 -367.482368) (xy 376.813826 -367.472468) (xy 376.791333 -367.454288)
			(xy 376.751597 -367.412267) (xy 376.718658 -367.36473) (xy 376.693271 -367.312766) (xy 376.676018 -367.257566)
			(xy 376.667293 -367.200395) (xy 376.66676 -367.171478) (xy 376.667246 -367.144227) (xy 376.675002 -367.090279)
			(xy 376.690357 -367.037984) (xy 376.712999 -366.988407) (xy 376.742465 -366.942557) (xy 376.778156 -366.901366)
			(xy 376.819347 -366.865675) (xy 376.865197 -366.836209) (xy 376.914774 -366.813567) (xy 376.967069 -366.798212)
			(xy 377.021017 -366.790456) (xy 377.075519 -366.790456) (xy 377.129467 -366.798212) (xy 377.181762 -366.813567)
			(xy 377.231339 -366.836209) (xy 377.277189 -366.865675) (xy 377.31838 -366.901366) (xy 377.354071 -366.942557)
			(xy 377.383537 -366.988407) (xy 377.406179 -367.037984) (xy 377.421534 -367.090279) (xy 377.42929 -367.144227)
			(xy 377.429776 -367.171478) (xy 377.429251 -367.200395) (xy 377.420525 -367.257566) (xy 377.403269 -367.312765)
			(xy 377.377878 -367.364727) (xy 377.344935 -367.412261) (xy 377.305195 -367.454278) (xy 377.28271 -367.472468)
			(xy 377.270927 -367.48239) (xy 377.25341 -367.507707) (xy 377.244232 -367.537093) (xy 377.244228 -367.56788)
			(xy 377.253398 -367.597269) (xy 377.270909 -367.62259) (xy 377.28271 -367.632488) (xy 377.30519 -367.650683)
			(xy 377.344925 -367.692702) (xy 377.377864 -367.740237) (xy 377.403253 -367.792197) (xy 377.42051 -367.847394)
			(xy 377.42924 -367.904562) (xy 377.429776 -367.933478) (xy 377.42929 -367.960729) (xy 377.421534 -368.014677)
			(xy 377.406179 -368.066972) (xy 377.383537 -368.116549) (xy 377.354071 -368.162399) (xy 377.336143 -368.18309)
			(xy 380.86182 -368.18309) (xy 380.86182 -368.098394) (xy 380.869871 -368.01408) (xy 380.8859 -367.930914)
			(xy 380.909761 -367.849647) (xy 380.94124 -367.771017) (xy 380.980051 -367.695736) (xy 381.025841 -367.624484)
			(xy 381.078197 -367.557908) (xy 381.136645 -367.49661) (xy 381.200655 -367.441145) (xy 381.269647 -367.392016)
			(xy 381.342997 -367.349667) (xy 381.42004 -367.314483) (xy 381.500079 -367.286781) (xy 381.582388 -367.266813)
			(xy 381.666223 -367.25476) (xy 381.750824 -367.25073) (xy 381.835425 -367.25476) (xy 381.91926 -367.266813)
			(xy 382.001569 -367.286781) (xy 382.081608 -367.314483) (xy 382.158651 -367.349667) (xy 382.232001 -367.392016)
			(xy 382.300993 -367.441145) (xy 382.365003 -367.49661) (xy 382.423451 -367.557908) (xy 382.475807 -367.624484)
			(xy 382.521597 -367.695736) (xy 382.560408 -367.771017) (xy 382.591887 -367.849647) (xy 382.615748 -367.930914)
			(xy 382.631777 -368.01408) (xy 382.639828 -368.098394) (xy 382.640332 -368.140742) (xy 382.639828 -368.18309)
			(xy 382.631777 -368.267404) (xy 382.615748 -368.35057) (xy 382.591887 -368.431837) (xy 382.560408 -368.510467)
			(xy 382.521597 -368.585748) (xy 382.475807 -368.657) (xy 382.423451 -368.723576) (xy 382.365003 -368.784874)
			(xy 382.300993 -368.840339) (xy 382.232001 -368.889468) (xy 382.158651 -368.931817) (xy 382.081608 -368.967001)
			(xy 382.001569 -368.994703) (xy 381.91926 -369.014671) (xy 381.835425 -369.026724) (xy 381.750824 -369.030755)
			(xy 381.666223 -369.026724) (xy 381.582388 -369.014671) (xy 381.500079 -368.994703) (xy 381.42004 -368.967001)
			(xy 381.342997 -368.931817) (xy 381.269647 -368.889468) (xy 381.200655 -368.840339) (xy 381.136645 -368.784874)
			(xy 381.078197 -368.723576) (xy 381.025841 -368.657) (xy 380.980051 -368.585748) (xy 380.94124 -368.510467)
			(xy 380.909761 -368.431837) (xy 380.8859 -368.35057) (xy 380.869871 -368.267404) (xy 380.86182 -368.18309)
			(xy 377.336143 -368.18309) (xy 377.31838 -368.20359) (xy 377.277189 -368.239281) (xy 377.231339 -368.268747)
			(xy 377.181762 -368.291389) (xy 377.129467 -368.306744) (xy 377.075519 -368.3145) (xy 377.021017 -368.3145)
			(xy 376.967069 -368.306744) (xy 376.914774 -368.291389) (xy 376.865197 -368.268747) (xy 376.819347 -368.239281)
			(xy 376.778156 -368.20359) (xy 376.742465 -368.162399) (xy 376.712999 -368.116549) (xy 376.690357 -368.066972)
			(xy 376.675002 -368.014677) (xy 376.667246 -367.960729) (xy 376.66676 -367.933478) (xy 375.276603 -367.933478)
			(xy 375.277126 -367.961926) (xy 375.27664 -367.989177) (xy 375.268884 -368.043125) (xy 375.253529 -368.09542)
			(xy 375.230887 -368.144997) (xy 375.201421 -368.190847) (xy 375.16573 -368.232038) (xy 375.124539 -368.267729)
			(xy 375.078689 -368.297195) (xy 375.029112 -368.319837) (xy 374.976817 -368.335192) (xy 374.922869 -368.342948)
			(xy 374.868367 -368.342948) (xy 374.814419 -368.335192) (xy 374.762124 -368.319837) (xy 374.712547 -368.297195)
			(xy 374.666697 -368.267729) (xy 374.625506 -368.232038) (xy 374.589815 -368.190847) (xy 374.560349 -368.144997)
			(xy 374.537707 -368.09542) (xy 374.522352 -368.043125) (xy 374.514596 -367.989177) (xy 374.51411 -367.961926)
			(xy 373.143526 -367.961926) (xy 373.14304 -367.989177) (xy 373.135284 -368.043125) (xy 373.119929 -368.09542)
			(xy 373.097287 -368.144997) (xy 373.067821 -368.190847) (xy 373.03213 -368.232038) (xy 372.990939 -368.267729)
			(xy 372.945089 -368.297195) (xy 372.895512 -368.319837) (xy 372.843217 -368.335192) (xy 372.789269 -368.342948)
			(xy 372.734767 -368.342948) (xy 372.680819 -368.335192) (xy 372.628524 -368.319837) (xy 372.578947 -368.297195)
			(xy 372.533097 -368.267729) (xy 372.491906 -368.232038) (xy 372.456215 -368.190847) (xy 372.426749 -368.144997)
			(xy 372.404107 -368.09542) (xy 372.388752 -368.043125) (xy 372.380996 -367.989177) (xy 372.38051 -367.961926)
			(xy 370.995702 -367.961926) (xy 370.995216 -367.989177) (xy 370.98746 -368.043125) (xy 370.972105 -368.09542)
			(xy 370.949463 -368.144997) (xy 370.919997 -368.190847) (xy 370.884306 -368.232038) (xy 370.843115 -368.267729)
			(xy 370.797265 -368.297195) (xy 370.747688 -368.319837) (xy 370.695393 -368.335192) (xy 370.641445 -368.342948)
			(xy 370.586943 -368.342948) (xy 370.532995 -368.335192) (xy 370.4807 -368.319837) (xy 370.431123 -368.297195)
			(xy 370.385273 -368.267729) (xy 370.344082 -368.232038) (xy 370.308391 -368.190847) (xy 370.278925 -368.144997)
			(xy 370.256283 -368.09542) (xy 370.240928 -368.043125) (xy 370.233172 -367.989177) (xy 370.232686 -367.961926)
			(xy 369.905269 -367.961926) (xy 369.904663 -367.963218) (xy 369.87389 -368.009731) (xy 369.836673 -368.051268)
			(xy 369.793805 -368.086943) (xy 369.746199 -368.115997) (xy 369.69487 -368.137809) (xy 369.640913 -368.151915)
			(xy 369.585476 -368.158015) (xy 369.529742 -368.155978) (xy 369.474899 -368.145848) (xy 369.422115 -368.127841)
			(xy 369.372515 -368.10234) (xy 369.327157 -368.069889) (xy 369.287008 -368.03118) (xy 369.252922 -367.987037)
			(xy 369.225626 -367.938402) (xy 369.205703 -367.886311) (xy 369.193577 -367.831874) (xy 369.189506 -367.776252)
			(xy 366.548906 -367.776252) (xy 371.071752 -372.299218) (xy 413.591022 -372.299218) (xy 413.594749 -372.24597)
			(xy 413.605863 -372.193761) (xy 413.624146 -372.143611) (xy 413.649242 -372.096499) (xy 413.68066 -372.053346)
			(xy 413.717787 -372.014993) (xy 413.738568 -371.99824) (xy 413.750345 -371.988311) (xy 413.767866 -371.962997)
			(xy 413.777047 -371.933611) (xy 413.777053 -371.902825) (xy 413.767883 -371.873436) (xy 413.75037 -371.848116)
			(xy 413.738568 -371.83822) (xy 413.716087 -371.820026) (xy 413.676354 -371.778006) (xy 413.643415 -371.730471)
			(xy 413.618027 -371.678511) (xy 413.600769 -371.623314) (xy 413.592038 -371.566146) (xy 413.591502 -371.53723)
			(xy 413.591985 -371.50986) (xy 413.599799 -371.455682) (xy 413.615284 -371.403179) (xy 413.638122 -371.353432)
			(xy 413.667843 -371.307464) (xy 413.685482 -371.286532) (xy 413.694691 -371.275184) (xy 413.706874 -371.248634)
			(xy 413.711053 -371.219723) (xy 413.706887 -371.19081) (xy 413.694716 -371.164255) (xy 413.685482 -371.152928)
			(xy 413.667873 -371.131971) (xy 413.63815 -371.086006) (xy 413.615306 -371.036264) (xy 413.599809 -370.983766)
			(xy 413.591979 -370.929591) (xy 413.591975 -370.874854) (xy 413.599799 -370.820679) (xy 413.61529 -370.768179)
			(xy 413.638128 -370.718434) (xy 413.667845 -370.672466) (xy 413.685482 -370.651532) (xy 413.694691 -370.640184)
			(xy 413.706874 -370.613634) (xy 413.711053 -370.584723) (xy 413.706887 -370.55581) (xy 413.694716 -370.529255)
			(xy 413.685482 -370.517928) (xy 413.66784 -370.496999) (xy 413.638129 -370.451025) (xy 413.615294 -370.401277)
			(xy 413.599804 -370.348775) (xy 413.591976 -370.294599) (xy 413.591502 -370.26723) (xy 413.591983 -370.239977)
			(xy 413.599736 -370.186027) (xy 413.615089 -370.133728) (xy 413.637729 -370.084148) (xy 413.667195 -370.038294)
			(xy 413.702887 -369.997101) (xy 413.744078 -369.961407) (xy 413.78993 -369.931938) (xy 413.83951 -369.909296)
			(xy 413.891807 -369.893941) (xy 413.945757 -369.886185) (xy 413.97301 -369.885722) (xy 414.000381 -369.886177)
			(xy 414.05456 -369.893997) (xy 414.107064 -369.909488) (xy 414.156811 -369.932332) (xy 414.202777 -369.962059)
			(xy 414.223708 -369.979702) (xy 414.235036 -369.988938) (xy 414.261593 -370.001114) (xy 414.29051 -370.005287)
			(xy 414.319427 -370.001114) (xy 414.345984 -369.988938) (xy 414.357312 -369.979702) (xy 414.378267 -369.962091)
			(xy 414.424233 -369.932375) (xy 414.473975 -369.909533) (xy 414.526471 -369.894036) (xy 414.580642 -369.8862)
			(xy 414.60801 -369.885722) (xy 414.636925 -369.886297) (xy 414.694094 -369.895013) (xy 414.749292 -369.912259)
			(xy 414.801254 -369.93764) (xy 414.848789 -369.970574) (xy 414.890808 -370.010307) (xy 414.909 -370.032788)
			(xy 414.918897 -370.044593) (xy 414.944221 -370.062112) (xy 414.973614 -370.071288) (xy 415.004406 -370.071288)
			(xy 415.033799 -370.062112) (xy 415.059123 -370.044593) (xy 415.06902 -370.032788) (xy 415.087197 -370.010292)
			(xy 415.12922 -369.970559) (xy 415.176758 -369.937621) (xy 415.228722 -369.912235) (xy 415.283922 -369.894981)
			(xy 415.341093 -369.886255) (xy 415.37001 -369.885722) (xy 415.397264 -369.886146) (xy 415.451218 -369.893905)
			(xy 415.503519 -369.909264) (xy 415.553101 -369.931909) (xy 415.598956 -369.961381) (xy 415.640149 -369.997079)
			(xy 415.675843 -370.038276) (xy 415.70531 -370.084134) (xy 415.72795 -370.133719) (xy 415.743304 -370.186021)
			(xy 415.751057 -370.239975) (xy 415.751518 -370.26723) (xy 415.75109 -370.294602) (xy 415.743266 -370.348783)
			(xy 415.727769 -370.401288) (xy 415.704918 -370.451034) (xy 415.675184 -370.496998) (xy 415.657538 -370.517928)
			(xy 415.648269 -370.529232) (xy 415.636091 -370.555798) (xy 415.631922 -370.584723) (xy 415.636104 -370.613646)
			(xy 415.648294 -370.640206) (xy 415.657538 -370.651532) (xy 415.67521 -370.67244) (xy 415.704936 -370.718411)
			(xy 415.727782 -370.768162) (xy 415.743277 -370.820668) (xy 415.751104 -370.87485) (xy 415.7511 -370.929595)
			(xy 415.743267 -370.983777) (xy 415.727766 -371.036281) (xy 415.704914 -371.086028) (xy 415.675182 -371.131996)
			(xy 415.657538 -371.152928) (xy 415.648269 -371.164232) (xy 415.636091 -371.190798) (xy 415.631922 -371.219723)
			(xy 415.636104 -371.248646) (xy 415.648294 -371.275206) (xy 415.657538 -371.286532) (xy 415.675165 -371.307474)
			(xy 415.704877 -371.353444) (xy 415.727715 -371.40319) (xy 415.743209 -371.455688) (xy 415.751042 -371.509862)
			(xy 415.751518 -371.53723) (xy 415.75098 -371.566147) (xy 415.74226 -371.623318) (xy 415.725008 -371.678518)
			(xy 415.69962 -371.730481) (xy 415.666678 -371.778015) (xy 415.626937 -371.820031) (xy 415.604452 -371.83822)
			(xy 415.592613 -371.848083) (xy 415.575089 -371.873414) (xy 415.565913 -371.902817) (xy 415.565919 -371.933619)
			(xy 415.575106 -371.963019) (xy 415.592639 -371.988344) (xy 415.604452 -371.99824) (xy 415.625264 -372.014958)
			(xy 415.662394 -372.053316) (xy 415.693814 -372.096475) (xy 415.718912 -372.143593) (xy 415.737196 -372.193749)
			(xy 415.748311 -372.245964) (xy 415.75026 -372.273818) (xy 416.956522 -372.273818) (xy 416.960249 -372.22057)
			(xy 416.971363 -372.168361) (xy 416.989646 -372.118211) (xy 417.014742 -372.071099) (xy 417.04616 -372.027946)
			(xy 417.083287 -371.989593) (xy 417.104068 -371.97284) (xy 417.115845 -371.962911) (xy 417.133366 -371.937597)
			(xy 417.142547 -371.908211) (xy 417.142553 -371.877425) (xy 417.133383 -371.848036) (xy 417.11587 -371.822716)
			(xy 417.104068 -371.81282) (xy 417.081587 -371.794626) (xy 417.041854 -371.752606) (xy 417.008915 -371.705071)
			(xy 416.983527 -371.653111) (xy 416.966269 -371.597914) (xy 416.957538 -371.540746) (xy 416.957002 -371.51183)
			(xy 416.957485 -371.48446) (xy 416.965299 -371.430282) (xy 416.980784 -371.377779) (xy 417.003622 -371.328032)
			(xy 417.033343 -371.282064) (xy 417.050982 -371.261132) (xy 417.060191 -371.249784) (xy 417.072374 -371.223234)
			(xy 417.076553 -371.194323) (xy 417.072387 -371.16541) (xy 417.060216 -371.138855) (xy 417.050982 -371.127528)
			(xy 417.033373 -371.106571) (xy 417.00365 -371.060606) (xy 416.980806 -371.010864) (xy 416.965309 -370.958366)
			(xy 416.957479 -370.904191) (xy 416.957475 -370.849454) (xy 416.965299 -370.795279) (xy 416.98079 -370.742779)
			(xy 417.003628 -370.693034) (xy 417.033345 -370.647066) (xy 417.050982 -370.626132) (xy 417.060191 -370.614784)
			(xy 417.072374 -370.588234) (xy 417.076553 -370.559323) (xy 417.072387 -370.53041) (xy 417.060216 -370.503855)
			(xy 417.050982 -370.492528) (xy 417.03334 -370.471599) (xy 417.003629 -370.425625) (xy 416.980794 -370.375877)
			(xy 416.965304 -370.323375) (xy 416.957476 -370.269199) (xy 416.957002 -370.24183) (xy 416.957488 -370.214579)
			(xy 416.965244 -370.160631) (xy 416.980599 -370.108336) (xy 417.003241 -370.058759) (xy 417.032707 -370.012909)
			(xy 417.068398 -369.971718) (xy 417.109589 -369.936027) (xy 417.155439 -369.906561) (xy 417.205016 -369.883919)
			(xy 417.257311 -369.868564) (xy 417.311259 -369.860808) (xy 417.365761 -369.860808) (xy 417.419709 -369.868564)
			(xy 417.472004 -369.883919) (xy 417.521581 -369.906561) (xy 417.567431 -369.936027) (xy 417.608622 -369.971718)
			(xy 417.644313 -370.012909) (xy 417.669658 -370.052346) (xy 419.301422 -370.052346) (xy 419.301948 -370.023176)
			(xy 419.310856 -369.96552) (xy 419.32844 -369.909892) (xy 419.35429 -369.857592) (xy 419.387803 -369.809837)
			(xy 419.428198 -369.767744) (xy 419.451028 -369.749578) (xy 419.461394 -369.741142) (xy 419.47769 -369.719968)
			(xy 419.487936 -369.695292) (xy 419.491432 -369.668804) (xy 419.487938 -369.642315) (xy 419.477693 -369.617638)
			(xy 419.4614 -369.596464) (xy 419.451028 -369.588034) (xy 419.428198 -369.569867) (xy 419.387796 -369.527782)
			(xy 419.35428 -369.480029) (xy 419.328434 -369.427727) (xy 419.310862 -369.372096) (xy 419.301975 -369.314436)
			(xy 419.301422 -369.285266) (xy 419.301846 -369.258013) (xy 419.309608 -369.204061) (xy 419.324969 -369.151763)
			(xy 419.347616 -369.102184) (xy 419.377089 -369.056332) (xy 419.412787 -369.015142) (xy 419.453984 -368.979451)
			(xy 419.49984 -368.949986) (xy 419.549423 -368.927347) (xy 419.601724 -368.911995) (xy 419.655676 -368.904242)
			(xy 419.68293 -368.903758) (xy 419.711846 -368.904305) (xy 419.769017 -368.913025) (xy 419.824216 -368.930276)
			(xy 419.876178 -368.955662) (xy 419.923713 -368.988602) (xy 419.96573 -369.02834) (xy 419.98392 -369.050824)
			(xy 419.993817 -369.062629) (xy 420.019141 -369.080148) (xy 420.048534 -369.089324) (xy 420.079326 -369.089324)
			(xy 420.108719 -369.080148) (xy 420.134043 -369.062629) (xy 420.14394 -369.050824) (xy 420.162115 -369.028326)
			(xy 420.204137 -368.988591) (xy 420.251675 -368.955653) (xy 420.30364 -368.930267) (xy 420.358841 -368.913014)
			(xy 420.416013 -368.90429) (xy 420.44493 -368.903758) (xy 420.473478 -368.904268) (xy 420.529933 -368.912792)
			(xy 420.584489 -368.929632) (xy 420.635927 -368.95441) (xy 420.659814 -368.970052) (xy 420.670957 -368.977114)
			(xy 420.69581 -368.985923) (xy 420.722092 -368.988052) (xy 420.748038 -368.983358) (xy 420.771908 -368.972156)
			(xy 420.792099 -368.955198) (xy 420.800022 -368.944652) (xy 420.815446 -368.923649) (xy 420.851043 -368.885595)
			(xy 420.891486 -368.852737) (xy 420.936022 -368.825686) (xy 420.983824 -368.804944) (xy 421.034003 -368.790897)
			(xy 421.085626 -368.783806) (xy 421.11168 -368.783362) (xy 421.140598 -368.783871) (xy 421.19777 -368.792599)
			(xy 421.25297 -368.809857) (xy 421.304932 -368.83525) (xy 421.352466 -368.868197) (xy 421.394481 -368.907941)
			(xy 421.41267 -368.930428) (xy 421.422567 -368.942233) (xy 421.447891 -368.959752) (xy 421.477284 -368.968928)
			(xy 421.508076 -368.968928) (xy 421.537469 -368.959752) (xy 421.562793 -368.942233) (xy 421.57269 -368.930428)
			(xy 421.590894 -368.907955) (xy 421.63291 -368.868218) (xy 421.680442 -368.835277) (xy 421.732401 -368.809886)
			(xy 421.787597 -368.792628) (xy 421.844765 -368.783898) (xy 421.87368 -368.783362) (xy 421.900929 -368.783897)
			(xy 421.954874 -368.79165) (xy 422.007166 -368.807001) (xy 422.056741 -368.829637) (xy 422.10259 -368.859099)
			(xy 422.143779 -368.894785) (xy 422.179471 -368.93597) (xy 422.208939 -368.981815) (xy 422.231582 -369.031387)
			(xy 422.24694 -369.083677) (xy 422.2547 -369.137621) (xy 422.255188 -369.16487) (xy 422.254738 -369.190913)
			(xy 422.247655 -369.242514) (xy 422.233618 -369.292672) (xy 422.212886 -369.340454) (xy 422.185846 -369.384971)
			(xy 422.153001 -369.425395) (xy 422.134284 -369.443508) (xy 422.124324 -369.453453) (xy 422.109861 -369.477587)
			(xy 422.102521 -369.504749) (xy 422.102859 -369.532884) (xy 422.110849 -369.559862) (xy 422.125888 -369.583642)
			(xy 422.136062 -369.593368) (xy 422.155664 -369.611509) (xy 422.190054 -369.652374) (xy 422.218408 -369.697637)
			(xy 422.240172 -369.746412) (xy 422.25492 -369.797746) (xy 422.262364 -369.850635) (xy 422.262808 -369.87734)
			(xy 422.262337 -369.905111) (xy 422.254279 -369.960065) (xy 422.238337 -370.01327) (xy 422.214849 -370.063601)
			(xy 422.184312 -370.109994) (xy 422.147371 -370.15147) (xy 422.12641 -370.169694) (xy 422.115726 -370.179181)
			(xy 422.099744 -370.202854) (xy 422.090956 -370.230032) (xy 422.090053 -370.258581) (xy 422.097104 -370.28626)
			(xy 422.111557 -370.310897) (xy 422.121584 -370.321078) (xy 422.139964 -370.339133) (xy 422.172132 -370.37938)
			(xy 422.198597 -370.423587) (xy 422.218876 -370.470952) (xy 422.232603 -370.520613) (xy 422.239527 -370.571668)
			(xy 422.239948 -370.59743) (xy 422.239512 -370.624801) (xy 422.231689 -370.678982) (xy 422.216194 -370.731486)
			(xy 422.193345 -370.781233) (xy 422.163613 -370.827198) (xy 422.145968 -370.848128) (xy 422.136705 -370.859435)
			(xy 422.124535 -370.886001) (xy 422.120369 -370.914923) (xy 422.124548 -370.943843) (xy 422.136729 -370.970403)
			(xy 422.145968 -370.981732) (xy 422.163638 -371.002641) (xy 422.193362 -371.048613) (xy 422.216206 -371.098363)
			(xy 422.2317 -371.150869) (xy 422.239526 -371.20505) (xy 422.239523 -371.259795) (xy 422.231691 -371.313976)
			(xy 422.21619 -371.36648) (xy 422.19334 -371.416227) (xy 422.163611 -371.462195) (xy 422.145968 -371.483128)
			(xy 422.136705 -371.494435) (xy 422.124535 -371.521001) (xy 422.120369 -371.549923) (xy 422.124548 -371.578843)
			(xy 422.136729 -371.605403) (xy 422.145968 -371.616732) (xy 422.163638 -371.637641) (xy 422.193362 -371.683613)
			(xy 422.216206 -371.733363) (xy 422.2317 -371.785869) (xy 422.235289 -371.810718) (xy 423.31665 -371.810718)
			(xy 423.31665 -371.726022) (xy 423.324701 -371.641708) (xy 423.34073 -371.558542) (xy 423.364591 -371.477275)
			(xy 423.39607 -371.398645) (xy 423.434881 -371.323364) (xy 423.480671 -371.252112) (xy 423.533027 -371.185536)
			(xy 423.591475 -371.124238) (xy 423.655485 -371.068773) (xy 423.724477 -371.019644) (xy 423.797827 -370.977295)
			(xy 423.87487 -370.942111) (xy 423.954909 -370.914409) (xy 424.037218 -370.894441) (xy 424.121053 -370.882388)
			(xy 424.205654 -370.878358) (xy 424.290255 -370.882388) (xy 424.37409 -370.894441) (xy 424.456399 -370.914409)
			(xy 424.536438 -370.942111) (xy 424.613481 -370.977295) (xy 424.686831 -371.019644) (xy 424.755823 -371.068773)
			(xy 424.819833 -371.124238) (xy 424.878281 -371.185536) (xy 424.930637 -371.252112) (xy 424.976427 -371.323364)
			(xy 425.015238 -371.398645) (xy 425.046717 -371.477275) (xy 425.070578 -371.558542) (xy 425.086607 -371.641708)
			(xy 425.094658 -371.726022) (xy 425.095162 -371.76837) (xy 425.841163 -371.76837) (xy 425.845199 -371.684923)
			(xy 425.857271 -371.602255) (xy 425.877264 -371.521138) (xy 425.904993 -371.442329) (xy 425.940199 -371.366564)
			(xy 425.982553 -371.294551) (xy 426.031659 -371.226962) (xy 426.08706 -371.164428) (xy 426.148237 -371.107533)
			(xy 426.21462 -371.056807) (xy 426.285588 -371.012726) (xy 426.36048 -370.9757) (xy 426.438596 -370.946074)
			(xy 426.519206 -370.924126) (xy 426.601558 -370.910061) (xy 426.684884 -370.904009) (xy 426.768404 -370.906028)
			(xy 426.85134 -370.916098) (xy 426.932916 -370.934126) (xy 427.012372 -370.959943) (xy 427.088965 -370.993308)
			(xy 427.161981 -371.033909) (xy 427.230737 -371.081368) (xy 427.294591 -371.135241) (xy 427.352948 -371.195026)
			(xy 427.405263 -371.260163) (xy 427.451046 -371.330046) (xy 427.489871 -371.404021) (xy 427.521376 -371.481398)
			(xy 427.545265 -371.561455) (xy 427.561316 -371.643443) (xy 427.569379 -371.726598) (xy 427.569884 -371.76837)
			(xy 427.569379 -371.810142) (xy 427.561316 -371.893297) (xy 427.545265 -371.975285) (xy 427.521376 -372.055342)
			(xy 427.489871 -372.132719) (xy 427.451046 -372.206694) (xy 427.405263 -372.276577) (xy 427.352948 -372.341714)
			(xy 427.294591 -372.401499) (xy 427.230737 -372.455372) (xy 427.161981 -372.502831) (xy 427.088965 -372.543432)
			(xy 427.012372 -372.576797) (xy 426.932916 -372.602614) (xy 426.85134 -372.620642) (xy 426.768404 -372.630712)
			(xy 426.684884 -372.632731) (xy 426.601558 -372.626679) (xy 426.519206 -372.612614) (xy 426.438596 -372.590666)
			(xy 426.36048 -372.56104) (xy 426.285588 -372.524014) (xy 426.21462 -372.479933) (xy 426.148237 -372.429207)
			(xy 426.08706 -372.372312) (xy 426.031659 -372.309778) (xy 425.982553 -372.242189) (xy 425.940199 -372.170176)
			(xy 425.904993 -372.094411) (xy 425.877264 -372.015602) (xy 425.857271 -371.934485) (xy 425.845199 -371.851817)
			(xy 425.841163 -371.76837) (xy 425.095162 -371.76837) (xy 425.094658 -371.810718) (xy 425.086607 -371.895032)
			(xy 425.070578 -371.978198) (xy 425.046717 -372.059465) (xy 425.015238 -372.138095) (xy 424.976427 -372.213376)
			(xy 424.930637 -372.284628) (xy 424.878281 -372.351204) (xy 424.819833 -372.412502) (xy 424.755823 -372.467967)
			(xy 424.686831 -372.517096) (xy 424.613481 -372.559445) (xy 424.536438 -372.594629) (xy 424.456399 -372.622331)
			(xy 424.37409 -372.642299) (xy 424.290255 -372.654352) (xy 424.205654 -372.658383) (xy 424.121053 -372.654352)
			(xy 424.037218 -372.642299) (xy 423.954909 -372.622331) (xy 423.87487 -372.594629) (xy 423.797827 -372.559445)
			(xy 423.724477 -372.517096) (xy 423.655485 -372.467967) (xy 423.591475 -372.412502) (xy 423.533027 -372.351204)
			(xy 423.480671 -372.284628) (xy 423.434881 -372.213376) (xy 423.39607 -372.138095) (xy 423.364591 -372.059465)
			(xy 423.34073 -371.978198) (xy 423.324701 -371.895032) (xy 423.31665 -371.810718) (xy 422.235289 -371.810718)
			(xy 422.239526 -371.84005) (xy 422.239523 -371.894795) (xy 422.231691 -371.948976) (xy 422.21619 -372.00148)
			(xy 422.19334 -372.051227) (xy 422.163611 -372.097195) (xy 422.145968 -372.118128) (xy 422.136705 -372.129435)
			(xy 422.124535 -372.156001) (xy 422.120369 -372.184923) (xy 422.124548 -372.213843) (xy 422.136729 -372.240403)
			(xy 422.145968 -372.251732) (xy 422.163584 -372.272683) (xy 422.1933 -372.31865) (xy 422.216141 -372.368393)
			(xy 422.231638 -372.420889) (xy 422.239471 -372.475062) (xy 422.239948 -372.50243) (xy 422.23945 -372.52968)
			(xy 422.231691 -372.583625) (xy 422.216334 -372.635917) (xy 422.193692 -372.685492) (xy 422.164226 -372.73134)
			(xy 422.128536 -372.772529) (xy 422.087348 -372.80822) (xy 422.041501 -372.837687) (xy 421.991927 -372.86033)
			(xy 421.939635 -372.875689) (xy 421.88569 -372.88345) (xy 421.85844 -372.883938) (xy 421.829523 -372.883415)
			(xy 421.772351 -372.87469) (xy 421.717151 -372.857435) (xy 421.665189 -372.832044) (xy 421.617655 -372.7991)
			(xy 421.575639 -372.759358) (xy 421.55745 -372.736872) (xy 421.547553 -372.725067) (xy 421.522229 -372.707548)
			(xy 421.492836 -372.698372) (xy 421.462044 -372.698372) (xy 421.432651 -372.707548) (xy 421.407327 -372.725067)
			(xy 421.39743 -372.736872) (xy 421.379215 -372.759335) (xy 421.337201 -372.799073) (xy 421.289671 -372.832015)
			(xy 421.237715 -372.857407) (xy 421.182521 -372.874668) (xy 421.125355 -372.883401) (xy 421.09644 -372.883938)
			(xy 421.069189 -372.883408) (xy 421.015243 -372.875657) (xy 420.962948 -372.860307) (xy 420.91337 -372.837672)
			(xy 420.867518 -372.808211) (xy 420.826326 -372.772524) (xy 420.790631 -372.731338) (xy 420.761162 -372.685492)
			(xy 420.738517 -372.635918) (xy 420.723158 -372.583626) (xy 420.715397 -372.52968) (xy 420.714932 -372.50243)
			(xy 420.715408 -372.47506) (xy 420.723222 -372.420881) (xy 420.738708 -372.368378) (xy 420.761548 -372.318631)
			(xy 420.791271 -372.272664) (xy 420.808912 -372.251732) (xy 420.818119 -372.240383) (xy 420.830298 -372.213833)
			(xy 420.834476 -372.184923) (xy 420.830311 -372.156011) (xy 420.818144 -372.129455) (xy 420.808912 -372.118128)
			(xy 420.791301 -372.097171) (xy 420.761576 -372.051207) (xy 420.73873 -372.001465) (xy 420.723232 -371.948967)
			(xy 420.715401 -371.894792) (xy 420.715398 -371.840054) (xy 420.723223 -371.785878) (xy 420.738714 -371.733378)
			(xy 420.761555 -371.683632) (xy 420.791274 -371.637665) (xy 420.808912 -371.616732) (xy 420.818119 -371.605383)
			(xy 420.830298 -371.578833) (xy 420.834476 -371.549923) (xy 420.830311 -371.521011) (xy 420.818144 -371.494455)
			(xy 420.808912 -371.483128) (xy 420.791301 -371.462171) (xy 420.761576 -371.416207) (xy 420.73873 -371.366465)
			(xy 420.723232 -371.313967) (xy 420.715401 -371.259792) (xy 420.715398 -371.205054) (xy 420.723223 -371.150878)
			(xy 420.738714 -371.098378) (xy 420.761555 -371.048632) (xy 420.791274 -371.002665) (xy 420.808912 -370.981732)
			(xy 420.818119 -370.970383) (xy 420.830298 -370.943833) (xy 420.834476 -370.914923) (xy 420.830311 -370.886011)
			(xy 420.818144 -370.859455) (xy 420.808912 -370.848128) (xy 420.791274 -370.827195) (xy 420.761562 -370.781222)
			(xy 420.738726 -370.731475) (xy 420.723234 -370.678975) (xy 420.715406 -370.624799) (xy 420.714932 -370.59743)
			(xy 420.71516 -370.578375) (xy 420.718982 -370.540457) (xy 420.722552 -370.521738) (xy 420.724834 -370.508255)
			(xy 420.723002 -370.480984) (xy 420.713998 -370.455177) (xy 420.698467 -370.432685) (xy 420.677525 -370.41512)
			(xy 420.652672 -370.403744) (xy 420.625691 -370.399371) (xy 420.598517 -370.402315) (xy 420.585646 -370.40693)
			(xy 420.563174 -370.415447) (xy 420.516636 -370.42744) (xy 420.468959 -370.433487) (xy 420.44493 -370.433854)
			(xy 420.416013 -370.433332) (xy 420.358841 -370.424606) (xy 420.303642 -370.40735) (xy 420.25168 -370.381959)
			(xy 420.204146 -370.349015) (xy 420.16213 -370.309274) (xy 420.14394 -370.286788) (xy 420.134043 -370.274983)
			(xy 420.108719 -370.257464) (xy 420.079326 -370.248288) (xy 420.048534 -370.248288) (xy 420.019141 -370.257464)
			(xy 419.993817 -370.274983) (xy 419.98392 -370.286788) (xy 419.965715 -370.309259) (xy 419.923698 -370.348996)
			(xy 419.876166 -370.381937) (xy 419.824208 -370.407327) (xy 419.769013 -370.424586) (xy 419.711845 -370.433318)
			(xy 419.68293 -370.433854) (xy 419.655682 -370.433294) (xy 419.601739 -370.425543) (xy 419.549448 -370.410194)
			(xy 419.499874 -370.387559) (xy 419.454026 -370.358101) (xy 419.412837 -370.322417) (xy 419.377145 -370.281235)
			(xy 419.347677 -370.235392) (xy 419.325033 -370.185823) (xy 419.309673 -370.133535) (xy 419.301911 -370.079594)
			(xy 419.301422 -370.052346) (xy 417.669658 -370.052346) (xy 417.673779 -370.058759) (xy 417.696421 -370.108336)
			(xy 417.711776 -370.160631) (xy 417.719532 -370.214579) (xy 417.720018 -370.24183) (xy 417.71959 -370.269202)
			(xy 417.711766 -370.323383) (xy 417.696269 -370.375888) (xy 417.673418 -370.425634) (xy 417.643684 -370.471598)
			(xy 417.626038 -370.492528) (xy 417.616769 -370.503832) (xy 417.604591 -370.530398) (xy 417.600422 -370.559323)
			(xy 417.604604 -370.588246) (xy 417.616794 -370.614806) (xy 417.626038 -370.626132) (xy 417.64371 -370.64704)
			(xy 417.673436 -370.693011) (xy 417.696282 -370.742762) (xy 417.711777 -370.795268) (xy 417.719604 -370.84945)
			(xy 417.7196 -370.904195) (xy 417.711767 -370.958377) (xy 417.696266 -371.010881) (xy 417.673414 -371.060628)
			(xy 417.643682 -371.106596) (xy 417.626038 -371.127528) (xy 417.616769 -371.138832) (xy 417.604591 -371.165398)
			(xy 417.600422 -371.194323) (xy 417.604604 -371.223246) (xy 417.616794 -371.249806) (xy 417.626038 -371.261132)
			(xy 417.643665 -371.282074) (xy 417.673377 -371.328044) (xy 417.696215 -371.37779) (xy 417.711709 -371.430288)
			(xy 417.719542 -371.484462) (xy 417.720018 -371.51183) (xy 417.71948 -371.540747) (xy 417.71076 -371.597918)
			(xy 417.693508 -371.653118) (xy 417.66812 -371.705081) (xy 417.635178 -371.752615) (xy 417.595437 -371.794631)
			(xy 417.572952 -371.81282) (xy 417.561113 -371.822683) (xy 417.543589 -371.848014) (xy 417.534413 -371.877417)
			(xy 417.534419 -371.908219) (xy 417.543606 -371.937619) (xy 417.561139 -371.962944) (xy 417.572952 -371.97284)
			(xy 417.593764 -371.989558) (xy 417.630894 -372.027916) (xy 417.662314 -372.071075) (xy 417.687412 -372.118193)
			(xy 417.705696 -372.168349) (xy 417.716811 -372.220564) (xy 417.720538 -372.273818) (xy 417.716805 -372.327073)
			(xy 417.705686 -372.379287) (xy 417.687397 -372.429441) (xy 417.662295 -372.476556) (xy 417.63087 -372.519712)
			(xy 417.593737 -372.558066) (xy 417.572952 -372.57482) (xy 417.561113 -372.584683) (xy 417.543589 -372.610014)
			(xy 417.534413 -372.639417) (xy 417.534419 -372.670219) (xy 417.543606 -372.699619) (xy 417.561139 -372.724944)
			(xy 417.572952 -372.73484) (xy 417.595465 -372.752995) (xy 417.635196 -372.795024) (xy 417.66813 -372.842567)
			(xy 417.693513 -372.894535) (xy 417.710763 -372.949738) (xy 417.719486 -373.006912) (xy 417.720018 -373.03583)
			(xy 417.719532 -373.063081) (xy 417.711776 -373.117029) (xy 417.696421 -373.169324) (xy 417.673779 -373.218901)
			(xy 417.644313 -373.264751) (xy 417.608622 -373.305942) (xy 417.567431 -373.341633) (xy 417.521581 -373.371099)
			(xy 417.472004 -373.393741) (xy 417.419709 -373.409096) (xy 417.365761 -373.416852) (xy 417.311259 -373.416852)
			(xy 417.257311 -373.409096) (xy 417.205016 -373.393741) (xy 417.155439 -373.371099) (xy 417.109589 -373.341633)
			(xy 417.068398 -373.305942) (xy 417.032707 -373.264751) (xy 417.003241 -373.218901) (xy 416.980599 -373.169324)
			(xy 416.965244 -373.117029) (xy 416.957488 -373.063081) (xy 416.957002 -373.03583) (xy 416.957541 -373.006914)
			(xy 416.966266 -372.949744) (xy 416.98352 -372.894545) (xy 417.008907 -372.842583) (xy 417.041847 -372.795049)
			(xy 417.081584 -372.753031) (xy 417.104068 -372.73484) (xy 417.115845 -372.724911) (xy 417.133366 -372.699597)
			(xy 417.142547 -372.670211) (xy 417.142553 -372.639425) (xy 417.133383 -372.610036) (xy 417.11587 -372.584716)
			(xy 417.104068 -372.57482) (xy 417.083314 -372.558031) (xy 417.046184 -372.519683) (xy 417.014761 -372.476532)
			(xy 416.989661 -372.429423) (xy 416.971373 -372.379275) (xy 416.960254 -372.327067) (xy 416.956522 -372.273818)
			(xy 415.75026 -372.273818) (xy 415.752038 -372.299218) (xy 415.748305 -372.352473) (xy 415.737186 -372.404687)
			(xy 415.718897 -372.454841) (xy 415.693795 -372.501956) (xy 415.66237 -372.545112) (xy 415.625237 -372.583466)
			(xy 415.604452 -372.60022) (xy 415.592613 -372.610083) (xy 415.575089 -372.635414) (xy 415.565913 -372.664817)
			(xy 415.565919 -372.695619) (xy 415.575106 -372.725019) (xy 415.592639 -372.750344) (xy 415.604452 -372.76024)
			(xy 415.626965 -372.778395) (xy 415.666696 -372.820424) (xy 415.69963 -372.867967) (xy 415.725013 -372.919935)
			(xy 415.742263 -372.975138) (xy 415.750986 -373.032312) (xy 415.751518 -373.06123) (xy 415.75105 -373.088482)
			(xy 415.74329 -373.142429) (xy 415.727931 -373.194724) (xy 415.705287 -373.244301) (xy 415.675819 -373.29015)
			(xy 415.640126 -373.33134) (xy 415.598934 -373.367031) (xy 415.553083 -373.396497) (xy 415.503505 -373.419138)
			(xy 415.45121 -373.434494) (xy 415.397262 -373.442252) (xy 415.37001 -373.442738) (xy 415.341092 -373.442236)
			(xy 415.283919 -373.433507) (xy 415.228719 -373.416247) (xy 415.176757 -373.390853) (xy 415.129224 -373.357905)
			(xy 415.087209 -373.31816) (xy 415.06902 -373.295672) (xy 415.059123 -373.283867) (xy 415.033799 -373.266348)
			(xy 415.004406 -373.257172) (xy 414.973614 -373.257172) (xy 414.944221 -373.266348) (xy 414.918897 -373.283867)
			(xy 414.909 -373.295672) (xy 414.890802 -373.31815) (xy 414.848784 -373.357886) (xy 414.801251 -373.390827)
			(xy 414.749291 -373.416217) (xy 414.694095 -373.433474) (xy 414.636926 -373.442203) (xy 414.60801 -373.442738)
			(xy 414.580639 -373.442281) (xy 414.526459 -373.434463) (xy 414.473955 -373.418973) (xy 414.424209 -373.396129)
			(xy 414.378243 -373.366401) (xy 414.357312 -373.348758) (xy 414.345984 -373.339522) (xy 414.319427 -373.327346)
			(xy 414.29051 -373.323173) (xy 414.261593 -373.327346) (xy 414.235036 -373.339522) (xy 414.223708 -373.348758)
			(xy 414.202778 -373.3664) (xy 414.156806 -373.396113) (xy 414.107058 -373.418949) (xy 414.054556 -373.434439)
			(xy 414.000379 -373.442265) (xy 413.97301 -373.442738) (xy 413.94576 -373.442213) (xy 413.891816 -373.434458)
			(xy 413.839524 -373.419106) (xy 413.789948 -373.396468) (xy 413.744099 -373.367006) (xy 413.70291 -373.331318)
			(xy 413.667218 -373.290133) (xy 413.637751 -373.244287) (xy 413.615108 -373.194714) (xy 413.59975 -373.142423)
			(xy 413.59199 -373.08848) (xy 413.591502 -373.06123) (xy 413.592041 -373.032314) (xy 413.600766 -372.975144)
			(xy 413.61802 -372.919945) (xy 413.643407 -372.867983) (xy 413.676347 -372.820449) (xy 413.716084 -372.778431)
			(xy 413.738568 -372.76024) (xy 413.750345 -372.750311) (xy 413.767866 -372.724997) (xy 413.777047 -372.695611)
			(xy 413.777053 -372.664825) (xy 413.767883 -372.635436) (xy 413.75037 -372.610116) (xy 413.738568 -372.60022)
			(xy 413.717814 -372.583431) (xy 413.680684 -372.545083) (xy 413.649261 -372.501932) (xy 413.624161 -372.454823)
			(xy 413.605873 -372.404675) (xy 413.594754 -372.352467) (xy 413.591022 -372.299218) (xy 371.071752 -372.299218)
			(xy 373.105532 -374.333052) (xy 416.088785 -374.333052) (xy 416.088785 -374.278548) (xy 416.096542 -374.224599)
			(xy 416.111899 -374.172302) (xy 416.134542 -374.122724) (xy 416.16401 -374.076873) (xy 416.199704 -374.035683)
			(xy 416.240897 -373.999992) (xy 416.286751 -373.970527) (xy 416.336331 -373.947888) (xy 416.388628 -373.932536)
			(xy 416.442578 -373.924783) (xy 416.46983 -373.924322) (xy 416.498745 -373.924882) (xy 416.555915 -373.933601)
			(xy 416.611113 -373.95085) (xy 416.663076 -373.976234) (xy 416.710611 -374.009171) (xy 416.752629 -374.048905)
			(xy 416.77082 -374.071388) (xy 416.780717 -374.083193) (xy 416.806041 -374.100712) (xy 416.835434 -374.109888)
			(xy 416.866226 -374.109888) (xy 416.895619 -374.100712) (xy 416.920943 -374.083193) (xy 416.93084 -374.071388)
			(xy 416.949005 -374.048883) (xy 416.991031 -374.00915) (xy 417.038571 -373.976213) (xy 417.090537 -373.950829)
			(xy 417.145739 -373.933577) (xy 417.202913 -373.924854) (xy 417.23183 -373.924322) (xy 417.259082 -373.92475)
			(xy 417.313031 -373.93251) (xy 417.365326 -373.947869) (xy 417.414903 -373.970514) (xy 417.460754 -373.999983)
			(xy 417.501943 -374.035678) (xy 417.537635 -374.07687) (xy 417.5671 -374.122723) (xy 417.589741 -374.172302)
			(xy 417.605096 -374.224599) (xy 417.612852 -374.278548) (xy 417.612852 -374.333052) (xy 417.605096 -374.387001)
			(xy 417.589741 -374.439298) (xy 417.5671 -374.488877) (xy 417.537635 -374.53473) (xy 417.501943 -374.575922)
			(xy 417.460754 -374.611617) (xy 417.414903 -374.641086) (xy 417.365326 -374.663731) (xy 417.313031 -374.67909)
			(xy 417.259082 -374.68685) (xy 417.23183 -374.687338) (xy 417.202913 -374.686822) (xy 417.14574 -374.678096)
			(xy 417.09054 -374.660839) (xy 417.038578 -374.635447) (xy 416.991045 -374.602502) (xy 416.949029 -374.562759)
			(xy 416.93084 -374.540272) (xy 416.920943 -374.528467) (xy 416.895619 -374.510948) (xy 416.866226 -374.501772)
			(xy 416.835434 -374.501772) (xy 416.806041 -374.510948) (xy 416.780717 -374.528467) (xy 416.77082 -374.540272)
			(xy 416.752611 -374.56274) (xy 416.710596 -374.602478) (xy 416.663065 -374.635419) (xy 416.611107 -374.66081)
			(xy 416.555912 -374.67807) (xy 416.498745 -374.686802) (xy 416.46983 -374.687338) (xy 416.442578 -374.686817)
			(xy 416.388628 -374.679064) (xy 416.336331 -374.663712) (xy 416.286751 -374.641073) (xy 416.240897 -374.611608)
			(xy 416.199704 -374.575917) (xy 416.16401 -374.534727) (xy 416.134542 -374.488876) (xy 416.111899 -374.439298)
			(xy 416.096542 -374.387001) (xy 416.088785 -374.333052) (xy 373.105532 -374.333052) (xy 375.455434 -376.683016)
			(xy 411.80004 -376.683016) (xy 412.126684 -376.356372) (xy 425.684696 -376.356372) (xy 426.467016 -375.574052)
			(xy 428.02048 -374.020334) (xy 428.02048 -370.18595) (xy 427.55439 -369.71986) (xy 423.816526 -369.71986)
			(xy 423.791531 -369.719221) (xy 423.742509 -369.709417) (xy 423.696342 -369.690241) (xy 423.654801 -369.662428)
			(xy 423.636694 -369.645184) (xy 422.431972 -368.440462) (xy 422.414751 -368.422352) (xy 422.387012 -368.380791)
			(xy 422.367905 -368.334622) (xy 422.358162 -368.285614) (xy 422.35755 -368.26063) (xy 422.35755 -366.87125)
			(xy 422.358156 -366.846265) (xy 422.367889 -366.797251) (xy 422.386992 -366.751076) (xy 422.414731 -366.709511)
			(xy 422.431972 -366.691418) (xy 423.234866 -365.888524) (xy 423.252978 -365.871308) (xy 423.294541 -365.843579)
			(xy 423.34071 -365.82448) (xy 423.389716 -365.814744) (xy 423.414698 -365.814102) (xy 423.488104 -365.814356)
			(xy 423.495216 -365.771684) (xy 423.500034 -365.745253) (xy 423.516116 -365.693993) (xy 423.539229 -365.645494)
			(xy 423.568917 -365.600718) (xy 423.604592 -365.560548) (xy 423.645549 -365.525781) (xy 423.690979 -365.497102)
			(xy 423.739982 -365.475079) (xy 423.79159 -365.460148) (xy 423.844782 -365.452604) (xy 423.871644 -365.452152)
			(xy 423.898894 -365.452641) (xy 423.952839 -365.460402) (xy 424.005131 -365.475761) (xy 424.054705 -365.498404)
			(xy 424.100553 -365.527871) (xy 424.141741 -365.563562) (xy 424.177432 -365.60475) (xy 424.206898 -365.650598)
			(xy 424.229541 -365.700173) (xy 424.244899 -365.752465) (xy 424.25266 -365.80641) (xy 424.252808 -365.81461)
			(xy 425.115482 -365.81461) (xy 425.115968 -365.787359) (xy 425.123724 -365.733411) (xy 425.139079 -365.681116)
			(xy 425.161721 -365.631539) (xy 425.191187 -365.585689) (xy 425.226878 -365.544498) (xy 425.268069 -365.508807)
			(xy 425.313919 -365.479341) (xy 425.363496 -365.456699) (xy 425.415791 -365.441344) (xy 425.469739 -365.433588)
			(xy 425.524241 -365.433588) (xy 425.578189 -365.441344) (xy 425.630484 -365.456699) (xy 425.680061 -365.479341)
			(xy 425.725911 -365.508807) (xy 425.767102 -365.544498) (xy 425.802793 -365.585689) (xy 425.832259 -365.631539)
			(xy 425.854901 -365.681116) (xy 425.870256 -365.733411) (xy 425.878012 -365.787359) (xy 425.878498 -365.81461)
			(xy 425.878261 -365.833277) (xy 425.874571 -365.870429) (xy 425.871132 -365.888778) (xy 425.868794 -365.903046)
			(xy 425.871323 -365.931834) (xy 425.88182 -365.958759) (xy 425.899444 -365.981662) (xy 425.922781 -365.998707)
			(xy 425.94996 -366.008527) (xy 425.96435 -366.009936) (xy 425.993007 -366.012269) (xy 426.049173 -366.024563)
			(xy 426.10286 -366.045144) (xy 426.152851 -366.073546) (xy 426.198016 -366.109126) (xy 426.237332 -366.151079)
			(xy 426.26991 -366.198455) (xy 426.295011 -366.250182) (xy 426.312069 -366.305089) (xy 426.320697 -366.361934)
			(xy 426.32122 -366.390682) (xy 426.320734 -366.417933) (xy 426.312978 -366.471881) (xy 426.297623 -366.524176)
			(xy 426.274981 -366.573753) (xy 426.245515 -366.619603) (xy 426.209824 -366.660794) (xy 426.168633 -366.696485)
			(xy 426.122783 -366.725951) (xy 426.073206 -366.748593) (xy 426.020911 -366.763948) (xy 425.966963 -366.771704)
			(xy 425.912461 -366.771704) (xy 425.858513 -366.763948) (xy 425.806218 -366.748593) (xy 425.756641 -366.725951)
			(xy 425.710791 -366.696485) (xy 425.6696 -366.660794) (xy 425.633909 -366.619603) (xy 425.604443 -366.573753)
			(xy 425.581801 -366.524176) (xy 425.566446 -366.471881) (xy 425.55869 -366.417933) (xy 425.558204 -366.390682)
			(xy 425.55844 -366.372015) (xy 425.56213 -366.334863) (xy 425.56557 -366.316514) (xy 425.567914 -366.302247)
			(xy 425.565383 -366.273459) (xy 425.554885 -366.246533) (xy 425.53726 -366.22363) (xy 425.513922 -366.206585)
			(xy 425.486742 -366.196765) (xy 425.472352 -366.195356) (xy 425.443694 -366.19303) (xy 425.387527 -366.180735)
			(xy 425.33384 -366.160154) (xy 425.283849 -366.131752) (xy 425.238684 -366.096171) (xy 425.199367 -366.054217)
			(xy 425.16679 -366.00684) (xy 425.141688 -365.955112) (xy 425.124631 -365.900204) (xy 425.116004 -365.843358)
			(xy 425.115482 -365.81461) (xy 424.252808 -365.81461) (xy 424.253152 -365.83366) (xy 424.252631 -365.862441)
			(xy 424.243988 -365.919351) (xy 424.226892 -365.974316) (xy 424.201732 -366.026088) (xy 424.169078 -366.073493)
			(xy 424.129673 -366.115452) (xy 424.107356 -366.133634) (xy 424.09676 -366.14355) (xy 424.081131 -366.167984)
			(xy 424.072993 -366.195825) (xy 424.073001 -366.22483) (xy 424.081154 -366.252666) (xy 424.096797 -366.277092)
			(xy 424.107356 -366.28705) (xy 424.129658 -366.305246) (xy 424.169054 -366.347207) (xy 424.2017 -366.394611)
			(xy 424.226854 -366.44638) (xy 424.243947 -366.501341) (xy 424.24639 -366.517428) (xy 424.505626 -366.517428)
			(xy 424.509697 -366.461806) (xy 424.521823 -366.407369) (xy 424.541746 -366.355278) (xy 424.569042 -366.306643)
			(xy 424.603128 -366.2625) (xy 424.643277 -366.223791) (xy 424.688635 -366.19134) (xy 424.738235 -366.165839)
			(xy 424.791019 -366.147832) (xy 424.845862 -366.137702) (xy 424.901596 -366.135665) (xy 424.957033 -366.141765)
			(xy 425.01099 -366.155871) (xy 425.062319 -366.177683) (xy 425.109925 -366.206737) (xy 425.152793 -366.242412)
			(xy 425.19001 -366.283949) (xy 425.220783 -366.330462) (xy 425.244455 -366.380959) (xy 425.260523 -366.434366)
			(xy 425.268643 -366.489542) (xy 425.269152 -366.517428) (xy 425.268643 -366.545314) (xy 425.260523 -366.60049)
			(xy 425.244455 -366.653897) (xy 425.220783 -366.704394) (xy 425.19001 -366.750907) (xy 425.152793 -366.792444)
			(xy 425.109925 -366.828119) (xy 425.062319 -366.857173) (xy 425.01099 -366.878985) (xy 424.957033 -366.893091)
			(xy 424.901596 -366.899191) (xy 424.845862 -366.897154) (xy 424.791019 -366.887024) (xy 424.738235 -366.869017)
			(xy 424.688635 -366.843516) (xy 424.643277 -366.811065) (xy 424.603128 -366.772356) (xy 424.569042 -366.728213)
			(xy 424.541746 -366.679578) (xy 424.521823 -366.627487) (xy 424.509697 -366.57305) (xy 424.505626 -366.517428)
			(xy 424.24639 -366.517428) (xy 424.252589 -366.558245) (xy 424.253152 -366.587024) (xy 424.252665 -366.614275)
			(xy 424.244906 -366.668223) (xy 424.229549 -366.720517) (xy 424.206907 -366.770094) (xy 424.177441 -366.815945)
			(xy 424.14175 -366.857136) (xy 424.100561 -366.892829) (xy 424.054712 -366.922297) (xy 424.005136 -366.944942)
			(xy 423.952842 -366.960301) (xy 423.898895 -366.968063) (xy 423.871644 -366.968532) (xy 423.846274 -366.968118)
			(xy 423.795982 -366.961399) (xy 423.747023 -366.948073) (xy 423.700264 -366.928374) (xy 423.656527 -366.902652)
			(xy 423.616586 -366.87136) (xy 423.598594 -366.85347) (xy 423.586656 -366.841532) (xy 423.540682 -366.841532)
			(xy 423.34561 -367.036604) (xy 423.247312 -367.134648) (xy 423.247312 -367.997232) (xy 423.526204 -368.276124)
			(xy 424.080178 -368.829844) (xy 427.818042 -368.829844) (xy 427.843039 -368.83048) (xy 427.892063 -368.840278)
			(xy 427.938235 -368.859451) (xy 427.97978 -368.887262) (xy 427.997874 -368.90452) (xy 428.83582 -369.742466)
			(xy 428.853074 -369.760563) (xy 428.880879 -369.80211) (xy 428.900052 -369.84828) (xy 428.909856 -369.897302)
			(xy 428.910496 -369.922298) (xy 428.910496 -374.283986) (xy 428.909856 -374.308981) (xy 428.900052 -374.358002)
			(xy 428.880875 -374.40417) (xy 428.853064 -374.445712) (xy 428.83582 -374.463818) (xy 427.113954 -376.18543)
			(xy 427.10423 -376.196586) (xy 427.091085 -376.223085) (xy 427.086074 -376.252238) (xy 427.089618 -376.281605)
			(xy 427.101419 -376.30873) (xy 427.120491 -376.331341) (xy 427.145236 -376.347548) (xy 427.173585 -376.355994)
			(xy 427.188376 -376.356372) (xy 428.269908 -376.356372) (xy 434.643784 -369.982496) (xy 434.643784 -361.863386)
			(xy 436.4482 -360.05897) (xy 436.4482 -333.517748) (xy 435.672738 -332.742286) (xy 382.546098 -332.742286)
			(xy 379.665484 -329.861672) (xy 374.709944 -329.861672) (xy 371.435884 -326.587612) (xy 343.084404 -326.587612)
			(xy 336.595212 -333.076804) (xy 322.766944 -333.076804) (xy 320.66738 -335.176368) (xy 340.981284 -335.176368)
			(xy 340.981711 -335.148996) (xy 340.989535 -335.094815) (xy 341.005032 -335.04231) (xy 341.027883 -334.992564)
			(xy 341.057618 -334.9466) (xy 341.075264 -334.92567) (xy 341.084535 -334.914367) (xy 341.096713 -334.887801)
			(xy 341.100881 -334.858876) (xy 341.096699 -334.829952) (xy 341.084508 -334.803392) (xy 341.075264 -334.792066)
			(xy 341.057637 -334.771124) (xy 341.027924 -334.725154) (xy 341.005087 -334.675409) (xy 340.989593 -334.62291)
			(xy 340.98176 -334.568736) (xy 340.981284 -334.541368) (xy 340.98177 -334.514117) (xy 340.989526 -334.460169)
			(xy 341.004881 -334.407874) (xy 341.027523 -334.358297) (xy 341.056989 -334.312447) (xy 341.09268 -334.271256)
			(xy 341.133871 -334.235565) (xy 341.179721 -334.206099) (xy 341.229298 -334.183457) (xy 341.281593 -334.168102)
			(xy 341.335541 -334.160346) (xy 341.390043 -334.160346) (xy 341.443991 -334.168102) (xy 341.496286 -334.183457)
			(xy 341.545863 -334.206099) (xy 341.591713 -334.235565) (xy 341.632904 -334.271256) (xy 341.668595 -334.312447)
			(xy 341.698061 -334.358297) (xy 341.720703 -334.407874) (xy 341.736058 -334.460169) (xy 341.743814 -334.514117)
			(xy 341.7443 -334.541368) (xy 341.743815 -334.568738) (xy 341.736002 -334.622916) (xy 341.720517 -334.675419)
			(xy 341.69768 -334.725166) (xy 341.667959 -334.771134) (xy 341.65032 -334.792066) (xy 341.641113 -334.803416)
			(xy 341.628929 -334.829965) (xy 341.62475 -334.858876) (xy 341.628916 -334.887788) (xy 341.641086 -334.914343)
			(xy 341.65032 -334.92567) (xy 341.667962 -334.9466) (xy 341.697672 -334.992574) (xy 341.720508 -335.042322)
			(xy 341.735998 -335.094823) (xy 341.743826 -335.148999) (xy 341.7443 -335.176368) (xy 341.743814 -335.203619)
			(xy 341.736058 -335.257567) (xy 341.720703 -335.309862) (xy 341.698061 -335.359439) (xy 341.668595 -335.405289)
			(xy 341.632904 -335.44648) (xy 341.591713 -335.482171) (xy 341.545863 -335.511637) (xy 341.496286 -335.534279)
			(xy 341.443991 -335.549634) (xy 341.390043 -335.55739) (xy 341.335541 -335.55739) (xy 341.281593 -335.549634)
			(xy 341.229298 -335.534279) (xy 341.179721 -335.511637) (xy 341.133871 -335.482171) (xy 341.09268 -335.44648)
			(xy 341.056989 -335.405289) (xy 341.027523 -335.359439) (xy 341.004881 -335.309862) (xy 340.989526 -335.257567)
			(xy 340.98177 -335.203619) (xy 340.981284 -335.176368) (xy 320.66738 -335.176368) (xy 320.088248 -335.7555)
			(xy 345.217421 -335.7555) (xy 345.22159 -335.699879) (xy 345.234002 -335.6455) (xy 345.254381 -335.593578)
			(xy 345.28227 -335.545274) (xy 345.317048 -335.501666) (xy 345.357937 -335.463729) (xy 345.404023 -335.432311)
			(xy 345.454278 -335.408112) (xy 345.507578 -335.391674) (xy 345.562733 -335.383363) (xy 345.590622 -335.38287)
			(xy 345.618201 -335.383365) (xy 345.672759 -335.391471) (xy 345.725522 -335.407545) (xy 345.750642 -335.418938)
			(xy 345.763019 -335.424383) (xy 345.789613 -335.429217) (xy 345.816543 -335.426897) (xy 345.841919 -335.417588)
			(xy 345.86396 -335.401941) (xy 345.881119 -335.381056) (xy 345.88704 -335.3689) (xy 345.898378 -335.344653)
			(xy 345.927062 -335.299459) (xy 345.96192 -335.258838) (xy 346.002233 -335.223624) (xy 346.047173 -335.194544)
			(xy 346.095812 -335.172197) (xy 346.14715 -335.157042) (xy 346.200128 -335.149393) (xy 346.226892 -335.148936)
			(xy 346.253364 -335.149401) (xy 346.305773 -335.156901) (xy 346.356596 -335.171737) (xy 346.404809 -335.193611)
			(xy 346.449445 -335.222083) (xy 346.489606 -335.256582) (xy 346.524485 -335.296413) (xy 346.55338 -335.340776)
			(xy 346.564966 -335.364582) (xy 346.571667 -335.377804) (xy 346.5913 -335.399992) (xy 346.616473 -335.415614)
			(xy 346.64507 -335.423359) (xy 346.674687 -335.422574) (xy 346.688918 -335.41843) (xy 346.717263 -335.409661)
			(xy 346.775839 -335.400225) (xy 346.805504 -335.399634) (xy 346.833361 -335.40015) (xy 346.888456 -335.40844)
			(xy 346.915232 -335.416144) (xy 346.929563 -335.419986) (xy 346.959217 -335.420195) (xy 346.987682 -335.411879)
			(xy 347.01256 -335.395739) (xy 347.031755 -335.373135) (xy 347.038168 -335.359756) (xy 347.049483 -335.335288)
			(xy 347.078037 -335.289568) (xy 347.112884 -335.248442) (xy 347.153294 -335.212767) (xy 347.198425 -335.18329)
			(xy 347.247333 -335.160625) (xy 347.298997 -335.145247) (xy 347.352338 -335.137476) (xy 347.37929 -335.136998)
			(xy 347.407178 -335.13746) (xy 347.462333 -335.145772) (xy 347.515632 -335.162211) (xy 347.54503 -335.176368)
			(xy 349.141796 -335.176368) (xy 349.142244 -335.148997) (xy 349.150067 -335.094817) (xy 349.16556 -335.042314)
			(xy 349.188405 -334.992568) (xy 349.218133 -334.946601) (xy 349.235776 -334.92567) (xy 349.245046 -334.914367)
			(xy 349.257222 -334.887801) (xy 349.26139 -334.858876) (xy 349.257208 -334.829953) (xy 349.245019 -334.803393)
			(xy 349.235776 -334.792066) (xy 349.218151 -334.771123) (xy 349.188438 -334.725153) (xy 349.165599 -334.675408)
			(xy 349.150105 -334.62291) (xy 349.142273 -334.568736) (xy 349.141796 -334.541368) (xy 349.142282 -334.514117)
			(xy 349.150038 -334.460169) (xy 349.165393 -334.407874) (xy 349.188035 -334.358297) (xy 349.217501 -334.312447)
			(xy 349.253192 -334.271256) (xy 349.294383 -334.235565) (xy 349.340233 -334.206099) (xy 349.38981 -334.183457)
			(xy 349.442105 -334.168102) (xy 349.496053 -334.160346) (xy 349.550555 -334.160346) (xy 349.604503 -334.168102)
			(xy 349.656798 -334.183457) (xy 349.706375 -334.206099) (xy 349.752225 -334.235565) (xy 349.793416 -334.271256)
			(xy 349.829107 -334.312447) (xy 349.858573 -334.358297) (xy 349.881215 -334.407874) (xy 349.89657 -334.460169)
			(xy 349.904326 -334.514117) (xy 349.904812 -334.541368) (xy 349.904324 -334.568737) (xy 349.896511 -334.622915)
			(xy 349.881027 -334.675418) (xy 349.85819 -334.725165) (xy 349.828471 -334.771133) (xy 349.810832 -334.792066)
			(xy 349.801624 -334.803415) (xy 349.789439 -334.829965) (xy 349.785259 -334.858876) (xy 349.789425 -334.887789)
			(xy 349.801598 -334.914344) (xy 349.810832 -334.92567) (xy 349.828475 -334.946598) (xy 349.858186 -334.992573)
			(xy 349.88102 -335.042321) (xy 349.89651 -335.094823) (xy 349.904338 -335.148999) (xy 349.904812 -335.176368)
			(xy 357.302308 -335.176368) (xy 357.302753 -335.148997) (xy 357.310576 -335.094817) (xy 357.32607 -335.042314)
			(xy 357.348916 -334.992567) (xy 357.378645 -334.946601) (xy 357.396288 -334.92567) (xy 357.405557 -334.914366)
			(xy 357.417732 -334.8878) (xy 357.421899 -334.858876) (xy 357.417718 -334.829953) (xy 357.40553 -334.803393)
			(xy 357.396288 -334.792066) (xy 357.378665 -334.771121) (xy 357.348951 -334.725152) (xy 357.326112 -334.675408)
			(xy 357.310617 -334.62291) (xy 357.302785 -334.568736) (xy 357.302308 -334.541368) (xy 357.302794 -334.514117)
			(xy 357.31055 -334.460169) (xy 357.325905 -334.407874) (xy 357.348547 -334.358297) (xy 357.378013 -334.312447)
			(xy 357.413704 -334.271256) (xy 357.454895 -334.235565) (xy 357.500745 -334.206099) (xy 357.550322 -334.183457)
			(xy 357.602617 -334.168102) (xy 357.656565 -334.160346) (xy 357.711067 -334.160346) (xy 357.765015 -334.168102)
			(xy 357.81731 -334.183457) (xy 357.866887 -334.206099) (xy 357.912737 -334.235565) (xy 357.953928 -334.271256)
			(xy 357.989619 -334.312447) (xy 358.019085 -334.358297) (xy 358.041727 -334.407874) (xy 358.057082 -334.460169)
			(xy 358.064838 -334.514117) (xy 358.065324 -334.541368) (xy 358.064858 -334.568738) (xy 358.057043 -334.622918)
			(xy 358.041555 -334.675422) (xy 358.018713 -334.725169) (xy 357.988986 -334.771135) (xy 357.971344 -334.792066)
			(xy 357.962142 -334.803418) (xy 357.949968 -334.829968) (xy 357.945792 -334.858876) (xy 357.949954 -334.887786)
			(xy 357.962116 -334.914341) (xy 357.971344 -334.92567) (xy 357.98899 -334.946597) (xy 358.018699 -334.992572)
			(xy 358.041533 -335.042321) (xy 358.057023 -335.094822) (xy 358.064851 -335.148999) (xy 358.065324 -335.176368)
			(xy 365.46282 -335.176368) (xy 365.463262 -335.148997) (xy 365.471085 -335.094817) (xy 365.48658 -335.042313)
			(xy 365.509427 -334.992567) (xy 365.539156 -334.946601) (xy 365.5568 -334.92567) (xy 365.566068 -334.914366)
			(xy 365.578241 -334.8878) (xy 365.582408 -334.858876) (xy 365.578228 -334.829954) (xy 365.566041 -334.803393)
			(xy 365.5568 -334.792066) (xy 365.539178 -334.77112) (xy 365.509464 -334.725151) (xy 365.486625 -334.675407)
			(xy 365.471129 -334.622909) (xy 365.463297 -334.568736) (xy 365.46282 -334.541368) (xy 365.463306 -334.514117)
			(xy 365.471062 -334.460169) (xy 365.486417 -334.407874) (xy 365.509059 -334.358297) (xy 365.538525 -334.312447)
			(xy 365.574216 -334.271256) (xy 365.615407 -334.235565) (xy 365.661257 -334.206099) (xy 365.710834 -334.183457)
			(xy 365.763129 -334.168102) (xy 365.817077 -334.160346) (xy 365.871579 -334.160346) (xy 365.925527 -334.168102)
			(xy 365.977822 -334.183457) (xy 366.027399 -334.206099) (xy 366.073249 -334.235565) (xy 366.11444 -334.271256)
			(xy 366.150131 -334.312447) (xy 366.179597 -334.358297) (xy 366.202239 -334.407874) (xy 366.217594 -334.460169)
			(xy 366.22535 -334.514117) (xy 366.225836 -334.541368) (xy 366.225367 -334.568738) (xy 366.217552 -334.622918)
			(xy 366.202065 -334.675422) (xy 366.179223 -334.725169) (xy 366.149498 -334.771135) (xy 366.131856 -334.792066)
			(xy 366.122653 -334.803418) (xy 366.110478 -334.829967) (xy 366.106301 -334.858876) (xy 366.110464 -334.887786)
			(xy 366.122627 -334.914341) (xy 366.131856 -334.92567) (xy 366.149488 -334.946608) (xy 366.179202 -334.992579)
			(xy 366.20204 -335.042324) (xy 366.217533 -335.094824) (xy 366.225362 -335.148999) (xy 366.225836 -335.176368)
			(xy 366.22535 -335.203619) (xy 366.217594 -335.257567) (xy 366.202239 -335.309862) (xy 366.179597 -335.359439)
			(xy 366.150131 -335.405289) (xy 366.11444 -335.44648) (xy 366.073249 -335.482171) (xy 366.027399 -335.511637)
			(xy 365.977822 -335.534279) (xy 365.925527 -335.549634) (xy 365.871579 -335.55739) (xy 365.817077 -335.55739)
			(xy 365.763129 -335.549634) (xy 365.710834 -335.534279) (xy 365.661257 -335.511637) (xy 365.615407 -335.482171)
			(xy 365.574216 -335.44648) (xy 365.538525 -335.405289) (xy 365.509059 -335.359439) (xy 365.486417 -335.309862)
			(xy 365.471062 -335.257567) (xy 365.463306 -335.203619) (xy 365.46282 -335.176368) (xy 358.065324 -335.176368)
			(xy 358.064838 -335.203619) (xy 358.057082 -335.257567) (xy 358.041727 -335.309862) (xy 358.019085 -335.359439)
			(xy 357.989619 -335.405289) (xy 357.953928 -335.44648) (xy 357.912737 -335.482171) (xy 357.866887 -335.511637)
			(xy 357.81731 -335.534279) (xy 357.765015 -335.549634) (xy 357.711067 -335.55739) (xy 357.656565 -335.55739)
			(xy 357.602617 -335.549634) (xy 357.550322 -335.534279) (xy 357.500745 -335.511637) (xy 357.454895 -335.482171)
			(xy 357.413704 -335.44648) (xy 357.378013 -335.405289) (xy 357.348547 -335.359439) (xy 357.325905 -335.309862)
			(xy 357.31055 -335.257567) (xy 357.302794 -335.203619) (xy 357.302308 -335.176368) (xy 349.904812 -335.176368)
			(xy 349.904326 -335.203619) (xy 349.89657 -335.257567) (xy 349.881215 -335.309862) (xy 349.858573 -335.359439)
			(xy 349.829107 -335.405289) (xy 349.793416 -335.44648) (xy 349.752225 -335.482171) (xy 349.706375 -335.511637)
			(xy 349.656798 -335.534279) (xy 349.604503 -335.549634) (xy 349.550555 -335.55739) (xy 349.496053 -335.55739)
			(xy 349.442105 -335.549634) (xy 349.38981 -335.534279) (xy 349.340233 -335.511637) (xy 349.294383 -335.482171)
			(xy 349.253192 -335.44648) (xy 349.217501 -335.405289) (xy 349.188035 -335.359439) (xy 349.165393 -335.309862)
			(xy 349.150038 -335.257567) (xy 349.142282 -335.203619) (xy 349.141796 -335.176368) (xy 347.54503 -335.176368)
			(xy 347.565885 -335.186411) (xy 347.611971 -335.217831) (xy 347.652859 -335.255768) (xy 347.687636 -335.299376)
			(xy 347.715525 -335.34768) (xy 347.735902 -335.399601) (xy 347.748314 -335.453979) (xy 347.752483 -335.5096)
			(xy 347.748314 -335.565221) (xy 347.735902 -335.619599) (xy 347.715525 -335.67152) (xy 347.687636 -335.719824)
			(xy 347.652859 -335.763432) (xy 347.611971 -335.801369) (xy 347.565885 -335.832789) (xy 347.515632 -335.856989)
			(xy 347.462333 -335.873428) (xy 347.407178 -335.88174) (xy 347.37929 -335.882234) (xy 347.351433 -335.88172)
			(xy 347.296338 -335.873428) (xy 347.269562 -335.865724) (xy 347.255229 -335.861894) (xy 347.225578 -335.861687)
			(xy 347.197116 -335.870002) (xy 347.172239 -335.886138) (xy 347.153041 -335.908736) (xy 347.146626 -335.922112)
			(xy 347.135349 -335.946598) (xy 347.106786 -335.992315) (xy 347.071933 -336.033439) (xy 347.031516 -336.069111)
			(xy 346.986381 -336.098585) (xy 346.937469 -336.121247) (xy 346.885801 -336.136624) (xy 346.832457 -336.144393)
			(xy 346.805504 -336.14487) (xy 346.779032 -336.144405) (xy 346.726623 -336.136904) (xy 346.675801 -336.122068)
			(xy 346.627587 -336.100194) (xy 346.582951 -336.071722) (xy 346.54279 -336.037224) (xy 346.507912 -335.997393)
			(xy 346.479016 -335.95303) (xy 346.46743 -335.929224) (xy 346.46073 -335.916001) (xy 346.441097 -335.893812)
			(xy 346.415924 -335.878189) (xy 346.387326 -335.870445) (xy 346.357709 -335.871231) (xy 346.343478 -335.875376)
			(xy 346.315133 -335.884146) (xy 346.256557 -335.893581) (xy 346.226892 -335.894172) (xy 346.199313 -335.893677)
			(xy 346.144755 -335.885572) (xy 346.091992 -335.869498) (xy 346.066872 -335.858104) (xy 346.054496 -335.852654)
			(xy 346.027901 -335.847814) (xy 346.000968 -335.850131) (xy 345.97559 -335.859442) (xy 345.953548 -335.875092)
			(xy 345.936392 -335.895983) (xy 345.930474 -335.908142) (xy 345.919098 -335.93237) (xy 345.890422 -335.977566)
			(xy 345.855571 -336.01819) (xy 345.815263 -336.053406) (xy 345.770329 -336.082489) (xy 345.721693 -336.104839)
			(xy 345.67036 -336.119996) (xy 345.617385 -336.127648) (xy 345.590622 -336.128106) (xy 345.562733 -336.127637)
			(xy 345.507578 -336.119326) (xy 345.454278 -336.102888) (xy 345.404023 -336.078689) (xy 345.357937 -336.047271)
			(xy 345.317048 -336.009334) (xy 345.28227 -335.965726) (xy 345.254381 -335.917422) (xy 345.234002 -335.8655)
			(xy 345.22159 -335.811121) (xy 345.217421 -335.7555) (xy 320.088248 -335.7555) (xy 319.212468 -336.63128)
			(xy 341.85682 -336.63128) (xy 341.860891 -336.575658) (xy 341.873017 -336.521221) (xy 341.89294 -336.46913)
			(xy 341.920236 -336.420495) (xy 341.954322 -336.376352) (xy 341.994471 -336.337643) (xy 342.039829 -336.305192)
			(xy 342.089429 -336.279691) (xy 342.142213 -336.261684) (xy 342.197056 -336.251554) (xy 342.25279 -336.249517)
			(xy 342.308227 -336.255617) (xy 342.362184 -336.269723) (xy 342.413513 -336.291535) (xy 342.461119 -336.320589)
			(xy 342.503987 -336.356264) (xy 342.541204 -336.397801) (xy 342.571977 -336.444314) (xy 342.595649 -336.494811)
			(xy 342.611717 -336.548218) (xy 342.619837 -336.603394) (xy 342.620346 -336.63128) (xy 342.619837 -336.659166)
			(xy 342.611717 -336.714342) (xy 342.595649 -336.767749) (xy 342.571977 -336.818246) (xy 342.541204 -336.864759)
			(xy 342.503987 -336.906296) (xy 342.461119 -336.941971) (xy 342.413513 -336.971025) (xy 342.362184 -336.992837)
			(xy 342.308227 -337.006943) (xy 342.25279 -337.013043) (xy 342.197056 -337.011006) (xy 342.142213 -337.000876)
			(xy 342.089429 -336.982869) (xy 342.039829 -336.957368) (xy 341.994471 -336.924917) (xy 341.954322 -336.886208)
			(xy 341.920236 -336.842065) (xy 341.89294 -336.79343) (xy 341.873017 -336.741339) (xy 341.860891 -336.686902)
			(xy 341.85682 -336.63128) (xy 319.212468 -336.63128) (xy 318.490854 -337.352894) (xy 341.12911 -337.352894)
			(xy 341.133181 -337.297272) (xy 341.145307 -337.242835) (xy 341.16523 -337.190744) (xy 341.192526 -337.142109)
			(xy 341.226612 -337.097966) (xy 341.266761 -337.059257) (xy 341.312119 -337.026806) (xy 341.361719 -337.001305)
			(xy 341.414503 -336.983298) (xy 341.469346 -336.973168) (xy 341.52508 -336.971131) (xy 341.580517 -336.977231)
			(xy 341.634474 -336.991337) (xy 341.685803 -337.013149) (xy 341.733409 -337.042203) (xy 341.776277 -337.077878)
			(xy 341.813494 -337.119415) (xy 341.844267 -337.165928) (xy 341.867939 -337.216425) (xy 341.884007 -337.269832)
			(xy 341.892127 -337.325008) (xy 341.892636 -337.352894) (xy 341.892127 -337.38078) (xy 341.884007 -337.435956)
			(xy 341.867939 -337.489363) (xy 341.844267 -337.53986) (xy 341.813494 -337.586373) (xy 341.776277 -337.62791)
			(xy 341.733409 -337.663585) (xy 341.685803 -337.692639) (xy 341.634474 -337.714451) (xy 341.580517 -337.728557)
			(xy 341.52508 -337.734657) (xy 341.469346 -337.73262) (xy 341.414503 -337.72249) (xy 341.361719 -337.704483)
			(xy 341.312119 -337.678982) (xy 341.266761 -337.646531) (xy 341.226612 -337.607822) (xy 341.192526 -337.563679)
			(xy 341.16523 -337.515044) (xy 341.145307 -337.462953) (xy 341.133181 -337.408516) (xy 341.12911 -337.352894)
			(xy 318.490854 -337.352894) (xy 317.257176 -338.586572) (xy 332.820772 -338.586572) (xy 332.821204 -338.5592)
			(xy 332.829027 -338.505019) (xy 332.844523 -338.452515) (xy 332.867373 -338.402769) (xy 332.897106 -338.356804)
			(xy 332.914752 -338.335874) (xy 332.924012 -338.324565) (xy 332.93618 -338.298) (xy 332.940345 -338.269079)
			(xy 332.936168 -338.240159) (xy 332.923989 -338.213599) (xy 332.914752 -338.20227) (xy 332.89714 -338.181316)
			(xy 332.867423 -338.13535) (xy 332.844581 -338.085608) (xy 332.829083 -338.033112) (xy 332.821249 -337.97894)
			(xy 332.820772 -337.951572) (xy 332.821258 -337.924321) (xy 332.829014 -337.870373) (xy 332.844369 -337.818078)
			(xy 332.867011 -337.768501) (xy 332.896477 -337.722651) (xy 332.932168 -337.68146) (xy 332.973359 -337.645769)
			(xy 333.019209 -337.616303) (xy 333.068786 -337.593661) (xy 333.121081 -337.578306) (xy 333.175029 -337.57055)
			(xy 333.229531 -337.57055) (xy 333.283479 -337.578306) (xy 333.335774 -337.593661) (xy 333.385351 -337.616303)
			(xy 333.431201 -337.645769) (xy 333.472392 -337.68146) (xy 333.508083 -337.722651) (xy 333.537549 -337.768501)
			(xy 333.560191 -337.818078) (xy 333.575546 -337.870373) (xy 333.583302 -337.924321) (xy 333.583788 -337.951572)
			(xy 333.583308 -337.978942) (xy 333.575494 -338.03312) (xy 333.560009 -338.085623) (xy 333.53717 -338.135371)
			(xy 333.507448 -338.181338) (xy 333.489808 -338.20227) (xy 333.480597 -338.213617) (xy 333.469256 -338.238338)
			(xy 342.578944 -338.238338) (xy 342.579509 -338.20865) (xy 342.588703 -338.149991) (xy 342.606875 -338.093464)
			(xy 342.633587 -338.040436) (xy 342.668192 -337.992187) (xy 342.709855 -337.949883) (xy 342.733376 -337.93176)
			(xy 342.74396 -337.923305) (xy 342.760672 -337.902001) (xy 342.771195 -337.877053) (xy 342.77479 -337.850216)
			(xy 342.771204 -337.823377) (xy 342.760688 -337.798426) (xy 342.743982 -337.777116) (xy 342.733376 -337.768692)
			(xy 342.709857 -337.750567) (xy 342.668198 -337.70826) (xy 342.633595 -337.660011) (xy 342.606884 -337.606984)
			(xy 342.588709 -337.550459) (xy 342.57951 -337.491801) (xy 342.578944 -337.462114) (xy 342.57943 -337.434863)
			(xy 342.587186 -337.380915) (xy 342.602541 -337.32862) (xy 342.625183 -337.279043) (xy 342.654649 -337.233193)
			(xy 342.69034 -337.192002) (xy 342.731531 -337.156311) (xy 342.777381 -337.126845) (xy 342.826958 -337.104203)
			(xy 342.879253 -337.088848) (xy 342.933201 -337.081092) (xy 342.987703 -337.081092) (xy 343.041651 -337.088848)
			(xy 343.093946 -337.104203) (xy 343.143523 -337.126845) (xy 343.189373 -337.156311) (xy 343.230564 -337.192002)
			(xy 343.266255 -337.233193) (xy 343.295721 -337.279043) (xy 343.318363 -337.32862) (xy 343.333718 -337.380915)
			(xy 343.341474 -337.434863) (xy 343.34196 -337.462114) (xy 343.341431 -337.491803) (xy 343.332229 -337.550464)
			(xy 343.31405 -337.606991) (xy 343.287332 -337.660019) (xy 343.275257 -337.676851) (xy 343.595444 -337.676851)
			(xy 343.595444 -337.622349) (xy 343.6032 -337.5684) (xy 343.618554 -337.516105) (xy 343.641193 -337.466526)
			(xy 343.670658 -337.420674) (xy 343.706347 -337.379481) (xy 343.747536 -337.343787) (xy 343.793384 -337.314316)
			(xy 343.84296 -337.291671) (xy 343.895253 -337.27631) (xy 343.949201 -337.268547) (xy 343.976452 -337.268058)
			(xy 344.001688 -337.268438) (xy 344.051722 -337.275062) (xy 344.100442 -337.28824) (xy 344.146994 -337.307741)
			(xy 344.168984 -337.320128) (xy 344.181966 -337.327134) (xy 344.210596 -337.334177) (xy 344.240045 -337.33274)
			(xy 344.267854 -337.322944) (xy 344.291702 -337.305606) (xy 344.309598 -337.282175) (xy 344.315288 -337.268566)
			(xy 344.325959 -337.241779) (xy 344.354252 -337.191538) (xy 344.389785 -337.146129) (xy 344.431751 -337.106587)
			(xy 344.479192 -337.073815) (xy 344.531026 -337.048559) (xy 344.586072 -337.031395) (xy 344.643074 -337.022715)
			(xy 344.671904 -337.022186) (xy 344.699155 -337.022674) (xy 344.753102 -337.030431) (xy 344.805397 -337.045786)
			(xy 344.854974 -337.068427) (xy 344.900824 -337.097894) (xy 344.942014 -337.133585) (xy 344.977705 -337.174775)
			(xy 345.007172 -337.220625) (xy 345.016538 -337.241134) (xy 347.15958 -337.241134) (xy 347.160076 -337.213561)
			(xy 347.168023 -337.158989) (xy 347.183743 -337.10613) (xy 347.206907 -337.056085) (xy 347.237034 -337.009894)
			(xy 347.273496 -336.968521) (xy 347.2942 -336.950304) (xy 347.305063 -336.940371) (xy 347.321136 -336.91573)
			(xy 347.329523 -336.887532) (xy 347.32953 -336.858112) (xy 347.321155 -336.82991) (xy 347.305092 -336.805263)
			(xy 347.2942 -336.795364) (xy 347.273468 -336.777175) (xy 347.237 -336.735802) (xy 347.20687 -336.689607)
			(xy 347.183708 -336.639555) (xy 347.167996 -336.586688) (xy 347.160062 -336.53211) (xy 347.15958 -336.504534)
			(xy 347.160087 -336.477283) (xy 347.167839 -336.423334) (xy 347.18319 -336.371037) (xy 347.205828 -336.321458)
			(xy 347.235291 -336.275606) (xy 347.27098 -336.234413) (xy 347.312169 -336.198719) (xy 347.358018 -336.16925)
			(xy 347.407594 -336.146606) (xy 347.459889 -336.131249) (xy 347.513837 -336.12349) (xy 347.541088 -336.123026)
			(xy 347.575378 -336.12455) (xy 347.588737 -336.125329) (xy 347.615099 -336.120819) (xy 347.639377 -336.109598)
			(xy 347.659895 -336.092442) (xy 347.675237 -336.070533) (xy 347.684343 -336.045386) (xy 347.685868 -336.032094)
			(xy 347.688871 -336.003927) (xy 347.702039 -335.948837) (xy 347.723211 -335.896301) (xy 347.751922 -335.847475)
			(xy 347.78754 -335.803434) (xy 347.829282 -335.765146) (xy 347.876228 -335.733455) (xy 347.927346 -335.709058)
			(xy 347.981511 -335.692491) (xy 348.037531 -335.684119) (xy 348.065852 -335.683606) (xy 348.083871 -335.683823)
			(xy 348.119746 -335.68726) (xy 348.13748 -335.690464) (xy 348.152691 -335.692778) (xy 348.183241 -335.689255)
			(xy 348.211358 -335.6768) (xy 348.234494 -335.65654) (xy 348.250551 -335.630313) (xy 348.254828 -335.615534)
			(xy 348.262201 -335.588483) (xy 348.283834 -335.536756) (xy 348.312802 -335.48875) (xy 348.348481 -335.445499)
			(xy 348.390103 -335.407933) (xy 348.436774 -335.37686) (xy 348.487488 -335.352948) (xy 348.541154 -335.336713)
			(xy 348.596618 -335.328504) (xy 348.624652 -335.328006) (xy 348.651904 -335.3285) (xy 348.705855 -335.336251)
			(xy 348.758153 -335.351601) (xy 348.807734 -335.374239) (xy 348.853588 -335.403704) (xy 348.894782 -335.439394)
			(xy 348.930476 -335.480585) (xy 348.959944 -335.526436) (xy 348.982587 -335.576015) (xy 348.983463 -335.579)
			(xy 353.390417 -335.579) (xy 353.394585 -335.523382) (xy 353.406996 -335.469006) (xy 353.427372 -335.417087)
			(xy 353.455258 -335.368785) (xy 353.490031 -335.325178) (xy 353.530916 -335.287241) (xy 353.576997 -335.255821)
			(xy 353.627247 -335.23162) (xy 353.680542 -335.215178) (xy 353.735693 -335.206862) (xy 353.76358 -335.20634)
			(xy 353.790913 -335.206792) (xy 353.844993 -335.214765) (xy 353.897328 -335.230556) (xy 353.946793 -335.253827)
			(xy 353.992325 -335.284078) (xy 354.032946 -335.320659) (xy 354.067785 -335.362784) (xy 354.08235 -335.385918)
			(xy 354.090244 -335.398163) (xy 354.111724 -335.417832) (xy 354.137885 -335.430633) (xy 354.166597 -335.435523)
			(xy 354.195521 -335.432104) (xy 354.209096 -335.426812) (xy 354.23231 -335.417332) (xy 354.280641 -335.403977)
			(xy 354.330329 -335.397245) (xy 354.3554 -335.39684) (xy 354.380469 -335.397275) (xy 354.430152 -335.40402)
			(xy 354.478486 -335.417348) (xy 354.501704 -335.426812) (xy 354.515304 -335.431992) (xy 354.544193 -335.435371)
			(xy 354.572863 -335.430475) (xy 354.598994 -335.417702) (xy 354.620468 -335.398086) (xy 354.62845 -335.385918)
			(xy 354.643019 -335.362787) (xy 354.677862 -335.320666) (xy 354.718485 -335.284087) (xy 354.764016 -335.253836)
			(xy 354.813478 -335.23056) (xy 354.865809 -335.21476) (xy 354.919888 -335.206774) (xy 354.974552 -335.206774)
			(xy 355.028631 -335.21476) (xy 355.080962 -335.23056) (xy 355.130424 -335.253836) (xy 355.175955 -335.284087)
			(xy 355.216578 -335.320666) (xy 355.251421 -335.362787) (xy 355.26599 -335.385918) (xy 355.273941 -335.398122)
			(xy 355.295405 -335.417791) (xy 355.321551 -335.430597) (xy 355.350249 -335.435498) (xy 355.379163 -335.432094)
			(xy 355.392736 -335.426812) (xy 355.415945 -335.41732) (xy 355.464278 -335.403969) (xy 355.513968 -335.397243)
			(xy 355.53904 -335.39684) (xy 355.56588 -335.397387) (xy 355.619004 -335.405082) (xy 355.670475 -335.420321)
			(xy 355.719225 -335.442789) (xy 355.764247 -335.472021) (xy 355.804608 -335.507411) (xy 355.839472 -335.548227)
			(xy 355.868118 -335.593623) (xy 355.889952 -335.642661) (xy 355.897688 -335.668366) (xy 355.902375 -335.682854)
			(xy 355.91889 -335.708414) (xy 355.9422 -335.727978) (xy 355.970239 -335.739808) (xy 356.000517 -335.742857)
			(xy 356.030351 -335.736853) (xy 356.043992 -335.730088) (xy 356.072132 -335.715442) (xy 356.132086 -335.694719)
			(xy 356.194647 -335.684226) (xy 356.226364 -335.683606) (xy 356.244384 -335.683822) (xy 356.280258 -335.687259)
			(xy 356.297992 -335.690464) (xy 356.313202 -335.69279) (xy 356.343753 -335.689265) (xy 356.371871 -335.676806)
			(xy 356.395007 -335.656544) (xy 356.411064 -335.630314) (xy 356.41534 -335.615534) (xy 356.422702 -335.588479)
			(xy 356.444336 -335.536752) (xy 356.473305 -335.488746) (xy 356.508985 -335.445495) (xy 356.550609 -335.407928)
			(xy 356.597281 -335.376856) (xy 356.647996 -335.352945) (xy 356.701664 -335.336711) (xy 356.757129 -335.328503)
			(xy 356.785164 -335.328006) (xy 356.812417 -335.328489) (xy 356.866368 -335.336241) (xy 356.918666 -335.351593)
			(xy 356.968247 -335.374233) (xy 357.014101 -335.403698) (xy 357.055294 -335.43939) (xy 357.090988 -335.480582)
			(xy 357.120457 -335.526434) (xy 357.143099 -335.576013) (xy 357.143976 -335.579) (xy 361.550917 -335.579)
			(xy 361.555086 -335.523381) (xy 361.567497 -335.469004) (xy 361.587873 -335.417084) (xy 361.61576 -335.368781)
			(xy 361.650535 -335.325174) (xy 361.691421 -335.287237) (xy 361.737504 -335.255817) (xy 361.787755 -335.231616)
			(xy 361.841052 -335.215175) (xy 361.896204 -335.206862) (xy 361.924092 -335.20634) (xy 361.951425 -335.206783)
			(xy 362.005506 -335.214757) (xy 362.057841 -335.23055) (xy 362.107306 -335.253822) (xy 362.152838 -335.284075)
			(xy 362.193459 -335.320657) (xy 362.228297 -335.362784) (xy 362.242862 -335.385918) (xy 362.250744 -335.398171)
			(xy 362.272228 -335.417841) (xy 362.298392 -335.43064) (xy 362.327106 -335.435528) (xy 362.356032 -335.432105)
			(xy 362.369608 -335.426812) (xy 362.39282 -335.417328) (xy 362.441152 -335.403975) (xy 362.490841 -335.397244)
			(xy 362.515912 -335.39684) (xy 362.540981 -335.397271) (xy 362.590664 -335.404017) (xy 362.638998 -335.417347)
			(xy 362.662216 -335.426812) (xy 362.675812 -335.432005) (xy 362.704703 -335.435381) (xy 362.733375 -335.430482)
			(xy 362.759506 -335.417706) (xy 362.78098 -335.398087) (xy 362.788962 -335.385918) (xy 362.803531 -335.362787)
			(xy 362.838374 -335.320666) (xy 362.878997 -335.284087) (xy 362.924528 -335.253836) (xy 362.97399 -335.23056)
			(xy 363.026321 -335.21476) (xy 363.0804 -335.206774) (xy 363.135064 -335.206774) (xy 363.189143 -335.21476)
			(xy 363.241474 -335.23056) (xy 363.290936 -335.253836) (xy 363.336467 -335.284087) (xy 363.37709 -335.320666)
			(xy 363.411933 -335.362787) (xy 363.426502 -335.385918) (xy 363.434441 -335.39813) (xy 363.455909 -335.417799)
			(xy 363.482058 -335.430604) (xy 363.510759 -335.435503) (xy 363.539675 -335.432096) (xy 363.553248 -335.426812)
			(xy 363.576455 -335.417316) (xy 363.624789 -335.403967) (xy 363.67448 -335.397242) (xy 363.699552 -335.39684)
			(xy 363.726392 -335.397376) (xy 363.779517 -335.405073) (xy 363.830988 -335.420314) (xy 363.879739 -335.442783)
			(xy 363.92476 -335.472016) (xy 363.965121 -335.507407) (xy 363.999985 -335.548224) (xy 364.02863 -335.593622)
			(xy 364.050464 -335.642661) (xy 364.0582 -335.668366) (xy 364.062871 -335.68286) (xy 364.079389 -335.708422)
			(xy 364.102703 -335.727986) (xy 364.130744 -335.739816) (xy 364.161026 -335.742862) (xy 364.190862 -335.736855)
			(xy 364.204504 -335.730088) (xy 364.232659 -335.715474) (xy 364.292606 -335.69474) (xy 364.35516 -335.684233)
			(xy 364.386876 -335.683606) (xy 364.404896 -335.68382) (xy 364.44077 -335.687259) (xy 364.458504 -335.690464)
			(xy 364.473713 -335.692802) (xy 364.504265 -335.689273) (xy 364.532384 -335.676812) (xy 364.555519 -335.656547)
			(xy 364.571576 -335.630315) (xy 364.575852 -335.615534) (xy 364.583203 -335.588476) (xy 364.604838 -335.536748)
			(xy 364.633808 -335.488742) (xy 364.66949 -335.44549) (xy 364.711115 -335.407924) (xy 364.757788 -335.376851)
			(xy 364.808505 -335.352942) (xy 364.862174 -335.336709) (xy 364.917641 -335.328502) (xy 364.945676 -335.328006)
			(xy 364.972929 -335.328478) (xy 365.02688 -335.336232) (xy 365.079179 -335.351585) (xy 365.12876 -335.374226)
			(xy 365.174614 -335.403693) (xy 365.215807 -335.439386) (xy 365.251501 -335.480578) (xy 365.280969 -335.526431)
			(xy 365.303611 -335.576012) (xy 365.304488 -335.579) (xy 369.711391 -335.579) (xy 369.71556 -335.523376)
			(xy 369.727972 -335.468994) (xy 369.748351 -335.41707) (xy 369.776242 -335.368763) (xy 369.81102 -335.325152)
			(xy 369.85191 -335.287212) (xy 369.897998 -335.255791) (xy 369.948254 -335.231589) (xy 370.001557 -335.215148)
			(xy 370.056714 -335.206835) (xy 370.084604 -335.20634) (xy 370.111937 -335.206773) (xy 370.166019 -335.214749)
			(xy 370.218354 -335.230543) (xy 370.267819 -335.253818) (xy 370.313351 -335.284071) (xy 370.353972 -335.320655)
			(xy 370.38881 -335.362783) (xy 370.403374 -335.385918) (xy 370.41134 -335.398111) (xy 370.4328 -335.41778)
			(xy 370.458942 -335.430588) (xy 370.487637 -335.435491) (xy 370.516548 -335.432092) (xy 370.53012 -335.426812)
			(xy 370.553331 -335.417325) (xy 370.601663 -335.403973) (xy 370.651352 -335.397244) (xy 370.676424 -335.39684)
			(xy 370.701493 -335.397267) (xy 370.751176 -335.404015) (xy 370.799511 -335.417346) (xy 370.822728 -335.426812)
			(xy 370.836319 -335.432017) (xy 370.865212 -335.435391) (xy 370.893886 -335.430489) (xy 370.920018 -335.41771)
			(xy 370.941493 -335.398088) (xy 370.949474 -335.385918) (xy 370.964043 -335.362787) (xy 370.998886 -335.320666)
			(xy 371.039509 -335.284087) (xy 371.08504 -335.253836) (xy 371.134502 -335.23056) (xy 371.186833 -335.21476)
			(xy 371.240912 -335.206774) (xy 371.295576 -335.206774) (xy 371.349655 -335.21476) (xy 371.401986 -335.23056)
			(xy 371.451448 -335.253836) (xy 371.496979 -335.284087) (xy 371.537602 -335.320666) (xy 371.572445 -335.362787)
			(xy 371.587014 -335.385918) (xy 371.594942 -335.398139) (xy 371.616413 -335.417808) (xy 371.642565 -335.430612)
			(xy 371.671268 -335.435508) (xy 371.700186 -335.432098) (xy 371.71376 -335.426812) (xy 371.736966 -335.417312)
			(xy 371.785301 -335.403965) (xy 371.834992 -335.397241) (xy 371.860064 -335.39684) (xy 371.887949 -335.397417)
			(xy 371.943098 -335.405724) (xy 371.996392 -335.422159) (xy 372.046641 -335.446353) (xy 372.092723 -335.477767)
			(xy 372.133608 -335.515699) (xy 372.168382 -335.5593) (xy 372.196269 -335.607598) (xy 372.216645 -335.659513)
			(xy 372.229056 -335.713885) (xy 372.233224 -335.7695) (xy 372.229056 -335.825115) (xy 372.216645 -335.879487)
			(xy 372.196269 -335.931402) (xy 372.168382 -335.9797) (xy 372.133608 -336.023301) (xy 372.092723 -336.061233)
			(xy 372.046641 -336.092647) (xy 371.996392 -336.116841) (xy 371.943098 -336.133276) (xy 371.887949 -336.141583)
			(xy 371.860064 -336.142076) (xy 371.832733 -336.141582) (xy 371.778654 -336.133616) (xy 371.726321 -336.117831)
			(xy 371.676857 -336.094567) (xy 371.631324 -336.064323) (xy 371.590701 -336.027748) (xy 371.55586 -335.985629)
			(xy 371.541294 -335.962498) (xy 371.533355 -335.950285) (xy 371.511888 -335.930614) (xy 371.485739 -335.917808)
			(xy 371.457037 -335.91291) (xy 371.428121 -335.916318) (xy 371.414548 -335.921604) (xy 371.391341 -335.931102)
			(xy 371.343007 -335.94445) (xy 371.293316 -335.951174) (xy 371.268244 -335.951576) (xy 371.243174 -335.951158)
			(xy 371.193491 -335.944406) (xy 371.145157 -335.931071) (xy 371.12194 -335.921604) (xy 371.108362 -335.916358)
			(xy 371.079462 -335.912991) (xy 371.050783 -335.917901) (xy 371.024648 -335.93069) (xy 371.003174 -335.950323)
			(xy 370.995194 -335.962498) (xy 370.980625 -335.985629) (xy 370.945782 -336.02775) (xy 370.905159 -336.064329)
			(xy 370.859628 -336.09458) (xy 370.810166 -336.117856) (xy 370.757835 -336.133656) (xy 370.703756 -336.141642)
			(xy 370.649092 -336.141642) (xy 370.595013 -336.133656) (xy 370.542682 -336.117856) (xy 370.49322 -336.09458)
			(xy 370.447689 -336.064329) (xy 370.407066 -336.02775) (xy 370.372223 -335.985629) (xy 370.357654 -335.962498)
			(xy 370.349753 -335.950258) (xy 370.328276 -335.930587) (xy 370.302116 -335.917784) (xy 370.273406 -335.912893)
			(xy 370.244483 -335.916312) (xy 370.230908 -335.921604) (xy 370.207694 -335.931084) (xy 370.159363 -335.944438)
			(xy 370.109675 -335.95117) (xy 370.084604 -335.951576) (xy 370.056714 -335.951165) (xy 370.001557 -335.942852)
			(xy 369.948254 -335.926411) (xy 369.897998 -335.902209) (xy 369.85191 -335.870788) (xy 369.81102 -335.832848)
			(xy 369.776242 -335.789237) (xy 369.748351 -335.74093) (xy 369.727972 -335.689006) (xy 369.71556 -335.634624)
			(xy 369.711391 -335.579) (xy 365.304488 -335.579) (xy 365.318966 -335.62831) (xy 365.326722 -335.682261)
			(xy 365.327184 -335.709514) (xy 365.326665 -335.737087) (xy 365.318724 -335.791657) (xy 365.30301 -335.844517)
			(xy 365.27985 -335.894563) (xy 365.249727 -335.940754) (xy 365.213267 -335.982127) (xy 365.192564 -336.000344)
			(xy 365.181647 -336.010225) (xy 365.165566 -336.034878) (xy 365.157178 -336.063092) (xy 365.157181 -336.092526)
			(xy 365.165573 -336.120739) (xy 365.181659 -336.145388) (xy 365.192564 -336.155284) (xy 365.213285 -336.173484)
			(xy 365.249752 -336.214856) (xy 365.279881 -336.261047) (xy 365.303045 -336.311096) (xy 365.318761 -336.363959)
			(xy 365.326701 -336.418534) (xy 365.326699 -336.473684) (xy 365.318757 -336.528258) (xy 365.303039 -336.581121)
			(xy 365.279872 -336.631168) (xy 365.249741 -336.677359) (xy 365.213272 -336.718729) (xy 365.192564 -336.736944)
			(xy 365.181647 -336.746825) (xy 365.165566 -336.771478) (xy 365.157178 -336.799692) (xy 365.157181 -336.829126)
			(xy 365.165573 -336.857339) (xy 365.181659 -336.881988) (xy 365.192564 -336.891884) (xy 365.213263 -336.910108)
			(xy 365.249736 -336.951473) (xy 365.279871 -336.99766) (xy 365.303039 -337.047706) (xy 365.318757 -337.100566)
			(xy 365.326698 -337.15514) (xy 365.327184 -337.182714) (xy 365.326758 -337.209968) (xy 365.318999 -337.263922)
			(xy 365.312332 -337.286625) (xy 365.717275 -337.286625) (xy 365.717279 -337.232123) (xy 365.725039 -337.178175)
			(xy 365.740398 -337.125881) (xy 365.763043 -337.076305) (xy 365.792513 -337.030457) (xy 365.828207 -336.989269)
			(xy 365.8694 -336.95358) (xy 365.915253 -336.924117) (xy 365.964832 -336.901479) (xy 366.017128 -336.886128)
			(xy 366.071077 -336.878375) (xy 366.098328 -336.877914) (xy 366.113057 -336.878063) (xy 366.142427 -336.880351)
			(xy 366.157002 -336.882486) (xy 366.171557 -336.88423) (xy 366.200601 -336.880377) (xy 366.227353 -336.86843)
			(xy 366.249607 -336.849374) (xy 366.265529 -336.82478) (xy 366.273806 -336.796675) (xy 366.273755 -336.767376)
			(xy 366.270032 -336.7532) (xy 366.262676 -336.726691) (xy 366.254769 -336.672249) (xy 366.254284 -336.644742)
			(xy 366.25471 -336.617485) (xy 366.262462 -336.563526) (xy 366.277815 -336.511219) (xy 366.300456 -336.46163)
			(xy 366.329924 -336.415768) (xy 366.365619 -336.374566) (xy 366.406814 -336.338864) (xy 366.452671 -336.309388)
			(xy 366.502256 -336.286739) (xy 366.55456 -336.271377) (xy 366.608518 -336.263615) (xy 366.663031 -336.263611)
			(xy 366.71699 -336.271366) (xy 366.769296 -336.286721) (xy 366.818885 -336.309364) (xy 366.864745 -336.338834)
			(xy 366.905946 -336.37453) (xy 366.941646 -336.415727) (xy 366.97112 -336.461586) (xy 366.993767 -336.511172)
			(xy 367.009127 -336.563476) (xy 367.016886 -336.617435) (xy 367.016888 -336.671948) (xy 367.009131 -336.725907)
			(xy 366.993773 -336.778212) (xy 366.971128 -336.827799) (xy 366.941656 -336.873659) (xy 366.905958 -336.914857)
			(xy 366.864759 -336.950556) (xy 366.8189 -336.980028) (xy 366.769313 -337.002673) (xy 366.717007 -337.01803)
			(xy 366.663049 -337.025788) (xy 366.635792 -337.02625) (xy 366.621063 -337.026099) (xy 366.591693 -337.023813)
			(xy 366.577118 -337.021678) (xy 366.562577 -337.019774) (xy 366.533512 -337.023648) (xy 366.506747 -337.03562)
			(xy 366.484486 -337.054704) (xy 366.468564 -337.079326) (xy 366.460293 -337.107457) (xy 366.460356 -337.136778)
			(xy 366.464088 -337.150964) (xy 366.471458 -337.17747) (xy 366.479357 -337.231915) (xy 366.479836 -337.259422)
			(xy 366.479321 -337.286673) (xy 366.471561 -337.340621) (xy 366.456203 -337.392915) (xy 366.433559 -337.442491)
			(xy 366.40409 -337.48834) (xy 366.368396 -337.529528) (xy 366.327203 -337.565217) (xy 366.281351 -337.594681)
			(xy 366.231772 -337.617319) (xy 366.179476 -337.632671) (xy 366.125527 -337.640424) (xy 366.071025 -337.640421)
			(xy 366.017077 -337.632661) (xy 365.964783 -337.617302) (xy 365.915207 -337.594658) (xy 365.869358 -337.565189)
			(xy 365.82817 -337.529494) (xy 365.792481 -337.488301) (xy 365.763018 -337.442449) (xy 365.74038 -337.39287)
			(xy 365.725028 -337.340574) (xy 365.717275 -337.286625) (xy 365.312332 -337.286625) (xy 365.30364 -337.316222)
			(xy 365.280994 -337.365804) (xy 365.251522 -337.411658) (xy 365.215824 -337.452851) (xy 365.174628 -337.488545)
			(xy 365.12877 -337.518012) (xy 365.079186 -337.540653) (xy 365.026885 -337.556007) (xy 364.97293 -337.563761)
			(xy 364.945676 -337.564222) (xy 364.917821 -337.563704) (xy 364.862706 -337.555578) (xy 364.809356 -337.53953)
			(xy 364.758904 -337.515902) (xy 364.71242 -337.485194) (xy 364.670891 -337.448059) (xy 364.635198 -337.405284)
			(xy 364.606098 -337.357777) (xy 364.584209 -337.306547) (xy 364.576614 -337.279742) (xy 364.572272 -337.26565)
			(xy 364.556899 -337.240508) (xy 364.534998 -337.22079) (xy 364.508385 -337.208132) (xy 364.479268 -337.203584)
			(xy 364.4646 -337.205066) (xy 364.451583 -337.206734) (xy 364.425399 -337.208514) (xy 364.412276 -337.208622)
			(xy 364.398127 -337.208531) (xy 364.369904 -337.206495) (xy 364.355888 -337.204558) (xy 364.342533 -337.203057)
			(xy 364.315853 -337.206144) (xy 364.290907 -337.216099) (xy 364.26943 -337.232227) (xy 364.252916 -337.253409)
			(xy 364.242512 -337.278171) (xy 364.240318 -337.291426) (xy 364.236214 -337.318577) (xy 364.221244 -337.371407)
			(xy 364.198855 -337.421545) (xy 364.169509 -337.467956) (xy 364.133814 -337.509681) (xy 364.092506 -337.545858)
			(xy 364.046438 -337.57574) (xy 363.996563 -337.598709) (xy 363.94391 -337.614291) (xy 363.889567 -337.622164)
			(xy 363.862112 -337.622642) (xy 363.834863 -337.622111) (xy 363.780918 -337.614357) (xy 363.728627 -337.599005)
			(xy 363.679052 -337.576368) (xy 363.633203 -337.546906) (xy 363.592014 -337.511219) (xy 363.556322 -337.470034)
			(xy 363.526855 -337.424189) (xy 363.504211 -337.374617) (xy 363.488853 -337.322327) (xy 363.481093 -337.268383)
			(xy 363.480604 -337.241134) (xy 363.481092 -337.21356) (xy 363.48904 -337.158988) (xy 363.50476 -337.106129)
			(xy 363.527926 -337.056083) (xy 363.558055 -337.009893) (xy 363.594519 -336.96852) (xy 363.615224 -336.950304)
			(xy 363.626084 -336.940369) (xy 363.642154 -336.915728) (xy 363.650539 -336.887531) (xy 363.650546 -336.858113)
			(xy 363.642173 -336.829912) (xy 363.626114 -336.805264) (xy 363.615224 -336.795364) (xy 363.594497 -336.77717)
			(xy 363.558027 -336.735798) (xy 363.527896 -336.689605) (xy 363.504733 -336.639553) (xy 363.48902 -336.586688)
			(xy 363.481086 -336.53211) (xy 363.480604 -336.504534) (xy 363.481038 -336.478032) (xy 363.488387 -336.42554)
			(xy 363.502936 -336.374572) (xy 363.524404 -336.32611) (xy 363.552377 -336.281088) (xy 363.568996 -336.26044)
			(xy 363.578467 -336.248313) (xy 363.590263 -336.219907) (xy 363.593087 -336.189278) (xy 363.586685 -336.159193)
			(xy 363.571635 -336.132369) (xy 363.549295 -336.111226) (xy 363.535722 -336.103976) (xy 363.512025 -336.091888)
			(xy 363.468045 -336.061961) (xy 363.428765 -336.026086) (xy 363.394984 -335.984992) (xy 363.380782 -335.962498)
			(xy 363.372854 -335.950277) (xy 363.351384 -335.930606) (xy 363.325232 -335.917801) (xy 363.296528 -335.912905)
			(xy 363.26761 -335.916317) (xy 363.254036 -335.921604) (xy 363.230819 -335.931075) (xy 363.18249 -335.944433)
			(xy 363.132803 -335.951169) (xy 363.107732 -335.951576) (xy 363.082662 -335.951162) (xy 363.032979 -335.944408)
			(xy 362.984645 -335.931072) (xy 362.961428 -335.921604) (xy 362.947855 -335.916345) (xy 362.918952 -335.912981)
			(xy 362.890271 -335.917894) (xy 362.864136 -335.930686) (xy 362.842662 -335.950321) (xy 362.834682 -335.962498)
			(xy 362.820113 -335.985629) (xy 362.78527 -336.02775) (xy 362.744647 -336.064329) (xy 362.699116 -336.09458)
			(xy 362.649654 -336.117856) (xy 362.597323 -336.133656) (xy 362.543244 -336.141642) (xy 362.48858 -336.141642)
			(xy 362.434501 -336.133656) (xy 362.38217 -336.117856) (xy 362.332708 -336.09458) (xy 362.287177 -336.064329)
			(xy 362.246554 -336.02775) (xy 362.211711 -335.985629) (xy 362.197142 -335.962498) (xy 362.189252 -335.95025)
			(xy 362.167772 -335.930579) (xy 362.141609 -335.917777) (xy 362.112896 -335.912888) (xy 362.083971 -335.916311)
			(xy 362.070396 -335.921604) (xy 362.047184 -335.931087) (xy 361.998852 -335.944441) (xy 361.949163 -335.951171)
			(xy 361.924092 -335.951576) (xy 361.896204 -335.951138) (xy 361.841052 -335.942825) (xy 361.787755 -335.926384)
			(xy 361.737504 -335.902183) (xy 361.691421 -335.870763) (xy 361.650535 -335.832826) (xy 361.61576 -335.789219)
			(xy 361.587873 -335.740916) (xy 361.567497 -335.688996) (xy 361.555086 -335.634619) (xy 361.550917 -335.579)
			(xy 357.143976 -335.579) (xy 357.158454 -335.628311) (xy 357.16621 -335.682261) (xy 357.166672 -335.709514)
			(xy 357.166157 -335.737087) (xy 357.158216 -335.791658) (xy 357.142501 -335.844517) (xy 357.119341 -335.894564)
			(xy 357.089216 -335.940755) (xy 357.052756 -335.982127) (xy 357.032052 -336.000344) (xy 357.021136 -336.010226)
			(xy 357.005057 -336.034879) (xy 356.99667 -336.063092) (xy 356.996673 -336.092526) (xy 357.005064 -336.120738)
			(xy 357.021148 -336.145388) (xy 357.032052 -336.155284) (xy 357.052774 -336.173483) (xy 357.089241 -336.214855)
			(xy 357.119372 -336.261047) (xy 357.142536 -336.311096) (xy 357.158253 -336.363959) (xy 357.166193 -336.418534)
			(xy 357.166192 -336.473684) (xy 357.158249 -336.528259) (xy 357.14253 -336.581121) (xy 357.119363 -336.631169)
			(xy 357.08923 -336.67736) (xy 357.052761 -336.718729) (xy 357.032052 -336.736944) (xy 357.021136 -336.746826)
			(xy 357.005057 -336.771479) (xy 356.99667 -336.799692) (xy 356.996673 -336.829126) (xy 357.005064 -336.857338)
			(xy 357.021148 -336.881988) (xy 357.032052 -336.891884) (xy 357.052749 -336.910111) (xy 357.089222 -336.951475)
			(xy 357.119358 -336.997661) (xy 357.142526 -337.047706) (xy 357.158245 -337.100567) (xy 357.166186 -337.15514)
			(xy 357.166672 -337.182714) (xy 357.166258 -337.209969) (xy 357.160641 -337.249022) (xy 357.497106 -337.249022)
			(xy 357.49711 -337.194524) (xy 357.50487 -337.140581) (xy 357.520227 -337.088292) (xy 357.54287 -337.03872)
			(xy 357.572337 -336.992875) (xy 357.608029 -336.951691) (xy 357.649218 -336.916005) (xy 357.695067 -336.886545)
			(xy 357.744642 -336.863909) (xy 357.796933 -336.848559) (xy 357.850877 -336.840806) (xy 357.878126 -336.840322)
			(xy 357.903517 -336.840764) (xy 357.953848 -336.847513) (xy 357.978456 -336.853784) (xy 357.993101 -336.857224)
			(xy 358.023156 -336.856294) (xy 358.051639 -336.846659) (xy 358.076088 -336.829153) (xy 358.094384 -336.805291)
			(xy 358.104946 -336.777137) (xy 358.106859 -336.747129) (xy 358.103932 -336.732372) (xy 358.099164 -336.71078)
			(xy 358.094072 -336.666853) (xy 358.093772 -336.644742) (xy 358.09421 -336.617485) (xy 358.101962 -336.563526)
			(xy 358.117315 -336.511219) (xy 358.139957 -336.461629) (xy 358.169425 -336.415767) (xy 358.20512 -336.374565)
			(xy 358.246316 -336.338863) (xy 358.292173 -336.309387) (xy 358.341759 -336.286738) (xy 358.394064 -336.271376)
			(xy 358.448022 -336.263615) (xy 358.502536 -336.263611) (xy 358.556495 -336.271367) (xy 358.608801 -336.286723)
			(xy 358.658389 -336.309366) (xy 358.70425 -336.338837) (xy 358.74545 -336.374535) (xy 358.78115 -336.415732)
			(xy 358.810623 -336.461592) (xy 358.83327 -336.511179) (xy 358.848628 -336.563484) (xy 358.856387 -336.617443)
			(xy 358.856387 -336.671956) (xy 358.848629 -336.725915) (xy 358.83327 -336.77822) (xy 358.810624 -336.827807)
			(xy 358.781151 -336.873667) (xy 358.745451 -336.914864) (xy 358.704251 -336.950562) (xy 358.65839 -336.980033)
			(xy 358.608802 -337.002677) (xy 358.556496 -337.018033) (xy 358.502537 -337.025788) (xy 358.47528 -337.02625)
			(xy 358.449889 -337.025807) (xy 358.399558 -337.019059) (xy 358.37495 -337.012788) (xy 358.360298 -337.009388)
			(xy 358.330251 -337.010317) (xy 358.301774 -337.019948) (xy 358.27733 -337.037447) (xy 358.259034 -337.061301)
			(xy 358.24847 -337.089446) (xy 358.246551 -337.119446) (xy 358.249474 -337.1342) (xy 358.254238 -337.155793)
			(xy 358.259332 -337.199719) (xy 358.259634 -337.22183) (xy 358.25909 -337.249079) (xy 358.25133 -337.303022)
			(xy 358.235972 -337.355311) (xy 358.213328 -337.404882) (xy 358.183861 -337.450727) (xy 358.148169 -337.491911)
			(xy 358.10698 -337.527596) (xy 358.061131 -337.557057) (xy 358.011556 -337.579692) (xy 357.959264 -337.595042)
			(xy 357.90532 -337.602794) (xy 357.850822 -337.60279) (xy 357.79688 -337.59503) (xy 357.74459 -337.579672)
			(xy 357.695019 -337.557029) (xy 357.649174 -337.527562) (xy 357.60799 -337.49187) (xy 357.572305 -337.450681)
			(xy 357.542844 -337.404832) (xy 357.520208 -337.355257) (xy 357.504858 -337.302966) (xy 357.497106 -337.249022)
			(xy 357.160641 -337.249022) (xy 357.158498 -337.263923) (xy 357.143139 -337.316225) (xy 357.120492 -337.365807)
			(xy 357.091019 -337.411662) (xy 357.05532 -337.452855) (xy 357.014122 -337.488549) (xy 356.968263 -337.518016)
			(xy 356.918678 -337.540656) (xy 356.866375 -337.556009) (xy 356.812419 -337.563762) (xy 356.785164 -337.564222)
			(xy 356.757309 -337.563715) (xy 356.702193 -337.555587) (xy 356.648843 -337.539538) (xy 356.598391 -337.515908)
			(xy 356.551907 -337.485199) (xy 356.510378 -337.448062) (xy 356.474685 -337.405286) (xy 356.445586 -337.357779)
			(xy 356.423697 -337.306547) (xy 356.416102 -337.279742) (xy 356.411772 -337.265645) (xy 356.396397 -337.240502)
			(xy 356.374492 -337.220784) (xy 356.347876 -337.208128) (xy 356.318757 -337.203582) (xy 356.304088 -337.205066)
			(xy 356.291071 -337.206735) (xy 356.264887 -337.208515) (xy 356.251764 -337.208622) (xy 356.237615 -337.208532)
			(xy 356.209392 -337.206495) (xy 356.195376 -337.204558) (xy 356.182023 -337.203045) (xy 356.155341 -337.206135)
			(xy 356.130394 -337.216092) (xy 356.108917 -337.232223) (xy 356.092403 -337.253406) (xy 356.082 -337.27817)
			(xy 356.079806 -337.291426) (xy 356.075714 -337.318579) (xy 356.060743 -337.37141) (xy 356.038353 -337.421549)
			(xy 356.009006 -337.46796) (xy 355.973309 -337.509686) (xy 355.932 -337.545862) (xy 355.885931 -337.575744)
			(xy 355.836054 -337.598712) (xy 355.7834 -337.614293) (xy 355.729056 -337.622165) (xy 355.7016 -337.622642)
			(xy 355.67435 -337.622122) (xy 355.620406 -337.614367) (xy 355.568114 -337.599013) (xy 355.518539 -337.576375)
			(xy 355.47269 -337.546911) (xy 355.4315 -337.511224) (xy 355.395809 -337.470037) (xy 355.366342 -337.424191)
			(xy 355.343699 -337.374618) (xy 355.328341 -337.322328) (xy 355.32058 -337.268384) (xy 355.320092 -337.241134)
			(xy 355.320584 -337.21356) (xy 355.328531 -337.158989) (xy 355.344252 -337.10613) (xy 355.367417 -337.056084)
			(xy 355.397544 -337.009893) (xy 355.434007 -336.968521) (xy 355.454712 -336.950304) (xy 355.465574 -336.94037)
			(xy 355.481645 -336.915729) (xy 355.490031 -336.887531) (xy 355.490038 -336.858113) (xy 355.481664 -336.829911)
			(xy 355.465603 -336.805263) (xy 355.454712 -336.795364) (xy 355.433983 -336.777173) (xy 355.397513 -336.7358)
			(xy 355.367383 -336.689606) (xy 355.34422 -336.639554) (xy 355.328508 -336.586688) (xy 355.320574 -336.53211)
			(xy 355.320092 -336.504534) (xy 355.320528 -336.478032) (xy 355.327878 -336.425541) (xy 355.342426 -336.374573)
			(xy 355.363893 -336.326111) (xy 355.391865 -336.281089) (xy 355.408484 -336.26044) (xy 355.417925 -336.248295)
			(xy 355.429707 -336.219894) (xy 355.432526 -336.189276) (xy 355.42613 -336.159201) (xy 355.411094 -336.13238)
			(xy 355.388774 -336.111232) (xy 355.37521 -336.103976) (xy 355.351511 -336.091892) (xy 355.307531 -336.061963)
			(xy 355.268253 -336.026087) (xy 355.234472 -335.984992) (xy 355.22027 -335.962498) (xy 355.212354 -335.950269)
			(xy 355.19088 -335.930598) (xy 355.164725 -335.917794) (xy 355.136018 -335.9129) (xy 355.107098 -335.916315)
			(xy 355.093524 -335.921604) (xy 355.070308 -335.931079) (xy 355.021978 -335.944435) (xy 354.972291 -335.951169)
			(xy 354.94722 -335.951576) (xy 354.922151 -335.951133) (xy 354.872469 -335.944392) (xy 354.824134 -335.931066)
			(xy 354.800916 -335.921604) (xy 354.787324 -335.916389) (xy 354.758423 -335.913003) (xy 354.729739 -335.917897)
			(xy 354.703596 -335.930674) (xy 354.682112 -335.950299) (xy 354.67417 -335.962498) (xy 354.659601 -335.985629)
			(xy 354.624758 -336.02775) (xy 354.584135 -336.064329) (xy 354.538604 -336.09458) (xy 354.489142 -336.117856)
			(xy 354.436811 -336.133656) (xy 354.382732 -336.141642) (xy 354.328068 -336.141642) (xy 354.273989 -336.133656)
			(xy 354.221658 -336.117856) (xy 354.172196 -336.09458) (xy 354.126665 -336.064329) (xy 354.086042 -336.02775)
			(xy 354.051199 -335.985629) (xy 354.03663 -335.962498) (xy 354.028751 -335.950242) (xy 354.007268 -335.93057)
			(xy 353.981103 -335.91777) (xy 353.952387 -335.912884) (xy 353.92346 -335.916309) (xy 353.909884 -335.921604)
			(xy 353.886673 -335.931091) (xy 353.838341 -335.944443) (xy 353.788652 -335.951172) (xy 353.76358 -335.951576)
			(xy 353.735693 -335.951138) (xy 353.680542 -335.942822) (xy 353.627247 -335.92638) (xy 353.576997 -335.902179)
			(xy 353.530916 -335.870759) (xy 353.490031 -335.832822) (xy 353.455258 -335.789215) (xy 353.427372 -335.740913)
			(xy 353.406996 -335.688994) (xy 353.394585 -335.634618) (xy 353.390417 -335.579) (xy 348.983463 -335.579)
			(xy 348.997942 -335.628312) (xy 349.005698 -335.682262) (xy 349.00616 -335.709514) (xy 349.005649 -335.737087)
			(xy 348.997708 -335.791659) (xy 348.981993 -335.844518) (xy 348.958831 -335.894565) (xy 348.928706 -335.940755)
			(xy 348.892245 -335.982128) (xy 348.87154 -336.000344) (xy 348.860626 -336.010227) (xy 348.844548 -336.03488)
			(xy 348.836162 -336.063093) (xy 348.836165 -336.092525) (xy 348.844555 -336.120737) (xy 348.860638 -336.145387)
			(xy 348.87154 -336.155284) (xy 348.892262 -336.173483) (xy 348.928731 -336.214854) (xy 348.958862 -336.261046)
			(xy 348.982028 -336.311095) (xy 348.997745 -336.363958) (xy 349.005685 -336.418534) (xy 349.005684 -336.473684)
			(xy 348.997741 -336.52826) (xy 348.982021 -336.581122) (xy 348.958854 -336.63117) (xy 348.92872 -336.67736)
			(xy 348.892249 -336.71873) (xy 348.87154 -336.736944) (xy 348.860626 -336.746827) (xy 348.844548 -336.77148)
			(xy 348.836162 -336.799693) (xy 348.836165 -336.829125) (xy 348.844555 -336.857337) (xy 348.860638 -336.881987)
			(xy 348.87154 -336.891884) (xy 348.892255 -336.910091) (xy 348.928723 -336.951462) (xy 348.958854 -336.997653)
			(xy 348.982018 -337.047701) (xy 348.997735 -337.100564) (xy 349.005674 -337.155139) (xy 349.00616 -337.182714)
			(xy 349.005954 -337.196688) (xy 349.431337 -337.196688) (xy 349.439088 -337.142734) (xy 349.454439 -337.090433)
			(xy 349.477077 -337.040848) (xy 349.506541 -336.99499) (xy 349.542231 -336.953792) (xy 349.583421 -336.918092)
			(xy 349.629273 -336.888618) (xy 349.678852 -336.865969) (xy 349.73115 -336.850606) (xy 349.785102 -336.842843)
			(xy 349.812356 -336.842354) (xy 349.83547 -336.843116) (xy 349.848795 -336.843542) (xy 349.874897 -336.838144)
			(xy 349.898719 -336.826187) (xy 349.918644 -336.808483) (xy 349.933321 -336.786233) (xy 349.941752 -336.760947)
			(xy 349.943367 -336.734342) (xy 349.941134 -336.721196) (xy 349.937481 -336.702293) (xy 349.933539 -336.663993)
			(xy 349.93326 -336.644742) (xy 349.93371 -336.617485) (xy 349.941463 -336.563525) (xy 349.956816 -336.511218)
			(xy 349.979457 -336.461628) (xy 350.008926 -336.415765) (xy 350.044621 -336.374563) (xy 350.085818 -336.338861)
			(xy 350.131676 -336.309386) (xy 350.181262 -336.286737) (xy 350.233567 -336.271375) (xy 350.287526 -336.263614)
			(xy 350.34204 -336.263612) (xy 350.395999 -336.271368) (xy 350.448305 -336.286724) (xy 350.497894 -336.309369)
			(xy 350.543755 -336.33884) (xy 350.584954 -336.374539) (xy 350.620654 -336.415737) (xy 350.650126 -336.461597)
			(xy 350.672772 -336.511185) (xy 350.68813 -336.563491) (xy 350.695887 -336.61745) (xy 350.695886 -336.671964)
			(xy 350.688127 -336.725923) (xy 350.672767 -336.778229) (xy 350.650119 -336.827815) (xy 350.620645 -336.873674)
			(xy 350.584944 -336.914871) (xy 350.543743 -336.950568) (xy 350.497881 -336.980038) (xy 350.448292 -337.002681)
			(xy 350.395985 -337.018035) (xy 350.342025 -337.025789) (xy 350.314768 -337.02625) (xy 350.291654 -337.025488)
			(xy 350.278329 -337.025079) (xy 350.252227 -337.030472) (xy 350.228404 -337.042425) (xy 350.208478 -337.060126)
			(xy 350.193801 -337.082374) (xy 350.18537 -337.107659) (xy 350.183757 -337.134263) (xy 350.18599 -337.147408)
			(xy 350.189644 -337.166311) (xy 350.193585 -337.204611) (xy 350.193864 -337.223862) (xy 350.193463 -337.251116)
			(xy 350.185711 -337.30507) (xy 350.17036 -337.357371) (xy 350.147721 -337.406955) (xy 350.118257 -337.452813)
			(xy 350.082566 -337.494011) (xy 350.041376 -337.52971) (xy 349.995524 -337.559184) (xy 349.945944 -337.581832)
			(xy 349.893646 -337.597194) (xy 349.839694 -337.604957) (xy 349.785186 -337.604963) (xy 349.731232 -337.597211)
			(xy 349.678931 -337.58186) (xy 349.629347 -337.559222) (xy 349.583489 -337.529758) (xy 349.542291 -337.494068)
			(xy 349.506591 -337.452877) (xy 349.477117 -337.407026) (xy 349.454468 -337.357446) (xy 349.439106 -337.305148)
			(xy 349.431343 -337.251196) (xy 349.431337 -337.196688) (xy 349.005954 -337.196688) (xy 349.005758 -337.209969)
			(xy 348.997998 -337.263925) (xy 348.982638 -337.316227) (xy 348.95999 -337.365811) (xy 348.930516 -337.411666)
			(xy 348.894816 -337.45286) (xy 348.853616 -337.488553) (xy 348.807756 -337.51802) (xy 348.758169 -337.540659)
			(xy 348.705864 -337.556011) (xy 348.651907 -337.563762) (xy 348.624652 -337.564222) (xy 348.596796 -337.563726)
			(xy 348.54168 -337.555596) (xy 348.48833 -337.539545) (xy 348.437878 -337.515914) (xy 348.391394 -337.485204)
			(xy 348.349865 -337.448066) (xy 348.314173 -337.405289) (xy 348.285073 -337.35778) (xy 348.263185 -337.306548)
			(xy 348.25559 -337.279742) (xy 348.251272 -337.265641) (xy 348.235894 -337.240497) (xy 348.213987 -337.220779)
			(xy 348.187368 -337.208124) (xy 348.158246 -337.203581) (xy 348.143576 -337.205066) (xy 348.13056 -337.206736)
			(xy 348.104375 -337.208515) (xy 348.091252 -337.208622) (xy 348.077103 -337.208522) (xy 348.04888 -337.206492)
			(xy 348.034864 -337.204558) (xy 348.021512 -337.203033) (xy 347.994829 -337.206126) (xy 347.969882 -337.216085)
			(xy 347.948405 -337.232218) (xy 347.931891 -337.253404) (xy 347.921488 -337.278169) (xy 347.919294 -337.291426)
			(xy 347.915213 -337.318581) (xy 347.900242 -337.371413) (xy 347.877851 -337.421553) (xy 347.848503 -337.467965)
			(xy 347.812805 -337.50969) (xy 347.771494 -337.545867) (xy 347.725423 -337.575748) (xy 347.675545 -337.598715)
			(xy 347.622889 -337.614295) (xy 347.568544 -337.622166) (xy 347.541088 -337.622642) (xy 347.513838 -337.622133)
			(xy 347.459893 -337.614376) (xy 347.407601 -337.599021) (xy 347.358026 -337.576381) (xy 347.312177 -337.546917)
			(xy 347.270988 -337.511228) (xy 347.235296 -337.470041) (xy 347.205829 -337.424194) (xy 347.183186 -337.37462)
			(xy 347.167828 -337.322329) (xy 347.160068 -337.268384) (xy 347.15958 -337.241134) (xy 345.016538 -337.241134)
			(xy 345.029813 -337.270201) (xy 345.045169 -337.322496) (xy 345.052926 -337.376443) (xy 345.053412 -337.403694)
			(xy 345.052886 -337.433599) (xy 345.043567 -337.492678) (xy 345.03487 -337.521296) (xy 345.030926 -337.535227)
			(xy 345.030004 -337.564145) (xy 345.037252 -337.592155) (xy 345.052087 -337.616995) (xy 345.073309 -337.63666)
			(xy 345.099206 -337.649562) (xy 345.113356 -337.652614) (xy 345.139432 -337.657766) (xy 345.189936 -337.674341)
			(xy 345.237648 -337.697767) (xy 345.281646 -337.727591) (xy 345.321075 -337.763236) (xy 345.355174 -337.804011)
			(xy 345.38328 -337.849126) (xy 345.404849 -337.897706) (xy 345.419464 -337.94881) (xy 345.426841 -338.001449)
			(xy 345.4273 -338.028026) (xy 345.426814 -338.055277) (xy 345.419058 -338.109225) (xy 345.403703 -338.16152)
			(xy 345.381061 -338.211097) (xy 345.363554 -338.238338) (xy 350.739456 -338.238338) (xy 350.740016 -338.20865)
			(xy 350.749211 -338.14999) (xy 350.767383 -338.093463) (xy 350.794096 -338.040435) (xy 350.828702 -337.992186)
			(xy 350.870366 -337.949883) (xy 350.893888 -337.93176) (xy 350.904471 -337.923305) (xy 350.921181 -337.902)
			(xy 350.931703 -337.877052) (xy 350.935297 -337.850216) (xy 350.931711 -337.823378) (xy 350.921197 -337.798427)
			(xy 350.904493 -337.777117) (xy 350.893888 -337.768692) (xy 350.870371 -337.750564) (xy 350.828712 -337.708258)
			(xy 350.794108 -337.66001) (xy 350.767397 -337.606983) (xy 350.749222 -337.550459) (xy 350.740022 -337.491801)
			(xy 350.739456 -337.462114) (xy 350.739942 -337.434863) (xy 350.747698 -337.380915) (xy 350.763053 -337.32862)
			(xy 350.785695 -337.279043) (xy 350.815161 -337.233193) (xy 350.850852 -337.192002) (xy 350.892043 -337.156311)
			(xy 350.937893 -337.126845) (xy 350.98747 -337.104203) (xy 351.039765 -337.088848) (xy 351.093713 -337.081092)
			(xy 351.148215 -337.081092) (xy 351.202163 -337.088848) (xy 351.254458 -337.104203) (xy 351.304035 -337.126845)
			(xy 351.349885 -337.156311) (xy 351.391076 -337.192002) (xy 351.426767 -337.233193) (xy 351.456233 -337.279043)
			(xy 351.478875 -337.32862) (xy 351.49423 -337.380915) (xy 351.501986 -337.434863) (xy 351.502472 -337.462114)
			(xy 351.501938 -337.491803) (xy 351.492737 -337.550464) (xy 351.474558 -337.60699) (xy 351.447841 -337.660018)
			(xy 351.435765 -337.676852) (xy 351.755944 -337.676852) (xy 351.755944 -337.622348) (xy 351.7637 -337.568399)
			(xy 351.779055 -337.516102) (xy 351.801695 -337.466523) (xy 351.831161 -337.42067) (xy 351.866852 -337.379477)
			(xy 351.908041 -337.343782) (xy 351.953891 -337.314313) (xy 352.003468 -337.291667) (xy 352.055763 -337.276308)
			(xy 352.109712 -337.268546) (xy 352.136964 -337.268058) (xy 352.1622 -337.268433) (xy 352.212235 -337.275058)
			(xy 352.260955 -337.288238) (xy 352.307506 -337.307741) (xy 352.329496 -337.320128) (xy 352.342471 -337.327148)
			(xy 352.371104 -337.334189) (xy 352.400555 -337.332749) (xy 352.428366 -337.322951) (xy 352.452214 -337.30561)
			(xy 352.47011 -337.282176) (xy 352.4758 -337.268566) (xy 352.486461 -337.241775) (xy 352.514755 -337.191533)
			(xy 352.55029 -337.146124) (xy 352.592257 -337.106583) (xy 352.639699 -337.073811) (xy 352.691535 -337.048556)
			(xy 352.746582 -337.031393) (xy 352.803586 -337.022714) (xy 352.832416 -337.022186) (xy 352.859667 -337.022663)
			(xy 352.913615 -337.030421) (xy 352.96591 -337.045778) (xy 353.015487 -337.068421) (xy 353.061337 -337.097888)
			(xy 353.102526 -337.133581) (xy 353.138218 -337.174771) (xy 353.167684 -337.220622) (xy 353.190325 -337.2702)
			(xy 353.205681 -337.322495) (xy 353.213438 -337.376443) (xy 353.213924 -337.403694) (xy 353.213398 -337.433599)
			(xy 353.204079 -337.492678) (xy 353.195382 -337.521296) (xy 353.191429 -337.535225) (xy 353.190506 -337.564145)
			(xy 353.197755 -337.592157) (xy 353.212592 -337.616998) (xy 353.233817 -337.636663) (xy 353.259717 -337.649563)
			(xy 353.273868 -337.652614) (xy 353.299946 -337.657757) (xy 353.350449 -337.674333) (xy 353.398162 -337.697761)
			(xy 353.442159 -337.727587) (xy 353.481589 -337.763233) (xy 353.515687 -337.804008) (xy 353.543792 -337.849124)
			(xy 353.565362 -337.897704) (xy 353.579976 -337.94881) (xy 353.587353 -338.001449) (xy 353.587812 -338.028026)
			(xy 353.587326 -338.055277) (xy 353.57957 -338.109225) (xy 353.564215 -338.16152) (xy 353.541573 -338.211097)
			(xy 353.524066 -338.238338) (xy 358.899968 -338.238338) (xy 358.900524 -338.20865) (xy 358.909719 -338.149989)
			(xy 358.927892 -338.093462) (xy 358.954605 -338.040434) (xy 358.989212 -337.992186) (xy 359.030878 -337.949883)
			(xy 359.0544 -337.93176) (xy 359.064982 -337.923304) (xy 359.08169 -337.901999) (xy 359.092211 -337.877051)
			(xy 359.095804 -337.850216) (xy 359.092219 -337.823379) (xy 359.081706 -337.798428) (xy 359.065004 -337.777118)
			(xy 359.0544 -337.768692) (xy 359.030886 -337.750561) (xy 358.989225 -337.708256) (xy 358.954621 -337.660008)
			(xy 358.927909 -337.606982) (xy 358.909734 -337.550458) (xy 358.900534 -337.491801) (xy 358.899968 -337.462114)
			(xy 358.900454 -337.434863) (xy 358.90821 -337.380915) (xy 358.923565 -337.32862) (xy 358.946207 -337.279043)
			(xy 358.975673 -337.233193) (xy 359.011364 -337.192002) (xy 359.052555 -337.156311) (xy 359.098405 -337.126845)
			(xy 359.147982 -337.104203) (xy 359.200277 -337.088848) (xy 359.254225 -337.081092) (xy 359.308727 -337.081092)
			(xy 359.362675 -337.088848) (xy 359.41497 -337.104203) (xy 359.464547 -337.126845) (xy 359.510397 -337.156311)
			(xy 359.551588 -337.192002) (xy 359.587279 -337.233193) (xy 359.616745 -337.279043) (xy 359.639387 -337.32862)
			(xy 359.654742 -337.380915) (xy 359.662498 -337.434863) (xy 359.662984 -337.462114) (xy 359.662446 -337.491803)
			(xy 359.653244 -337.550463) (xy 359.635066 -337.606989) (xy 359.60835 -337.660017) (xy 359.596273 -337.676853)
			(xy 359.916444 -337.676853) (xy 359.916444 -337.622347) (xy 359.9242 -337.568397) (xy 359.939556 -337.516099)
			(xy 359.962197 -337.466519) (xy 359.991664 -337.420666) (xy 360.027356 -337.379473) (xy 360.068547 -337.343778)
			(xy 360.114398 -337.314309) (xy 360.163977 -337.291664) (xy 360.216274 -337.276305) (xy 360.270223 -337.268546)
			(xy 360.297476 -337.268058) (xy 360.322712 -337.268427) (xy 360.372747 -337.275055) (xy 360.421467 -337.288236)
			(xy 360.468018 -337.30774) (xy 360.490008 -337.320128) (xy 360.502976 -337.327162) (xy 360.531612 -337.334201)
			(xy 360.561065 -337.332759) (xy 360.588877 -337.322957) (xy 360.612726 -337.305614) (xy 360.630622 -337.282177)
			(xy 360.636312 -337.268566) (xy 360.646963 -337.241771) (xy 360.675258 -337.191528) (xy 360.710794 -337.146119)
			(xy 360.752763 -337.106578) (xy 360.800207 -337.073806) (xy 360.852044 -337.048552) (xy 360.907092 -337.03139)
			(xy 360.964097 -337.022713) (xy 360.992928 -337.022186) (xy 361.02018 -337.022652) (xy 361.074128 -337.030412)
			(xy 361.126423 -337.04577) (xy 361.175999 -337.068414) (xy 361.221849 -337.097883) (xy 361.263039 -337.133576)
			(xy 361.29873 -337.174768) (xy 361.328196 -337.22062) (xy 361.350837 -337.270198) (xy 361.366193 -337.322494)
			(xy 361.37395 -337.376442) (xy 361.374436 -337.403694) (xy 361.373909 -337.433599) (xy 361.364591 -337.492678)
			(xy 361.355894 -337.521296) (xy 361.351931 -337.535223) (xy 361.351008 -337.564145) (xy 361.358258 -337.592159)
			(xy 361.373097 -337.617001) (xy 361.394325 -337.636666) (xy 361.420227 -337.649564) (xy 361.43438 -337.652614)
			(xy 361.460445 -337.657823) (xy 361.510948 -337.674387) (xy 361.558661 -337.697804) (xy 361.60266 -337.727621)
			(xy 361.642092 -337.763259) (xy 361.676192 -337.804028) (xy 361.704301 -337.849138) (xy 361.725872 -337.897714)
			(xy 361.740488 -337.948815) (xy 361.747865 -338.001451) (xy 361.748324 -338.028026) (xy 361.747838 -338.055277)
			(xy 361.740082 -338.109225) (xy 361.724727 -338.16152) (xy 361.702085 -338.211097) (xy 361.684578 -338.238338)
			(xy 367.06048 -338.238338) (xy 367.061071 -338.208651) (xy 367.070263 -338.149994) (xy 367.088432 -338.09347)
			(xy 367.115138 -338.040442) (xy 367.149738 -337.992192) (xy 367.191394 -337.949885) (xy 367.214912 -337.93176)
			(xy 367.225493 -337.923304) (xy 367.242199 -337.901998) (xy 367.252719 -337.877051) (xy 367.256312 -337.850216)
			(xy 367.252727 -337.82338) (xy 367.242215 -337.798429) (xy 367.225516 -337.777118) (xy 367.214912 -337.768692)
			(xy 367.1914 -337.750558) (xy 367.149739 -337.708254) (xy 367.115135 -337.660007) (xy 367.088422 -337.606981)
			(xy 367.070246 -337.550458) (xy 367.061046 -337.491801) (xy 367.06048 -337.462114) (xy 367.060966 -337.434863)
			(xy 367.068722 -337.380915) (xy 367.084077 -337.32862) (xy 367.106719 -337.279043) (xy 367.136185 -337.233193)
			(xy 367.171876 -337.192002) (xy 367.213067 -337.156311) (xy 367.258917 -337.126845) (xy 367.308494 -337.104203)
			(xy 367.360789 -337.088848) (xy 367.414737 -337.081092) (xy 367.469239 -337.081092) (xy 367.523187 -337.088848)
			(xy 367.575482 -337.104203) (xy 367.625059 -337.126845) (xy 367.670909 -337.156311) (xy 367.7121 -337.192002)
			(xy 367.747791 -337.233193) (xy 367.777257 -337.279043) (xy 367.799899 -337.32862) (xy 367.815254 -337.380915)
			(xy 367.82301 -337.434863) (xy 367.823496 -337.462114) (xy 367.822953 -337.491802) (xy 367.813752 -337.550462)
			(xy 367.795574 -337.606988) (xy 367.768859 -337.660016) (xy 367.756782 -337.676853) (xy 368.076944 -337.676853)
			(xy 368.076944 -337.622347) (xy 368.084701 -337.568395) (xy 368.100057 -337.516097) (xy 368.122699 -337.466516)
			(xy 368.152167 -337.420662) (xy 368.18786 -337.379469) (xy 368.229053 -337.343774) (xy 368.274906 -337.314305)
			(xy 368.324486 -337.291661) (xy 368.376784 -337.276303) (xy 368.430735 -337.268545) (xy 368.457988 -337.268058)
			(xy 368.483223 -337.268466) (xy 368.533256 -337.275082) (xy 368.581977 -337.288252) (xy 368.628529 -337.307745)
			(xy 368.65052 -337.320128) (xy 368.66348 -337.327177) (xy 368.692119 -337.334213) (xy 368.721575 -337.332769)
			(xy 368.749388 -337.322964) (xy 368.773238 -337.305619) (xy 368.791135 -337.282179) (xy 368.796824 -337.268566)
			(xy 368.807549 -337.241802) (xy 368.835835 -337.191563) (xy 368.871361 -337.146155) (xy 368.913319 -337.106613)
			(xy 368.960752 -337.073838) (xy 369.012578 -337.048578) (xy 369.067617 -337.031408) (xy 369.124613 -337.022719)
			(xy 369.15344 -337.022186) (xy 369.180692 -337.022641) (xy 369.23464 -337.030402) (xy 369.286935 -337.045762)
			(xy 369.336512 -337.068408) (xy 369.382362 -337.097878) (xy 369.423552 -337.133572) (xy 369.459243 -337.174765)
			(xy 369.488709 -337.220617) (xy 369.51135 -337.270196) (xy 369.526705 -337.322493) (xy 369.534462 -337.376442)
			(xy 369.534948 -337.403694) (xy 369.534421 -337.433599) (xy 369.526679 -337.482688) (xy 371.647212 -337.482688)
			(xy 371.647734 -337.455115) (xy 371.655675 -337.400545) (xy 371.671388 -337.347686) (xy 371.694547 -337.29764)
			(xy 371.72467 -337.251449) (xy 371.761129 -337.210075) (xy 371.781832 -337.191858) (xy 371.792738 -337.18197)
			(xy 371.808804 -337.157315) (xy 371.817183 -337.129106) (xy 371.817181 -337.099679) (xy 371.808798 -337.071471)
			(xy 371.792728 -337.046819) (xy 371.781832 -337.036918) (xy 371.761133 -337.018694) (xy 371.72466 -336.977329)
			(xy 371.694526 -336.931142) (xy 371.671358 -336.881096) (xy 371.655639 -336.828235) (xy 371.647698 -336.773662)
			(xy 371.647212 -336.746088) (xy 371.647644 -336.718834) (xy 371.655403 -336.664881) (xy 371.670761 -336.612581)
			(xy 371.693407 -336.562999) (xy 371.722878 -336.517145) (xy 371.758575 -336.475952) (xy 371.799771 -336.440259)
			(xy 371.845628 -336.410791) (xy 371.895211 -336.38815) (xy 371.947512 -336.372796) (xy 372.001466 -336.365041)
			(xy 372.02872 -336.36458) (xy 372.040882 -336.364673) (xy 372.065157 -336.366196) (xy 372.077234 -336.367628)
			(xy 372.090996 -336.368863) (xy 372.118323 -336.364892) (xy 372.143589 -336.353747) (xy 372.164947 -336.336242)
			(xy 372.180837 -336.313657) (xy 372.190098 -336.287642) (xy 372.191534 -336.273902) (xy 372.194089 -336.24537)
			(xy 372.206571 -336.189465) (xy 372.227274 -336.136055) (xy 372.255732 -336.086344) (xy 372.291306 -336.041447)
			(xy 372.333195 -336.002377) (xy 372.380457 -335.970012) (xy 372.432028 -335.945079) (xy 372.486747 -335.92814)
			(xy 372.543385 -335.919577) (xy 372.572026 -335.919064) (xy 372.590045 -335.919286) (xy 372.62592 -335.922719)
			(xy 372.643654 -335.925922) (xy 372.658866 -335.928241) (xy 372.689419 -335.924725) (xy 372.71754 -335.91227)
			(xy 372.740676 -335.892007) (xy 372.756729 -335.865774) (xy 372.761002 -335.850992) (xy 372.768437 -335.823959)
			(xy 372.790061 -335.772233) (xy 372.819019 -335.724227) (xy 372.854689 -335.680974) (xy 372.896304 -335.643406)
			(xy 372.942967 -335.61233) (xy 372.993675 -335.588415) (xy 373.047335 -335.572177) (xy 373.102794 -335.563964)
			(xy 373.130826 -335.563464) (xy 373.158077 -335.563954) (xy 373.212023 -335.571713) (xy 373.264316 -335.58707)
			(xy 373.313891 -335.609712) (xy 373.35974 -335.639178) (xy 373.400929 -335.674869) (xy 373.43662 -335.716058)
			(xy 373.466087 -335.761907) (xy 373.488729 -335.811482) (xy 373.504087 -335.863775) (xy 373.511846 -335.917721)
			(xy 373.512334 -335.944972) (xy 373.511872 -335.972547) (xy 373.503922 -336.027121) (xy 373.488198 -336.079982)
			(xy 373.465027 -336.130028) (xy 373.434893 -336.176218) (xy 373.398423 -336.217587) (xy 373.377714 -336.235802)
			(xy 373.366844 -336.245729) (xy 373.350769 -336.27037) (xy 373.342381 -336.298571) (xy 373.342376 -336.327993)
			(xy 373.350753 -336.356197) (xy 373.36682 -336.380844) (xy 373.377714 -336.390742) (xy 373.398391 -336.408989)
			(xy 373.434853 -336.450357) (xy 373.464979 -336.496543) (xy 373.488141 -336.546586) (xy 373.503857 -336.599442)
			(xy 373.511799 -336.65401) (xy 373.511802 -336.709154) (xy 373.503865 -336.763723) (xy 373.488154 -336.81658)
			(xy 373.464997 -336.866625) (xy 373.434875 -336.912815) (xy 373.398417 -336.954186) (xy 373.377714 -336.972402)
			(xy 373.366844 -336.982329) (xy 373.350769 -337.00697) (xy 373.342381 -337.035171) (xy 373.342376 -337.064593)
			(xy 373.350753 -337.092797) (xy 373.36682 -337.117444) (xy 373.377714 -337.127342) (xy 373.398403 -337.145577)
			(xy 373.434875 -337.186941) (xy 373.465009 -337.233126) (xy 373.488179 -337.283169) (xy 373.5039 -337.336028)
			(xy 373.511845 -337.390599) (xy 373.512334 -337.418172) (xy 373.511819 -337.445423) (xy 373.504066 -337.499371)
			(xy 373.488715 -337.551666) (xy 373.466078 -337.601244) (xy 373.436615 -337.647096) (xy 373.400927 -337.688289)
			(xy 373.35974 -337.723983) (xy 373.313892 -337.753452) (xy 373.264317 -337.776096) (xy 373.212024 -337.791455)
			(xy 373.158077 -337.799215) (xy 373.130826 -337.79968) (xy 373.102971 -337.799148) (xy 373.047855 -337.791028)
			(xy 372.994504 -337.774985) (xy 372.944051 -337.75136) (xy 372.897566 -337.720654) (xy 372.856036 -337.683519)
			(xy 372.820343 -337.640744) (xy 372.791244 -337.593237) (xy 372.769358 -337.542005) (xy 372.761764 -337.5152)
			(xy 372.757496 -337.501082) (xy 372.742104 -337.475937) (xy 372.720184 -337.456222) (xy 372.693554 -337.443572)
			(xy 372.664424 -337.439035) (xy 372.64975 -337.440524) (xy 372.636734 -337.442196) (xy 372.610549 -337.443974)
			(xy 372.597426 -337.44408) (xy 372.579795 -337.443842) (xy 372.544687 -337.440537) (xy 372.527322 -337.437476)
			(xy 372.513546 -337.435268) (xy 372.485761 -337.437711) (xy 372.459678 -337.447592) (xy 372.437249 -337.464172)
			(xy 372.420152 -337.48621) (xy 372.409666 -337.512056) (xy 372.407688 -337.525868) (xy 372.404033 -337.553442)
			(xy 372.389802 -337.607212) (xy 372.36791 -337.658344) (xy 372.338821 -337.705752) (xy 372.303152 -337.748431)
			(xy 372.261661 -337.785475) (xy 372.215229 -337.816097) (xy 372.16484 -337.839648) (xy 372.111563 -337.855628)
			(xy 372.056531 -337.863698) (xy 372.02872 -337.864196) (xy 372.001467 -337.863726) (xy 371.947516 -337.855971)
			(xy 371.895217 -337.840617) (xy 371.845636 -337.817976) (xy 371.799783 -337.788509) (xy 371.758589 -337.752816)
			(xy 371.722896 -337.711624) (xy 371.693428 -337.665771) (xy 371.670785 -337.61619) (xy 371.65543 -337.563892)
			(xy 371.647675 -337.509941) (xy 371.647212 -337.482688) (xy 369.526679 -337.482688) (xy 369.525103 -337.492678)
			(xy 369.516406 -337.521296) (xy 369.512434 -337.535221) (xy 369.51151 -337.564145) (xy 369.518761 -337.59216)
			(xy 369.533602 -337.617004) (xy 369.554832 -337.636669) (xy 369.580738 -337.649566) (xy 369.594892 -337.652614)
			(xy 369.620959 -337.657814) (xy 369.671462 -337.67438) (xy 369.719175 -337.697798) (xy 369.763174 -337.727617)
			(xy 369.802605 -337.763256) (xy 369.836705 -337.804026) (xy 369.864813 -337.849136) (xy 369.886384 -337.897713)
			(xy 369.901 -337.948814) (xy 369.908377 -338.001451) (xy 369.908836 -338.028026) (xy 369.90835 -338.055277)
			(xy 369.900594 -338.109225) (xy 369.885239 -338.16152) (xy 369.862597 -338.211097) (xy 369.833131 -338.256947)
			(xy 369.79744 -338.298138) (xy 369.756249 -338.333829) (xy 369.710399 -338.363295) (xy 369.660822 -338.385937)
			(xy 369.608527 -338.401292) (xy 369.554579 -338.409048) (xy 369.500077 -338.409048) (xy 369.446129 -338.401292)
			(xy 369.393834 -338.385937) (xy 369.344257 -338.363295) (xy 369.298407 -338.333829) (xy 369.257216 -338.298138)
			(xy 369.221525 -338.256947) (xy 369.192059 -338.211097) (xy 369.169417 -338.16152) (xy 369.154062 -338.109225)
			(xy 369.146306 -338.055277) (xy 369.14582 -338.028026) (xy 369.146349 -337.998121) (xy 369.155665 -337.939042)
			(xy 369.164362 -337.910424) (xy 369.168449 -337.896528) (xy 369.169356 -337.867586) (xy 369.162084 -337.839558)
			(xy 369.147221 -337.814708) (xy 369.125967 -337.795042) (xy 369.10004 -337.78215) (xy 369.085876 -337.779106)
			(xy 369.053035 -337.77253) (xy 368.990184 -337.749402) (xy 368.960908 -337.733132) (xy 368.947922 -337.726137)
			(xy 368.919294 -337.719101) (xy 368.889849 -337.720539) (xy 368.862044 -337.730333) (xy 368.838197 -337.747665)
			(xy 368.820298 -337.771089) (xy 368.814604 -337.784694) (xy 368.803918 -337.811475) (xy 368.77563 -337.861718)
			(xy 368.740099 -337.907128) (xy 368.698136 -337.946671) (xy 368.650697 -337.979445) (xy 368.598864 -338.004702)
			(xy 368.543819 -338.021866) (xy 368.486817 -338.030546) (xy 368.457988 -338.031074) (xy 368.430735 -338.030655)
			(xy 368.376784 -338.022897) (xy 368.324486 -338.007539) (xy 368.274906 -337.984895) (xy 368.229053 -337.955426)
			(xy 368.18786 -337.919731) (xy 368.152167 -337.878538) (xy 368.122699 -337.832684) (xy 368.100057 -337.783103)
			(xy 368.084701 -337.730805) (xy 368.076944 -337.676853) (xy 367.756782 -337.676853) (xy 367.734251 -337.708264)
			(xy 367.692586 -337.750569) (xy 367.669064 -337.768692) (xy 367.658433 -337.77709) (xy 367.641731 -337.79841)
			(xy 367.631218 -337.82337) (xy 367.627632 -337.850216) (xy 367.631226 -337.87706) (xy 367.641747 -337.902017)
			(xy 367.658456 -337.923332) (xy 367.669064 -337.93176) (xy 367.692595 -337.94987) (xy 367.734256 -337.992178)
			(xy 367.76886 -338.04043) (xy 367.795569 -338.09346) (xy 367.81374 -338.149989) (xy 367.822934 -338.208649)
			(xy 367.823496 -338.238338) (xy 367.82301 -338.265589) (xy 367.815254 -338.319537) (xy 367.799899 -338.371832)
			(xy 367.777257 -338.421409) (xy 367.747791 -338.467259) (xy 367.7121 -338.50845) (xy 367.670909 -338.544141)
			(xy 367.625059 -338.573607) (xy 367.582767 -338.592922) (xy 373.623332 -338.592922) (xy 373.623824 -338.564881)
			(xy 373.632024 -338.509403) (xy 373.648249 -338.45572) (xy 373.672151 -338.404988) (xy 373.703217 -338.358297)
			(xy 373.72163 -338.337144) (xy 373.731299 -338.325722) (xy 373.74407 -338.298671) (xy 373.748448 -338.269079)
			(xy 373.744057 -338.239489) (xy 373.731275 -338.212444) (xy 373.72163 -338.201) (xy 373.703177 -338.179876)
			(xy 373.67209 -338.133191) (xy 373.648181 -338.082453) (xy 373.631968 -338.028758) (xy 373.623802 -337.973267)
			(xy 373.623332 -337.945222) (xy 373.623818 -337.917971) (xy 373.631574 -337.864023) (xy 373.646929 -337.811728)
			(xy 373.669571 -337.762151) (xy 373.699037 -337.716301) (xy 373.734728 -337.67511) (xy 373.775919 -337.639419)
			(xy 373.821769 -337.609953) (xy 373.871346 -337.587311) (xy 373.923641 -337.571956) (xy 373.977589 -337.5642)
			(xy 374.032091 -337.5642) (xy 374.086039 -337.571956) (xy 374.138334 -337.587311) (xy 374.187911 -337.609953)
			(xy 374.233761 -337.639419) (xy 374.274952 -337.67511) (xy 374.310643 -337.716301) (xy 374.340109 -337.762151)
			(xy 374.362751 -337.811728) (xy 374.378106 -337.864023) (xy 374.385862 -337.917971) (xy 374.386348 -337.945222)
			(xy 374.385861 -337.973263) (xy 374.377658 -338.02874) (xy 374.36143 -338.082422) (xy 374.337527 -338.133154)
			(xy 374.306462 -338.179846) (xy 374.28805 -338.201) (xy 374.27843 -338.212462) (xy 374.265642 -338.239497)
			(xy 374.261249 -338.269079) (xy 374.26563 -338.298663) (xy 374.278406 -338.325704) (xy 374.28805 -338.337144)
			(xy 374.306473 -338.358293) (xy 374.337565 -338.404971) (xy 374.36148 -338.455703) (xy 374.377699 -338.509392)
			(xy 374.385874 -338.564879) (xy 374.386348 -338.592922) (xy 374.385862 -338.620173) (xy 374.378106 -338.674121)
			(xy 374.362751 -338.726416) (xy 374.340109 -338.775993) (xy 374.310643 -338.821843) (xy 374.274952 -338.863034)
			(xy 374.233761 -338.898725) (xy 374.187911 -338.928191) (xy 374.138334 -338.950833) (xy 374.086039 -338.966188)
			(xy 374.032091 -338.973944) (xy 373.977589 -338.973944) (xy 373.923641 -338.966188) (xy 373.871346 -338.950833)
			(xy 373.821769 -338.928191) (xy 373.775919 -338.898725) (xy 373.734728 -338.863034) (xy 373.699037 -338.821843)
			(xy 373.669571 -338.775993) (xy 373.646929 -338.726416) (xy 373.631574 -338.674121) (xy 373.623818 -338.620173)
			(xy 373.623332 -338.592922) (xy 367.582767 -338.592922) (xy 367.575482 -338.596249) (xy 367.523187 -338.611604)
			(xy 367.469239 -338.61936) (xy 367.414737 -338.61936) (xy 367.360789 -338.611604) (xy 367.308494 -338.596249)
			(xy 367.258917 -338.573607) (xy 367.213067 -338.544141) (xy 367.171876 -338.50845) (xy 367.136185 -338.467259)
			(xy 367.106719 -338.421409) (xy 367.084077 -338.371832) (xy 367.068722 -338.319537) (xy 367.060966 -338.265589)
			(xy 367.06048 -338.238338) (xy 361.684578 -338.238338) (xy 361.672619 -338.256947) (xy 361.636928 -338.298138)
			(xy 361.595737 -338.333829) (xy 361.549887 -338.363295) (xy 361.50031 -338.385937) (xy 361.448015 -338.401292)
			(xy 361.394067 -338.409048) (xy 361.339565 -338.409048) (xy 361.285617 -338.401292) (xy 361.233322 -338.385937)
			(xy 361.183745 -338.363295) (xy 361.137895 -338.333829) (xy 361.096704 -338.298138) (xy 361.061013 -338.256947)
			(xy 361.031547 -338.211097) (xy 361.008905 -338.16152) (xy 360.99355 -338.109225) (xy 360.985794 -338.055277)
			(xy 360.985308 -338.028026) (xy 360.985837 -337.998121) (xy 360.995154 -337.939042) (xy 361.00385 -337.910424)
			(xy 361.007868 -337.896513) (xy 361.008772 -337.867586) (xy 361.001506 -337.839571) (xy 360.986658 -337.814728)
			(xy 360.965424 -337.795062) (xy 360.939518 -337.782159) (xy 360.925364 -337.779106) (xy 360.892528 -337.772509)
			(xy 360.829674 -337.749396) (xy 360.800396 -337.733132) (xy 360.787417 -337.726123) (xy 360.758786 -337.719088)
			(xy 360.729339 -337.720529) (xy 360.701532 -337.730326) (xy 360.677684 -337.74766) (xy 360.659785 -337.771087)
			(xy 360.654092 -337.784694) (xy 360.643416 -337.811479) (xy 360.615127 -337.861723) (xy 360.579595 -337.907133)
			(xy 360.53763 -337.946676) (xy 360.49019 -337.979449) (xy 360.438355 -338.004705) (xy 360.383309 -338.021868)
			(xy 360.326306 -338.030547) (xy 360.297476 -338.031074) (xy 360.270223 -338.030654) (xy 360.216274 -338.022895)
			(xy 360.163977 -338.007536) (xy 360.114398 -337.984891) (xy 360.068547 -337.955422) (xy 360.027356 -337.919727)
			(xy 359.991664 -337.878534) (xy 359.962197 -337.832681) (xy 359.939556 -337.783101) (xy 359.9242 -337.730803)
			(xy 359.916444 -337.676853) (xy 359.596273 -337.676853) (xy 359.57374 -337.708265) (xy 359.532074 -337.750569)
			(xy 359.508552 -337.768692) (xy 359.497922 -337.77709) (xy 359.481222 -337.798411) (xy 359.47071 -337.823371)
			(xy 359.467125 -337.850216) (xy 359.470718 -337.877059) (xy 359.481238 -337.902016) (xy 359.497945 -337.923332)
			(xy 359.508552 -337.93176) (xy 359.532102 -337.949846) (xy 359.573758 -337.992162) (xy 359.608356 -338.04042)
			(xy 359.635062 -338.093454) (xy 359.65323 -338.149985) (xy 359.662422 -338.208649) (xy 359.662984 -338.238338)
			(xy 359.662498 -338.265589) (xy 359.654742 -338.319537) (xy 359.639387 -338.371832) (xy 359.616745 -338.421409)
			(xy 359.587279 -338.467259) (xy 359.551588 -338.50845) (xy 359.510397 -338.544141) (xy 359.464547 -338.573607)
			(xy 359.41497 -338.596249) (xy 359.362675 -338.611604) (xy 359.308727 -338.61936) (xy 359.254225 -338.61936)
			(xy 359.200277 -338.611604) (xy 359.147982 -338.596249) (xy 359.098405 -338.573607) (xy 359.052555 -338.544141)
			(xy 359.011364 -338.50845) (xy 358.975673 -338.467259) (xy 358.946207 -338.421409) (xy 358.923565 -338.371832)
			(xy 358.90821 -338.319537) (xy 358.900454 -338.265589) (xy 358.899968 -338.238338) (xy 353.524066 -338.238338)
			(xy 353.512107 -338.256947) (xy 353.476416 -338.298138) (xy 353.435225 -338.333829) (xy 353.389375 -338.363295)
			(xy 353.339798 -338.385937) (xy 353.287503 -338.401292) (xy 353.233555 -338.409048) (xy 353.179053 -338.409048)
			(xy 353.125105 -338.401292) (xy 353.07281 -338.385937) (xy 353.023233 -338.363295) (xy 352.977383 -338.333829)
			(xy 352.936192 -338.298138) (xy 352.900501 -338.256947) (xy 352.871035 -338.211097) (xy 352.848393 -338.16152)
			(xy 352.833038 -338.109225) (xy 352.825282 -338.055277) (xy 352.824796 -338.028026) (xy 352.825326 -337.998121)
			(xy 352.834642 -337.939042) (xy 352.843338 -337.910424) (xy 352.847365 -337.896515) (xy 352.848269 -337.867586)
			(xy 352.841003 -337.839569) (xy 352.826153 -337.814726) (xy 352.804916 -337.79506) (xy 352.779007 -337.782158)
			(xy 352.764852 -337.779106) (xy 352.732015 -337.772512) (xy 352.669162 -337.749397) (xy 352.639884 -337.733132)
			(xy 352.626912 -337.726109) (xy 352.598279 -337.719076) (xy 352.568829 -337.72052) (xy 352.541021 -337.730319)
			(xy 352.517172 -337.747656) (xy 352.499273 -337.771086) (xy 352.49358 -337.784694) (xy 352.482914 -337.811483)
			(xy 352.454624 -337.861727) (xy 352.41909 -337.907138) (xy 352.377124 -337.946681) (xy 352.329682 -337.979454)
			(xy 352.277846 -338.004709) (xy 352.222799 -338.021871) (xy 352.165794 -338.030548) (xy 352.136964 -338.031074)
			(xy 352.109712 -338.030654) (xy 352.055763 -338.022892) (xy 352.003468 -338.007533) (xy 351.953891 -337.984887)
			(xy 351.908041 -337.955418) (xy 351.866852 -337.919723) (xy 351.831161 -337.87853) (xy 351.801695 -337.832677)
			(xy 351.779055 -337.783098) (xy 351.7637 -337.730801) (xy 351.755944 -337.676852) (xy 351.435765 -337.676852)
			(xy 351.41323 -337.708266) (xy 351.371563 -337.750569) (xy 351.34804 -337.768692) (xy 351.337403 -337.777085)
			(xy 351.320688 -337.798403) (xy 351.310166 -337.823365) (xy 351.306577 -337.850216) (xy 351.310174 -337.877065)
			(xy 351.320704 -337.902024) (xy 351.337425 -337.923336) (xy 351.34804 -337.93176) (xy 351.371587 -337.94985)
			(xy 351.413244 -337.992164) (xy 351.447843 -338.040421) (xy 351.474549 -338.093455) (xy 351.492718 -338.149986)
			(xy 351.50191 -338.208649) (xy 351.502472 -338.238338) (xy 351.501986 -338.265589) (xy 351.49423 -338.319537)
			(xy 351.478875 -338.371832) (xy 351.456233 -338.421409) (xy 351.426767 -338.467259) (xy 351.391076 -338.50845)
			(xy 351.349885 -338.544141) (xy 351.304035 -338.573607) (xy 351.254458 -338.596249) (xy 351.202163 -338.611604)
			(xy 351.148215 -338.61936) (xy 351.093713 -338.61936) (xy 351.039765 -338.611604) (xy 350.98747 -338.596249)
			(xy 350.937893 -338.573607) (xy 350.892043 -338.544141) (xy 350.850852 -338.50845) (xy 350.815161 -338.467259)
			(xy 350.785695 -338.421409) (xy 350.763053 -338.371832) (xy 350.747698 -338.319537) (xy 350.739942 -338.265589)
			(xy 350.739456 -338.238338) (xy 345.363554 -338.238338) (xy 345.351595 -338.256947) (xy 345.315904 -338.298138)
			(xy 345.274713 -338.333829) (xy 345.228863 -338.363295) (xy 345.179286 -338.385937) (xy 345.126991 -338.401292)
			(xy 345.073043 -338.409048) (xy 345.018541 -338.409048) (xy 344.964593 -338.401292) (xy 344.912298 -338.385937)
			(xy 344.862721 -338.363295) (xy 344.816871 -338.333829) (xy 344.77568 -338.298138) (xy 344.739989 -338.256947)
			(xy 344.710523 -338.211097) (xy 344.687881 -338.16152) (xy 344.672526 -338.109225) (xy 344.66477 -338.055277)
			(xy 344.664284 -338.028026) (xy 344.664815 -337.998121) (xy 344.67413 -337.939042) (xy 344.682826 -337.910424)
			(xy 344.686863 -337.896517) (xy 344.687767 -337.867586) (xy 344.6805 -337.839567) (xy 344.665647 -337.814723)
			(xy 344.644409 -337.795057) (xy 344.618497 -337.782157) (xy 344.60434 -337.779106) (xy 344.571503 -337.772515)
			(xy 344.508649 -337.749398) (xy 344.479372 -337.733132) (xy 344.466407 -337.726095) (xy 344.437771 -337.719064)
			(xy 344.40832 -337.72051) (xy 344.38051 -337.730312) (xy 344.35666 -337.747652) (xy 344.338761 -337.771085)
			(xy 344.333068 -337.784694) (xy 344.322329 -337.811452) (xy 344.294047 -337.861692) (xy 344.258523 -337.907102)
			(xy 344.216568 -337.946646) (xy 344.169137 -337.979422) (xy 344.117312 -338.004683) (xy 344.062274 -338.021853)
			(xy 344.005279 -338.030541) (xy 343.976452 -338.031074) (xy 343.949201 -338.030653) (xy 343.895253 -338.02289)
			(xy 343.84296 -338.007529) (xy 343.793384 -337.984884) (xy 343.747536 -337.955413) (xy 343.706347 -337.919719)
			(xy 343.670658 -337.878526) (xy 343.641193 -337.832674) (xy 343.618554 -337.783095) (xy 343.6032 -337.7308)
			(xy 343.595444 -337.676851) (xy 343.275257 -337.676851) (xy 343.25272 -337.708267) (xy 343.211052 -337.75057)
			(xy 343.187528 -337.768692) (xy 343.176892 -337.777086) (xy 343.160179 -337.798404) (xy 343.149658 -337.823366)
			(xy 343.14607 -337.850216) (xy 343.149666 -337.877064) (xy 343.160195 -337.902023) (xy 343.176914 -337.923336)
			(xy 343.187528 -337.93176) (xy 343.211073 -337.949853) (xy 343.25273 -337.992167) (xy 343.28733 -338.040423)
			(xy 343.314037 -338.093456) (xy 343.332205 -338.149986) (xy 343.341398 -338.208649) (xy 343.34196 -338.238338)
			(xy 343.341474 -338.265589) (xy 343.333718 -338.319537) (xy 343.318363 -338.371832) (xy 343.295721 -338.421409)
			(xy 343.266255 -338.467259) (xy 343.230564 -338.50845) (xy 343.189373 -338.544141) (xy 343.143523 -338.573607)
			(xy 343.093946 -338.596249) (xy 343.041651 -338.611604) (xy 342.987703 -338.61936) (xy 342.933201 -338.61936)
			(xy 342.879253 -338.611604) (xy 342.826958 -338.596249) (xy 342.777381 -338.573607) (xy 342.731531 -338.544141)
			(xy 342.69034 -338.50845) (xy 342.654649 -338.467259) (xy 342.625183 -338.421409) (xy 342.602541 -338.371832)
			(xy 342.587186 -338.319537) (xy 342.57943 -338.265589) (xy 342.578944 -338.238338) (xy 333.469256 -338.238338)
			(xy 333.468416 -338.240168) (xy 333.464238 -338.269079) (xy 333.468404 -338.297992) (xy 333.480574 -338.324547)
			(xy 333.489808 -338.335874) (xy 333.50745 -338.356804) (xy 333.537161 -338.402778) (xy 333.559996 -338.452526)
			(xy 333.575487 -338.505027) (xy 333.583314 -338.559203) (xy 333.583788 -338.586572) (xy 333.583302 -338.613823)
			(xy 333.575546 -338.667771) (xy 333.560191 -338.720066) (xy 333.537549 -338.769643) (xy 333.508083 -338.815493)
			(xy 333.472392 -338.856684) (xy 333.431201 -338.892375) (xy 333.385351 -338.921841) (xy 333.335774 -338.944483)
			(xy 333.283479 -338.959838) (xy 333.229531 -338.967594) (xy 333.175029 -338.967594) (xy 333.121081 -338.959838)
			(xy 333.068786 -338.944483) (xy 333.019209 -338.921841) (xy 332.973359 -338.892375) (xy 332.932168 -338.856684)
			(xy 332.896477 -338.815493) (xy 332.867011 -338.769643) (xy 332.844369 -338.720066) (xy 332.829014 -338.667771)
			(xy 332.821258 -338.613823) (xy 332.820772 -338.586572) (xy 317.257176 -338.586572) (xy 316.854548 -338.9892)
			(xy 337.069421 -338.9892) (xy 337.073589 -338.933585) (xy 337.085998 -338.879212) (xy 337.106372 -338.827295)
			(xy 337.134256 -338.778995) (xy 337.169027 -338.73539) (xy 337.209907 -338.697453) (xy 337.255985 -338.666033)
			(xy 337.306231 -338.64183) (xy 337.359523 -338.625386) (xy 337.41467 -338.617068) (xy 337.442556 -338.616544)
			(xy 337.469888 -338.617013) (xy 337.523968 -338.624982) (xy 337.576303 -338.64077) (xy 337.625767 -338.664039)
			(xy 337.6713 -338.694287) (xy 337.711922 -338.730866) (xy 337.746761 -338.772989) (xy 337.761326 -338.796122)
			(xy 337.769241 -338.808351) (xy 337.790716 -338.82802) (xy 337.816871 -338.840823) (xy 337.845578 -338.845717)
			(xy 337.874498 -338.842304) (xy 337.888072 -338.837016) (xy 337.911288 -338.827544) (xy 337.959618 -338.814186)
			(xy 338.009305 -338.807451) (xy 338.034376 -338.807044) (xy 338.059446 -338.807454) (xy 338.109129 -338.814209)
			(xy 338.157463 -338.827547) (xy 338.18068 -338.837016) (xy 338.194253 -338.842275) (xy 338.223156 -338.845636)
			(xy 338.251835 -338.840723) (xy 338.27797 -338.827931) (xy 338.299445 -338.808297) (xy 338.307426 -338.796122)
			(xy 338.321995 -338.772991) (xy 338.356838 -338.73087) (xy 338.397461 -338.694291) (xy 338.442992 -338.66404)
			(xy 338.492454 -338.640764) (xy 338.544785 -338.624964) (xy 338.598864 -338.616978) (xy 338.653528 -338.616978)
			(xy 338.707607 -338.624964) (xy 338.759938 -338.640764) (xy 338.8094 -338.66404) (xy 338.854931 -338.694291)
			(xy 338.895554 -338.73087) (xy 338.930397 -338.772991) (xy 338.944966 -338.796122) (xy 338.952843 -338.808379)
			(xy 338.974328 -338.828047) (xy 339.000494 -338.840846) (xy 339.029209 -338.845733) (xy 339.058136 -338.84231)
			(xy 339.071712 -338.837016) (xy 339.094924 -338.827531) (xy 339.143256 -338.814178) (xy 339.192945 -338.807448)
			(xy 339.218016 -338.807044) (xy 339.245655 -338.807541) (xy 339.300322 -338.815736) (xy 339.35318 -338.831914)
			(xy 339.40307 -338.85572) (xy 339.448896 -338.886633) (xy 339.489656 -338.923974) (xy 339.524454 -338.966925)
			(xy 339.552528 -339.014544) (xy 339.573262 -339.065786) (xy 339.58022 -339.09254) (xy 339.583825 -339.105648)
			(xy 339.596965 -339.129436) (xy 339.615914 -339.148918) (xy 339.639329 -339.162712) (xy 339.665554 -339.169842)
			(xy 339.69273 -339.169804) (xy 339.718934 -339.1626) (xy 339.730842 -339.15604) (xy 339.752985 -339.143402)
			(xy 339.799938 -339.123527) (xy 339.849122 -339.110092) (xy 339.899659 -339.103338) (xy 339.925152 -339.102954)
			(xy 339.93201 -339.102954) (xy 339.947094 -339.102679) (xy 339.976082 -339.094373) (xy 340.001392 -339.07798)
			(xy 340.020827 -339.054924) (xy 340.032701 -339.027205) (xy 340.03488 -339.012276) (xy 340.038284 -338.984522)
			(xy 340.052283 -338.930385) (xy 340.07403 -338.878869) (xy 340.103059 -338.831077) (xy 340.13875 -338.788031)
			(xy 340.180338 -338.750652) (xy 340.226935 -338.71974) (xy 340.277543 -338.695956) (xy 340.331079 -338.67981)
			(xy 340.386397 -338.671646) (xy 340.414356 -338.671154) (xy 340.441606 -338.671696) (xy 340.495552 -338.679446)
			(xy 340.547846 -338.694795) (xy 340.597424 -338.717429) (xy 340.643275 -338.746889) (xy 340.684467 -338.782575)
			(xy 340.720162 -338.823759) (xy 340.749631 -338.869604) (xy 340.772277 -338.919177) (xy 340.787636 -338.971468)
			(xy 340.790187 -338.9892) (xy 377.871895 -338.9892) (xy 377.876064 -338.933575) (xy 377.888477 -338.879193)
			(xy 377.908856 -338.827269) (xy 377.936747 -338.778961) (xy 377.971527 -338.735351) (xy 378.012418 -338.697411)
			(xy 378.058507 -338.66599) (xy 378.108764 -338.641789) (xy 378.162068 -338.625349) (xy 378.217226 -338.617038)
			(xy 378.245116 -338.616544) (xy 378.27245 -338.616965) (xy 378.326532 -338.624943) (xy 378.378868 -338.64074)
			(xy 378.428332 -338.664016) (xy 378.473864 -338.694271) (xy 378.514485 -338.730857) (xy 378.549322 -338.772986)
			(xy 378.563886 -338.796122) (xy 378.571839 -338.808324) (xy 378.593304 -338.827993) (xy 378.619449 -338.840799)
			(xy 378.648146 -338.8457) (xy 378.677059 -338.842298) (xy 378.690632 -338.837016) (xy 378.713841 -338.827525)
			(xy 378.762174 -338.814174) (xy 378.811864 -338.807447) (xy 378.836936 -338.807044) (xy 378.862005 -338.807467)
			(xy 378.911688 -338.814217) (xy 378.960023 -338.82755) (xy 378.98324 -338.837016) (xy 378.996827 -338.842232)
			(xy 379.025723 -338.845603) (xy 379.054397 -338.840699) (xy 379.08053 -338.827917) (xy 379.102005 -338.808293)
			(xy 379.109986 -338.796122) (xy 379.124555 -338.772991) (xy 379.159398 -338.73087) (xy 379.200021 -338.694291)
			(xy 379.245552 -338.66404) (xy 379.295014 -338.640764) (xy 379.347345 -338.624964) (xy 379.401424 -338.616978)
			(xy 379.456088 -338.616978) (xy 379.510167 -338.624964) (xy 379.562498 -338.640764) (xy 379.61196 -338.66404)
			(xy 379.657491 -338.694291) (xy 379.698114 -338.73087) (xy 379.732957 -338.772991) (xy 379.747526 -338.796122)
			(xy 379.755441 -338.808351) (xy 379.776916 -338.82802) (xy 379.803071 -338.840823) (xy 379.831778 -338.845717)
			(xy 379.860698 -338.842304) (xy 379.874272 -338.837016) (xy 379.897488 -338.827544) (xy 379.945818 -338.814186)
			(xy 379.995505 -338.807451) (xy 380.020576 -338.807044) (xy 380.045517 -338.807416) (xy 380.094955 -338.814065)
			(xy 380.143064 -338.827247) (xy 380.188986 -338.846727) (xy 380.231899 -338.872158) (xy 380.251716 -338.887308)
			(xy 380.26328 -338.895793) (xy 380.289788 -338.906699) (xy 380.318285 -338.909788) (xy 380.346513 -338.904813)
			(xy 380.372238 -338.89217) (xy 380.393421 -338.872859) (xy 380.401322 -338.860892) (xy 380.416313 -338.837415)
			(xy 380.451977 -338.794632) (xy 380.493486 -338.757491) (xy 380.539956 -338.726784) (xy 380.590398 -338.703162)
			(xy 380.64374 -338.68713) (xy 380.698846 -338.679027) (xy 380.726696 -338.67852) (xy 380.754851 -338.678952)
			(xy 380.810552 -338.687216) (xy 380.864433 -338.703578) (xy 380.915323 -338.727684) (xy 380.962116 -338.75901)
			(xy 381.003795 -338.796875) (xy 381.039454 -338.840456) (xy 381.068319 -338.888806) (xy 381.089761 -338.940874)
			(xy 381.097028 -338.96808) (xy 381.101361 -338.983027) (xy 381.117615 -339.009543) (xy 381.141093 -339.029942)
			(xy 381.169619 -339.042335) (xy 381.200552 -339.045572) (xy 381.2159 -339.04301) (xy 381.234683 -339.039438)
			(xy 381.272728 -339.035624) (xy 381.291846 -339.03539) (xy 381.319095 -339.035883) (xy 381.373037 -339.043645)
			(xy 381.425326 -339.059004) (xy 381.474898 -339.081647) (xy 381.520742 -339.111115) (xy 381.561926 -339.146806)
			(xy 381.597613 -339.187995) (xy 381.627075 -339.233843) (xy 381.649712 -339.283417) (xy 381.665065 -339.335708)
			(xy 381.67282 -339.389651) (xy 381.67282 -339.444149) (xy 381.665065 -339.498092) (xy 381.649712 -339.550383)
			(xy 381.627075 -339.599957) (xy 381.597613 -339.645805) (xy 381.561926 -339.686994) (xy 381.520742 -339.722685)
			(xy 381.474898 -339.752153) (xy 381.425326 -339.774796) (xy 381.373037 -339.790155) (xy 381.319095 -339.797917)
			(xy 381.291846 -339.798406) (xy 381.263693 -339.797916) (xy 381.207995 -339.789659) (xy 381.154117 -339.773304)
			(xy 381.103229 -339.749205) (xy 381.056436 -339.717886) (xy 381.014757 -339.680028) (xy 380.979096 -339.636454)
			(xy 380.950229 -339.588111) (xy 380.928783 -339.536049) (xy 380.921514 -339.508846) (xy 380.917228 -339.493882)
			(xy 380.900967 -339.467358) (xy 380.877478 -339.446956) (xy 380.848939 -339.434569) (xy 380.817994 -339.431344)
			(xy 380.802642 -339.433916) (xy 380.783858 -339.437482) (xy 380.745814 -339.4413) (xy 380.726696 -339.441536)
			(xy 380.700531 -339.44109) (xy 380.648686 -339.43398) (xy 380.598303 -339.419839) (xy 380.550329 -339.398935)
			(xy 380.505669 -339.37166) (xy 380.485142 -339.35543) (xy 380.473724 -339.346722) (xy 380.44736 -339.335384)
			(xy 380.41888 -339.33185) (xy 380.390544 -339.3364) (xy 380.364601 -339.348673) (xy 380.343112 -339.367694)
			(xy 380.335028 -339.37956) (xy 380.3293 -339.388435) (xy 380.316971 -339.405588) (xy 380.31039 -339.41385)
			(xy 380.301159 -339.426158) (xy 380.289769 -339.454718) (xy 380.287381 -339.485373) (xy 380.29421 -339.515353)
			(xy 380.30964 -339.541948) (xy 380.332277 -339.562757) (xy 380.34595 -339.569806) (xy 380.369084 -339.581162)
			(xy 380.412323 -339.609201) (xy 380.451386 -339.642814) (xy 380.485561 -339.681387) (xy 380.514222 -339.724216)
			(xy 380.536847 -339.770519) (xy 380.54534 -339.79485) (xy 380.550438 -339.808602) (xy 380.567205 -339.832649)
			(xy 380.590102 -339.850956) (xy 380.61725 -339.862021) (xy 380.64642 -339.864934) (xy 380.66091 -339.862668)
			(xy 380.678835 -339.859457) (xy 380.715091 -339.856019) (xy 380.7333 -339.85581) (xy 380.760554 -339.856255)
			(xy 380.814506 -339.864013) (xy 380.866805 -339.87937) (xy 380.916387 -339.902014) (xy 380.962241 -339.931483)
			(xy 381.003434 -339.967179) (xy 381.039128 -340.008374) (xy 381.068595 -340.054229) (xy 381.091237 -340.103811)
			(xy 381.106591 -340.156111) (xy 381.114346 -340.210064) (xy 381.114808 -340.237318) (xy 381.114554 -340.247732)
			(xy 381.114676 -340.262099) (xy 381.12194 -340.289884) (xy 381.136646 -340.31455) (xy 381.157635 -340.334151)
			(xy 381.183249 -340.347138) (xy 381.211465 -340.352486) (xy 381.225806 -340.351618) (xy 381.262382 -340.34984)
			(xy 381.289639 -340.350206) (xy 381.343599 -340.357962) (xy 381.395906 -340.373318) (xy 381.445494 -340.395962)
			(xy 381.491355 -340.425434) (xy 381.532555 -340.461132) (xy 381.568256 -340.50233) (xy 381.597729 -340.54819)
			(xy 381.620376 -340.597778) (xy 381.635735 -340.650084) (xy 381.643493 -340.704043) (xy 381.643493 -340.758557)
			(xy 381.635735 -340.812516) (xy 381.620376 -340.864822) (xy 381.597729 -340.91441) (xy 381.568256 -340.96027)
			(xy 381.532555 -341.001468) (xy 381.491355 -341.037166) (xy 381.445494 -341.066638) (xy 381.395906 -341.089282)
			(xy 381.343599 -341.104638) (xy 381.289639 -341.112394) (xy 381.262382 -341.112856) (xy 381.251371 -341.112781)
			(xy 381.229386 -341.111508) (xy 381.21844 -341.110316) (xy 381.203582 -341.109091) (xy 381.174247 -341.11434)
			(xy 381.14768 -341.12784) (xy 381.126144 -341.148439) (xy 381.111478 -341.17438) (xy 381.107696 -341.188802)
			(xy 381.100847 -341.216546) (xy 381.07999 -341.269747) (xy 381.051435 -341.319245) (xy 381.015821 -341.363933)
			(xy 380.973944 -341.402814) (xy 380.926739 -341.435018) (xy 380.875262 -341.459826) (xy 380.820661 -341.476683)
			(xy 380.764158 -341.485214) (xy 380.735586 -341.485728) (xy 380.706599 -341.485189) (xy 380.649292 -341.476416)
			(xy 380.593972 -341.459074) (xy 380.541912 -341.433561) (xy 380.494312 -341.400467) (xy 380.452267 -341.360551)
			(xy 380.416744 -341.314734) (xy 380.388562 -341.26407) (xy 380.36837 -341.209726) (xy 380.356632 -341.152952)
			(xy 380.354586 -341.124032) (xy 380.353411 -341.109958) (xy 380.34432 -341.083231) (xy 380.328247 -341.060024)
			(xy 380.306424 -341.042115) (xy 380.280526 -341.030879) (xy 380.252539 -341.027179) (xy 380.238508 -341.028782)
			(xy 380.224743 -341.030678) (xy 380.19703 -341.032711) (xy 380.183136 -341.032846) (xy 380.155887 -341.032288)
			(xy 380.101944 -341.024538) (xy 380.049653 -341.009189) (xy 380.000079 -340.986555) (xy 379.95423 -340.957096)
			(xy 379.91304 -340.921412) (xy 379.877348 -340.880229) (xy 379.847881 -340.834386) (xy 379.825237 -340.784816)
			(xy 379.809878 -340.732528) (xy 379.802117 -340.678587) (xy 379.801628 -340.651338) (xy 379.80211 -340.623764)
			(xy 379.810058 -340.569191) (xy 379.825779 -340.516331) (xy 379.848946 -340.466285) (xy 379.879076 -340.420095)
			(xy 379.915542 -340.378724) (xy 379.936248 -340.360508) (xy 379.947111 -340.350573) (xy 379.963193 -340.325935)
			(xy 379.971585 -340.297735) (xy 379.971592 -340.268314) (xy 379.963214 -340.24011) (xy 379.947144 -340.215464)
			(xy 379.936248 -340.205568) (xy 379.915528 -340.187366) (xy 379.879056 -340.145997) (xy 379.848924 -340.099805)
			(xy 379.825759 -340.049755) (xy 379.810046 -339.99689) (xy 379.80211 -339.942313) (xy 379.801628 -339.914738)
			(xy 379.802058 -339.888236) (xy 379.809408 -339.835744) (xy 379.823958 -339.784775) (xy 379.845426 -339.736313)
			(xy 379.8734 -339.691292) (xy 379.89002 -339.670644) (xy 379.899478 -339.658509) (xy 379.911271 -339.630105)
			(xy 379.914094 -339.59948) (xy 379.907695 -339.569399) (xy 379.892649 -339.542576) (xy 379.870316 -339.521432)
			(xy 379.856746 -339.51418) (xy 379.833054 -339.502083) (xy 379.789072 -339.472159) (xy 379.749792 -339.436287)
			(xy 379.716009 -339.395195) (xy 379.701806 -339.372702) (xy 379.693854 -339.360498) (xy 379.672391 -339.340827)
			(xy 379.646245 -339.328019) (xy 379.617547 -339.323119) (xy 379.588632 -339.326524) (xy 379.57506 -339.331808)
			(xy 379.551852 -339.341303) (xy 379.503518 -339.354652) (xy 379.453828 -339.361378) (xy 379.428756 -339.36178)
			(xy 379.403687 -339.361358) (xy 379.354004 -339.354608) (xy 379.305669 -339.341274) (xy 379.282452 -339.331808)
			(xy 379.26887 -339.326573) (xy 379.239972 -339.323203) (xy 379.211294 -339.32811) (xy 379.18516 -339.340897)
			(xy 379.163686 -339.360528) (xy 379.155706 -339.372702) (xy 379.141137 -339.395833) (xy 379.106294 -339.437954)
			(xy 379.065671 -339.474533) (xy 379.02014 -339.504784) (xy 378.970678 -339.52806) (xy 378.918347 -339.54386)
			(xy 378.864268 -339.551846) (xy 378.809604 -339.551846) (xy 378.755525 -339.54386) (xy 378.703194 -339.52806)
			(xy 378.653732 -339.504784) (xy 378.608201 -339.474533) (xy 378.567578 -339.437954) (xy 378.532735 -339.395833)
			(xy 378.518166 -339.372702) (xy 378.510252 -339.360471) (xy 378.488779 -339.340799) (xy 378.462623 -339.327995)
			(xy 378.433915 -339.323102) (xy 378.404994 -339.326518) (xy 378.39142 -339.331808) (xy 378.368205 -339.341284)
			(xy 378.319875 -339.35464) (xy 378.270187 -339.361374) (xy 378.245116 -339.36178) (xy 378.217226 -339.361362)
			(xy 378.162068 -339.353051) (xy 378.108764 -339.336611) (xy 378.058507 -339.31241) (xy 378.012418 -339.280989)
			(xy 377.971527 -339.243049) (xy 377.936747 -339.199439) (xy 377.908856 -339.151131) (xy 377.888477 -339.099207)
			(xy 377.876064 -339.044825) (xy 377.871895 -338.9892) (xy 340.790187 -338.9892) (xy 340.795398 -339.025412)
			(xy 340.795864 -339.052662) (xy 340.795316 -339.082032) (xy 340.786317 -339.14008) (xy 340.768526 -339.196061)
			(xy 340.742363 -339.248654) (xy 340.708447 -339.296614) (xy 340.66758 -339.338808) (xy 340.64448 -339.356954)
			(xy 340.633399 -339.366027) (xy 340.616251 -339.388944) (xy 340.606145 -339.415722) (xy 340.603874 -339.444253)
			(xy 340.609619 -339.472293) (xy 340.622926 -339.497633) (xy 340.642749 -339.518279) (xy 340.654894 -339.525864)
			(xy 340.679326 -339.540649) (xy 340.723967 -339.576255) (xy 340.762805 -339.618116) (xy 340.794972 -339.665295)
			(xy 340.819752 -339.716741) (xy 340.836589 -339.771304) (xy 340.845109 -339.827767) (xy 340.845648 -339.856318)
			(xy 340.845255 -339.882212) (xy 340.838252 -339.933526) (xy 340.824365 -339.983418) (xy 340.803849 -340.03097)
			(xy 340.777082 -340.075305) (xy 340.744557 -340.115607) (xy 340.726014 -340.133686) (xy 340.715911 -340.143825)
			(xy 340.701296 -340.168419) (xy 340.694088 -340.196105) (xy 340.694855 -340.224704) (xy 340.703535 -340.251965)
			(xy 340.719447 -340.275741) (xy 340.730078 -340.285324) (xy 340.750901 -340.30352) (xy 340.787573 -340.344907)
			(xy 340.817878 -340.39116) (xy 340.841179 -340.441307) (xy 340.856987 -340.494296) (xy 340.864971 -340.549014)
			(xy 340.86546 -340.576662) (xy 340.865009 -340.603916) (xy 340.861078 -340.631272) (xy 374.003316 -340.631272)
			(xy 374.003769 -340.603734) (xy 374.011666 -340.549227) (xy 374.027321 -340.496423) (xy 374.050409 -340.44642)
			(xy 374.080448 -340.400257) (xy 374.116816 -340.358896) (xy 374.158754 -340.323195) (xy 374.205391 -340.293897)
			(xy 374.255757 -340.271613) (xy 374.308805 -340.256804) (xy 374.336056 -340.252812) (xy 374.349853 -340.250659)
			(xy 374.375538 -340.239719) (xy 374.397306 -340.222238) (xy 374.413534 -340.199522) (xy 374.423013 -340.173262)
			(xy 374.425036 -340.145418) (xy 374.42267 -340.131654) (xy 374.419017 -340.112687) (xy 374.415068 -340.07426)
			(xy 374.414796 -340.054946) (xy 374.415282 -340.027695) (xy 374.423038 -339.973747) (xy 374.438393 -339.921452)
			(xy 374.461035 -339.871875) (xy 374.490501 -339.826025) (xy 374.526192 -339.784834) (xy 374.567383 -339.749143)
			(xy 374.613233 -339.719677) (xy 374.66281 -339.697035) (xy 374.715105 -339.68168) (xy 374.769053 -339.673924)
			(xy 374.823555 -339.673924) (xy 374.877503 -339.68168) (xy 374.929798 -339.697035) (xy 374.979375 -339.719677)
			(xy 375.025225 -339.749143) (xy 375.066416 -339.784834) (xy 375.102107 -339.826025) (xy 375.131573 -339.871875)
			(xy 375.154215 -339.921452) (xy 375.16957 -339.973747) (xy 375.177326 -340.027695) (xy 375.177812 -340.054946)
			(xy 375.177351 -340.082484) (xy 375.169452 -340.136989) (xy 375.153796 -340.189791) (xy 375.130709 -340.239793)
			(xy 375.10067 -340.285954) (xy 375.064304 -340.327316) (xy 375.022367 -340.363016) (xy 374.975732 -340.392315)
			(xy 374.925368 -340.414601) (xy 374.872322 -340.429412) (xy 374.845072 -340.433406) (xy 374.831299 -340.435672)
			(xy 374.805626 -340.446595) (xy 374.783863 -340.464053) (xy 374.767632 -340.486746) (xy 374.758143 -340.512982)
			(xy 374.756103 -340.540807) (xy 374.758458 -340.554564) (xy 374.762114 -340.573531) (xy 374.766061 -340.611958)
			(xy 374.766332 -340.631272) (xy 374.765846 -340.658523) (xy 374.75809 -340.712471) (xy 374.742735 -340.764766)
			(xy 374.720093 -340.814343) (xy 374.690627 -340.860193) (xy 374.654936 -340.901384) (xy 374.613745 -340.937075)
			(xy 374.567895 -340.966541) (xy 374.518318 -340.989183) (xy 374.466023 -341.004538) (xy 374.412075 -341.012294)
			(xy 374.357573 -341.012294) (xy 374.303625 -341.004538) (xy 374.25133 -340.989183) (xy 374.201753 -340.966541)
			(xy 374.155903 -340.937075) (xy 374.114712 -340.901384) (xy 374.079021 -340.860193) (xy 374.049555 -340.814343)
			(xy 374.026913 -340.764766) (xy 374.011558 -340.712471) (xy 374.003802 -340.658523) (xy 374.003316 -340.631272)
			(xy 340.861078 -340.631272) (xy 340.857256 -340.65787) (xy 340.841903 -340.710171) (xy 340.819261 -340.759754)
			(xy 340.789792 -340.80561) (xy 340.754097 -340.846804) (xy 340.712902 -340.882498) (xy 340.667045 -340.911966)
			(xy 340.617462 -340.934606) (xy 340.56516 -340.949958) (xy 340.511206 -340.95771) (xy 340.483952 -340.95817)
			(xy 340.454875 -340.957639) (xy 340.397395 -340.948821) (xy 340.341918 -340.93138) (xy 340.289732 -340.905722)
			(xy 340.242044 -340.872441) (xy 340.19996 -340.832307) (xy 340.164454 -340.786251) (xy 340.136351 -340.735339)
			(xy 340.125812 -340.708234) (xy 340.120356 -340.694656) (xy 340.102875 -340.671198) (xy 340.07946 -340.653661)
			(xy 340.052032 -340.643485) (xy 340.022844 -340.641505) (xy 340.008464 -340.644226) (xy 339.987905 -340.648519)
			(xy 339.946153 -340.653097) (xy 339.925152 -340.65337) (xy 339.910936 -340.653208) (xy 339.882586 -340.65105)
			(xy 339.86851 -340.649052) (xy 339.853186 -340.647282) (xy 339.822729 -340.652112) (xy 339.795094 -340.665797)
			(xy 339.772792 -340.687094) (xy 339.757848 -340.714069) (xy 339.75421 -340.729062) (xy 339.747713 -340.757293)
			(xy 339.727473 -340.811567) (xy 339.699262 -340.862158) (xy 339.663727 -340.907903) (xy 339.621687 -340.947751)
			(xy 339.574106 -340.980787) (xy 339.522078 -341.006251) (xy 339.466799 -341.023558) (xy 339.409539 -341.03231)
			(xy 339.380576 -341.032846) (xy 339.353326 -341.032345) (xy 339.299381 -341.024586) (xy 339.247089 -341.00923)
			(xy 339.197514 -340.986588) (xy 339.151665 -340.957123) (xy 339.110476 -340.921434) (xy 339.074785 -340.880246)
			(xy 339.045318 -340.834399) (xy 339.022675 -340.784825) (xy 339.007317 -340.732533) (xy 338.999556 -340.678588)
			(xy 338.999068 -340.651338) (xy 338.999571 -340.623765) (xy 339.007517 -340.569194) (xy 339.023236 -340.516336)
			(xy 339.046399 -340.46629) (xy 339.076524 -340.420099) (xy 339.112984 -340.378726) (xy 339.133688 -340.360508)
			(xy 339.144548 -340.350571) (xy 339.160623 -340.325932) (xy 339.169012 -340.297734) (xy 339.169019 -340.268315)
			(xy 339.160644 -340.240113) (xy 339.14458 -340.215466) (xy 339.133688 -340.205568) (xy 339.112956 -340.18738)
			(xy 339.076488 -340.146006) (xy 339.046358 -340.099811) (xy 339.023196 -340.049759) (xy 339.007484 -339.996892)
			(xy 338.99955 -339.942314) (xy 338.999068 -339.914738) (xy 338.999512 -339.888237) (xy 339.006861 -339.835745)
			(xy 339.021408 -339.784778) (xy 339.042873 -339.736316) (xy 339.070842 -339.691293) (xy 339.08746 -339.670644)
			(xy 339.096904 -339.6585) (xy 339.10869 -339.630099) (xy 339.111512 -339.599479) (xy 339.105115 -339.569402)
			(xy 339.090076 -339.542581) (xy 339.067752 -339.521435) (xy 339.054186 -339.51418) (xy 339.0305 -339.502071)
			(xy 338.986517 -339.472151) (xy 338.947235 -339.436283) (xy 338.91345 -339.395194) (xy 338.899246 -339.372702)
			(xy 338.891351 -339.360457) (xy 338.869873 -339.340786) (xy 338.843711 -339.327983) (xy 338.814999 -339.323094)
			(xy 338.786075 -339.326515) (xy 338.7725 -339.331808) (xy 338.749287 -339.34129) (xy 338.700956 -339.354644)
			(xy 338.651267 -339.361375) (xy 338.626196 -339.36178) (xy 338.601127 -339.361345) (xy 338.551444 -339.3546)
			(xy 338.50311 -339.341272) (xy 338.479892 -339.331808) (xy 338.466296 -339.326615) (xy 338.437405 -339.323236)
			(xy 338.408732 -339.328134) (xy 338.3826 -339.340911) (xy 338.361126 -339.360532) (xy 338.353146 -339.372702)
			(xy 338.338577 -339.395833) (xy 338.303734 -339.437954) (xy 338.263111 -339.474533) (xy 338.21758 -339.504784)
			(xy 338.168118 -339.52806) (xy 338.115787 -339.54386) (xy 338.061708 -339.551846) (xy 338.007044 -339.551846)
			(xy 337.952965 -339.54386) (xy 337.900634 -339.52806) (xy 337.851172 -339.504784) (xy 337.805641 -339.474533)
			(xy 337.765018 -339.437954) (xy 337.730175 -339.395833) (xy 337.715606 -339.372702) (xy 337.707654 -339.360498)
			(xy 337.686191 -339.340827) (xy 337.660045 -339.328019) (xy 337.631347 -339.323119) (xy 337.602432 -339.326524)
			(xy 337.58886 -339.331808) (xy 337.565652 -339.341303) (xy 337.517318 -339.354652) (xy 337.467628 -339.361378)
			(xy 337.442556 -339.36178) (xy 337.41467 -339.361332) (xy 337.359523 -339.353014) (xy 337.306231 -339.33657)
			(xy 337.255985 -339.312367) (xy 337.209907 -339.280947) (xy 337.169027 -339.24301) (xy 337.134256 -339.199405)
			(xy 337.106372 -339.151105) (xy 337.085998 -339.099188) (xy 337.073589 -339.044815) (xy 337.069421 -338.9892)
			(xy 316.854548 -338.9892) (xy 315.788802 -340.054946) (xy 333.611726 -340.054946) (xy 333.615797 -339.999324)
			(xy 333.627923 -339.944887) (xy 333.647846 -339.892796) (xy 333.675142 -339.844161) (xy 333.709228 -339.800018)
			(xy 333.749377 -339.761309) (xy 333.794735 -339.728858) (xy 333.844335 -339.703357) (xy 333.897119 -339.68535)
			(xy 333.951962 -339.67522) (xy 334.007696 -339.673183) (xy 334.063133 -339.679283) (xy 334.11709 -339.693389)
			(xy 334.168419 -339.715201) (xy 334.216025 -339.744255) (xy 334.258893 -339.77993) (xy 334.29611 -339.821467)
			(xy 334.326883 -339.86798) (xy 334.350555 -339.918477) (xy 334.366623 -339.971884) (xy 334.374743 -340.02706)
			(xy 334.375252 -340.054946) (xy 334.374743 -340.082832) (xy 334.366623 -340.138008) (xy 334.350555 -340.191415)
			(xy 334.326883 -340.241912) (xy 334.29611 -340.288425) (xy 334.258893 -340.329962) (xy 334.216025 -340.365637)
			(xy 334.168419 -340.394691) (xy 334.11709 -340.416503) (xy 334.063133 -340.430609) (xy 334.007696 -340.436709)
			(xy 333.951962 -340.434672) (xy 333.897119 -340.424542) (xy 333.844335 -340.406535) (xy 333.794735 -340.381034)
			(xy 333.749377 -340.348583) (xy 333.709228 -340.309874) (xy 333.675142 -340.265731) (xy 333.647846 -340.217096)
			(xy 333.627923 -340.165005) (xy 333.615797 -340.110568) (xy 333.611726 -340.054946) (xy 315.788802 -340.054946)
			(xy 314.83046 -341.013288) (xy 333.031082 -341.013288) (xy 333.035153 -340.957666) (xy 333.047279 -340.903229)
			(xy 333.067202 -340.851138) (xy 333.094498 -340.802503) (xy 333.128584 -340.75836) (xy 333.168733 -340.719651)
			(xy 333.214091 -340.6872) (xy 333.263691 -340.661699) (xy 333.316475 -340.643692) (xy 333.371318 -340.633562)
			(xy 333.427052 -340.631525) (xy 333.482489 -340.637625) (xy 333.536446 -340.651731) (xy 333.587775 -340.673543)
			(xy 333.635381 -340.702597) (xy 333.678249 -340.738272) (xy 333.715466 -340.779809) (xy 333.746239 -340.826322)
			(xy 333.769911 -340.876819) (xy 333.785979 -340.930226) (xy 333.794099 -340.985402) (xy 333.794608 -341.013288)
			(xy 333.794099 -341.041174) (xy 333.785979 -341.09635) (xy 333.769911 -341.149757) (xy 333.746239 -341.200254)
			(xy 333.715466 -341.246767) (xy 333.678249 -341.288304) (xy 333.635381 -341.323979) (xy 333.587775 -341.353033)
			(xy 333.536446 -341.374845) (xy 333.482489 -341.388951) (xy 333.427052 -341.395051) (xy 333.371318 -341.393014)
			(xy 333.316475 -341.382884) (xy 333.263691 -341.364877) (xy 333.214091 -341.339376) (xy 333.168733 -341.306925)
			(xy 333.128584 -341.268216) (xy 333.094498 -341.224073) (xy 333.067202 -341.175438) (xy 333.047279 -341.123347)
			(xy 333.035153 -341.06891) (xy 333.031082 -341.013288) (xy 314.83046 -341.013288) (xy 314.195206 -341.648542)
			(xy 334.418432 -341.648542) (xy 334.419005 -341.618854) (xy 334.428198 -341.560196) (xy 334.446369 -341.50367)
			(xy 334.473079 -341.450642) (xy 334.507682 -341.402392) (xy 334.549344 -341.360088) (xy 334.572864 -341.341964)
			(xy 334.583445 -341.333505) (xy 334.600159 -341.312203) (xy 334.610684 -341.287255) (xy 334.61428 -341.260418)
			(xy 334.610693 -341.23358) (xy 334.600177 -341.208628) (xy 334.583471 -341.18732) (xy 334.572864 -341.178896)
			(xy 334.549344 -341.160772) (xy 334.507686 -341.118465) (xy 334.473083 -341.070215) (xy 334.446373 -341.017188)
			(xy 334.428198 -340.960663) (xy 334.418998 -340.902005) (xy 334.418432 -340.872318) (xy 334.418918 -340.845067)
			(xy 334.426674 -340.791119) (xy 334.442029 -340.738824) (xy 334.464671 -340.689247) (xy 334.494137 -340.643397)
			(xy 334.529828 -340.602206) (xy 334.571019 -340.566515) (xy 334.616869 -340.537049) (xy 334.666446 -340.514407)
			(xy 334.718741 -340.499052) (xy 334.772689 -340.491296) (xy 334.827191 -340.491296) (xy 334.881139 -340.499052)
			(xy 334.933434 -340.514407) (xy 334.983011 -340.537049) (xy 335.028861 -340.566515) (xy 335.070052 -340.602206)
			(xy 335.105743 -340.643397) (xy 335.135209 -340.689247) (xy 335.157851 -340.738824) (xy 335.173206 -340.791119)
			(xy 335.180962 -340.845067) (xy 335.181448 -340.872318) (xy 335.180927 -340.902008) (xy 335.171724 -340.960669)
			(xy 335.153543 -341.017197) (xy 335.126824 -341.070225) (xy 335.114749 -341.087057) (xy 335.434825 -341.087057)
			(xy 335.434825 -341.032543) (xy 335.442584 -340.978584) (xy 335.457943 -340.926279) (xy 335.48059 -340.876692)
			(xy 335.510064 -340.830834) (xy 335.545765 -340.789637) (xy 335.586966 -340.75394) (xy 335.632828 -340.724471)
			(xy 335.682417 -340.701829) (xy 335.734724 -340.686475) (xy 335.788683 -340.678722) (xy 335.81594 -340.678262)
			(xy 335.841176 -340.678647) (xy 335.89121 -340.685269) (xy 335.93993 -340.698446) (xy 335.986482 -340.717946)
			(xy 336.008472 -340.730332) (xy 336.021462 -340.737322) (xy 336.050089 -340.744366) (xy 336.079535 -340.742932)
			(xy 336.107342 -340.733139) (xy 336.131189 -340.715805) (xy 336.149085 -340.692377) (xy 336.154776 -340.67877)
			(xy 336.16546 -340.651988) (xy 336.19375 -340.601747) (xy 336.229282 -340.556338) (xy 336.271246 -340.516797)
			(xy 336.318685 -340.484024) (xy 336.370517 -340.458767) (xy 336.425562 -340.441602) (xy 336.482563 -340.432919)
			(xy 336.511392 -340.43239) (xy 336.538645 -340.432863) (xy 336.592595 -340.440619) (xy 336.644893 -340.455974)
			(xy 336.694473 -340.478615) (xy 336.740326 -340.508082) (xy 336.781518 -340.543775) (xy 336.817212 -340.584966)
			(xy 336.84668 -340.630819) (xy 336.869323 -340.680398) (xy 336.884679 -340.732695) (xy 336.892437 -340.786645)
			(xy 336.8929 -340.813898) (xy 336.892376 -340.843803) (xy 336.883056 -340.902883) (xy 336.874358 -340.9315)
			(xy 336.870419 -340.945432) (xy 336.869498 -340.974349) (xy 336.876747 -341.002357) (xy 336.89158 -341.027197)
			(xy 336.9128 -341.046861) (xy 336.938695 -341.059765) (xy 336.952844 -341.062818) (xy 336.978919 -341.067975)
			(xy 337.029423 -341.084548) (xy 337.077136 -341.107974) (xy 337.121134 -341.137797) (xy 337.160564 -341.173442)
			(xy 337.194662 -341.214216) (xy 337.222769 -341.25933) (xy 337.244338 -341.30791) (xy 337.258953 -341.359015)
			(xy 337.26633 -341.411653) (xy 337.266788 -341.43823) (xy 337.266302 -341.465481) (xy 337.258546 -341.519429)
			(xy 337.243191 -341.571724) (xy 337.220549 -341.621301) (xy 337.203042 -341.648542) (xy 375.220992 -341.648542)
			(xy 375.221581 -341.618855) (xy 375.230773 -341.560198) (xy 375.248942 -341.503673) (xy 375.275649 -341.450645)
			(xy 375.310249 -341.402396) (xy 375.351906 -341.360089) (xy 375.375424 -341.341964) (xy 375.386 -341.333502)
			(xy 375.402704 -341.312197) (xy 375.413223 -341.287251) (xy 375.416816 -341.260418) (xy 375.413232 -341.233583)
			(xy 375.402723 -341.208634) (xy 375.386026 -341.187323) (xy 375.375424 -341.178896) (xy 375.351917 -341.160756)
			(xy 375.310255 -341.118454) (xy 375.275649 -341.070208) (xy 375.248936 -341.017184) (xy 375.230759 -340.960661)
			(xy 375.221558 -340.902005) (xy 375.220992 -340.872318) (xy 375.221478 -340.845067) (xy 375.229234 -340.791119)
			(xy 375.244589 -340.738824) (xy 375.267231 -340.689247) (xy 375.296697 -340.643397) (xy 375.332388 -340.602206)
			(xy 375.373579 -340.566515) (xy 375.419429 -340.537049) (xy 375.469006 -340.514407) (xy 375.521301 -340.499052)
			(xy 375.575249 -340.491296) (xy 375.629751 -340.491296) (xy 375.683699 -340.499052) (xy 375.735994 -340.514407)
			(xy 375.785571 -340.537049) (xy 375.831421 -340.566515) (xy 375.872612 -340.602206) (xy 375.908303 -340.643397)
			(xy 375.937769 -340.689247) (xy 375.960411 -340.738824) (xy 375.975766 -340.791119) (xy 375.983522 -340.845067)
			(xy 375.984008 -340.872318) (xy 375.983463 -340.902006) (xy 375.974262 -340.960666) (xy 375.956084 -341.017192)
			(xy 375.929369 -341.070219) (xy 375.917294 -341.087053) (xy 376.237448 -341.087053) (xy 376.237448 -341.032547)
			(xy 376.245205 -340.978595) (xy 376.260561 -340.926296) (xy 376.283204 -340.876715) (xy 376.312673 -340.830861)
			(xy 376.348367 -340.789667) (xy 376.389561 -340.753973) (xy 376.435415 -340.724504) (xy 376.484996 -340.701861)
			(xy 376.537295 -340.686505) (xy 376.591247 -340.678748) (xy 376.6185 -340.678262) (xy 376.643735 -340.678664)
			(xy 376.693769 -340.685282) (xy 376.742489 -340.698453) (xy 376.789041 -340.717948) (xy 376.811032 -340.730332)
			(xy 376.823986 -340.737393) (xy 376.852628 -340.744427) (xy 376.882085 -340.74298) (xy 376.909899 -340.733173)
			(xy 376.93375 -340.715825) (xy 376.951646 -340.692384) (xy 376.957336 -340.67877) (xy 376.968053 -340.652003)
			(xy 376.996339 -340.601763) (xy 377.031867 -340.556355) (xy 377.073826 -340.516813) (xy 377.12126 -340.484038)
			(xy 377.173088 -340.458779) (xy 377.228127 -340.44161) (xy 377.285124 -340.432922) (xy 377.313952 -340.43239)
			(xy 377.341204 -340.4329) (xy 377.395153 -340.44065) (xy 377.44745 -340.456) (xy 377.497029 -340.478637)
			(xy 377.542883 -340.5081) (xy 377.584076 -340.543789) (xy 377.61977 -340.584977) (xy 377.649239 -340.630827)
			(xy 377.671882 -340.680403) (xy 377.687239 -340.732698) (xy 377.694996 -340.786646) (xy 377.69546 -340.813898)
			(xy 377.694933 -340.843803) (xy 377.685615 -340.902882) (xy 377.676918 -340.9315) (xy 377.672932 -340.945422)
			(xy 377.672009 -340.974348) (xy 377.679262 -341.002366) (xy 377.694105 -341.027211) (xy 377.715339 -341.046875)
			(xy 377.741249 -341.059771) (xy 377.755404 -341.062818) (xy 377.781473 -341.068005) (xy 377.831977 -341.084573)
			(xy 377.87969 -341.107993) (xy 377.923689 -341.137813) (xy 377.96312 -341.173454) (xy 377.99722 -341.214225)
			(xy 378.025327 -341.259337) (xy 378.046897 -341.307914) (xy 378.061513 -341.359017) (xy 378.06889 -341.411654)
			(xy 378.069348 -341.43823) (xy 378.068862 -341.465481) (xy 378.061106 -341.519429) (xy 378.045751 -341.571724)
			(xy 378.023109 -341.621301) (xy 377.993643 -341.667151) (xy 377.957952 -341.708342) (xy 377.916761 -341.744033)
			(xy 377.870911 -341.773499) (xy 377.821334 -341.796141) (xy 377.769039 -341.811496) (xy 377.715091 -341.819252)
			(xy 377.660589 -341.819252) (xy 377.606641 -341.811496) (xy 377.554346 -341.796141) (xy 377.504769 -341.773499)
			(xy 377.458919 -341.744033) (xy 377.417728 -341.708342) (xy 377.382037 -341.667151) (xy 377.352571 -341.621301)
			(xy 377.329929 -341.571724) (xy 377.314574 -341.519429) (xy 377.306818 -341.465481) (xy 377.306332 -341.43823)
			(xy 377.306862 -341.408325) (xy 377.316178 -341.349246) (xy 377.324874 -341.320628) (xy 377.328947 -341.306729)
			(xy 377.329854 -341.27779) (xy 377.322584 -341.249764) (xy 377.307724 -341.224915) (xy 377.286474 -341.205249)
			(xy 377.26055 -341.192355) (xy 377.246388 -341.18931) (xy 377.213548 -341.182731) (xy 377.150696 -341.159605)
			(xy 377.12142 -341.143336) (xy 377.108428 -341.136353) (xy 377.079802 -341.129314) (xy 377.050359 -341.13075)
			(xy 377.022554 -341.140542) (xy 376.998708 -341.157871) (xy 376.980809 -341.181294) (xy 376.975116 -341.194898)
			(xy 376.964422 -341.221675) (xy 376.936135 -341.271918) (xy 376.900605 -341.317328) (xy 376.858643 -341.356871)
			(xy 376.811205 -341.389645) (xy 376.759374 -341.414902) (xy 376.70433 -341.432068) (xy 376.647329 -341.440749)
			(xy 376.6185 -341.441278) (xy 376.591247 -341.440852) (xy 376.537295 -341.433095) (xy 376.484996 -341.417739)
			(xy 376.435415 -341.395096) (xy 376.389561 -341.365627) (xy 376.348367 -341.329933) (xy 376.312673 -341.288739)
			(xy 376.283204 -341.242885) (xy 376.260561 -341.193304) (xy 376.245205 -341.141005) (xy 376.237448 -341.087053)
			(xy 375.917294 -341.087053) (xy 375.894761 -341.118468) (xy 375.853097 -341.160772) (xy 375.829576 -341.178896)
			(xy 375.81894 -341.187288) (xy 375.802236 -341.208609) (xy 375.791721 -341.233571) (xy 375.788136 -341.260418)
			(xy 375.791731 -341.287264) (xy 375.802254 -341.312222) (xy 375.818966 -341.333537) (xy 375.829576 -341.341964)
			(xy 375.853064 -341.360127) (xy 375.894727 -341.402425) (xy 375.929335 -341.450666) (xy 375.956052 -341.503686)
			(xy 375.974232 -341.560204) (xy 375.983439 -341.618857) (xy 375.984008 -341.648542) (xy 375.983522 -341.675793)
			(xy 375.975766 -341.729741) (xy 375.960411 -341.782036) (xy 375.937769 -341.831613) (xy 375.908303 -341.877463)
			(xy 375.872612 -341.918654) (xy 375.831421 -341.954345) (xy 375.785571 -341.983811) (xy 375.735994 -342.006453)
			(xy 375.683699 -342.021808) (xy 375.629751 -342.029564) (xy 375.575249 -342.029564) (xy 375.521301 -342.021808)
			(xy 375.469006 -342.006453) (xy 375.419429 -341.983811) (xy 375.373579 -341.954345) (xy 375.332388 -341.918654)
			(xy 375.296697 -341.877463) (xy 375.267231 -341.831613) (xy 375.244589 -341.782036) (xy 375.229234 -341.729741)
			(xy 375.221478 -341.675793) (xy 375.220992 -341.648542) (xy 337.203042 -341.648542) (xy 337.191083 -341.667151)
			(xy 337.155392 -341.708342) (xy 337.114201 -341.744033) (xy 337.068351 -341.773499) (xy 337.018774 -341.796141)
			(xy 336.966479 -341.811496) (xy 336.912531 -341.819252) (xy 336.858029 -341.819252) (xy 336.804081 -341.811496)
			(xy 336.751786 -341.796141) (xy 336.702209 -341.773499) (xy 336.656359 -341.744033) (xy 336.615168 -341.708342)
			(xy 336.579477 -341.667151) (xy 336.550011 -341.621301) (xy 336.527369 -341.571724) (xy 336.512014 -341.519429)
			(xy 336.504258 -341.465481) (xy 336.503772 -341.43823) (xy 336.504304 -341.408325) (xy 336.513619 -341.349246)
			(xy 336.522314 -341.320628) (xy 336.526356 -341.306722) (xy 336.527261 -341.277789) (xy 336.519994 -341.24977)
			(xy 336.505141 -341.224924) (xy 336.4839 -341.205258) (xy 336.457986 -341.19236) (xy 336.443828 -341.18931)
			(xy 336.41099 -341.182721) (xy 336.348137 -341.159602) (xy 336.31886 -341.143336) (xy 336.305903 -341.136282)
			(xy 336.277264 -341.129254) (xy 336.24781 -341.130702) (xy 336.219998 -341.140507) (xy 336.196148 -341.157851)
			(xy 336.178248 -341.181287) (xy 336.172556 -341.194898) (xy 336.161829 -341.221661) (xy 336.133545 -341.271902)
			(xy 336.09802 -341.317312) (xy 336.056063 -341.356855) (xy 336.00863 -341.38963) (xy 335.956803 -341.414891)
			(xy 335.901764 -341.43206) (xy 335.844767 -341.440746) (xy 335.81594 -341.441278) (xy 335.788683 -341.440878)
			(xy 335.734724 -341.433125) (xy 335.682417 -341.417771) (xy 335.632828 -341.395129) (xy 335.586966 -341.36566)
			(xy 335.545765 -341.329963) (xy 335.510064 -341.288766) (xy 335.48059 -341.242908) (xy 335.457943 -341.193321)
			(xy 335.442584 -341.141016) (xy 335.434825 -341.087057) (xy 335.114749 -341.087057) (xy 335.092211 -341.118472)
			(xy 335.05054 -341.160774) (xy 335.027016 -341.178896) (xy 335.016377 -341.187286) (xy 334.999666 -341.208606)
			(xy 334.989147 -341.233568) (xy 334.98556 -341.260418) (xy 334.989156 -341.287267) (xy 334.999684 -341.312225)
			(xy 335.016403 -341.333539) (xy 335.027016 -341.341964) (xy 335.050513 -341.360117) (xy 335.092173 -341.402418)
			(xy 335.126779 -341.450661) (xy 335.153494 -341.503683) (xy 335.171673 -341.560203) (xy 335.180879 -341.618856)
			(xy 335.181448 -341.648542) (xy 335.180962 -341.675793) (xy 335.173206 -341.729741) (xy 335.157851 -341.782036)
			(xy 335.135209 -341.831613) (xy 335.105743 -341.877463) (xy 335.070052 -341.918654) (xy 335.028861 -341.954345)
			(xy 334.983011 -341.983811) (xy 334.933434 -342.006453) (xy 334.881139 -342.021808) (xy 334.827191 -342.029564)
			(xy 334.772689 -342.029564) (xy 334.718741 -342.021808) (xy 334.666446 -342.006453) (xy 334.616869 -341.983811)
			(xy 334.571019 -341.954345) (xy 334.529828 -341.918654) (xy 334.494137 -341.877463) (xy 334.464671 -341.831613)
			(xy 334.442029 -341.782036) (xy 334.426674 -341.729741) (xy 334.418918 -341.675793) (xy 334.418432 -341.648542)
			(xy 314.195206 -341.648542) (xy 312.687716 -343.156032) (xy 319.06667 -343.156032) (xy 319.070741 -343.10041)
			(xy 319.082867 -343.045973) (xy 319.10279 -342.993882) (xy 319.130086 -342.945247) (xy 319.164172 -342.901104)
			(xy 319.204321 -342.862395) (xy 319.249679 -342.829944) (xy 319.299279 -342.804443) (xy 319.352063 -342.786436)
			(xy 319.406906 -342.776306) (xy 319.46264 -342.774269) (xy 319.518077 -342.780369) (xy 319.572034 -342.794475)
			(xy 319.623363 -342.816287) (xy 319.670969 -342.845341) (xy 319.713837 -342.881016) (xy 319.751054 -342.922553)
			(xy 319.781827 -342.969066) (xy 319.805499 -343.019563) (xy 319.821567 -343.07297) (xy 319.829687 -343.128146)
			(xy 319.830196 -343.156032) (xy 319.829687 -343.183918) (xy 319.821567 -343.239094) (xy 319.805499 -343.292501)
			(xy 319.781827 -343.342998) (xy 319.751054 -343.389511) (xy 319.713837 -343.431048) (xy 319.670969 -343.466723)
			(xy 319.623363 -343.495777) (xy 319.572034 -343.517589) (xy 319.518077 -343.531695) (xy 319.46264 -343.537795)
			(xy 319.406906 -343.535758) (xy 319.352063 -343.525628) (xy 319.299279 -343.507621) (xy 319.249679 -343.48212)
			(xy 319.204321 -343.449669) (xy 319.164172 -343.41096) (xy 319.130086 -343.366817) (xy 319.10279 -343.318182)
			(xy 319.082867 -343.266091) (xy 319.070741 -343.211654) (xy 319.06667 -343.156032) (xy 312.687716 -343.156032)
			(xy 311.98058 -343.863168) (xy 311.501282 -343.863168) (xy 311.479329 -343.875679) (xy 311.432813 -343.895411)
			(xy 311.384086 -343.908785) (xy 311.334014 -343.915561) (xy 311.30875 -343.916) (xy 300.412912 -343.916)
			(xy 300.398096 -343.916506) (xy 300.369713 -343.925013) (xy 300.344969 -343.941314) (xy 300.325949 -343.964035)
			(xy 300.314257 -343.991262) (xy 300.310877 -344.020699) (xy 300.316095 -344.049867) (xy 300.32947 -344.076308)
			(xy 300.339252 -344.08745) (xy 300.368016 -344.118427) (xy 300.420193 -344.184942) (xy 300.465824 -344.256108)
			(xy 300.504497 -344.331282) (xy 300.535864 -344.409785) (xy 300.559641 -344.490911) (xy 300.575614 -344.573926)
			(xy 300.583639 -344.658083) (xy 300.584108 -344.700352) (xy 300.583604 -344.7427) (xy 300.575553 -344.827014)
			(xy 300.559524 -344.91018) (xy 300.535663 -344.991447) (xy 300.504184 -345.070077) (xy 300.465373 -345.145358)
			(xy 300.419583 -345.21661) (xy 300.367227 -345.283186) (xy 300.308779 -345.344484) (xy 300.244769 -345.399949)
			(xy 300.175777 -345.449078) (xy 300.102427 -345.491427) (xy 300.025384 -345.526611) (xy 299.945345 -345.554313)
			(xy 299.863036 -345.574281) (xy 299.779201 -345.586334) (xy 299.6946 -345.590365) (xy 299.609999 -345.586334)
			(xy 299.526164 -345.574281) (xy 299.443855 -345.554313) (xy 299.363816 -345.526611) (xy 299.286773 -345.491427)
			(xy 299.213423 -345.449078) (xy 299.144431 -345.399949) (xy 299.080421 -345.344484) (xy 299.021973 -345.283186)
			(xy 298.969617 -345.21661) (xy 298.923827 -345.145358) (xy 298.885016 -345.070077) (xy 298.853537 -344.991447)
			(xy 298.829676 -344.91018) (xy 298.813647 -344.827014) (xy 298.805596 -344.7427) (xy 298.805092 -344.700352)
			(xy 298.80559 -344.658061) (xy 298.813616 -344.57386) (xy 298.829599 -344.490801) (xy 298.853395 -344.409635)
			(xy 298.884789 -344.331095) (xy 298.923498 -344.25589) (xy 298.969172 -344.184699) (xy 299.021399 -344.118167)
			(xy 299.050202 -344.087196) (xy 299.059969 -344.076077) (xy 299.073211 -344.049625) (xy 299.07832 -344.020488)
			(xy 299.074866 -343.991108) (xy 299.063139 -343.96395) (xy 299.044123 -343.94129) (xy 299.019413 -343.925029)
			(xy 298.991078 -343.916529) (xy 298.976288 -343.916) (xy 294.215312 -343.916) (xy 294.200496 -343.916506)
			(xy 294.172113 -343.925013) (xy 294.147369 -343.941314) (xy 294.128349 -343.964035) (xy 294.116657 -343.991262)
			(xy 294.113277 -344.020699) (xy 294.118495 -344.049867) (xy 294.13187 -344.076308) (xy 294.141652 -344.08745)
			(xy 294.170416 -344.118427) (xy 294.222593 -344.184942) (xy 294.268224 -344.256108) (xy 294.306897 -344.331282)
			(xy 294.338264 -344.409785) (xy 294.362041 -344.490911) (xy 294.378014 -344.573926) (xy 294.386039 -344.658083)
			(xy 294.386508 -344.700352) (xy 294.386004 -344.7427) (xy 294.377953 -344.827014) (xy 294.361924 -344.91018)
			(xy 294.338063 -344.991447) (xy 294.306584 -345.070077) (xy 294.267773 -345.145358) (xy 294.221983 -345.21661)
			(xy 294.169627 -345.283186) (xy 294.111179 -345.344484) (xy 294.047169 -345.399949) (xy 293.978177 -345.449078)
			(xy 293.904827 -345.491427) (xy 293.827784 -345.526611) (xy 293.747745 -345.554313) (xy 293.665436 -345.574281)
			(xy 293.581601 -345.586334) (xy 293.497 -345.590365) (xy 293.412399 -345.586334) (xy 293.328564 -345.574281)
			(xy 293.246255 -345.554313) (xy 293.166216 -345.526611) (xy 293.089173 -345.491427) (xy 293.015823 -345.449078)
			(xy 292.946831 -345.399949) (xy 292.882821 -345.344484) (xy 292.824373 -345.283186) (xy 292.772017 -345.21661)
			(xy 292.726227 -345.145358) (xy 292.687416 -345.070077) (xy 292.655937 -344.991447) (xy 292.632076 -344.91018)
			(xy 292.616047 -344.827014) (xy 292.607996 -344.7427) (xy 292.607492 -344.700352) (xy 292.60799 -344.658061)
			(xy 292.616016 -344.57386) (xy 292.631999 -344.490801) (xy 292.655795 -344.409635) (xy 292.687189 -344.331095)
			(xy 292.725898 -344.25589) (xy 292.771572 -344.184699) (xy 292.823799 -344.118167) (xy 292.852602 -344.087196)
			(xy 292.862369 -344.076077) (xy 292.875611 -344.049625) (xy 292.88072 -344.020488) (xy 292.877266 -343.991108)
			(xy 292.865539 -343.96395) (xy 292.846523 -343.94129) (xy 292.821813 -343.925029) (xy 292.793478 -343.916529)
			(xy 292.778688 -343.916) (xy 287.977326 -343.916) (xy 287.912302 -343.927176) (xy 287.845246 -343.939114)
			(xy 287.857184 -344.007186) (xy 287.871408 -344.019124) (xy 287.904104 -344.047239) (xy 287.964472 -344.108822)
			(xy 288.018597 -344.175958) (xy 288.065969 -344.248018) (xy 288.106145 -344.324325) (xy 288.138747 -344.404162)
			(xy 288.163469 -344.486779) (xy 288.180079 -344.571401) (xy 288.18842 -344.657234) (xy 288.188908 -344.700352)
			(xy 288.18845 -344.741457) (xy 288.180869 -344.823315) (xy 288.165767 -344.904126) (xy 288.143273 -344.983197)
			(xy 288.113579 -345.059856) (xy 288.076938 -345.133448) (xy 288.033662 -345.203346) (xy 287.984122 -345.268951)
			(xy 287.92874 -345.329706) (xy 287.867988 -345.385092) (xy 287.802385 -345.434635) (xy 287.73249 -345.477914)
			(xy 287.6589 -345.514559) (xy 287.582243 -345.544257) (xy 287.503172 -345.566756) (xy 287.422363 -345.581862)
			(xy 287.340505 -345.589448) (xy 287.2994 -345.58986) (xy 287.258409 -345.589391) (xy 287.176774 -345.581847)
			(xy 287.096179 -345.566824) (xy 287.017309 -345.544449) (xy 286.940832 -345.514911) (xy 286.867398 -345.478462)
			(xy 286.797628 -345.435411) (xy 286.732117 -345.386122) (xy 286.671418 -345.331015) (xy 286.616047 -345.270556)
			(xy 286.566475 -345.205258) (xy 286.523121 -345.135677) (xy 286.486353 -345.062401) (xy 286.456484 -344.986053)
			(xy 286.433767 -344.907281) (xy 286.418394 -344.826753) (xy 286.410496 -344.745151) (xy 286.409892 -344.704162)
			(xy 286.409892 -344.700098) (xy 286.410326 -344.661132) (xy 286.417174 -344.583501) (xy 286.430782 -344.506767)
			(xy 286.451045 -344.431515) (xy 286.47781 -344.358323) (xy 286.51087 -344.28775) (xy 286.530034 -344.25382)
			(xy 286.534495 -344.245283) (xy 286.53731 -344.226244) (xy 286.532904 -344.207508) (xy 286.521899 -344.191719)
			(xy 286.505846 -344.181101) (xy 286.487009 -344.177153) (xy 286.477456 -344.178382) (xy 286.382714 -344.194892)
			(xy 286.231584 -344.257376) (xy 286.160972 -344.286586) (xy 281.432 -349.015558) (xy 281.432 -351.8408)
			(xy 285.286958 -351.8408) (xy 285.28741 -351.813429) (xy 285.295229 -351.759249) (xy 285.310721 -351.706745)
			(xy 285.333566 -351.656998) (xy 285.363295 -351.611033) (xy 285.380938 -351.590102) (xy 285.390172 -351.578773)
			(xy 285.402345 -351.552215) (xy 285.406515 -351.5233) (xy 285.402345 -351.494385) (xy 285.390172 -351.467827)
			(xy 285.380938 -351.456498) (xy 285.363297 -351.435565) (xy 285.333571 -351.389598) (xy 285.310725 -351.339852)
			(xy 285.295228 -351.28735) (xy 285.2874 -351.233171) (xy 285.2874 -351.178429) (xy 285.295228 -351.12425)
			(xy 285.310725 -351.071748) (xy 285.333571 -351.022002) (xy 285.363297 -350.976035) (xy 285.380938 -350.955102)
			(xy 285.390172 -350.943773) (xy 285.402345 -350.917215) (xy 285.406515 -350.8883) (xy 285.402345 -350.859385)
			(xy 285.390172 -350.832827) (xy 285.380938 -350.821498) (xy 285.363297 -350.800565) (xy 285.333571 -350.754598)
			(xy 285.310725 -350.704852) (xy 285.295228 -350.65235) (xy 285.2874 -350.598171) (xy 285.2874 -350.543429)
			(xy 285.295228 -350.48925) (xy 285.310725 -350.436748) (xy 285.333571 -350.387002) (xy 285.363297 -350.341035)
			(xy 285.380938 -350.320102) (xy 285.390172 -350.308773) (xy 285.402345 -350.282215) (xy 285.406515 -350.2533)
			(xy 285.402345 -350.224385) (xy 285.390172 -350.197827) (xy 285.380938 -350.186498) (xy 285.363297 -350.165565)
			(xy 285.333571 -350.119598) (xy 285.310725 -350.069852) (xy 285.295228 -350.01735) (xy 285.2874 -349.963171)
			(xy 285.2874 -349.908429) (xy 285.295228 -349.85425) (xy 285.310725 -349.801748) (xy 285.333571 -349.752002)
			(xy 285.363297 -349.706035) (xy 285.380938 -349.685102) (xy 285.390172 -349.673773) (xy 285.402345 -349.647215)
			(xy 285.406515 -349.6183) (xy 285.402345 -349.589385) (xy 285.390172 -349.562827) (xy 285.380938 -349.551498)
			(xy 285.363297 -349.530565) (xy 285.333571 -349.484598) (xy 285.310725 -349.434852) (xy 285.295228 -349.38235)
			(xy 285.2874 -349.328171) (xy 285.2874 -349.273429) (xy 285.295228 -349.21925) (xy 285.310725 -349.166748)
			(xy 285.333571 -349.117002) (xy 285.363297 -349.071035) (xy 285.380938 -349.050102) (xy 285.390172 -349.038773)
			(xy 285.402345 -349.012215) (xy 285.406515 -348.9833) (xy 285.402345 -348.954385) (xy 285.390172 -348.927827)
			(xy 285.380938 -348.916498) (xy 285.363297 -348.895565) (xy 285.333571 -348.849598) (xy 285.310725 -348.799852)
			(xy 285.295228 -348.74735) (xy 285.2874 -348.693171) (xy 285.2874 -348.638429) (xy 285.295228 -348.58425)
			(xy 285.310725 -348.531748) (xy 285.333571 -348.482002) (xy 285.363297 -348.436035) (xy 285.380938 -348.415102)
			(xy 285.390172 -348.403773) (xy 285.402345 -348.377215) (xy 285.406515 -348.3483) (xy 285.402345 -348.319385)
			(xy 285.390172 -348.292827) (xy 285.380938 -348.281498) (xy 285.36329 -348.260573) (xy 285.333579 -348.214599)
			(xy 285.310744 -348.164849) (xy 285.295255 -348.112347) (xy 285.28743 -348.05817) (xy 285.286958 -348.0308)
			(xy 285.287478 -348.00355) (xy 285.295233 -347.949606) (xy 285.310587 -347.897314) (xy 285.333225 -347.847739)
			(xy 285.362689 -347.80189) (xy 285.398376 -347.7607) (xy 285.439563 -347.725009) (xy 285.485409 -347.695542)
			(xy 285.534982 -347.672899) (xy 285.587272 -347.657541) (xy 285.641216 -347.64978) (xy 285.668466 -347.649292)
			(xy 285.695835 -347.64978) (xy 285.750013 -347.657593) (xy 285.802516 -347.673077) (xy 285.852263 -347.695914)
			(xy 285.898231 -347.725633) (xy 285.919164 -347.743272) (xy 285.930492 -347.752508) (xy 285.957049 -347.764684)
			(xy 285.985966 -347.768857) (xy 286.014883 -347.764684) (xy 286.04144 -347.752508) (xy 286.052768 -347.743272)
			(xy 286.073698 -347.72563) (xy 286.119672 -347.69592) (xy 286.16942 -347.673085) (xy 286.221921 -347.657594)
			(xy 286.276097 -347.649766) (xy 286.303466 -347.649292) (xy 286.331506 -347.649802) (xy 286.386983 -347.657998)
			(xy 286.440665 -347.67422) (xy 286.491398 -347.698118) (xy 286.53809 -347.729179) (xy 286.559244 -347.74759)
			(xy 286.570686 -347.757235) (xy 286.597729 -347.770015) (xy 286.627316 -347.774401) (xy 286.656903 -347.770015)
			(xy 286.683946 -347.757235) (xy 286.695388 -347.74759) (xy 286.71379 -347.731553) (xy 286.753943 -347.703798)
			(xy 286.797303 -347.68138) (xy 286.820102 -347.67266) (xy 286.833437 -347.667262) (xy 286.856596 -347.650215)
			(xy 286.874094 -347.627394) (xy 286.884546 -347.600604) (xy 286.887126 -347.571964) (xy 286.88163 -347.543737)
			(xy 286.868493 -347.518156) (xy 286.848753 -347.497245) (xy 286.836612 -347.489526) (xy 286.799538 -347.467197)
			(xy 286.729339 -347.416569) (xy 286.664236 -347.359536) (xy 286.604811 -347.296608) (xy 286.551597 -347.228348)
			(xy 286.505069 -347.155367) (xy 286.465642 -347.078317) (xy 286.433671 -346.997887) (xy 286.40944 -346.914797)
			(xy 286.393166 -346.829789) (xy 286.384995 -346.743624) (xy 286.384492 -346.700348) (xy 286.38498 -346.658072)
			(xy 286.392782 -346.57388) (xy 286.408318 -346.490767) (xy 286.431457 -346.409443) (xy 286.462001 -346.3306)
			(xy 286.499689 -346.254912) (xy 286.5442 -346.183024) (xy 286.595154 -346.11555) (xy 286.652117 -346.053065)
			(xy 286.714602 -345.996102) (xy 286.782076 -345.945148) (xy 286.853964 -345.900637) (xy 286.929652 -345.862949)
			(xy 287.008495 -345.832405) (xy 287.089819 -345.809266) (xy 287.172932 -345.79373) (xy 287.257124 -345.785928)
			(xy 287.341676 -345.785928) (xy 287.425868 -345.79373) (xy 287.508981 -345.809266) (xy 287.590305 -345.832405)
			(xy 287.669148 -345.862949) (xy 287.744836 -345.900637) (xy 287.816724 -345.945148) (xy 287.884198 -345.996102)
			(xy 287.946683 -346.053065) (xy 288.003646 -346.11555) (xy 288.0546 -346.183024) (xy 288.099111 -346.254912)
			(xy 288.136799 -346.3306) (xy 288.167343 -346.409443) (xy 288.190482 -346.490767) (xy 288.206018 -346.57388)
			(xy 288.21382 -346.658072) (xy 288.214308 -346.700348) (xy 292.581589 -346.700348) (xy 292.585611 -346.614628)
			(xy 292.597642 -346.52966) (xy 292.617578 -346.446193) (xy 292.645241 -346.364959) (xy 292.68039 -346.286673)
			(xy 292.722716 -346.212022) (xy 292.771845 -346.141663) (xy 292.827348 -346.076213) (xy 292.888735 -346.016249)
			(xy 292.955468 -345.962296) (xy 293.02696 -345.914829) (xy 293.102582 -345.874265) (xy 293.181671 -345.840961)
			(xy 293.263531 -345.815209) (xy 293.347442 -345.797236) (xy 293.432668 -345.7872) (xy 293.51846 -345.785188)
			(xy 293.604062 -345.791219) (xy 293.688724 -345.805239) (xy 293.771701 -345.827125) (xy 293.852264 -345.856686)
			(xy 293.929704 -345.89366) (xy 294.003343 -345.937724) (xy 294.072531 -345.98849) (xy 294.136662 -346.045511)
			(xy 294.195171 -346.108287) (xy 294.247544 -346.176267) (xy 294.293322 -346.248852) (xy 294.332102 -346.325404)
			(xy 294.363543 -346.405252) (xy 294.387369 -346.487693) (xy 294.40337 -346.572003) (xy 294.411405 -346.657441)
			(xy 294.411908 -346.700348) (xy 298.779189 -346.700348) (xy 298.783211 -346.614628) (xy 298.795242 -346.52966)
			(xy 298.815178 -346.446193) (xy 298.842841 -346.364959) (xy 298.87799 -346.286673) (xy 298.920316 -346.212022)
			(xy 298.969445 -346.141663) (xy 299.024948 -346.076213) (xy 299.086335 -346.016249) (xy 299.153068 -345.962296)
			(xy 299.22456 -345.914829) (xy 299.300182 -345.874265) (xy 299.379271 -345.840961) (xy 299.461131 -345.815209)
			(xy 299.545042 -345.797236) (xy 299.630268 -345.7872) (xy 299.71606 -345.785188) (xy 299.801662 -345.791219)
			(xy 299.886324 -345.805239) (xy 299.969301 -345.827125) (xy 300.049864 -345.856686) (xy 300.127304 -345.89366)
			(xy 300.200943 -345.937724) (xy 300.270131 -345.98849) (xy 300.334262 -346.045511) (xy 300.392771 -346.108287)
			(xy 300.445144 -346.176267) (xy 300.490922 -346.248852) (xy 300.529702 -346.325404) (xy 300.561143 -346.405252)
			(xy 300.584969 -346.487693) (xy 300.60097 -346.572003) (xy 300.609005 -346.657441) (xy 300.609508 -346.700348)
			(xy 300.609005 -346.743255) (xy 300.60097 -346.828693) (xy 300.584969 -346.913003) (xy 300.561143 -346.995444)
			(xy 300.529702 -347.075292) (xy 300.490922 -347.151844) (xy 300.445144 -347.224429) (xy 300.392771 -347.292409)
			(xy 300.334262 -347.355185) (xy 300.270131 -347.412206) (xy 300.200943 -347.462972) (xy 300.127304 -347.507036)
			(xy 300.049864 -347.54401) (xy 299.969301 -347.573571) (xy 299.886324 -347.595457) (xy 299.801662 -347.609477)
			(xy 299.71606 -347.615508) (xy 299.630268 -347.613496) (xy 299.545042 -347.60346) (xy 299.461131 -347.585487)
			(xy 299.379271 -347.559735) (xy 299.300182 -347.526431) (xy 299.22456 -347.485867) (xy 299.153068 -347.4384)
			(xy 299.086335 -347.384447) (xy 299.024948 -347.324483) (xy 298.969445 -347.259033) (xy 298.920316 -347.188674)
			(xy 298.87799 -347.114023) (xy 298.842841 -347.035737) (xy 298.815178 -346.954503) (xy 298.795242 -346.871036)
			(xy 298.783211 -346.786068) (xy 298.779189 -346.700348) (xy 294.411908 -346.700348) (xy 294.411405 -346.743255)
			(xy 294.40337 -346.828693) (xy 294.387369 -346.913003) (xy 294.363543 -346.995444) (xy 294.332102 -347.075292)
			(xy 294.293322 -347.151844) (xy 294.247544 -347.224429) (xy 294.195171 -347.292409) (xy 294.136662 -347.355185)
			(xy 294.072531 -347.412206) (xy 294.003343 -347.462972) (xy 293.929704 -347.507036) (xy 293.852264 -347.54401)
			(xy 293.771701 -347.573571) (xy 293.688724 -347.595457) (xy 293.604062 -347.609477) (xy 293.51846 -347.615508)
			(xy 293.432668 -347.613496) (xy 293.347442 -347.60346) (xy 293.263531 -347.585487) (xy 293.181671 -347.559735)
			(xy 293.102582 -347.526431) (xy 293.02696 -347.485867) (xy 292.955468 -347.4384) (xy 292.888735 -347.384447)
			(xy 292.827348 -347.324483) (xy 292.771845 -347.259033) (xy 292.722716 -347.188674) (xy 292.68039 -347.114023)
			(xy 292.645241 -347.035737) (xy 292.617578 -346.954503) (xy 292.597642 -346.871036) (xy 292.585611 -346.786068)
			(xy 292.581589 -346.700348) (xy 288.214308 -346.700348) (xy 288.21379 -346.742119) (xy 288.206161 -346.825312)
			(xy 288.190979 -346.907463) (xy 288.168372 -346.987888) (xy 288.138526 -347.065917) (xy 288.101692 -347.140901)
			(xy 288.058175 -347.212214) (xy 288.008338 -347.279263) (xy 287.952597 -347.34149) (xy 287.891415 -347.398376)
			(xy 287.825301 -347.449448) (xy 287.754807 -347.49428) (xy 287.68052 -347.532499) (xy 287.603058 -347.563786)
			(xy 287.523066 -347.587882) (xy 287.44121 -347.604585) (xy 287.358173 -347.613756) (xy 287.316418 -347.615002)
			(xy 287.302046 -347.615754) (xy 287.274565 -347.624259) (xy 287.250547 -347.640089) (xy 287.231895 -347.661989)
			(xy 287.22009 -347.688222) (xy 287.216068 -347.716706) (xy 287.220149 -347.745181) (xy 287.232008 -347.771389)
			(xy 287.24098 -347.782642) (xy 287.258186 -347.803491) (xy 287.287192 -347.849105) (xy 287.309471 -347.898356)
			(xy 287.324576 -347.950258) (xy 287.332204 -348.003772) (xy 287.332674 -348.0308) (xy 287.332214 -348.058171)
			(xy 287.324396 -348.11235) (xy 287.308906 -348.164854) (xy 287.286062 -348.2146) (xy 287.256336 -348.260567)
			(xy 287.238694 -348.281498) (xy 287.229458 -348.292825) (xy 287.217281 -348.319383) (xy 287.213109 -348.3483)
			(xy 287.217281 -348.377217) (xy 287.229458 -348.403775) (xy 287.238694 -348.415102) (xy 287.256334 -348.436035)
			(xy 287.286057 -348.482003) (xy 287.308901 -348.53175) (xy 287.324396 -348.584252) (xy 287.332225 -348.63843)
			(xy 287.332225 -348.69317) (xy 287.324396 -348.747348) (xy 287.308901 -348.79985) (xy 287.286057 -348.849597)
			(xy 287.256334 -348.895565) (xy 287.238694 -348.916498) (xy 287.229458 -348.927825) (xy 287.217281 -348.954383)
			(xy 287.213109 -348.9833) (xy 287.217281 -349.012217) (xy 287.229458 -349.038775) (xy 287.238694 -349.050102)
			(xy 287.256334 -349.071035) (xy 287.286057 -349.117003) (xy 287.308901 -349.16675) (xy 287.324396 -349.219252)
			(xy 287.332225 -349.27343) (xy 287.332225 -349.32817) (xy 287.324396 -349.382348) (xy 287.308901 -349.43485)
			(xy 287.286057 -349.484597) (xy 287.256334 -349.530565) (xy 287.238694 -349.551498) (xy 287.229458 -349.562825)
			(xy 287.217281 -349.589383) (xy 287.213109 -349.6183) (xy 287.217281 -349.647217) (xy 287.229458 -349.673775)
			(xy 287.238694 -349.685102) (xy 287.256334 -349.706035) (xy 287.286057 -349.752003) (xy 287.308901 -349.80175)
			(xy 287.324396 -349.854252) (xy 287.332225 -349.90843) (xy 287.332225 -349.96317) (xy 287.324396 -350.017348)
			(xy 287.308901 -350.06985) (xy 287.286057 -350.119597) (xy 287.256334 -350.165565) (xy 287.238694 -350.186498)
			(xy 287.229458 -350.197825) (xy 287.217281 -350.224383) (xy 287.213109 -350.2533) (xy 287.217281 -350.282217)
			(xy 287.229458 -350.308775) (xy 287.238694 -350.320102) (xy 287.256334 -350.341035) (xy 287.286057 -350.387003)
			(xy 287.308901 -350.43675) (xy 287.324396 -350.489252) (xy 287.332225 -350.54343) (xy 287.332225 -350.59817)
			(xy 287.324396 -350.652348) (xy 287.308901 -350.70485) (xy 287.286057 -350.754597) (xy 287.256334 -350.800565)
			(xy 287.238694 -350.821498) (xy 287.229458 -350.832825) (xy 287.217281 -350.859383) (xy 287.213109 -350.8883)
			(xy 287.217281 -350.917217) (xy 287.229458 -350.943775) (xy 287.238694 -350.955102) (xy 287.256334 -350.976035)
			(xy 287.286057 -351.022003) (xy 287.308901 -351.07175) (xy 287.324396 -351.124252) (xy 287.332225 -351.17843)
			(xy 287.332225 -351.23317) (xy 287.324396 -351.287348) (xy 287.308901 -351.33985) (xy 287.286057 -351.389597)
			(xy 287.256334 -351.435565) (xy 287.238694 -351.456498) (xy 287.229458 -351.467825) (xy 287.217281 -351.494383)
			(xy 287.213109 -351.5233) (xy 287.217281 -351.552217) (xy 287.229458 -351.578775) (xy 287.238694 -351.590102)
			(xy 287.256347 -351.611023) (xy 287.286057 -351.656999) (xy 287.30889 -351.706749) (xy 287.324378 -351.759252)
			(xy 287.332202 -351.81343) (xy 287.332674 -351.8408) (xy 290.25723 -351.8408) (xy 290.257689 -351.813429)
			(xy 290.265507 -351.75925) (xy 290.280998 -351.706746) (xy 290.303841 -351.656999) (xy 290.333568 -351.611033)
			(xy 290.35121 -351.590102) (xy 290.360446 -351.578774) (xy 290.372622 -351.552217) (xy 290.376794 -351.5233)
			(xy 290.372622 -351.494383) (xy 290.360446 -351.467826) (xy 290.35121 -351.456498) (xy 290.33357 -351.435565)
			(xy 290.303847 -351.389597) (xy 290.281002 -351.33985) (xy 290.265507 -351.287349) (xy 290.257678 -351.23317)
			(xy 290.257678 -351.17843) (xy 290.265507 -351.124251) (xy 290.281002 -351.07175) (xy 290.303847 -351.022003)
			(xy 290.33357 -350.976035) (xy 290.35121 -350.955102) (xy 290.360446 -350.943774) (xy 290.372622 -350.917217)
			(xy 290.376794 -350.8883) (xy 290.372622 -350.859383) (xy 290.360446 -350.832826) (xy 290.35121 -350.821498)
			(xy 290.33357 -350.800565) (xy 290.303847 -350.754597) (xy 290.281002 -350.70485) (xy 290.265507 -350.652349)
			(xy 290.257678 -350.59817) (xy 290.257678 -350.54343) (xy 290.265507 -350.489251) (xy 290.281002 -350.43675)
			(xy 290.303847 -350.387003) (xy 290.33357 -350.341035) (xy 290.35121 -350.320102) (xy 290.360446 -350.308774)
			(xy 290.372622 -350.282217) (xy 290.376794 -350.2533) (xy 290.372622 -350.224383) (xy 290.360446 -350.197826)
			(xy 290.35121 -350.186498) (xy 290.33357 -350.165565) (xy 290.303847 -350.119597) (xy 290.281002 -350.06985)
			(xy 290.265507 -350.017349) (xy 290.257678 -349.96317) (xy 290.257678 -349.90843) (xy 290.265507 -349.854251)
			(xy 290.281002 -349.80175) (xy 290.303847 -349.752003) (xy 290.33357 -349.706035) (xy 290.35121 -349.685102)
			(xy 290.360446 -349.673774) (xy 290.372622 -349.647217) (xy 290.376794 -349.6183) (xy 290.372622 -349.589383)
			(xy 290.360446 -349.562826) (xy 290.35121 -349.551498) (xy 290.33357 -349.530565) (xy 290.303847 -349.484597)
			(xy 290.281002 -349.43485) (xy 290.265507 -349.382349) (xy 290.257678 -349.32817) (xy 290.257678 -349.27343)
			(xy 290.265507 -349.219251) (xy 290.281002 -349.16675) (xy 290.303847 -349.117003) (xy 290.33357 -349.071035)
			(xy 290.35121 -349.050102) (xy 290.360446 -349.038774) (xy 290.372622 -349.012217) (xy 290.376794 -348.9833)
			(xy 290.372622 -348.954383) (xy 290.360446 -348.927826) (xy 290.35121 -348.916498) (xy 290.33357 -348.895565)
			(xy 290.303847 -348.849597) (xy 290.281002 -348.79985) (xy 290.265507 -348.747349) (xy 290.257678 -348.69317)
			(xy 290.257678 -348.63843) (xy 290.265507 -348.584251) (xy 290.281002 -348.53175) (xy 290.303847 -348.482003)
			(xy 290.33357 -348.436035) (xy 290.35121 -348.415102) (xy 290.360446 -348.403774) (xy 290.372622 -348.377217)
			(xy 290.376794 -348.3483) (xy 290.372622 -348.319383) (xy 290.360446 -348.292826) (xy 290.35121 -348.281498)
			(xy 290.333558 -348.260576) (xy 290.303848 -348.214601) (xy 290.281014 -348.164851) (xy 290.265526 -348.112348)
			(xy 290.257702 -348.05817) (xy 290.25723 -348.0308) (xy 290.257655 -348.003545) (xy 290.265413 -347.949591)
			(xy 290.280771 -347.89729) (xy 290.303417 -347.847708) (xy 290.332888 -347.801853) (xy 290.368586 -347.760659)
			(xy 290.409783 -347.724965) (xy 290.455641 -347.695498) (xy 290.505226 -347.672858) (xy 290.557528 -347.657505)
			(xy 290.611483 -347.649753) (xy 290.638738 -347.649292) (xy 290.666779 -347.649759) (xy 290.722259 -347.657966)
			(xy 290.775941 -347.674198) (xy 290.826673 -347.698105) (xy 290.873363 -347.729175) (xy 290.894516 -347.74759)
			(xy 290.905958 -347.757235) (xy 290.933001 -347.770015) (xy 290.962588 -347.774401) (xy 290.992175 -347.770015)
			(xy 291.019218 -347.757235) (xy 291.03066 -347.74759) (xy 291.051808 -347.729166) (xy 291.098486 -347.698072)
			(xy 291.149217 -347.674157) (xy 291.202907 -347.657938) (xy 291.258395 -347.649765) (xy 291.286438 -347.649292)
			(xy 291.313807 -347.649796) (xy 291.367984 -347.657605) (xy 291.420487 -347.673085) (xy 291.470234 -347.695919)
			(xy 291.516203 -347.725635) (xy 291.537136 -347.743272) (xy 291.548464 -347.752508) (xy 291.575021 -347.764684)
			(xy 291.603938 -347.768857) (xy 291.632855 -347.764684) (xy 291.659412 -347.752508) (xy 291.67074 -347.743272)
			(xy 291.69168 -347.725643) (xy 291.737651 -347.695931) (xy 291.787397 -347.673093) (xy 291.839895 -347.6576)
			(xy 291.894069 -347.649768) (xy 291.921438 -347.649292) (xy 291.94869 -347.649742) (xy 292.002639 -347.657504)
			(xy 292.054935 -347.672864) (xy 292.104512 -347.69551) (xy 292.150362 -347.72498) (xy 292.191552 -347.760675)
			(xy 292.227243 -347.801868) (xy 292.256709 -347.847721) (xy 292.279349 -347.897301) (xy 292.294704 -347.949598)
			(xy 292.30246 -348.003548) (xy 292.302946 -348.0308) (xy 292.302493 -348.058171) (xy 292.294674 -348.112351)
			(xy 292.279183 -348.164855) (xy 292.256338 -348.214602) (xy 292.226609 -348.260567) (xy 292.208966 -348.281498)
			(xy 292.199732 -348.292826) (xy 292.187559 -348.319384) (xy 292.183388 -348.3483) (xy 292.187559 -348.377216)
			(xy 292.199732 -348.403774) (xy 292.208966 -348.415102) (xy 292.226607 -348.436035) (xy 292.256332 -348.482002)
			(xy 292.279178 -348.531748) (xy 292.294675 -348.584251) (xy 292.302503 -348.638429) (xy 292.302503 -348.693171)
			(xy 292.294675 -348.747349) (xy 292.279178 -348.799852) (xy 292.256332 -348.849598) (xy 292.226607 -348.895565)
			(xy 292.208966 -348.916498) (xy 292.199732 -348.927826) (xy 292.187559 -348.954384) (xy 292.183388 -348.9833)
			(xy 292.187559 -349.012216) (xy 292.199732 -349.038774) (xy 292.208966 -349.050102) (xy 292.226607 -349.071035)
			(xy 292.256332 -349.117002) (xy 292.279178 -349.166748) (xy 292.294675 -349.219251) (xy 292.302503 -349.273429)
			(xy 292.302503 -349.328171) (xy 292.294675 -349.382349) (xy 292.279178 -349.434852) (xy 292.256332 -349.484598)
			(xy 292.226607 -349.530565) (xy 292.208966 -349.551498) (xy 292.199732 -349.562826) (xy 292.187559 -349.589384)
			(xy 292.183388 -349.6183) (xy 292.187559 -349.647216) (xy 292.199732 -349.673774) (xy 292.208966 -349.685102)
			(xy 292.226607 -349.706035) (xy 292.256332 -349.752002) (xy 292.279178 -349.801748) (xy 292.294675 -349.854251)
			(xy 292.302503 -349.908429) (xy 292.302503 -349.963171) (xy 292.294675 -350.017349) (xy 292.279178 -350.069852)
			(xy 292.256332 -350.119598) (xy 292.226607 -350.165565) (xy 292.208966 -350.186498) (xy 292.199732 -350.197826)
			(xy 292.187559 -350.224384) (xy 292.183388 -350.2533) (xy 292.187559 -350.282216) (xy 292.199732 -350.308774)
			(xy 292.208966 -350.320102) (xy 292.226607 -350.341035) (xy 292.256332 -350.387002) (xy 292.279178 -350.436748)
			(xy 292.294675 -350.489251) (xy 292.302503 -350.543429) (xy 292.302503 -350.598171) (xy 292.294675 -350.652349)
			(xy 292.279178 -350.704852) (xy 292.256332 -350.754598) (xy 292.226607 -350.800565) (xy 292.208966 -350.821498)
			(xy 292.199732 -350.832826) (xy 292.187559 -350.859384) (xy 292.183388 -350.8883) (xy 292.187559 -350.917216)
			(xy 292.199732 -350.943774) (xy 292.208966 -350.955102) (xy 292.226607 -350.976035) (xy 292.256332 -351.022002)
			(xy 292.279178 -351.071748) (xy 292.294675 -351.124251) (xy 292.302503 -351.178429) (xy 292.302503 -351.233171)
			(xy 292.294675 -351.287349) (xy 292.279178 -351.339852) (xy 292.256332 -351.389598) (xy 292.226607 -351.435565)
			(xy 292.208966 -351.456498) (xy 292.199732 -351.467826) (xy 292.187559 -351.494384) (xy 292.183388 -351.5233)
			(xy 292.187559 -351.552216) (xy 292.199732 -351.578774) (xy 292.208966 -351.590102) (xy 292.226614 -351.611027)
			(xy 292.256326 -351.657001) (xy 292.279161 -351.70675) (xy 292.294649 -351.759253) (xy 292.302474 -351.81343)
			(xy 292.302946 -351.8408) (xy 294.964358 -351.8408) (xy 294.96481 -351.813429) (xy 294.972629 -351.759249)
			(xy 294.988121 -351.706745) (xy 295.010966 -351.656998) (xy 295.040695 -351.611033) (xy 295.058338 -351.590102)
			(xy 295.067572 -351.578773) (xy 295.079745 -351.552215) (xy 295.083915 -351.5233) (xy 295.079745 -351.494385)
			(xy 295.067572 -351.467827) (xy 295.058338 -351.456498) (xy 295.040697 -351.435565) (xy 295.010971 -351.389598)
			(xy 294.988125 -351.339852) (xy 294.972628 -351.28735) (xy 294.9648 -351.233171) (xy 294.9648 -351.178429)
			(xy 294.972628 -351.12425) (xy 294.988125 -351.071748) (xy 295.010971 -351.022002) (xy 295.040697 -350.976035)
			(xy 295.058338 -350.955102) (xy 295.067572 -350.943773) (xy 295.079745 -350.917215) (xy 295.083915 -350.8883)
			(xy 295.079745 -350.859385) (xy 295.067572 -350.832827) (xy 295.058338 -350.821498) (xy 295.040697 -350.800565)
			(xy 295.010971 -350.754598) (xy 294.988125 -350.704852) (xy 294.972628 -350.65235) (xy 294.9648 -350.598171)
			(xy 294.9648 -350.543429) (xy 294.972628 -350.48925) (xy 294.988125 -350.436748) (xy 295.010971 -350.387002)
			(xy 295.040697 -350.341035) (xy 295.058338 -350.320102) (xy 295.067572 -350.308773) (xy 295.079745 -350.282215)
			(xy 295.083915 -350.2533) (xy 295.079745 -350.224385) (xy 295.067572 -350.197827) (xy 295.058338 -350.186498)
			(xy 295.040697 -350.165565) (xy 295.010971 -350.119598) (xy 294.988125 -350.069852) (xy 294.972628 -350.01735)
			(xy 294.9648 -349.963171) (xy 294.9648 -349.908429) (xy 294.972628 -349.85425) (xy 294.988125 -349.801748)
			(xy 295.010971 -349.752002) (xy 295.040697 -349.706035) (xy 295.058338 -349.685102) (xy 295.067572 -349.673773)
			(xy 295.079745 -349.647215) (xy 295.083915 -349.6183) (xy 295.079745 -349.589385) (xy 295.067572 -349.562827)
			(xy 295.058338 -349.551498) (xy 295.040697 -349.530565) (xy 295.010971 -349.484598) (xy 294.988125 -349.434852)
			(xy 294.972628 -349.38235) (xy 294.9648 -349.328171) (xy 294.9648 -349.273429) (xy 294.972628 -349.21925)
			(xy 294.988125 -349.166748) (xy 295.010971 -349.117002) (xy 295.040697 -349.071035) (xy 295.058338 -349.050102)
			(xy 295.067572 -349.038773) (xy 295.079745 -349.012215) (xy 295.083915 -348.9833) (xy 295.079745 -348.954385)
			(xy 295.067572 -348.927827) (xy 295.058338 -348.916498) (xy 295.040697 -348.895565) (xy 295.010971 -348.849598)
			(xy 294.988125 -348.799852) (xy 294.972628 -348.74735) (xy 294.9648 -348.693171) (xy 294.9648 -348.638429)
			(xy 294.972628 -348.58425) (xy 294.988125 -348.531748) (xy 295.010971 -348.482002) (xy 295.040697 -348.436035)
			(xy 295.058338 -348.415102) (xy 295.067572 -348.403773) (xy 295.079745 -348.377215) (xy 295.083915 -348.3483)
			(xy 295.079745 -348.319385) (xy 295.067572 -348.292827) (xy 295.058338 -348.281498) (xy 295.04069 -348.260573)
			(xy 295.010979 -348.214599) (xy 294.988144 -348.164849) (xy 294.972655 -348.112347) (xy 294.96483 -348.05817)
			(xy 294.964358 -348.0308) (xy 294.964878 -348.00355) (xy 294.972633 -347.949606) (xy 294.987987 -347.897314)
			(xy 295.010625 -347.847739) (xy 295.040089 -347.80189) (xy 295.075776 -347.7607) (xy 295.116963 -347.725009)
			(xy 295.162809 -347.695542) (xy 295.212382 -347.672899) (xy 295.264672 -347.657541) (xy 295.318616 -347.64978)
			(xy 295.345866 -347.649292) (xy 295.373235 -347.64978) (xy 295.427413 -347.657593) (xy 295.479916 -347.673077)
			(xy 295.529663 -347.695914) (xy 295.575631 -347.725633) (xy 295.596564 -347.743272) (xy 295.607892 -347.752508)
			(xy 295.634449 -347.764684) (xy 295.663366 -347.768857) (xy 295.692283 -347.764684) (xy 295.71884 -347.752508)
			(xy 295.730168 -347.743272) (xy 295.751098 -347.72563) (xy 295.797072 -347.69592) (xy 295.84682 -347.673085)
			(xy 295.899321 -347.657594) (xy 295.953497 -347.649766) (xy 295.980866 -347.649292) (xy 296.008906 -347.649802)
			(xy 296.064383 -347.657998) (xy 296.118065 -347.67422) (xy 296.168798 -347.698118) (xy 296.21549 -347.729179)
			(xy 296.236644 -347.74759) (xy 296.248086 -347.757235) (xy 296.275129 -347.770015) (xy 296.304716 -347.774401)
			(xy 296.334303 -347.770015) (xy 296.361346 -347.757235) (xy 296.372788 -347.74759) (xy 296.393925 -347.729153)
			(xy 296.440606 -347.698061) (xy 296.49134 -347.674149) (xy 296.545032 -347.657932) (xy 296.600522 -347.649763)
			(xy 296.628566 -347.649292) (xy 296.655818 -347.649787) (xy 296.709768 -347.657539) (xy 296.762065 -347.672891)
			(xy 296.811645 -347.69553) (xy 296.857498 -347.724994) (xy 296.898691 -347.760684) (xy 296.934386 -347.801874)
			(xy 296.963854 -347.847725) (xy 296.986497 -347.897303) (xy 297.001853 -347.949599) (xy 297.009611 -348.003548)
			(xy 297.010074 -348.0308) (xy 297.009614 -348.058171) (xy 297.001796 -348.11235) (xy 296.986306 -348.164854)
			(xy 296.963462 -348.2146) (xy 296.933736 -348.260567) (xy 296.916094 -348.281498) (xy 296.906858 -348.292825)
			(xy 296.894681 -348.319383) (xy 296.890509 -348.3483) (xy 296.894681 -348.377217) (xy 296.906858 -348.403775)
			(xy 296.916094 -348.415102) (xy 296.933734 -348.436035) (xy 296.963457 -348.482003) (xy 296.986301 -348.53175)
			(xy 297.001796 -348.584252) (xy 297.009625 -348.63843) (xy 297.009625 -348.69317) (xy 297.001796 -348.747348)
			(xy 296.986301 -348.79985) (xy 296.963457 -348.849597) (xy 296.933734 -348.895565) (xy 296.916094 -348.916498)
			(xy 296.906858 -348.927825) (xy 296.894681 -348.954383) (xy 296.890509 -348.9833) (xy 296.894681 -349.012217)
			(xy 296.906858 -349.038775) (xy 296.916094 -349.050102) (xy 296.933734 -349.071035) (xy 296.963457 -349.117003)
			(xy 296.986301 -349.16675) (xy 297.001796 -349.219252) (xy 297.009625 -349.27343) (xy 297.009625 -349.32817)
			(xy 297.001796 -349.382348) (xy 296.986301 -349.43485) (xy 296.963457 -349.484597) (xy 296.933734 -349.530565)
			(xy 296.916094 -349.551498) (xy 296.906858 -349.562825) (xy 296.894681 -349.589383) (xy 296.890509 -349.6183)
			(xy 296.894681 -349.647217) (xy 296.906858 -349.673775) (xy 296.916094 -349.685102) (xy 296.933734 -349.706035)
			(xy 296.963457 -349.752003) (xy 296.986301 -349.80175) (xy 297.001796 -349.854252) (xy 297.009625 -349.90843)
			(xy 297.009625 -349.96317) (xy 297.001796 -350.017348) (xy 296.986301 -350.06985) (xy 296.963457 -350.119597)
			(xy 296.933734 -350.165565) (xy 296.916094 -350.186498) (xy 296.906858 -350.197825) (xy 296.894681 -350.224383)
			(xy 296.890509 -350.2533) (xy 296.894681 -350.282217) (xy 296.906858 -350.308775) (xy 296.916094 -350.320102)
			(xy 296.933734 -350.341035) (xy 296.963457 -350.387003) (xy 296.986301 -350.43675) (xy 297.001796 -350.489252)
			(xy 297.009625 -350.54343) (xy 297.009625 -350.59817) (xy 297.001796 -350.652348) (xy 296.986301 -350.70485)
			(xy 296.963457 -350.754597) (xy 296.933734 -350.800565) (xy 296.916094 -350.821498) (xy 296.906858 -350.832825)
			(xy 296.894681 -350.859383) (xy 296.890509 -350.8883) (xy 296.894681 -350.917217) (xy 296.906858 -350.943775)
			(xy 296.916094 -350.955102) (xy 296.933734 -350.976035) (xy 296.963457 -351.022003) (xy 296.986301 -351.07175)
			(xy 297.001796 -351.124252) (xy 297.009625 -351.17843) (xy 297.009625 -351.23317) (xy 297.001796 -351.287348)
			(xy 296.986301 -351.33985) (xy 296.963457 -351.389597) (xy 296.933734 -351.435565) (xy 296.916094 -351.456498)
			(xy 296.906858 -351.467825) (xy 296.894681 -351.494383) (xy 296.890509 -351.5233) (xy 296.894681 -351.552217)
			(xy 296.906858 -351.578775) (xy 296.916094 -351.590102) (xy 296.933747 -351.611023) (xy 296.963457 -351.656999)
			(xy 296.98629 -351.706749) (xy 297.001778 -351.759252) (xy 297.009602 -351.81343) (xy 297.010074 -351.8408)
			(xy 300.03623 -351.8408) (xy 300.036689 -351.813429) (xy 300.044507 -351.75925) (xy 300.059998 -351.706746)
			(xy 300.082841 -351.656999) (xy 300.112568 -351.611033) (xy 300.13021 -351.590102) (xy 300.139446 -351.578774)
			(xy 300.151622 -351.552217) (xy 300.155794 -351.5233) (xy 300.151622 -351.494383) (xy 300.139446 -351.467826)
			(xy 300.13021 -351.456498) (xy 300.11257 -351.435565) (xy 300.082847 -351.389597) (xy 300.060002 -351.33985)
			(xy 300.044507 -351.287349) (xy 300.036678 -351.23317) (xy 300.036678 -351.17843) (xy 300.044507 -351.124251)
			(xy 300.060002 -351.07175) (xy 300.082847 -351.022003) (xy 300.11257 -350.976035) (xy 300.13021 -350.955102)
			(xy 300.139446 -350.943774) (xy 300.151622 -350.917217) (xy 300.155794 -350.8883) (xy 300.151622 -350.859383)
			(xy 300.139446 -350.832826) (xy 300.13021 -350.821498) (xy 300.11257 -350.800565) (xy 300.082847 -350.754597)
			(xy 300.060002 -350.70485) (xy 300.044507 -350.652349) (xy 300.036678 -350.59817) (xy 300.036678 -350.54343)
			(xy 300.044507 -350.489251) (xy 300.060002 -350.43675) (xy 300.082847 -350.387003) (xy 300.11257 -350.341035)
			(xy 300.13021 -350.320102) (xy 300.139446 -350.308774) (xy 300.151622 -350.282217) (xy 300.155794 -350.2533)
			(xy 300.151622 -350.224383) (xy 300.139446 -350.197826) (xy 300.13021 -350.186498) (xy 300.11257 -350.165565)
			(xy 300.082847 -350.119597) (xy 300.060002 -350.06985) (xy 300.044507 -350.017349) (xy 300.036678 -349.96317)
			(xy 300.036678 -349.90843) (xy 300.044507 -349.854251) (xy 300.060002 -349.80175) (xy 300.082847 -349.752003)
			(xy 300.11257 -349.706035) (xy 300.13021 -349.685102) (xy 300.139446 -349.673774) (xy 300.151622 -349.647217)
			(xy 300.155794 -349.6183) (xy 300.151622 -349.589383) (xy 300.139446 -349.562826) (xy 300.13021 -349.551498)
			(xy 300.11257 -349.530565) (xy 300.082847 -349.484597) (xy 300.060002 -349.43485) (xy 300.044507 -349.382349)
			(xy 300.036678 -349.32817) (xy 300.036678 -349.27343) (xy 300.044507 -349.219251) (xy 300.060002 -349.16675)
			(xy 300.082847 -349.117003) (xy 300.11257 -349.071035) (xy 300.13021 -349.050102) (xy 300.139446 -349.038774)
			(xy 300.151622 -349.012217) (xy 300.155794 -348.9833) (xy 300.151622 -348.954383) (xy 300.139446 -348.927826)
			(xy 300.13021 -348.916498) (xy 300.11257 -348.895565) (xy 300.082847 -348.849597) (xy 300.060002 -348.79985)
			(xy 300.044507 -348.747349) (xy 300.036678 -348.69317) (xy 300.036678 -348.63843) (xy 300.044507 -348.584251)
			(xy 300.060002 -348.53175) (xy 300.082847 -348.482003) (xy 300.11257 -348.436035) (xy 300.13021 -348.415102)
			(xy 300.139446 -348.403774) (xy 300.151622 -348.377217) (xy 300.155794 -348.3483) (xy 300.151622 -348.319383)
			(xy 300.139446 -348.292826) (xy 300.13021 -348.281498) (xy 300.112558 -348.260576) (xy 300.082848 -348.214601)
			(xy 300.060014 -348.164851) (xy 300.044526 -348.112348) (xy 300.036702 -348.05817) (xy 300.03623 -348.0308)
			(xy 300.036655 -348.003545) (xy 300.044413 -347.949591) (xy 300.059771 -347.89729) (xy 300.082417 -347.847708)
			(xy 300.111888 -347.801853) (xy 300.147586 -347.760659) (xy 300.188783 -347.724965) (xy 300.234641 -347.695498)
			(xy 300.284226 -347.672858) (xy 300.336528 -347.657505) (xy 300.390483 -347.649753) (xy 300.417738 -347.649292)
			(xy 300.445779 -347.649759) (xy 300.501259 -347.657966) (xy 300.554941 -347.674198) (xy 300.605673 -347.698105)
			(xy 300.652363 -347.729175) (xy 300.673516 -347.74759) (xy 300.684958 -347.757235) (xy 300.712001 -347.770015)
			(xy 300.741588 -347.774401) (xy 300.771175 -347.770015) (xy 300.798218 -347.757235) (xy 300.80966 -347.74759)
			(xy 300.830808 -347.729166) (xy 300.877486 -347.698072) (xy 300.928217 -347.674157) (xy 300.981907 -347.657938)
			(xy 301.037395 -347.649765) (xy 301.065438 -347.649292) (xy 301.092807 -347.649796) (xy 301.146984 -347.657605)
			(xy 301.199487 -347.673085) (xy 301.249234 -347.695919) (xy 301.295203 -347.725635) (xy 301.316136 -347.743272)
			(xy 301.327464 -347.752508) (xy 301.354021 -347.764684) (xy 301.382938 -347.768857) (xy 301.411855 -347.764684)
			(xy 301.438412 -347.752508) (xy 301.44974 -347.743272) (xy 301.47068 -347.725643) (xy 301.516651 -347.695931)
			(xy 301.566397 -347.673093) (xy 301.618895 -347.6576) (xy 301.673069 -347.649768) (xy 301.700438 -347.649292)
			(xy 301.72769 -347.649742) (xy 301.781639 -347.657504) (xy 301.833935 -347.672864) (xy 301.883512 -347.69551)
			(xy 301.929362 -347.72498) (xy 301.970552 -347.760675) (xy 302.006243 -347.801868) (xy 302.035709 -347.847721)
			(xy 302.058349 -347.897301) (xy 302.073704 -347.949598) (xy 302.08146 -348.003548) (xy 302.081946 -348.0308)
			(xy 302.081493 -348.058171) (xy 302.073674 -348.112351) (xy 302.058183 -348.164855) (xy 302.035338 -348.214602)
			(xy 302.005609 -348.260567) (xy 301.987966 -348.281498) (xy 301.978732 -348.292826) (xy 301.966559 -348.319384)
			(xy 301.962388 -348.3483) (xy 301.966559 -348.377216) (xy 301.978732 -348.403774) (xy 301.987966 -348.415102)
			(xy 302.005607 -348.436035) (xy 302.035332 -348.482002) (xy 302.058178 -348.531748) (xy 302.073675 -348.584251)
			(xy 302.081503 -348.638429) (xy 302.081503 -348.693171) (xy 302.073675 -348.747349) (xy 302.058178 -348.799852)
			(xy 302.035332 -348.849598) (xy 302.005607 -348.895565) (xy 301.987966 -348.916498) (xy 301.978732 -348.927826)
			(xy 301.966559 -348.954384) (xy 301.962388 -348.9833) (xy 301.966559 -349.012216) (xy 301.978732 -349.038774)
			(xy 301.987966 -349.050102) (xy 302.005607 -349.071035) (xy 302.035332 -349.117002) (xy 302.058178 -349.166748)
			(xy 302.073675 -349.219251) (xy 302.081503 -349.273429) (xy 302.081503 -349.328171) (xy 302.073675 -349.382349)
			(xy 302.058178 -349.434852) (xy 302.035332 -349.484598) (xy 302.005607 -349.530565) (xy 301.987966 -349.551498)
			(xy 301.978732 -349.562826) (xy 301.966559 -349.589384) (xy 301.962388 -349.6183) (xy 301.966559 -349.647216)
			(xy 301.978732 -349.673774) (xy 301.987966 -349.685102) (xy 302.005607 -349.706035) (xy 302.035332 -349.752002)
			(xy 302.058178 -349.801748) (xy 302.073675 -349.854251) (xy 302.081503 -349.908429) (xy 302.081503 -349.963171)
			(xy 302.073675 -350.017349) (xy 302.058178 -350.069852) (xy 302.035332 -350.119598) (xy 302.005607 -350.165565)
			(xy 301.987966 -350.186498) (xy 301.978732 -350.197826) (xy 301.966559 -350.224384) (xy 301.962388 -350.2533)
			(xy 301.966559 -350.282216) (xy 301.978732 -350.308774) (xy 301.987966 -350.320102) (xy 302.005607 -350.341035)
			(xy 302.035332 -350.387002) (xy 302.058178 -350.436748) (xy 302.073675 -350.489251) (xy 302.081503 -350.543429)
			(xy 302.081503 -350.598171) (xy 302.073675 -350.652349) (xy 302.058178 -350.704852) (xy 302.035332 -350.754598)
			(xy 302.005607 -350.800565) (xy 301.987966 -350.821498) (xy 301.978732 -350.832826) (xy 301.966559 -350.859384)
			(xy 301.962388 -350.8883) (xy 301.966559 -350.917216) (xy 301.978732 -350.943774) (xy 301.987966 -350.955102)
			(xy 302.005607 -350.976035) (xy 302.035332 -351.022002) (xy 302.058178 -351.071748) (xy 302.073675 -351.124251)
			(xy 302.081503 -351.178429) (xy 302.081503 -351.233171) (xy 302.073675 -351.287349) (xy 302.058178 -351.339852)
			(xy 302.035332 -351.389598) (xy 302.005607 -351.435565) (xy 301.987966 -351.456498) (xy 301.978732 -351.467826)
			(xy 301.966559 -351.494384) (xy 301.962388 -351.5233) (xy 301.966559 -351.552216) (xy 301.978732 -351.578774)
			(xy 301.987966 -351.590102) (xy 302.005614 -351.611027) (xy 302.035326 -351.657001) (xy 302.058161 -351.70675)
			(xy 302.073649 -351.759253) (xy 302.081474 -351.81343) (xy 302.081946 -351.8408) (xy 302.081422 -351.86805)
			(xy 302.073667 -351.921994) (xy 302.058314 -351.974286) (xy 302.035675 -352.02386) (xy 302.006212 -352.069709)
			(xy 301.970525 -352.110898) (xy 301.929339 -352.14659) (xy 301.883494 -352.176057) (xy 301.833921 -352.1987)
			(xy 301.781631 -352.214059) (xy 301.727687 -352.22182) (xy 301.700438 -352.222308) (xy 301.673069 -352.221818)
			(xy 301.618891 -352.214005) (xy 301.566388 -352.198522) (xy 301.516641 -352.175686) (xy 301.470673 -352.145967)
			(xy 301.44974 -352.128328) (xy 301.438412 -352.119092) (xy 301.411855 -352.106916) (xy 301.382938 -352.102743)
			(xy 301.354021 -352.106916) (xy 301.327464 -352.119092) (xy 301.316136 -352.128328) (xy 301.295205 -352.145968)
			(xy 301.249231 -352.175679) (xy 301.199484 -352.198514) (xy 301.146983 -352.214005) (xy 301.092807 -352.221834)
			(xy 301.065438 -352.222308) (xy 301.037398 -352.221796) (xy 300.981921 -352.2136) (xy 300.928239 -352.197379)
			(xy 300.877507 -352.173481) (xy 300.830814 -352.142421) (xy 300.80966 -352.12401) (xy 300.798218 -352.114365)
			(xy 300.771175 -352.101585) (xy 300.741588 -352.097199) (xy 300.712001 -352.101585) (xy 300.684958 -352.114365)
			(xy 300.673516 -352.12401) (xy 300.652378 -352.142445) (xy 300.605697 -352.173537) (xy 300.554963 -352.19745)
			(xy 300.501271 -352.213667) (xy 300.445782 -352.221837) (xy 300.417738 -352.222308) (xy 300.390486 -352.221809)
			(xy 300.336536 -352.214058) (xy 300.284239 -352.198706) (xy 300.234659 -352.176068) (xy 300.188806 -352.146604)
			(xy 300.147613 -352.110914) (xy 300.111919 -352.069725) (xy 300.08245 -352.023874) (xy 300.059807 -351.974296)
			(xy 300.044451 -351.922001) (xy 300.036693 -351.868052) (xy 300.03623 -351.8408) (xy 297.010074 -351.8408)
			(xy 297.009645 -351.868054) (xy 297.001887 -351.922008) (xy 296.986529 -351.974309) (xy 296.963884 -352.023891)
			(xy 296.934413 -352.069746) (xy 296.898715 -352.11094) (xy 296.857519 -352.146633) (xy 296.811661 -352.1761)
			(xy 296.762077 -352.198741) (xy 296.709775 -352.214094) (xy 296.65582 -352.221847) (xy 296.628566 -352.222308)
			(xy 296.600525 -352.221839) (xy 296.545046 -352.213632) (xy 296.491363 -352.197401) (xy 296.440631 -352.173494)
			(xy 296.393941 -352.142425) (xy 296.372788 -352.12401) (xy 296.361346 -352.114365) (xy 296.334303 -352.101585)
			(xy 296.304716 -352.097199) (xy 296.275129 -352.101585) (xy 296.248086 -352.114365) (xy 296.236644 -352.12401)
			(xy 296.215495 -352.142432) (xy 296.168817 -352.173526) (xy 296.118086 -352.197441) (xy 296.064396 -352.213661)
			(xy 296.008909 -352.221835) (xy 295.980866 -352.222308) (xy 295.953495 -352.22186) (xy 295.899315 -352.214037)
			(xy 295.846812 -352.198544) (xy 295.797066 -352.175698) (xy 295.751099 -352.145971) (xy 295.730168 -352.128328)
			(xy 295.71884 -352.119092) (xy 295.692283 -352.106916) (xy 295.663366 -352.102743) (xy 295.634449 -352.106916)
			(xy 295.607892 -352.119092) (xy 295.596564 -352.128328) (xy 295.575622 -352.145955) (xy 295.529652 -352.175668)
			(xy 295.479907 -352.198505) (xy 295.427408 -352.213999) (xy 295.373234 -352.221832) (xy 295.345866 -352.222308)
			(xy 295.318614 -352.221854) (xy 295.264665 -352.214093) (xy 295.21237 -352.198733) (xy 295.162792 -352.176088)
			(xy 295.116942 -352.146618) (xy 295.075752 -352.110924) (xy 295.040061 -352.069731) (xy 295.010596 -352.023878)
			(xy 294.987955 -351.974298) (xy 294.9726 -351.922002) (xy 294.964844 -351.868052) (xy 294.964358 -351.8408)
			(xy 292.302946 -351.8408) (xy 292.302422 -351.86805) (xy 292.294667 -351.921994) (xy 292.279314 -351.974286)
			(xy 292.256675 -352.02386) (xy 292.227212 -352.069709) (xy 292.191525 -352.110898) (xy 292.150339 -352.14659)
			(xy 292.104494 -352.176057) (xy 292.054921 -352.1987) (xy 292.002631 -352.214059) (xy 291.948687 -352.22182)
			(xy 291.921438 -352.222308) (xy 291.894069 -352.221818) (xy 291.839891 -352.214005) (xy 291.787388 -352.198522)
			(xy 291.737641 -352.175686) (xy 291.691673 -352.145967) (xy 291.67074 -352.128328) (xy 291.659412 -352.119092)
			(xy 291.632855 -352.106916) (xy 291.603938 -352.102743) (xy 291.575021 -352.106916) (xy 291.548464 -352.119092)
			(xy 291.537136 -352.128328) (xy 291.516205 -352.145968) (xy 291.470231 -352.175679) (xy 291.420484 -352.198514)
			(xy 291.367983 -352.214005) (xy 291.313807 -352.221834) (xy 291.286438 -352.222308) (xy 291.258398 -352.221796)
			(xy 291.202921 -352.2136) (xy 291.149239 -352.197379) (xy 291.098507 -352.173481) (xy 291.051814 -352.142421)
			(xy 291.03066 -352.12401) (xy 291.019218 -352.114365) (xy 290.992175 -352.101585) (xy 290.962588 -352.097199)
			(xy 290.933001 -352.101585) (xy 290.905958 -352.114365) (xy 290.894516 -352.12401) (xy 290.873378 -352.142445)
			(xy 290.826697 -352.173537) (xy 290.775963 -352.19745) (xy 290.722271 -352.213667) (xy 290.666782 -352.221837)
			(xy 290.638738 -352.222308) (xy 290.611486 -352.221809) (xy 290.557536 -352.214058) (xy 290.505239 -352.198706)
			(xy 290.455659 -352.176068) (xy 290.409806 -352.146604) (xy 290.368613 -352.110914) (xy 290.332919 -352.069725)
			(xy 290.30345 -352.023874) (xy 290.280807 -351.974296) (xy 290.265451 -351.922001) (xy 290.257693 -351.868052)
			(xy 290.25723 -351.8408) (xy 287.332674 -351.8408) (xy 287.332245 -351.868054) (xy 287.324487 -351.922008)
			(xy 287.309129 -351.974309) (xy 287.286484 -352.023891) (xy 287.257013 -352.069746) (xy 287.221315 -352.11094)
			(xy 287.180119 -352.146633) (xy 287.134261 -352.1761) (xy 287.084677 -352.198741) (xy 287.032375 -352.214094)
			(xy 286.97842 -352.221847) (xy 286.951166 -352.222308) (xy 286.923125 -352.221839) (xy 286.867646 -352.213632)
			(xy 286.813963 -352.197401) (xy 286.763231 -352.173494) (xy 286.716541 -352.142425) (xy 286.695388 -352.12401)
			(xy 286.683946 -352.114365) (xy 286.656903 -352.101585) (xy 286.627316 -352.097199) (xy 286.597729 -352.101585)
			(xy 286.570686 -352.114365) (xy 286.559244 -352.12401) (xy 286.538095 -352.142432) (xy 286.491417 -352.173526)
			(xy 286.440686 -352.197441) (xy 286.386996 -352.213661) (xy 286.331509 -352.221835) (xy 286.303466 -352.222308)
			(xy 286.276095 -352.22186) (xy 286.221915 -352.214037) (xy 286.169412 -352.198544) (xy 286.119666 -352.175698)
			(xy 286.073699 -352.145971) (xy 286.052768 -352.128328) (xy 286.04144 -352.119092) (xy 286.014883 -352.106916)
			(xy 285.985966 -352.102743) (xy 285.957049 -352.106916) (xy 285.930492 -352.119092) (xy 285.919164 -352.128328)
			(xy 285.898222 -352.145955) (xy 285.852252 -352.175668) (xy 285.802507 -352.198505) (xy 285.750008 -352.213999)
			(xy 285.695834 -352.221832) (xy 285.668466 -352.222308) (xy 285.641214 -352.221854) (xy 285.587265 -352.214093)
			(xy 285.53497 -352.198733) (xy 285.485392 -352.176088) (xy 285.439542 -352.146618) (xy 285.398352 -352.110924)
			(xy 285.362661 -352.069731) (xy 285.333196 -352.023878) (xy 285.310555 -351.974298) (xy 285.2952 -351.922002)
			(xy 285.287444 -351.868052) (xy 285.286958 -351.8408) (xy 281.432 -351.8408) (xy 281.432 -363.649006)
			(xy 281.815032 -363.649006) (xy 281.815032 -358.483916) (xy 281.81549 -358.448254) (xy 281.823478 -358.377379)
			(xy 281.839355 -358.307844) (xy 281.862921 -358.240526) (xy 281.89388 -358.176271) (xy 281.931842 -358.115889)
			(xy 281.976329 -358.060139) (xy 282.001214 -358.03459) (xy 283.982922 -356.052882) (xy 284.008494 -356.028023)
			(xy 284.064243 -355.983541) (xy 284.124623 -355.945583) (xy 284.188874 -355.914625) (xy 284.256187 -355.891058)
			(xy 284.325717 -355.875178) (xy 284.396588 -355.867185) (xy 284.432248 -355.8667) (xy 303.749456 -355.8667)
			(xy 314.591954 -345.024202) (xy 314.617515 -344.999331) (xy 314.673265 -344.95485) (xy 314.733647 -344.916892)
			(xy 314.7979 -344.885936) (xy 314.865216 -344.862371) (xy 314.934747 -344.846493) (xy 315.005619 -344.838503)
			(xy 315.04128 -344.83802) (xy 322.300854 -344.83802) (xy 322.636134 -344.50274) (xy 322.66169 -344.477874)
			(xy 322.717456 -344.433434) (xy 322.777847 -344.395517) (xy 322.842104 -344.364601) (xy 322.909418 -344.341075)
			(xy 322.978944 -344.325235) (xy 323.049806 -344.317279) (xy 323.08546 -344.316812) (xy 323.119822 -344.317214)
			(xy 323.188146 -344.324626) (xy 323.255271 -344.339368) (xy 323.320413 -344.361268) (xy 323.382811 -344.390069)
			(xy 323.441737 -344.425436) (xy 323.46966 -344.446606) (xy 324.569328 -344.446606) (xy 324.569934 -344.416953)
			(xy 324.579123 -344.358362) (xy 324.597265 -344.301898) (xy 324.623923 -344.24892) (xy 324.658456 -344.200704)
			(xy 324.700032 -344.15841) (xy 324.723506 -344.140282) (xy 324.735339 -344.13073) (xy 324.753323 -344.106233)
			(xy 324.763305 -344.077529) (xy 324.764401 -344.047159) (xy 324.756515 -344.017811) (xy 324.748906 -344.004646)
			(xy 324.735111 -343.981796) (xy 324.713366 -343.933051) (xy 324.698629 -343.88175) (xy 324.691187 -343.828896)
			(xy 324.69074 -343.802208) (xy 324.691226 -343.774957) (xy 324.698982 -343.721009) (xy 324.714337 -343.668714)
			(xy 324.736979 -343.619137) (xy 324.766445 -343.573287) (xy 324.802136 -343.532096) (xy 324.843327 -343.496405)
			(xy 324.889177 -343.466939) (xy 324.938754 -343.444297) (xy 324.991049 -343.428942) (xy 325.044997 -343.421186)
			(xy 325.099499 -343.421186) (xy 325.153447 -343.428942) (xy 325.205742 -343.444297) (xy 325.255319 -343.466939)
			(xy 325.301169 -343.496405) (xy 325.34236 -343.532096) (xy 325.378051 -343.573287) (xy 325.407517 -343.619137)
			(xy 325.430159 -343.668714) (xy 325.445514 -343.721009) (xy 325.45327 -343.774957) (xy 325.453756 -343.802208)
			(xy 325.453167 -343.831862) (xy 325.443975 -343.890454) (xy 325.426565 -343.944632) (xy 344.389706 -343.944632)
			(xy 344.389706 -343.859936) (xy 344.397757 -343.775622) (xy 344.413786 -343.692456) (xy 344.437647 -343.611189)
			(xy 344.469126 -343.532559) (xy 344.507937 -343.457278) (xy 344.553727 -343.386026) (xy 344.606083 -343.31945)
			(xy 344.664531 -343.258152) (xy 344.728541 -343.202687) (xy 344.797533 -343.153558) (xy 344.870883 -343.111209)
			(xy 344.947926 -343.076025) (xy 345.027965 -343.048323) (xy 345.110274 -343.028355) (xy 345.194109 -343.016302)
			(xy 345.27871 -343.012272) (xy 345.363311 -343.016302) (xy 345.447146 -343.028355) (xy 345.529455 -343.048323)
			(xy 345.609494 -343.076025) (xy 345.686537 -343.111209) (xy 345.759887 -343.153558) (xy 345.828879 -343.202687)
			(xy 345.892889 -343.258152) (xy 345.951337 -343.31945) (xy 346.003693 -343.386026) (xy 346.049483 -343.457278)
			(xy 346.088294 -343.532559) (xy 346.119773 -343.611189) (xy 346.143634 -343.692456) (xy 346.159663 -343.775622)
			(xy 346.167714 -343.859936) (xy 346.168218 -343.902284) (xy 346.914219 -343.902284) (xy 346.918255 -343.818837)
			(xy 346.930327 -343.736169) (xy 346.95032 -343.655052) (xy 346.978049 -343.576243) (xy 347.013255 -343.500478)
			(xy 347.055609 -343.428465) (xy 347.104715 -343.360876) (xy 347.160116 -343.298342) (xy 347.221293 -343.241447)
			(xy 347.287676 -343.190721) (xy 347.358644 -343.14664) (xy 347.433536 -343.109614) (xy 347.511652 -343.079988)
			(xy 347.592262 -343.05804) (xy 347.674614 -343.043975) (xy 347.75794 -343.037923) (xy 347.84146 -343.039942)
			(xy 347.924396 -343.050012) (xy 348.005972 -343.06804) (xy 348.085428 -343.093857) (xy 348.162021 -343.127222)
			(xy 348.235037 -343.167823) (xy 348.303793 -343.215282) (xy 348.367647 -343.269155) (xy 348.426004 -343.32894)
			(xy 348.478319 -343.394077) (xy 348.524102 -343.46396) (xy 348.562927 -343.537935) (xy 348.594432 -343.615312)
			(xy 348.618321 -343.695369) (xy 348.634372 -343.777357) (xy 348.642435 -343.860512) (xy 348.64294 -343.902284)
			(xy 348.642435 -343.944056) (xy 348.642379 -343.944632) (xy 351.95027 -343.944632) (xy 351.95027 -343.859936)
			(xy 351.958321 -343.775622) (xy 351.97435 -343.692456) (xy 351.998211 -343.611189) (xy 352.02969 -343.532559)
			(xy 352.068501 -343.457278) (xy 352.114291 -343.386026) (xy 352.166647 -343.31945) (xy 352.225095 -343.258152)
			(xy 352.289105 -343.202687) (xy 352.358097 -343.153558) (xy 352.431447 -343.111209) (xy 352.50849 -343.076025)
			(xy 352.588529 -343.048323) (xy 352.670838 -343.028355) (xy 352.754673 -343.016302) (xy 352.839274 -343.012272)
			(xy 352.923875 -343.016302) (xy 353.00771 -343.028355) (xy 353.090019 -343.048323) (xy 353.170058 -343.076025)
			(xy 353.247101 -343.111209) (xy 353.320451 -343.153558) (xy 353.389443 -343.202687) (xy 353.453453 -343.258152)
			(xy 353.511901 -343.31945) (xy 353.564257 -343.386026) (xy 353.610047 -343.457278) (xy 353.648858 -343.532559)
			(xy 353.680337 -343.611189) (xy 353.704198 -343.692456) (xy 353.720227 -343.775622) (xy 353.728278 -343.859936)
			(xy 353.728782 -343.902284) (xy 354.474783 -343.902284) (xy 354.478819 -343.818837) (xy 354.490891 -343.736169)
			(xy 354.510884 -343.655052) (xy 354.538613 -343.576243) (xy 354.573819 -343.500478) (xy 354.616173 -343.428465)
			(xy 354.665279 -343.360876) (xy 354.72068 -343.298342) (xy 354.781857 -343.241447) (xy 354.84824 -343.190721)
			(xy 354.919208 -343.14664) (xy 354.9941 -343.109614) (xy 355.072216 -343.079988) (xy 355.152826 -343.05804)
			(xy 355.235178 -343.043975) (xy 355.318504 -343.037923) (xy 355.402024 -343.039942) (xy 355.48496 -343.050012)
			(xy 355.566536 -343.06804) (xy 355.645992 -343.093857) (xy 355.722585 -343.127222) (xy 355.795601 -343.167823)
			(xy 355.864357 -343.215282) (xy 355.928211 -343.269155) (xy 355.986568 -343.32894) (xy 356.038883 -343.394077)
			(xy 356.084666 -343.46396) (xy 356.123491 -343.537935) (xy 356.154996 -343.615312) (xy 356.178885 -343.695369)
			(xy 356.194936 -343.777357) (xy 356.202999 -343.860512) (xy 356.203504 -343.902284) (xy 356.202999 -343.944056)
			(xy 356.202943 -343.944632) (xy 359.655614 -343.944632) (xy 359.655614 -343.859936) (xy 359.663665 -343.775622)
			(xy 359.679694 -343.692456) (xy 359.703555 -343.611189) (xy 359.735034 -343.532559) (xy 359.773845 -343.457278)
			(xy 359.819635 -343.386026) (xy 359.871991 -343.31945) (xy 359.930439 -343.258152) (xy 359.994449 -343.202687)
			(xy 360.063441 -343.153558) (xy 360.136791 -343.111209) (xy 360.213834 -343.076025) (xy 360.293873 -343.048323)
			(xy 360.376182 -343.028355) (xy 360.460017 -343.016302) (xy 360.544618 -343.012272) (xy 360.629219 -343.016302)
			(xy 360.713054 -343.028355) (xy 360.795363 -343.048323) (xy 360.875402 -343.076025) (xy 360.952445 -343.111209)
			(xy 361.025795 -343.153558) (xy 361.094787 -343.202687) (xy 361.158797 -343.258152) (xy 361.217245 -343.31945)
			(xy 361.269601 -343.386026) (xy 361.315391 -343.457278) (xy 361.354202 -343.532559) (xy 361.385681 -343.611189)
			(xy 361.409542 -343.692456) (xy 361.425571 -343.775622) (xy 361.433622 -343.859936) (xy 361.434126 -343.902284)
			(xy 362.180127 -343.902284) (xy 362.184163 -343.818837) (xy 362.196235 -343.736169) (xy 362.216228 -343.655052)
			(xy 362.243957 -343.576243) (xy 362.279163 -343.500478) (xy 362.321517 -343.428465) (xy 362.370623 -343.360876)
			(xy 362.426024 -343.298342) (xy 362.487201 -343.241447) (xy 362.553584 -343.190721) (xy 362.624552 -343.14664)
			(xy 362.699444 -343.109614) (xy 362.77756 -343.079988) (xy 362.85817 -343.05804) (xy 362.940522 -343.043975)
			(xy 363.023848 -343.037923) (xy 363.107368 -343.039942) (xy 363.190304 -343.050012) (xy 363.27188 -343.06804)
			(xy 363.351336 -343.093857) (xy 363.427929 -343.127222) (xy 363.500945 -343.167823) (xy 363.569701 -343.215282)
			(xy 363.633555 -343.269155) (xy 363.691912 -343.32894) (xy 363.744227 -343.394077) (xy 363.79001 -343.46396)
			(xy 363.828835 -343.537935) (xy 363.86034 -343.615312) (xy 363.884229 -343.695369) (xy 363.90028 -343.777357)
			(xy 363.908343 -343.860512) (xy 363.908848 -343.902284) (xy 363.908343 -343.944056) (xy 363.908287 -343.944632)
			(xy 367.216178 -343.944632) (xy 367.216178 -343.859936) (xy 367.224229 -343.775622) (xy 367.240258 -343.692456)
			(xy 367.264119 -343.611189) (xy 367.295598 -343.532559) (xy 367.334409 -343.457278) (xy 367.380199 -343.386026)
			(xy 367.432555 -343.31945) (xy 367.491003 -343.258152) (xy 367.555013 -343.202687) (xy 367.624005 -343.153558)
			(xy 367.697355 -343.111209) (xy 367.774398 -343.076025) (xy 367.854437 -343.048323) (xy 367.936746 -343.028355)
			(xy 368.020581 -343.016302) (xy 368.105182 -343.012272) (xy 368.189783 -343.016302) (xy 368.273618 -343.028355)
			(xy 368.355927 -343.048323) (xy 368.435966 -343.076025) (xy 368.513009 -343.111209) (xy 368.586359 -343.153558)
			(xy 368.655351 -343.202687) (xy 368.719361 -343.258152) (xy 368.777809 -343.31945) (xy 368.830165 -343.386026)
			(xy 368.875955 -343.457278) (xy 368.914766 -343.532559) (xy 368.946245 -343.611189) (xy 368.970106 -343.692456)
			(xy 368.986135 -343.775622) (xy 368.994186 -343.859936) (xy 368.99469 -343.902284) (xy 369.740691 -343.902284)
			(xy 369.744727 -343.818837) (xy 369.756799 -343.736169) (xy 369.776792 -343.655052) (xy 369.804521 -343.576243)
			(xy 369.839727 -343.500478) (xy 369.882081 -343.428465) (xy 369.931187 -343.360876) (xy 369.986588 -343.298342)
			(xy 370.047765 -343.241447) (xy 370.114148 -343.190721) (xy 370.185116 -343.14664) (xy 370.260008 -343.109614)
			(xy 370.338124 -343.079988) (xy 370.418734 -343.05804) (xy 370.501086 -343.043975) (xy 370.584412 -343.037923)
			(xy 370.667932 -343.039942) (xy 370.750868 -343.050012) (xy 370.832444 -343.06804) (xy 370.9119 -343.093857)
			(xy 370.988493 -343.127222) (xy 371.061509 -343.167823) (xy 371.130265 -343.215282) (xy 371.194119 -343.269155)
			(xy 371.252476 -343.32894) (xy 371.304791 -343.394077) (xy 371.350574 -343.46396) (xy 371.389399 -343.537935)
			(xy 371.420904 -343.615312) (xy 371.444793 -343.695369) (xy 371.460844 -343.777357) (xy 371.468907 -343.860512)
			(xy 371.469412 -343.902284) (xy 371.468907 -343.944056) (xy 371.460844 -344.027211) (xy 371.444793 -344.109199)
			(xy 371.420904 -344.189256) (xy 371.389399 -344.266633) (xy 371.350574 -344.340608) (xy 371.326559 -344.377264)
			(xy 381.783844 -344.377264) (xy 381.784278 -344.349892) (xy 381.792102 -344.295712) (xy 381.807598 -344.243208)
			(xy 381.830447 -344.193461) (xy 381.860179 -344.147496) (xy 381.877824 -344.126566) (xy 381.887094 -344.115264)
			(xy 381.899264 -344.088697) (xy 381.903429 -344.059773) (xy 381.899248 -344.030851) (xy 381.887064 -344.00429)
			(xy 381.877824 -343.992962) (xy 381.860204 -343.972014) (xy 381.830489 -343.926046) (xy 381.807649 -343.876303)
			(xy 381.792153 -343.823805) (xy 381.78432 -343.769632) (xy 381.783844 -343.742264) (xy 381.78433 -343.715013)
			(xy 381.792086 -343.661065) (xy 381.807441 -343.60877) (xy 381.830083 -343.559193) (xy 381.859549 -343.513343)
			(xy 381.89524 -343.472152) (xy 381.936431 -343.436461) (xy 381.982281 -343.406995) (xy 382.031858 -343.384353)
			(xy 382.084153 -343.368998) (xy 382.138101 -343.361242) (xy 382.192603 -343.361242) (xy 382.246551 -343.368998)
			(xy 382.298846 -343.384353) (xy 382.348423 -343.406995) (xy 382.394273 -343.436461) (xy 382.435464 -343.472152)
			(xy 382.471155 -343.513343) (xy 382.500621 -343.559193) (xy 382.523263 -343.60877) (xy 382.538618 -343.661065)
			(xy 382.546374 -343.715013) (xy 382.54686 -343.742264) (xy 382.546383 -343.769634) (xy 382.538569 -343.823813)
			(xy 382.523083 -343.876316) (xy 382.500244 -343.926063) (xy 382.470521 -343.97203) (xy 382.45288 -343.992962)
			(xy 382.443679 -344.004316) (xy 382.4315 -344.030864) (xy 382.428251 -344.053344) (xy 414.212782 -344.053344)
			(xy 414.212782 -343.968648) (xy 414.220833 -343.884334) (xy 414.236862 -343.801168) (xy 414.260723 -343.719901)
			(xy 414.292202 -343.641271) (xy 414.331013 -343.56599) (xy 414.376803 -343.494738) (xy 414.429159 -343.428162)
			(xy 414.487607 -343.366864) (xy 414.551617 -343.311399) (xy 414.620609 -343.26227) (xy 414.693959 -343.219921)
			(xy 414.771002 -343.184737) (xy 414.851041 -343.157035) (xy 414.93335 -343.137067) (xy 415.017185 -343.125014)
			(xy 415.101786 -343.120984) (xy 415.186387 -343.125014) (xy 415.270222 -343.137067) (xy 415.352531 -343.157035)
			(xy 415.43257 -343.184737) (xy 415.509613 -343.219921) (xy 415.582963 -343.26227) (xy 415.651955 -343.311399)
			(xy 415.715965 -343.366864) (xy 415.774413 -343.428162) (xy 415.826769 -343.494738) (xy 415.872559 -343.56599)
			(xy 415.91137 -343.641271) (xy 415.942849 -343.719901) (xy 415.96671 -343.801168) (xy 415.982739 -343.884334)
			(xy 415.99079 -343.968648) (xy 415.991294 -344.010996) (xy 415.99079 -344.053344) (xy 415.990184 -344.059694)
			(xy 420.403524 -344.059694) (xy 420.403524 -343.974998) (xy 420.411575 -343.890684) (xy 420.427604 -343.807518)
			(xy 420.451465 -343.726251) (xy 420.482944 -343.647621) (xy 420.521755 -343.57234) (xy 420.567545 -343.501088)
			(xy 420.619901 -343.434512) (xy 420.678349 -343.373214) (xy 420.742359 -343.317749) (xy 420.811351 -343.26862)
			(xy 420.884701 -343.226271) (xy 420.961744 -343.191087) (xy 421.041783 -343.163385) (xy 421.124092 -343.143417)
			(xy 421.207927 -343.131364) (xy 421.292528 -343.127334) (xy 421.377129 -343.131364) (xy 421.460964 -343.143417)
			(xy 421.543273 -343.163385) (xy 421.623312 -343.191087) (xy 421.700355 -343.226271) (xy 421.773705 -343.26862)
			(xy 421.842697 -343.317749) (xy 421.906707 -343.373214) (xy 421.965155 -343.434512) (xy 422.017511 -343.501088)
			(xy 422.063301 -343.57234) (xy 422.102112 -343.647621) (xy 422.133591 -343.726251) (xy 422.157452 -343.807518)
			(xy 422.173481 -343.890684) (xy 422.181532 -343.974998) (xy 422.182036 -344.017346) (xy 422.181532 -344.059694)
			(xy 426.601124 -344.059694) (xy 426.601124 -343.974998) (xy 426.609175 -343.890684) (xy 426.625204 -343.807518)
			(xy 426.649065 -343.726251) (xy 426.680544 -343.647621) (xy 426.719355 -343.57234) (xy 426.765145 -343.501088)
			(xy 426.817501 -343.434512) (xy 426.875949 -343.373214) (xy 426.939959 -343.317749) (xy 427.008951 -343.26862)
			(xy 427.082301 -343.226271) (xy 427.159344 -343.191087) (xy 427.239383 -343.163385) (xy 427.321692 -343.143417)
			(xy 427.405527 -343.131364) (xy 427.490128 -343.127334) (xy 427.574729 -343.131364) (xy 427.658564 -343.143417)
			(xy 427.740873 -343.163385) (xy 427.820912 -343.191087) (xy 427.897955 -343.226271) (xy 427.971305 -343.26862)
			(xy 428.040297 -343.317749) (xy 428.104307 -343.373214) (xy 428.162755 -343.434512) (xy 428.215111 -343.501088)
			(xy 428.260901 -343.57234) (xy 428.299712 -343.647621) (xy 428.331191 -343.726251) (xy 428.355052 -343.807518)
			(xy 428.371081 -343.890684) (xy 428.379132 -343.974998) (xy 428.379636 -344.017346) (xy 428.379132 -344.059694)
			(xy 428.371081 -344.144008) (xy 428.355052 -344.227174) (xy 428.331191 -344.308441) (xy 428.299712 -344.387071)
			(xy 428.260901 -344.462352) (xy 428.215111 -344.533604) (xy 428.162755 -344.60018) (xy 428.104307 -344.661478)
			(xy 428.040297 -344.716943) (xy 427.971305 -344.766072) (xy 427.897955 -344.808421) (xy 427.820912 -344.843605)
			(xy 427.740873 -344.871307) (xy 427.658564 -344.891275) (xy 427.574729 -344.903328) (xy 427.490128 -344.907359)
			(xy 427.405527 -344.903328) (xy 427.321692 -344.891275) (xy 427.239383 -344.871307) (xy 427.159344 -344.843605)
			(xy 427.082301 -344.808421) (xy 427.008951 -344.766072) (xy 426.939959 -344.716943) (xy 426.875949 -344.661478)
			(xy 426.817501 -344.60018) (xy 426.765145 -344.533604) (xy 426.719355 -344.462352) (xy 426.680544 -344.387071)
			(xy 426.649065 -344.308441) (xy 426.625204 -344.227174) (xy 426.609175 -344.144008) (xy 426.601124 -344.059694)
			(xy 422.181532 -344.059694) (xy 422.173481 -344.144008) (xy 422.157452 -344.227174) (xy 422.133591 -344.308441)
			(xy 422.102112 -344.387071) (xy 422.063301 -344.462352) (xy 422.017511 -344.533604) (xy 421.965155 -344.60018)
			(xy 421.906707 -344.661478) (xy 421.842697 -344.716943) (xy 421.773705 -344.766072) (xy 421.700355 -344.808421)
			(xy 421.623312 -344.843605) (xy 421.543273 -344.871307) (xy 421.460964 -344.891275) (xy 421.377129 -344.903328)
			(xy 421.292528 -344.907359) (xy 421.207927 -344.903328) (xy 421.124092 -344.891275) (xy 421.041783 -344.871307)
			(xy 420.961744 -344.843605) (xy 420.884701 -344.808421) (xy 420.811351 -344.766072) (xy 420.742359 -344.716943)
			(xy 420.678349 -344.661478) (xy 420.619901 -344.60018) (xy 420.567545 -344.533604) (xy 420.521755 -344.462352)
			(xy 420.482944 -344.387071) (xy 420.451465 -344.308441) (xy 420.427604 -344.227174) (xy 420.411575 -344.144008)
			(xy 420.403524 -344.059694) (xy 415.990184 -344.059694) (xy 415.982739 -344.137658) (xy 415.96671 -344.220824)
			(xy 415.942849 -344.302091) (xy 415.91137 -344.380721) (xy 415.872559 -344.456002) (xy 415.826769 -344.527254)
			(xy 415.774413 -344.59383) (xy 415.715965 -344.655128) (xy 415.651955 -344.710593) (xy 415.582963 -344.759722)
			(xy 415.509613 -344.802071) (xy 415.43257 -344.837255) (xy 415.352531 -344.864957) (xy 415.270222 -344.884925)
			(xy 415.186387 -344.896978) (xy 415.101786 -344.901009) (xy 415.017185 -344.896978) (xy 414.93335 -344.884925)
			(xy 414.851041 -344.864957) (xy 414.771002 -344.837255) (xy 414.693959 -344.802071) (xy 414.620609 -344.759722)
			(xy 414.551617 -344.710593) (xy 414.487607 -344.655128) (xy 414.429159 -344.59383) (xy 414.376803 -344.527254)
			(xy 414.331013 -344.456002) (xy 414.292202 -344.380721) (xy 414.260723 -344.302091) (xy 414.236862 -344.220824)
			(xy 414.220833 -344.137658) (xy 414.212782 -344.053344) (xy 382.428251 -344.053344) (xy 382.427322 -344.059773)
			(xy 382.431485 -344.088683) (xy 382.44365 -344.115238) (xy 382.45288 -344.126566) (xy 382.470514 -344.147503)
			(xy 382.500227 -344.193474) (xy 382.523064 -344.24322) (xy 382.538557 -344.29572) (xy 382.546386 -344.349895)
			(xy 382.54686 -344.377264) (xy 382.546374 -344.404515) (xy 382.538618 -344.458463) (xy 382.523263 -344.510758)
			(xy 382.500621 -344.560335) (xy 382.471155 -344.606185) (xy 382.435464 -344.647376) (xy 382.394273 -344.683067)
			(xy 382.348423 -344.712533) (xy 382.298846 -344.735175) (xy 382.246551 -344.75053) (xy 382.192603 -344.758286)
			(xy 382.138101 -344.758286) (xy 382.084153 -344.75053) (xy 382.031858 -344.735175) (xy 381.982281 -344.712533)
			(xy 381.936431 -344.683067) (xy 381.89524 -344.647376) (xy 381.859549 -344.606185) (xy 381.830083 -344.560335)
			(xy 381.807441 -344.510758) (xy 381.792086 -344.458463) (xy 381.78433 -344.404515) (xy 381.783844 -344.377264)
			(xy 371.326559 -344.377264) (xy 371.304791 -344.410491) (xy 371.252476 -344.475628) (xy 371.194119 -344.535413)
			(xy 371.130265 -344.589286) (xy 371.061509 -344.636745) (xy 370.988493 -344.677346) (xy 370.9119 -344.710711)
			(xy 370.832444 -344.736528) (xy 370.750868 -344.754556) (xy 370.667932 -344.764626) (xy 370.584412 -344.766645)
			(xy 370.501086 -344.760593) (xy 370.418734 -344.746528) (xy 370.338124 -344.72458) (xy 370.260008 -344.694954)
			(xy 370.185116 -344.657928) (xy 370.114148 -344.613847) (xy 370.047765 -344.563121) (xy 369.986588 -344.506226)
			(xy 369.931187 -344.443692) (xy 369.882081 -344.376103) (xy 369.839727 -344.30409) (xy 369.804521 -344.228325)
			(xy 369.776792 -344.149516) (xy 369.756799 -344.068399) (xy 369.744727 -343.985731) (xy 369.740691 -343.902284)
			(xy 368.99469 -343.902284) (xy 368.994186 -343.944632) (xy 368.986135 -344.028946) (xy 368.970106 -344.112112)
			(xy 368.946245 -344.193379) (xy 368.914766 -344.272009) (xy 368.875955 -344.34729) (xy 368.830165 -344.418542)
			(xy 368.777809 -344.485118) (xy 368.719361 -344.546416) (xy 368.655351 -344.601881) (xy 368.586359 -344.65101)
			(xy 368.513009 -344.693359) (xy 368.435966 -344.728543) (xy 368.355927 -344.756245) (xy 368.273618 -344.776213)
			(xy 368.247973 -344.7799) (xy 386.032387 -344.7799) (xy 386.036556 -344.724273) (xy 386.04897 -344.669889)
			(xy 386.069351 -344.617962) (xy 386.097243 -344.569653) (xy 386.132025 -344.526041) (xy 386.172918 -344.488101)
			(xy 386.21901 -344.456679) (xy 386.26927 -344.432478) (xy 386.322576 -344.416039) (xy 386.377736 -344.407729)
			(xy 386.405628 -344.407236) (xy 386.432959 -344.407731) (xy 386.487038 -344.415696) (xy 386.539372 -344.43148)
			(xy 386.588836 -344.454744) (xy 386.634369 -344.484988) (xy 386.674992 -344.521563) (xy 386.709832 -344.563683)
			(xy 386.724398 -344.586814) (xy 386.732342 -344.599023) (xy 386.753808 -344.618693) (xy 386.779956 -344.631498)
			(xy 386.808656 -344.636398) (xy 386.837571 -344.632992) (xy 386.851144 -344.627708) (xy 386.874352 -344.618213)
			(xy 386.922686 -344.604864) (xy 386.972376 -344.598138) (xy 386.997448 -344.597736) (xy 387.022517 -344.598156)
			(xy 387.072201 -344.604907) (xy 387.120535 -344.618241) (xy 387.143752 -344.627708) (xy 387.157334 -344.63294)
			(xy 387.186232 -344.636309) (xy 387.214909 -344.631401) (xy 387.241043 -344.618616) (xy 387.262517 -344.598987)
			(xy 387.270498 -344.586814) (xy 387.285067 -344.563683) (xy 387.31991 -344.521562) (xy 387.360533 -344.484983)
			(xy 387.406064 -344.454732) (xy 387.455526 -344.431456) (xy 387.507857 -344.415656) (xy 387.561936 -344.40767)
			(xy 387.6166 -344.40767) (xy 387.670679 -344.415656) (xy 387.72301 -344.431456) (xy 387.772472 -344.454732)
			(xy 387.818003 -344.484983) (xy 387.858626 -344.521562) (xy 387.893469 -344.563683) (xy 387.908038 -344.586814)
			(xy 387.915944 -344.59905) (xy 387.937421 -344.61872) (xy 387.963579 -344.631522) (xy 387.992288 -344.636414)
			(xy 388.021209 -344.632998) (xy 388.034784 -344.627708) (xy 388.057999 -344.618232) (xy 388.106329 -344.604875)
			(xy 388.156017 -344.598142) (xy 388.181088 -344.597736) (xy 388.207932 -344.598171) (xy 388.261065 -344.605875)
			(xy 388.312542 -344.621125) (xy 388.361297 -344.643606) (xy 388.406321 -344.672851) (xy 388.446681 -344.708256)
			(xy 388.481541 -344.749087) (xy 388.510181 -344.794499) (xy 388.532006 -344.843551) (xy 388.539736 -344.869262)
			(xy 388.544362 -344.883773) (xy 388.560887 -344.909341) (xy 388.584211 -344.928907) (xy 388.612263 -344.940734)
			(xy 388.642554 -344.943775) (xy 388.672397 -344.937757) (xy 388.68604 -344.930984) (xy 388.714189 -344.916356)
			(xy 388.774138 -344.895627) (xy 388.836696 -344.885126) (xy 388.868412 -344.884502) (xy 388.886431 -344.884725)
			(xy 388.922306 -344.888158) (xy 388.94004 -344.89136) (xy 388.955244 -344.893737) (xy 388.985802 -344.890199)
			(xy 389.013922 -344.877728) (xy 389.037058 -344.857454) (xy 389.053113 -344.831214) (xy 389.057388 -344.81643)
			(xy 389.064795 -344.789389) (xy 389.086426 -344.737665) (xy 389.11539 -344.689661) (xy 389.151065 -344.64641)
			(xy 389.192683 -344.608844) (xy 389.239348 -344.577769) (xy 389.290058 -344.553856) (xy 389.343719 -344.537617)
			(xy 389.39918 -344.529403) (xy 389.427212 -344.528902) (xy 389.454464 -344.529367) (xy 389.508413 -344.537125)
			(xy 389.560709 -344.552482) (xy 389.610287 -344.575125) (xy 389.656138 -344.604594) (xy 389.697328 -344.640288)
			(xy 389.733019 -344.68148) (xy 389.762485 -344.727333) (xy 389.785125 -344.776912) (xy 389.80048 -344.829209)
			(xy 389.808235 -344.883158) (xy 389.80872 -344.91041) (xy 389.808185 -344.937982) (xy 389.800246 -344.992551)
			(xy 389.784534 -345.04541) (xy 389.761377 -345.095456) (xy 389.731257 -345.141647) (xy 389.694801 -345.183022)
			(xy 389.6741 -345.20124) (xy 389.663193 -345.211129) (xy 389.647122 -345.235782) (xy 389.638739 -345.263992)
			(xy 389.638741 -345.293421) (xy 389.647127 -345.32163) (xy 389.663202 -345.346281) (xy 389.6741 -345.35618)
			(xy 389.694815 -345.374385) (xy 389.731279 -345.415758) (xy 389.761405 -345.461949) (xy 389.784567 -345.511998)
			(xy 389.800281 -345.564859) (xy 389.808221 -345.619433) (xy 389.80822 -345.67458) (xy 389.800279 -345.729153)
			(xy 389.784563 -345.782015) (xy 389.761399 -345.832062) (xy 389.731271 -345.878253) (xy 389.694806 -345.919624)
			(xy 389.6741 -345.93784) (xy 389.663193 -345.947729) (xy 389.647122 -345.972382) (xy 389.638739 -346.000592)
			(xy 389.63874 -346.010992) (xy 414.186375 -346.010992) (xy 414.190397 -345.925272) (xy 414.202428 -345.840304)
			(xy 414.222364 -345.756837) (xy 414.250027 -345.675603) (xy 414.285176 -345.597317) (xy 414.327502 -345.522666)
			(xy 414.376631 -345.452307) (xy 414.432134 -345.386857) (xy 414.493521 -345.326893) (xy 414.560254 -345.27294)
			(xy 414.631746 -345.225473) (xy 414.707368 -345.184909) (xy 414.786457 -345.151605) (xy 414.868317 -345.125853)
			(xy 414.952228 -345.10788) (xy 415.037454 -345.097844) (xy 415.123246 -345.095832) (xy 415.208848 -345.101863)
			(xy 415.29351 -345.115883) (xy 415.376487 -345.137769) (xy 415.45705 -345.16733) (xy 415.53449 -345.204304)
			(xy 415.608129 -345.248368) (xy 415.677317 -345.299134) (xy 415.741448 -345.356155) (xy 415.799957 -345.418931)
			(xy 415.85233 -345.486911) (xy 415.898108 -345.559496) (xy 415.936888 -345.636048) (xy 415.968329 -345.715896)
			(xy 415.992155 -345.798337) (xy 416.008156 -345.882647) (xy 416.016191 -345.968085) (xy 416.016694 -346.010992)
			(xy 416.01662 -346.017342) (xy 420.377117 -346.017342) (xy 420.381139 -345.931622) (xy 420.39317 -345.846654)
			(xy 420.413106 -345.763187) (xy 420.440769 -345.681953) (xy 420.475918 -345.603667) (xy 420.518244 -345.529016)
			(xy 420.567373 -345.458657) (xy 420.622876 -345.393207) (xy 420.684263 -345.333243) (xy 420.750996 -345.27929)
			(xy 420.822488 -345.231823) (xy 420.89811 -345.191259) (xy 420.977199 -345.157955) (xy 421.059059 -345.132203)
			(xy 421.14297 -345.11423) (xy 421.228196 -345.104194) (xy 421.313988 -345.102182) (xy 421.39959 -345.108213)
			(xy 421.484252 -345.122233) (xy 421.567229 -345.144119) (xy 421.647792 -345.17368) (xy 421.725232 -345.210654)
			(xy 421.798871 -345.254718) (xy 421.868059 -345.305484) (xy 421.93219 -345.362505) (xy 421.990699 -345.425281)
			(xy 422.043072 -345.493261) (xy 422.08885 -345.565846) (xy 422.12763 -345.642398) (xy 422.159071 -345.722246)
			(xy 422.182897 -345.804687) (xy 422.198898 -345.888997) (xy 422.206933 -345.974435) (xy 422.207436 -346.017342)
			(xy 426.574717 -346.017342) (xy 426.578739 -345.931622) (xy 426.59077 -345.846654) (xy 426.610706 -345.763187)
			(xy 426.638369 -345.681953) (xy 426.673518 -345.603667) (xy 426.715844 -345.529016) (xy 426.764973 -345.458657)
			(xy 426.820476 -345.393207) (xy 426.881863 -345.333243) (xy 426.948596 -345.27929) (xy 427.020088 -345.231823)
			(xy 427.09571 -345.191259) (xy 427.174799 -345.157955) (xy 427.256659 -345.132203) (xy 427.34057 -345.11423)
			(xy 427.425796 -345.104194) (xy 427.511588 -345.102182) (xy 427.59719 -345.108213) (xy 427.681852 -345.122233)
			(xy 427.764829 -345.144119) (xy 427.845392 -345.17368) (xy 427.922832 -345.210654) (xy 427.996471 -345.254718)
			(xy 428.065659 -345.305484) (xy 428.12979 -345.362505) (xy 428.188299 -345.425281) (xy 428.240672 -345.493261)
			(xy 428.28645 -345.565846) (xy 428.32523 -345.642398) (xy 428.356671 -345.722246) (xy 428.380497 -345.804687)
			(xy 428.396498 -345.888997) (xy 428.404533 -345.974435) (xy 428.405036 -346.017342) (xy 428.404533 -346.060249)
			(xy 428.396498 -346.145687) (xy 428.380497 -346.229997) (xy 428.356671 -346.312438) (xy 428.32523 -346.392286)
			(xy 428.28645 -346.468838) (xy 428.240672 -346.541423) (xy 428.188299 -346.609403) (xy 428.12979 -346.672179)
			(xy 428.065659 -346.7292) (xy 427.996471 -346.779966) (xy 427.922832 -346.82403) (xy 427.845392 -346.861004)
			(xy 427.764829 -346.890565) (xy 427.681852 -346.912451) (xy 427.59719 -346.926471) (xy 427.511588 -346.932502)
			(xy 427.425796 -346.93049) (xy 427.34057 -346.920454) (xy 427.256659 -346.902481) (xy 427.174799 -346.876729)
			(xy 427.09571 -346.843425) (xy 427.020088 -346.802861) (xy 426.948596 -346.755394) (xy 426.881863 -346.701441)
			(xy 426.820476 -346.641477) (xy 426.764973 -346.576027) (xy 426.715844 -346.505668) (xy 426.673518 -346.431017)
			(xy 426.638369 -346.352731) (xy 426.610706 -346.271497) (xy 426.59077 -346.18803) (xy 426.578739 -346.103062)
			(xy 426.574717 -346.017342) (xy 422.207436 -346.017342) (xy 422.206933 -346.060249) (xy 422.198898 -346.145687)
			(xy 422.182897 -346.229997) (xy 422.159071 -346.312438) (xy 422.12763 -346.392286) (xy 422.08885 -346.468838)
			(xy 422.043072 -346.541423) (xy 421.990699 -346.609403) (xy 421.93219 -346.672179) (xy 421.868059 -346.7292)
			(xy 421.798871 -346.779966) (xy 421.725232 -346.82403) (xy 421.647792 -346.861004) (xy 421.567229 -346.890565)
			(xy 421.484252 -346.912451) (xy 421.39959 -346.926471) (xy 421.313988 -346.932502) (xy 421.228196 -346.93049)
			(xy 421.14297 -346.920454) (xy 421.059059 -346.902481) (xy 420.977199 -346.876729) (xy 420.89811 -346.843425)
			(xy 420.822488 -346.802861) (xy 420.750996 -346.755394) (xy 420.684263 -346.701441) (xy 420.622876 -346.641477)
			(xy 420.567373 -346.576027) (xy 420.518244 -346.505668) (xy 420.475918 -346.431017) (xy 420.440769 -346.352731)
			(xy 420.413106 -346.271497) (xy 420.39317 -346.18803) (xy 420.381139 -346.103062) (xy 420.377117 -346.017342)
			(xy 416.01662 -346.017342) (xy 416.016191 -346.053899) (xy 416.008156 -346.139337) (xy 415.992155 -346.223647)
			(xy 415.968329 -346.306088) (xy 415.936888 -346.385936) (xy 415.898108 -346.462488) (xy 415.85233 -346.535073)
			(xy 415.799957 -346.603053) (xy 415.741448 -346.665829) (xy 415.677317 -346.72285) (xy 415.608129 -346.773616)
			(xy 415.53449 -346.81768) (xy 415.45705 -346.854654) (xy 415.376487 -346.884215) (xy 415.29351 -346.906101)
			(xy 415.208848 -346.920121) (xy 415.123246 -346.926152) (xy 415.037454 -346.92414) (xy 414.952228 -346.914104)
			(xy 414.868317 -346.896131) (xy 414.786457 -346.870379) (xy 414.707368 -346.837075) (xy 414.631746 -346.796511)
			(xy 414.560254 -346.749044) (xy 414.493521 -346.695091) (xy 414.432134 -346.635127) (xy 414.376631 -346.569677)
			(xy 414.327502 -346.499318) (xy 414.285176 -346.424667) (xy 414.250027 -346.346381) (xy 414.222364 -346.265147)
			(xy 414.202428 -346.18168) (xy 414.190397 -346.096712) (xy 414.186375 -346.010992) (xy 389.63874 -346.010992)
			(xy 389.638741 -346.030021) (xy 389.647127 -346.05823) (xy 389.663202 -346.082881) (xy 389.6741 -346.09278)
			(xy 389.694805 -346.110998) (xy 389.731275 -346.152365) (xy 389.761408 -346.198554) (xy 389.784575 -346.2486)
			(xy 389.800293 -346.301462) (xy 389.808234 -346.356036) (xy 389.80872 -346.38361) (xy 389.808232 -346.410861)
			(xy 389.800474 -346.464808) (xy 389.785118 -346.517102) (xy 389.762477 -346.566678) (xy 389.733011 -346.612528)
			(xy 389.697319 -346.653718) (xy 389.65613 -346.689409) (xy 389.61028 -346.718876) (xy 389.560704 -346.741517)
			(xy 389.50841 -346.756874) (xy 389.454463 -346.764631) (xy 389.427212 -346.765118) (xy 389.399358 -346.764571)
			(xy 389.344244 -346.756449) (xy 389.290895 -346.740406) (xy 389.240443 -346.716782) (xy 389.193959 -346.686078)
			(xy 389.152429 -346.648946) (xy 389.116736 -346.606174) (xy 389.087635 -346.55867) (xy 389.065746 -346.507442)
			(xy 389.05815 -346.480638) (xy 389.053874 -346.466522) (xy 389.038487 -346.441374) (xy 389.01657 -346.421656)
			(xy 388.98994 -346.409005) (xy 388.96081 -346.404471) (xy 388.946136 -346.405962) (xy 388.93312 -346.407636)
			(xy 388.906935 -346.409413) (xy 388.893812 -346.409518) (xy 388.879663 -346.409423) (xy 388.85144 -346.40739)
			(xy 388.837424 -346.405454) (xy 388.82408 -346.403805) (xy 388.797379 -346.40691) (xy 388.772419 -346.416889)
			(xy 388.750936 -346.433048) (xy 388.734426 -346.454261) (xy 388.724036 -346.479053) (xy 388.721854 -346.492322)
			(xy 388.717712 -346.519466) (xy 388.702744 -346.572294) (xy 388.680358 -346.62243) (xy 388.651017 -346.668839)
			(xy 388.615326 -346.710563) (xy 388.574022 -346.74674) (xy 388.527959 -346.776623) (xy 388.478089 -346.799595)
			(xy 388.42544 -346.81518) (xy 388.371101 -346.823057) (xy 388.343648 -346.823538) (xy 388.316398 -346.823)
			(xy 388.262451 -346.81525) (xy 388.210156 -346.799902) (xy 388.160578 -346.777267) (xy 388.114726 -346.747807)
			(xy 388.073534 -346.712121) (xy 388.03784 -346.670936) (xy 388.00837 -346.62509) (xy 387.985725 -346.575517)
			(xy 387.970366 -346.523225) (xy 387.962605 -346.46928) (xy 387.96214 -346.44203) (xy 387.962612 -346.414456)
			(xy 387.970562 -346.359882) (xy 387.986284 -346.307022) (xy 388.009453 -346.256976) (xy 388.039585 -346.210786)
			(xy 388.076053 -346.169415) (xy 388.09676 -346.1512) (xy 388.10763 -346.141273) (xy 388.12371 -346.116632)
			(xy 388.1321 -346.088431) (xy 388.132106 -346.059008) (xy 388.123726 -346.030803) (xy 388.107656 -346.006157)
			(xy 388.09676 -345.99626) (xy 388.076067 -345.97803) (xy 388.039597 -345.936664) (xy 388.009463 -345.890478)
			(xy 387.986295 -345.840434) (xy 387.970574 -345.787575) (xy 387.962629 -345.733003) (xy 387.96214 -345.70543)
			(xy 387.962563 -345.678928) (xy 387.969914 -345.626435) (xy 387.984465 -345.575466) (xy 388.005935 -345.527005)
			(xy 388.033911 -345.481984) (xy 388.050532 -345.461336) (xy 388.059995 -345.449205) (xy 388.071785 -345.4208)
			(xy 388.074606 -345.390175) (xy 388.068206 -345.360093) (xy 388.05316 -345.33327) (xy 388.030828 -345.312125)
			(xy 388.017258 -345.304872) (xy 387.993566 -345.292774) (xy 387.949585 -345.262851) (xy 387.910304 -345.226979)
			(xy 387.876521 -345.185887) (xy 387.862318 -345.163394) (xy 387.854357 -345.151197) (xy 387.832896 -345.131527)
			(xy 387.806753 -345.118719) (xy 387.778056 -345.113816) (xy 387.749144 -345.117218) (xy 387.735572 -345.1225)
			(xy 387.712363 -345.13199) (xy 387.664029 -345.145341) (xy 387.61434 -345.152069) (xy 387.589268 -345.152472)
			(xy 387.564199 -345.152047) (xy 387.514516 -345.145298) (xy 387.466181 -345.131966) (xy 387.442964 -345.1225)
			(xy 387.429377 -345.117281) (xy 387.400481 -345.113909) (xy 387.371806 -345.118813) (xy 387.345673 -345.131595)
			(xy 387.324198 -345.151222) (xy 387.316218 -345.163394) (xy 387.301649 -345.186525) (xy 387.266806 -345.228646)
			(xy 387.226183 -345.265225) (xy 387.180652 -345.295476) (xy 387.13119 -345.318752) (xy 387.078859 -345.334552)
			(xy 387.02478 -345.342538) (xy 386.970116 -345.342538) (xy 386.916037 -345.334552) (xy 386.863706 -345.318752)
			(xy 386.814244 -345.295476) (xy 386.768713 -345.265225) (xy 386.72809 -345.228646) (xy 386.693247 -345.186525)
			(xy 386.678678 -345.163394) (xy 386.670755 -345.15117) (xy 386.649283 -345.131499) (xy 386.62313 -345.118695)
			(xy 386.594425 -345.1138) (xy 386.565506 -345.117212) (xy 386.551932 -345.1225) (xy 386.528715 -345.131972)
			(xy 386.480386 -345.14533) (xy 386.430699 -345.152065) (xy 386.405628 -345.152472) (xy 386.377736 -345.152071)
			(xy 386.322576 -345.143761) (xy 386.26927 -345.127322) (xy 386.21901 -345.103121) (xy 386.172918 -345.071699)
			(xy 386.132025 -345.033759) (xy 386.097243 -344.990147) (xy 386.069351 -344.941838) (xy 386.04897 -344.889911)
			(xy 386.036556 -344.835527) (xy 386.032387 -344.7799) (xy 368.247973 -344.7799) (xy 368.189783 -344.788266)
			(xy 368.105182 -344.792297) (xy 368.020581 -344.788266) (xy 367.936746 -344.776213) (xy 367.854437 -344.756245)
			(xy 367.774398 -344.728543) (xy 367.697355 -344.693359) (xy 367.624005 -344.65101) (xy 367.555013 -344.601881)
			(xy 367.491003 -344.546416) (xy 367.432555 -344.485118) (xy 367.380199 -344.418542) (xy 367.334409 -344.34729)
			(xy 367.295598 -344.272009) (xy 367.264119 -344.193379) (xy 367.240258 -344.112112) (xy 367.224229 -344.028946)
			(xy 367.216178 -343.944632) (xy 363.908287 -343.944632) (xy 363.90028 -344.027211) (xy 363.884229 -344.109199)
			(xy 363.86034 -344.189256) (xy 363.828835 -344.266633) (xy 363.79001 -344.340608) (xy 363.744227 -344.410491)
			(xy 363.691912 -344.475628) (xy 363.633555 -344.535413) (xy 363.569701 -344.589286) (xy 363.500945 -344.636745)
			(xy 363.427929 -344.677346) (xy 363.351336 -344.710711) (xy 363.27188 -344.736528) (xy 363.190304 -344.754556)
			(xy 363.107368 -344.764626) (xy 363.023848 -344.766645) (xy 362.940522 -344.760593) (xy 362.85817 -344.746528)
			(xy 362.77756 -344.72458) (xy 362.699444 -344.694954) (xy 362.624552 -344.657928) (xy 362.553584 -344.613847)
			(xy 362.487201 -344.563121) (xy 362.426024 -344.506226) (xy 362.370623 -344.443692) (xy 362.321517 -344.376103)
			(xy 362.279163 -344.30409) (xy 362.243957 -344.228325) (xy 362.216228 -344.149516) (xy 362.196235 -344.068399)
			(xy 362.184163 -343.985731) (xy 362.180127 -343.902284) (xy 361.434126 -343.902284) (xy 361.433622 -343.944632)
			(xy 361.425571 -344.028946) (xy 361.409542 -344.112112) (xy 361.385681 -344.193379) (xy 361.354202 -344.272009)
			(xy 361.315391 -344.34729) (xy 361.269601 -344.418542) (xy 361.217245 -344.485118) (xy 361.158797 -344.546416)
			(xy 361.094787 -344.601881) (xy 361.025795 -344.65101) (xy 360.952445 -344.693359) (xy 360.875402 -344.728543)
			(xy 360.795363 -344.756245) (xy 360.713054 -344.776213) (xy 360.629219 -344.788266) (xy 360.544618 -344.792297)
			(xy 360.460017 -344.788266) (xy 360.376182 -344.776213) (xy 360.293873 -344.756245) (xy 360.213834 -344.728543)
			(xy 360.136791 -344.693359) (xy 360.063441 -344.65101) (xy 359.994449 -344.601881) (xy 359.930439 -344.546416)
			(xy 359.871991 -344.485118) (xy 359.819635 -344.418542) (xy 359.773845 -344.34729) (xy 359.735034 -344.272009)
			(xy 359.703555 -344.193379) (xy 359.679694 -344.112112) (xy 359.663665 -344.028946) (xy 359.655614 -343.944632)
			(xy 356.202943 -343.944632) (xy 356.194936 -344.027211) (xy 356.178885 -344.109199) (xy 356.154996 -344.189256)
			(xy 356.123491 -344.266633) (xy 356.084666 -344.340608) (xy 356.038883 -344.410491) (xy 355.986568 -344.475628)
			(xy 355.928211 -344.535413) (xy 355.864357 -344.589286) (xy 355.795601 -344.636745) (xy 355.722585 -344.677346)
			(xy 355.645992 -344.710711) (xy 355.566536 -344.736528) (xy 355.48496 -344.754556) (xy 355.402024 -344.764626)
			(xy 355.318504 -344.766645) (xy 355.235178 -344.760593) (xy 355.152826 -344.746528) (xy 355.072216 -344.72458)
			(xy 354.9941 -344.694954) (xy 354.919208 -344.657928) (xy 354.84824 -344.613847) (xy 354.781857 -344.563121)
			(xy 354.72068 -344.506226) (xy 354.665279 -344.443692) (xy 354.616173 -344.376103) (xy 354.573819 -344.30409)
			(xy 354.538613 -344.228325) (xy 354.510884 -344.149516) (xy 354.490891 -344.068399) (xy 354.478819 -343.985731)
			(xy 354.474783 -343.902284) (xy 353.728782 -343.902284) (xy 353.728278 -343.944632) (xy 353.720227 -344.028946)
			(xy 353.704198 -344.112112) (xy 353.680337 -344.193379) (xy 353.648858 -344.272009) (xy 353.610047 -344.34729)
			(xy 353.564257 -344.418542) (xy 353.511901 -344.485118) (xy 353.453453 -344.546416) (xy 353.389443 -344.601881)
			(xy 353.320451 -344.65101) (xy 353.247101 -344.693359) (xy 353.170058 -344.728543) (xy 353.090019 -344.756245)
			(xy 353.00771 -344.776213) (xy 352.923875 -344.788266) (xy 352.839274 -344.792297) (xy 352.754673 -344.788266)
			(xy 352.670838 -344.776213) (xy 352.588529 -344.756245) (xy 352.50849 -344.728543) (xy 352.431447 -344.693359)
			(xy 352.358097 -344.65101) (xy 352.289105 -344.601881) (xy 352.225095 -344.546416) (xy 352.166647 -344.485118)
			(xy 352.114291 -344.418542) (xy 352.068501 -344.34729) (xy 352.02969 -344.272009) (xy 351.998211 -344.193379)
			(xy 351.97435 -344.112112) (xy 351.958321 -344.028946) (xy 351.95027 -343.944632) (xy 348.642379 -343.944632)
			(xy 348.634372 -344.027211) (xy 348.618321 -344.109199) (xy 348.594432 -344.189256) (xy 348.562927 -344.266633)
			(xy 348.524102 -344.340608) (xy 348.478319 -344.410491) (xy 348.426004 -344.475628) (xy 348.367647 -344.535413)
			(xy 348.303793 -344.589286) (xy 348.235037 -344.636745) (xy 348.162021 -344.677346) (xy 348.085428 -344.710711)
			(xy 348.005972 -344.736528) (xy 347.924396 -344.754556) (xy 347.84146 -344.764626) (xy 347.75794 -344.766645)
			(xy 347.674614 -344.760593) (xy 347.592262 -344.746528) (xy 347.511652 -344.72458) (xy 347.433536 -344.694954)
			(xy 347.358644 -344.657928) (xy 347.287676 -344.613847) (xy 347.221293 -344.563121) (xy 347.160116 -344.506226)
			(xy 347.104715 -344.443692) (xy 347.055609 -344.376103) (xy 347.013255 -344.30409) (xy 346.978049 -344.228325)
			(xy 346.95032 -344.149516) (xy 346.930327 -344.068399) (xy 346.918255 -343.985731) (xy 346.914219 -343.902284)
			(xy 346.168218 -343.902284) (xy 346.167714 -343.944632) (xy 346.159663 -344.028946) (xy 346.143634 -344.112112)
			(xy 346.119773 -344.193379) (xy 346.088294 -344.272009) (xy 346.049483 -344.34729) (xy 346.003693 -344.418542)
			(xy 345.951337 -344.485118) (xy 345.892889 -344.546416) (xy 345.828879 -344.601881) (xy 345.759887 -344.65101)
			(xy 345.686537 -344.693359) (xy 345.609494 -344.728543) (xy 345.529455 -344.756245) (xy 345.447146 -344.776213)
			(xy 345.363311 -344.788266) (xy 345.27871 -344.792297) (xy 345.194109 -344.788266) (xy 345.110274 -344.776213)
			(xy 345.027965 -344.756245) (xy 344.947926 -344.728543) (xy 344.870883 -344.693359) (xy 344.797533 -344.65101)
			(xy 344.728541 -344.601881) (xy 344.664531 -344.546416) (xy 344.606083 -344.485118) (xy 344.553727 -344.418542)
			(xy 344.507937 -344.34729) (xy 344.469126 -344.272009) (xy 344.437647 -344.193379) (xy 344.413786 -344.112112)
			(xy 344.397757 -344.028946) (xy 344.389706 -343.944632) (xy 325.426565 -343.944632) (xy 325.42583 -343.946919)
			(xy 325.399169 -343.999897) (xy 325.364633 -344.048112) (xy 325.323054 -344.090405) (xy 325.299578 -344.108532)
			(xy 325.287732 -344.118069) (xy 325.26975 -344.142571) (xy 325.259772 -344.171279) (xy 325.258678 -344.201652)
			(xy 325.266567 -344.231003) (xy 325.274178 -344.244168) (xy 325.287977 -344.267016) (xy 325.309721 -344.315762)
			(xy 325.324457 -344.367063) (xy 325.331898 -344.419918) (xy 325.332344 -344.446606) (xy 325.331858 -344.473857)
			(xy 325.324102 -344.527805) (xy 325.308747 -344.5801) (xy 325.286105 -344.629677) (xy 325.256639 -344.675527)
			(xy 325.220948 -344.716718) (xy 325.179757 -344.752409) (xy 325.133907 -344.781875) (xy 325.08433 -344.804517)
			(xy 325.032035 -344.819872) (xy 324.978087 -344.827628) (xy 324.923585 -344.827628) (xy 324.869637 -344.819872)
			(xy 324.817342 -344.804517) (xy 324.767765 -344.781875) (xy 324.721915 -344.752409) (xy 324.680724 -344.716718)
			(xy 324.645033 -344.675527) (xy 324.615567 -344.629677) (xy 324.592925 -344.5801) (xy 324.57757 -344.527805)
			(xy 324.569814 -344.473857) (xy 324.569328 -344.446606) (xy 323.46966 -344.446606) (xy 323.496502 -344.466956)
			(xy 323.546467 -344.514142) (xy 323.591048 -344.566446) (xy 323.629724 -344.623254) (xy 323.646292 -344.653362)
			(xy 323.652887 -344.664972) (xy 323.671137 -344.684455) (xy 323.693813 -344.698542) (xy 323.719366 -344.70627)
			(xy 323.746048 -344.707112) (xy 323.772037 -344.70101) (xy 323.795556 -344.688381) (xy 323.80555 -344.679524)
			(xy 323.826887 -344.660051) (xy 323.874385 -344.627177) (xy 323.926297 -344.60184) (xy 323.981436 -344.584622)
			(xy 324.038541 -344.575915) (xy 324.067424 -344.575384) (xy 324.094675 -344.575855) (xy 324.148623 -344.583615)
			(xy 324.200918 -344.598973) (xy 324.250495 -344.621616) (xy 324.296344 -344.651084) (xy 324.337534 -344.686777)
			(xy 324.373225 -344.727968) (xy 324.402692 -344.773819) (xy 324.425333 -344.823397) (xy 324.430149 -344.8398)
			(xy 328.939331 -344.8398) (xy 328.9435 -344.78418) (xy 328.955912 -344.729802) (xy 328.97629 -344.677882)
			(xy 329.004179 -344.629579) (xy 329.038956 -344.585973) (xy 329.079844 -344.548037) (xy 329.12593 -344.516619)
			(xy 329.176183 -344.492421) (xy 329.229482 -344.475983) (xy 329.284636 -344.467673) (xy 329.312524 -344.46718)
			(xy 329.339854 -344.467705) (xy 329.39393 -344.475668) (xy 329.446262 -344.491448) (xy 329.495725 -344.514708)
			(xy 329.541258 -344.544947) (xy 329.581882 -344.581516) (xy 329.616726 -344.62363) (xy 329.631294 -344.646758)
			(xy 329.639256 -344.658956) (xy 329.660714 -344.678632) (xy 329.686857 -344.691442) (xy 329.715555 -344.696344)
			(xy 329.744468 -344.692937) (xy 329.75804 -344.687652) (xy 329.781247 -344.678155) (xy 329.829581 -344.664808)
			(xy 329.879272 -344.658082) (xy 329.904344 -344.65768) (xy 329.929413 -344.658105) (xy 329.979096 -344.664855)
			(xy 330.02743 -344.678187) (xy 330.050648 -344.687652) (xy 330.064237 -344.692861) (xy 330.09313 -344.696228)
			(xy 330.121802 -344.691324) (xy 330.147934 -344.678545) (xy 330.16941 -344.658926) (xy 330.177394 -344.646758)
			(xy 330.191963 -344.623627) (xy 330.226806 -344.581506) (xy 330.267429 -344.544927) (xy 330.31296 -344.514676)
			(xy 330.362422 -344.4914) (xy 330.414753 -344.4756) (xy 330.468832 -344.467614) (xy 330.523496 -344.467614)
			(xy 330.577575 -344.4756) (xy 330.629906 -344.4914) (xy 330.679368 -344.514676) (xy 330.724899 -344.544927)
			(xy 330.765522 -344.581506) (xy 330.800365 -344.623627) (xy 330.814934 -344.646758) (xy 330.822858 -344.658983)
			(xy 330.844326 -344.678659) (xy 330.87048 -344.691467) (xy 330.899187 -344.696361) (xy 330.928107 -344.692944)
			(xy 330.94168 -344.687652) (xy 330.964894 -344.678174) (xy 331.013225 -344.664819) (xy 331.062913 -344.658086)
			(xy 331.087984 -344.65768) (xy 331.114841 -344.658135) (xy 331.167998 -344.665853) (xy 331.219498 -344.681117)
			(xy 331.268276 -344.703613) (xy 331.313321 -344.732873) (xy 331.353703 -344.768293) (xy 331.388585 -344.80914)
			(xy 331.417247 -344.854569) (xy 331.428598 -344.878914) (xy 331.434622 -344.891386) (xy 331.452244 -344.912739)
			(xy 331.474963 -344.92856) (xy 331.501102 -344.937683) (xy 331.528733 -344.939433) (xy 331.555814 -344.933682)
			(xy 331.568298 -344.927682) (xy 331.595706 -344.914059) (xy 331.653801 -344.894808) (xy 331.714226 -344.885084)
			(xy 331.744828 -344.884502) (xy 331.767947 -344.884832) (xy 331.813848 -344.890401) (xy 331.858736 -344.90149)
			(xy 331.880464 -344.909394) (xy 331.894243 -344.914198) (xy 331.923328 -344.916452) (xy 331.951865 -344.910395)
			(xy 331.977527 -344.896521) (xy 331.998222 -344.87596) (xy 332.012263 -344.850389) (xy 332.015846 -344.836242)
			(xy 332.022456 -344.808278) (xy 332.043051 -344.754635) (xy 332.071459 -344.704687) (xy 332.107036 -344.659565)
			(xy 332.148979 -344.620289) (xy 332.196338 -344.587748) (xy 332.248042 -344.562678) (xy 332.302921 -344.545646)
			(xy 332.359733 -344.537038) (xy 332.388464 -344.536522) (xy 332.415717 -344.536989) (xy 332.46967 -344.544742)
			(xy 332.521969 -344.560095) (xy 332.571551 -344.582735) (xy 332.617406 -344.612202) (xy 332.6586 -344.647896)
			(xy 332.694294 -344.689089) (xy 332.723762 -344.734943) (xy 332.746403 -344.784525) (xy 332.761757 -344.836824)
			(xy 332.769511 -344.890777) (xy 332.769972 -344.91803) (xy 332.76953 -344.945401) (xy 332.761708 -344.999582)
			(xy 332.746213 -345.052085) (xy 332.723366 -345.101832) (xy 332.693636 -345.147797) (xy 332.675992 -345.168728)
			(xy 332.666727 -345.180034) (xy 332.654554 -345.2066) (xy 332.650387 -345.235523) (xy 332.654567 -345.264444)
			(xy 332.666752 -345.291004) (xy 332.675992 -345.302332) (xy 332.693611 -345.32328) (xy 332.723326 -345.369248)
			(xy 332.746166 -345.418992) (xy 332.761662 -345.471489) (xy 332.769495 -345.525662) (xy 332.769972 -345.55303)
			(xy 332.769468 -345.580603) (xy 332.761525 -345.635175) (xy 332.745808 -345.688034) (xy 332.722645 -345.738081)
			(xy 332.692519 -345.784271) (xy 332.656057 -345.825644) (xy 332.635352 -345.84386) (xy 332.62442 -345.853726)
			(xy 332.608341 -345.878383) (xy 332.599957 -345.906601) (xy 332.599962 -345.936038) (xy 332.608358 -345.964252)
			(xy 332.624446 -345.988904) (xy 332.635352 -345.9988) (xy 332.656057 -346.017018) (xy 332.69253 -346.058384)
			(xy 332.722664 -346.104572) (xy 332.745831 -346.154619) (xy 332.761548 -346.207481) (xy 332.769487 -346.262055)
			(xy 332.769972 -346.28963) (xy 332.769573 -346.316885) (xy 332.761811 -346.37084) (xy 332.746449 -346.423142)
			(xy 332.723801 -346.472724) (xy 332.694326 -346.518579) (xy 332.678323 -346.537044) (xy 382.033826 -346.537044)
			(xy 382.033826 -346.482551) (xy 382.041582 -346.428612) (xy 382.056934 -346.376326) (xy 382.079571 -346.326756)
			(xy 382.109032 -346.280913) (xy 382.144717 -346.239729) (xy 382.185899 -346.204042) (xy 382.231741 -346.174579)
			(xy 382.281309 -346.15194) (xy 382.333595 -346.136585) (xy 382.387533 -346.128828) (xy 382.41478 -346.12834)
			(xy 382.43435 -346.128544) (xy 382.473291 -346.132488) (xy 382.492504 -346.136214) (xy 382.506172 -346.138647)
			(xy 382.533865 -346.136801) (xy 382.560034 -346.127559) (xy 382.582744 -346.111605) (xy 382.600312 -346.090118)
			(xy 382.611437 -346.064692) (xy 382.615296 -346.037208) (xy 382.611603 -346.009701) (xy 382.60655 -345.996768)
			(xy 382.596661 -345.972815) (xy 382.582754 -345.922894) (xy 382.57574 -345.871549) (xy 382.575308 -345.845638)
			(xy 382.575714 -345.818382) (xy 382.583467 -345.764424) (xy 382.59882 -345.712119) (xy 382.62146 -345.662531)
			(xy 382.650927 -345.61667) (xy 382.686621 -345.57547) (xy 382.727815 -345.539768) (xy 382.773671 -345.510293)
			(xy 382.823255 -345.487644) (xy 382.875557 -345.472281) (xy 382.929513 -345.464519) (xy 382.984025 -345.464515)
			(xy 383.037983 -345.472268) (xy 383.090288 -345.487622) (xy 383.139875 -345.510263) (xy 383.185736 -345.539731)
			(xy 383.226936 -345.575426) (xy 383.262636 -345.616621) (xy 383.292111 -345.662477) (xy 383.314759 -345.712061)
			(xy 383.33012 -345.764364) (xy 383.337881 -345.818321) (xy 383.337885 -345.872833) (xy 383.33013 -345.92679)
			(xy 383.314775 -345.979095) (xy 383.292133 -346.028682) (xy 383.262664 -346.074542) (xy 383.226969 -346.115741)
			(xy 383.185773 -346.151441) (xy 383.139916 -346.180914) (xy 383.090332 -346.203562) (xy 383.038029 -346.218922)
			(xy 382.984072 -346.226682) (xy 382.956816 -346.227146) (xy 382.937246 -346.226943) (xy 382.898305 -346.222999)
			(xy 382.879092 -346.219272) (xy 382.865405 -346.216953) (xy 382.837722 -346.218776) (xy 382.811557 -346.227999)
			(xy 382.78885 -346.243937) (xy 382.771282 -346.265408) (xy 382.760157 -346.290823) (xy 382.756298 -346.318296)
			(xy 382.759992 -346.345791) (xy 382.765046 -346.358718) (xy 382.774931 -346.382673) (xy 382.78884 -346.432593)
			(xy 382.795855 -346.483937) (xy 382.796288 -346.509848) (xy 382.79577 -346.537095) (xy 382.788009 -346.591033)
			(xy 382.77265 -346.643317) (xy 382.750007 -346.692884) (xy 382.720541 -346.738723) (xy 382.684851 -346.779903)
			(xy 382.643665 -346.815585) (xy 382.597819 -346.845042) (xy 382.548248 -346.867676) (xy 382.495961 -346.883024)
			(xy 382.442021 -346.890776) (xy 382.387528 -346.890772) (xy 382.33359 -346.883014) (xy 382.281304 -346.867658)
			(xy 382.231736 -346.845018) (xy 382.185895 -346.815555) (xy 382.144713 -346.779867) (xy 382.109029 -346.738683)
			(xy 382.079568 -346.692839) (xy 382.056932 -346.643269) (xy 382.04158 -346.590983) (xy 382.033826 -346.537044)
			(xy 332.678323 -346.537044) (xy 332.658626 -346.559772) (xy 332.617426 -346.595466) (xy 332.571566 -346.624932)
			(xy 332.52198 -346.647572) (xy 332.469676 -346.662925) (xy 332.415719 -346.670678) (xy 332.388464 -346.671138)
			(xy 332.360591 -346.670614) (xy 332.305439 -346.662496) (xy 332.252055 -346.646438) (xy 332.201576 -346.622782)
			(xy 332.155078 -346.592032) (xy 332.11355 -346.554842) (xy 332.077876 -346.512004) (xy 332.048817 -346.464431)
			(xy 332.037436 -346.438982) (xy 332.030807 -346.424806) (xy 332.01038 -346.401115) (xy 331.983751 -346.384701)
			(xy 331.953407 -346.377099) (xy 331.922185 -346.379018) (xy 331.907388 -346.384118) (xy 331.885434 -346.392189)
			(xy 331.840046 -346.4035) (xy 331.793616 -346.409181) (xy 331.770228 -346.409518) (xy 331.756079 -346.409421)
			(xy 331.727856 -346.407389) (xy 331.71384 -346.405454) (xy 331.700495 -346.403821) (xy 331.673795 -346.406923)
			(xy 331.648836 -346.416899) (xy 331.627353 -346.433054) (xy 331.610843 -346.454264) (xy 331.600453 -346.479054)
			(xy 331.59827 -346.492322) (xy 331.594113 -346.519464) (xy 331.579146 -346.57229) (xy 331.556761 -346.622425)
			(xy 331.527421 -346.668834) (xy 331.491731 -346.710557) (xy 331.45043 -346.746735) (xy 331.404369 -346.776618)
			(xy 331.3545 -346.79959) (xy 331.301854 -346.815177) (xy 331.247517 -346.823056) (xy 331.220064 -346.823538)
			(xy 331.192813 -346.823056) (xy 331.138867 -346.815295) (xy 331.086574 -346.799937) (xy 331.036999 -346.777294)
			(xy 330.99115 -346.747827) (xy 330.949961 -346.712135) (xy 330.91427 -346.670945) (xy 330.884803 -346.625096)
			(xy 330.862161 -346.57552) (xy 330.846804 -346.523227) (xy 330.839044 -346.469281) (xy 330.838556 -346.44203)
			(xy 330.839023 -346.414455) (xy 330.846972 -346.359882) (xy 330.862696 -346.307021) (xy 330.885866 -346.256974)
			(xy 330.915999 -346.210785) (xy 330.952468 -346.169415) (xy 330.973176 -346.1512) (xy 330.984045 -346.141272)
			(xy 331.000122 -346.116631) (xy 331.008511 -346.08843) (xy 331.008517 -346.059008) (xy 331.000138 -346.030805)
			(xy 330.984071 -346.006157) (xy 330.973176 -345.99626) (xy 330.952486 -345.978026) (xy 330.916015 -345.936662)
			(xy 330.885881 -345.890476) (xy 330.862712 -345.840433) (xy 330.84699 -345.787575) (xy 330.839045 -345.733003)
			(xy 330.838556 -345.70543) (xy 330.839066 -345.675958) (xy 330.848108 -345.617712) (xy 330.865997 -345.561549)
			(xy 330.892307 -345.508804) (xy 330.908914 -345.48445) (xy 330.91637 -345.473083) (xy 330.925686 -345.44756)
			(xy 330.927945 -345.420484) (xy 330.922989 -345.39377) (xy 330.911167 -345.369307) (xy 330.893316 -345.348824)
			(xy 330.882244 -345.34094) (xy 330.859621 -345.325432) (xy 330.818807 -345.288794) (xy 330.783827 -345.246549)
			(xy 330.769214 -345.223338) (xy 330.761245 -345.211145) (xy 330.739789 -345.19147) (xy 330.713648 -345.178659)
			(xy 330.684951 -345.173756) (xy 330.656039 -345.17716) (xy 330.642468 -345.182444) (xy 330.61926 -345.191938)
			(xy 330.570926 -345.205287) (xy 330.521236 -345.212013) (xy 330.496164 -345.212416) (xy 330.471095 -345.211988)
			(xy 330.421412 -345.20524) (xy 330.373078 -345.191909) (xy 330.34986 -345.182444) (xy 330.336267 -345.177245)
			(xy 330.307376 -345.173876) (xy 330.278705 -345.178779) (xy 330.252575 -345.191555) (xy 330.231098 -345.211171)
			(xy 330.223114 -345.223338) (xy 330.208545 -345.246469) (xy 330.173702 -345.28859) (xy 330.133079 -345.325169)
			(xy 330.087548 -345.35542) (xy 330.038086 -345.378696) (xy 329.985755 -345.394496) (xy 329.931676 -345.402482)
			(xy 329.877012 -345.402482) (xy 329.822933 -345.394496) (xy 329.770602 -345.378696) (xy 329.72114 -345.35542)
			(xy 329.675609 -345.325169) (xy 329.634986 -345.28859) (xy 329.600143 -345.246469) (xy 329.585574 -345.223338)
			(xy 329.577644 -345.211118) (xy 329.556177 -345.191442) (xy 329.530025 -345.178634) (xy 329.50132 -345.173738)
			(xy 329.472401 -345.177154) (xy 329.458828 -345.182444) (xy 329.435613 -345.191919) (xy 329.387282 -345.205275)
			(xy 329.337595 -345.212009) (xy 329.312524 -345.212416) (xy 329.284636 -345.211927) (xy 329.229482 -345.203617)
			(xy 329.176183 -345.187179) (xy 329.12593 -345.162981) (xy 329.079844 -345.131563) (xy 329.038956 -345.093627)
			(xy 329.004179 -345.050021) (xy 328.97629 -345.001718) (xy 328.955912 -344.949798) (xy 328.9435 -344.89542)
			(xy 328.939331 -344.8398) (xy 324.430149 -344.8398) (xy 324.440688 -344.875692) (xy 324.448446 -344.929641)
			(xy 324.448932 -344.956892) (xy 324.448501 -344.983094) (xy 324.441325 -345.035004) (xy 324.427106 -345.085442)
			(xy 324.406113 -345.133457) (xy 324.392798 -345.156028) (xy 324.385432 -345.16822) (xy 324.385432 -345.337384)
			(xy 324.384935 -345.36237) (xy 324.377104 -345.411725) (xy 324.361647 -345.459247) (xy 324.338946 -345.503765)
			(xy 324.30956 -345.544184) (xy 324.292214 -345.562174) (xy 324.234302 -345.620086) (xy 324.225004 -345.630009)
			(xy 324.211582 -345.653648) (xy 324.204872 -345.679992) (xy 324.20535 -345.707172) (xy 324.212983 -345.733262)
			(xy 324.22723 -345.756414) (xy 324.24708 -345.774987) (xy 324.271127 -345.787664) (xy 324.297667 -345.793548)
			(xy 324.311264 -345.793314) (xy 324.330314 -345.792806) (xy 324.357564 -345.793293) (xy 324.411508 -345.801051)
			(xy 324.4638 -345.816407) (xy 324.513374 -345.839049) (xy 324.559221 -345.868515) (xy 324.600408 -345.904205)
			(xy 324.601601 -345.905582) (xy 325.481694 -345.905582) (xy 325.485765 -345.84996) (xy 325.497891 -345.795523)
			(xy 325.517814 -345.743432) (xy 325.54511 -345.694797) (xy 325.579196 -345.650654) (xy 325.619345 -345.611945)
			(xy 325.664703 -345.579494) (xy 325.714303 -345.553993) (xy 325.767087 -345.535986) (xy 325.82193 -345.525856)
			(xy 325.877664 -345.523819) (xy 325.933101 -345.529919) (xy 325.987058 -345.544025) (xy 326.038387 -345.565837)
			(xy 326.085993 -345.594891) (xy 326.128861 -345.630566) (xy 326.166078 -345.672103) (xy 326.196851 -345.718616)
			(xy 326.220523 -345.769113) (xy 326.236591 -345.82252) (xy 326.244711 -345.877696) (xy 326.24522 -345.905582)
			(xy 326.244711 -345.933468) (xy 326.236591 -345.988644) (xy 326.220523 -346.042051) (xy 326.196851 -346.092548)
			(xy 326.166078 -346.139061) (xy 326.128861 -346.180598) (xy 326.085993 -346.216273) (xy 326.038387 -346.245327)
			(xy 325.987058 -346.267139) (xy 325.933101 -346.281245) (xy 325.877664 -346.287345) (xy 325.82193 -346.285308)
			(xy 325.767087 -346.275178) (xy 325.714303 -346.257171) (xy 325.664703 -346.23167) (xy 325.619345 -346.199219)
			(xy 325.579196 -346.16051) (xy 325.54511 -346.116367) (xy 325.517814 -346.067732) (xy 325.497891 -346.015641)
			(xy 325.485765 -345.961204) (xy 325.481694 -345.905582) (xy 324.601601 -345.905582) (xy 324.636097 -345.945394)
			(xy 324.66556 -345.991243) (xy 324.688199 -346.040818) (xy 324.703553 -346.09311) (xy 324.711308 -346.147055)
			(xy 324.711307 -346.201554) (xy 324.703551 -346.255499) (xy 324.688196 -346.307791) (xy 324.665556 -346.357365)
			(xy 324.636091 -346.403213) (xy 324.600401 -346.444401) (xy 324.559213 -346.480091) (xy 324.513365 -346.509556)
			(xy 324.463791 -346.532196) (xy 324.411499 -346.547551) (xy 324.357554 -346.555307) (xy 324.303055 -346.555308)
			(xy 324.24911 -346.547553) (xy 324.196818 -346.532199) (xy 324.147243 -346.50956) (xy 324.101394 -346.480097)
			(xy 324.060205 -346.444408) (xy 324.024515 -346.403221) (xy 323.995049 -346.357374) (xy 323.972407 -346.3078)
			(xy 323.957051 -346.255508) (xy 323.949293 -346.201564) (xy 323.948806 -346.174314) (xy 323.949314 -346.155264)
			(xy 323.949513 -346.141652) (xy 323.943687 -346.115076) (xy 323.931041 -346.090987) (xy 323.912474 -346.0711)
			(xy 323.889308 -346.056832) (xy 323.863194 -346.049198) (xy 323.835991 -346.048743) (xy 323.809635 -346.055498)
			(xy 323.786005 -346.068982) (xy 323.776086 -346.078302) (xy 323.229732 -346.624656) (xy 323.211717 -346.641964)
			(xy 323.171297 -346.671317) (xy 323.12678 -346.69398) (xy 323.079263 -346.709393) (xy 323.029919 -346.717174)
			(xy 323.004942 -346.71762) (xy 315.575442 -346.71762) (xy 313.883079 -348.410022) (xy 321.94754 -348.410022)
			(xy 321.947925 -348.38364) (xy 321.955189 -348.331379) (xy 321.969582 -348.280617) (xy 321.990828 -348.23232)
			(xy 322.018525 -348.18741) (xy 322.052142 -348.146743) (xy 322.09104 -348.111093) (xy 322.134478 -348.081141)
			(xy 322.157852 -348.0689) (xy 322.170193 -348.062167) (xy 322.190922 -348.043198) (xy 322.205685 -348.01929)
			(xy 322.213359 -347.992259) (xy 322.213362 -347.96416) (xy 322.205693 -347.937128) (xy 322.190935 -347.913217)
			(xy 322.170209 -347.894244) (xy 322.157852 -347.887544) (xy 322.13448 -347.875306) (xy 322.091058 -347.845342)
			(xy 322.052174 -347.809685) (xy 322.018569 -347.769015) (xy 321.990883 -347.724105) (xy 321.969642 -347.675813)
			(xy 321.955252 -347.625056) (xy 321.947987 -347.572801) (xy 321.94754 -347.546422) (xy 321.948026 -347.519171)
			(xy 321.955782 -347.465223) (xy 321.971137 -347.412928) (xy 321.993779 -347.363351) (xy 322.023245 -347.317501)
			(xy 322.058936 -347.27631) (xy 322.100127 -347.240619) (xy 322.145977 -347.211153) (xy 322.195554 -347.188511)
			(xy 322.247849 -347.173156) (xy 322.301797 -347.1654) (xy 322.356299 -347.1654) (xy 322.410247 -347.173156)
			(xy 322.462542 -347.188511) (xy 322.512119 -347.211153) (xy 322.557969 -347.240619) (xy 322.59916 -347.27631)
			(xy 322.634851 -347.317501) (xy 322.664317 -347.363351) (xy 322.686959 -347.412928) (xy 322.702314 -347.465223)
			(xy 322.707196 -347.499178) (xy 326.2884 -347.499178) (xy 326.288939 -347.469489) (xy 326.298141 -347.410829)
			(xy 326.31632 -347.354303) (xy 326.343036 -347.301276) (xy 326.377645 -347.253028) (xy 326.41931 -347.210723)
			(xy 326.442832 -347.1926) (xy 326.453471 -347.184212) (xy 326.470174 -347.162889) (xy 326.480687 -347.137927)
			(xy 326.484272 -347.11108) (xy 326.480677 -347.084233) (xy 326.470153 -347.059275) (xy 326.453442 -347.03796)
			(xy 326.442832 -347.029532) (xy 326.419344 -347.011369) (xy 326.37768 -346.969072) (xy 326.343072 -346.920831)
			(xy 326.316356 -346.867811) (xy 326.298175 -346.811292) (xy 326.288969 -346.752639) (xy 326.2884 -346.722954)
			(xy 326.288886 -346.695703) (xy 326.296642 -346.641755) (xy 326.311997 -346.58946) (xy 326.334639 -346.539883)
			(xy 326.364105 -346.494033) (xy 326.399796 -346.452842) (xy 326.440987 -346.417151) (xy 326.486837 -346.387685)
			(xy 326.536414 -346.365043) (xy 326.588709 -346.349688) (xy 326.642657 -346.341932) (xy 326.697159 -346.341932)
			(xy 326.751107 -346.349688) (xy 326.803402 -346.365043) (xy 326.852979 -346.387685) (xy 326.898829 -346.417151)
			(xy 326.94002 -346.452842) (xy 326.975711 -346.494033) (xy 327.005177 -346.539883) (xy 327.027819 -346.58946)
			(xy 327.043174 -346.641755) (xy 327.05093 -346.695703) (xy 327.051416 -346.722954) (xy 327.050821 -346.75264)
			(xy 327.04163 -346.811297) (xy 327.023462 -346.867822) (xy 326.996756 -346.92085) (xy 326.984707 -346.937653)
			(xy 327.304861 -346.937653) (xy 327.304861 -346.883147) (xy 327.312618 -346.829196) (xy 327.327975 -346.776899)
			(xy 327.350617 -346.727319) (xy 327.380086 -346.681466) (xy 327.41578 -346.640274) (xy 327.456973 -346.604581)
			(xy 327.502826 -346.575113) (xy 327.552406 -346.552472) (xy 327.604704 -346.537117) (xy 327.658655 -346.529361)
			(xy 327.685908 -346.528898) (xy 327.711143 -346.529292) (xy 327.761178 -346.535911) (xy 327.809898 -346.549085)
			(xy 327.85645 -346.568583) (xy 327.87844 -346.580968) (xy 327.891398 -346.58802) (xy 327.920037 -346.595048)
			(xy 327.94949 -346.593599) (xy 327.977302 -346.583795) (xy 328.001152 -346.566452) (xy 328.019051 -346.543016)
			(xy 328.024744 -346.529406) (xy 328.035473 -346.502644) (xy 328.063756 -346.452403) (xy 328.099281 -346.406993)
			(xy 328.141238 -346.367449) (xy 328.188671 -346.334674) (xy 328.240497 -346.309414) (xy 328.295536 -346.292244)
			(xy 328.352533 -346.283558) (xy 328.38136 -346.283026) (xy 328.408613 -346.283493) (xy 328.462566 -346.291245)
			(xy 328.514866 -346.306598) (xy 328.564448 -346.329238) (xy 328.610303 -346.358705) (xy 328.651497 -346.394399)
			(xy 328.687191 -346.435592) (xy 328.716659 -346.481447) (xy 328.7393 -346.531028) (xy 328.754654 -346.583328)
			(xy 328.762407 -346.637281) (xy 328.762868 -346.664534) (xy 328.76233 -346.694439) (xy 328.753019 -346.753518)
			(xy 328.744326 -346.782136) (xy 328.740293 -346.796046) (xy 328.739378 -346.824979) (xy 328.74664 -346.853002)
			(xy 328.761492 -346.877849) (xy 328.782735 -346.897514) (xy 328.808653 -346.910408) (xy 328.822812 -346.913454)
			(xy 328.84889 -346.918601) (xy 328.899396 -346.935172) (xy 328.947111 -346.958596) (xy 328.991111 -346.98842)
			(xy 329.030542 -347.024066) (xy 329.064641 -347.064842) (xy 329.092747 -347.109958) (xy 329.114315 -347.158541)
			(xy 329.128927 -347.209648) (xy 329.1363 -347.262289) (xy 329.136756 -347.288866) (xy 329.13627 -347.316117)
			(xy 329.128514 -347.370065) (xy 329.113159 -347.42236) (xy 329.105453 -347.439234) (xy 383.381504 -347.439234)
			(xy 383.382082 -347.409547) (xy 383.391276 -347.350889) (xy 383.409446 -347.294363) (xy 383.436155 -347.241336)
			(xy 383.470757 -347.193086) (xy 383.512417 -347.15078) (xy 383.535936 -347.132656) (xy 383.546519 -347.124203)
			(xy 383.563221 -347.102895) (xy 383.573738 -347.077948) (xy 383.57733 -347.051113) (xy 383.573745 -347.024278)
			(xy 383.563235 -346.999328) (xy 383.546538 -346.978015) (xy 383.535936 -346.969588) (xy 383.512428 -346.95145)
			(xy 383.470765 -346.909147) (xy 383.436159 -346.860901) (xy 383.409446 -346.807877) (xy 383.39127 -346.751353)
			(xy 383.38207 -346.692697) (xy 383.381504 -346.66301) (xy 383.38199 -346.635759) (xy 383.389746 -346.581811)
			(xy 383.405101 -346.529516) (xy 383.427743 -346.479939) (xy 383.457209 -346.434089) (xy 383.4929 -346.392898)
			(xy 383.534091 -346.357207) (xy 383.579941 -346.327741) (xy 383.629518 -346.305099) (xy 383.681813 -346.289744)
			(xy 383.735761 -346.281988) (xy 383.790263 -346.281988) (xy 383.844211 -346.289744) (xy 383.896506 -346.305099)
			(xy 383.946083 -346.327741) (xy 383.991933 -346.357207) (xy 384.033124 -346.392898) (xy 384.068815 -346.434089)
			(xy 384.098281 -346.479939) (xy 384.120923 -346.529516) (xy 384.136278 -346.581811) (xy 384.144034 -346.635759)
			(xy 384.14452 -346.66301) (xy 384.143964 -346.692698) (xy 384.134764 -346.751357) (xy 384.116589 -346.807882)
			(xy 384.089876 -346.860909) (xy 384.077793 -346.877756) (xy 384.397917 -346.877756) (xy 384.397917 -346.823244)
			(xy 384.405675 -346.769286) (xy 384.421033 -346.716982) (xy 384.443679 -346.667396) (xy 384.473151 -346.621538)
			(xy 384.50885 -346.580341) (xy 384.550048 -346.544644) (xy 384.595907 -346.515173) (xy 384.645494 -346.492529)
			(xy 384.697798 -346.477172) (xy 384.751756 -346.469416) (xy 384.779012 -346.468954) (xy 384.804247 -346.469352)
			(xy 384.854281 -346.475971) (xy 384.903001 -346.489144) (xy 384.949553 -346.50864) (xy 384.971544 -346.521024)
			(xy 384.984489 -346.528103) (xy 385.013135 -346.535136) (xy 385.042595 -346.533686) (xy 385.070411 -346.523876)
			(xy 385.094263 -346.506524) (xy 385.112159 -346.483078) (xy 385.117848 -346.469462) (xy 385.128551 -346.442689)
			(xy 385.156839 -346.392449) (xy 385.192369 -346.347041) (xy 385.23433 -346.307499) (xy 385.281766 -346.274725)
			(xy 385.333596 -346.249467) (xy 385.388637 -346.232299) (xy 385.445636 -346.223613) (xy 385.474464 -346.223082)
			(xy 385.501716 -346.223589) (xy 385.555664 -346.231341) (xy 385.607961 -346.246692) (xy 385.65754 -346.269329)
			(xy 385.703393 -346.298792) (xy 385.744586 -346.334482) (xy 385.78028 -346.37567) (xy 385.809749 -346.421519)
			(xy 385.832392 -346.471096) (xy 385.84775 -346.523391) (xy 385.855508 -346.577339) (xy 385.855972 -346.60459)
			(xy 385.855447 -346.634495) (xy 385.846127 -346.693574) (xy 385.83743 -346.722192) (xy 385.833331 -346.736085)
			(xy 385.832428 -346.765028) (xy 385.839703 -346.793056) (xy 385.854568 -346.817907) (xy 385.875823 -346.837573)
			(xy 385.901752 -346.850466) (xy 385.915916 -346.85351) (xy 385.941986 -346.858696) (xy 385.992488 -346.875265)
			(xy 386.040201 -346.898686) (xy 386.084199 -346.928506) (xy 386.12363 -346.964147) (xy 386.157729 -347.004918)
			(xy 386.185837 -347.05003) (xy 386.207407 -347.098607) (xy 386.222023 -347.149709) (xy 386.229401 -347.202346)
			(xy 386.22986 -347.228922) (xy 386.229374 -347.256173) (xy 386.221618 -347.310121) (xy 386.206263 -347.362416)
			(xy 386.183621 -347.411993) (xy 386.154155 -347.457843) (xy 386.118464 -347.499034) (xy 386.077273 -347.534725)
			(xy 386.031423 -347.564191) (xy 385.981846 -347.586833) (xy 385.929551 -347.602188) (xy 385.875603 -347.609944)
			(xy 385.821101 -347.609944) (xy 385.767153 -347.602188) (xy 385.714858 -347.586833) (xy 385.665281 -347.564191)
			(xy 385.619431 -347.534725) (xy 385.57824 -347.499034) (xy 385.542549 -347.457843) (xy 385.513083 -347.411993)
			(xy 385.490441 -347.362416) (xy 385.475086 -347.310121) (xy 385.46733 -347.256173) (xy 385.466844 -347.228922)
			(xy 385.467375 -347.199017) (xy 385.476691 -347.139938) (xy 385.485386 -347.11132) (xy 385.489459 -347.097421)
			(xy 385.490364 -347.068483) (xy 385.483092 -347.040458) (xy 385.468233 -347.015609) (xy 385.446984 -346.995944)
			(xy 385.421061 -346.983049) (xy 385.4069 -346.980002) (xy 385.37406 -346.973421) (xy 385.311208 -346.950297)
			(xy 385.281932 -346.934028) (xy 385.26899 -346.926946) (xy 385.240345 -346.919923) (xy 385.210887 -346.921377)
			(xy 385.183072 -346.931188) (xy 385.159221 -346.948537) (xy 385.141321 -346.971977) (xy 385.135628 -346.98559)
			(xy 385.12492 -347.012361) (xy 385.096635 -347.062604) (xy 385.061107 -347.108014) (xy 385.019147 -347.147557)
			(xy 384.971711 -347.180332) (xy 384.919882 -347.20559) (xy 384.86484 -347.222757) (xy 384.80784 -347.23144)
			(xy 384.779012 -347.23197) (xy 384.751756 -347.231584) (xy 384.697798 -347.223828) (xy 384.645494 -347.208471)
			(xy 384.595907 -347.185827) (xy 384.550048 -347.156356) (xy 384.50885 -347.120659) (xy 384.473151 -347.079462)
			(xy 384.443679 -347.033604) (xy 384.421033 -346.984018) (xy 384.405675 -346.931714) (xy 384.397917 -346.877756)
			(xy 384.077793 -346.877756) (xy 384.05527 -346.909158) (xy 384.013608 -346.951464) (xy 383.990088 -346.969588)
			(xy 383.979459 -346.977989) (xy 383.962753 -346.999307) (xy 383.952237 -347.024267) (xy 383.948649 -347.051113)
			(xy 383.952243 -347.077958) (xy 383.962766 -347.102915) (xy 383.979478 -347.12423) (xy 383.990088 -347.132656)
			(xy 384.013622 -347.150762) (xy 384.055282 -347.193072) (xy 384.089884 -347.241325) (xy 384.116593 -347.294356)
			(xy 384.134764 -347.350884) (xy 384.143958 -347.409545) (xy 384.14452 -347.439234) (xy 384.144034 -347.466485)
			(xy 384.136278 -347.520433) (xy 384.120923 -347.572728) (xy 384.098281 -347.622305) (xy 384.068815 -347.668155)
			(xy 384.033124 -347.709346) (xy 383.991933 -347.745037) (xy 383.946083 -347.774503) (xy 383.896506 -347.797145)
			(xy 383.844211 -347.8125) (xy 383.790263 -347.820256) (xy 383.735761 -347.820256) (xy 383.681813 -347.8125)
			(xy 383.629518 -347.797145) (xy 383.579941 -347.774503) (xy 383.534091 -347.745037) (xy 383.4929 -347.709346)
			(xy 383.457209 -347.668155) (xy 383.427743 -347.622305) (xy 383.405101 -347.572728) (xy 383.389746 -347.520433)
			(xy 383.38199 -347.466485) (xy 383.381504 -347.439234) (xy 329.105453 -347.439234) (xy 329.090517 -347.471937)
			(xy 329.061051 -347.517787) (xy 329.02536 -347.558978) (xy 328.984169 -347.594669) (xy 328.938319 -347.624135)
			(xy 328.888742 -347.646777) (xy 328.836447 -347.662132) (xy 328.782499 -347.669888) (xy 328.727997 -347.669888)
			(xy 328.674049 -347.662132) (xy 328.621754 -347.646777) (xy 328.572177 -347.624135) (xy 328.526327 -347.594669)
			(xy 328.485136 -347.558978) (xy 328.449445 -347.517787) (xy 328.419979 -347.471937) (xy 328.397337 -347.42236)
			(xy 328.381982 -347.370065) (xy 328.374226 -347.316117) (xy 328.37374 -347.288866) (xy 328.374282 -347.258961)
			(xy 328.38359 -347.199882) (xy 328.392282 -347.171264) (xy 328.396308 -347.157353) (xy 328.397223 -347.128421)
			(xy 328.389962 -347.1004) (xy 328.375111 -347.075553) (xy 328.35387 -347.055888) (xy 328.327954 -347.042993)
			(xy 328.313796 -347.039946) (xy 328.280955 -347.033371) (xy 328.218103 -347.010243) (xy 328.188828 -346.993972)
			(xy 328.175839 -346.98698) (xy 328.147211 -346.979935) (xy 328.117765 -346.98137) (xy 328.089957 -346.991163)
			(xy 328.06611 -347.008498) (xy 328.048214 -347.031927) (xy 328.042524 -347.045534) (xy 328.031843 -347.072316)
			(xy 328.003552 -347.122557) (xy 327.968019 -347.167966) (xy 327.926055 -347.207508) (xy 327.878616 -347.24028)
			(xy 327.826783 -347.265537) (xy 327.771739 -347.282702) (xy 327.714737 -347.291385) (xy 327.685908 -347.291914)
			(xy 327.658655 -347.291439) (xy 327.604704 -347.283683) (xy 327.552406 -347.268328) (xy 327.502826 -347.245687)
			(xy 327.456973 -347.216219) (xy 327.41578 -347.180526) (xy 327.380086 -347.139334) (xy 327.350617 -347.093481)
			(xy 327.327975 -347.043901) (xy 327.312618 -346.991604) (xy 327.304861 -346.937653) (xy 326.984707 -346.937653)
			(xy 326.962158 -346.9691) (xy 326.920501 -347.011407) (xy 326.896984 -347.029532) (xy 326.886411 -347.037998)
			(xy 326.869706 -347.059302) (xy 326.859187 -347.084247) (xy 326.855592 -347.11108) (xy 326.859176 -347.137914)
			(xy 326.869685 -347.162863) (xy 326.886382 -347.184173) (xy 326.896984 -347.1926) (xy 326.920491 -347.21074)
			(xy 326.962153 -347.253043) (xy 326.996758 -347.301289) (xy 327.023471 -347.354313) (xy 327.041648 -347.410835)
			(xy 327.050849 -347.469491) (xy 327.051416 -347.499178) (xy 327.05093 -347.526429) (xy 327.043174 -347.580377)
			(xy 327.027819 -347.632672) (xy 327.005177 -347.682249) (xy 326.975711 -347.728099) (xy 326.94002 -347.76929)
			(xy 326.898829 -347.804981) (xy 326.852979 -347.834447) (xy 326.803402 -347.857089) (xy 326.751107 -347.872444)
			(xy 326.697159 -347.8802) (xy 326.642657 -347.8802) (xy 326.588709 -347.872444) (xy 326.536414 -347.857089)
			(xy 326.486837 -347.834447) (xy 326.440987 -347.804981) (xy 326.399796 -347.76929) (xy 326.364105 -347.728099)
			(xy 326.334639 -347.682249) (xy 326.311997 -347.632672) (xy 326.296642 -347.580377) (xy 326.288886 -347.526429)
			(xy 326.2884 -347.499178) (xy 322.707196 -347.499178) (xy 322.71007 -347.519171) (xy 322.710556 -347.546422)
			(xy 322.710072 -347.5728) (xy 322.702818 -347.625054) (xy 322.688437 -347.675812) (xy 322.667203 -347.724105)
			(xy 322.63952 -347.769015) (xy 322.605918 -347.809684) (xy 322.567034 -347.845339) (xy 322.523611 -347.875299)
			(xy 322.500244 -347.887544) (xy 322.487865 -347.894212) (xy 322.467132 -347.913193) (xy 322.452369 -347.937113)
			(xy 322.444697 -347.964155) (xy 322.4447 -347.992264) (xy 322.452377 -348.019305) (xy 322.467145 -348.043222)
			(xy 322.487881 -348.062199) (xy 322.500244 -348.0689) (xy 322.523634 -348.081106) (xy 322.567057 -348.111075)
			(xy 322.60594 -348.146736) (xy 322.639544 -348.187411) (xy 322.667229 -348.232325) (xy 322.688466 -348.280622)
			(xy 322.702852 -348.331383) (xy 322.710112 -348.383642) (xy 322.710556 -348.410022) (xy 322.71007 -348.437273)
			(xy 322.702314 -348.491221) (xy 322.686959 -348.543516) (xy 322.664317 -348.593093) (xy 322.634851 -348.638943)
			(xy 322.59916 -348.680134) (xy 322.557969 -348.715825) (xy 322.512119 -348.745291) (xy 322.462542 -348.767933)
			(xy 322.410247 -348.783288) (xy 322.356299 -348.791044) (xy 322.301797 -348.791044) (xy 322.247849 -348.783288)
			(xy 322.195554 -348.767933) (xy 322.145977 -348.745291) (xy 322.100127 -348.715825) (xy 322.058936 -348.680134)
			(xy 322.023245 -348.638943) (xy 321.993779 -348.593093) (xy 321.971137 -348.543516) (xy 321.955782 -348.491221)
			(xy 321.948026 -348.437273) (xy 321.94754 -348.410022) (xy 313.883079 -348.410022) (xy 311.397746 -350.895412)
			(xy 336.039206 -350.895412) (xy 336.039731 -350.866495) (xy 336.048458 -350.809324) (xy 336.065715 -350.754126)
			(xy 336.091105 -350.702164) (xy 336.124048 -350.65463) (xy 336.163787 -350.612612) (xy 336.186272 -350.594422)
			(xy 336.198067 -350.584512) (xy 336.215587 -350.559193) (xy 336.224765 -350.529802) (xy 336.224768 -350.499012)
			(xy 336.215593 -350.469621) (xy 336.198077 -350.444299) (xy 336.186272 -350.434402) (xy 336.163784 -350.416217)
			(xy 336.12405 -350.374195) (xy 336.091112 -350.326659) (xy 336.065725 -350.274696) (xy 336.04847 -350.219498)
			(xy 336.039741 -350.162328) (xy 336.039206 -350.133412) (xy 336.039743 -350.1044) (xy 336.048511 -350.047042)
			(xy 336.065861 -349.991673) (xy 336.091395 -349.939569) (xy 336.124522 -349.891931) (xy 336.144108 -349.870522)
			(xy 336.154365 -349.858964) (xy 336.167938 -349.831216) (xy 336.1726 -349.80068) (xy 336.167925 -349.770145)
			(xy 336.154342 -349.742403) (xy 336.144108 -349.730822) (xy 336.124536 -349.709401) (xy 336.091417 -349.661761)
			(xy 336.065886 -349.609659) (xy 336.04853 -349.554295) (xy 336.039748 -349.496942) (xy 336.039206 -349.467932)
			(xy 336.039729 -349.440676) (xy 336.04749 -349.386719) (xy 336.062846 -349.334415) (xy 336.085484 -349.284826)
			(xy 336.114944 -349.23896) (xy 336.150627 -349.19775) (xy 336.191808 -349.162033) (xy 336.214466 -349.146876)
			(xy 336.226362 -349.138554) (xy 336.245364 -349.116627) (xy 336.25742 -349.090236) (xy 336.261553 -349.061517)
			(xy 336.25743 -349.032797) (xy 336.245383 -349.006402) (xy 336.226389 -348.984469) (xy 336.214466 -348.976188)
			(xy 336.19178 -348.961065) (xy 336.150579 -348.925356) (xy 336.11488 -348.884147) (xy 336.085409 -348.838276)
			(xy 336.062767 -348.788677) (xy 336.047415 -348.736361) (xy 336.039664 -348.682393) (xy 336.039206 -348.655132)
			(xy 336.039685 -348.627879) (xy 336.047438 -348.573928) (xy 336.062791 -348.52163) (xy 336.085431 -348.472049)
			(xy 336.114897 -348.426195) (xy 336.150589 -348.385001) (xy 336.19178 -348.349307) (xy 336.237633 -348.319839)
			(xy 336.287213 -348.297197) (xy 336.339511 -348.281842) (xy 336.393461 -348.274086) (xy 336.420714 -348.273624)
			(xy 336.446635 -348.274074) (xy 336.497997 -348.281107) (xy 336.547935 -348.295027) (xy 336.595529 -348.315578)
			(xy 336.639903 -348.342383) (xy 336.680241 -348.374947) (xy 336.698336 -348.393512) (xy 336.707692 -348.402998)
			(xy 336.730329 -348.417038) (xy 336.755831 -348.424737) (xy 336.782456 -348.425569) (xy 336.808389 -348.419477)
			(xy 336.831858 -348.406876) (xy 336.851264 -348.388627) (xy 336.85861 -348.37751) (xy 336.873637 -348.354274)
			(xy 336.909342 -348.312) (xy 336.950778 -348.275326) (xy 336.997075 -348.245019) (xy 337.047264 -348.221716)
			(xy 337.100292 -348.205904) (xy 337.155047 -348.197915) (xy 337.182714 -348.197424) (xy 337.209967 -348.197847)
			(xy 337.263918 -348.205606) (xy 337.316215 -348.220963) (xy 337.365795 -348.243607) (xy 337.411647 -348.273076)
			(xy 337.452839 -348.308771) (xy 337.488532 -348.349964) (xy 337.518 -348.395818) (xy 337.540642 -348.445398)
			(xy 337.555997 -348.497696) (xy 337.563754 -348.551647) (xy 337.563754 -348.606153) (xy 337.560749 -348.627052)
			(xy 337.766138 -348.627052) (xy 337.766138 -348.572548) (xy 337.773894 -348.518599) (xy 337.789248 -348.466303)
			(xy 337.811888 -348.416723) (xy 337.841353 -348.37087) (xy 337.877043 -348.329677) (xy 337.918232 -348.293982)
			(xy 337.964081 -348.264511) (xy 338.013657 -348.241865) (xy 338.065952 -348.226504) (xy 338.1199 -348.218741)
			(xy 338.147152 -348.218252) (xy 338.176069 -348.218785) (xy 338.23324 -348.227508) (xy 338.288439 -348.244762)
			(xy 338.340402 -348.270151) (xy 338.387936 -348.303093) (xy 338.429952 -348.342833) (xy 338.448142 -348.365318)
			(xy 338.458039 -348.377123) (xy 338.483363 -348.394642) (xy 338.512756 -348.403818) (xy 338.543548 -348.403818)
			(xy 338.572941 -348.394642) (xy 338.598265 -348.377123) (xy 338.608162 -348.365318) (xy 338.624915 -348.344535)
			(xy 338.663269 -348.307405) (xy 338.706423 -348.275983) (xy 338.753537 -348.250884) (xy 338.803689 -348.232598)
			(xy 338.8559 -348.221481) (xy 338.909152 -348.217751) (xy 338.962404 -348.221481) (xy 339.014615 -348.232598)
			(xy 339.064767 -348.250884) (xy 339.111881 -348.275983) (xy 339.155035 -348.307405) (xy 339.193389 -348.344535)
			(xy 339.210142 -348.365318) (xy 339.220039 -348.377123) (xy 339.245363 -348.394642) (xy 339.274756 -348.403818)
			(xy 339.305548 -348.403818) (xy 339.334941 -348.394642) (xy 339.360265 -348.377123) (xy 339.370162 -348.365318)
			(xy 339.386915 -348.344535) (xy 339.425269 -348.307405) (xy 339.468423 -348.275983) (xy 339.515537 -348.250884)
			(xy 339.565689 -348.232598) (xy 339.6179 -348.221481) (xy 339.671152 -348.217751) (xy 339.724404 -348.221481)
			(xy 339.776615 -348.232598) (xy 339.826767 -348.250884) (xy 339.873881 -348.275983) (xy 339.917035 -348.307405)
			(xy 339.955389 -348.344535) (xy 339.972142 -348.365318) (xy 339.982039 -348.377123) (xy 340.007363 -348.394642)
			(xy 340.036756 -348.403818) (xy 340.067548 -348.403818) (xy 340.096941 -348.394642) (xy 340.122265 -348.377123)
			(xy 340.132162 -348.365318) (xy 340.150379 -348.342856) (xy 340.192393 -348.303119) (xy 340.239922 -348.270177)
			(xy 340.291878 -348.244785) (xy 340.347072 -348.227524) (xy 340.404237 -348.21879) (xy 340.433152 -348.218252)
			(xy 340.461719 -348.218782) (xy 340.518214 -348.227316) (xy 340.572807 -348.244169) (xy 340.624281 -348.268966)
			(xy 340.671487 -348.301155) (xy 340.713371 -348.340015) (xy 340.731602 -348.362016) (xy 340.741172 -348.373259)
			(xy 340.765411 -348.390096) (xy 340.793451 -348.399307) (xy 340.822953 -348.400124) (xy 340.851459 -348.392478)
			(xy 340.876593 -348.377006) (xy 340.886796 -348.366334) (xy 340.904952 -348.346705) (xy 340.945838 -348.312247)
			(xy 340.991134 -348.283834) (xy 341.039954 -348.262024) (xy 341.09134 -348.247243) (xy 341.144287 -348.239782)
			(xy 341.171022 -348.239334) (xy 341.199937 -348.239896) (xy 341.257107 -348.248614) (xy 341.312306 -348.265862)
			(xy 341.364268 -348.291246) (xy 341.411803 -348.324183) (xy 341.453821 -348.363917) (xy 341.472012 -348.3864)
			(xy 341.481909 -348.398205) (xy 341.507233 -348.415724) (xy 341.536626 -348.4249) (xy 341.567418 -348.4249)
			(xy 341.596811 -348.415724) (xy 341.622135 -348.398205) (xy 341.632032 -348.3864) (xy 341.650205 -348.363901)
			(xy 341.692228 -348.324167) (xy 341.739767 -348.29123) (xy 341.791732 -348.265844) (xy 341.846933 -348.248591)
			(xy 341.904105 -348.239867) (xy 341.933022 -348.239334) (xy 341.960275 -348.239737) (xy 342.014227 -348.247497)
			(xy 342.066524 -348.262856) (xy 342.116104 -348.285501) (xy 342.161957 -348.314971) (xy 342.203149 -348.350666)
			(xy 342.238842 -348.391861) (xy 342.26831 -348.437715) (xy 342.290952 -348.487296) (xy 342.306307 -348.539595)
			(xy 342.314064 -348.593547) (xy 342.314064 -348.648053) (xy 342.306307 -348.702005) (xy 342.290952 -348.754304)
			(xy 342.26831 -348.803885) (xy 342.238842 -348.849739) (xy 342.203149 -348.890934) (xy 342.161957 -348.926629)
			(xy 342.116104 -348.956099) (xy 342.066524 -348.978744) (xy 342.014227 -348.994103) (xy 341.960275 -349.001863)
			(xy 341.933022 -349.00235) (xy 341.904105 -349.001835) (xy 341.846933 -348.993108) (xy 341.791733 -348.975851)
			(xy 341.739771 -348.950458) (xy 341.692237 -348.917513) (xy 341.650221 -348.877771) (xy 341.632032 -348.855284)
			(xy 341.622135 -348.843479) (xy 341.596811 -348.82596) (xy 341.567418 -348.816784) (xy 341.536626 -348.816784)
			(xy 341.507233 -348.82596) (xy 341.481909 -348.843479) (xy 341.472012 -348.855284) (xy 341.45381 -348.877758)
			(xy 341.411793 -348.917495) (xy 341.364261 -348.950435) (xy 341.312301 -348.975826) (xy 341.257106 -348.993084)
			(xy 341.199937 -349.001814) (xy 341.171022 -349.00235) (xy 341.142456 -349.001766) (xy 341.085964 -348.993244)
			(xy 341.031372 -348.976401) (xy 340.979898 -348.951614) (xy 340.932691 -348.919435) (xy 340.890804 -348.880583)
			(xy 340.872572 -348.858586) (xy 340.86303 -348.847318) (xy 340.838783 -348.83048) (xy 340.810736 -348.821272)
			(xy 340.781228 -348.82046) (xy 340.752717 -348.828113) (xy 340.727582 -348.843592) (xy 340.717378 -348.854268)
			(xy 340.699186 -348.873862) (xy 340.658307 -348.908323) (xy 340.613018 -348.93674) (xy 340.564206 -348.958556)
			(xy 340.512826 -348.973344) (xy 340.459885 -348.980815) (xy 340.433152 -348.981268) (xy 340.404236 -348.980725)
			(xy 340.347065 -348.972002) (xy 340.291866 -348.95475) (xy 340.239904 -348.929363) (xy 340.19237 -348.896424)
			(xy 340.150352 -348.856686) (xy 340.132162 -348.834202) (xy 340.122265 -348.822397) (xy 340.096941 -348.804878)
			(xy 340.067548 -348.795702) (xy 340.036756 -348.795702) (xy 340.007363 -348.804878) (xy 339.982039 -348.822397)
			(xy 339.972142 -348.834202) (xy 339.955389 -348.854985) (xy 339.917035 -348.892115) (xy 339.873881 -348.923537)
			(xy 339.826767 -348.948636) (xy 339.776615 -348.966922) (xy 339.724404 -348.978039) (xy 339.671152 -348.981769)
			(xy 339.6179 -348.978039) (xy 339.565689 -348.966922) (xy 339.515537 -348.948636) (xy 339.468423 -348.923537)
			(xy 339.425269 -348.892115) (xy 339.386915 -348.854985) (xy 339.370162 -348.834202) (xy 339.360265 -348.822397)
			(xy 339.334941 -348.804878) (xy 339.305548 -348.795702) (xy 339.274756 -348.795702) (xy 339.245363 -348.804878)
			(xy 339.220039 -348.822397) (xy 339.210142 -348.834202) (xy 339.193389 -348.854985) (xy 339.155035 -348.892115)
			(xy 339.111881 -348.923537) (xy 339.064767 -348.948636) (xy 339.014615 -348.966922) (xy 338.962404 -348.978039)
			(xy 338.909152 -348.981769) (xy 338.8559 -348.978039) (xy 338.803689 -348.966922) (xy 338.753537 -348.948636)
			(xy 338.706423 -348.923537) (xy 338.663269 -348.892115) (xy 338.624915 -348.854985) (xy 338.608162 -348.834202)
			(xy 338.598265 -348.822397) (xy 338.572941 -348.804878) (xy 338.543548 -348.795702) (xy 338.512756 -348.795702)
			(xy 338.483363 -348.804878) (xy 338.458039 -348.822397) (xy 338.448142 -348.834202) (xy 338.429928 -348.856666)
			(xy 338.387913 -348.896402) (xy 338.340383 -348.929343) (xy 338.288426 -348.954735) (xy 338.233233 -348.971996)
			(xy 338.176067 -348.98073) (xy 338.147152 -348.981268) (xy 338.1199 -348.980859) (xy 338.065952 -348.973096)
			(xy 338.013657 -348.957735) (xy 337.964081 -348.935089) (xy 337.918232 -348.905618) (xy 337.877043 -348.869923)
			(xy 337.841353 -348.82873) (xy 337.811888 -348.782877) (xy 337.789248 -348.733297) (xy 337.773894 -348.681001)
			(xy 337.766138 -348.627052) (xy 337.560749 -348.627052) (xy 337.555997 -348.660104) (xy 337.540642 -348.712402)
			(xy 337.518 -348.761982) (xy 337.488532 -348.807836) (xy 337.452839 -348.849029) (xy 337.411647 -348.884724)
			(xy 337.365795 -348.914193) (xy 337.316215 -348.936837) (xy 337.263918 -348.952194) (xy 337.209967 -348.959953)
			(xy 337.182714 -348.96044) (xy 337.156793 -348.960017) (xy 337.10543 -348.952976) (xy 337.055492 -348.939049)
			(xy 337.007899 -348.918493) (xy 336.963525 -348.891684) (xy 336.923187 -348.859117) (xy 336.905092 -348.840552)
			(xy 336.895703 -348.831104) (xy 336.873072 -348.817068) (xy 336.84758 -348.809369) (xy 336.820963 -348.808534)
			(xy 336.795038 -348.814618) (xy 336.771572 -348.827208) (xy 336.752166 -348.845443) (xy 336.744818 -348.856554)
			(xy 336.729487 -348.880269) (xy 336.692936 -348.923312) (xy 336.650442 -348.960499) (xy 336.626962 -348.976188)
			(xy 336.614968 -348.984388) (xy 336.595949 -349.006342) (xy 336.583886 -349.032766) (xy 336.579756 -349.061517)
			(xy 336.583895 -349.090268) (xy 336.595967 -349.116687) (xy 336.614994 -349.138635) (xy 336.626962 -349.146876)
			(xy 336.653745 -349.164882) (xy 336.701371 -349.208427) (xy 336.721704 -349.23349) (xy 336.731601 -349.245295)
			(xy 336.756925 -349.262814) (xy 336.786318 -349.27199) (xy 336.81711 -349.27199) (xy 336.846503 -349.262814)
			(xy 336.871827 -349.245295) (xy 336.881724 -349.23349) (xy 336.899899 -349.210993) (xy 336.941922 -349.171259)
			(xy 336.989461 -349.138322) (xy 337.041425 -349.112936) (xy 337.096625 -349.095683) (xy 337.153797 -349.086957)
			(xy 337.182714 -349.086424) (xy 337.209969 -349.086842) (xy 337.263923 -349.094602) (xy 337.316224 -349.109961)
			(xy 337.365806 -349.132608) (xy 337.411661 -349.16208) (xy 337.452854 -349.197779) (xy 337.488548 -349.238976)
			(xy 337.518015 -349.284834) (xy 337.540655 -349.33442) (xy 337.556008 -349.386722) (xy 337.563761 -349.440677)
			(xy 337.564222 -349.467932) (xy 337.563704 -349.496945) (xy 337.554931 -349.554303) (xy 337.537575 -349.609672)
			(xy 337.512038 -349.661775) (xy 337.478908 -349.709413) (xy 337.45932 -349.730822) (xy 337.449116 -349.742424)
			(xy 337.435534 -349.770156) (xy 337.43086 -349.80068) (xy 337.435521 -349.831205) (xy 337.449093 -349.858943)
			(xy 337.45932 -349.870522) (xy 337.478917 -349.891921) (xy 337.512032 -349.939567) (xy 337.537558 -349.991675)
			(xy 337.554908 -350.047044) (xy 337.563683 -350.1044) (xy 337.564222 -350.133412) (xy 337.563824 -350.15424)
			(xy 337.765644 -350.15424) (xy 337.766188 -350.125228) (xy 337.774952 -350.06787) (xy 337.792301 -350.012501)
			(xy 337.817833 -349.960397) (xy 337.85096 -349.912759) (xy 337.870546 -349.89135) (xy 337.880781 -349.879772)
			(xy 337.894365 -349.852032) (xy 337.899035 -349.8215) (xy 337.894365 -349.790968) (xy 337.880781 -349.763228)
			(xy 337.870546 -349.75165) (xy 337.850977 -349.730227) (xy 337.81786 -349.682586) (xy 337.79233 -349.630485)
			(xy 337.774972 -349.575122) (xy 337.766188 -349.51777) (xy 337.765644 -349.48876) (xy 337.76614 -349.46151)
			(xy 337.773901 -349.407565) (xy 337.789259 -349.355274) (xy 337.811901 -349.305699) (xy 337.841367 -349.259851)
			(xy 337.877057 -349.218663) (xy 337.918245 -349.182972) (xy 337.964092 -349.153505) (xy 338.013666 -349.130862)
			(xy 338.065957 -349.115503) (xy 338.119902 -349.107741) (xy 338.147152 -349.107252) (xy 338.176069 -349.107785)
			(xy 338.23324 -349.116508) (xy 338.288439 -349.133762) (xy 338.340402 -349.159151) (xy 338.387936 -349.192093)
			(xy 338.429952 -349.231833) (xy 338.448142 -349.254318) (xy 338.458039 -349.266123) (xy 338.483363 -349.283642)
			(xy 338.512756 -349.292818) (xy 338.543548 -349.292818) (xy 338.572941 -349.283642) (xy 338.598265 -349.266123)
			(xy 338.608162 -349.254318) (xy 338.624915 -349.233535) (xy 338.663269 -349.196405) (xy 338.706423 -349.164983)
			(xy 338.753537 -349.139884) (xy 338.803689 -349.121598) (xy 338.8559 -349.110481) (xy 338.909152 -349.106751)
			(xy 338.962404 -349.110481) (xy 339.014615 -349.121598) (xy 339.064767 -349.139884) (xy 339.111881 -349.164983)
			(xy 339.155035 -349.196405) (xy 339.193389 -349.233535) (xy 339.210142 -349.254318) (xy 339.220039 -349.266123)
			(xy 339.245363 -349.283642) (xy 339.274756 -349.292818) (xy 339.305548 -349.292818) (xy 339.334941 -349.283642)
			(xy 339.360265 -349.266123) (xy 339.370162 -349.254318) (xy 339.386915 -349.233535) (xy 339.425269 -349.196405)
			(xy 339.468423 -349.164983) (xy 339.515537 -349.139884) (xy 339.565689 -349.121598) (xy 339.6179 -349.110481)
			(xy 339.671152 -349.106751) (xy 339.724404 -349.110481) (xy 339.776615 -349.121598) (xy 339.826767 -349.139884)
			(xy 339.873881 -349.164983) (xy 339.917035 -349.196405) (xy 339.955389 -349.233535) (xy 339.972142 -349.254318)
			(xy 339.982039 -349.266123) (xy 340.007363 -349.283642) (xy 340.036756 -349.292818) (xy 340.067548 -349.292818)
			(xy 340.096941 -349.283642) (xy 340.122265 -349.266123) (xy 340.132162 -349.254318) (xy 340.150379 -349.231856)
			(xy 340.192393 -349.192119) (xy 340.239922 -349.159177) (xy 340.291878 -349.133785) (xy 340.347072 -349.116524)
			(xy 340.404237 -349.10779) (xy 340.433152 -349.107252) (xy 340.461719 -349.107782) (xy 340.518214 -349.116316)
			(xy 340.572807 -349.133169) (xy 340.624281 -349.157966) (xy 340.671487 -349.190155) (xy 340.713371 -349.229015)
			(xy 340.731602 -349.251016) (xy 340.741172 -349.262259) (xy 340.765411 -349.279096) (xy 340.793451 -349.288307)
			(xy 340.822953 -349.289124) (xy 340.851459 -349.281478) (xy 340.876593 -349.266006) (xy 340.886796 -349.255334)
			(xy 340.904952 -349.235705) (xy 340.945838 -349.201247) (xy 340.991134 -349.172834) (xy 341.039954 -349.151024)
			(xy 341.09134 -349.136243) (xy 341.144287 -349.128782) (xy 341.171022 -349.128334) (xy 341.199937 -349.128896)
			(xy 341.257107 -349.137614) (xy 341.312306 -349.154862) (xy 341.364268 -349.180246) (xy 341.411803 -349.213183)
			(xy 341.453821 -349.252917) (xy 341.472012 -349.2754) (xy 341.481909 -349.287205) (xy 341.507233 -349.304724)
			(xy 341.536626 -349.3139) (xy 341.567418 -349.3139) (xy 341.596811 -349.304724) (xy 341.622135 -349.287205)
			(xy 341.632032 -349.2754) (xy 341.650205 -349.252901) (xy 341.692228 -349.213167) (xy 341.739767 -349.18023)
			(xy 341.791732 -349.154844) (xy 341.846933 -349.137591) (xy 341.904105 -349.128867) (xy 341.933022 -349.128334)
			(xy 341.960275 -349.128737) (xy 342.014227 -349.136497) (xy 342.066524 -349.151856) (xy 342.116104 -349.174501)
			(xy 342.161957 -349.203971) (xy 342.203149 -349.239666) (xy 342.238842 -349.280861) (xy 342.26831 -349.326715)
			(xy 342.290952 -349.376296) (xy 342.306307 -349.428595) (xy 342.314064 -349.482547) (xy 342.314064 -349.537053)
			(xy 342.306307 -349.591005) (xy 342.290952 -349.643304) (xy 342.26831 -349.692885) (xy 342.238842 -349.738739)
			(xy 342.203149 -349.779934) (xy 342.161957 -349.815629) (xy 342.116104 -349.845099) (xy 342.066524 -349.867744)
			(xy 342.014227 -349.883103) (xy 341.960275 -349.890863) (xy 341.933022 -349.89135) (xy 341.904105 -349.890835)
			(xy 341.846933 -349.882108) (xy 341.791733 -349.864851) (xy 341.739771 -349.839458) (xy 341.692237 -349.806513)
			(xy 341.650221 -349.766771) (xy 341.632032 -349.744284) (xy 341.622135 -349.732479) (xy 341.596811 -349.71496)
			(xy 341.567418 -349.705784) (xy 341.536626 -349.705784) (xy 341.507233 -349.71496) (xy 341.481909 -349.732479)
			(xy 341.472012 -349.744284) (xy 341.45381 -349.766758) (xy 341.411793 -349.806495) (xy 341.364261 -349.839435)
			(xy 341.312301 -349.864826) (xy 341.257106 -349.882084) (xy 341.199937 -349.890814) (xy 341.171022 -349.89135)
			(xy 341.142456 -349.890766) (xy 341.085964 -349.882244) (xy 341.031372 -349.865401) (xy 340.979898 -349.840614)
			(xy 340.932691 -349.808435) (xy 340.890804 -349.769583) (xy 340.872572 -349.747586) (xy 340.86303 -349.736318)
			(xy 340.838783 -349.71948) (xy 340.810736 -349.710272) (xy 340.781228 -349.70946) (xy 340.752717 -349.717113)
			(xy 340.727582 -349.732592) (xy 340.717378 -349.743268) (xy 340.699186 -349.762862) (xy 340.658307 -349.797323)
			(xy 340.613018 -349.82574) (xy 340.564206 -349.847556) (xy 340.512826 -349.862344) (xy 340.459885 -349.869815)
			(xy 340.433152 -349.870268) (xy 340.404236 -349.869725) (xy 340.347065 -349.861002) (xy 340.291866 -349.84375)
			(xy 340.239904 -349.818363) (xy 340.19237 -349.785424) (xy 340.150352 -349.745686) (xy 340.132162 -349.723202)
			(xy 340.122265 -349.711397) (xy 340.096941 -349.693878) (xy 340.067548 -349.684702) (xy 340.036756 -349.684702)
			(xy 340.007363 -349.693878) (xy 339.982039 -349.711397) (xy 339.972142 -349.723202) (xy 339.955389 -349.743985)
			(xy 339.917035 -349.781115) (xy 339.873881 -349.812537) (xy 339.826767 -349.837636) (xy 339.776615 -349.855922)
			(xy 339.724404 -349.867039) (xy 339.671152 -349.870769) (xy 339.6179 -349.867039) (xy 339.565689 -349.855922)
			(xy 339.515537 -349.837636) (xy 339.468423 -349.812537) (xy 339.425269 -349.781115) (xy 339.386915 -349.743985)
			(xy 339.370162 -349.723202) (xy 339.360265 -349.711397) (xy 339.334941 -349.693878) (xy 339.305548 -349.684702)
			(xy 339.274756 -349.684702) (xy 339.245363 -349.693878) (xy 339.220039 -349.711397) (xy 339.210142 -349.723202)
			(xy 339.193389 -349.743985) (xy 339.155035 -349.781115) (xy 339.111881 -349.812537) (xy 339.064767 -349.837636)
			(xy 339.014615 -349.855922) (xy 338.962404 -349.867039) (xy 338.909152 -349.870769) (xy 338.8559 -349.867039)
			(xy 338.803689 -349.855922) (xy 338.753537 -349.837636) (xy 338.706423 -349.812537) (xy 338.663269 -349.781115)
			(xy 338.624915 -349.743985) (xy 338.608162 -349.723202) (xy 338.598265 -349.711397) (xy 338.572941 -349.693878)
			(xy 338.543548 -349.684702) (xy 338.512756 -349.684702) (xy 338.483363 -349.693878) (xy 338.458039 -349.711397)
			(xy 338.448142 -349.723202) (xy 338.423758 -349.75165) (xy 338.413523 -349.763228) (xy 338.399939 -349.790968)
			(xy 338.395268 -349.8215) (xy 338.399939 -349.852032) (xy 338.413523 -349.879772) (xy 338.423758 -349.89135)
			(xy 338.443327 -349.912773) (xy 338.476444 -349.960414) (xy 338.501975 -350.012515) (xy 338.519332 -350.067878)
			(xy 338.528116 -350.12523) (xy 338.52866 -350.15424) (xy 338.528174 -350.181491) (xy 338.520418 -350.235439)
			(xy 338.505063 -350.287734) (xy 338.482421 -350.337311) (xy 338.452955 -350.383161) (xy 338.417264 -350.424352)
			(xy 338.376073 -350.460043) (xy 338.330223 -350.489509) (xy 338.280646 -350.512151) (xy 338.228351 -350.527506)
			(xy 338.174403 -350.535262) (xy 338.119901 -350.535262) (xy 338.065953 -350.527506) (xy 338.013658 -350.512151)
			(xy 337.964081 -350.489509) (xy 337.918231 -350.460043) (xy 337.87704 -350.424352) (xy 337.841349 -350.383161)
			(xy 337.811883 -350.337311) (xy 337.789241 -350.287734) (xy 337.773886 -350.235439) (xy 337.76613 -350.181491)
			(xy 337.765644 -350.15424) (xy 337.563824 -350.15424) (xy 337.56367 -350.162328) (xy 337.554952 -350.219499)
			(xy 337.537703 -350.274698) (xy 337.512318 -350.326661) (xy 337.479378 -350.374195) (xy 337.43964 -350.416212)
			(xy 337.417156 -350.434402) (xy 337.405335 -350.444284) (xy 337.38781 -350.46961) (xy 337.378631 -350.499008)
			(xy 337.378634 -350.529806) (xy 337.387816 -350.559204) (xy 337.405345 -350.584527) (xy 337.417156 -350.594422)
			(xy 337.439641 -350.612612) (xy 337.479378 -350.65463) (xy 337.512318 -350.702165) (xy 337.537707 -350.754127)
			(xy 337.554962 -350.809325) (xy 337.563689 -350.866496) (xy 337.564222 -350.895412) (xy 337.563848 -350.91624)
			(xy 342.433656 -350.91624) (xy 342.434182 -350.887323) (xy 342.442906 -350.830151) (xy 342.460161 -350.774952)
			(xy 342.485551 -350.722989) (xy 342.518495 -350.675455) (xy 342.558236 -350.633439) (xy 342.580722 -350.61525)
			(xy 342.592484 -350.605307) (xy 342.609996 -350.579994) (xy 342.619172 -350.550614) (xy 342.61918 -350.519835)
			(xy 342.610018 -350.49045) (xy 342.592518 -350.465129) (xy 342.580722 -350.45523) (xy 342.558257 -350.437016)
			(xy 342.51852 -350.395002) (xy 342.485578 -350.347472) (xy 342.460186 -350.295515) (xy 342.442926 -350.240321)
			(xy 342.434193 -350.183155) (xy 342.433656 -350.15424) (xy 342.434224 -350.125229) (xy 342.442986 -350.067874)
			(xy 342.46033 -350.012505) (xy 342.485856 -349.960401) (xy 342.518976 -349.912761) (xy 342.538558 -349.89135)
			(xy 342.548791 -349.879771) (xy 342.562374 -349.852032) (xy 342.567044 -349.8215) (xy 342.562374 -349.790968)
			(xy 342.548791 -349.763229) (xy 342.538558 -349.75165) (xy 342.518991 -349.730225) (xy 342.485874 -349.682585)
			(xy 342.460342 -349.630484) (xy 342.442985 -349.575121) (xy 342.4342 -349.51777) (xy 342.433656 -349.48876)
			(xy 342.43414 -349.461509) (xy 342.441902 -349.407564) (xy 342.45726 -349.355271) (xy 342.479903 -349.305696)
			(xy 342.50937 -349.259848) (xy 342.545062 -349.218659) (xy 342.586251 -349.182968) (xy 342.632099 -349.153501)
			(xy 342.681675 -349.130858) (xy 342.733967 -349.115501) (xy 342.787913 -349.10774) (xy 342.815164 -349.107252)
			(xy 342.844081 -349.107776) (xy 342.901253 -349.116501) (xy 342.956452 -349.133757) (xy 343.008415 -349.159147)
			(xy 343.055948 -349.192091) (xy 343.097965 -349.231832) (xy 343.116154 -349.254318) (xy 343.126051 -349.266123)
			(xy 343.151375 -349.283642) (xy 343.180768 -349.292818) (xy 343.21156 -349.292818) (xy 343.240953 -349.283642)
			(xy 343.266277 -349.266123) (xy 343.276174 -349.254318) (xy 343.294384 -349.231851) (xy 343.336399 -349.192114)
			(xy 343.38393 -349.159172) (xy 343.435888 -349.133781) (xy 343.491082 -349.116521) (xy 343.548249 -349.107789)
			(xy 343.577164 -349.107252) (xy 343.604413 -349.107812) (xy 343.658355 -349.115562) (xy 343.710646 -349.130911)
			(xy 343.760221 -349.153545) (xy 343.806069 -349.183003) (xy 343.847259 -349.218687) (xy 343.882951 -349.25987)
			(xy 343.912419 -349.305713) (xy 343.935063 -349.355282) (xy 343.950422 -349.40757) (xy 343.958183 -349.461512)
			(xy 343.958672 -349.48876) (xy 343.958124 -349.517772) (xy 343.94936 -349.575129) (xy 343.932012 -349.630498)
			(xy 343.906481 -349.682603) (xy 343.873356 -349.730241) (xy 343.85377 -349.75165) (xy 343.843534 -349.763227)
			(xy 343.829948 -349.790967) (xy 343.825277 -349.8215) (xy 343.829948 -349.852033) (xy 343.843534 -349.879773)
			(xy 343.85377 -349.89135) (xy 343.873341 -349.912771) (xy 343.906457 -349.960413) (xy 343.931987 -350.012514)
			(xy 343.949344 -350.067878) (xy 343.958128 -350.12523) (xy 343.958672 -350.15424) (xy 343.958121 -350.183156)
			(xy 343.949401 -350.240326) (xy 343.93215 -350.295525) (xy 343.906764 -350.347487) (xy 343.873826 -350.395021)
			(xy 343.834089 -350.437039) (xy 343.811606 -350.45523) (xy 343.799761 -350.465084) (xy 343.782246 -350.49042)
			(xy 343.773075 -350.519824) (xy 343.773082 -350.550625) (xy 343.782267 -350.580025) (xy 343.799795 -350.605352)
			(xy 343.811606 -350.61525) (xy 343.834067 -350.633468) (xy 343.866564 -350.667828) (xy 354.882702 -350.667828)
			(xy 354.886773 -350.612206) (xy 354.898899 -350.557769) (xy 354.918822 -350.505678) (xy 354.946118 -350.457043)
			(xy 354.980204 -350.4129) (xy 355.020353 -350.374191) (xy 355.065711 -350.34174) (xy 355.115311 -350.316239)
			(xy 355.168095 -350.298232) (xy 355.222938 -350.288102) (xy 355.278672 -350.286065) (xy 355.334109 -350.292165)
			(xy 355.388066 -350.306271) (xy 355.439395 -350.328083) (xy 355.487001 -350.357137) (xy 355.529869 -350.392812)
			(xy 355.536575 -350.400296) (xy 363.397796 -350.400296) (xy 363.397796 -350.3156) (xy 363.405847 -350.231286)
			(xy 363.421876 -350.14812) (xy 363.445737 -350.066853) (xy 363.477216 -349.988223) (xy 363.516027 -349.912942)
			(xy 363.561817 -349.84169) (xy 363.614173 -349.775114) (xy 363.672621 -349.713816) (xy 363.736631 -349.658351)
			(xy 363.805623 -349.609222) (xy 363.878973 -349.566873) (xy 363.956016 -349.531689) (xy 364.036055 -349.503987)
			(xy 364.118364 -349.484019) (xy 364.202199 -349.471966) (xy 364.2868 -349.467936) (xy 364.371401 -349.471966)
			(xy 364.455236 -349.484019) (xy 364.537545 -349.503987) (xy 364.617584 -349.531689) (xy 364.694627 -349.566873)
			(xy 364.767977 -349.609222) (xy 364.836969 -349.658351) (xy 364.900979 -349.713816) (xy 364.959427 -349.775114)
			(xy 365.011783 -349.84169) (xy 365.057573 -349.912942) (xy 365.096384 -349.988223) (xy 365.127863 -350.066853)
			(xy 365.151724 -350.14812) (xy 365.167753 -350.231286) (xy 365.175804 -350.3156) (xy 365.176308 -350.357948)
			(xy 365.922309 -350.357948) (xy 365.926345 -350.274501) (xy 365.938417 -350.191833) (xy 365.95841 -350.110716)
			(xy 365.986139 -350.031907) (xy 366.021345 -349.956142) (xy 366.063699 -349.884129) (xy 366.112805 -349.81654)
			(xy 366.168206 -349.754006) (xy 366.229383 -349.697111) (xy 366.295766 -349.646385) (xy 366.366734 -349.602304)
			(xy 366.441626 -349.565278) (xy 366.519742 -349.535652) (xy 366.600352 -349.513704) (xy 366.682704 -349.499639)
			(xy 366.76603 -349.493587) (xy 366.84955 -349.495606) (xy 366.932486 -349.505676) (xy 367.014062 -349.523704)
			(xy 367.093518 -349.549521) (xy 367.170111 -349.582886) (xy 367.243127 -349.623487) (xy 367.311883 -349.670946)
			(xy 367.375737 -349.724819) (xy 367.434094 -349.784604) (xy 367.486409 -349.849741) (xy 367.532192 -349.919624)
			(xy 367.571017 -349.993599) (xy 367.602522 -350.070976) (xy 367.626411 -350.151033) (xy 367.642462 -350.233021)
			(xy 367.650525 -350.316176) (xy 367.65103 -350.357948) (xy 367.650525 -350.39972) (xy 367.642462 -350.482875)
			(xy 367.626411 -350.564863) (xy 367.602522 -350.64492) (xy 367.571017 -350.722297) (xy 367.532192 -350.796272)
			(xy 367.486409 -350.866155) (xy 367.434094 -350.931292) (xy 367.375737 -350.991077) (xy 367.311883 -351.04495)
			(xy 367.243127 -351.092409) (xy 367.170111 -351.13301) (xy 367.124295 -351.152968) (xy 412.661354 -351.152968)
			(xy 412.661788 -351.125596) (xy 412.669612 -351.071415) (xy 412.685107 -351.018912) (xy 412.707957 -350.969165)
			(xy 412.737689 -350.9232) (xy 412.755334 -350.90227) (xy 412.764599 -350.890965) (xy 412.776768 -350.864398)
			(xy 412.780933 -350.835476) (xy 412.776755 -350.806555) (xy 412.764573 -350.779995) (xy 412.755334 -350.768666)
			(xy 412.737662 -350.747759) (xy 412.707938 -350.701787) (xy 412.685094 -350.652036) (xy 412.6696 -350.59953)
			(xy 412.661774 -350.545348) (xy 412.661777 -350.490604) (xy 412.66961 -350.436423) (xy 412.685111 -350.383918)
			(xy 412.707961 -350.334171) (xy 412.737691 -350.288203) (xy 412.755334 -350.26727) (xy 412.764599 -350.255965)
			(xy 412.776768 -350.229398) (xy 412.780933 -350.200476) (xy 412.776755 -350.171555) (xy 412.764573 -350.144995)
			(xy 412.755334 -350.133666) (xy 412.737662 -350.112759) (xy 412.707938 -350.066787) (xy 412.685094 -350.017036)
			(xy 412.6696 -349.96453) (xy 412.661774 -349.910348) (xy 412.661777 -349.855604) (xy 412.66961 -349.801423)
			(xy 412.685111 -349.748918) (xy 412.707961 -349.699171) (xy 412.737691 -349.653203) (xy 412.755334 -349.63227)
			(xy 412.764599 -349.620965) (xy 412.776768 -349.594398) (xy 412.780933 -349.565476) (xy 412.776755 -349.536555)
			(xy 412.764573 -349.509995) (xy 412.755334 -349.498666) (xy 412.737662 -349.477759) (xy 412.707938 -349.431787)
			(xy 412.685094 -349.382036) (xy 412.6696 -349.32953) (xy 412.661774 -349.275348) (xy 412.661777 -349.220604)
			(xy 412.66961 -349.166423) (xy 412.685111 -349.113918) (xy 412.707961 -349.064171) (xy 412.737691 -349.018203)
			(xy 412.755334 -348.99727) (xy 412.764599 -348.985965) (xy 412.776768 -348.959398) (xy 412.780933 -348.930476)
			(xy 412.776755 -348.901555) (xy 412.764573 -348.874995) (xy 412.755334 -348.863666) (xy 412.737662 -348.842759)
			(xy 412.707938 -348.796787) (xy 412.685094 -348.747036) (xy 412.6696 -348.69453) (xy 412.661774 -348.640348)
			(xy 412.661777 -348.585604) (xy 412.66961 -348.531423) (xy 412.685111 -348.478918) (xy 412.707961 -348.429171)
			(xy 412.737691 -348.383203) (xy 412.755334 -348.36227) (xy 412.764599 -348.350965) (xy 412.776768 -348.324398)
			(xy 412.780933 -348.295476) (xy 412.776755 -348.266555) (xy 412.764573 -348.239995) (xy 412.755334 -348.228666)
			(xy 412.737662 -348.207759) (xy 412.707938 -348.161787) (xy 412.685094 -348.112036) (xy 412.6696 -348.05953)
			(xy 412.661774 -348.005348) (xy 412.661777 -347.950604) (xy 412.66961 -347.896423) (xy 412.685111 -347.843918)
			(xy 412.707961 -347.794171) (xy 412.737691 -347.748203) (xy 412.755334 -347.72727) (xy 412.764599 -347.715965)
			(xy 412.776768 -347.689398) (xy 412.780933 -347.660476) (xy 412.776755 -347.631555) (xy 412.764573 -347.604995)
			(xy 412.755334 -347.593666) (xy 412.737718 -347.572715) (xy 412.708001 -347.526748) (xy 412.68516 -347.477006)
			(xy 412.669664 -347.424509) (xy 412.661831 -347.370336) (xy 412.661354 -347.342968) (xy 412.661848 -347.315718)
			(xy 412.669608 -347.261772) (xy 412.684965 -347.20948) (xy 412.707607 -347.159905) (xy 412.737073 -347.114057)
			(xy 412.772764 -347.072868) (xy 412.813952 -347.037177) (xy 412.8598 -347.00771) (xy 412.909374 -346.985067)
			(xy 412.961666 -346.969709) (xy 413.015612 -346.961948) (xy 413.042862 -346.96146) (xy 413.070232 -346.961934)
			(xy 413.124411 -346.969747) (xy 413.176915 -346.985234) (xy 413.226662 -347.008074) (xy 413.272629 -347.037799)
			(xy 413.29356 -347.05544) (xy 413.304888 -347.064676) (xy 413.331445 -347.076852) (xy 413.360362 -347.081025)
			(xy 413.389279 -347.076852) (xy 413.415836 -347.064676) (xy 413.427164 -347.05544) (xy 413.448104 -347.037811)
			(xy 413.494074 -347.008096) (xy 413.543819 -346.985257) (xy 413.596319 -346.969764) (xy 413.650493 -346.961935)
			(xy 413.677862 -346.96146) (xy 413.705901 -346.96198) (xy 413.761378 -346.970176) (xy 413.815059 -346.986395)
			(xy 413.865792 -347.010291) (xy 413.912485 -347.041349) (xy 413.93364 -347.059758) (xy 413.945082 -347.069403)
			(xy 413.972125 -347.082183) (xy 414.001712 -347.086569) (xy 414.031299 -347.082183) (xy 414.058342 -347.069403)
			(xy 414.069784 -347.059758) (xy 414.090918 -347.041318) (xy 414.1376 -347.010227) (xy 414.188336 -346.986316)
			(xy 414.242028 -346.970101) (xy 414.297518 -346.961931) (xy 414.325562 -346.96146) (xy 414.352812 -346.961991)
			(xy 414.406759 -346.969742) (xy 414.459054 -346.985091) (xy 414.508632 -347.007727) (xy 414.554484 -347.037188)
			(xy 414.595676 -347.072875) (xy 414.63137 -347.11406) (xy 414.66084 -347.159907) (xy 414.683484 -347.20948)
			(xy 414.698844 -347.261772) (xy 414.706604 -347.315718) (xy 414.70707 -347.342968) (xy 414.706592 -347.370338)
			(xy 414.698779 -347.424517) (xy 414.683293 -347.47702) (xy 414.660453 -347.526767) (xy 414.63073 -347.572734)
			(xy 414.61309 -347.593666) (xy 414.603885 -347.605017) (xy 414.591705 -347.631566) (xy 414.587527 -347.660476)
			(xy 414.591691 -347.689387) (xy 414.603858 -347.715943) (xy 414.61309 -347.72727) (xy 414.630699 -347.748228)
			(xy 414.660423 -347.794192) (xy 414.68327 -347.843934) (xy 414.698768 -347.896432) (xy 414.706599 -347.950607)
			(xy 414.706602 -348.005345) (xy 414.698778 -348.059521) (xy 414.683287 -348.11202) (xy 414.660447 -348.161765)
			(xy 414.630728 -348.207733) (xy 414.61309 -348.228666) (xy 414.603885 -348.240017) (xy 414.591705 -348.266566)
			(xy 414.587527 -348.295476) (xy 414.591691 -348.324387) (xy 414.603858 -348.350943) (xy 414.61309 -348.36227)
			(xy 414.630699 -348.383228) (xy 414.660423 -348.429192) (xy 414.68327 -348.478934) (xy 414.698768 -348.531432)
			(xy 414.706599 -348.585607) (xy 414.706602 -348.640345) (xy 414.698778 -348.694521) (xy 414.683287 -348.74702)
			(xy 414.660447 -348.796765) (xy 414.630728 -348.842733) (xy 414.61309 -348.863666) (xy 414.603885 -348.875017)
			(xy 414.591705 -348.901566) (xy 414.587527 -348.930476) (xy 414.591691 -348.959387) (xy 414.603858 -348.985943)
			(xy 414.61309 -348.99727) (xy 414.630699 -349.018228) (xy 414.660423 -349.064192) (xy 414.68327 -349.113934)
			(xy 414.698768 -349.166432) (xy 414.706599 -349.220607) (xy 414.706602 -349.275345) (xy 414.698778 -349.329521)
			(xy 414.683287 -349.38202) (xy 414.660447 -349.431765) (xy 414.630728 -349.477733) (xy 414.61309 -349.498666)
			(xy 414.603885 -349.510017) (xy 414.591705 -349.536566) (xy 414.587527 -349.565476) (xy 414.591691 -349.594387)
			(xy 414.603858 -349.620943) (xy 414.61309 -349.63227) (xy 414.630699 -349.653228) (xy 414.660423 -349.699192)
			(xy 414.68327 -349.748934) (xy 414.698768 -349.801432) (xy 414.706599 -349.855607) (xy 414.706602 -349.910345)
			(xy 414.698778 -349.964521) (xy 414.683287 -350.01702) (xy 414.660447 -350.066765) (xy 414.630728 -350.112733)
			(xy 414.61309 -350.133666) (xy 414.603885 -350.145017) (xy 414.591705 -350.171566) (xy 414.587527 -350.200476)
			(xy 414.591691 -350.229387) (xy 414.603858 -350.255943) (xy 414.61309 -350.26727) (xy 414.630699 -350.288228)
			(xy 414.660423 -350.334192) (xy 414.68327 -350.383934) (xy 414.698768 -350.436432) (xy 414.706599 -350.490607)
			(xy 414.706602 -350.545345) (xy 414.698778 -350.599521) (xy 414.683287 -350.65202) (xy 414.660447 -350.701765)
			(xy 414.630728 -350.747733) (xy 414.61309 -350.768666) (xy 414.603885 -350.780017) (xy 414.591705 -350.806566)
			(xy 414.587527 -350.835476) (xy 414.591691 -350.864387) (xy 414.603858 -350.890943) (xy 414.61309 -350.90227)
			(xy 414.630727 -350.923204) (xy 414.660439 -350.969176) (xy 414.683276 -351.018923) (xy 414.698767 -351.071423)
			(xy 414.706596 -351.125599) (xy 414.70707 -351.152968) (xy 417.631626 -351.152968) (xy 417.632067 -351.125597)
			(xy 417.63989 -351.071416) (xy 417.655384 -351.018913) (xy 417.678232 -350.969166) (xy 417.707962 -350.923201)
			(xy 417.725606 -350.90227) (xy 417.734873 -350.890966) (xy 417.747046 -350.864399) (xy 417.751212 -350.835476)
			(xy 417.747032 -350.806554) (xy 417.734847 -350.779994) (xy 417.725606 -350.768666) (xy 417.707935 -350.747758)
			(xy 417.678213 -350.701786) (xy 417.655371 -350.652035) (xy 417.639878 -350.599529) (xy 417.632053 -350.545348)
			(xy 417.632056 -350.490604) (xy 417.639888 -350.436423) (xy 417.655388 -350.38392) (xy 417.678236 -350.334172)
			(xy 417.707964 -350.288203) (xy 417.725606 -350.26727) (xy 417.734873 -350.255966) (xy 417.747046 -350.229399)
			(xy 417.751212 -350.200476) (xy 417.747032 -350.171554) (xy 417.734847 -350.144994) (xy 417.725606 -350.133666)
			(xy 417.707935 -350.112758) (xy 417.678213 -350.066786) (xy 417.655371 -350.017035) (xy 417.639878 -349.964529)
			(xy 417.632053 -349.910348) (xy 417.632056 -349.855604) (xy 417.639888 -349.801423) (xy 417.655388 -349.74892)
			(xy 417.678236 -349.699172) (xy 417.707964 -349.653203) (xy 417.725606 -349.63227) (xy 417.734873 -349.620966)
			(xy 417.747046 -349.594399) (xy 417.751212 -349.565476) (xy 417.747032 -349.536554) (xy 417.734847 -349.509994)
			(xy 417.725606 -349.498666) (xy 417.707935 -349.477758) (xy 417.678213 -349.431786) (xy 417.655371 -349.382035)
			(xy 417.639878 -349.329529) (xy 417.632053 -349.275348) (xy 417.632056 -349.220604) (xy 417.639888 -349.166423)
			(xy 417.655388 -349.11392) (xy 417.678236 -349.064172) (xy 417.707964 -349.018203) (xy 417.725606 -348.99727)
			(xy 417.734873 -348.985966) (xy 417.747046 -348.959399) (xy 417.751212 -348.930476) (xy 417.747032 -348.901554)
			(xy 417.734847 -348.874994) (xy 417.725606 -348.863666) (xy 417.707935 -348.842758) (xy 417.678213 -348.796786)
			(xy 417.655371 -348.747035) (xy 417.639878 -348.694529) (xy 417.632053 -348.640348) (xy 417.632056 -348.585604)
			(xy 417.639888 -348.531423) (xy 417.655388 -348.47892) (xy 417.678236 -348.429172) (xy 417.707964 -348.383203)
			(xy 417.725606 -348.36227) (xy 417.734873 -348.350966) (xy 417.747046 -348.324399) (xy 417.751212 -348.295476)
			(xy 417.747032 -348.266554) (xy 417.734847 -348.239994) (xy 417.725606 -348.228666) (xy 417.707935 -348.207758)
			(xy 417.678213 -348.161786) (xy 417.655371 -348.112035) (xy 417.639878 -348.059529) (xy 417.632053 -348.005348)
			(xy 417.632056 -347.950604) (xy 417.639888 -347.896423) (xy 417.655388 -347.84392) (xy 417.678236 -347.794172)
			(xy 417.707964 -347.748203) (xy 417.725606 -347.72727) (xy 417.734873 -347.715966) (xy 417.747046 -347.689399)
			(xy 417.751212 -347.660476) (xy 417.747032 -347.631554) (xy 417.734847 -347.604994) (xy 417.725606 -347.593666)
			(xy 417.707985 -347.572719) (xy 417.678271 -347.52675) (xy 417.655431 -347.477007) (xy 417.639936 -347.424509)
			(xy 417.632103 -347.370336) (xy 417.631626 -347.342968) (xy 417.632025 -347.315713) (xy 417.639787 -347.261758)
			(xy 417.655149 -347.209457) (xy 417.677798 -347.159874) (xy 417.707273 -347.114019) (xy 417.742973 -347.072826)
			(xy 417.784172 -347.037133) (xy 417.830032 -347.007666) (xy 417.879619 -346.985026) (xy 417.931922 -346.969673)
			(xy 417.985879 -346.96192) (xy 418.013134 -346.96146) (xy 418.041175 -346.961937) (xy 418.096653 -346.970143)
			(xy 418.150335 -346.986373) (xy 418.201067 -347.010278) (xy 418.247758 -347.041345) (xy 418.268912 -347.059758)
			(xy 418.280354 -347.069403) (xy 418.307397 -347.082183) (xy 418.336984 -347.086569) (xy 418.366571 -347.082183)
			(xy 418.393614 -347.069403) (xy 418.405056 -347.059758) (xy 418.426201 -347.041331) (xy 418.47288 -347.010239)
			(xy 418.523613 -346.986325) (xy 418.577303 -346.970106) (xy 418.63279 -346.961933) (xy 418.660834 -346.96146)
			(xy 418.688206 -346.961892) (xy 418.742387 -346.969715) (xy 418.794891 -346.985212) (xy 418.844637 -347.008062)
			(xy 418.890602 -347.037795) (xy 418.911532 -347.05544) (xy 418.92286 -347.064676) (xy 418.949417 -347.076852)
			(xy 418.978334 -347.081025) (xy 419.007251 -347.076852) (xy 419.033808 -347.064676) (xy 419.045136 -347.05544)
			(xy 419.066087 -347.037824) (xy 419.112054 -347.008107) (xy 419.161796 -346.985266) (xy 419.214293 -346.96977)
			(xy 419.268466 -346.961937) (xy 419.295834 -346.96146) (xy 419.323085 -346.961946) (xy 419.377031 -346.969706)
			(xy 419.429323 -346.985064) (xy 419.478899 -347.007707) (xy 419.524747 -347.037174) (xy 419.565936 -347.072865)
			(xy 419.601627 -347.114054) (xy 419.631094 -347.159903) (xy 419.653736 -347.209478) (xy 419.669094 -347.261771)
			(xy 419.676854 -347.315717) (xy 419.677342 -347.342968) (xy 419.676871 -347.370338) (xy 419.669057 -347.424518)
			(xy 419.65357 -347.477021) (xy 419.630728 -347.526768) (xy 419.601004 -347.572735) (xy 419.583362 -347.593666)
			(xy 419.574159 -347.605018) (xy 419.561982 -347.631567) (xy 419.557806 -347.660476) (xy 419.561969 -347.689386)
			(xy 419.574133 -347.715942) (xy 419.583362 -347.72727) (xy 419.600972 -347.748228) (xy 419.630699 -347.794191)
			(xy 419.653547 -347.843933) (xy 419.669046 -347.896431) (xy 419.676878 -347.950607) (xy 419.676881 -348.005345)
			(xy 419.669056 -348.059521) (xy 419.653564 -348.112022) (xy 419.630722 -348.161767) (xy 419.601001 -348.207734)
			(xy 419.583362 -348.228666) (xy 419.574159 -348.240018) (xy 419.561982 -348.266567) (xy 419.557806 -348.295476)
			(xy 419.561969 -348.324386) (xy 419.574133 -348.350942) (xy 419.583362 -348.36227) (xy 419.600972 -348.383228)
			(xy 419.630699 -348.429191) (xy 419.653547 -348.478933) (xy 419.669046 -348.531431) (xy 419.676878 -348.585607)
			(xy 419.676881 -348.640345) (xy 419.669056 -348.694521) (xy 419.653564 -348.747022) (xy 419.630722 -348.796767)
			(xy 419.601001 -348.842734) (xy 419.583362 -348.863666) (xy 419.574159 -348.875018) (xy 419.561982 -348.901567)
			(xy 419.557806 -348.930476) (xy 419.561969 -348.959386) (xy 419.574133 -348.985942) (xy 419.583362 -348.99727)
			(xy 419.600972 -349.018228) (xy 419.630699 -349.064191) (xy 419.653547 -349.113933) (xy 419.669046 -349.166431)
			(xy 419.676878 -349.220607) (xy 419.676881 -349.275345) (xy 419.669056 -349.329521) (xy 419.653564 -349.382022)
			(xy 419.630722 -349.431767) (xy 419.601001 -349.477734) (xy 419.583362 -349.498666) (xy 419.574159 -349.510018)
			(xy 419.561982 -349.536567) (xy 419.557806 -349.565476) (xy 419.561969 -349.594386) (xy 419.574133 -349.620942)
			(xy 419.583362 -349.63227) (xy 419.600972 -349.653228) (xy 419.630699 -349.699191) (xy 419.653547 -349.748933)
			(xy 419.669046 -349.801431) (xy 419.676878 -349.855607) (xy 419.676881 -349.910345) (xy 419.669056 -349.964521)
			(xy 419.653564 -350.017022) (xy 419.630722 -350.066767) (xy 419.601001 -350.112734) (xy 419.583362 -350.133666)
			(xy 419.574159 -350.145018) (xy 419.561982 -350.171567) (xy 419.557806 -350.200476) (xy 419.561969 -350.229386)
			(xy 419.574133 -350.255942) (xy 419.583362 -350.26727) (xy 419.600972 -350.288228) (xy 419.630699 -350.334191)
			(xy 419.653547 -350.383933) (xy 419.669046 -350.436431) (xy 419.676878 -350.490607) (xy 419.676881 -350.545345)
			(xy 419.669056 -350.599521) (xy 419.653564 -350.652022) (xy 419.630722 -350.701767) (xy 419.601001 -350.747734)
			(xy 419.583362 -350.768666) (xy 419.574159 -350.780018) (xy 419.561982 -350.806567) (xy 419.557806 -350.835476)
			(xy 419.561969 -350.864386) (xy 419.574133 -350.890942) (xy 419.583362 -350.90227) (xy 419.600995 -350.923207)
			(xy 419.630709 -350.969178) (xy 419.653547 -351.018924) (xy 419.669039 -351.071424) (xy 419.676868 -351.125599)
			(xy 419.677342 -351.152968) (xy 422.338754 -351.152968) (xy 422.339188 -351.125596) (xy 422.347012 -351.071415)
			(xy 422.362507 -351.018912) (xy 422.385357 -350.969165) (xy 422.415089 -350.9232) (xy 422.432734 -350.90227)
			(xy 422.441999 -350.890965) (xy 422.454168 -350.864398) (xy 422.458333 -350.835476) (xy 422.454155 -350.806555)
			(xy 422.441973 -350.779995) (xy 422.432734 -350.768666) (xy 422.415062 -350.747759) (xy 422.385338 -350.701787)
			(xy 422.362494 -350.652036) (xy 422.347 -350.59953) (xy 422.339174 -350.545348) (xy 422.339177 -350.490604)
			(xy 422.34701 -350.436423) (xy 422.362511 -350.383918) (xy 422.385361 -350.334171) (xy 422.415091 -350.288203)
			(xy 422.432734 -350.26727) (xy 422.441999 -350.255965) (xy 422.454168 -350.229398) (xy 422.458333 -350.200476)
			(xy 422.454155 -350.171555) (xy 422.441973 -350.144995) (xy 422.432734 -350.133666) (xy 422.415062 -350.112759)
			(xy 422.385338 -350.066787) (xy 422.362494 -350.017036) (xy 422.347 -349.96453) (xy 422.339174 -349.910348)
			(xy 422.339177 -349.855604) (xy 422.34701 -349.801423) (xy 422.362511 -349.748918) (xy 422.385361 -349.699171)
			(xy 422.415091 -349.653203) (xy 422.432734 -349.63227) (xy 422.441999 -349.620965) (xy 422.454168 -349.594398)
			(xy 422.458333 -349.565476) (xy 422.454155 -349.536555) (xy 422.441973 -349.509995) (xy 422.432734 -349.498666)
			(xy 422.415062 -349.477759) (xy 422.385338 -349.431787) (xy 422.362494 -349.382036) (xy 422.347 -349.32953)
			(xy 422.339174 -349.275348) (xy 422.339177 -349.220604) (xy 422.34701 -349.166423) (xy 422.362511 -349.113918)
			(xy 422.385361 -349.064171) (xy 422.415091 -349.018203) (xy 422.432734 -348.99727) (xy 422.441999 -348.985965)
			(xy 422.454168 -348.959398) (xy 422.458333 -348.930476) (xy 422.454155 -348.901555) (xy 422.441973 -348.874995)
			(xy 422.432734 -348.863666) (xy 422.415062 -348.842759) (xy 422.385338 -348.796787) (xy 422.362494 -348.747036)
			(xy 422.347 -348.69453) (xy 422.339174 -348.640348) (xy 422.339177 -348.585604) (xy 422.34701 -348.531423)
			(xy 422.362511 -348.478918) (xy 422.385361 -348.429171) (xy 422.415091 -348.383203) (xy 422.432734 -348.36227)
			(xy 422.441999 -348.350965) (xy 422.454168 -348.324398) (xy 422.458333 -348.295476) (xy 422.454155 -348.266555)
			(xy 422.441973 -348.239995) (xy 422.432734 -348.228666) (xy 422.415062 -348.207759) (xy 422.385338 -348.161787)
			(xy 422.362494 -348.112036) (xy 422.347 -348.05953) (xy 422.339174 -348.005348) (xy 422.339177 -347.950604)
			(xy 422.34701 -347.896423) (xy 422.362511 -347.843918) (xy 422.385361 -347.794171) (xy 422.415091 -347.748203)
			(xy 422.432734 -347.72727) (xy 422.441999 -347.715965) (xy 422.454168 -347.689398) (xy 422.458333 -347.660476)
			(xy 422.454155 -347.631555) (xy 422.441973 -347.604995) (xy 422.432734 -347.593666) (xy 422.415118 -347.572715)
			(xy 422.385401 -347.526748) (xy 422.36256 -347.477006) (xy 422.347064 -347.424509) (xy 422.339231 -347.370336)
			(xy 422.338754 -347.342968) (xy 422.339248 -347.315718) (xy 422.347008 -347.261772) (xy 422.362365 -347.20948)
			(xy 422.385007 -347.159905) (xy 422.414473 -347.114057) (xy 422.450164 -347.072868) (xy 422.491352 -347.037177)
			(xy 422.5372 -347.00771) (xy 422.586774 -346.985067) (xy 422.639066 -346.969709) (xy 422.693012 -346.961948)
			(xy 422.720262 -346.96146) (xy 422.747632 -346.961934) (xy 422.801811 -346.969747) (xy 422.854315 -346.985234)
			(xy 422.904062 -347.008074) (xy 422.950029 -347.037799) (xy 422.97096 -347.05544) (xy 422.982288 -347.064676)
			(xy 423.008845 -347.076852) (xy 423.037762 -347.081025) (xy 423.066679 -347.076852) (xy 423.093236 -347.064676)
			(xy 423.104564 -347.05544) (xy 423.125504 -347.037811) (xy 423.171474 -347.008096) (xy 423.221219 -346.985257)
			(xy 423.273719 -346.969764) (xy 423.327893 -346.961935) (xy 423.355262 -346.96146) (xy 423.383301 -346.96198)
			(xy 423.438778 -346.970176) (xy 423.492459 -346.986395) (xy 423.543192 -347.010291) (xy 423.589885 -347.041349)
			(xy 423.61104 -347.059758) (xy 423.622482 -347.069403) (xy 423.649525 -347.082183) (xy 423.679112 -347.086569)
			(xy 423.708699 -347.082183) (xy 423.735742 -347.069403) (xy 423.747184 -347.059758) (xy 423.768318 -347.041318)
			(xy 423.815 -347.010227) (xy 423.865736 -346.986316) (xy 423.919428 -346.970101) (xy 423.974918 -346.961931)
			(xy 424.002962 -346.96146) (xy 424.030212 -346.961991) (xy 424.084159 -346.969742) (xy 424.136454 -346.985091)
			(xy 424.186032 -347.007727) (xy 424.231884 -347.037188) (xy 424.273076 -347.072875) (xy 424.30877 -347.11406)
			(xy 424.33824 -347.159907) (xy 424.360884 -347.20948) (xy 424.376244 -347.261772) (xy 424.384004 -347.315718)
			(xy 424.38447 -347.342968) (xy 424.383992 -347.370338) (xy 424.376179 -347.424517) (xy 424.360693 -347.47702)
			(xy 424.337853 -347.526767) (xy 424.30813 -347.572734) (xy 424.29049 -347.593666) (xy 424.281285 -347.605017)
			(xy 424.269105 -347.631566) (xy 424.264927 -347.660476) (xy 424.269091 -347.689387) (xy 424.281258 -347.715943)
			(xy 424.29049 -347.72727) (xy 424.308099 -347.748228) (xy 424.337823 -347.794192) (xy 424.36067 -347.843934)
			(xy 424.376168 -347.896432) (xy 424.383999 -347.950607) (xy 424.384002 -348.005345) (xy 424.376178 -348.059521)
			(xy 424.360687 -348.11202) (xy 424.337847 -348.161765) (xy 424.308128 -348.207733) (xy 424.29049 -348.228666)
			(xy 424.281285 -348.240017) (xy 424.269105 -348.266566) (xy 424.264927 -348.295476) (xy 424.269091 -348.324387)
			(xy 424.281258 -348.350943) (xy 424.29049 -348.36227) (xy 424.308099 -348.383228) (xy 424.337823 -348.429192)
			(xy 424.36067 -348.478934) (xy 424.376168 -348.531432) (xy 424.383999 -348.585607) (xy 424.384002 -348.640345)
			(xy 424.376178 -348.694521) (xy 424.360687 -348.74702) (xy 424.337847 -348.796765) (xy 424.308128 -348.842733)
			(xy 424.29049 -348.863666) (xy 424.281285 -348.875017) (xy 424.269105 -348.901566) (xy 424.264927 -348.930476)
			(xy 424.269091 -348.959387) (xy 424.281258 -348.985943) (xy 424.29049 -348.99727) (xy 424.308099 -349.018228)
			(xy 424.337823 -349.064192) (xy 424.36067 -349.113934) (xy 424.376168 -349.166432) (xy 424.383999 -349.220607)
			(xy 424.384002 -349.275345) (xy 424.376178 -349.329521) (xy 424.360687 -349.38202) (xy 424.337847 -349.431765)
			(xy 424.308128 -349.477733) (xy 424.29049 -349.498666) (xy 424.281285 -349.510017) (xy 424.269105 -349.536566)
			(xy 424.264927 -349.565476) (xy 424.269091 -349.594387) (xy 424.281258 -349.620943) (xy 424.29049 -349.63227)
			(xy 424.308099 -349.653228) (xy 424.337823 -349.699192) (xy 424.36067 -349.748934) (xy 424.376168 -349.801432)
			(xy 424.383999 -349.855607) (xy 424.384002 -349.910345) (xy 424.376178 -349.964521) (xy 424.360687 -350.01702)
			(xy 424.337847 -350.066765) (xy 424.308128 -350.112733) (xy 424.29049 -350.133666) (xy 424.281285 -350.145017)
			(xy 424.269105 -350.171566) (xy 424.264927 -350.200476) (xy 424.269091 -350.229387) (xy 424.281258 -350.255943)
			(xy 424.29049 -350.26727) (xy 424.308099 -350.288228) (xy 424.337823 -350.334192) (xy 424.36067 -350.383934)
			(xy 424.376168 -350.436432) (xy 424.383999 -350.490607) (xy 424.384002 -350.545345) (xy 424.376178 -350.599521)
			(xy 424.360687 -350.65202) (xy 424.337847 -350.701765) (xy 424.308128 -350.747733) (xy 424.29049 -350.768666)
			(xy 424.281285 -350.780017) (xy 424.269105 -350.806566) (xy 424.264927 -350.835476) (xy 424.269091 -350.864387)
			(xy 424.281258 -350.890943) (xy 424.29049 -350.90227) (xy 424.308127 -350.923204) (xy 424.337839 -350.969176)
			(xy 424.360676 -351.018923) (xy 424.376167 -351.071423) (xy 424.383996 -351.125599) (xy 424.38447 -351.152968)
			(xy 427.95444 -351.152968) (xy 427.954878 -351.125597) (xy 427.962701 -351.071416) (xy 427.978196 -351.018912)
			(xy 428.001044 -350.969166) (xy 428.030775 -350.9232) (xy 428.04842 -350.90227) (xy 428.057686 -350.890965)
			(xy 428.069857 -350.864399) (xy 428.074023 -350.835476) (xy 428.069843 -350.806555) (xy 428.05766 -350.779994)
			(xy 428.04842 -350.768666) (xy 428.030748 -350.747758) (xy 428.001025 -350.701786) (xy 427.978182 -350.652036)
			(xy 427.962689 -350.59953) (xy 427.954863 -350.545348) (xy 427.954867 -350.490604) (xy 427.962699 -350.436423)
			(xy 427.978199 -350.383919) (xy 428.001049 -350.334172) (xy 428.030777 -350.288203) (xy 428.04842 -350.26727)
			(xy 428.057686 -350.255965) (xy 428.069857 -350.229399) (xy 428.074023 -350.200476) (xy 428.069843 -350.171555)
			(xy 428.05766 -350.144994) (xy 428.04842 -350.133666) (xy 428.030748 -350.112758) (xy 428.001025 -350.066786)
			(xy 427.978182 -350.017036) (xy 427.962689 -349.96453) (xy 427.954863 -349.910348) (xy 427.954867 -349.855604)
			(xy 427.962699 -349.801423) (xy 427.978199 -349.748919) (xy 428.001049 -349.699172) (xy 428.030777 -349.653203)
			(xy 428.04842 -349.63227) (xy 428.057686 -349.620965) (xy 428.069857 -349.594399) (xy 428.074023 -349.565476)
			(xy 428.069843 -349.536555) (xy 428.05766 -349.509994) (xy 428.04842 -349.498666) (xy 428.030748 -349.477758)
			(xy 428.001025 -349.431786) (xy 427.978182 -349.382036) (xy 427.962689 -349.32953) (xy 427.954863 -349.275348)
			(xy 427.954867 -349.220604) (xy 427.962699 -349.166423) (xy 427.978199 -349.113919) (xy 428.001049 -349.064172)
			(xy 428.030777 -349.018203) (xy 428.04842 -348.99727) (xy 428.057686 -348.985965) (xy 428.069857 -348.959399)
			(xy 428.074023 -348.930476) (xy 428.069843 -348.901555) (xy 428.05766 -348.874994) (xy 428.04842 -348.863666)
			(xy 428.030748 -348.842758) (xy 428.001025 -348.796786) (xy 427.978182 -348.747036) (xy 427.962689 -348.69453)
			(xy 427.954863 -348.640348) (xy 427.954867 -348.585604) (xy 427.962699 -348.531423) (xy 427.978199 -348.478919)
			(xy 428.001049 -348.429172) (xy 428.030777 -348.383203) (xy 428.04842 -348.36227) (xy 428.057686 -348.350965)
			(xy 428.069857 -348.324399) (xy 428.074023 -348.295476) (xy 428.069843 -348.266555) (xy 428.05766 -348.239994)
			(xy 428.04842 -348.228666) (xy 428.030748 -348.207758) (xy 428.001025 -348.161786) (xy 427.978182 -348.112036)
			(xy 427.962689 -348.05953) (xy 427.954863 -348.005348) (xy 427.954867 -347.950604) (xy 427.962699 -347.896423)
			(xy 427.978199 -347.843919) (xy 428.001049 -347.794172) (xy 428.030777 -347.748203) (xy 428.04842 -347.72727)
			(xy 428.057686 -347.715965) (xy 428.069857 -347.689399) (xy 428.074023 -347.660476) (xy 428.069843 -347.631555)
			(xy 428.05766 -347.604994) (xy 428.04842 -347.593666) (xy 428.030801 -347.572717) (xy 428.001086 -347.526749)
			(xy 427.978246 -347.477006) (xy 427.96275 -347.424509) (xy 427.954917 -347.370336) (xy 427.95444 -347.342968)
			(xy 427.954825 -347.315712) (xy 427.962588 -347.261756) (xy 427.97795 -347.209454) (xy 428.0006 -347.15987)
			(xy 428.030076 -347.114015) (xy 428.065778 -347.072821) (xy 428.106979 -347.037128) (xy 428.15284 -347.007662)
			(xy 428.202429 -346.985022) (xy 428.254734 -346.969671) (xy 428.308692 -346.96192) (xy 428.335948 -346.96146)
			(xy 428.363987 -346.961989) (xy 428.419463 -346.970182) (xy 428.473145 -346.9864) (xy 428.523877 -347.010293)
			(xy 428.570571 -347.041349) (xy 428.591726 -347.059758) (xy 428.603168 -347.069403) (xy 428.630211 -347.082183)
			(xy 428.659798 -347.086569) (xy 428.689385 -347.082183) (xy 428.716428 -347.069403) (xy 428.72787 -347.059758)
			(xy 428.74901 -347.041324) (xy 428.79569 -347.010233) (xy 428.846424 -346.98632) (xy 428.900115 -346.970103)
			(xy 428.955604 -346.961932) (xy 428.983648 -346.96146) (xy 429.011018 -346.961942) (xy 429.065197 -346.969754)
			(xy 429.1177 -346.985238) (xy 429.167448 -347.008077) (xy 429.213414 -347.037799) (xy 429.234346 -347.05544)
			(xy 429.245674 -347.064676) (xy 429.272231 -347.076852) (xy 429.301148 -347.081025) (xy 429.330065 -347.076852)
			(xy 429.356622 -347.064676) (xy 429.36795 -347.05544) (xy 429.388895 -347.037817) (xy 429.434864 -347.008101)
			(xy 429.484608 -346.985262) (xy 429.537106 -346.969767) (xy 429.59128 -346.961936) (xy 429.618648 -346.96146)
			(xy 429.645899 -346.961933) (xy 429.699845 -346.969695) (xy 429.752138 -346.985055) (xy 429.801714 -347.007699)
			(xy 429.847562 -347.037168) (xy 429.888751 -347.07286) (xy 429.924442 -347.11405) (xy 429.953908 -347.1599)
			(xy 429.976551 -347.209477) (xy 429.991908 -347.26177) (xy 429.999668 -347.315717) (xy 430.000156 -347.342968)
			(xy 429.999682 -347.370338) (xy 429.991868 -347.424517) (xy 429.976381 -347.477021) (xy 429.953541 -347.526768)
			(xy 429.923817 -347.572734) (xy 429.906176 -347.593666) (xy 429.896972 -347.605017) (xy 429.884794 -347.631567)
			(xy 429.880616 -347.660476) (xy 429.88478 -347.689387) (xy 429.896946 -347.715942) (xy 429.906176 -347.72727)
			(xy 429.923785 -347.748228) (xy 429.953511 -347.794192) (xy 429.976358 -347.843934) (xy 429.991857 -347.896432)
			(xy 429.999688 -347.950607) (xy 429.999692 -348.005345) (xy 429.991867 -348.059521) (xy 429.976375 -348.112021)
			(xy 429.953534 -348.161766) (xy 429.923814 -348.207733) (xy 429.906176 -348.228666) (xy 429.896972 -348.240017)
			(xy 429.884794 -348.266567) (xy 429.880616 -348.295476) (xy 429.88478 -348.324387) (xy 429.896946 -348.350942)
			(xy 429.906176 -348.36227) (xy 429.923785 -348.383228) (xy 429.953511 -348.429192) (xy 429.976358 -348.478934)
			(xy 429.991857 -348.531432) (xy 429.999688 -348.585607) (xy 429.999692 -348.640345) (xy 429.991867 -348.694521)
			(xy 429.976375 -348.747021) (xy 429.953534 -348.796766) (xy 429.923814 -348.842733) (xy 429.906176 -348.863666)
			(xy 429.896972 -348.875017) (xy 429.884794 -348.901567) (xy 429.880616 -348.930476) (xy 429.88478 -348.959387)
			(xy 429.896946 -348.985942) (xy 429.906176 -348.99727) (xy 429.923785 -349.018228) (xy 429.953511 -349.064192)
			(xy 429.976358 -349.113934) (xy 429.991857 -349.166432) (xy 429.999688 -349.220607) (xy 429.999692 -349.275345)
			(xy 429.991867 -349.329521) (xy 429.976375 -349.382021) (xy 429.953534 -349.431766) (xy 429.923814 -349.477733)
			(xy 429.906176 -349.498666) (xy 429.896972 -349.510017) (xy 429.884794 -349.536567) (xy 429.880616 -349.565476)
			(xy 429.88478 -349.594387) (xy 429.896946 -349.620942) (xy 429.906176 -349.63227) (xy 429.923785 -349.653228)
			(xy 429.953511 -349.699192) (xy 429.976358 -349.748934) (xy 429.991857 -349.801432) (xy 429.999688 -349.855607)
			(xy 429.999692 -349.910345) (xy 429.991867 -349.964521) (xy 429.976375 -350.017021) (xy 429.953534 -350.066766)
			(xy 429.923814 -350.112733) (xy 429.906176 -350.133666) (xy 429.896972 -350.145017) (xy 429.884794 -350.171567)
			(xy 429.880616 -350.200476) (xy 429.88478 -350.229387) (xy 429.896946 -350.255942) (xy 429.906176 -350.26727)
			(xy 429.923785 -350.288228) (xy 429.953511 -350.334192) (xy 429.976358 -350.383934) (xy 429.991857 -350.436432)
			(xy 429.999688 -350.490607) (xy 429.999692 -350.545345) (xy 429.991867 -350.599521) (xy 429.976375 -350.652021)
			(xy 429.953534 -350.701766) (xy 429.923814 -350.747733) (xy 429.906176 -350.768666) (xy 429.896972 -350.780017)
			(xy 429.884794 -350.806567) (xy 429.880616 -350.835476) (xy 429.88478 -350.864387) (xy 429.896946 -350.890942)
			(xy 429.906176 -350.90227) (xy 429.923811 -350.923206) (xy 429.953524 -350.969177) (xy 429.976361 -351.018924)
			(xy 429.991853 -351.071424) (xy 429.999682 -351.125599) (xy 430.000156 -351.152968) (xy 429.999592 -351.180216)
			(xy 429.991841 -351.234159) (xy 429.976493 -351.286449) (xy 429.953859 -351.336023) (xy 429.9244 -351.381871)
			(xy 429.888717 -351.42306) (xy 429.847535 -351.458752) (xy 429.801693 -351.48822) (xy 429.752124 -351.510865)
			(xy 429.699837 -351.526224) (xy 429.645896 -351.533986) (xy 429.618648 -351.534476) (xy 429.591279 -351.533988)
			(xy 429.5371 -351.526176) (xy 429.484597 -351.510693) (xy 429.43485 -351.487856) (xy 429.388882 -351.458135)
			(xy 429.36795 -351.440496) (xy 429.356622 -351.43126) (xy 429.330065 -351.419084) (xy 429.301148 -351.414911)
			(xy 429.272231 -351.419084) (xy 429.245674 -351.43126) (xy 429.234346 -351.440496) (xy 429.213407 -351.458126)
			(xy 429.167436 -351.48784) (xy 429.11769 -351.510677) (xy 429.065191 -351.52617) (xy 429.011017 -351.534001)
			(xy 428.983648 -351.534476) (xy 428.955608 -351.533966) (xy 428.900131 -351.525771) (xy 428.846448 -351.509549)
			(xy 428.795716 -351.485651) (xy 428.749024 -351.45459) (xy 428.72787 -351.436178) (xy 428.716428 -351.426533)
			(xy 428.689385 -351.413753) (xy 428.659798 -351.409367) (xy 428.630211 -351.413753) (xy 428.603168 -351.426533)
			(xy 428.591726 -351.436178) (xy 428.570593 -351.45462) (xy 428.52391 -351.485709) (xy 428.473174 -351.509619)
			(xy 428.419482 -351.525835) (xy 428.363992 -351.534005) (xy 428.335948 -351.534476) (xy 428.308695 -351.534)
			(xy 428.254743 -351.526249) (xy 428.202443 -351.510897) (xy 428.152861 -351.488258) (xy 428.107006 -351.458792)
			(xy 428.065812 -351.423099) (xy 428.030118 -351.381907) (xy 428.00065 -351.336053) (xy 427.978008 -351.286472)
			(xy 427.962655 -351.234173) (xy 427.954901 -351.180221) (xy 427.95444 -351.152968) (xy 424.38447 -351.152968)
			(xy 424.384015 -351.180222) (xy 424.376261 -351.234175) (xy 424.360907 -351.286475) (xy 424.338266 -351.336058)
			(xy 424.308798 -351.381913) (xy 424.273103 -351.423107) (xy 424.231908 -351.458801) (xy 424.186053 -351.488269)
			(xy 424.13647 -351.510909) (xy 424.084169 -351.526262) (xy 424.030216 -351.534015) (xy 424.002962 -351.534476)
			(xy 423.97492 -351.534017) (xy 423.91944 -351.52581) (xy 423.865757 -351.509576) (xy 423.815026 -351.485667)
			(xy 423.768336 -351.454594) (xy 423.747184 -351.436178) (xy 423.735742 -351.426533) (xy 423.708699 -351.413753)
			(xy 423.679112 -351.409367) (xy 423.649525 -351.413753) (xy 423.622482 -351.426533) (xy 423.61104 -351.436178)
			(xy 423.589902 -351.454613) (xy 423.54322 -351.485703) (xy 423.492486 -351.509615) (xy 423.438794 -351.525832)
			(xy 423.383306 -351.534004) (xy 423.355262 -351.534476) (xy 423.327893 -351.533979) (xy 423.273715 -351.52617)
			(xy 423.221212 -351.510688) (xy 423.171464 -351.487853) (xy 423.125496 -351.458135) (xy 423.104564 -351.440496)
			(xy 423.093236 -351.43126) (xy 423.066679 -351.419084) (xy 423.037762 -351.414911) (xy 423.008845 -351.419084)
			(xy 422.982288 -351.43126) (xy 422.97096 -351.440496) (xy 422.950016 -351.45812) (xy 422.904046 -351.487834)
			(xy 422.854302 -351.510673) (xy 422.801804 -351.526168) (xy 422.74763 -351.534) (xy 422.720262 -351.534476)
			(xy 422.693008 -351.534057) (xy 422.639057 -351.526295) (xy 422.586759 -351.510933) (xy 422.537179 -351.488285)
			(xy 422.491327 -351.458812) (xy 422.450137 -351.423114) (xy 422.414446 -351.381917) (xy 422.384981 -351.336059)
			(xy 422.362342 -351.286476) (xy 422.34699 -351.234175) (xy 422.339238 -351.180222) (xy 422.338754 -351.152968)
			(xy 419.677342 -351.152968) (xy 419.676792 -351.180217) (xy 419.669041 -351.234161) (xy 419.653691 -351.286452)
			(xy 419.631057 -351.336027) (xy 419.601597 -351.381876) (xy 419.565912 -351.423065) (xy 419.524728 -351.458757)
			(xy 419.478885 -351.488225) (xy 419.429314 -351.510868) (xy 419.377025 -351.526227) (xy 419.323083 -351.533987)
			(xy 419.295834 -351.534476) (xy 419.268464 -351.533996) (xy 419.214285 -351.526182) (xy 419.161782 -351.510697)
			(xy 419.112035 -351.487858) (xy 419.066068 -351.458136) (xy 419.045136 -351.440496) (xy 419.033808 -351.43126)
			(xy 419.007251 -351.419084) (xy 418.978334 -351.414911) (xy 418.949417 -351.419084) (xy 418.92286 -351.43126)
			(xy 418.911532 -351.440496) (xy 418.890598 -351.458133) (xy 418.844626 -351.487845) (xy 418.794879 -351.510682)
			(xy 418.742379 -351.526173) (xy 418.688203 -351.534002) (xy 418.660834 -351.534476) (xy 418.632794 -351.533974)
			(xy 418.577316 -351.525777) (xy 418.523633 -351.509554) (xy 418.472901 -351.485654) (xy 418.42621 -351.45459)
			(xy 418.405056 -351.436178) (xy 418.393614 -351.426533) (xy 418.366571 -351.413753) (xy 418.336984 -351.409367)
			(xy 418.307397 -351.413753) (xy 418.280354 -351.426533) (xy 418.268912 -351.436178) (xy 418.247785 -351.454626)
			(xy 418.2011 -351.485714) (xy 418.150363 -351.509624) (xy 418.096669 -351.525837) (xy 418.041179 -351.534006)
			(xy 418.013134 -351.534476) (xy 417.985881 -351.534013) (xy 417.931928 -351.52626) (xy 417.879628 -351.510906)
			(xy 417.830046 -351.488266) (xy 417.784191 -351.458798) (xy 417.742997 -351.423104) (xy 417.707303 -351.38191)
			(xy 417.677835 -351.336056) (xy 417.655194 -351.286474) (xy 417.639841 -351.234174) (xy 417.632087 -351.180221)
			(xy 417.631626 -351.152968) (xy 414.70707 -351.152968) (xy 414.706615 -351.180222) (xy 414.698861 -351.234175)
			(xy 414.683507 -351.286475) (xy 414.660866 -351.336058) (xy 414.631398 -351.381913) (xy 414.595703 -351.423107)
			(xy 414.554508 -351.458801) (xy 414.508653 -351.488269) (xy 414.45907 -351.510909) (xy 414.406769 -351.526262)
			(xy 414.352816 -351.534015) (xy 414.325562 -351.534476) (xy 414.29752 -351.534017) (xy 414.24204 -351.52581)
			(xy 414.188357 -351.509576) (xy 414.137626 -351.485667) (xy 414.090936 -351.454594) (xy 414.069784 -351.436178)
			(xy 414.058342 -351.426533) (xy 414.031299 -351.413753) (xy 414.001712 -351.409367) (xy 413.972125 -351.413753)
			(xy 413.945082 -351.426533) (xy 413.93364 -351.436178) (xy 413.912502 -351.454613) (xy 413.86582 -351.485703)
			(xy 413.815086 -351.509615) (xy 413.761394 -351.525832) (xy 413.705906 -351.534004) (xy 413.677862 -351.534476)
			(xy 413.650493 -351.533979) (xy 413.596315 -351.52617) (xy 413.543812 -351.510688) (xy 413.494064 -351.487853)
			(xy 413.448096 -351.458135) (xy 413.427164 -351.440496) (xy 413.415836 -351.43126) (xy 413.389279 -351.419084)
			(xy 413.360362 -351.414911) (xy 413.331445 -351.419084) (xy 413.304888 -351.43126) (xy 413.29356 -351.440496)
			(xy 413.272616 -351.45812) (xy 413.226646 -351.487834) (xy 413.176902 -351.510673) (xy 413.124404 -351.526168)
			(xy 413.07023 -351.534) (xy 413.042862 -351.534476) (xy 413.015608 -351.534057) (xy 412.961657 -351.526295)
			(xy 412.909359 -351.510933) (xy 412.859779 -351.488285) (xy 412.813927 -351.458812) (xy 412.772737 -351.423114)
			(xy 412.737046 -351.381917) (xy 412.707581 -351.336059) (xy 412.684942 -351.286476) (xy 412.66959 -351.234175)
			(xy 412.661838 -351.180222) (xy 412.661354 -351.152968) (xy 367.124295 -351.152968) (xy 367.093518 -351.166375)
			(xy 367.014062 -351.192192) (xy 366.932486 -351.21022) (xy 366.84955 -351.22029) (xy 366.76603 -351.222309)
			(xy 366.682704 -351.216257) (xy 366.600352 -351.202192) (xy 366.519742 -351.180244) (xy 366.441626 -351.150618)
			(xy 366.366734 -351.113592) (xy 366.295766 -351.069511) (xy 366.229383 -351.018785) (xy 366.168206 -350.96189)
			(xy 366.112805 -350.899356) (xy 366.063699 -350.831767) (xy 366.021345 -350.759754) (xy 365.986139 -350.683989)
			(xy 365.95841 -350.60518) (xy 365.938417 -350.524063) (xy 365.926345 -350.441395) (xy 365.922309 -350.357948)
			(xy 365.176308 -350.357948) (xy 365.175804 -350.400296) (xy 365.167753 -350.48461) (xy 365.151724 -350.567776)
			(xy 365.127863 -350.649043) (xy 365.096384 -350.727673) (xy 365.057573 -350.802954) (xy 365.011783 -350.874206)
			(xy 364.959427 -350.940782) (xy 364.900979 -351.00208) (xy 364.836969 -351.057545) (xy 364.767977 -351.106674)
			(xy 364.694627 -351.149023) (xy 364.617584 -351.184207) (xy 364.537545 -351.211909) (xy 364.455236 -351.231877)
			(xy 364.371401 -351.24393) (xy 364.2868 -351.247961) (xy 364.202199 -351.24393) (xy 364.118364 -351.231877)
			(xy 364.036055 -351.211909) (xy 363.956016 -351.184207) (xy 363.878973 -351.149023) (xy 363.805623 -351.106674)
			(xy 363.736631 -351.057545) (xy 363.672621 -351.00208) (xy 363.614173 -350.940782) (xy 363.561817 -350.874206)
			(xy 363.516027 -350.802954) (xy 363.477216 -350.727673) (xy 363.445737 -350.649043) (xy 363.421876 -350.567776)
			(xy 363.405847 -350.48461) (xy 363.397796 -350.400296) (xy 355.536575 -350.400296) (xy 355.567086 -350.434349)
			(xy 355.597859 -350.480862) (xy 355.621531 -350.531359) (xy 355.637599 -350.584766) (xy 355.645719 -350.639942)
			(xy 355.646228 -350.667828) (xy 355.645719 -350.695714) (xy 355.637599 -350.75089) (xy 355.621531 -350.804297)
			(xy 355.597859 -350.854794) (xy 355.567086 -350.901307) (xy 355.529869 -350.942844) (xy 355.487001 -350.978519)
			(xy 355.439395 -351.007573) (xy 355.388066 -351.029385) (xy 355.334109 -351.043491) (xy 355.278672 -351.049591)
			(xy 355.222938 -351.047554) (xy 355.168095 -351.037424) (xy 355.115311 -351.019417) (xy 355.065711 -350.993916)
			(xy 355.020353 -350.961465) (xy 354.980204 -350.922756) (xy 354.946118 -350.878613) (xy 354.918822 -350.829978)
			(xy 354.898899 -350.777887) (xy 354.886773 -350.72345) (xy 354.882702 -350.667828) (xy 343.866564 -350.667828)
			(xy 343.873803 -350.675482) (xy 343.906745 -350.723012) (xy 343.932137 -350.774968) (xy 343.949398 -350.83016)
			(xy 343.958133 -350.887326) (xy 343.958672 -350.91624) (xy 343.958259 -350.943494) (xy 343.950496 -350.997446)
			(xy 343.935134 -351.049744) (xy 343.912486 -351.099324) (xy 343.883012 -351.145176) (xy 343.847313 -351.186367)
			(xy 343.806115 -351.222058) (xy 343.760257 -351.251522) (xy 343.710673 -351.274161) (xy 343.658372 -351.289513)
			(xy 343.604418 -351.297265) (xy 343.577164 -351.297748) (xy 343.548248 -351.297203) (xy 343.491077 -351.288482)
			(xy 343.435878 -351.271231) (xy 343.383916 -351.245844) (xy 343.336381 -351.212904) (xy 343.294364 -351.173166)
			(xy 343.276174 -351.150682) (xy 343.266277 -351.138877) (xy 343.240953 -351.121358) (xy 343.21156 -351.112182)
			(xy 343.180768 -351.112182) (xy 343.151375 -351.121358) (xy 343.126051 -351.138877) (xy 343.116154 -351.150682)
			(xy 343.097928 -351.173136) (xy 343.055916 -351.212874) (xy 343.008389 -351.245817) (xy 342.956434 -351.27121)
			(xy 342.901243 -351.288473) (xy 342.844078 -351.297209) (xy 342.815164 -351.297748) (xy 342.787914 -351.297256)
			(xy 342.733968 -351.289495) (xy 342.681676 -351.274138) (xy 342.632101 -351.251495) (xy 342.586253 -351.222029)
			(xy 342.545064 -351.186338) (xy 342.509373 -351.14515) (xy 342.479907 -351.099302) (xy 342.457264 -351.049728)
			(xy 342.441905 -350.997436) (xy 342.434144 -350.94349) (xy 342.433656 -350.91624) (xy 337.563848 -350.91624)
			(xy 337.563733 -350.922663) (xy 337.555976 -350.97661) (xy 337.54062 -351.028904) (xy 337.517978 -351.07848)
			(xy 337.488512 -351.12433) (xy 337.452821 -351.165519) (xy 337.411631 -351.201211) (xy 337.365782 -351.230677)
			(xy 337.316206 -351.253319) (xy 337.263912 -351.268675) (xy 337.209965 -351.276433) (xy 337.182714 -351.27692)
			(xy 337.153796 -351.276422) (xy 337.096622 -351.267693) (xy 337.041422 -351.250433) (xy 336.98946 -351.225038)
			(xy 336.941926 -351.192089) (xy 336.899912 -351.152342) (xy 336.881724 -351.129854) (xy 336.871827 -351.118049)
			(xy 336.846503 -351.10053) (xy 336.81711 -351.091354) (xy 336.786318 -351.091354) (xy 336.756925 -351.10053)
			(xy 336.731601 -351.118049) (xy 336.721704 -351.129854) (xy 336.703524 -351.152347) (xy 336.661501 -351.192079)
			(xy 336.613963 -351.225015) (xy 336.562 -351.250402) (xy 336.506801 -351.267656) (xy 336.44963 -351.276385)
			(xy 336.420714 -351.27692) (xy 336.393462 -351.276432) (xy 336.339513 -351.268677) (xy 336.287216 -351.253323)
			(xy 336.237637 -351.230683) (xy 336.191784 -351.201218) (xy 336.150592 -351.165527) (xy 336.114898 -351.124337)
			(xy 336.085429 -351.078486) (xy 336.062786 -351.028908) (xy 336.047429 -350.976613) (xy 336.03967 -350.922664)
			(xy 336.039206 -350.895412) (xy 311.397746 -350.895412) (xy 310.688086 -351.605088) (xy 351.934778 -351.605088)
			(xy 351.938849 -351.549466) (xy 351.950975 -351.495029) (xy 351.970898 -351.442938) (xy 351.998194 -351.394303)
			(xy 352.03228 -351.35016) (xy 352.072429 -351.311451) (xy 352.117787 -351.279) (xy 352.167387 -351.253499)
			(xy 352.220171 -351.235492) (xy 352.275014 -351.225362) (xy 352.330748 -351.223325) (xy 352.386185 -351.229425)
			(xy 352.440142 -351.243531) (xy 352.491471 -351.265343) (xy 352.539077 -351.294397) (xy 352.581945 -351.330072)
			(xy 352.619162 -351.371609) (xy 352.649935 -351.418122) (xy 352.673607 -351.468619) (xy 352.689675 -351.522026)
			(xy 352.697795 -351.577202) (xy 352.698304 -351.605088) (xy 352.697795 -351.632974) (xy 352.689675 -351.68815)
			(xy 352.673607 -351.741557) (xy 352.649935 -351.792054) (xy 352.627431 -351.826068) (xy 352.798378 -351.826068)
			(xy 352.802449 -351.770446) (xy 352.814575 -351.716009) (xy 352.834498 -351.663918) (xy 352.861794 -351.615283)
			(xy 352.89588 -351.57114) (xy 352.936029 -351.532431) (xy 352.981387 -351.49998) (xy 353.030987 -351.474479)
			(xy 353.083771 -351.456472) (xy 353.138614 -351.446342) (xy 353.194348 -351.444305) (xy 353.249785 -351.450405)
			(xy 353.303742 -351.464511) (xy 353.355071 -351.486323) (xy 353.402677 -351.515377) (xy 353.445545 -351.551052)
			(xy 353.482762 -351.592589) (xy 353.513535 -351.639102) (xy 353.537207 -351.689599) (xy 353.553275 -351.743006)
			(xy 353.561395 -351.798182) (xy 353.561904 -351.826068) (xy 353.561395 -351.853954) (xy 353.553275 -351.90913)
			(xy 353.537207 -351.962537) (xy 353.533311 -351.970848) (xy 354.280976 -351.970848) (xy 354.285047 -351.915226)
			(xy 354.297173 -351.860789) (xy 354.317096 -351.808698) (xy 354.344392 -351.760063) (xy 354.378478 -351.71592)
			(xy 354.418627 -351.677211) (xy 354.463985 -351.64476) (xy 354.513585 -351.619259) (xy 354.566369 -351.601252)
			(xy 354.621212 -351.591122) (xy 354.676946 -351.589085) (xy 354.732383 -351.595185) (xy 354.78634 -351.609291)
			(xy 354.837669 -351.631103) (xy 354.885275 -351.660157) (xy 354.928143 -351.695832) (xy 354.93878 -351.707704)
			(xy 355.638352 -351.707704) (xy 355.642423 -351.652082) (xy 355.654549 -351.597645) (xy 355.674472 -351.545554)
			(xy 355.701768 -351.496919) (xy 355.735854 -351.452776) (xy 355.776003 -351.414067) (xy 355.821361 -351.381616)
			(xy 355.870961 -351.356115) (xy 355.923745 -351.338108) (xy 355.978588 -351.327978) (xy 356.034322 -351.325941)
			(xy 356.089759 -351.332041) (xy 356.143716 -351.346147) (xy 356.195045 -351.367959) (xy 356.242651 -351.397013)
			(xy 356.285519 -351.432688) (xy 356.322736 -351.474225) (xy 356.340416 -351.500948) (xy 356.859076 -351.500948)
			(xy 356.863147 -351.445326) (xy 356.875273 -351.390889) (xy 356.895196 -351.338798) (xy 356.922492 -351.290163)
			(xy 356.956578 -351.24602) (xy 356.996727 -351.207311) (xy 357.042085 -351.17486) (xy 357.091685 -351.149359)
			(xy 357.144469 -351.131352) (xy 357.199312 -351.121222) (xy 357.255046 -351.119185) (xy 357.310483 -351.125285)
			(xy 357.36444 -351.139391) (xy 357.415769 -351.161203) (xy 357.463375 -351.190257) (xy 357.506243 -351.225932)
			(xy 357.54346 -351.267469) (xy 357.574233 -351.313982) (xy 357.597905 -351.364479) (xy 357.613973 -351.417886)
			(xy 357.619842 -351.457768) (xy 359.071416 -351.457768) (xy 359.075487 -351.402146) (xy 359.087613 -351.347709)
			(xy 359.107536 -351.295618) (xy 359.134832 -351.246983) (xy 359.168918 -351.20284) (xy 359.209067 -351.164131)
			(xy 359.254425 -351.13168) (xy 359.304025 -351.106179) (xy 359.356809 -351.088172) (xy 359.411652 -351.078042)
			(xy 359.467386 -351.076005) (xy 359.522823 -351.082105) (xy 359.57678 -351.096211) (xy 359.628109 -351.118023)
			(xy 359.675715 -351.147077) (xy 359.718583 -351.182752) (xy 359.7558 -351.224289) (xy 359.786573 -351.270802)
			(xy 359.810245 -351.321299) (xy 359.821423 -351.358454) (xy 360.956858 -351.358454) (xy 360.960929 -351.302832)
			(xy 360.973055 -351.248395) (xy 360.992978 -351.196304) (xy 361.020274 -351.147669) (xy 361.05436 -351.103526)
			(xy 361.094509 -351.064817) (xy 361.139867 -351.032366) (xy 361.189467 -351.006865) (xy 361.242251 -350.988858)
			(xy 361.297094 -350.978728) (xy 361.352828 -350.976691) (xy 361.408265 -350.982791) (xy 361.462222 -350.996897)
			(xy 361.513551 -351.018709) (xy 361.561157 -351.047763) (xy 361.604025 -351.083438) (xy 361.641242 -351.124975)
			(xy 361.672015 -351.171488) (xy 361.695687 -351.221985) (xy 361.711755 -351.275392) (xy 361.719875 -351.330568)
			(xy 361.720384 -351.358454) (xy 361.719875 -351.38634) (xy 361.711755 -351.441516) (xy 361.695687 -351.494923)
			(xy 361.672015 -351.54542) (xy 361.641242 -351.591933) (xy 361.604025 -351.63347) (xy 361.561157 -351.669145)
			(xy 361.513551 -351.698199) (xy 361.462222 -351.720011) (xy 361.408265 -351.734117) (xy 361.352828 -351.740217)
			(xy 361.297094 -351.73818) (xy 361.242251 -351.72805) (xy 361.189467 -351.710043) (xy 361.139867 -351.684542)
			(xy 361.094509 -351.652091) (xy 361.05436 -351.613382) (xy 361.020274 -351.569239) (xy 360.992978 -351.520604)
			(xy 360.973055 -351.468513) (xy 360.960929 -351.414076) (xy 360.956858 -351.358454) (xy 359.821423 -351.358454)
			(xy 359.826313 -351.374706) (xy 359.834433 -351.429882) (xy 359.834942 -351.457768) (xy 359.834433 -351.485654)
			(xy 359.826313 -351.54083) (xy 359.810245 -351.594237) (xy 359.786573 -351.644734) (xy 359.7558 -351.691247)
			(xy 359.718583 -351.732784) (xy 359.675715 -351.768459) (xy 359.628109 -351.797513) (xy 359.57678 -351.819325)
			(xy 359.522823 -351.833431) (xy 359.467386 -351.839531) (xy 359.411652 -351.837494) (xy 359.356809 -351.827364)
			(xy 359.304025 -351.809357) (xy 359.254425 -351.783856) (xy 359.209067 -351.751405) (xy 359.168918 -351.712696)
			(xy 359.134832 -351.668553) (xy 359.107536 -351.619918) (xy 359.087613 -351.567827) (xy 359.075487 -351.51339)
			(xy 359.071416 -351.457768) (xy 357.619842 -351.457768) (xy 357.622093 -351.473062) (xy 357.622602 -351.500948)
			(xy 357.622093 -351.528834) (xy 357.613973 -351.58401) (xy 357.597905 -351.637417) (xy 357.574233 -351.687914)
			(xy 357.54346 -351.734427) (xy 357.506243 -351.775964) (xy 357.463375 -351.811639) (xy 357.415769 -351.840693)
			(xy 357.36444 -351.862505) (xy 357.310483 -351.876611) (xy 357.255046 -351.882711) (xy 357.199312 -351.880674)
			(xy 357.144469 -351.870544) (xy 357.091685 -351.852537) (xy 357.042085 -351.827036) (xy 356.996727 -351.794585)
			(xy 356.956578 -351.755876) (xy 356.922492 -351.711733) (xy 356.895196 -351.663098) (xy 356.875273 -351.611007)
			(xy 356.863147 -351.55657) (xy 356.859076 -351.500948) (xy 356.340416 -351.500948) (xy 356.353509 -351.520738)
			(xy 356.377181 -351.571235) (xy 356.393249 -351.624642) (xy 356.401369 -351.679818) (xy 356.401878 -351.707704)
			(xy 356.401369 -351.73559) (xy 356.393249 -351.790766) (xy 356.377181 -351.844173) (xy 356.353509 -351.89467)
			(xy 356.322736 -351.941183) (xy 356.285519 -351.98272) (xy 356.242651 -352.018395) (xy 356.195045 -352.047449)
			(xy 356.143716 -352.069261) (xy 356.089759 -352.083367) (xy 356.034322 -352.089467) (xy 355.978588 -352.08743)
			(xy 355.923745 -352.0773) (xy 355.870961 -352.059293) (xy 355.821361 -352.033792) (xy 355.776003 -352.001341)
			(xy 355.735854 -351.962632) (xy 355.701768 -351.918489) (xy 355.674472 -351.869854) (xy 355.654549 -351.817763)
			(xy 355.642423 -351.763326) (xy 355.638352 -351.707704) (xy 354.93878 -351.707704) (xy 354.96536 -351.737369)
			(xy 354.996133 -351.783882) (xy 355.019805 -351.834379) (xy 355.035873 -351.887786) (xy 355.043993 -351.942962)
			(xy 355.044502 -351.970848) (xy 355.043993 -351.998734) (xy 355.035873 -352.05391) (xy 355.019805 -352.107317)
			(xy 354.996133 -352.157814) (xy 354.96536 -352.204327) (xy 354.928143 -352.245864) (xy 354.885275 -352.281539)
			(xy 354.837669 -352.310593) (xy 354.78634 -352.332405) (xy 354.732383 -352.346511) (xy 354.676946 -352.352611)
			(xy 354.621212 -352.350574) (xy 354.566369 -352.340444) (xy 354.513585 -352.322437) (xy 354.463985 -352.296936)
			(xy 354.418627 -352.264485) (xy 354.378478 -352.225776) (xy 354.344392 -352.181633) (xy 354.317096 -352.132998)
			(xy 354.297173 -352.080907) (xy 354.285047 -352.02647) (xy 354.280976 -351.970848) (xy 353.533311 -351.970848)
			(xy 353.513535 -352.013034) (xy 353.482762 -352.059547) (xy 353.445545 -352.101084) (xy 353.402677 -352.136759)
			(xy 353.355071 -352.165813) (xy 353.303742 -352.187625) (xy 353.249785 -352.201731) (xy 353.194348 -352.207831)
			(xy 353.138614 -352.205794) (xy 353.083771 -352.195664) (xy 353.030987 -352.177657) (xy 352.981387 -352.152156)
			(xy 352.936029 -352.119705) (xy 352.89588 -352.080996) (xy 352.861794 -352.036853) (xy 352.834498 -351.988218)
			(xy 352.814575 -351.936127) (xy 352.802449 -351.88169) (xy 352.798378 -351.826068) (xy 352.627431 -351.826068)
			(xy 352.619162 -351.838567) (xy 352.581945 -351.880104) (xy 352.539077 -351.915779) (xy 352.491471 -351.944833)
			(xy 352.440142 -351.966645) (xy 352.386185 -351.980751) (xy 352.330748 -351.986851) (xy 352.275014 -351.984814)
			(xy 352.220171 -351.974684) (xy 352.167387 -351.956677) (xy 352.117787 -351.931176) (xy 352.072429 -351.898725)
			(xy 352.03228 -351.860016) (xy 351.998194 -351.815873) (xy 351.970898 -351.767238) (xy 351.950975 -351.715147)
			(xy 351.938849 -351.66071) (xy 351.934778 -351.605088) (xy 310.688086 -351.605088) (xy 309.896894 -352.396298)
			(xy 358.510076 -352.396298) (xy 358.514147 -352.340676) (xy 358.526273 -352.286239) (xy 358.546196 -352.234148)
			(xy 358.573492 -352.185513) (xy 358.607578 -352.14137) (xy 358.647727 -352.102661) (xy 358.693085 -352.07021)
			(xy 358.742685 -352.044709) (xy 358.795469 -352.026702) (xy 358.850312 -352.016572) (xy 358.906046 -352.014535)
			(xy 358.961483 -352.020635) (xy 359.01544 -352.034741) (xy 359.066769 -352.056553) (xy 359.114375 -352.085607)
			(xy 359.157243 -352.121282) (xy 359.19446 -352.162819) (xy 359.225233 -352.209332) (xy 359.248905 -352.259829)
			(xy 359.264973 -352.313236) (xy 359.273093 -352.368412) (xy 359.273602 -352.396298) (xy 359.273301 -352.412808)
			(xy 360.041442 -352.412808) (xy 360.045513 -352.357186) (xy 360.057639 -352.302749) (xy 360.077562 -352.250658)
			(xy 360.104858 -352.202023) (xy 360.138944 -352.15788) (xy 360.179093 -352.119171) (xy 360.224451 -352.08672)
			(xy 360.274051 -352.061219) (xy 360.326835 -352.043212) (xy 360.381678 -352.033082) (xy 360.437412 -352.031045)
			(xy 360.492849 -352.037145) (xy 360.546806 -352.051251) (xy 360.598135 -352.073063) (xy 360.645741 -352.102117)
			(xy 360.688609 -352.137792) (xy 360.725826 -352.179329) (xy 360.756599 -352.225842) (xy 360.780271 -352.276339)
			(xy 360.796339 -352.329746) (xy 360.804459 -352.384922) (xy 360.804968 -352.412808) (xy 360.804459 -352.440694)
			(xy 360.796339 -352.49587) (xy 360.780271 -352.549277) (xy 360.756599 -352.599774) (xy 360.725826 -352.646287)
			(xy 360.688609 -352.687824) (xy 360.645741 -352.723499) (xy 360.598135 -352.752553) (xy 360.546806 -352.774365)
			(xy 360.492849 -352.788471) (xy 360.437412 -352.794571) (xy 360.381678 -352.792534) (xy 360.326835 -352.782404)
			(xy 360.274051 -352.764397) (xy 360.224451 -352.738896) (xy 360.179093 -352.706445) (xy 360.138944 -352.667736)
			(xy 360.104858 -352.623593) (xy 360.077562 -352.574958) (xy 360.057639 -352.522867) (xy 360.045513 -352.46843)
			(xy 360.041442 -352.412808) (xy 359.273301 -352.412808) (xy 359.273093 -352.424184) (xy 359.264973 -352.47936)
			(xy 359.248905 -352.532767) (xy 359.225233 -352.583264) (xy 359.19446 -352.629777) (xy 359.157243 -352.671314)
			(xy 359.114375 -352.706989) (xy 359.066769 -352.736043) (xy 359.01544 -352.757855) (xy 358.961483 -352.771961)
			(xy 358.906046 -352.778061) (xy 358.850312 -352.776024) (xy 358.795469 -352.765894) (xy 358.742685 -352.747887)
			(xy 358.693085 -352.722386) (xy 358.647727 -352.689935) (xy 358.607578 -352.651226) (xy 358.573492 -352.607083)
			(xy 358.546196 -352.558448) (xy 358.526273 -352.506357) (xy 358.514147 -352.45192) (xy 358.510076 -352.396298)
			(xy 309.896894 -352.396298) (xy 305.399646 -356.89365) (xy 336.912199 -356.89365) (xy 336.912199 -356.83915)
			(xy 336.919955 -356.785205) (xy 336.93531 -356.732913) (xy 336.95795 -356.683338) (xy 336.987415 -356.63749)
			(xy 337.023105 -356.596302) (xy 337.064293 -356.560613) (xy 337.110142 -356.531148) (xy 337.159717 -356.508508)
			(xy 337.212009 -356.493155) (xy 337.265954 -356.485399) (xy 337.293204 -356.484936) (xy 337.319273 -356.485399)
			(xy 337.370924 -356.492507) (xy 337.421127 -356.506577) (xy 337.468949 -356.527347) (xy 337.5135 -356.55443)
			(xy 337.553953 -356.587323) (xy 337.589553 -356.625414) (xy 337.619639 -356.667995) (xy 337.63204 -356.69093)
			(xy 337.638853 -356.703047) (xy 337.65782 -356.723352) (xy 337.681561 -356.737788) (xy 337.708317 -356.745284)
			(xy 337.736103 -356.745284) (xy 337.762859 -356.737788) (xy 337.7866 -356.723352) (xy 337.805567 -356.703047)
			(xy 337.81238 -356.69093) (xy 337.825437 -356.666805) (xy 337.857419 -356.622237) (xy 337.895431 -356.582687)
			(xy 337.916774 -356.565454) (xy 337.928536 -356.555509) (xy 337.946057 -356.530199) (xy 337.955239 -356.500818)
			(xy 337.955247 -356.470036) (xy 337.946081 -356.44065) (xy 337.928574 -356.41533) (xy 337.916774 -356.405434)
			(xy 337.894301 -356.38723) (xy 337.854567 -356.345212) (xy 337.821627 -356.29768) (xy 337.796237 -356.245721)
			(xy 337.778978 -356.190526) (xy 337.770245 -356.133359) (xy 337.769708 -356.104444) (xy 337.770196 -356.077192)
			(xy 337.777948 -356.023241) (xy 337.793299 -355.970942) (xy 337.815937 -355.921361) (xy 337.845402 -355.875507)
			(xy 337.881094 -355.834314) (xy 337.922285 -355.798619) (xy 337.968137 -355.769151) (xy 338.017716 -355.746509)
			(xy 338.070013 -355.731154) (xy 338.123964 -355.723398) (xy 338.151216 -355.722936) (xy 338.180131 -355.723501)
			(xy 338.237301 -355.732219) (xy 338.292499 -355.749466) (xy 338.344462 -355.774849) (xy 338.391997 -355.807785)
			(xy 338.434015 -355.84752) (xy 338.452206 -355.870002) (xy 338.462103 -355.881807) (xy 338.487427 -355.899326)
			(xy 338.51682 -355.908502) (xy 338.547612 -355.908502) (xy 338.577005 -355.899326) (xy 338.602329 -355.881807)
			(xy 338.612226 -355.870002) (xy 338.628979 -355.849219) (xy 338.667333 -355.812089) (xy 338.710487 -355.780667)
			(xy 338.757601 -355.755568) (xy 338.807753 -355.737282) (xy 338.859964 -355.726165) (xy 338.913216 -355.722435)
			(xy 338.966468 -355.726165) (xy 339.018679 -355.737282) (xy 339.068831 -355.755568) (xy 339.115945 -355.780667)
			(xy 339.159099 -355.812089) (xy 339.197453 -355.849219) (xy 339.214206 -355.870002) (xy 339.224103 -355.881807)
			(xy 339.249427 -355.899326) (xy 339.27882 -355.908502) (xy 339.309612 -355.908502) (xy 339.339005 -355.899326)
			(xy 339.364329 -355.881807) (xy 339.374226 -355.870002) (xy 339.390979 -355.849219) (xy 339.429333 -355.812089)
			(xy 339.472487 -355.780667) (xy 339.519601 -355.755568) (xy 339.569753 -355.737282) (xy 339.621964 -355.726165)
			(xy 339.675216 -355.722435) (xy 339.728468 -355.726165) (xy 339.780679 -355.737282) (xy 339.830831 -355.755568)
			(xy 339.877945 -355.780667) (xy 339.921099 -355.812089) (xy 339.959453 -355.849219) (xy 339.976206 -355.870002)
			(xy 339.986103 -355.881807) (xy 340.011427 -355.899326) (xy 340.04082 -355.908502) (xy 340.071612 -355.908502)
			(xy 340.101005 -355.899326) (xy 340.126329 -355.881807) (xy 340.136226 -355.870002) (xy 340.152979 -355.849219)
			(xy 340.191333 -355.812089) (xy 340.234487 -355.780667) (xy 340.281601 -355.755568) (xy 340.331753 -355.737282)
			(xy 340.383964 -355.726165) (xy 340.437216 -355.722435) (xy 340.490468 -355.726165) (xy 340.542679 -355.737282)
			(xy 340.592831 -355.755568) (xy 340.639945 -355.780667) (xy 340.683099 -355.812089) (xy 340.721453 -355.849219)
			(xy 340.738206 -355.870002) (xy 340.748103 -355.881807) (xy 340.773427 -355.899326) (xy 340.80282 -355.908502)
			(xy 340.833612 -355.908502) (xy 340.863005 -355.899326) (xy 340.888329 -355.881807) (xy 340.898226 -355.870002)
			(xy 340.914979 -355.849219) (xy 340.953333 -355.812089) (xy 340.996487 -355.780667) (xy 341.043601 -355.755568)
			(xy 341.093753 -355.737282) (xy 341.145964 -355.726165) (xy 341.199216 -355.722435) (xy 341.252468 -355.726165)
			(xy 341.304679 -355.737282) (xy 341.354831 -355.755568) (xy 341.401945 -355.780667) (xy 341.445099 -355.812089)
			(xy 341.483453 -355.849219) (xy 341.500206 -355.870002) (xy 341.510103 -355.881807) (xy 341.535427 -355.899326)
			(xy 341.56482 -355.908502) (xy 341.595612 -355.908502) (xy 341.625005 -355.899326) (xy 341.650329 -355.881807)
			(xy 341.660226 -355.870002) (xy 341.678403 -355.847506) (xy 341.720425 -355.807772) (xy 341.767963 -355.774834)
			(xy 341.819927 -355.749448) (xy 341.875127 -355.732194) (xy 341.932299 -355.723469) (xy 341.961216 -355.722936)
			(xy 341.987469 -355.723337) (xy 342.03948 -355.730528) (xy 342.090012 -355.744786) (xy 342.138112 -355.76584)
			(xy 342.182868 -355.793294) (xy 342.223436 -355.826627) (xy 342.259047 -355.86521) (xy 342.274398 -355.886512)
			(xy 342.282762 -355.897725) (xy 342.304387 -355.915451) (xy 342.330011 -355.926648) (xy 342.35771 -355.930476)
			(xy 342.385409 -355.926648) (xy 342.411033 -355.915451) (xy 342.432658 -355.897725) (xy 342.441022 -355.886512)
			(xy 342.456356 -355.865201) (xy 342.491981 -355.826635) (xy 342.532557 -355.793316) (xy 342.577317 -355.765873)
			(xy 342.625416 -355.744825) (xy 342.675946 -355.730568) (xy 342.727953 -355.723372) (xy 342.754204 -355.722936)
			(xy 342.784327 -355.723508) (xy 342.843823 -355.73299) (xy 342.901091 -355.7517) (xy 342.954708 -355.779176)
			(xy 343.003343 -355.814733) (xy 343.024968 -355.835712) (xy 343.03469 -355.84493) (xy 343.057852 -355.858375)
			(xy 343.083713 -355.865337) (xy 343.110495 -355.865337) (xy 343.136356 -355.858375) (xy 343.159518 -355.84493)
			(xy 343.16924 -355.835712) (xy 343.19087 -355.814737) (xy 343.239497 -355.779168) (xy 343.293112 -355.751687)
			(xy 343.350382 -355.732977) (xy 343.40988 -355.723505) (xy 343.440004 -355.722936) (xy 343.467259 -355.723352)
			(xy 343.521214 -355.73111) (xy 343.573515 -355.746469) (xy 343.623098 -355.769115) (xy 343.668954 -355.798588)
			(xy 343.710147 -355.834287) (xy 343.745841 -355.875485) (xy 343.775308 -355.921344) (xy 343.797948 -355.97093)
			(xy 343.8133 -356.023233) (xy 343.821052 -356.077189) (xy 343.821512 -356.104444) (xy 343.820987 -356.133361)
			(xy 343.812264 -356.190533) (xy 343.795009 -356.245734) (xy 343.769619 -356.297696) (xy 343.736675 -356.34523)
			(xy 343.696932 -356.387245) (xy 343.674446 -356.405434) (xy 343.662593 -356.415281) (xy 343.645071 -356.440617)
			(xy 343.635897 -356.470024) (xy 343.635905 -356.500829) (xy 343.645095 -356.530232) (xy 343.662631 -356.555558)
			(xy 343.674446 -356.565454) (xy 343.696917 -356.583659) (xy 343.736651 -356.625678) (xy 343.76959 -356.67321)
			(xy 343.79498 -356.725168) (xy 343.81224 -356.780362) (xy 343.820974 -356.837529) (xy 343.821512 -356.866444)
			(xy 343.821063 -356.893696) (xy 343.813301 -356.947645) (xy 343.79794 -356.99994) (xy 343.775294 -357.049517)
			(xy 343.745824 -357.095367) (xy 343.710129 -357.136557) (xy 343.668935 -357.172248) (xy 343.623082 -357.201713)
			(xy 343.573503 -357.224354) (xy 343.521206 -357.239709) (xy 343.467256 -357.247466) (xy 343.440004 -357.247952)
			(xy 343.409881 -357.247378) (xy 343.350384 -357.237898) (xy 343.293117 -357.219188) (xy 343.2395 -357.191712)
			(xy 343.190865 -357.156155) (xy 343.16924 -357.135176) (xy 343.159518 -357.125958) (xy 343.136356 -357.112513)
			(xy 343.110495 -357.105551) (xy 343.083713 -357.105551) (xy 343.057852 -357.112513) (xy 343.03469 -357.125958)
			(xy 343.024968 -357.135176) (xy 343.003332 -357.156145) (xy 342.954707 -357.191715) (xy 342.901093 -357.219198)
			(xy 342.843825 -357.237909) (xy 342.784328 -357.247383) (xy 342.754204 -357.247952) (xy 342.727951 -357.247541)
			(xy 342.675941 -357.240352) (xy 342.625408 -357.226097) (xy 342.577309 -357.205044) (xy 342.532552 -357.177592)
			(xy 342.491984 -357.14426) (xy 342.456373 -357.105677) (xy 342.441022 -357.084376) (xy 342.432658 -357.073163)
			(xy 342.411033 -357.055437) (xy 342.385409 -357.04424) (xy 342.35771 -357.040412) (xy 342.330011 -357.04424)
			(xy 342.304387 -357.055437) (xy 342.282762 -357.073163) (xy 342.274398 -357.084376) (xy 342.259048 -357.105675)
			(xy 342.223426 -357.144242) (xy 342.182853 -357.177562) (xy 342.138096 -357.205006) (xy 342.09 -357.226057)
			(xy 342.039472 -357.240316) (xy 341.987467 -357.247514) (xy 341.961216 -357.247952) (xy 341.932299 -357.24744)
			(xy 341.875126 -357.238713) (xy 341.819927 -357.221454) (xy 341.767964 -357.196062) (xy 341.720431 -357.163116)
			(xy 341.678415 -357.123373) (xy 341.660226 -357.100886) (xy 341.650329 -357.089081) (xy 341.625005 -357.071562)
			(xy 341.595612 -357.062386) (xy 341.56482 -357.062386) (xy 341.535427 -357.071562) (xy 341.510103 -357.089081)
			(xy 341.500206 -357.100886) (xy 341.483453 -357.121669) (xy 341.445099 -357.158799) (xy 341.401945 -357.190221)
			(xy 341.354831 -357.21532) (xy 341.304679 -357.233606) (xy 341.252468 -357.244723) (xy 341.199216 -357.248453)
			(xy 341.145964 -357.244723) (xy 341.093753 -357.233606) (xy 341.043601 -357.21532) (xy 340.996487 -357.190221)
			(xy 340.953333 -357.158799) (xy 340.914979 -357.121669) (xy 340.898226 -357.100886) (xy 340.888329 -357.089081)
			(xy 340.863005 -357.071562) (xy 340.833612 -357.062386) (xy 340.80282 -357.062386) (xy 340.773427 -357.071562)
			(xy 340.748103 -357.089081) (xy 340.738206 -357.100886) (xy 340.721453 -357.121669) (xy 340.683099 -357.158799)
			(xy 340.639945 -357.190221) (xy 340.592831 -357.21532) (xy 340.542679 -357.233606) (xy 340.490468 -357.244723)
			(xy 340.437216 -357.248453) (xy 340.383964 -357.244723) (xy 340.331753 -357.233606) (xy 340.281601 -357.21532)
			(xy 340.234487 -357.190221) (xy 340.191333 -357.158799) (xy 340.152979 -357.121669) (xy 340.136226 -357.100886)
			(xy 340.126329 -357.089081) (xy 340.101005 -357.071562) (xy 340.071612 -357.062386) (xy 340.04082 -357.062386)
			(xy 340.011427 -357.071562) (xy 339.986103 -357.089081) (xy 339.976206 -357.100886) (xy 339.959453 -357.121669)
			(xy 339.921099 -357.158799) (xy 339.877945 -357.190221) (xy 339.830831 -357.21532) (xy 339.780679 -357.233606)
			(xy 339.728468 -357.244723) (xy 339.675216 -357.248453) (xy 339.621964 -357.244723) (xy 339.569753 -357.233606)
			(xy 339.519601 -357.21532) (xy 339.472487 -357.190221) (xy 339.429333 -357.158799) (xy 339.390979 -357.121669)
			(xy 339.374226 -357.100886) (xy 339.364329 -357.089081) (xy 339.339005 -357.071562) (xy 339.309612 -357.062386)
			(xy 339.27882 -357.062386) (xy 339.249427 -357.071562) (xy 339.224103 -357.089081) (xy 339.214206 -357.100886)
			(xy 339.197453 -357.121669) (xy 339.159099 -357.158799) (xy 339.115945 -357.190221) (xy 339.068831 -357.21532)
			(xy 339.018679 -357.233606) (xy 338.966468 -357.244723) (xy 338.913216 -357.248453) (xy 338.859964 -357.244723)
			(xy 338.807753 -357.233606) (xy 338.757601 -357.21532) (xy 338.710487 -357.190221) (xy 338.667333 -357.158799)
			(xy 338.628979 -357.121669) (xy 338.612226 -357.100886) (xy 338.602329 -357.089081) (xy 338.577005 -357.071562)
			(xy 338.547612 -357.062386) (xy 338.51682 -357.062386) (xy 338.487427 -357.071562) (xy 338.462103 -357.089081)
			(xy 338.452206 -357.100886) (xy 338.434008 -357.123364) (xy 338.39199 -357.1631) (xy 338.344457 -357.19604)
			(xy 338.292497 -357.221429) (xy 338.2373 -357.238687) (xy 338.180132 -357.247417) (xy 338.151216 -357.247952)
			(xy 338.125148 -357.247479) (xy 338.073497 -357.240373) (xy 338.023293 -357.226305) (xy 337.975471 -357.205538)
			(xy 337.93092 -357.178456) (xy 337.890467 -357.145564) (xy 337.854867 -357.107473) (xy 337.82478 -357.064893)
			(xy 337.81238 -357.041958) (xy 337.805567 -357.029841) (xy 337.7866 -357.009536) (xy 337.762859 -356.9951)
			(xy 337.736103 -356.987604) (xy 337.708317 -356.987604) (xy 337.681561 -356.9951) (xy 337.65782 -357.009536)
			(xy 337.638853 -357.029841) (xy 337.63204 -357.041958) (xy 337.619684 -357.064922) (xy 337.589607 -357.107522)
			(xy 337.554009 -357.145628) (xy 337.513553 -357.178532) (xy 337.468992 -357.20562) (xy 337.421158 -357.226386)
			(xy 337.370941 -357.240445) (xy 337.319278 -357.247534) (xy 337.293204 -357.247952) (xy 337.265954 -357.247401)
			(xy 337.212009 -357.239645) (xy 337.159717 -357.224292) (xy 337.110142 -357.201652) (xy 337.064293 -357.172187)
			(xy 337.023105 -357.136498) (xy 336.987415 -357.09531) (xy 336.95795 -357.049462) (xy 336.93531 -356.999887)
			(xy 336.919955 -356.947595) (xy 336.912199 -356.89365) (xy 305.399646 -356.89365) (xy 304.529998 -357.763318)
			(xy 304.511992 -357.78065) (xy 304.471587 -357.810059) (xy 304.427074 -357.832776) (xy 304.379552 -357.84824)
			(xy 304.330195 -357.856069) (xy 304.305208 -357.856536) (xy 284.845252 -357.856536) (xy 283.744416 -358.957118)
			(xy 283.744416 -359.238802) (xy 335.453223 -359.238802) (xy 335.456952 -359.18555) (xy 335.46807 -359.133337)
			(xy 335.486358 -359.083185) (xy 335.511459 -359.036072) (xy 335.542884 -358.992918) (xy 335.580018 -358.954566)
			(xy 335.600802 -358.937814) (xy 335.612602 -358.927911) (xy 335.630117 -358.902589) (xy 335.639292 -358.873197)
			(xy 335.639292 -358.842407) (xy 335.630119 -358.813016) (xy 335.612605 -358.787692) (xy 335.600802 -358.777794)
			(xy 335.578316 -358.759606) (xy 335.538581 -358.717586) (xy 335.505642 -358.67005) (xy 335.480254 -358.618088)
			(xy 335.462999 -358.56289) (xy 335.45427 -358.50572) (xy 335.453736 -358.476804) (xy 335.454159 -358.449549)
			(xy 335.461917 -358.395595) (xy 335.477275 -358.343293) (xy 335.49992 -358.29371) (xy 335.529391 -358.247855)
			(xy 335.565089 -358.206661) (xy 335.606287 -358.170967) (xy 335.652145 -358.141501) (xy 335.701731 -358.118861)
			(xy 335.754034 -358.103508) (xy 335.807989 -358.095756) (xy 335.835244 -358.095296) (xy 335.864296 -358.095875)
			(xy 335.92173 -358.104666) (xy 335.977166 -358.122067) (xy 336.029321 -358.147676) (xy 336.076988 -358.1809)
			(xy 336.119063 -358.220971) (xy 336.13725 -358.243632) (xy 336.146504 -358.254707) (xy 336.169828 -358.271677)
			(xy 336.196969 -358.281442) (xy 336.225758 -358.283222) (xy 336.253895 -358.276877) (xy 336.279133 -358.262911)
			(xy 336.28965 -358.25303) (xy 336.298332 -358.244396) (xy 336.316634 -358.228128) (xy 336.326226 -358.220518)
			(xy 336.33802 -358.21061) (xy 336.355531 -358.185287) (xy 336.364703 -358.155898) (xy 336.364705 -358.125111)
			(xy 336.355535 -358.095721) (xy 336.338026 -358.070397) (xy 336.326226 -358.060498) (xy 336.303747 -358.042302)
			(xy 336.26401 -358.000284) (xy 336.23107 -357.95275) (xy 336.205681 -357.90079) (xy 336.188424 -357.845593)
			(xy 336.179695 -357.788424) (xy 336.17916 -357.759508) (xy 336.179685 -357.732258) (xy 336.18744 -357.678314)
			(xy 336.202792 -357.626022) (xy 336.22543 -357.576447) (xy 336.254893 -357.530598) (xy 336.29058 -357.489408)
			(xy 336.331766 -357.453717) (xy 336.377611 -357.424249) (xy 336.427184 -357.401606) (xy 336.479475 -357.386248)
			(xy 336.533418 -357.378488) (xy 336.560668 -357.378) (xy 336.588047 -357.378477) (xy 336.64224 -357.386314)
			(xy 336.694757 -357.401816) (xy 336.744519 -357.424665) (xy 336.790505 -357.454393) (xy 336.831769 -357.490388)
			(xy 336.849974 -357.510842) (xy 336.860022 -357.521832) (xy 336.885087 -357.537887) (xy 336.913716 -357.54604)
			(xy 336.943479 -357.545599) (xy 336.971854 -357.536602) (xy 336.996433 -357.519812) (xy 337.006184 -357.508556)
			(xy 337.024421 -357.486776) (xy 337.066213 -357.448305) (xy 337.113247 -357.416454) (xy 337.164482 -357.391927)
			(xy 337.218787 -357.375267) (xy 337.274962 -357.366841) (xy 337.303364 -357.366316) (xy 337.331062 -357.366795)
			(xy 337.385876 -357.374797) (xy 337.438957 -357.390639) (xy 337.489191 -357.413988) (xy 337.535522 -357.444352)
			(xy 337.576978 -357.481096) (xy 337.59521 -357.501952) (xy 337.604729 -357.512643) (xy 337.628495 -357.528585)
			(xy 337.655753 -357.537301) (xy 337.684359 -357.538106) (xy 337.712064 -357.530938) (xy 337.736689 -357.516359)
			(xy 337.746848 -357.50627) (xy 337.764952 -357.487755) (xy 337.805259 -357.455249) (xy 337.849593 -357.428494)
			(xy 337.897138 -357.407982) (xy 337.947021 -357.394091) (xy 337.998325 -357.387075) (xy 338.024216 -357.386636)
			(xy 338.051471 -357.38704) (xy 338.105427 -357.3948) (xy 338.157728 -357.410161) (xy 338.207312 -357.432808)
			(xy 338.253167 -357.462282) (xy 338.29436 -357.497982) (xy 338.330054 -357.539181) (xy 338.35952 -357.585041)
			(xy 338.38216 -357.634628) (xy 338.397512 -357.686932) (xy 338.405264 -357.740889) (xy 338.405724 -357.768144)
			(xy 338.405194 -357.797061) (xy 338.396471 -357.854233) (xy 338.379218 -357.909433) (xy 338.353828 -357.961395)
			(xy 338.320885 -358.008929) (xy 338.281144 -358.050945) (xy 338.258658 -358.069134) (xy 338.246804 -358.078981)
			(xy 338.22928 -358.104316) (xy 338.220104 -358.133724) (xy 338.220112 -358.16453) (xy 338.229303 -358.193933)
			(xy 338.246842 -358.219259) (xy 338.258658 -358.229154) (xy 338.281111 -358.247382) (xy 338.32085 -358.289392)
			(xy 338.353794 -358.336919) (xy 338.379188 -358.388874) (xy 338.39645 -358.444065) (xy 338.405186 -358.50123)
			(xy 338.405724 -358.530144) (xy 338.405225 -358.557347) (xy 338.397493 -358.611202) (xy 338.382179 -358.663409)
			(xy 338.359595 -358.712906) (xy 338.330198 -358.758688) (xy 338.31276 -358.779572) (xy 338.303282 -358.791464)
			(xy 338.291054 -358.819286) (xy 338.287557 -358.849474) (xy 338.293099 -358.879354) (xy 338.307191 -358.906279)
			(xy 338.328583 -358.927865) (xy 338.341716 -358.935528) (xy 338.364879 -358.948451) (xy 338.407693 -358.979759)
			(xy 338.445736 -359.016719) (xy 338.462366 -359.037382) (xy 338.472263 -359.049187) (xy 338.497587 -359.066706)
			(xy 338.52698 -359.075882) (xy 338.557772 -359.075882) (xy 338.587165 -359.066706) (xy 338.612489 -359.049187)
			(xy 338.622386 -359.037382) (xy 338.639139 -359.016599) (xy 338.677493 -358.979469) (xy 338.720647 -358.948047)
			(xy 338.767761 -358.922948) (xy 338.817913 -358.904662) (xy 338.870124 -358.893545) (xy 338.923376 -358.889815)
			(xy 338.976628 -358.893545) (xy 339.028839 -358.904662) (xy 339.078991 -358.922948) (xy 339.126105 -358.948047)
			(xy 339.169259 -358.979469) (xy 339.207613 -359.016599) (xy 339.224366 -359.037382) (xy 339.234263 -359.049187)
			(xy 339.259587 -359.066706) (xy 339.28898 -359.075882) (xy 339.319772 -359.075882) (xy 339.349165 -359.066706)
			(xy 339.374489 -359.049187) (xy 339.384386 -359.037382) (xy 339.401139 -359.016599) (xy 339.439493 -358.979469)
			(xy 339.482647 -358.948047) (xy 339.529761 -358.922948) (xy 339.579913 -358.904662) (xy 339.632124 -358.893545)
			(xy 339.685376 -358.889815) (xy 339.738628 -358.893545) (xy 339.790839 -358.904662) (xy 339.840991 -358.922948)
			(xy 339.888105 -358.948047) (xy 339.931259 -358.979469) (xy 339.969613 -359.016599) (xy 339.986366 -359.037382)
			(xy 339.996263 -359.049187) (xy 340.021587 -359.066706) (xy 340.05098 -359.075882) (xy 340.081772 -359.075882)
			(xy 340.111165 -359.066706) (xy 340.136489 -359.049187) (xy 340.146386 -359.037382) (xy 340.163139 -359.016599)
			(xy 340.201493 -358.979469) (xy 340.244647 -358.948047) (xy 340.291761 -358.922948) (xy 340.341913 -358.904662)
			(xy 340.394124 -358.893545) (xy 340.447376 -358.889815) (xy 340.500628 -358.893545) (xy 340.552839 -358.904662)
			(xy 340.602991 -358.922948) (xy 340.650105 -358.948047) (xy 340.693259 -358.979469) (xy 340.731613 -359.016599)
			(xy 340.748366 -359.037382) (xy 340.758263 -359.049187) (xy 340.783587 -359.066706) (xy 340.81298 -359.075882)
			(xy 340.843772 -359.075882) (xy 340.873165 -359.066706) (xy 340.898489 -359.049187) (xy 340.908386 -359.037382)
			(xy 340.925139 -359.016599) (xy 340.963493 -358.979469) (xy 341.006647 -358.948047) (xy 341.053761 -358.922948)
			(xy 341.103913 -358.904662) (xy 341.156124 -358.893545) (xy 341.209376 -358.889815) (xy 341.262628 -358.893545)
			(xy 341.314839 -358.904662) (xy 341.364991 -358.922948) (xy 341.412105 -358.948047) (xy 341.455259 -358.979469)
			(xy 341.493613 -359.016599) (xy 341.510366 -359.037382) (xy 341.520263 -359.049187) (xy 341.545587 -359.066706)
			(xy 341.57498 -359.075882) (xy 341.605772 -359.075882) (xy 341.635165 -359.066706) (xy 341.660489 -359.049187)
			(xy 341.670386 -359.037382) (xy 341.688207 -359.015359) (xy 341.729273 -358.976336) (xy 341.752174 -358.959658)
			(xy 341.764272 -358.950505) (xy 341.782866 -358.926555) (xy 341.793608 -358.8982) (xy 341.795551 -358.867941)
			(xy 341.788523 -358.838446) (xy 341.773144 -358.812314) (xy 341.762334 -358.80167) (xy 341.743114 -358.783539)
			(xy 341.709397 -358.742857) (xy 341.681616 -358.697912) (xy 341.660303 -358.649563) (xy 341.645864 -358.598736)
			(xy 341.638575 -358.546403) (xy 341.638128 -358.519984) (xy 341.638696 -358.491069) (xy 341.647413 -358.4339)
			(xy 341.664661 -358.378701) (xy 341.690043 -358.326739) (xy 341.722978 -358.279204) (xy 341.762712 -358.237186)
			(xy 341.785194 -358.218994) (xy 341.797015 -358.209114) (xy 341.814531 -358.183785) (xy 341.823704 -358.154388)
			(xy 341.823701 -358.123593) (xy 341.814522 -358.094197) (xy 341.797001 -358.068872) (xy 341.785194 -358.058974)
			(xy 341.762697 -358.040799) (xy 341.722963 -357.998776) (xy 341.690026 -357.951238) (xy 341.66464 -357.899273)
			(xy 341.647386 -357.844073) (xy 341.638661 -357.786901) (xy 341.638128 -357.757984) (xy 341.63854 -357.730729)
			(xy 341.6463 -357.676774) (xy 341.66166 -357.624473) (xy 341.684307 -357.574891) (xy 341.71378 -357.529036)
			(xy 341.749479 -357.487842) (xy 341.790678 -357.452149) (xy 341.836536 -357.422682) (xy 341.886122 -357.400042)
			(xy 341.938425 -357.384689) (xy 341.992381 -357.376936) (xy 342.019636 -357.376476) (xy 342.0472 -357.376933)
			(xy 342.101756 -357.384854) (xy 342.154606 -357.400539) (xy 342.20465 -357.423664) (xy 342.250847 -357.453746)
			(xy 342.292236 -357.490161) (xy 342.310466 -357.510842) (xy 342.320577 -357.521809) (xy 342.345631 -357.537962)
			(xy 342.374281 -357.5462) (xy 342.404088 -357.545822) (xy 342.432519 -357.536859) (xy 342.457154 -357.520074)
			(xy 342.46693 -357.50881) (xy 342.485142 -357.486967) (xy 342.526959 -357.448426) (xy 342.574034 -357.416519)
			(xy 342.625322 -357.39195) (xy 342.679689 -357.375266) (xy 342.735929 -357.366836) (xy 342.764364 -357.366316)
			(xy 342.794486 -357.366919) (xy 342.85398 -357.376394) (xy 342.911248 -357.395098) (xy 342.964865 -357.422566)
			(xy 343.013502 -357.458117) (xy 343.035128 -357.479092) (xy 343.04485 -357.48831) (xy 343.068012 -357.501755)
			(xy 343.093873 -357.508717) (xy 343.120655 -357.508717) (xy 343.146516 -357.501755) (xy 343.169678 -357.48831)
			(xy 343.1794 -357.479092) (xy 343.201 -357.458085) (xy 343.249636 -357.422521) (xy 343.303259 -357.395046)
			(xy 343.360534 -357.376344) (xy 343.420038 -357.36688) (xy 343.450164 -357.366316) (xy 343.477417 -357.366789)
			(xy 343.531369 -357.374542) (xy 343.583668 -357.389894) (xy 343.63325 -357.412534) (xy 343.679104 -357.442001)
			(xy 343.720298 -357.477694) (xy 343.755992 -357.518886) (xy 343.78546 -357.56474) (xy 343.808102 -357.614321)
			(xy 343.823456 -357.666619) (xy 343.83121 -357.720571) (xy 343.831672 -357.747824) (xy 343.83111 -357.776739)
			(xy 343.822392 -357.833909) (xy 343.805143 -357.889108) (xy 343.77976 -357.94107) (xy 343.746823 -357.988605)
			(xy 343.707089 -358.030623) (xy 343.684606 -358.048814) (xy 343.672777 -358.058686) (xy 343.655261 -358.084017)
			(xy 343.646089 -358.113416) (xy 343.646093 -358.144213) (xy 343.655274 -358.17361) (xy 343.672798 -358.198936)
			(xy 343.684606 -358.208834) (xy 343.705414 -358.225558) (xy 343.742548 -358.263913) (xy 343.773972 -358.307071)
			(xy 343.799073 -358.354188) (xy 343.81736 -358.404344) (xy 343.828477 -358.456559) (xy 343.832205 -358.509815)
			(xy 343.828473 -358.56307) (xy 343.817352 -358.615285) (xy 343.799061 -358.665439) (xy 343.773957 -358.712554)
			(xy 343.742529 -358.755709) (xy 343.705392 -358.794062) (xy 343.684606 -358.810814) (xy 343.672777 -358.820686)
			(xy 343.655261 -358.846017) (xy 343.646089 -358.875416) (xy 343.646093 -358.906213) (xy 343.655274 -358.93561)
			(xy 343.672798 -358.960936) (xy 343.684606 -358.970834) (xy 343.705414 -358.987558) (xy 343.742548 -359.025913)
			(xy 343.773972 -359.069071) (xy 343.799073 -359.116188) (xy 343.81736 -359.166344) (xy 343.828477 -359.218559)
			(xy 343.832205 -359.271815) (xy 343.828473 -359.32507) (xy 343.817352 -359.377285) (xy 343.799061 -359.427439)
			(xy 343.773957 -359.474554) (xy 343.742529 -359.517709) (xy 343.705392 -359.556062) (xy 343.684606 -359.572814)
			(xy 343.672777 -359.582686) (xy 343.655261 -359.608017) (xy 343.646089 -359.637416) (xy 343.646093 -359.668213)
			(xy 343.655274 -359.69761) (xy 343.672798 -359.722936) (xy 343.684606 -359.732834) (xy 343.705414 -359.749558)
			(xy 343.742548 -359.787913) (xy 343.773972 -359.831071) (xy 343.799073 -359.878188) (xy 343.81736 -359.928344)
			(xy 343.828477 -359.980559) (xy 343.832205 -360.033815) (xy 343.828473 -360.08707) (xy 343.817352 -360.139285)
			(xy 343.799061 -360.189439) (xy 343.773957 -360.236554) (xy 343.742529 -360.279709) (xy 343.705392 -360.318062)
			(xy 343.684606 -360.334814) (xy 343.672777 -360.344686) (xy 343.655261 -360.370017) (xy 343.646089 -360.399416)
			(xy 343.646093 -360.430213) (xy 343.655274 -360.45961) (xy 343.672798 -360.484936) (xy 343.684606 -360.494834)
			(xy 343.707107 -360.513004) (xy 343.746841 -360.555029) (xy 343.779778 -360.602568) (xy 343.805163 -360.654533)
			(xy 343.822415 -360.709734) (xy 343.83114 -360.766907) (xy 343.831672 -360.795824) (xy 343.831267 -360.823079)
			(xy 343.823506 -360.877034) (xy 343.808145 -360.929335) (xy 343.785497 -360.978918) (xy 343.756023 -361.024773)
			(xy 343.720324 -361.065966) (xy 343.679125 -361.101659) (xy 343.633265 -361.131126) (xy 343.583679 -361.153766)
			(xy 343.531375 -361.169119) (xy 343.477419 -361.176872) (xy 343.450164 -361.177332) (xy 343.420835 -361.17678)
			(xy 343.362867 -361.167803) (xy 343.306955 -361.150067) (xy 343.254413 -361.123987) (xy 343.206477 -361.090179)
			(xy 343.164276 -361.049438) (xy 343.128803 -361.002721) (xy 343.114376 -360.97718) (xy 343.109557 -360.969235)
			(xy 343.095458 -360.957159) (xy 343.077983 -360.950894) (xy 343.059423 -360.951261) (xy 343.04221 -360.958212)
			(xy 343.035128 -360.964226) (xy 343.02319 -360.974894) (xy 343.013502 -360.983802) (xy 342.998565 -361.005455)
			(xy 342.98967 -361.030211) (xy 342.987408 -361.056418) (xy 342.991932 -361.082332) (xy 343.002939 -361.106223)
			(xy 343.010998 -361.116626) (xy 343.027386 -361.137204) (xy 343.054961 -361.182004) (xy 343.076115 -361.23017)
			(xy 343.090444 -361.280787) (xy 343.097678 -361.332893) (xy 343.09812 -361.359196) (xy 343.097619 -361.386447)
			(xy 343.089863 -361.440393) (xy 343.074509 -361.492687) (xy 343.051869 -361.542263) (xy 343.022404 -361.588113)
			(xy 342.986714 -361.629303) (xy 342.945526 -361.664995) (xy 342.899677 -361.694461) (xy 342.850102 -361.717103)
			(xy 342.797809 -361.732459) (xy 342.743863 -361.740217) (xy 342.716612 -361.740704) (xy 342.687694 -361.740214)
			(xy 342.630519 -361.731484) (xy 342.575318 -361.714223) (xy 342.523356 -361.688826) (xy 342.475823 -361.655876)
			(xy 342.43381 -361.616127) (xy 342.415622 -361.593638) (xy 342.405725 -361.581833) (xy 342.380401 -361.564314)
			(xy 342.351008 -361.555138) (xy 342.320216 -361.555138) (xy 342.290823 -361.564314) (xy 342.265499 -361.581833)
			(xy 342.255602 -361.593638) (xy 342.248333 -361.602813) (xy 342.232828 -361.620351) (xy 342.224614 -361.62869)
			(xy 342.214238 -361.639813) (xy 342.200039 -361.666701) (xy 342.19437 -361.696575) (xy 342.197731 -361.726795)
			(xy 342.209827 -361.754692) (xy 342.21928 -361.766612) (xy 342.236469 -361.78743) (xy 342.265387 -361.833019)
			(xy 342.287596 -361.882227) (xy 342.302652 -361.934073) (xy 342.310254 -361.987522) (xy 342.31072 -362.014516)
			(xy 342.310237 -362.041767) (xy 342.302479 -362.095714) (xy 342.287122 -362.148008) (xy 342.26448 -362.197585)
			(xy 342.235013 -362.243435) (xy 342.199322 -362.284624) (xy 342.158131 -362.320316) (xy 342.112281 -362.349782)
			(xy 342.062705 -362.372424) (xy 342.01041 -362.38778) (xy 341.956463 -362.395537) (xy 341.929212 -362.396024)
			(xy 341.901243 -362.395556) (xy 341.845902 -362.3874) (xy 341.792347 -362.371247) (xy 341.741726 -362.347444)
			(xy 341.695126 -362.3165) (xy 341.653546 -362.279081) (xy 341.635334 -362.257848) (xy 341.625758 -362.247132)
			(xy 341.601994 -362.231) (xy 341.574677 -362.222124) (xy 341.545969 -362.221208) (xy 341.518142 -362.228325)
			(xy 341.493398 -362.24291) (xy 341.483188 -362.253022) (xy 341.465075 -362.271613) (xy 341.424725 -362.30426)
			(xy 341.38032 -362.331132) (xy 341.33268 -362.351734) (xy 341.282687 -362.365685) (xy 341.231264 -362.372726)
			(xy 341.205312 -362.373164) (xy 341.176395 -362.372651) (xy 341.119223 -362.363923) (xy 341.064023 -362.346664)
			(xy 341.012061 -362.321272) (xy 340.964528 -362.288327) (xy 340.922511 -362.248584) (xy 340.904322 -362.226098)
			(xy 340.894425 -362.214293) (xy 340.869101 -362.196774) (xy 340.839708 -362.187598) (xy 340.808916 -362.187598)
			(xy 340.779523 -362.196774) (xy 340.754199 -362.214293) (xy 340.744302 -362.226098) (xy 340.727549 -362.246881)
			(xy 340.689195 -362.284011) (xy 340.646041 -362.315433) (xy 340.598927 -362.340532) (xy 340.548775 -362.358818)
			(xy 340.496564 -362.369935) (xy 340.443312 -362.373665) (xy 340.39006 -362.369935) (xy 340.337849 -362.358818)
			(xy 340.287697 -362.340532) (xy 340.240583 -362.315433) (xy 340.197429 -362.284011) (xy 340.159075 -362.246881)
			(xy 340.142322 -362.226098) (xy 340.132425 -362.214293) (xy 340.107101 -362.196774) (xy 340.077708 -362.187598)
			(xy 340.046916 -362.187598) (xy 340.017523 -362.196774) (xy 339.992199 -362.214293) (xy 339.982302 -362.226098)
			(xy 339.964109 -362.24858) (xy 339.92209 -362.288315) (xy 339.874555 -362.321255) (xy 339.822594 -362.346643)
			(xy 339.767397 -362.3639) (xy 339.710228 -362.372629) (xy 339.681312 -362.373164) (xy 339.654097 -362.372702)
			(xy 339.600221 -362.364968) (xy 339.54799 -362.349654) (xy 339.498466 -362.327072) (xy 339.452655 -362.297681)
			(xy 339.411486 -362.262076) (xy 339.393276 -362.241846) (xy 339.383459 -362.231266) (xy 339.359238 -362.215595)
			(xy 339.331598 -362.207332) (xy 339.302751 -362.207139) (xy 339.275003 -362.215032) (xy 339.250575 -362.230378)
			(xy 339.240622 -362.24083) (xy 339.222462 -362.260636) (xy 339.18151 -362.295429) (xy 339.13608 -362.324127)
			(xy 339.08707 -362.346163) (xy 339.035452 -362.3611) (xy 338.982248 -362.368642) (xy 338.95538 -362.3691)
			(xy 338.926465 -362.368524) (xy 338.869297 -362.359807) (xy 338.814099 -362.342561) (xy 338.762137 -362.31718)
			(xy 338.714602 -362.284246) (xy 338.672582 -362.244515) (xy 338.65439 -362.222034) (xy 338.644493 -362.210229)
			(xy 338.619169 -362.19271) (xy 338.589776 -362.183534) (xy 338.558984 -362.183534) (xy 338.529591 -362.19271)
			(xy 338.504267 -362.210229) (xy 338.49437 -362.222034) (xy 338.476205 -362.244539) (xy 338.434178 -362.284271)
			(xy 338.386638 -362.317207) (xy 338.334672 -362.342591) (xy 338.27947 -362.359843) (xy 338.222297 -362.368567)
			(xy 338.19338 -362.3691) (xy 338.167312 -362.36863) (xy 338.115662 -362.361521) (xy 338.06546 -362.347451)
			(xy 338.017638 -362.326681) (xy 337.973087 -362.299599) (xy 337.932635 -362.266708) (xy 337.897034 -362.228618)
			(xy 337.866946 -362.18604) (xy 337.854544 -362.163106) (xy 337.847731 -362.150989) (xy 337.828764 -362.130684)
			(xy 337.805023 -362.116248) (xy 337.778267 -362.108752) (xy 337.750481 -362.108752) (xy 337.723725 -362.116248)
			(xy 337.699984 -362.130684) (xy 337.681017 -362.150989) (xy 337.674204 -362.163106) (xy 337.661804 -362.186044)
			(xy 337.63173 -362.228638) (xy 337.596136 -362.266741) (xy 337.555686 -362.299643) (xy 337.511132 -362.326731)
			(xy 337.463305 -362.347499) (xy 337.413096 -362.361562) (xy 337.361439 -362.368658) (xy 337.335368 -362.3691)
			(xy 337.30799 -362.368598) (xy 337.253798 -362.360767) (xy 337.201281 -362.345269) (xy 337.151519 -362.322425)
			(xy 337.105533 -362.292702) (xy 337.064268 -362.256711) (xy 337.046062 -362.236258) (xy 337.035978 -362.225304)
			(xy 337.010922 -362.209248) (xy 336.982304 -362.201091) (xy 336.952548 -362.201525) (xy 336.924179 -362.210513)
			(xy 336.899603 -362.227293) (xy 336.889852 -362.238544) (xy 336.871595 -362.260307) (xy 336.829807 -362.298779)
			(xy 336.782778 -362.330632) (xy 336.731546 -362.355162) (xy 336.677245 -362.371826) (xy 336.621073 -362.380257)
			(xy 336.592672 -362.380784) (xy 336.563618 -362.380272) (xy 336.50618 -362.371469) (xy 336.450742 -362.354055)
			(xy 336.398587 -362.328433) (xy 336.350922 -362.295197) (xy 336.30885 -362.255115) (xy 336.290666 -362.232448)
			(xy 336.281394 -362.221386) (xy 336.258079 -362.204404) (xy 336.230941 -362.19463) (xy 336.202152 -362.192845)
			(xy 336.174014 -362.199193) (xy 336.14878 -362.213165) (xy 336.138266 -362.22305) (xy 336.116651 -362.244093)
			(xy 336.067986 -362.279738) (xy 336.014317 -362.307277) (xy 335.956981 -362.326024) (xy 335.897409 -362.335512)
			(xy 335.867248 -362.33608) (xy 335.839995 -362.3356) (xy 335.786043 -362.327849) (xy 335.733744 -362.312497)
			(xy 335.684162 -362.289858) (xy 335.638307 -362.260393) (xy 335.597114 -362.224701) (xy 335.561419 -362.183509)
			(xy 335.531951 -362.137655) (xy 335.50931 -362.088075) (xy 335.493955 -362.035776) (xy 335.486201 -361.981825)
			(xy 335.48574 -361.954572) (xy 335.486232 -361.926969) (xy 335.494193 -361.872338) (xy 335.509943 -361.819426)
			(xy 335.533154 -361.769336) (xy 335.563343 -361.723113) (xy 335.581244 -361.702096) (xy 335.590775 -361.690438)
			(xy 335.603212 -361.663031) (xy 335.607139 -361.633191) (xy 335.602218 -361.6035) (xy 335.588874 -361.576523)
			(xy 335.578958 -361.56519) (xy 335.559548 -361.543811) (xy 335.526716 -361.496311) (xy 335.501424 -361.444403)
			(xy 335.484248 -361.389275) (xy 335.475583 -361.332187) (xy 335.475072 -361.303316) (xy 335.475523 -361.275711)
			(xy 335.483492 -361.221079) (xy 335.499252 -361.168165) (xy 335.522473 -361.118076) (xy 335.55267 -361.071856)
			(xy 335.570576 -361.05084) (xy 335.580061 -361.039148) (xy 335.592499 -361.011753) (xy 335.596433 -360.981925)
			(xy 335.591524 -360.952241) (xy 335.578196 -360.925268) (xy 335.56829 -360.913934) (xy 335.548859 -360.892573)
			(xy 335.516029 -360.845069) (xy 335.490739 -360.793157) (xy 335.473569 -360.738024) (xy 335.464911 -360.680933)
			(xy 335.464404 -360.65206) (xy 335.464898 -360.624457) (xy 335.472859 -360.569827) (xy 335.48861 -360.516915)
			(xy 335.511821 -360.466825) (xy 335.542007 -360.420602) (xy 335.559908 -360.399584) (xy 335.569445 -360.387932)
			(xy 335.581872 -360.360522) (xy 335.585794 -360.330682) (xy 335.580873 -360.300991) (xy 335.567534 -360.274013)
			(xy 335.557622 -360.262678) (xy 335.5382 -360.241309) (xy 335.505372 -360.193806) (xy 335.480082 -360.141896)
			(xy 335.462909 -360.086765) (xy 335.454246 -360.029676) (xy 335.453736 -360.000804) (xy 335.454244 -359.971887)
			(xy 335.462973 -359.914714) (xy 335.480232 -359.859515) (xy 335.505626 -359.807553) (xy 335.538572 -359.760019)
			(xy 335.578315 -359.718003) (xy 335.600802 -359.699814) (xy 335.612602 -359.689911) (xy 335.630117 -359.664589)
			(xy 335.639292 -359.635197) (xy 335.639292 -359.604407) (xy 335.630119 -359.575016) (xy 335.612605 -359.549692)
			(xy 335.600802 -359.539794) (xy 335.580021 -359.523037) (xy 335.542887 -359.484686) (xy 335.511462 -359.441533)
			(xy 335.48636 -359.39442) (xy 335.468071 -359.344267) (xy 335.456953 -359.292055) (xy 335.453223 -359.238802)
			(xy 283.744416 -359.238802) (xy 283.744416 -362.079794) (xy 283.759478 -362.103373) (xy 283.783313 -362.15399)
			(xy 283.799495 -362.207547) (xy 283.807676 -362.262894) (xy 283.80817 -362.290868) (xy 283.807715 -362.318122)
			(xy 283.799961 -362.372075) (xy 283.784607 -362.424375) (xy 283.761966 -362.473958) (xy 283.732498 -362.519813)
			(xy 283.696803 -362.561007) (xy 283.655608 -362.596701) (xy 283.609753 -362.626169) (xy 283.56017 -362.648809)
			(xy 283.507869 -362.664162) (xy 283.453916 -362.671915) (xy 283.426662 -362.672376) (xy 283.401941 -362.671996)
			(xy 283.352912 -362.665618) (xy 283.305118 -362.652961) (xy 283.259358 -362.634237) (xy 283.237686 -362.622338)
			(xy 283.224208 -362.615361) (xy 283.194591 -362.608814) (xy 283.164357 -362.611255) (xy 283.136174 -362.622467)
			(xy 283.112527 -362.641464) (xy 283.095503 -362.666567) (xy 283.086602 -362.695564) (xy 283.086048 -362.71073)
			(xy 283.086048 -363.385862) (xy 283.875988 -364.175802) (xy 283.900843 -364.201368) (xy 283.933301 -364.242096)
			(xy 284.829758 -364.242096) (xy 284.830254 -364.214056) (xy 284.838455 -364.158578) (xy 284.854681 -364.104896)
			(xy 284.878582 -364.054164) (xy 284.909644 -364.007472) (xy 284.928056 -363.986318) (xy 284.937658 -363.974842)
			(xy 284.950447 -363.947812) (xy 284.954843 -363.918234) (xy 284.950467 -363.888653) (xy 284.937697 -363.861615)
			(xy 284.928056 -363.850174) (xy 284.909643 -363.829017) (xy 284.878549 -363.782341) (xy 284.854632 -363.731612)
			(xy 284.83841 -363.677924) (xy 284.830233 -363.622439) (xy 284.829758 -363.594396) (xy 284.830244 -363.567145)
			(xy 284.838 -363.513197) (xy 284.853355 -363.460902) (xy 284.875997 -363.411325) (xy 284.905463 -363.365475)
			(xy 284.941154 -363.324284) (xy 284.982345 -363.288593) (xy 285.028195 -363.259127) (xy 285.077772 -363.236485)
			(xy 285.130067 -363.22113) (xy 285.184015 -363.213374) (xy 285.238517 -363.213374) (xy 285.292465 -363.22113)
			(xy 285.34476 -363.236485) (xy 285.394337 -363.259127) (xy 285.440187 -363.288593) (xy 285.481378 -363.324284)
			(xy 285.517069 -363.365475) (xy 285.546535 -363.411325) (xy 285.569177 -363.460902) (xy 285.584532 -363.513197)
			(xy 285.592288 -363.567145) (xy 285.592774 -363.594396) (xy 285.592291 -363.622437) (xy 285.584089 -363.677916)
			(xy 285.567862 -363.731598) (xy 285.543957 -363.78233) (xy 285.51289 -363.829021) (xy 285.494476 -363.850174)
			(xy 285.489947 -363.855508) (xy 292.807134 -363.855508) (xy 292.811205 -363.799886) (xy 292.823331 -363.745449)
			(xy 292.843254 -363.693358) (xy 292.87055 -363.644723) (xy 292.904636 -363.60058) (xy 292.944785 -363.561871)
			(xy 292.990143 -363.52942) (xy 293.039743 -363.503919) (xy 293.092527 -363.485912) (xy 293.14737 -363.475782)
			(xy 293.203104 -363.473745) (xy 293.258541 -363.479845) (xy 293.312498 -363.493951) (xy 293.363827 -363.515763)
			(xy 293.411433 -363.544817) (xy 293.454301 -363.580492) (xy 293.491518 -363.622029) (xy 293.522291 -363.668542)
			(xy 293.545963 -363.719039) (xy 293.562031 -363.772446) (xy 293.570151 -363.827622) (xy 293.57066 -363.855508)
			(xy 293.570151 -363.883394) (xy 293.562031 -363.93857) (xy 293.545963 -363.991977) (xy 293.522291 -364.042474)
			(xy 293.491518 -364.088987) (xy 293.454301 -364.130524) (xy 293.411433 -364.166199) (xy 293.363827 -364.195253)
			(xy 293.312498 -364.217065) (xy 293.258541 -364.231171) (xy 293.216963 -364.235746) (xy 294.51808 -364.235746)
			(xy 294.518554 -364.208376) (xy 294.526367 -364.154196) (xy 294.541853 -364.101692) (xy 294.564693 -364.051945)
			(xy 294.594418 -364.005979) (xy 294.61206 -363.985048) (xy 294.621255 -363.973689) (xy 294.633443 -363.947143)
			(xy 294.637626 -363.918235) (xy 294.633463 -363.889324) (xy 294.621293 -363.86277) (xy 294.61206 -363.851444)
			(xy 294.594421 -363.830512) (xy 294.564711 -363.784538) (xy 294.541875 -363.734791) (xy 294.526384 -363.68229)
			(xy 294.518554 -363.628115) (xy 294.51808 -363.600746) (xy 294.518566 -363.573495) (xy 294.526322 -363.519547)
			(xy 294.541677 -363.467252) (xy 294.564319 -363.417675) (xy 294.593785 -363.371825) (xy 294.629476 -363.330634)
			(xy 294.670667 -363.294943) (xy 294.716517 -363.265477) (xy 294.766094 -363.242835) (xy 294.818389 -363.22748)
			(xy 294.872337 -363.219724) (xy 294.926839 -363.219724) (xy 294.980787 -363.22748) (xy 295.033082 -363.242835)
			(xy 295.082659 -363.265477) (xy 295.128509 -363.294943) (xy 295.1697 -363.330634) (xy 295.205391 -363.371825)
			(xy 295.234857 -363.417675) (xy 295.257499 -363.467252) (xy 295.272854 -363.519547) (xy 295.28061 -363.573495)
			(xy 295.281096 -363.600746) (xy 295.280599 -363.628115) (xy 295.272789 -363.682293) (xy 295.257307 -363.734796)
			(xy 295.234472 -363.784543) (xy 295.204754 -363.830511) (xy 295.187116 -363.851444) (xy 295.180853 -363.859064)
			(xy 302.365154 -363.859064) (xy 302.369225 -363.803442) (xy 302.381351 -363.749005) (xy 302.401274 -363.696914)
			(xy 302.42857 -363.648279) (xy 302.462656 -363.604136) (xy 302.502805 -363.565427) (xy 302.548163 -363.532976)
			(xy 302.597763 -363.507475) (xy 302.650547 -363.489468) (xy 302.70539 -363.479338) (xy 302.761124 -363.477301)
			(xy 302.816561 -363.483401) (xy 302.870518 -363.497507) (xy 302.921847 -363.519319) (xy 302.969453 -363.548373)
			(xy 303.012321 -363.584048) (xy 303.049538 -363.625585) (xy 303.080311 -363.672098) (xy 303.103983 -363.722595)
			(xy 303.120051 -363.776002) (xy 303.128171 -363.831178) (xy 303.12868 -363.859064) (xy 303.128171 -363.88695)
			(xy 303.120051 -363.942126) (xy 303.103983 -363.995533) (xy 303.080311 -364.04603) (xy 303.049538 -364.092543)
			(xy 303.012321 -364.13408) (xy 302.969453 -364.169755) (xy 302.921847 -364.198809) (xy 302.870518 -364.220621)
			(xy 302.816561 -364.234727) (xy 302.761124 -364.240827) (xy 302.70539 -364.23879) (xy 302.650547 -364.22866)
			(xy 302.597763 -364.210653) (xy 302.548163 -364.185152) (xy 302.502805 -364.152701) (xy 302.462656 -364.113992)
			(xy 302.42857 -364.069849) (xy 302.401274 -364.021214) (xy 302.381351 -363.969123) (xy 302.369225 -363.914686)
			(xy 302.365154 -363.859064) (xy 295.180853 -363.859064) (xy 295.177834 -363.862738) (xy 295.16566 -363.889307)
			(xy 295.161495 -363.918235) (xy 295.165679 -363.94716) (xy 295.177871 -363.973721) (xy 295.187116 -363.985048)
			(xy 295.204747 -364.005987) (xy 295.234459 -364.051958) (xy 295.257297 -364.101704) (xy 295.27279 -364.154203)
			(xy 295.28062 -364.208377) (xy 295.281096 -364.235746) (xy 295.28061 -364.262997) (xy 295.272854 -364.316945)
			(xy 295.257499 -364.36924) (xy 295.234857 -364.418817) (xy 295.205391 -364.464667) (xy 295.1697 -364.505858)
			(xy 295.128509 -364.541549) (xy 295.082659 -364.571015) (xy 295.033082 -364.593657) (xy 294.980787 -364.609012)
			(xy 294.926839 -364.616768) (xy 294.872337 -364.616768) (xy 294.818389 -364.609012) (xy 294.766094 -364.593657)
			(xy 294.716517 -364.571015) (xy 294.670667 -364.541549) (xy 294.629476 -364.505858) (xy 294.593785 -364.464667)
			(xy 294.564319 -364.418817) (xy 294.541677 -364.36924) (xy 294.526322 -364.316945) (xy 294.518566 -364.262997)
			(xy 294.51808 -364.235746) (xy 293.216963 -364.235746) (xy 293.203104 -364.237271) (xy 293.14737 -364.235234)
			(xy 293.092527 -364.225104) (xy 293.039743 -364.207097) (xy 292.990143 -364.181596) (xy 292.944785 -364.149145)
			(xy 292.904636 -364.110436) (xy 292.87055 -364.066293) (xy 292.843254 -364.017658) (xy 292.823331 -363.965567)
			(xy 292.811205 -363.91113) (xy 292.807134 -363.855508) (xy 285.489947 -363.855508) (xy 285.484789 -363.861583)
			(xy 285.47202 -363.888638) (xy 285.467644 -363.918234) (xy 285.47204 -363.947827) (xy 285.484827 -363.974874)
			(xy 285.494476 -363.986318) (xy 285.512891 -364.007473) (xy 285.543984 -364.05415) (xy 285.567899 -364.10488)
			(xy 285.584121 -364.158568) (xy 285.592299 -364.214053) (xy 285.592774 -364.242096) (xy 285.592288 -364.269347)
			(xy 285.584532 -364.323295) (xy 285.569177 -364.37559) (xy 285.546535 -364.425167) (xy 285.517069 -364.471017)
			(xy 285.481378 -364.512208) (xy 285.440187 -364.547899) (xy 285.394337 -364.577365) (xy 285.34476 -364.600007)
			(xy 285.292465 -364.615362) (xy 285.238517 -364.623118) (xy 285.184015 -364.623118) (xy 285.130067 -364.615362)
			(xy 285.077772 -364.600007) (xy 285.028195 -364.577365) (xy 284.982345 -364.547899) (xy 284.941154 -364.512208)
			(xy 284.905463 -364.471017) (xy 284.875997 -364.425167) (xy 284.853355 -364.37559) (xy 284.838 -364.323295)
			(xy 284.830244 -364.269347) (xy 284.829758 -364.242096) (xy 283.933301 -364.242096) (xy 283.945284 -364.257132)
			(xy 283.983201 -364.317521) (xy 284.014118 -364.381777) (xy 284.037646 -364.44909) (xy 284.053489 -364.518614)
			(xy 284.061447 -364.589475) (xy 284.061916 -364.625128) (xy 284.061738 -364.6383) (xy 289.07837 -364.6383)
			(xy 289.082538 -364.582684) (xy 289.094949 -364.52831) (xy 289.115327 -364.476394) (xy 289.143215 -364.428095)
			(xy 289.17799 -364.384492) (xy 289.218876 -364.34656) (xy 289.264959 -364.315146) (xy 289.31521 -364.290951)
			(xy 289.368506 -364.274517) (xy 289.423656 -364.26621) (xy 289.451542 -364.265718) (xy 289.478873 -364.26621)
			(xy 289.532952 -364.274177) (xy 289.585285 -364.289962) (xy 289.634749 -364.313227) (xy 289.680282 -364.343471)
			(xy 289.720905 -364.380046) (xy 289.755745 -364.422165) (xy 289.770312 -364.445296) (xy 289.778247 -364.457512)
			(xy 289.799715 -364.477184) (xy 289.825865 -364.48999) (xy 289.854568 -364.494887) (xy 289.883485 -364.491477)
			(xy 289.897058 -364.48619) (xy 289.920264 -364.47669) (xy 289.968599 -364.463343) (xy 290.01829 -364.456619)
			(xy 290.043362 -364.456218) (xy 290.068432 -364.456634) (xy 290.118115 -364.463387) (xy 290.166449 -364.476723)
			(xy 290.189666 -364.48619) (xy 290.203241 -364.491445) (xy 290.232143 -364.494811) (xy 290.260823 -364.4899)
			(xy 290.286959 -364.477108) (xy 290.308433 -364.457473) (xy 290.316412 -364.445296) (xy 290.330981 -364.422165)
			(xy 290.365824 -364.380044) (xy 290.406447 -364.343465) (xy 290.451978 -364.313214) (xy 290.50144 -364.289938)
			(xy 290.553771 -364.274138) (xy 290.60785 -364.266152) (xy 290.662514 -364.266152) (xy 290.716593 -364.274138)
			(xy 290.768924 -364.289938) (xy 290.818386 -364.313214) (xy 290.863917 -364.343465) (xy 290.90454 -364.380044)
			(xy 290.939383 -364.422165) (xy 290.953952 -364.445296) (xy 290.961849 -364.457539) (xy 290.983327 -364.477211)
			(xy 291.009488 -364.490013) (xy 291.038199 -364.494904) (xy 291.067123 -364.491483) (xy 291.080698 -364.48619)
			(xy 291.103911 -364.476708) (xy 291.152242 -364.463354) (xy 291.201931 -364.456623) (xy 291.227002 -364.456218)
			(xy 291.254319 -364.456686) (xy 291.308365 -364.464677) (xy 291.360665 -364.480472) (xy 291.410099 -364.503733)
			(xy 291.455607 -364.533963) (xy 291.496215 -364.570512) (xy 291.531052 -364.612598) (xy 291.559371 -364.659318)
			(xy 291.57041 -364.68431) (xy 291.575959 -364.69653) (xy 291.592461 -364.717688) (xy 291.613901 -364.733822)
			(xy 291.638801 -364.74382) (xy 291.665445 -364.746992) (xy 291.691997 -364.743119) (xy 291.716625 -364.73247)
			(xy 291.727382 -364.724442) (xy 291.747719 -364.708764) (xy 291.791824 -364.682466) (xy 291.839056 -364.662316)
			(xy 291.888563 -364.648679) (xy 291.939451 -364.641799) (xy 291.965126 -364.641384) (xy 291.983145 -364.641606)
			(xy 292.01902 -364.645039) (xy 292.036754 -364.648242) (xy 292.051967 -364.650546) (xy 292.082518 -364.64703)
			(xy 292.110636 -364.634578) (xy 292.133772 -364.614319) (xy 292.149827 -364.588091) (xy 292.154102 -364.573312)
			(xy 292.161484 -364.546264) (xy 292.183118 -364.494539) (xy 292.212086 -364.446535) (xy 292.247764 -364.403285)
			(xy 292.289385 -364.365719) (xy 292.336054 -364.334645) (xy 292.386766 -364.310733) (xy 292.44043 -364.294496)
			(xy 292.495893 -364.286284) (xy 292.523926 -364.285784) (xy 292.551178 -364.286254) (xy 292.605125 -364.294013)
			(xy 292.65742 -364.309371) (xy 292.706997 -364.332015) (xy 292.752847 -364.361483) (xy 292.794036 -364.397176)
			(xy 292.829728 -364.438368) (xy 292.859194 -364.484219) (xy 292.881835 -364.533797) (xy 292.89719 -364.586092)
			(xy 292.904698 -364.6383) (xy 298.766795 -364.6383) (xy 298.770962 -364.582695) (xy 298.783369 -364.528332)
			(xy 298.80374 -364.476425) (xy 298.831619 -364.428134) (xy 298.866383 -364.384537) (xy 298.907257 -364.346608)
			(xy 298.953327 -364.315194) (xy 299.003564 -364.290997) (xy 299.056846 -364.274557) (xy 299.111984 -364.266241)
			(xy 299.139864 -364.265718) (xy 299.167196 -364.266193) (xy 299.221275 -364.274163) (xy 299.273609 -364.289951)
			(xy 299.323073 -364.313218) (xy 299.368605 -364.343465) (xy 299.409228 -364.380043) (xy 299.444068 -364.422164)
			(xy 299.458634 -364.445296) (xy 299.466548 -364.457527) (xy 299.488021 -364.477199) (xy 299.514177 -364.490003)
			(xy 299.542885 -364.494896) (xy 299.571806 -364.49148) (xy 299.58538 -364.48619) (xy 299.608595 -364.476714)
			(xy 299.656925 -364.463358) (xy 299.706613 -364.456624) (xy 299.731684 -364.456218) (xy 299.756753 -364.45666)
			(xy 299.806435 -364.463402) (xy 299.85477 -364.476727) (xy 299.877988 -364.48619) (xy 299.891578 -364.491412)
			(xy 299.92048 -364.494797) (xy 299.949165 -364.489902) (xy 299.975309 -364.477123) (xy 299.996793 -364.457496)
			(xy 300.004734 -364.445296) (xy 300.019303 -364.422165) (xy 300.054146 -364.380044) (xy 300.094769 -364.343465)
			(xy 300.1403 -364.313214) (xy 300.189762 -364.289938) (xy 300.242093 -364.274138) (xy 300.296172 -364.266152)
			(xy 300.350836 -364.266152) (xy 300.404915 -364.274138) (xy 300.457246 -364.289938) (xy 300.506708 -364.313214)
			(xy 300.552239 -364.343465) (xy 300.592862 -364.380044) (xy 300.627705 -364.422165) (xy 300.642274 -364.445296)
			(xy 300.650245 -364.457486) (xy 300.671703 -364.477157) (xy 300.697843 -364.489967) (xy 300.726538 -364.494871)
			(xy 300.755449 -364.491471) (xy 300.76902 -364.48619) (xy 300.79223 -364.476701) (xy 300.840563 -364.46335)
			(xy 300.890252 -364.456622) (xy 300.915324 -364.456218) (xy 300.942169 -364.456634) (xy 300.995301 -364.464342)
			(xy 301.046778 -364.479596) (xy 301.095533 -364.50208) (xy 301.140556 -364.531328) (xy 301.180915 -364.566735)
			(xy 301.215776 -364.607567) (xy 301.244415 -364.65298) (xy 301.266241 -364.702032) (xy 301.273972 -364.727744)
			(xy 301.27869 -364.742221) (xy 301.295197 -364.767781) (xy 301.318501 -364.787346) (xy 301.346533 -364.799179)
			(xy 301.376807 -364.80223) (xy 301.406637 -364.796229) (xy 301.420276 -364.789466) (xy 301.448418 -364.774824)
			(xy 301.508371 -364.7541) (xy 301.570931 -364.743605) (xy 301.602648 -364.742984) (xy 301.620667 -364.743202)
			(xy 301.656542 -364.746638) (xy 301.674276 -364.749842) (xy 301.689487 -364.752168) (xy 301.720039 -364.748646)
			(xy 301.748159 -364.736189) (xy 301.771295 -364.715925) (xy 301.787349 -364.689693) (xy 301.791624 -364.674912)
			(xy 301.798986 -364.647858) (xy 301.820622 -364.596131) (xy 301.849592 -364.548127) (xy 301.885273 -364.504876)
			(xy 301.926896 -364.46731) (xy 301.973568 -364.436238) (xy 302.024282 -364.412327) (xy 302.077949 -364.396092)
			(xy 302.133414 -364.387882) (xy 302.161448 -364.387384) (xy 302.1887 -364.387833) (xy 302.242649 -364.395596)
			(xy 302.294944 -364.410957) (xy 302.34452 -364.433603) (xy 302.39037 -364.463073) (xy 302.43156 -364.498769)
			(xy 302.467251 -364.539962) (xy 302.496716 -364.585815) (xy 302.519357 -364.635394) (xy 302.534713 -364.68769)
			(xy 302.54247 -364.74164) (xy 302.542956 -364.768892) (xy 302.5425 -364.796467) (xy 302.534548 -364.851041)
			(xy 302.518822 -364.903902) (xy 302.49565 -364.953948) (xy 302.465515 -365.000137) (xy 302.429045 -365.041507)
			(xy 302.408336 -365.059722) (xy 302.397444 -365.069627) (xy 302.381366 -365.094274) (xy 302.372978 -365.122481)
			(xy 302.372977 -365.151909) (xy 302.381361 -365.180116) (xy 302.397437 -365.204765) (xy 302.408336 -365.214662)
			(xy 302.429032 -365.232888) (xy 302.465492 -365.274259) (xy 302.495616 -365.320449) (xy 302.518776 -365.370494)
			(xy 302.53449 -365.423352) (xy 302.54243 -365.477922) (xy 302.542431 -365.533067) (xy 302.534492 -365.587637)
			(xy 302.51878 -365.640496) (xy 302.495621 -365.690542) (xy 302.465498 -365.736733) (xy 302.429039 -365.778105)
			(xy 302.408336 -365.796322) (xy 302.397444 -365.806227) (xy 302.381366 -365.830874) (xy 302.372978 -365.859081)
			(xy 302.372977 -365.888509) (xy 302.381361 -365.916716) (xy 302.397437 -365.941365) (xy 302.408336 -365.951262)
			(xy 302.429039 -365.969482) (xy 302.465509 -366.010849) (xy 302.495641 -366.057038) (xy 302.518808 -366.107084)
			(xy 302.534526 -366.159945) (xy 302.542469 -366.214518) (xy 302.542956 -366.242092) (xy 302.542415 -366.269341)
			(xy 302.534661 -366.323284) (xy 302.519309 -366.375575) (xy 302.496672 -366.425149) (xy 302.467211 -366.470997)
			(xy 302.431526 -366.512186) (xy 302.390342 -366.547878) (xy 302.344498 -366.577345) (xy 302.294927 -366.599989)
			(xy 302.242639 -366.615349) (xy 302.188697 -366.623111) (xy 302.161448 -366.6236) (xy 302.133594 -366.623034)
			(xy 302.07848 -366.614917) (xy 302.025131 -366.598878) (xy 301.974679 -366.575257) (xy 301.928194 -366.544555)
			(xy 301.886664 -366.507425) (xy 301.85097 -366.464655) (xy 301.82187 -366.417151) (xy 301.799981 -366.365923)
			(xy 301.792386 -366.33912) (xy 301.788085 -366.325013) (xy 301.772701 -366.29987) (xy 301.75079 -366.280153)
			(xy 301.724168 -366.2675) (xy 301.695043 -366.262958) (xy 301.680372 -366.264444) (xy 301.667356 -366.266114)
			(xy 301.641171 -366.267893) (xy 301.628048 -366.268) (xy 301.613899 -366.267901) (xy 301.585676 -366.26587)
			(xy 301.57166 -366.263936) (xy 301.558312 -366.262339) (xy 301.531617 -366.265436) (xy 301.506661 -366.275405)
			(xy 301.485179 -366.291553) (xy 301.468668 -366.312756) (xy 301.458275 -366.337539) (xy 301.45609 -366.350804)
			(xy 301.451996 -366.377957) (xy 301.437027 -366.430789) (xy 301.414638 -366.480929) (xy 301.385293 -366.527342)
			(xy 301.349596 -366.569067) (xy 301.308286 -366.605245) (xy 301.262217 -366.635126) (xy 301.21234 -366.658094)
			(xy 301.159685 -366.673674) (xy 301.10534 -366.681544) (xy 301.077884 -366.68202) (xy 301.050633 -366.681537)
			(xy 300.996686 -366.673779) (xy 300.944392 -366.658422) (xy 300.894815 -366.63578) (xy 300.848965 -366.606313)
			(xy 300.807776 -366.570622) (xy 300.772084 -366.529431) (xy 300.742618 -366.483581) (xy 300.719976 -366.434005)
			(xy 300.70462 -366.38171) (xy 300.696863 -366.327763) (xy 300.696376 -366.300512) (xy 300.696858 -366.272938)
			(xy 300.704809 -366.218366) (xy 300.720531 -366.165507) (xy 300.743698 -366.115461) (xy 300.773827 -366.069271)
			(xy 300.810291 -366.027899) (xy 300.830996 -366.009682) (xy 300.841881 -365.999771) (xy 300.857954 -365.975124)
			(xy 300.866339 -365.94692) (xy 300.866342 -365.917495) (xy 300.857961 -365.88929) (xy 300.841891 -365.864641)
			(xy 300.830996 -365.854742) (xy 300.810301 -365.836513) (xy 300.77383 -365.795148) (xy 300.743696 -365.748962)
			(xy 300.720527 -365.698917) (xy 300.704807 -365.646058) (xy 300.696864 -365.591486) (xy 300.696376 -365.563912)
			(xy 300.69686 -365.537412) (xy 300.704199 -365.484922) (xy 300.718737 -365.433955) (xy 300.740193 -365.385492)
			(xy 300.768154 -365.340468) (xy 300.784768 -365.319818) (xy 300.79424 -365.307695) (xy 300.806022 -365.279286)
			(xy 300.808838 -365.248661) (xy 300.802436 -365.218581) (xy 300.787392 -365.191757) (xy 300.765062 -365.170609)
			(xy 300.751494 -365.163354) (xy 300.727822 -365.15122) (xy 300.683837 -365.121307) (xy 300.644551 -365.085446)
			(xy 300.610762 -365.044364) (xy 300.596554 -365.021876) (xy 300.588658 -365.009633) (xy 300.567178 -364.989964)
			(xy 300.541017 -364.977164) (xy 300.512307 -364.972273) (xy 300.483383 -364.975691) (xy 300.469808 -364.980982)
			(xy 300.446594 -364.99046) (xy 300.398263 -365.003816) (xy 300.348575 -365.010548) (xy 300.323504 -365.010954)
			(xy 300.298435 -365.010518) (xy 300.248752 -365.003774) (xy 300.200418 -364.990446) (xy 300.1772 -364.980982)
			(xy 300.163598 -364.975809) (xy 300.13471 -364.972429) (xy 300.106041 -364.977324) (xy 300.079911 -364.990095)
			(xy 300.058436 -365.009709) (xy 300.050454 -365.021876) (xy 300.035885 -365.045007) (xy 300.001042 -365.087128)
			(xy 299.960419 -365.123707) (xy 299.914888 -365.153958) (xy 299.865426 -365.177234) (xy 299.813095 -365.193034)
			(xy 299.759016 -365.20102) (xy 299.704352 -365.20102) (xy 299.650273 -365.193034) (xy 299.597942 -365.177234)
			(xy 299.54848 -365.153958) (xy 299.502949 -365.123707) (xy 299.462326 -365.087128) (xy 299.427483 -365.045007)
			(xy 299.412914 -365.021876) (xy 299.404961 -365.009674) (xy 299.383497 -364.990005) (xy 299.357351 -364.977199)
			(xy 299.328654 -364.972298) (xy 299.299741 -364.9757) (xy 299.286168 -364.980982) (xy 299.262959 -364.990473)
			(xy 299.214626 -365.003824) (xy 299.164936 -365.010551) (xy 299.139864 -365.010954) (xy 299.111984 -365.010359)
			(xy 299.056846 -365.002043) (xy 299.003564 -364.985603) (xy 298.953327 -364.961406) (xy 298.907257 -364.929992)
			(xy 298.866383 -364.892063) (xy 298.831619 -364.848466) (xy 298.80374 -364.800175) (xy 298.783369 -364.748268)
			(xy 298.770962 -364.693905) (xy 298.766795 -364.6383) (xy 292.904698 -364.6383) (xy 292.904948 -364.64004)
			(xy 292.905434 -364.667292) (xy 292.904986 -364.694867) (xy 292.897033 -364.749442) (xy 292.881306 -364.802303)
			(xy 292.858133 -364.85235) (xy 292.827996 -364.898539) (xy 292.791524 -364.939908) (xy 292.770814 -364.958122)
			(xy 292.759924 -364.968028) (xy 292.743849 -364.992676) (xy 292.735464 -365.020882) (xy 292.735462 -365.050308)
			(xy 292.743845 -365.078515) (xy 292.759917 -365.103164) (xy 292.770814 -365.113062) (xy 292.791511 -365.131287)
			(xy 292.827973 -365.172658) (xy 292.858099 -365.218847) (xy 292.88126 -365.268892) (xy 292.896975 -365.321751)
			(xy 292.904916 -365.376322) (xy 292.904916 -365.431468) (xy 292.896977 -365.486038) (xy 292.881264 -365.538898)
			(xy 292.858104 -365.588944) (xy 292.827979 -365.635134) (xy 292.791518 -365.676506) (xy 292.770814 -365.694722)
			(xy 292.760482 -365.70412) (xy 295.309034 -365.70412) (xy 295.313105 -365.648498) (xy 295.325231 -365.594061)
			(xy 295.345154 -365.54197) (xy 295.37245 -365.493335) (xy 295.406536 -365.449192) (xy 295.446685 -365.410483)
			(xy 295.492043 -365.378032) (xy 295.541643 -365.352531) (xy 295.594427 -365.334524) (xy 295.64927 -365.324394)
			(xy 295.705004 -365.322357) (xy 295.760441 -365.328457) (xy 295.814398 -365.342563) (xy 295.865727 -365.364375)
			(xy 295.913333 -365.393429) (xy 295.956201 -365.429104) (xy 295.993418 -365.470641) (xy 296.024191 -365.517154)
			(xy 296.047863 -365.567651) (xy 296.063931 -365.621058) (xy 296.072051 -365.676234) (xy 296.07256 -365.70412)
			(xy 296.072051 -365.732006) (xy 296.063931 -365.787182) (xy 296.047863 -365.840589) (xy 296.024191 -365.891086)
			(xy 295.993418 -365.937599) (xy 295.956201 -365.979136) (xy 295.913333 -366.014811) (xy 295.865727 -366.043865)
			(xy 295.814398 -366.065677) (xy 295.760441 -366.079783) (xy 295.705004 -366.085883) (xy 295.64927 -366.083846)
			(xy 295.594427 -366.073716) (xy 295.541643 -366.055709) (xy 295.492043 -366.030208) (xy 295.446685 -365.997757)
			(xy 295.406536 -365.959048) (xy 295.37245 -365.914905) (xy 295.345154 -365.86627) (xy 295.325231 -365.814179)
			(xy 295.313105 -365.759742) (xy 295.309034 -365.70412) (xy 292.760482 -365.70412) (xy 292.759924 -365.704628)
			(xy 292.743849 -365.729276) (xy 292.735464 -365.757482) (xy 292.735462 -365.786908) (xy 292.743845 -365.815115)
			(xy 292.759917 -365.839764) (xy 292.770814 -365.849662) (xy 292.791513 -365.867886) (xy 292.827983 -365.909253)
			(xy 292.858117 -365.95544) (xy 292.881285 -366.005485) (xy 292.897004 -366.058345) (xy 292.904947 -366.112918)
			(xy 292.905434 -366.140492) (xy 292.904915 -366.167742) (xy 292.89716 -366.221687) (xy 292.881807 -366.27398)
			(xy 292.859169 -366.323555) (xy 292.829706 -366.369404) (xy 292.794018 -366.410594) (xy 292.752832 -366.446286)
			(xy 292.706985 -366.475753) (xy 292.657412 -366.498395) (xy 292.60512 -366.513753) (xy 292.551176 -366.521512)
			(xy 292.523926 -366.522) (xy 292.496072 -366.521453) (xy 292.440957 -366.513334) (xy 292.387607 -366.497291)
			(xy 292.337155 -366.473668) (xy 292.29067 -366.442964) (xy 292.24914 -366.405831) (xy 292.213447 -366.363059)
			(xy 292.184347 -366.315553) (xy 292.162459 -366.264324) (xy 292.154864 -366.23752) (xy 292.150585 -366.223406)
			(xy 292.135197 -366.19826) (xy 292.11328 -366.178543) (xy 292.086652 -366.165892) (xy 292.057523 -366.161355)
			(xy 292.04285 -366.162844) (xy 292.029834 -366.164516) (xy 292.003649 -366.166294) (xy 291.990526 -366.1664)
			(xy 291.966978 -366.166093) (xy 291.920234 -366.160356) (xy 291.897308 -366.15497) (xy 291.884306 -366.152198)
			(xy 291.857736 -366.152613) (xy 291.832177 -366.159878) (xy 291.809361 -366.1735) (xy 291.79084 -366.192554)
			(xy 291.77787 -366.215746) (xy 291.771332 -366.241501) (xy 291.77107 -366.254792) (xy 291.77107 -366.259872)
			(xy 291.770584 -366.287123) (xy 291.762828 -366.341071) (xy 291.747473 -366.393366) (xy 291.724831 -366.442943)
			(xy 291.695365 -366.488793) (xy 291.659674 -366.529984) (xy 291.618483 -366.565675) (xy 291.572633 -366.595141)
			(xy 291.523056 -366.617783) (xy 291.470761 -366.633138) (xy 291.416813 -366.640894) (xy 291.362311 -366.640894)
			(xy 291.308363 -366.633138) (xy 291.256068 -366.617783) (xy 291.206491 -366.595141) (xy 291.160641 -366.565675)
			(xy 291.11945 -366.529984) (xy 291.083759 -366.488793) (xy 291.054293 -366.442943) (xy 291.031651 -366.393366)
			(xy 291.016296 -366.341071) (xy 291.00854 -366.287123) (xy 291.008054 -366.259872) (xy 291.00855 -366.232298)
			(xy 291.016494 -366.177726) (xy 291.032212 -366.124866) (xy 291.055376 -366.074819) (xy 291.085504 -366.028629)
			(xy 291.121968 -365.987258) (xy 291.142674 -365.969042) (xy 291.153601 -365.959173) (xy 291.169676 -365.934515)
			(xy 291.178059 -365.906299) (xy 291.178054 -365.876865) (xy 291.169661 -365.848652) (xy 291.153577 -365.824)
			(xy 291.142674 -365.814102) (xy 291.121955 -365.795899) (xy 291.085487 -365.754528) (xy 291.055356 -365.708336)
			(xy 291.032192 -365.658287) (xy 291.016477 -365.605423) (xy 291.008539 -365.550847) (xy 291.008054 -365.523272)
			(xy 291.008619 -365.493749) (xy 291.017752 -365.435413) (xy 291.035766 -365.379181) (xy 291.062229 -365.326397)
			(xy 291.07892 -365.302038) (xy 291.08686 -365.290159) (xy 291.096379 -365.263229) (xy 291.098067 -365.234716)
			(xy 291.09179 -365.206852) (xy 291.078041 -365.181816) (xy 291.057895 -365.161568) (xy 291.045646 -365.15421)
			(xy 291.024749 -365.14215) (xy 290.985971 -365.113443) (xy 290.951219 -365.079973) (xy 290.921074 -365.042301)
			(xy 290.908232 -365.021876) (xy 290.900357 -365.009618) (xy 290.878871 -364.989949) (xy 290.852705 -364.977151)
			(xy 290.823989 -364.972264) (xy 290.795062 -364.975688) (xy 290.781486 -364.980982) (xy 290.758274 -364.990467)
			(xy 290.709942 -365.00382) (xy 290.660253 -365.01055) (xy 290.635182 -365.010954) (xy 290.610113 -365.010525)
			(xy 290.56043 -365.003778) (xy 290.512095 -364.990447) (xy 290.488878 -364.980982) (xy 290.475284 -364.975785)
			(xy 290.446392 -364.972411) (xy 290.41772 -364.977311) (xy 290.391589 -364.990088) (xy 290.370114 -365.009707)
			(xy 290.362132 -365.021876) (xy 290.347563 -365.045007) (xy 290.31272 -365.087128) (xy 290.272097 -365.123707)
			(xy 290.226566 -365.153958) (xy 290.177104 -365.177234) (xy 290.124773 -365.193034) (xy 290.070694 -365.20102)
			(xy 290.01603 -365.20102) (xy 289.961951 -365.193034) (xy 289.90962 -365.177234) (xy 289.860158 -365.153958)
			(xy 289.814627 -365.123707) (xy 289.774004 -365.087128) (xy 289.739161 -365.045007) (xy 289.724592 -365.021876)
			(xy 289.71666 -365.009659) (xy 289.69519 -364.98999) (xy 289.669039 -364.977186) (xy 289.640337 -364.972289)
			(xy 289.61142 -364.975697) (xy 289.597846 -364.980982) (xy 289.574639 -364.99048) (xy 289.526305 -365.003828)
			(xy 289.476614 -365.010553) (xy 289.451542 -365.010954) (xy 289.423656 -365.01039) (xy 289.368506 -365.002083)
			(xy 289.31521 -364.985649) (xy 289.264959 -364.961454) (xy 289.218876 -364.93004) (xy 289.17799 -364.892108)
			(xy 289.143215 -364.848505) (xy 289.115327 -364.800206) (xy 289.094949 -364.74829) (xy 289.082538 -364.693916)
			(xy 289.07837 -364.6383) (xy 284.061738 -364.6383) (xy 284.061435 -364.66078) (xy 284.053451 -364.731637)
			(xy 284.037585 -364.801155) (xy 284.014038 -364.86846) (xy 283.983106 -364.932706) (xy 283.945176 -364.993086)
			(xy 283.900727 -365.048841) (xy 283.850316 -365.099271) (xy 283.794577 -365.143741) (xy 283.734211 -365.181692)
			(xy 283.669976 -365.212649) (xy 283.60268 -365.23622) (xy 283.533168 -365.252111) (xy 283.462314 -365.260122)
			(xy 283.426662 -365.260636) (xy 283.391001 -365.260128) (xy 283.320129 -365.252146) (xy 283.250596 -365.236276)
			(xy 283.183278 -365.212717) (xy 283.119023 -365.181767) (xy 283.058639 -365.143813) (xy 283.002887 -365.099335)
			(xy 282.977336 -365.074454) (xy 282.001214 -364.098332) (xy 281.976338 -364.072775) (xy 281.931857 -364.017024)
			(xy 281.8939 -363.956642) (xy 281.862944 -363.892388) (xy 281.83938 -363.825072) (xy 281.823503 -363.75554)
			(xy 281.815514 -363.684667) (xy 281.815032 -363.649006) (xy 281.432 -363.649006) (xy 281.432 -365.70412)
			(xy 285.620712 -365.70412) (xy 285.624783 -365.648498) (xy 285.636909 -365.594061) (xy 285.656832 -365.54197)
			(xy 285.684128 -365.493335) (xy 285.718214 -365.449192) (xy 285.758363 -365.410483) (xy 285.803721 -365.378032)
			(xy 285.853321 -365.352531) (xy 285.906105 -365.334524) (xy 285.960948 -365.324394) (xy 286.016682 -365.322357)
			(xy 286.072119 -365.328457) (xy 286.126076 -365.342563) (xy 286.177405 -365.364375) (xy 286.225011 -365.393429)
			(xy 286.267879 -365.429104) (xy 286.305096 -365.470641) (xy 286.335869 -365.517154) (xy 286.359541 -365.567651)
			(xy 286.375609 -365.621058) (xy 286.383729 -365.676234) (xy 286.384238 -365.70412) (xy 286.383729 -365.732006)
			(xy 286.375609 -365.787182) (xy 286.359541 -365.840589) (xy 286.335869 -365.891086) (xy 286.305096 -365.937599)
			(xy 286.267879 -365.979136) (xy 286.225011 -366.014811) (xy 286.177405 -366.043865) (xy 286.126076 -366.065677)
			(xy 286.072119 -366.079783) (xy 286.016682 -366.085883) (xy 285.960948 -366.083846) (xy 285.906105 -366.073716)
			(xy 285.853321 -366.055709) (xy 285.803721 -366.030208) (xy 285.758363 -365.997757) (xy 285.718214 -365.959048)
			(xy 285.684128 -365.914905) (xy 285.656832 -365.86627) (xy 285.636909 -365.814179) (xy 285.624783 -365.759742)
			(xy 285.620712 -365.70412) (xy 281.432 -365.70412) (xy 281.432 -366.670082) (xy 284.956248 -366.670082)
			(xy 284.960319 -366.61446) (xy 284.972445 -366.560023) (xy 284.992368 -366.507932) (xy 285.019664 -366.459297)
			(xy 285.05375 -366.415154) (xy 285.093899 -366.376445) (xy 285.139257 -366.343994) (xy 285.188857 -366.318493)
			(xy 285.241641 -366.300486) (xy 285.296484 -366.290356) (xy 285.352218 -366.288319) (xy 285.407655 -366.294419)
			(xy 285.461612 -366.308525) (xy 285.512941 -366.330337) (xy 285.560547 -366.359391) (xy 285.603415 -366.395066)
			(xy 285.640632 -366.436603) (xy 285.671405 -366.483116) (xy 285.695077 -366.533613) (xy 285.711145 -366.58702)
			(xy 285.719265 -366.642196) (xy 285.719774 -366.670082) (xy 285.719265 -366.697968) (xy 285.711145 -366.753144)
			(xy 285.695077 -366.806551) (xy 285.671405 -366.857048) (xy 285.640632 -366.903561) (xy 285.603415 -366.945098)
			(xy 285.560547 -366.980773) (xy 285.512941 -367.009827) (xy 285.461612 -367.031639) (xy 285.407655 -367.045745)
			(xy 285.352218 -367.051845) (xy 285.296484 -367.049808) (xy 285.241641 -367.039678) (xy 285.188857 -367.021671)
			(xy 285.139257 -366.99617) (xy 285.093899 -366.963719) (xy 285.05375 -366.92501) (xy 285.019664 -366.880867)
			(xy 284.992368 -366.832232) (xy 284.972445 -366.780141) (xy 284.960319 -366.725704) (xy 284.956248 -366.670082)
			(xy 281.432 -366.670082) (xy 281.432 -367.212626) (xy 286.427418 -367.212626) (xy 286.427844 -367.187288)
			(xy 286.43455 -367.137057) (xy 286.447848 -367.088157) (xy 286.467504 -367.041447) (xy 286.493171 -366.997752)
			(xy 286.524398 -366.95784) (xy 286.542226 -366.93983) (xy 286.5517 -366.930126) (xy 286.565495 -366.906784)
			(xy 286.572642 -366.880629) (xy 286.572634 -366.853515) (xy 286.565473 -366.827364) (xy 286.551665 -366.804029)
			(xy 286.542226 -366.794288) (xy 286.524397 -366.776279) (xy 286.493168 -366.736367) (xy 286.467499 -366.692672)
			(xy 286.447841 -366.645963) (xy 286.434541 -366.597062) (xy 286.427832 -366.546831) (xy 286.427418 -366.521492)
			(xy 286.427904 -366.494241) (xy 286.43566 -366.440293) (xy 286.451015 -366.387998) (xy 286.473657 -366.338421)
			(xy 286.503123 -366.292571) (xy 286.538814 -366.25138) (xy 286.580005 -366.215689) (xy 286.625855 -366.186223)
			(xy 286.675432 -366.163581) (xy 286.727727 -366.148226) (xy 286.781675 -366.14047) (xy 286.836177 -366.14047)
			(xy 286.890125 -366.148226) (xy 286.94242 -366.163581) (xy 286.991997 -366.186223) (xy 287.037847 -366.215689)
			(xy 287.079038 -366.25138) (xy 287.114729 -366.292571) (xy 287.144195 -366.338421) (xy 287.166837 -366.387998)
			(xy 287.182192 -366.440293) (xy 287.189948 -366.494241) (xy 287.190094 -366.502442) (xy 288.052764 -366.502442)
			(xy 288.05325 -366.475191) (xy 288.061006 -366.421243) (xy 288.076361 -366.368948) (xy 288.099003 -366.319371)
			(xy 288.128469 -366.273521) (xy 288.16416 -366.23233) (xy 288.205351 -366.196639) (xy 288.251201 -366.167173)
			(xy 288.300778 -366.144531) (xy 288.353073 -366.129176) (xy 288.407021 -366.12142) (xy 288.461523 -366.12142)
			(xy 288.515471 -366.129176) (xy 288.567766 -366.144531) (xy 288.617343 -366.167173) (xy 288.663193 -366.196639)
			(xy 288.704384 -366.23233) (xy 288.740075 -366.273521) (xy 288.769541 -366.319371) (xy 288.792183 -366.368948)
			(xy 288.807538 -366.421243) (xy 288.815294 -366.475191) (xy 288.81578 -366.502442) (xy 288.815548 -366.521109)
			(xy 288.811855 -366.558261) (xy 288.808414 -366.57661) (xy 288.806165 -366.590889) (xy 288.808676 -366.619667)
			(xy 288.819156 -366.646586) (xy 288.836762 -366.669487) (xy 288.853909 -366.68202) (xy 294.64457 -366.68202)
			(xy 294.648641 -366.626398) (xy 294.660767 -366.571961) (xy 294.68069 -366.51987) (xy 294.707986 -366.471235)
			(xy 294.742072 -366.427092) (xy 294.782221 -366.388383) (xy 294.827579 -366.355932) (xy 294.877179 -366.330431)
			(xy 294.929963 -366.312424) (xy 294.984806 -366.302294) (xy 295.04054 -366.300257) (xy 295.095977 -366.306357)
			(xy 295.149934 -366.320463) (xy 295.201263 -366.342275) (xy 295.248869 -366.371329) (xy 295.291737 -366.407004)
			(xy 295.328954 -366.448541) (xy 295.359727 -366.495054) (xy 295.383399 -366.545551) (xy 295.399467 -366.598958)
			(xy 295.407587 -366.654134) (xy 295.408096 -366.68202) (xy 295.407587 -366.709906) (xy 295.399467 -366.765082)
			(xy 295.383399 -366.818489) (xy 295.359727 -366.868986) (xy 295.328954 -366.915499) (xy 295.291737 -366.957036)
			(xy 295.248869 -366.992711) (xy 295.201263 -367.021765) (xy 295.149934 -367.043577) (xy 295.095977 -367.057683)
			(xy 295.04054 -367.063783) (xy 294.984806 -367.061746) (xy 294.929963 -367.051616) (xy 294.877179 -367.033609)
			(xy 294.827579 -367.008108) (xy 294.782221 -366.975657) (xy 294.742072 -366.936948) (xy 294.707986 -366.892805)
			(xy 294.68069 -366.84417) (xy 294.660767 -366.792079) (xy 294.648641 -366.737642) (xy 294.64457 -366.68202)
			(xy 288.853909 -366.68202) (xy 288.860084 -366.686533) (xy 288.887249 -366.696356) (xy 288.901632 -366.697768)
			(xy 288.930316 -366.700088) (xy 288.986533 -366.712399) (xy 289.040263 -366.733013) (xy 289.090289 -366.76146)
			(xy 289.135477 -366.797097) (xy 289.1748 -366.839116) (xy 289.207368 -366.886563) (xy 289.232442 -366.938362)
			(xy 289.249454 -366.993339) (xy 289.258018 -367.050247) (xy 289.258502 -367.079022) (xy 289.258502 -367.100358)
			(xy 289.433 -367.274856) (xy 296.11574 -367.274856) (xy 296.116241 -367.246409) (xy 296.124701 -367.190149)
			(xy 296.141428 -367.13577) (xy 296.166048 -367.084479) (xy 296.198017 -367.037417) (xy 296.236624 -366.995627)
			(xy 296.258488 -366.977422) (xy 296.269983 -366.967503) (xy 296.287 -366.942374) (xy 296.295897 -366.913358)
			(xy 296.295892 -366.883009) (xy 296.286985 -366.853997) (xy 296.269961 -366.828873) (xy 296.258488 -366.818926)
			(xy 296.236618 -366.800728) (xy 296.198016 -366.758936) (xy 296.166053 -366.711871) (xy 296.141438 -366.660579)
			(xy 296.124719 -366.606199) (xy 296.116266 -366.549938) (xy 296.11574 -366.521492) (xy 296.116226 -366.494241)
			(xy 296.123982 -366.440293) (xy 296.139337 -366.387998) (xy 296.161979 -366.338421) (xy 296.191445 -366.292571)
			(xy 296.227136 -366.25138) (xy 296.268327 -366.215689) (xy 296.314177 -366.186223) (xy 296.363754 -366.163581)
			(xy 296.416049 -366.148226) (xy 296.469997 -366.14047) (xy 296.524499 -366.14047) (xy 296.578447 -366.148226)
			(xy 296.630742 -366.163581) (xy 296.680319 -366.186223) (xy 296.726169 -366.215689) (xy 296.76736 -366.25138)
			(xy 296.803051 -366.292571) (xy 296.832517 -366.338421) (xy 296.855159 -366.387998) (xy 296.870514 -366.440293)
			(xy 296.87827 -366.494241) (xy 296.878416 -366.502442) (xy 297.741086 -366.502442) (xy 297.741572 -366.475191)
			(xy 297.749328 -366.421243) (xy 297.764683 -366.368948) (xy 297.787325 -366.319371) (xy 297.816791 -366.273521)
			(xy 297.852482 -366.23233) (xy 297.893673 -366.196639) (xy 297.939523 -366.167173) (xy 297.9891 -366.144531)
			(xy 298.041395 -366.129176) (xy 298.095343 -366.12142) (xy 298.149845 -366.12142) (xy 298.203793 -366.129176)
			(xy 298.256088 -366.144531) (xy 298.305665 -366.167173) (xy 298.351515 -366.196639) (xy 298.392706 -366.23233)
			(xy 298.428397 -366.273521) (xy 298.457863 -366.319371) (xy 298.480505 -366.368948) (xy 298.49586 -366.421243)
			(xy 298.503616 -366.475191) (xy 298.504102 -366.502442) (xy 298.503863 -366.521109) (xy 298.50017 -366.55826)
			(xy 298.496736 -366.57661) (xy 298.494466 -366.590887) (xy 298.496978 -366.619669) (xy 298.50746 -366.646591)
			(xy 298.525071 -366.669494) (xy 298.548398 -366.686539) (xy 298.575569 -366.696359) (xy 298.589954 -366.697768)
			(xy 298.618632 -366.700155) (xy 298.674847 -366.712455) (xy 298.728577 -366.733058) (xy 298.778604 -366.761497)
			(xy 298.823792 -366.797126) (xy 298.863117 -366.839137) (xy 298.895687 -366.886578) (xy 298.920763 -366.938372)
			(xy 298.937776 -366.993345) (xy 298.94634 -367.050249) (xy 298.946824 -367.079022) (xy 298.946824 -367.100358)
			(xy 299.086016 -367.239296) (xy 330.685394 -367.239296) (xy 331.958188 -365.966756) (xy 331.976304 -365.949522)
			(xy 332.017841 -365.921705) (xy 332.064006 -365.902526) (xy 332.113025 -365.89272) (xy 332.13802 -365.89208)
			(xy 346.38742 -365.89208) (xy 346.412418 -365.892687) (xy 346.461443 -365.902498) (xy 346.507613 -365.92168)
			(xy 346.549158 -365.949496) (xy 346.567252 -365.966756) (xy 347.8657 -367.265204) (xy 347.882951 -367.283304)
			(xy 347.910762 -367.324848) (xy 347.929937 -367.371017) (xy 347.939738 -367.42004) (xy 347.940376 -367.445036)
			(xy 347.940376 -367.828068) (xy 347.959994 -367.846236) (xy 347.994452 -367.887119) (xy 348.022866 -367.932414)
			(xy 348.044678 -367.981231) (xy 348.059461 -368.032615) (xy 348.066927 -368.08556) (xy 348.067376 -368.112294)
			(xy 348.06689 -368.139545) (xy 348.059134 -368.193493) (xy 348.043779 -368.245788) (xy 348.021137 -368.295365)
			(xy 347.991671 -368.341215) (xy 347.95598 -368.382406) (xy 347.914789 -368.418097) (xy 347.868939 -368.447563)
			(xy 347.819362 -368.470205) (xy 347.767067 -368.48556) (xy 347.713119 -368.493316) (xy 347.658617 -368.493316)
			(xy 347.604669 -368.48556) (xy 347.552374 -368.470205) (xy 347.502797 -368.447563) (xy 347.456947 -368.418097)
			(xy 347.415756 -368.382406) (xy 347.380065 -368.341215) (xy 347.350599 -368.295365) (xy 347.327957 -368.245788)
			(xy 347.312602 -368.193493) (xy 347.304846 -368.139545) (xy 347.30436 -368.112294) (xy 347.304837 -368.08556)
			(xy 347.312291 -368.032615) (xy 347.327067 -367.98123) (xy 347.348874 -367.932413) (xy 347.377286 -367.887119)
			(xy 347.411745 -367.846237) (xy 347.43136 -367.828068) (xy 347.43136 -367.550446) (xy 346.28201 -366.401096)
			(xy 332.24343 -366.401096) (xy 330.970636 -367.673636) (xy 330.952577 -367.690936) (xy 330.911023 -367.718751)
			(xy 330.864841 -367.737925) (xy 330.815806 -367.74772) (xy 330.790804 -367.748312) (xy 298.980606 -367.748312)
			(xy 298.955609 -367.747691) (xy 298.906585 -367.737885) (xy 298.860414 -367.718707) (xy 298.818869 -367.690894)
			(xy 298.800774 -367.673636) (xy 298.58716 -367.460022) (xy 298.565824 -367.460022) (xy 298.538548 -367.459564)
			(xy 298.484544 -367.451869) (xy 298.432187 -367.436559) (xy 298.382544 -367.413949) (xy 298.336628 -367.384497)
			(xy 298.295374 -367.348807) (xy 298.259625 -367.307604) (xy 298.230109 -367.261729) (xy 298.207429 -367.212118)
			(xy 298.192046 -367.159782) (xy 298.184274 -367.105789) (xy 298.183808 -367.078514) (xy 298.184048 -367.059847)
			(xy 298.187736 -367.022695) (xy 298.191174 -367.004346) (xy 298.193481 -366.990074) (xy 298.190958 -366.96129)
			(xy 298.180467 -366.934367) (xy 298.16285 -366.911464) (xy 298.139518 -366.894419) (xy 298.112343 -366.884598)
			(xy 298.097956 -366.883188) (xy 298.069302 -366.880827) (xy 298.013138 -366.868534) (xy 297.959454 -366.847956)
			(xy 297.909464 -366.819557) (xy 297.864299 -366.78398) (xy 297.824983 -366.742031) (xy 297.792405 -366.694658)
			(xy 297.767301 -366.642935) (xy 297.750241 -366.588031) (xy 297.74161 -366.531189) (xy 297.741086 -366.502442)
			(xy 296.878416 -366.502442) (xy 296.878756 -366.521492) (xy 296.87822 -366.549937) (xy 296.869767 -366.606197)
			(xy 296.853048 -366.660575) (xy 296.828434 -366.711865) (xy 296.796471 -366.758929) (xy 296.75787 -366.80072)
			(xy 296.736008 -366.818926) (xy 296.724565 -366.8289) (xy 296.707548 -366.854015) (xy 296.698646 -366.883016)
			(xy 296.698641 -366.913352) (xy 296.707534 -366.942356) (xy 296.724543 -366.967475) (xy 296.736008 -366.977422)
			(xy 296.757852 -366.995649) (xy 296.796456 -367.037436) (xy 296.828422 -367.084494) (xy 296.853041 -367.13578)
			(xy 296.869766 -367.190155) (xy 296.87051 -367.1951) (xy 297.13936 -367.1951) (xy 297.139846 -367.167849)
			(xy 297.147602 -367.113901) (xy 297.162957 -367.061606) (xy 297.185599 -367.012029) (xy 297.215065 -366.966179)
			(xy 297.250756 -366.924988) (xy 297.291947 -366.889297) (xy 297.337797 -366.859831) (xy 297.387374 -366.837189)
			(xy 297.439669 -366.821834) (xy 297.493617 -366.814078) (xy 297.548119 -366.814078) (xy 297.602067 -366.821834)
			(xy 297.654362 -366.837189) (xy 297.703939 -366.859831) (xy 297.749789 -366.889297) (xy 297.79098 -366.924988)
			(xy 297.826671 -366.966179) (xy 297.856137 -367.012029) (xy 297.878779 -367.061606) (xy 297.894134 -367.113901)
			(xy 297.90189 -367.167849) (xy 297.902376 -367.1951) (xy 297.901951 -367.221835) (xy 297.894485 -367.274782)
			(xy 297.879698 -367.326168) (xy 297.857881 -367.374985) (xy 297.829461 -367.420277) (xy 297.794995 -367.461158)
			(xy 297.775376 -367.479326) (xy 297.775376 -367.707926) (xy 298.12615 -368.0587) (xy 331.45349 -368.0587)
			(xy 332.593188 -366.919256) (xy 332.611304 -366.902022) (xy 332.652841 -366.874205) (xy 332.699006 -366.855026)
			(xy 332.748025 -366.84522) (xy 332.77302 -366.84458) (xy 345.767914 -366.84458) (xy 345.7861 -366.82498)
			(xy 345.826981 -366.790522) (xy 345.872271 -366.762107) (xy 345.921085 -366.740292) (xy 345.972465 -366.725504)
			(xy 346.025407 -366.718033) (xy 346.05214 -366.71758) (xy 346.079388 -366.718093) (xy 346.13333 -366.725854)
			(xy 346.185618 -366.741212) (xy 346.235189 -366.763855) (xy 346.281033 -366.793321) (xy 346.322217 -366.829011)
			(xy 346.357903 -366.870199) (xy 346.387365 -366.916046) (xy 346.410002 -366.965619) (xy 346.425355 -367.017909)
			(xy 346.43311 -367.071851) (xy 346.43311 -367.126349) (xy 346.425355 -367.180291) (xy 346.410002 -367.232581)
			(xy 346.387365 -367.282154) (xy 346.357903 -367.328001) (xy 346.322217 -367.369189) (xy 346.281033 -367.404879)
			(xy 346.235189 -367.434345) (xy 346.185618 -367.456988) (xy 346.13333 -367.472346) (xy 346.079388 -367.480107)
			(xy 346.05214 -367.480596) (xy 346.025404 -367.48017) (xy 345.972457 -367.472707) (xy 345.92107 -367.457923)
			(xy 345.872252 -367.436106) (xy 345.82696 -367.407685) (xy 345.786081 -367.373216) (xy 345.767914 -367.353596)
			(xy 332.87843 -367.353596) (xy 331.738732 -368.49304) (xy 331.720675 -368.510343) (xy 331.679121 -368.538157)
			(xy 331.632938 -368.55733) (xy 331.583902 -368.567124) (xy 331.5589 -368.567716) (xy 298.02074 -368.567716)
			(xy 297.995744 -368.567073) (xy 297.946721 -368.557273) (xy 297.90055 -368.538102) (xy 297.859004 -368.510295)
			(xy 297.840908 -368.49304) (xy 297.341036 -367.993168) (xy 297.323778 -367.975074) (xy 297.295966 -367.933529)
			(xy 297.276793 -367.887358) (xy 297.266996 -367.838333) (xy 297.26636 -367.813336) (xy 297.26636 -367.479326)
			(xy 297.246746 -367.461154) (xy 297.212286 -367.420272) (xy 297.183871 -367.374979) (xy 297.162058 -367.326163)
			(xy 297.147274 -367.274779) (xy 297.139809 -367.221834) (xy 297.13936 -367.1951) (xy 296.87051 -367.1951)
			(xy 296.878226 -367.246412) (xy 296.878756 -367.274856) (xy 296.87827 -367.302107) (xy 296.870514 -367.356055)
			(xy 296.855159 -367.40835) (xy 296.832517 -367.457927) (xy 296.803051 -367.503777) (xy 296.76736 -367.544968)
			(xy 296.726169 -367.580659) (xy 296.680319 -367.610125) (xy 296.630742 -367.632767) (xy 296.578447 -367.648122)
			(xy 296.524499 -367.655878) (xy 296.469997 -367.655878) (xy 296.416049 -367.648122) (xy 296.363754 -367.632767)
			(xy 296.314177 -367.610125) (xy 296.268327 -367.580659) (xy 296.227136 -367.544968) (xy 296.191445 -367.503777)
			(xy 296.161979 -367.457927) (xy 296.139337 -367.40835) (xy 296.123982 -367.356055) (xy 296.116226 -367.302107)
			(xy 296.11574 -367.274856) (xy 289.433 -367.274856) (xy 289.518852 -367.360708) (xy 294.468804 -367.360708)
			(xy 294.493786 -367.361347) (xy 294.542792 -367.371084) (xy 294.588961 -367.390183) (xy 294.630524 -367.417913)
			(xy 294.648636 -367.43513) (xy 295.210738 -367.997232) (xy 295.22794 -368.01536) (xy 295.255686 -368.056913)
			(xy 295.274799 -368.103077) (xy 295.284546 -368.152082) (xy 295.28516 -368.177064) (xy 295.28516 -368.634264)
			(xy 295.676066 -369.024916) (xy 301.22622 -369.024916) (xy 301.251216 -369.025542) (xy 301.300239 -369.03535)
			(xy 301.34641 -369.054527) (xy 301.387956 -369.082336) (xy 301.406052 -369.099592) (xy 302.899064 -370.592604)
			(xy 330.38288 -370.592604) (xy 333.050642 -367.924842) (xy 333.068763 -367.907632) (xy 333.110318 -367.879889)
			(xy 333.156485 -367.860778) (xy 333.205491 -367.851033) (xy 333.230474 -367.85042) (xy 346.374974 -367.85042)
			(xy 346.393132 -367.830781) (xy 346.434005 -367.796282) (xy 346.479293 -367.767826) (xy 346.52811 -367.745971)
			(xy 346.579501 -367.731144) (xy 346.632457 -367.723636) (xy 346.6592 -367.723166) (xy 346.686449 -367.723704)
			(xy 346.740393 -367.73146) (xy 346.792684 -367.746814) (xy 346.842258 -367.769454) (xy 346.888105 -367.798918)
			(xy 346.929293 -367.834607) (xy 346.964982 -367.875795) (xy 346.994446 -367.921642) (xy 347.017086 -367.971216)
			(xy 347.03244 -368.023507) (xy 347.040196 -368.077451) (xy 347.040196 -368.131949) (xy 347.03244 -368.185893)
			(xy 347.017086 -368.238184) (xy 346.994446 -368.287758) (xy 346.964982 -368.333605) (xy 346.929293 -368.374793)
			(xy 346.888105 -368.410482) (xy 346.842258 -368.439946) (xy 346.792684 -368.462586) (xy 346.740393 -368.47794)
			(xy 346.686449 -368.485696) (xy 346.6592 -368.486182) (xy 346.632457 -368.485685) (xy 346.579498 -368.478197)
			(xy 346.528104 -368.463383) (xy 346.479285 -368.441532) (xy 346.433998 -368.413074) (xy 346.393132 -368.378567)
			(xy 346.374974 -368.358928) (xy 333.335884 -368.358928) (xy 330.668122 -371.02669) (xy 330.650006 -371.043906)
			(xy 330.60845 -371.071651) (xy 330.562282 -371.090761) (xy 330.513274 -371.100502) (xy 330.48829 -371.101112)
			(xy 302.793654 -371.101112) (xy 302.768669 -371.100521) (xy 302.71966 -371.090773) (xy 302.67349 -371.07166)
			(xy 302.631931 -371.043915) (xy 302.613822 -371.02669) (xy 301.12081 -369.533932) (xy 295.570656 -369.533932)
			(xy 295.545661 -369.533274) (xy 295.496639 -369.523479) (xy 295.450468 -369.504312) (xy 295.408921 -369.476509)
			(xy 295.390824 -369.459256) (xy 294.851074 -368.919506) (xy 294.833845 -368.901403) (xy 294.806104 -368.859842)
			(xy 294.786998 -368.813669) (xy 294.777261 -368.764659) (xy 294.776652 -368.739674) (xy 294.776652 -368.282474)
			(xy 294.363394 -367.869216) (xy 289.413442 -367.869216) (xy 289.388457 -367.868631) (xy 289.339447 -367.858881)
			(xy 289.293277 -367.839766) (xy 289.251718 -367.812019) (xy 289.23361 -367.794794) (xy 288.898838 -367.460022)
			(xy 288.877502 -367.460022) (xy 288.850226 -367.459585) (xy 288.796221 -367.451886) (xy 288.743863 -367.436574)
			(xy 288.69422 -367.413961) (xy 288.648304 -367.384507) (xy 288.607051 -367.348814) (xy 288.571302 -367.30761)
			(xy 288.541787 -367.261733) (xy 288.519106 -367.212121) (xy 288.503724 -367.159784) (xy 288.495952 -367.105789)
			(xy 288.495486 -367.078514) (xy 288.495734 -367.059847) (xy 288.499421 -367.022696) (xy 288.502852 -367.004346)
			(xy 288.505179 -366.990076) (xy 288.502656 -366.961288) (xy 288.492163 -366.934361) (xy 288.474541 -366.911457)
			(xy 288.451204 -366.894413) (xy 288.424024 -366.884595) (xy 288.409634 -366.883188) (xy 288.380986 -366.88076)
			(xy 288.324824 -366.868479) (xy 288.27114 -366.84791) (xy 288.221149 -366.81952) (xy 288.175984 -366.783951)
			(xy 288.136666 -366.742009) (xy 288.104086 -366.694643) (xy 288.078981 -366.642924) (xy 288.06192 -366.588025)
			(xy 288.053288 -366.531187) (xy 288.052764 -366.502442) (xy 287.190094 -366.502442) (xy 287.190434 -366.521492)
			(xy 287.190004 -366.54683) (xy 287.183297 -366.59706) (xy 287.169998 -366.64596) (xy 287.150343 -366.692669)
			(xy 287.124677 -366.736364) (xy 287.093453 -366.776278) (xy 287.075626 -366.794288) (xy 287.066284 -366.80409)
			(xy 287.052572 -366.827425) (xy 287.045463 -366.853539) (xy 287.045456 -366.880604) (xy 287.05255 -366.906722)
			(xy 287.066249 -366.930064) (xy 287.075626 -366.93983) (xy 287.093474 -366.957822) (xy 287.124698 -366.997738)
			(xy 287.150364 -367.041438) (xy 287.170018 -367.08815) (xy 287.183315 -367.137053) (xy 287.190021 -367.187287)
			(xy 287.190314 -367.20526) (xy 287.442908 -367.20526) (xy 287.446979 -367.149638) (xy 287.459105 -367.095201)
			(xy 287.479028 -367.04311) (xy 287.506324 -366.994475) (xy 287.54041 -366.950332) (xy 287.580559 -366.911623)
			(xy 287.625917 -366.879172) (xy 287.675517 -366.853671) (xy 287.728301 -366.835664) (xy 287.783144 -366.825534)
			(xy 287.838878 -366.823497) (xy 287.894315 -366.829597) (xy 287.948272 -366.843703) (xy 287.999601 -366.865515)
			(xy 288.047207 -366.894569) (xy 288.090075 -366.930244) (xy 288.127292 -366.971781) (xy 288.158065 -367.018294)
			(xy 288.181737 -367.068791) (xy 288.197805 -367.122198) (xy 288.205925 -367.177374) (xy 288.206434 -367.20526)
			(xy 288.205925 -367.233146) (xy 288.197805 -367.288322) (xy 288.181737 -367.341729) (xy 288.158065 -367.392226)
			(xy 288.127292 -367.438739) (xy 288.090075 -367.480276) (xy 288.047207 -367.515951) (xy 287.999601 -367.545005)
			(xy 287.948272 -367.566817) (xy 287.894315 -367.580923) (xy 287.838878 -367.587023) (xy 287.783144 -367.584986)
			(xy 287.728301 -367.574856) (xy 287.675517 -367.556849) (xy 287.625917 -367.531348) (xy 287.580559 -367.498897)
			(xy 287.54041 -367.460188) (xy 287.506324 -367.416045) (xy 287.479028 -367.36741) (xy 287.459105 -367.315319)
			(xy 287.446979 -367.260882) (xy 287.442908 -367.20526) (xy 287.190314 -367.20526) (xy 287.190434 -367.212626)
			(xy 287.189948 -367.239877) (xy 287.182192 -367.293825) (xy 287.166837 -367.34612) (xy 287.144195 -367.395697)
			(xy 287.114729 -367.441547) (xy 287.079038 -367.482738) (xy 287.037847 -367.518429) (xy 286.991997 -367.547895)
			(xy 286.94242 -367.570537) (xy 286.890125 -367.585892) (xy 286.836177 -367.593648) (xy 286.781675 -367.593648)
			(xy 286.727727 -367.585892) (xy 286.675432 -367.570537) (xy 286.625855 -367.547895) (xy 286.580005 -367.518429)
			(xy 286.538814 -367.482738) (xy 286.503123 -367.441547) (xy 286.473657 -367.395697) (xy 286.451015 -367.34612)
			(xy 286.43566 -367.293825) (xy 286.427904 -367.239877) (xy 286.427418 -367.212626) (xy 281.432 -367.212626)
			(xy 281.432 -372.987077) (xy 286.21657 -372.987077) (xy 286.220304 -372.933821) (xy 286.231425 -372.881605)
			(xy 286.249717 -372.83145) (xy 286.274821 -372.784334) (xy 286.306249 -372.741178) (xy 286.343386 -372.702825)
			(xy 286.364172 -372.686072) (xy 286.376017 -372.676217) (xy 286.393536 -372.650882) (xy 286.402709 -372.621478)
			(xy 286.402702 -372.590676) (xy 286.393516 -372.561275) (xy 286.375984 -372.535949) (xy 286.364172 -372.526052)
			(xy 286.341708 -372.507839) (xy 286.301972 -372.465823) (xy 286.269032 -372.418292) (xy 286.243641 -372.366335)
			(xy 286.22638 -372.311142) (xy 286.217645 -372.253977) (xy 286.217106 -372.225062) (xy 286.217607 -372.197693)
			(xy 286.225416 -372.143515) (xy 286.240897 -372.091013) (xy 286.263731 -372.041265) (xy 286.293448 -371.995297)
			(xy 286.311086 -371.974364) (xy 286.320361 -371.963065) (xy 286.332535 -371.936497) (xy 286.336701 -371.907571)
			(xy 286.332519 -371.878648) (xy 286.320329 -371.852087) (xy 286.311086 -371.84076) (xy 286.29341 -371.819857)
			(xy 286.26369 -371.773883) (xy 286.240849 -371.724131) (xy 286.225357 -371.671625) (xy 286.217533 -371.617443)
			(xy 286.217537 -371.562699) (xy 286.22537 -371.508519) (xy 286.240869 -371.456015) (xy 286.263717 -371.406267)
			(xy 286.293444 -371.360298) (xy 286.311086 -371.339364) (xy 286.320361 -371.328065) (xy 286.332535 -371.301497)
			(xy 286.336701 -371.272571) (xy 286.332519 -371.243648) (xy 286.320329 -371.217087) (xy 286.311086 -371.20576)
			(xy 286.293459 -371.184818) (xy 286.263746 -371.138848) (xy 286.240908 -371.089103) (xy 286.225414 -371.036604)
			(xy 286.217582 -370.98243) (xy 286.217106 -370.955062) (xy 286.217543 -370.927809) (xy 286.225305 -370.873859)
			(xy 286.240665 -370.821562) (xy 286.263312 -370.771984) (xy 286.292783 -370.726133) (xy 286.32848 -370.684943)
			(xy 286.369675 -370.649252) (xy 286.41553 -370.619787) (xy 286.465111 -370.597147) (xy 286.51741 -370.581793)
			(xy 286.571361 -370.574039) (xy 286.598614 -370.573554) (xy 286.625985 -370.573999) (xy 286.680166 -370.58182)
			(xy 286.73267 -370.597313) (xy 286.782416 -370.62016) (xy 286.828382 -370.64989) (xy 286.849312 -370.667534)
			(xy 286.86064 -370.67677) (xy 286.887197 -370.688946) (xy 286.916114 -370.693119) (xy 286.945031 -370.688946)
			(xy 286.971588 -370.67677) (xy 286.982916 -370.667534) (xy 287.003873 -370.649926) (xy 287.049839 -370.620208)
			(xy 287.09958 -370.597366) (xy 287.152075 -370.581868) (xy 287.206246 -370.574032) (xy 287.233614 -370.573554)
			(xy 287.26253 -370.574114) (xy 287.3197 -370.582831) (xy 287.374899 -370.60008) (xy 287.426861 -370.625464)
			(xy 287.474396 -370.658401) (xy 287.516413 -370.698137) (xy 287.534604 -370.72062) (xy 287.544501 -370.732425)
			(xy 287.569825 -370.749944) (xy 287.599218 -370.75912) (xy 287.63001 -370.75912) (xy 287.659403 -370.749944)
			(xy 287.684727 -370.732425) (xy 287.694624 -370.72062) (xy 287.712807 -370.698129) (xy 287.754827 -370.658394)
			(xy 287.802364 -370.625455) (xy 287.854327 -370.600068) (xy 287.909526 -370.582813) (xy 287.966697 -370.574087)
			(xy 287.995614 -370.573554) (xy 288.022864 -370.574065) (xy 288.076809 -370.581822) (xy 288.129101 -370.597177)
			(xy 288.178675 -370.619817) (xy 288.224524 -370.649281) (xy 288.265713 -370.68497) (xy 288.301404 -370.726157)
			(xy 288.330871 -370.772003) (xy 288.353515 -370.821577) (xy 288.368873 -370.873868) (xy 288.376634 -370.927812)
			(xy 288.377122 -370.955062) (xy 288.376653 -370.982432) (xy 288.368839 -371.036612) (xy 288.353351 -371.089116)
			(xy 288.33051 -371.138863) (xy 288.300784 -371.184829) (xy 288.283142 -371.20576) (xy 288.273946 -371.217117)
			(xy 288.261772 -371.243665) (xy 288.257594 -371.272571) (xy 288.261755 -371.30148) (xy 288.273915 -371.328035)
			(xy 288.283142 -371.339364) (xy 288.300747 -371.360326) (xy 288.330475 -371.406288) (xy 288.353325 -371.456029)
			(xy 288.368825 -371.508527) (xy 288.376658 -371.562702) (xy 288.376662 -371.617441) (xy 288.368838 -371.671617)
			(xy 288.353345 -371.724117) (xy 288.330503 -371.773862) (xy 288.300781 -371.819828) (xy 288.283142 -371.84076)
			(xy 288.273946 -371.852117) (xy 288.261772 -371.878665) (xy 288.257594 -371.907571) (xy 288.261755 -371.93648)
			(xy 288.273915 -371.963035) (xy 288.283142 -371.974364) (xy 288.300785 -371.995293) (xy 288.330495 -372.041267)
			(xy 288.353329 -372.091016) (xy 288.36882 -372.143517) (xy 288.376648 -372.197693) (xy 288.377122 -372.225062)
			(xy 288.376606 -372.253979) (xy 288.367881 -372.311152) (xy 288.350624 -372.366352) (xy 288.325232 -372.418315)
			(xy 288.292287 -372.465848) (xy 288.252543 -372.507863) (xy 288.230056 -372.526052) (xy 288.218285 -372.535989)
			(xy 288.200759 -372.561299) (xy 288.191575 -372.590684) (xy 288.191568 -372.62147) (xy 288.200738 -372.650858)
			(xy 288.218252 -372.676177) (xy 288.230056 -372.686072) (xy 288.250801 -372.702871) (xy 288.287929 -372.741219)
			(xy 288.319349 -372.784369) (xy 288.344448 -372.831477) (xy 288.362735 -372.881624) (xy 288.373854 -372.93383)
			(xy 288.375806 -372.961677) (xy 289.58207 -372.961677) (xy 289.585804 -372.908421) (xy 289.596925 -372.856205)
			(xy 289.615217 -372.80605) (xy 289.640321 -372.758934) (xy 289.671749 -372.715778) (xy 289.708886 -372.677425)
			(xy 289.729672 -372.660672) (xy 289.741517 -372.650817) (xy 289.759036 -372.625482) (xy 289.768209 -372.596078)
			(xy 289.768202 -372.565276) (xy 289.759016 -372.535875) (xy 289.741484 -372.510549) (xy 289.729672 -372.500652)
			(xy 289.707208 -372.482439) (xy 289.667472 -372.440423) (xy 289.634532 -372.392892) (xy 289.609141 -372.340935)
			(xy 289.59188 -372.285742) (xy 289.583145 -372.228577) (xy 289.582606 -372.199662) (xy 289.583107 -372.172293)
			(xy 289.590916 -372.118115) (xy 289.606397 -372.065613) (xy 289.629231 -372.015865) (xy 289.658948 -371.969897)
			(xy 289.676586 -371.948964) (xy 289.685861 -371.937665) (xy 289.698035 -371.911097) (xy 289.702201 -371.882171)
			(xy 289.698019 -371.853248) (xy 289.685829 -371.826687) (xy 289.676586 -371.81536) (xy 289.65891 -371.794457)
			(xy 289.62919 -371.748483) (xy 289.606349 -371.698731) (xy 289.590857 -371.646225) (xy 289.583033 -371.592043)
			(xy 289.583037 -371.537299) (xy 289.59087 -371.483119) (xy 289.606369 -371.430615) (xy 289.629217 -371.380867)
			(xy 289.658944 -371.334898) (xy 289.676586 -371.313964) (xy 289.685861 -371.302665) (xy 289.698035 -371.276097)
			(xy 289.702201 -371.247171) (xy 289.698019 -371.218248) (xy 289.685829 -371.191687) (xy 289.676586 -371.18036)
			(xy 289.658959 -371.159418) (xy 289.629246 -371.113448) (xy 289.606408 -371.063703) (xy 289.590914 -371.011204)
			(xy 289.583082 -370.95703) (xy 289.582606 -370.929662) (xy 289.583092 -370.902411) (xy 289.590848 -370.848463)
			(xy 289.606203 -370.796168) (xy 289.628845 -370.746591) (xy 289.658311 -370.700741) (xy 289.694002 -370.65955)
			(xy 289.735193 -370.623859) (xy 289.781043 -370.594393) (xy 289.83062 -370.571751) (xy 289.882915 -370.556396)
			(xy 289.936863 -370.54864) (xy 289.991365 -370.54864) (xy 290.045313 -370.556396) (xy 290.097608 -370.571751)
			(xy 290.147185 -370.594393) (xy 290.193035 -370.623859) (xy 290.234226 -370.65955) (xy 290.269917 -370.700741)
			(xy 290.295262 -370.740178) (xy 291.927026 -370.740178) (xy 291.927573 -370.711009) (xy 291.936476 -370.653353)
			(xy 291.954056 -370.597726) (xy 291.979902 -370.545425) (xy 292.013412 -370.497671) (xy 292.053803 -370.455576)
			(xy 292.076632 -370.43741) (xy 292.086966 -370.428937) (xy 292.103261 -370.407771) (xy 292.113508 -370.383104)
			(xy 292.117008 -370.356623) (xy 292.113521 -370.330141) (xy 292.103284 -370.305469) (xy 292.086999 -370.284296)
			(xy 292.076632 -370.275866) (xy 292.053819 -370.25768) (xy 292.013415 -370.215598) (xy 291.979897 -370.16785)
			(xy 291.954048 -370.115551) (xy 291.936473 -370.059924) (xy 291.927582 -370.002267) (xy 291.927026 -369.973098)
			(xy 291.927454 -369.945844) (xy 291.935212 -369.89189) (xy 291.95057 -369.839589) (xy 291.973215 -369.790007)
			(xy 292.002686 -369.744152) (xy 292.038384 -369.702958) (xy 292.079581 -369.667265) (xy 292.125438 -369.637798)
			(xy 292.175023 -369.615157) (xy 292.227325 -369.599804) (xy 292.28128 -369.592051) (xy 292.308534 -369.59159)
			(xy 292.337451 -369.592122) (xy 292.394623 -369.600843) (xy 292.449823 -369.618096) (xy 292.501786 -369.643485)
			(xy 292.549319 -369.676428) (xy 292.591335 -369.71617) (xy 292.609524 -369.738656) (xy 292.619421 -369.750461)
			(xy 292.644745 -369.76798) (xy 292.674138 -369.777156) (xy 292.70493 -369.777156) (xy 292.734323 -369.76798)
			(xy 292.759647 -369.750461) (xy 292.769544 -369.738656) (xy 292.787699 -369.716142) (xy 292.829728 -369.676411)
			(xy 292.87727 -369.643477) (xy 292.929239 -369.618094) (xy 292.984442 -369.600844) (xy 293.041616 -369.592122)
			(xy 293.070534 -369.59159) (xy 293.099081 -369.59211) (xy 293.155536 -369.600633) (xy 293.210091 -369.61747)
			(xy 293.26153 -369.642244) (xy 293.285418 -369.657884) (xy 293.296563 -369.664941) (xy 293.321415 -369.673747)
			(xy 293.347695 -369.675874) (xy 293.37364 -369.671181) (xy 293.39751 -369.659982) (xy 293.417702 -369.643028)
			(xy 293.425626 -369.632484) (xy 293.441057 -369.611486) (xy 293.476652 -369.573431) (xy 293.517093 -369.540572)
			(xy 293.561628 -369.513519) (xy 293.609429 -369.492776) (xy 293.659607 -369.478729) (xy 293.71123 -369.471638)
			(xy 293.737284 -369.471194) (xy 293.766202 -369.471688) (xy 293.823376 -369.480417) (xy 293.878577 -369.497677)
			(xy 293.93054 -369.523073) (xy 293.978072 -369.556023) (xy 294.020086 -369.595771) (xy 294.038274 -369.61826)
			(xy 294.048171 -369.630065) (xy 294.073495 -369.647584) (xy 294.102888 -369.65676) (xy 294.13368 -369.65676)
			(xy 294.163073 -369.647584) (xy 294.188397 -369.630065) (xy 294.198294 -369.61826) (xy 294.216478 -369.595771)
			(xy 294.258501 -369.556038) (xy 294.306037 -369.523101) (xy 294.358 -369.497714) (xy 294.413198 -369.480458)
			(xy 294.470368 -369.471729) (xy 294.499284 -369.471194) (xy 294.526537 -369.47167) (xy 294.580487 -369.479425)
			(xy 294.632785 -369.494779) (xy 294.682365 -369.51742) (xy 294.728218 -369.546886) (xy 294.769411 -369.582579)
			(xy 294.805105 -369.62377) (xy 294.834573 -369.669623) (xy 294.857216 -369.719202) (xy 294.872572 -369.771499)
			(xy 294.880329 -369.825449) (xy 294.880792 -369.852702) (xy 294.880362 -369.878745) (xy 294.873275 -369.930348)
			(xy 294.859233 -369.980506) (xy 294.838498 -370.028288) (xy 294.811455 -370.072804) (xy 294.778606 -370.113227)
			(xy 294.759888 -370.13134) (xy 294.749997 -370.141348) (xy 294.735529 -370.165464) (xy 294.72818 -370.19261)
			(xy 294.728505 -370.220731) (xy 294.73648 -370.247699) (xy 294.7515 -370.271474) (xy 294.761666 -370.2812)
			(xy 294.781236 -370.299374) (xy 294.815628 -370.340233) (xy 294.843987 -370.385488) (xy 294.865756 -370.434257)
			(xy 294.880511 -370.485585) (xy 294.887963 -370.538469) (xy 294.888412 -370.565172) (xy 294.887892 -370.592941)
			(xy 294.879843 -370.647893) (xy 294.863911 -370.701096) (xy 294.840433 -370.751428) (xy 294.809904 -370.797823)
			(xy 294.772971 -370.8393) (xy 294.752014 -370.857526) (xy 294.741396 -370.867082) (xy 294.725411 -370.890736)
			(xy 294.716616 -370.917896) (xy 294.7157 -370.94643) (xy 294.722736 -370.974099) (xy 294.737171 -370.998729)
			(xy 294.747188 -371.00891) (xy 294.765535 -371.026997) (xy 294.797707 -371.067237) (xy 294.824176 -371.111437)
			(xy 294.844461 -371.158796) (xy 294.858194 -371.208451) (xy 294.865127 -371.259502) (xy 294.865552 -371.285262)
			(xy 294.865075 -371.312632) (xy 294.857262 -371.366811) (xy 294.841776 -371.419315) (xy 294.818936 -371.469062)
			(xy 294.789213 -371.515028) (xy 294.771572 -371.53596) (xy 294.762374 -371.547316) (xy 294.750196 -371.573864)
			(xy 294.746017 -371.602771) (xy 294.750179 -371.631681) (xy 294.762343 -371.658236) (xy 294.771572 -371.669564)
			(xy 294.789176 -371.690527) (xy 294.818902 -371.736489) (xy 294.84175 -371.786231) (xy 294.857249 -371.838728)
			(xy 294.865081 -371.892903) (xy 294.865085 -371.94764) (xy 294.857261 -372.001816) (xy 294.84177 -372.054316)
			(xy 294.81893 -372.10406) (xy 294.78921 -372.150027) (xy 294.771572 -372.17096) (xy 294.762374 -372.182316)
			(xy 294.750196 -372.208864) (xy 294.746017 -372.237771) (xy 294.750179 -372.266681) (xy 294.762343 -372.293236)
			(xy 294.771572 -372.304564) (xy 294.789176 -372.325527) (xy 294.818902 -372.371489) (xy 294.84175 -372.421231)
			(xy 294.857249 -372.473728) (xy 294.860837 -372.49855) (xy 295.942254 -372.49855) (xy 295.942254 -372.413854)
			(xy 295.950305 -372.32954) (xy 295.966334 -372.246374) (xy 295.990195 -372.165107) (xy 296.021674 -372.086477)
			(xy 296.060485 -372.011196) (xy 296.106275 -371.939944) (xy 296.158631 -371.873368) (xy 296.217079 -371.81207)
			(xy 296.281089 -371.756605) (xy 296.350081 -371.707476) (xy 296.423431 -371.665127) (xy 296.500474 -371.629943)
			(xy 296.580513 -371.602241) (xy 296.662822 -371.582273) (xy 296.746657 -371.57022) (xy 296.831258 -371.56619)
			(xy 296.915859 -371.57022) (xy 296.999694 -371.582273) (xy 297.082003 -371.602241) (xy 297.162042 -371.629943)
			(xy 297.239085 -371.665127) (xy 297.312435 -371.707476) (xy 297.381427 -371.756605) (xy 297.445437 -371.81207)
			(xy 297.503885 -371.873368) (xy 297.556241 -371.939944) (xy 297.602031 -372.011196) (xy 297.640842 -372.086477)
			(xy 297.672321 -372.165107) (xy 297.696182 -372.246374) (xy 297.712211 -372.32954) (xy 297.720262 -372.413854)
			(xy 297.720766 -372.456202) (xy 298.466767 -372.456202) (xy 298.470803 -372.372755) (xy 298.482875 -372.290087)
			(xy 298.502868 -372.20897) (xy 298.530597 -372.130161) (xy 298.565803 -372.054396) (xy 298.608157 -371.982383)
			(xy 298.657263 -371.914794) (xy 298.712664 -371.85226) (xy 298.773841 -371.795365) (xy 298.840224 -371.744639)
			(xy 298.911192 -371.700558) (xy 298.986084 -371.663532) (xy 299.0642 -371.633906) (xy 299.14481 -371.611958)
			(xy 299.227162 -371.597893) (xy 299.310488 -371.591841) (xy 299.394008 -371.59386) (xy 299.476944 -371.60393)
			(xy 299.55852 -371.621958) (xy 299.637976 -371.647775) (xy 299.714569 -371.68114) (xy 299.787585 -371.721741)
			(xy 299.856341 -371.7692) (xy 299.920195 -371.823073) (xy 299.978552 -371.882858) (xy 300.030867 -371.947995)
			(xy 300.07665 -372.017878) (xy 300.115475 -372.091853) (xy 300.14698 -372.16923) (xy 300.170869 -372.249287)
			(xy 300.18692 -372.331275) (xy 300.194983 -372.41443) (xy 300.195488 -372.456202) (xy 300.194983 -372.497974)
			(xy 300.18692 -372.581129) (xy 300.170869 -372.663117) (xy 300.14698 -372.743174) (xy 300.115475 -372.820551)
			(xy 300.07665 -372.894526) (xy 300.030867 -372.964409) (xy 299.978552 -373.029546) (xy 299.920195 -373.089331)
			(xy 299.856341 -373.143204) (xy 299.787585 -373.190663) (xy 299.714569 -373.231264) (xy 299.637976 -373.264629)
			(xy 299.55852 -373.290446) (xy 299.476944 -373.308474) (xy 299.394008 -373.318544) (xy 299.310488 -373.320563)
			(xy 299.227162 -373.314511) (xy 299.14481 -373.300446) (xy 299.0642 -373.278498) (xy 298.986084 -373.248872)
			(xy 298.911192 -373.211846) (xy 298.840224 -373.167765) (xy 298.773841 -373.117039) (xy 298.712664 -373.060144)
			(xy 298.657263 -372.99761) (xy 298.608157 -372.930021) (xy 298.565803 -372.858008) (xy 298.530597 -372.782243)
			(xy 298.502868 -372.703434) (xy 298.482875 -372.622317) (xy 298.470803 -372.539649) (xy 298.466767 -372.456202)
			(xy 297.720766 -372.456202) (xy 297.720262 -372.49855) (xy 297.712211 -372.582864) (xy 297.696182 -372.66603)
			(xy 297.672321 -372.747297) (xy 297.640842 -372.825927) (xy 297.602031 -372.901208) (xy 297.556241 -372.97246)
			(xy 297.503885 -373.039036) (xy 297.445437 -373.100334) (xy 297.381427 -373.155799) (xy 297.312435 -373.204928)
			(xy 297.239085 -373.247277) (xy 297.162042 -373.282461) (xy 297.082003 -373.310163) (xy 296.999694 -373.330131)
			(xy 296.915859 -373.342184) (xy 296.831258 -373.346215) (xy 296.746657 -373.342184) (xy 296.662822 -373.330131)
			(xy 296.580513 -373.310163) (xy 296.500474 -373.282461) (xy 296.423431 -373.247277) (xy 296.350081 -373.204928)
			(xy 296.281089 -373.155799) (xy 296.217079 -373.100334) (xy 296.158631 -373.039036) (xy 296.106275 -372.97246)
			(xy 296.060485 -372.901208) (xy 296.021674 -372.825927) (xy 295.990195 -372.747297) (xy 295.966334 -372.66603)
			(xy 295.950305 -372.582864) (xy 295.942254 -372.49855) (xy 294.860837 -372.49855) (xy 294.865081 -372.527903)
			(xy 294.865085 -372.58264) (xy 294.857261 -372.636816) (xy 294.84177 -372.689316) (xy 294.81893 -372.73906)
			(xy 294.78921 -372.785027) (xy 294.771572 -372.80596) (xy 294.762374 -372.817316) (xy 294.750196 -372.843864)
			(xy 294.746017 -372.872771) (xy 294.750179 -372.901681) (xy 294.762343 -372.928236) (xy 294.771572 -372.939564)
			(xy 294.789203 -372.960502) (xy 294.818917 -373.006473) (xy 294.841755 -373.056219) (xy 294.857248 -373.108718)
			(xy 294.865077 -373.162893) (xy 294.865552 -373.190262) (xy 294.864987 -373.21751) (xy 294.857236 -373.271453)
			(xy 294.841888 -373.323743) (xy 294.819255 -373.373317) (xy 294.789797 -373.419166) (xy 294.754113 -373.460355)
			(xy 294.712932 -373.496047) (xy 294.667089 -373.525515) (xy 294.61752 -373.54816) (xy 294.565233 -373.563519)
			(xy 294.511292 -373.571281) (xy 294.484044 -373.57177) (xy 294.455128 -373.571232) (xy 294.397957 -373.562508)
			(xy 294.342758 -373.545255) (xy 294.290796 -373.519867) (xy 294.243262 -373.486927) (xy 294.201244 -373.447188)
			(xy 294.183054 -373.424704) (xy 294.173157 -373.412899) (xy 294.147833 -373.39538) (xy 294.11844 -373.386204)
			(xy 294.087648 -373.386204) (xy 294.058255 -373.39538) (xy 294.032931 -373.412899) (xy 294.023034 -373.424704)
			(xy 294.004825 -373.447172) (xy 293.962809 -373.486908) (xy 293.915278 -373.519849) (xy 293.86332 -373.54524)
			(xy 293.808126 -373.562499) (xy 293.750959 -373.571233) (xy 293.722044 -373.57177) (xy 293.694791 -373.571304)
			(xy 293.640838 -373.563552) (xy 293.588538 -373.548199) (xy 293.538955 -373.525559) (xy 293.4931 -373.496092)
			(xy 293.451906 -373.460399) (xy 293.416211 -373.419205) (xy 293.386744 -373.37335) (xy 293.364103 -373.323768)
			(xy 293.34875 -373.271468) (xy 293.340997 -373.217515) (xy 293.340536 -373.190262) (xy 293.34103 -373.162893)
			(xy 293.348839 -373.108714) (xy 293.364322 -373.056211) (xy 293.387157 -373.006464) (xy 293.416877 -372.960496)
			(xy 293.434516 -372.939564) (xy 293.443788 -372.928264) (xy 293.455959 -372.901696) (xy 293.460124 -372.872771)
			(xy 293.455943 -372.843849) (xy 293.443757 -372.817288) (xy 293.434516 -372.80596) (xy 293.416839 -372.785057)
			(xy 293.387116 -372.739084) (xy 293.364274 -372.689333) (xy 293.348781 -372.636826) (xy 293.340956 -372.582644)
			(xy 293.34096 -372.527899) (xy 293.348793 -372.473718) (xy 293.364294 -372.421214) (xy 293.387144 -372.371466)
			(xy 293.416873 -372.325497) (xy 293.434516 -372.304564) (xy 293.443788 -372.293264) (xy 293.455959 -372.266696)
			(xy 293.460124 -372.237771) (xy 293.455943 -372.208849) (xy 293.443757 -372.182288) (xy 293.434516 -372.17096)
			(xy 293.416839 -372.150057) (xy 293.387116 -372.104084) (xy 293.364274 -372.054333) (xy 293.348781 -372.001826)
			(xy 293.340956 -371.947644) (xy 293.34096 -371.892899) (xy 293.348793 -371.838718) (xy 293.364294 -371.786214)
			(xy 293.387144 -371.736466) (xy 293.416873 -371.690497) (xy 293.434516 -371.669564) (xy 293.443788 -371.658264)
			(xy 293.455959 -371.631696) (xy 293.460124 -371.602771) (xy 293.455943 -371.573849) (xy 293.443757 -371.547288)
			(xy 293.434516 -371.53596) (xy 293.416894 -371.515014) (xy 293.387179 -371.469045) (xy 293.36434 -371.419301)
			(xy 293.348845 -371.366804) (xy 293.341012 -371.31263) (xy 293.340536 -371.285262) (xy 293.340768 -371.266207)
			(xy 293.344587 -371.228289) (xy 293.348156 -371.20957) (xy 293.3505 -371.196098) (xy 293.348653 -371.168823)
			(xy 293.339636 -371.143015) (xy 293.324096 -371.120524) (xy 293.303147 -371.102961) (xy 293.278289 -371.091584)
			(xy 293.251304 -371.087209) (xy 293.224125 -371.09015) (xy 293.21125 -371.094762) (xy 293.188788 -371.103308)
			(xy 293.142245 -371.11529) (xy 293.094564 -371.121325) (xy 293.070534 -371.121686) (xy 293.041618 -371.121149)
			(xy 292.984447 -371.112424) (xy 292.929249 -371.09517) (xy 292.877287 -371.069782) (xy 292.829752 -371.036842)
			(xy 292.787735 -370.997104) (xy 292.769544 -370.97462) (xy 292.759647 -370.962815) (xy 292.734323 -370.945296)
			(xy 292.70493 -370.93612) (xy 292.674138 -370.93612) (xy 292.644745 -370.945296) (xy 292.619421 -370.962815)
			(xy 292.609524 -370.97462) (xy 292.591324 -370.997096) (xy 292.549306 -371.036831) (xy 292.501773 -371.06977)
			(xy 292.449813 -371.09516) (xy 292.394617 -371.112418) (xy 292.337449 -371.121149) (xy 292.308534 -371.121686)
			(xy 292.281281 -371.121213) (xy 292.227329 -371.11346) (xy 292.17503 -371.098107) (xy 292.125449 -371.075467)
			(xy 292.079594 -371.046001) (xy 292.038401 -371.010308) (xy 292.002707 -370.969115) (xy 291.973239 -370.923262)
			(xy 291.950597 -370.873681) (xy 291.935242 -370.821382) (xy 291.927488 -370.767431) (xy 291.927026 -370.740178)
			(xy 290.295262 -370.740178) (xy 290.299383 -370.746591) (xy 290.322025 -370.796168) (xy 290.33738 -370.848463)
			(xy 290.345136 -370.902411) (xy 290.345622 -370.929662) (xy 290.345153 -370.957032) (xy 290.337339 -371.011212)
			(xy 290.321851 -371.063716) (xy 290.29901 -371.113463) (xy 290.269284 -371.159429) (xy 290.251642 -371.18036)
			(xy 290.242446 -371.191717) (xy 290.230272 -371.218265) (xy 290.226094 -371.247171) (xy 290.230255 -371.27608)
			(xy 290.242415 -371.302635) (xy 290.251642 -371.313964) (xy 290.269247 -371.334926) (xy 290.298975 -371.380888)
			(xy 290.321825 -371.430629) (xy 290.337325 -371.483127) (xy 290.345158 -371.537302) (xy 290.345162 -371.592041)
			(xy 290.337338 -371.646217) (xy 290.321845 -371.698717) (xy 290.299003 -371.748462) (xy 290.269281 -371.794428)
			(xy 290.251642 -371.81536) (xy 290.242446 -371.826717) (xy 290.230272 -371.853265) (xy 290.226094 -371.882171)
			(xy 290.230255 -371.91108) (xy 290.242415 -371.937635) (xy 290.251642 -371.948964) (xy 290.269285 -371.969893)
			(xy 290.298995 -372.015867) (xy 290.321829 -372.065616) (xy 290.33732 -372.118117) (xy 290.345148 -372.172293)
			(xy 290.345622 -372.199662) (xy 290.345106 -372.228579) (xy 290.336381 -372.285752) (xy 290.319124 -372.340952)
			(xy 290.293732 -372.392915) (xy 290.260787 -372.440448) (xy 290.221043 -372.482463) (xy 290.198556 -372.500652)
			(xy 290.186785 -372.510589) (xy 290.169259 -372.535899) (xy 290.160075 -372.565284) (xy 290.160068 -372.59607)
			(xy 290.169238 -372.625458) (xy 290.186752 -372.650777) (xy 290.198556 -372.660672) (xy 290.219301 -372.677471)
			(xy 290.256429 -372.715819) (xy 290.287849 -372.758969) (xy 290.312948 -372.806077) (xy 290.331235 -372.856224)
			(xy 290.342354 -372.90843) (xy 290.346086 -372.961677) (xy 290.34236 -373.014924) (xy 290.331248 -373.067131)
			(xy 290.312967 -373.11728) (xy 290.287874 -373.164392) (xy 290.256459 -373.207545) (xy 290.219335 -373.245898)
			(xy 290.198556 -373.262652) (xy 290.186785 -373.272589) (xy 290.169259 -373.297899) (xy 290.160075 -373.327284)
			(xy 290.160068 -373.35807) (xy 290.169238 -373.387458) (xy 290.186752 -373.412777) (xy 290.198556 -373.422672)
			(xy 290.221017 -373.44089) (xy 290.260756 -373.482903) (xy 290.293698 -373.530432) (xy 290.319091 -373.582388)
			(xy 290.336352 -373.637581) (xy 290.345085 -373.694747) (xy 290.345622 -373.723662) (xy 290.345136 -373.750913)
			(xy 290.33738 -373.804861) (xy 290.322025 -373.857156) (xy 290.299383 -373.906733) (xy 290.269917 -373.952583)
			(xy 290.234226 -373.993774) (xy 290.193035 -374.029465) (xy 290.147185 -374.058931) (xy 290.097608 -374.081573)
			(xy 290.045313 -374.096928) (xy 289.991365 -374.104684) (xy 289.936863 -374.104684) (xy 289.882915 -374.096928)
			(xy 289.83062 -374.081573) (xy 289.781043 -374.058931) (xy 289.735193 -374.029465) (xy 289.694002 -373.993774)
			(xy 289.658311 -373.952583) (xy 289.628845 -373.906733) (xy 289.606203 -373.857156) (xy 289.590848 -373.804861)
			(xy 289.583092 -373.750913) (xy 289.582606 -373.723662) (xy 289.583167 -373.694747) (xy 289.591886 -373.637577)
			(xy 289.609136 -373.582379) (xy 289.63452 -373.530417) (xy 289.667456 -373.482882) (xy 289.70719 -373.440863)
			(xy 289.729672 -373.422672) (xy 289.741517 -373.412817) (xy 289.759036 -373.387482) (xy 289.768209 -373.358078)
			(xy 289.768202 -373.327276) (xy 289.759016 -373.297875) (xy 289.741484 -373.272549) (xy 289.729672 -373.262652)
			(xy 289.708851 -373.245944) (xy 289.671719 -373.207586) (xy 289.640296 -373.164426) (xy 289.615197 -373.117307)
			(xy 289.596912 -373.06715) (xy 289.585797 -373.014933) (xy 289.58207 -372.961677) (xy 288.375806 -372.961677)
			(xy 288.377586 -372.987077) (xy 288.37386 -373.040324) (xy 288.362748 -373.092531) (xy 288.344467 -373.14268)
			(xy 288.319374 -373.189792) (xy 288.287959 -373.232945) (xy 288.250835 -373.271298) (xy 288.230056 -373.288052)
			(xy 288.218285 -373.297989) (xy 288.200759 -373.323299) (xy 288.191575 -373.352684) (xy 288.191568 -373.38347)
			(xy 288.200738 -373.412858) (xy 288.218252 -373.438177) (xy 288.230056 -373.448072) (xy 288.252517 -373.46629)
			(xy 288.292256 -373.508303) (xy 288.325198 -373.555832) (xy 288.350591 -373.607788) (xy 288.367852 -373.662981)
			(xy 288.376585 -373.720147) (xy 288.377122 -373.749062) (xy 288.376609 -373.776313) (xy 288.368858 -373.830262)
			(xy 288.353507 -373.882558) (xy 288.33087 -373.932137) (xy 288.301408 -373.977989) (xy 288.265719 -374.019182)
			(xy 288.224531 -374.054876) (xy 288.178683 -374.084345) (xy 288.129107 -374.106989) (xy 288.076813 -374.122347)
			(xy 288.022865 -374.130106) (xy 287.995614 -374.13057) (xy 287.966697 -374.130053) (xy 287.909525 -374.121325)
			(xy 287.854326 -374.104068) (xy 287.802364 -374.078676) (xy 287.75483 -374.045732) (xy 287.712814 -374.00599)
			(xy 287.694624 -373.983504) (xy 287.684727 -373.971699) (xy 287.659403 -373.95418) (xy 287.63001 -373.945004)
			(xy 287.599218 -373.945004) (xy 287.569825 -373.95418) (xy 287.544501 -373.971699) (xy 287.534604 -373.983504)
			(xy 287.516412 -374.005986) (xy 287.474392 -374.045721) (xy 287.426857 -374.07866) (xy 287.374896 -374.104049)
			(xy 287.319699 -374.121306) (xy 287.26253 -374.130035) (xy 287.233614 -374.13057) (xy 287.206244 -374.130103)
			(xy 287.152064 -374.122287) (xy 287.099561 -374.106798) (xy 287.049814 -374.083956) (xy 287.003847 -374.054232)
			(xy 286.982916 -374.03659) (xy 286.971588 -374.027354) (xy 286.945031 -374.015178) (xy 286.916114 -374.011005)
			(xy 286.887197 -374.015178) (xy 286.86064 -374.027354) (xy 286.849312 -374.03659) (xy 286.828385 -374.054235)
			(xy 286.782411 -374.083947) (xy 286.732662 -374.106782) (xy 286.68016 -374.122271) (xy 286.625984 -374.130097)
			(xy 286.598614 -374.13057) (xy 286.57136 -374.130132) (xy 286.517406 -374.122375) (xy 286.465105 -374.107019)
			(xy 286.415523 -374.084376) (xy 286.369668 -374.054906) (xy 286.328474 -374.019209) (xy 286.29278 -373.978013)
			(xy 286.263313 -373.932156) (xy 286.240672 -373.882572) (xy 286.225319 -373.830271) (xy 286.217567 -373.776316)
			(xy 286.217106 -373.749062) (xy 286.217667 -373.720147) (xy 286.226386 -373.662977) (xy 286.243636 -373.607779)
			(xy 286.26902 -373.555817) (xy 286.301956 -373.508282) (xy 286.34169 -373.466263) (xy 286.364172 -373.448072)
			(xy 286.376017 -373.438217) (xy 286.393536 -373.412882) (xy 286.402709 -373.383478) (xy 286.402702 -373.352676)
			(xy 286.393516 -373.323275) (xy 286.375984 -373.297949) (xy 286.364172 -373.288052) (xy 286.343351 -373.271344)
			(xy 286.306219 -373.232986) (xy 286.274796 -373.189826) (xy 286.249697 -373.142707) (xy 286.231412 -373.09255)
			(xy 286.220297 -373.040333) (xy 286.21657 -372.987077) (xy 281.432 -372.987077) (xy 281.432 -380.248668)
			(xy 282.017724 -380.834392) (xy 321.539616 -380.834392)
		)
		(stroke
			(width 0)
			(type solid)
		)
		(fill yes)
		(layer "In6.Cu")
		(net "GND")
	)
	(gr_poly
		(pts
			(arc
				(start 278.10841 -405.924766)
				(mid 278.127045 -405.923069)
				(end 278.145748 -405.92248)
			)
			(xy 280.90622 -405.92248) (xy 281.051508 -405.777192) (xy 281.051508 -397.72844) (xy 280.706068 -397.383)
			(xy 275.6408 -397.383) (xy 275.3868 -397.637) (xy 275.3868 -405.8285) (xy 275.48332 -405.92502) (xy 278.105616 -405.92502)
		)
		(stroke
			(width 0)
			(type solid)
		)
		(fill yes)
		(layer "In7.Cu")
		(net "P12V_MAIN_R_0")
	)
	(gr_poly
		(pts
			(arc
				(start 273.791172 -406.781)
				(mid 273.810393 -406.777119)
				(end 273.826732 -406.766268)
			)
			(xy 274.30476 -406.28824) (xy 274.32 -406.274016) (xy 274.32 -397.635984) (xy 274.30476 -397.62176)
			(xy 274.083018 -397.400018) (xy 274.067016 -397.383) (xy 240.155984 -397.383) (xy 240.14176 -397.39824)
			(xy 239.666018 -397.873982) (xy 239.665764 -397.874236) (xy 239.649 -397.889984) (xy 239.649 -406.528016)
			(xy 239.66424 -406.54224) (xy 239.88776 -406.76576) (xy 239.901984 -406.781)
		)
		(stroke
			(width 0)
			(type solid)
		)
		(fill yes)
		(layer "In7.Cu")
		(net "P12V_MAIN_R")
	)
	(gr_poly
		(pts
			(xy 230.38054 -434.93182)
			(arc
				(start 230.38054 -423.4688)
				(mid 230.404693 -423.347284)
				(end 230.473504 -423.244264)
			)
			(arc
				(start 232.983024 -420.734744)
				(mid 233.086056 -420.665963)
				(end 233.20756 -420.64178)
			)
			(xy 270.34998 -420.64178)
			(arc
				(start 275.456396 -415.535364)
				(mid 275.559428 -415.466583)
				(end 275.680932 -415.4424)
			)
			(xy 279.79624 -415.4424) (xy 280.19756 -415.04108) (xy 280.19756 -408.29992) (xy 279.96896 -408.07132)
			(arc
				(start 239.699292 -408.07132)
				(mid 239.577776 -408.047167)
				(end 239.474756 -407.978356)
			)
			(xy 237.61446 -406.11806)
			(arc
				(start 235.520992 -406.11806)
				(mid 235.399476 -406.093907)
				(end 235.296456 -406.025096)
			)
			(arc
				(start 233.973624 -404.702264)
				(mid 233.904843 -404.599232)
				(end 233.88066 -404.477728)
			)
			(xy 233.88066 -401.03298) (xy 233.86542 -401.01774) (xy 230.47706 -401.01774) (xy 230.46182 -401.03298)
			(arc
				(start 230.46182 -404.473156)
				(mid 230.437667 -404.594672)
				(end 230.368856 -404.697692)
			)
			(xy 230.256588 -404.80996)
			(arc
				(start 230.256588 -407.3906)
				(mid 230.232435 -407.512116)
				(end 230.163624 -407.615136)
			)
			(arc
				(start 228.159564 -409.619196)
				(mid 228.056532 -409.687977)
				(end 227.935028 -409.71216)
			)
			(arc
				(start 225.70694 -409.71216)
				(mid 225.585424 -409.688007)
				(end 225.482404 -409.619196)
			)
			(arc
				(start 223.491552 -407.628344)
				(mid 223.422771 -407.525312)
				(end 223.398588 -407.403808)
			)
			(xy 223.398588 -404.79218)
			(arc
				(start 223.310704 -404.704296)
				(mid 223.241923 -404.601264)
				(end 223.21774 -404.47976)
			)
			(xy 223.21774 -401.04568) (xy 223.19234 -401.02028) (xy 219.81414 -401.02028) (xy 219.79636 -401.03806)
			(arc
				(start 219.79636 -404.490936)
				(mid 219.772207 -404.612452)
				(end 219.703396 -404.715472)
			)
			(xy 219.613988 -404.80488)
			(arc
				(start 219.613988 -407.259028)
				(mid 219.589835 -407.380544)
				(end 219.521024 -407.483564)
			)
			(arc
				(start 217.497152 -409.507436)
				(mid 217.39412 -409.576217)
				(end 217.272616 -409.6004)
			)
			(arc
				(start 214.794592 -409.6004)
				(mid 214.673076 -409.576247)
				(end 214.570056 -409.507436)
			)
			(arc
				(start 212.812884 -407.750264)
				(mid 212.744103 -407.647232)
				(end 212.71992 -407.525728)
			)
			(xy 212.71992 -404.79472)
			(arc
				(start 212.635084 -404.709884)
				(mid 212.566303 -404.606852)
				(end 212.54212 -404.485348)
			)
			(xy 212.54212 -401.02536) (xy 212.53704 -401.02028) (xy 209.14106 -401.02028) (xy 209.13598 -401.02536)
			(arc
				(start 209.13598 -404.452836)
				(mid 209.111827 -404.574352)
				(end 209.043016 -404.677372)
			)
			(xy 208.945988 -404.7744)
			(arc
				(start 208.945988 -407.30424)
				(mid 208.921835 -407.425756)
				(end 208.853024 -407.528776)
			)
			(arc
				(start 206.770224 -409.611576)
				(mid 206.667192 -409.680357)
				(end 206.545688 -409.70454)
			)
			(arc
				(start 204.16012 -409.70454)
				(mid 204.038604 -409.680387)
				(end 203.935584 -409.611576)
			)
			(arc
				(start 202.155552 -407.831544)
				(mid 202.086771 -407.728512)
				(end 202.062588 -407.607008)
			)
			(xy 202.062588 -404.779988)
			(arc
				(start 201.969624 -404.687024)
				(mid 201.900843 -404.583992)
				(end 201.87666 -404.462488)
			)
			(xy 201.87666 -401.03298) (xy 201.86396 -401.02028) (xy 198.47306 -401.02028) (xy 198.46798 -401.02536)
			(arc
				(start 198.46798 -404.487888)
				(mid 198.443827 -404.609404)
				(end 198.375016 -404.712424)
			)
			(arc
				(start 197.194424 -405.893016)
				(mid 197.091392 -405.961797)
				(end 196.969888 -405.98598)
			)
			(arc
				(start 190.870332 -405.98598)
				(mid 190.748816 -405.961827)
				(end 190.645796 -405.893016)
			)
			(arc
				(start 189.455552 -404.702518)
				(mid 189.386771 -404.599486)
				(end 189.362588 -404.477982)
			)
			(xy 189.362588 -404.177754) (xy 189.337188 -404.152354)
			(arc
				(start 189.11316 -404.152354)
				(mid 188.991644 -404.128201)
				(end 188.888624 -404.05939)
			)
			(arc
				(start 188.710824 -403.88159)
				(mid 188.642043 -403.778558)
				(end 188.61786 -403.657054)
			)
			(xy 188.61786 -401.02028) (xy 188.600588 -401.002754) (xy 185.196988 -401.002754) (xy 185.196988 -406.489154)
			(arc
				(start 185.434224 -406.72639)
				(mid 185.480227 -406.78458)
				(end 185.51144 -406.851866)
			)
			(arc
				(start 185.51144 -406.851866)
				(mid 185.548193 -406.942536)
				(end 185.560716 -407.039572)
			)
			(arc
				(start 185.560716 -407.039572)
				(mid 185.553298 -407.114694)
				(end 185.531252 -407.186892)
			)
			(xy 185.527188 -407.19629)
			(arc
				(start 185.527188 -408.287982)
				(mid 185.503035 -408.409498)
				(end 185.434224 -408.512518)
			)
			(xy 185.323988 -408.622754) (xy 185.323988 -413.032956) (xy 192.902332 -420.6113)
			(arc
				(start 197.416928 -420.6113)
				(mid 197.538444 -420.635453)
				(end 197.641464 -420.704264)
			)
			(arc
				(start 206.398876 -429.461676)
				(mid 206.467657 -429.564708)
				(end 206.49184 -429.686212)
			)
			(xy 206.49184 -435.39156) (xy 207.63484 -436.53456) (xy 228.7778 -436.53456)
		)
		(stroke
			(width 0)
			(type solid)
		)
		(fill yes)
		(layer "In7.Cu")
		(net "P12V_PSU")
	)
	(gr_poly
		(pts
			(xy 531.7998 -462.520284) (xy 531.855607 -462.519775) (xy 531.96691 -462.511434) (xy 532.077278 -462.494798)
			(xy 532.186094 -462.469962) (xy 532.29275 -462.437062) (xy 532.396649 -462.396285) (xy 532.49721 -462.347857)
			(xy 532.593871 -462.292049) (xy 532.686092 -462.229174) (xy 532.773355 -462.159583) (xy 532.855174 -462.083666)
			(xy 532.931091 -462.001846) (xy 533.000681 -461.914582) (xy 533.063556 -461.822361) (xy 533.119362 -461.7257)
			(xy 533.16779 -461.625138) (xy 533.208566 -461.521239) (xy 533.241465 -461.414583) (xy 533.266301 -461.305766)
			(xy 533.282935 -461.195398) (xy 533.291275 -461.084095) (xy 533.291796 -461.028288) (xy 533.291796 -455.0283)
			(xy 533.291274 -454.972493) (xy 533.282933 -454.861191) (xy 533.266298 -454.750824) (xy 533.241462 -454.642008)
			(xy 533.208563 -454.535353) (xy 533.167786 -454.431454) (xy 533.119358 -454.330893) (xy 533.063551 -454.234233)
			(xy 533.000677 -454.142013) (xy 532.931086 -454.054749) (xy 532.85517 -453.97293) (xy 532.773351 -453.897014)
			(xy 532.686087 -453.827423) (xy 532.593867 -453.764549) (xy 532.497207 -453.708742) (xy 532.396646 -453.660314)
			(xy 532.292747 -453.619537) (xy 532.186092 -453.586638) (xy 532.077276 -453.561802) (xy 531.966909 -453.545167)
			(xy 531.855607 -453.536826) (xy 531.7998 -453.536304) (xy 516.019796 -453.536304) (xy 515.949442 -453.535811)
			(xy 515.808956 -453.527921) (xy 515.669133 -453.512166) (xy 515.530414 -453.488597) (xy 515.393234 -453.457286)
			(xy 515.258026 -453.418334) (xy 515.125215 -453.371861) (xy 514.995218 -453.318014) (xy 514.868445 -453.256963)
			(xy 514.745294 -453.188901) (xy 514.626154 -453.11404) (xy 514.511398 -453.032616) (xy 514.401389 -452.944887)
			(xy 514.296471 -452.851127) (xy 514.196976 -452.751632) (xy 514.103216 -452.646714) (xy 514.015486 -452.536705)
			(xy 513.934063 -452.421949) (xy 513.859201 -452.302809) (xy 513.791138 -452.179659) (xy 513.730087 -452.052886)
			(xy 513.676241 -451.922889) (xy 513.629768 -451.790078) (xy 513.590815 -451.65487) (xy 513.559504 -451.51769)
			(xy 513.535934 -451.378971) (xy 513.520179 -451.239148) (xy 513.512289 -451.098662) (xy 513.5118 -451.028308)
			(xy 513.5118 -312.408316) (xy 513.512284 -312.337962) (xy 513.520173 -312.197474) (xy 513.535926 -312.05765)
			(xy 513.559495 -311.91893) (xy 513.590805 -311.781749) (xy 513.629757 -311.646539) (xy 513.676229 -311.513726)
			(xy 513.730076 -311.383728) (xy 513.791126 -311.256954) (xy 513.859189 -311.133802) (xy 513.93405 -311.01466)
			(xy 514.015474 -310.899903) (xy 514.103203 -310.789893) (xy 514.196964 -310.684974) (xy 514.296459 -310.585477)
			(xy 514.401377 -310.491716) (xy 514.511387 -310.403986) (xy 514.626144 -310.322561) (xy 514.745285 -310.247699)
			(xy 514.868436 -310.179635) (xy 514.99521 -310.118584) (xy 515.125208 -310.064737) (xy 515.25802 -310.018263)
			(xy 515.393229 -309.97931) (xy 515.53041 -309.947999) (xy 515.669131 -309.924429) (xy 515.808954 -309.908674)
			(xy 515.949442 -309.900784) (xy 516.019796 -309.90032) (xy 531.7998 -309.90032) (xy 531.855607 -309.899798)
			(xy 531.96691 -309.891457) (xy 532.077278 -309.874822) (xy 532.186094 -309.849986) (xy 532.292751 -309.817087)
			(xy 532.39665 -309.77631) (xy 532.497211 -309.727883) (xy 532.593873 -309.672076) (xy 532.686094 -309.609202)
			(xy 532.773358 -309.539612) (xy 532.855178 -309.463695) (xy 532.931096 -309.381876) (xy 533.000687 -309.294613)
			(xy 533.063563 -309.202393) (xy 533.119372 -309.105733) (xy 533.167801 -309.005172) (xy 533.208579 -308.901273)
			(xy 533.24148 -308.794618) (xy 533.266318 -308.685802) (xy 533.282955 -308.575434) (xy 533.291297 -308.464131)
			(xy 533.291796 -308.408324) (xy 533.291796 10.40003) (xy 533.291273 10.455836) (xy 533.28293 10.567137)
			(xy 533.266293 10.677502) (xy 533.241455 10.786316) (xy 533.208555 10.89297) (xy 533.167777 10.996866)
			(xy 533.119348 11.097425) (xy 533.063541 11.194084) (xy 533.000666 11.286302) (xy 532.931076 11.373563)
			(xy 532.855159 11.45538) (xy 532.77334 11.531295) (xy 532.686078 11.600884) (xy 532.593858 11.663757)
			(xy 532.497199 11.719562) (xy 532.396639 11.767989) (xy 532.292741 11.808765) (xy 532.186087 11.841663)
			(xy 532.077273 11.866499) (xy 531.966907 11.883134) (xy 531.855606 11.891474) (xy 531.7998 11.892026)
			(xy 475.799912 11.892026) (xy 475.744104 11.891505) (xy 475.632801 11.883165) (xy 475.522432 11.86653)
			(xy 475.413615 11.841695) (xy 475.306958 11.808796) (xy 475.203057 11.76802) (xy 475.102495 11.719593)
			(xy 475.005832 11.663786) (xy 474.91361 11.600912) (xy 474.826345 11.531322) (xy 474.744524 11.455406)
			(xy 474.668605 11.373587) (xy 474.599013 11.286323) (xy 474.536136 11.194103) (xy 474.480327 11.097442)
			(xy 474.431897 10.996881) (xy 474.391117 10.892982) (xy 474.358216 10.786326) (xy 474.333378 10.677509)
			(xy 474.31674 10.567141) (xy 474.308397 10.455838) (xy 474.307916 10.40003) (xy 474.307916 7.335466)
			(xy 526.704041 7.335466) (xy 526.704041 7.464606) (xy 526.711991 7.593501) (xy 526.727861 7.721661)
			(xy 526.75159 7.848602) (xy 526.783089 7.973841) (xy 526.822238 8.096904) (xy 526.868889 8.217323)
			(xy 526.922864 8.334642) (xy 526.983959 8.448416) (xy 527.051942 8.558213) (xy 527.126556 8.663616)
			(xy 527.207517 8.764226) (xy 527.294517 8.859661) (xy 527.387228 8.94956) (xy 527.485298 9.033581)
			(xy 527.588353 9.111405) (xy 527.696004 9.182737) (xy 527.807843 9.247307) (xy 527.923444 9.304869)
			(xy 528.042369 9.355206) (xy 528.164168 9.398126) (xy 528.288378 9.433467) (xy 528.414527 9.461094)
			(xy 528.542139 9.480903) (xy 528.670728 9.492819) (xy 528.799806 9.496796) (xy 528.928884 9.492819)
			(xy 529.057473 9.480903) (xy 529.185085 9.461094) (xy 529.311234 9.433467) (xy 529.435444 9.398126)
			(xy 529.557243 9.355206) (xy 529.676168 9.304869) (xy 529.791769 9.247307) (xy 529.903608 9.182737)
			(xy 530.011259 9.111405) (xy 530.114314 9.033581) (xy 530.212384 8.94956) (xy 530.305095 8.859661)
			(xy 530.392095 8.764226) (xy 530.473056 8.663616) (xy 530.54767 8.558213) (xy 530.615653 8.448416)
			(xy 530.676748 8.334642) (xy 530.730723 8.217323) (xy 530.777374 8.096904) (xy 530.816523 7.973841)
			(xy 530.848022 7.848602) (xy 530.871751 7.721661) (xy 530.887621 7.593501) (xy 530.895571 7.464606)
			(xy 530.896068 7.400036) (xy 530.895571 7.335466) (xy 530.887621 7.206571) (xy 530.871751 7.078411)
			(xy 530.848022 6.95147) (xy 530.816523 6.826231) (xy 530.777374 6.703168) (xy 530.730723 6.582749)
			(xy 530.676748 6.46543) (xy 530.615653 6.351656) (xy 530.54767 6.241859) (xy 530.473056 6.136456)
			(xy 530.392095 6.035846) (xy 530.305095 5.940411) (xy 530.212384 5.850512) (xy 530.114314 5.766491)
			(xy 530.011259 5.688667) (xy 529.903608 5.617335) (xy 529.791769 5.552765) (xy 529.676168 5.495203)
			(xy 529.557243 5.444866) (xy 529.435444 5.401946) (xy 529.311234 5.366605) (xy 529.185085 5.338978)
			(xy 529.057473 5.319169) (xy 528.928884 5.307253) (xy 528.799806 5.303277) (xy 528.670728 5.307253)
			(xy 528.542139 5.319169) (xy 528.414527 5.338978) (xy 528.288378 5.366605) (xy 528.164168 5.401946)
			(xy 528.042369 5.444866) (xy 527.923444 5.495203) (xy 527.807843 5.552765) (xy 527.696004 5.617335)
			(xy 527.588353 5.688667) (xy 527.485298 5.766491) (xy 527.387228 5.850512) (xy 527.294517 5.940411)
			(xy 527.207517 6.035846) (xy 527.126556 6.136456) (xy 527.051942 6.241859) (xy 526.983959 6.351656)
			(xy 526.922864 6.46543) (xy 526.868889 6.582749) (xy 526.822238 6.703168) (xy 526.783089 6.826231)
			(xy 526.75159 6.95147) (xy 526.727861 7.078411) (xy 526.711991 7.206571) (xy 526.704041 7.335466)
			(xy 474.307916 7.335466) (xy 474.307916 -77.67193) (xy 474.307428 -77.765094) (xy 474.299715 -77.951262)
			(xy 474.284317 -78.136953) (xy 474.261258 -78.321849) (xy 474.23058 -78.505634) (xy 474.192333 -78.687994)
			(xy 474.146584 -78.868619) (xy 474.093411 -79.047199) (xy 474.032904 -79.223429) (xy 473.965167 -79.397008)
			(xy 473.890315 -79.56764) (xy 473.808477 -79.735034) (xy 473.719792 -79.898903) (xy 473.624411 -80.058968)
			(xy 473.522498 -80.214955) (xy 473.414227 -80.366597) (xy 473.299782 -80.513637) (xy 473.17936 -80.655821)
			(xy 473.053165 -80.792909) (xy 472.987624 -80.859122) (xy 471.245184 -82.601562) (xy 471.207836 -82.63956)
			(xy 471.138049 -82.720082) (xy 471.074185 -82.805378) (xy 471.01657 -82.895014) (xy 470.965496 -82.988531)
			(xy 470.921226 -83.085455) (xy 470.883983 -83.18529) (xy 470.853958 -83.287527) (xy 470.831304 -83.391646)
			(xy 470.816136 -83.497117) (xy 470.808532 -83.6034) (xy 470.80805 -83.656678) (xy 470.80805 -404.871936)
			(xy 470.807562 -404.9651) (xy 470.799849 -405.151268) (xy 470.78445 -405.336959) (xy 470.761392 -405.521855)
			(xy 470.730713 -405.70564) (xy 470.692467 -405.888001) (xy 470.646718 -406.068625) (xy 470.593544 -406.247205)
			(xy 470.533038 -406.423435) (xy 470.465301 -406.597015) (xy 470.39045 -406.767647) (xy 470.308612 -406.935041)
			(xy 470.219927 -407.098911) (xy 470.124547 -407.258976) (xy 470.022634 -407.414963) (xy 469.914363 -407.566606)
			(xy 469.799919 -407.713645) (xy 469.679497 -407.855831) (xy 469.553302 -407.992919) (xy 469.487758 -408.059128)
			(xy 468.244936 -409.30195) (xy 468.207612 -409.339964) (xy 468.137859 -409.4205) (xy 468.074028 -409.505805)
			(xy 468.016443 -409.595446) (xy 467.965398 -409.688966) (xy 467.921153 -409.785888) (xy 467.883933 -409.885719)
			(xy 467.853928 -409.98795) (xy 467.831291 -410.092061) (xy 467.816137 -410.197522) (xy 467.808543 -410.303794)
			(xy 467.808056 -410.357066) (xy 467.808056 -439.989976) (xy 467.808577 -440.045784) (xy 467.816916 -440.157089)
			(xy 467.83355 -440.267459) (xy 467.858385 -440.376277) (xy 467.891282 -440.482936) (xy 467.932058 -440.586837)
			(xy 467.980485 -440.687401) (xy 468.036291 -440.784065) (xy 468.099165 -440.876289) (xy 468.168754 -440.963556)
			(xy 468.244671 -441.045378) (xy 468.32649 -441.121299) (xy 468.413753 -441.190893) (xy 468.505974 -441.253771)
			(xy 468.602635 -441.309582) (xy 468.703197 -441.358013) (xy 468.807096 -441.398794) (xy 468.913753 -441.431697)
			(xy 469.02257 -441.456537) (xy 469.13294 -441.473176) (xy 469.244244 -441.48152) (xy 469.300052 -441.481972)
			(xy 471.79992 -441.481972) (xy 471.870274 -441.482466) (xy 472.01076 -441.490356) (xy 472.150582 -441.506112)
			(xy 472.289302 -441.529682) (xy 472.426481 -441.560993) (xy 472.561689 -441.599946) (xy 472.6945 -441.646419)
			(xy 472.824497 -441.700266) (xy 472.95127 -441.761317) (xy 473.07442 -441.82938) (xy 473.19356 -441.904241)
			(xy 473.308316 -441.985664) (xy 473.418325 -442.073394) (xy 473.523243 -442.167153) (xy 473.622738 -442.266648)
			(xy 473.716499 -442.371565) (xy 473.804229 -442.481575) (xy 473.885652 -442.59633) (xy 473.960514 -442.71547)
			(xy 474.028578 -442.83862) (xy 474.089629 -442.965392) (xy 474.143476 -443.095389) (xy 474.18995 -443.2282)
			(xy 474.228904 -443.363407) (xy 474.260216 -443.500587) (xy 474.283787 -443.639306) (xy 474.299543 -443.779128)
			(xy 474.307434 -443.919614) (xy 474.307916 -443.989968) (xy 474.307916 -458.092864) (xy 526.704041 -458.092864)
			(xy 526.704041 -457.963724) (xy 526.711991 -457.834829) (xy 526.727861 -457.706669) (xy 526.75159 -457.579728)
			(xy 526.783089 -457.454489) (xy 526.822238 -457.331426) (xy 526.868889 -457.211007) (xy 526.922864 -457.093688)
			(xy 526.983959 -456.979914) (xy 527.051942 -456.870117) (xy 527.126556 -456.764714) (xy 527.207517 -456.664104)
			(xy 527.294517 -456.568669) (xy 527.387228 -456.47877) (xy 527.485298 -456.394749) (xy 527.588353 -456.316925)
			(xy 527.696004 -456.245593) (xy 527.807843 -456.181023) (xy 527.923444 -456.123461) (xy 528.042369 -456.073124)
			(xy 528.164168 -456.030204) (xy 528.288378 -455.994863) (xy 528.414527 -455.967236) (xy 528.542139 -455.947427)
			(xy 528.670728 -455.935511) (xy 528.799806 -455.931535) (xy 528.928884 -455.935511) (xy 529.057473 -455.947427)
			(xy 529.185085 -455.967236) (xy 529.311234 -455.994863) (xy 529.435444 -456.030204) (xy 529.557243 -456.073124)
			(xy 529.676168 -456.123461) (xy 529.791769 -456.181023) (xy 529.903608 -456.245593) (xy 530.011259 -456.316925)
			(xy 530.114314 -456.394749) (xy 530.212384 -456.47877) (xy 530.305095 -456.568669) (xy 530.392095 -456.664104)
			(xy 530.473056 -456.764714) (xy 530.54767 -456.870117) (xy 530.615653 -456.979914) (xy 530.676748 -457.093688)
			(xy 530.730723 -457.211007) (xy 530.777374 -457.331426) (xy 530.816523 -457.454489) (xy 530.848022 -457.579728)
			(xy 530.871751 -457.706669) (xy 530.887621 -457.834829) (xy 530.895571 -457.963724) (xy 530.896068 -458.028294)
			(xy 530.895571 -458.092864) (xy 530.887621 -458.221759) (xy 530.871751 -458.349919) (xy 530.848022 -458.47686)
			(xy 530.816523 -458.602099) (xy 530.777374 -458.725162) (xy 530.730723 -458.845581) (xy 530.676748 -458.9629)
			(xy 530.615653 -459.076674) (xy 530.54767 -459.186471) (xy 530.473056 -459.291874) (xy 530.392095 -459.392484)
			(xy 530.305095 -459.487919) (xy 530.212384 -459.577818) (xy 530.114314 -459.661839) (xy 530.011259 -459.739663)
			(xy 529.903608 -459.810995) (xy 529.791769 -459.875565) (xy 529.676168 -459.933127) (xy 529.557243 -459.983464)
			(xy 529.435444 -460.026384) (xy 529.311234 -460.061725) (xy 529.185085 -460.089352) (xy 529.057473 -460.109161)
			(xy 528.928884 -460.121077) (xy 528.799806 -460.125054) (xy 528.670728 -460.121077) (xy 528.542139 -460.109161)
			(xy 528.414527 -460.089352) (xy 528.288378 -460.061725) (xy 528.164168 -460.026384) (xy 528.042369 -459.983464)
			(xy 527.923444 -459.933127) (xy 527.807843 -459.875565) (xy 527.696004 -459.810995) (xy 527.588353 -459.739663)
			(xy 527.485298 -459.661839) (xy 527.387228 -459.577818) (xy 527.294517 -459.487919) (xy 527.207517 -459.392484)
			(xy 527.126556 -459.291874) (xy 527.051942 -459.186471) (xy 526.983959 -459.076674) (xy 526.922864 -458.9629)
			(xy 526.868889 -458.845581) (xy 526.822238 -458.725162) (xy 526.783089 -458.602099) (xy 526.75159 -458.47686)
			(xy 526.727861 -458.349919) (xy 526.711991 -458.221759) (xy 526.704041 -458.092864) (xy 474.307916 -458.092864)
			(xy 474.307916 -461.028288) (xy 474.308425 -461.084096) (xy 474.316765 -461.195399) (xy 474.3334 -461.305768)
			(xy 474.358236 -461.414584) (xy 474.391134 -461.521241) (xy 474.431912 -461.625141) (xy 474.480339 -461.725703)
			(xy 474.536147 -461.822365) (xy 474.599022 -461.914586) (xy 474.668612 -462.00185) (xy 474.74453 -462.08367)
			(xy 474.82635 -462.159588) (xy 474.913614 -462.229178) (xy 475.005835 -462.292053) (xy 475.102497 -462.347861)
			(xy 475.203059 -462.396288) (xy 475.306959 -462.437066) (xy 475.413616 -462.469964) (xy 475.522432 -462.4948)
			(xy 475.632801 -462.511435) (xy 475.744104 -462.519775) (xy 475.799912 -462.520284)
		)
		(stroke
			(width 0)
			(type solid)
		)
		(fill yes)
		(layer "In7.Cu")
		(net "T1_GND")
	)
	(gr_poly
		(pts
			(xy 256.292096 -31.120588) (xy 256.292096 -11.780012) (xy 256.29258 -11.709658) (xy 256.300469 -11.56917)
			(xy 256.316223 -11.429347) (xy 256.339792 -11.290626) (xy 256.371101 -11.153445) (xy 256.410054 -11.018236)
			(xy 256.456527 -10.885423) (xy 256.510373 -10.755425) (xy 256.571423 -10.628651) (xy 256.639486 -10.505499)
			(xy 256.714347 -10.386357) (xy 256.795771 -10.2716) (xy 256.883501 -10.16159) (xy 256.977261 -10.056671)
			(xy 257.076757 -9.957175) (xy 257.181674 -9.863414) (xy 257.291684 -9.775683) (xy 257.406441 -9.694258)
			(xy 257.525582 -9.619396) (xy 257.648733 -9.551333) (xy 257.775507 -9.490281) (xy 257.905504 -9.436434)
			(xy 258.038317 -9.38996) (xy 258.173526 -9.351006) (xy 258.310706 -9.319695) (xy 258.449427 -9.296125)
			(xy 258.589251 -9.280371) (xy 258.729738 -9.272481) (xy 258.800092 -9.272016) (xy 383.601976 -9.272016)
			(xy 383.657784 -9.271508) (xy 383.769089 -9.263168) (xy 383.879459 -9.246534) (xy 383.988278 -9.221699)
			(xy 384.094936 -9.188801) (xy 384.198838 -9.148025) (xy 384.299402 -9.099598) (xy 384.396066 -9.043791)
			(xy 384.488289 -8.980916) (xy 384.575555 -8.911326) (xy 384.657377 -8.835408) (xy 384.733297 -8.753588)
			(xy 384.80289 -8.666324) (xy 384.865767 -8.574103) (xy 384.921577 -8.477441) (xy 384.970007 -8.376878)
			(xy 385.010787 -8.272978) (xy 385.043688 -8.16632) (xy 385.068526 -8.057503) (xy 385.085163 -7.947133)
			(xy 385.093506 -7.835828) (xy 385.093972 -7.78002) (xy 385.093972 0.999998) (xy 385.094465 1.070352)
			(xy 385.102355 1.210839) (xy 385.118109 1.350662) (xy 385.141678 1.489383) (xy 385.172988 1.626563)
			(xy 385.211941 1.761772) (xy 385.258413 1.894584) (xy 385.312259 2.024582) (xy 385.37331 2.151356)
			(xy 385.441373 2.274507) (xy 385.516233 2.393649) (xy 385.597656 2.508405) (xy 385.685386 2.618416)
			(xy 385.779146 2.723335) (xy 385.878641 2.822831) (xy 385.983558 2.916592) (xy 386.093567 3.004323)
			(xy 386.208323 3.085748) (xy 386.327463 3.16061) (xy 386.450614 3.228674) (xy 386.577387 3.289727)
			(xy 386.707384 3.343575) (xy 386.840195 3.390049) (xy 386.975404 3.429003) (xy 387.112584 3.460315)
			(xy 387.251304 3.483887) (xy 387.391127 3.499643) (xy 387.531614 3.507534) (xy 387.601968 3.507994)
			(xy 456.202034 3.507994) (xy 456.272387 3.5075) (xy 456.412872 3.499608) (xy 456.552693 3.483853)
			(xy 456.691411 3.460282) (xy 456.828589 3.42897) (xy 456.963796 3.390016) (xy 457.096605 3.343542)
			(xy 457.226601 3.289695) (xy 457.353372 3.228644) (xy 457.476521 3.16058) (xy 457.595659 3.085719)
			(xy 457.710413 3.004295) (xy 457.820421 2.916565) (xy 457.925337 2.822806) (xy 458.02483 2.723311)
			(xy 458.118589 2.618393) (xy 458.206317 2.508384) (xy 458.287739 2.393629) (xy 458.362598 2.27449)
			(xy 458.43066 2.15134) (xy 458.49171 2.024568) (xy 458.545555 1.894572) (xy 458.592027 1.761761)
			(xy 458.630979 1.626554) (xy 458.662289 1.489376) (xy 458.685858 1.350658) (xy 458.701612 1.210836)
			(xy 458.709501 1.070351) (xy 458.71003 0.999998) (xy 458.71003 -7.78002) (xy 458.71054 -7.835827)
			(xy 458.718882 -7.947128) (xy 458.735519 -8.057494) (xy 458.760357 -8.166309) (xy 458.793257 -8.272963)
			(xy 458.834035 -8.37686) (xy 458.882464 -8.47742) (xy 458.938272 -8.574079) (xy 459.001148 -8.666297)
			(xy 459.070739 -8.753559) (xy 459.146656 -8.835376) (xy 459.228476 -8.911291) (xy 459.31574 -8.98088)
			(xy 459.40796 -9.043752) (xy 459.504621 -9.099557) (xy 459.605182 -9.147983) (xy 459.70908 -9.188758)
			(xy 459.815736 -9.221655) (xy 459.924551 -9.24649) (xy 460.034918 -9.263123) (xy 460.146219 -9.271462)
			(xy 460.202026 -9.272016) (xy 464.327748 -9.272016) (xy 464.332574 -9.271) (xy 464.357024 -9.266474)
			(xy 464.406516 -9.261643) (xy 464.43138 -9.261348) (xy 464.456244 -9.26164) (xy 464.505735 -9.266479)
			(xy 464.530186 -9.271) (xy 464.535012 -9.272016) (xy 469.799924 -9.272016) (xy 469.855731 -9.271493)
			(xy 469.967032 -9.263151) (xy 470.077399 -9.246514) (xy 470.186213 -9.221677) (xy 470.292868 -9.188777)
			(xy 470.396765 -9.147999) (xy 470.497325 -9.099571) (xy 470.593985 -9.043764) (xy 470.686204 -8.980889)
			(xy 470.773467 -8.911299) (xy 470.855285 -8.835382) (xy 470.931202 -8.753564) (xy 471.000791 -8.666301)
			(xy 471.063666 -8.574082) (xy 471.119473 -8.477422) (xy 471.167901 -8.376862) (xy 471.208678 -8.272964)
			(xy 471.241578 -8.166309) (xy 471.266415 -8.057495) (xy 471.283051 -7.947128) (xy 471.291394 -7.835827)
			(xy 471.29192 -7.78002) (xy 471.29192 10.40003) (xy 471.291397 10.455837) (xy 471.283054 10.567138)
			(xy 471.266417 10.677504) (xy 471.241579 10.786319) (xy 471.208679 10.892973) (xy 471.167901 10.99687)
			(xy 471.119473 11.09743) (xy 471.063666 11.194089) (xy 471.000791 11.286308) (xy 470.931201 11.373571)
			(xy 470.855284 11.455389) (xy 470.773466 11.531305) (xy 470.686203 11.600895) (xy 470.593984 11.663769)
			(xy 470.497324 11.719576) (xy 470.396765 11.768004) (xy 470.292867 11.808781) (xy 470.186213 11.841681)
			(xy 470.077398 11.866518) (xy 469.967032 11.883155) (xy 469.855731 11.891497) (xy 469.799924 11.892026)
			(xy 1.999996 11.892026) (xy 1.944189 11.891504) (xy 1.832887 11.883163) (xy 1.72252 11.866527) (xy 1.613705 11.841691)
			(xy 1.50705 11.808792) (xy 1.403151 11.768014) (xy 1.302591 11.719587) (xy 1.20593 11.66378) (xy 1.113711 11.600905)
			(xy 1.026448 11.531315) (xy 0.944629 11.455398) (xy 0.868712 11.373579) (xy 0.799122 11.286316) (xy 0.736248 11.194096)
			(xy 0.680441 11.097436) (xy 0.632014 10.996875) (xy 0.591237 10.892977) (xy 0.558338 10.786321) (xy 0.533502 10.677506)
			(xy 0.516867 10.567139) (xy 0.508526 10.455837) (xy 0.508 10.40003) (xy 0.508 7.335466) (xy 2.904225 7.335466)
			(xy 2.904225 7.464606) (xy 2.912175 7.593501) (xy 2.928045 7.721661) (xy 2.951774 7.848602) (xy 2.983273 7.973841)
			(xy 3.022422 8.096904) (xy 3.069073 8.217323) (xy 3.123048 8.334642) (xy 3.184143 8.448416) (xy 3.252126 8.558213)
			(xy 3.32674 8.663616) (xy 3.407701 8.764226) (xy 3.494701 8.859661) (xy 3.587412 8.94956) (xy 3.685482 9.033581)
			(xy 3.788537 9.111405) (xy 3.896188 9.182737) (xy 4.008027 9.247307) (xy 4.123628 9.304869) (xy 4.242553 9.355206)
			(xy 4.364352 9.398126) (xy 4.488562 9.433467) (xy 4.614711 9.461094) (xy 4.742323 9.480903) (xy 4.870912 9.492819)
			(xy 4.99999 9.496796) (xy 5.129068 9.492819) (xy 5.257657 9.480903) (xy 5.385269 9.461094) (xy 5.511418 9.433467)
			(xy 5.635628 9.398126) (xy 5.757427 9.355206) (xy 5.876352 9.304869) (xy 5.991953 9.247307) (xy 6.020338 9.230919)
			(xy 256.921241 9.230919) (xy 256.921241 9.316669) (xy 256.929153 9.402052) (xy 256.944909 9.486342)
			(xy 256.968376 9.568818) (xy 256.999352 9.648777) (xy 257.037574 9.725537) (xy 257.082715 9.798443)
			(xy 257.134391 9.866872) (xy 257.19216 9.930242) (xy 257.25553 9.988011) (xy 257.323959 10.039687)
			(xy 257.396865 10.084828) (xy 257.473625 10.12305) (xy 257.553584 10.154026) (xy 257.63606 10.177493)
			(xy 257.72035 10.193249) (xy 257.805733 10.201161) (xy 257.891483 10.201161) (xy 257.976866 10.193249)
			(xy 258.061156 10.177493) (xy 258.143632 10.154026) (xy 258.223591 10.12305) (xy 258.300351 10.084828)
			(xy 258.373257 10.039687) (xy 258.441686 9.988011) (xy 258.505056 9.930242) (xy 258.562825 9.866872)
			(xy 258.614501 9.798443) (xy 258.659642 9.725537) (xy 258.697864 9.648777) (xy 258.72884 9.568818)
			(xy 258.752307 9.486342) (xy 258.768063 9.402052) (xy 258.775975 9.316669) (xy 258.77647 9.273794)
			(xy 258.775975 9.230919) (xy 263.271241 9.230919) (xy 263.271241 9.316669) (xy 263.279153 9.402052)
			(xy 263.294909 9.486342) (xy 263.318376 9.568818) (xy 263.349352 9.648777) (xy 263.387574 9.725537)
			(xy 263.432715 9.798443) (xy 263.484391 9.866872) (xy 263.54216 9.930242) (xy 263.60553 9.988011)
			(xy 263.673959 10.039687) (xy 263.746865 10.084828) (xy 263.823625 10.12305) (xy 263.903584 10.154026)
			(xy 263.98606 10.177493) (xy 264.07035 10.193249) (xy 264.155733 10.201161) (xy 264.241483 10.201161)
			(xy 264.326866 10.193249) (xy 264.411156 10.177493) (xy 264.493632 10.154026) (xy 264.573591 10.12305)
			(xy 264.650351 10.084828) (xy 264.723257 10.039687) (xy 264.791686 9.988011) (xy 264.855056 9.930242)
			(xy 264.912825 9.866872) (xy 264.964501 9.798443) (xy 265.009642 9.725537) (xy 265.047864 9.648777)
			(xy 265.07884 9.568818) (xy 265.102307 9.486342) (xy 265.118063 9.402052) (xy 265.125975 9.316669)
			(xy 265.12647 9.273794) (xy 265.125975 9.230919) (xy 324.845921 9.230919) (xy 324.845921 9.316669)
			(xy 324.853833 9.402052) (xy 324.869589 9.486342) (xy 324.893056 9.568818) (xy 324.924032 9.648777)
			(xy 324.962254 9.725537) (xy 325.007395 9.798443) (xy 325.059071 9.866872) (xy 325.11684 9.930242)
			(xy 325.18021 9.988011) (xy 325.248639 10.039687) (xy 325.321545 10.084828) (xy 325.398305 10.12305)
			(xy 325.478264 10.154026) (xy 325.56074 10.177493) (xy 325.64503 10.193249) (xy 325.730413 10.201161)
			(xy 325.816163 10.201161) (xy 325.901546 10.193249) (xy 325.985836 10.177493) (xy 326.068312 10.154026)
			(xy 326.148271 10.12305) (xy 326.225031 10.084828) (xy 326.297937 10.039687) (xy 326.366366 9.988011)
			(xy 326.429736 9.930242) (xy 326.487505 9.866872) (xy 326.539181 9.798443) (xy 326.584322 9.725537)
			(xy 326.622544 9.648777) (xy 326.65352 9.568818) (xy 326.676987 9.486342) (xy 326.692743 9.402052)
			(xy 326.700655 9.316669) (xy 326.70115 9.273794) (xy 326.700655 9.230919) (xy 331.195921 9.230919)
			(xy 331.195921 9.316669) (xy 331.203833 9.402052) (xy 331.219589 9.486342) (xy 331.243056 9.568818)
			(xy 331.274032 9.648777) (xy 331.312254 9.725537) (xy 331.357395 9.798443) (xy 331.409071 9.866872)
			(xy 331.46684 9.930242) (xy 331.53021 9.988011) (xy 331.598639 10.039687) (xy 331.671545 10.084828)
			(xy 331.748305 10.12305) (xy 331.828264 10.154026) (xy 331.91074 10.177493) (xy 331.99503 10.193249)
			(xy 332.080413 10.201161) (xy 332.166163 10.201161) (xy 332.251546 10.193249) (xy 332.335836 10.177493)
			(xy 332.418312 10.154026) (xy 332.498271 10.12305) (xy 332.575031 10.084828) (xy 332.647937 10.039687)
			(xy 332.716366 9.988011) (xy 332.779736 9.930242) (xy 332.837505 9.866872) (xy 332.889181 9.798443)
			(xy 332.934322 9.725537) (xy 332.972544 9.648777) (xy 333.00352 9.568818) (xy 333.026987 9.486342)
			(xy 333.042743 9.402052) (xy 333.050655 9.316669) (xy 333.05115 9.273794) (xy 333.050655 9.230919)
			(xy 335.488267 9.230919) (xy 335.488267 9.316669) (xy 335.496179 9.402052) (xy 335.511935 9.486342)
			(xy 335.535402 9.568818) (xy 335.566378 9.648777) (xy 335.6046 9.725537) (xy 335.649741 9.798443)
			(xy 335.701417 9.866872) (xy 335.759186 9.930242) (xy 335.822556 9.988011) (xy 335.890985 10.039687)
			(xy 335.963891 10.084828) (xy 336.040651 10.12305) (xy 336.12061 10.154026) (xy 336.203086 10.177493)
			(xy 336.287376 10.193249) (xy 336.372759 10.201161) (xy 336.458509 10.201161) (xy 336.543892 10.193249)
			(xy 336.628182 10.177493) (xy 336.710658 10.154026) (xy 336.790617 10.12305) (xy 336.867377 10.084828)
			(xy 336.940283 10.039687) (xy 337.008712 9.988011) (xy 337.072082 9.930242) (xy 337.129851 9.866872)
			(xy 337.181527 9.798443) (xy 337.226668 9.725537) (xy 337.26489 9.648777) (xy 337.295866 9.568818)
			(xy 337.319333 9.486342) (xy 337.335089 9.402052) (xy 337.343001 9.316669) (xy 337.343496 9.273794)
			(xy 337.343001 9.230919) (xy 341.838267 9.230919) (xy 341.838267 9.316669) (xy 341.846179 9.402052)
			(xy 341.861935 9.486342) (xy 341.885402 9.568818) (xy 341.916378 9.648777) (xy 341.9546 9.725537)
			(xy 341.999741 9.798443) (xy 342.051417 9.866872) (xy 342.109186 9.930242) (xy 342.172556 9.988011)
			(xy 342.240985 10.039687) (xy 342.313891 10.084828) (xy 342.390651 10.12305) (xy 342.47061 10.154026)
			(xy 342.553086 10.177493) (xy 342.637376 10.193249) (xy 342.722759 10.201161) (xy 342.808509 10.201161)
			(xy 342.893892 10.193249) (xy 342.978182 10.177493) (xy 343.060658 10.154026) (xy 343.140617 10.12305)
			(xy 343.217377 10.084828) (xy 343.290283 10.039687) (xy 343.358712 9.988011) (xy 343.422082 9.930242)
			(xy 343.479851 9.866872) (xy 343.531527 9.798443) (xy 343.576668 9.725537) (xy 343.61489 9.648777)
			(xy 343.645866 9.568818) (xy 343.669333 9.486342) (xy 343.685089 9.402052) (xy 343.693001 9.316669)
			(xy 343.693496 9.273794) (xy 343.693001 9.230919) (xy 373.705107 9.230919) (xy 373.705107 9.316669)
			(xy 373.713019 9.402052) (xy 373.728775 9.486342) (xy 373.752242 9.568818) (xy 373.783218 9.648777)
			(xy 373.82144 9.725537) (xy 373.866581 9.798443) (xy 373.918257 9.866872) (xy 373.976026 9.930242)
			(xy 374.039396 9.988011) (xy 374.107825 10.039687) (xy 374.180731 10.084828) (xy 374.257491 10.12305)
			(xy 374.33745 10.154026) (xy 374.419926 10.177493) (xy 374.504216 10.193249) (xy 374.589599 10.201161)
			(xy 374.675349 10.201161) (xy 374.760732 10.193249) (xy 374.845022 10.177493) (xy 374.927498 10.154026)
			(xy 375.007457 10.12305) (xy 375.084217 10.084828) (xy 375.157123 10.039687) (xy 375.225552 9.988011)
			(xy 375.288922 9.930242) (xy 375.346691 9.866872) (xy 375.398367 9.798443) (xy 375.443508 9.725537)
			(xy 375.48173 9.648777) (xy 375.512706 9.568818) (xy 375.536173 9.486342) (xy 375.551929 9.402052)
			(xy 375.559841 9.316669) (xy 375.560336 9.273794) (xy 375.559841 9.230919) (xy 380.055107 9.230919)
			(xy 380.055107 9.316669) (xy 380.063019 9.402052) (xy 380.078775 9.486342) (xy 380.102242 9.568818)
			(xy 380.133218 9.648777) (xy 380.17144 9.725537) (xy 380.216581 9.798443) (xy 380.268257 9.866872)
			(xy 380.326026 9.930242) (xy 380.389396 9.988011) (xy 380.457825 10.039687) (xy 380.530731 10.084828)
			(xy 380.607491 10.12305) (xy 380.68745 10.154026) (xy 380.769926 10.177493) (xy 380.854216 10.193249)
			(xy 380.939599 10.201161) (xy 381.025349 10.201161) (xy 381.110732 10.193249) (xy 381.195022 10.177493)
			(xy 381.277498 10.154026) (xy 381.357457 10.12305) (xy 381.434217 10.084828) (xy 381.507123 10.039687)
			(xy 381.575552 9.988011) (xy 381.638922 9.930242) (xy 381.696691 9.866872) (xy 381.748367 9.798443)
			(xy 381.793508 9.725537) (xy 381.83173 9.648777) (xy 381.862706 9.568818) (xy 381.886173 9.486342)
			(xy 381.901929 9.402052) (xy 381.909841 9.316669) (xy 381.910336 9.273794) (xy 381.909841 9.230919)
			(xy 381.901929 9.145536) (xy 381.886173 9.061246) (xy 381.862706 8.97877) (xy 381.83173 8.898811)
			(xy 381.793508 8.822051) (xy 381.748367 8.749145) (xy 381.696691 8.680716) (xy 381.638922 8.617346)
			(xy 381.575552 8.559577) (xy 381.507123 8.507901) (xy 381.434217 8.46276) (xy 381.357457 8.424538)
			(xy 381.277498 8.393562) (xy 381.195022 8.370095) (xy 381.110732 8.354339) (xy 381.025349 8.346427)
			(xy 380.939599 8.346427) (xy 380.854216 8.354339) (xy 380.769926 8.370095) (xy 380.68745 8.393562)
			(xy 380.607491 8.424538) (xy 380.530731 8.46276) (xy 380.457825 8.507901) (xy 380.389396 8.559577)
			(xy 380.326026 8.617346) (xy 380.268257 8.680716) (xy 380.216581 8.749145) (xy 380.17144 8.822051)
			(xy 380.133218 8.898811) (xy 380.102242 8.97877) (xy 380.078775 9.061246) (xy 380.063019 9.145536)
			(xy 380.055107 9.230919) (xy 375.559841 9.230919) (xy 375.551929 9.145536) (xy 375.536173 9.061246)
			(xy 375.512706 8.97877) (xy 375.48173 8.898811) (xy 375.443508 8.822051) (xy 375.398367 8.749145)
			(xy 375.346691 8.680716) (xy 375.288922 8.617346) (xy 375.225552 8.559577) (xy 375.157123 8.507901)
			(xy 375.084217 8.46276) (xy 375.007457 8.424538) (xy 374.927498 8.393562) (xy 374.845022 8.370095)
			(xy 374.760732 8.354339) (xy 374.675349 8.346427) (xy 374.589599 8.346427) (xy 374.504216 8.354339)
			(xy 374.419926 8.370095) (xy 374.33745 8.393562) (xy 374.257491 8.424538) (xy 374.180731 8.46276)
			(xy 374.107825 8.507901) (xy 374.039396 8.559577) (xy 373.976026 8.617346) (xy 373.918257 8.680716)
			(xy 373.866581 8.749145) (xy 373.82144 8.822051) (xy 373.783218 8.898811) (xy 373.752242 8.97877)
			(xy 373.728775 9.061246) (xy 373.713019 9.145536) (xy 373.705107 9.230919) (xy 343.693001 9.230919)
			(xy 343.685089 9.145536) (xy 343.669333 9.061246) (xy 343.645866 8.97877) (xy 343.61489 8.898811)
			(xy 343.576668 8.822051) (xy 343.531527 8.749145) (xy 343.479851 8.680716) (xy 343.422082 8.617346)
			(xy 343.358712 8.559577) (xy 343.290283 8.507901) (xy 343.217377 8.46276) (xy 343.140617 8.424538)
			(xy 343.060658 8.393562) (xy 342.978182 8.370095) (xy 342.893892 8.354339) (xy 342.808509 8.346427)
			(xy 342.722759 8.346427) (xy 342.637376 8.354339) (xy 342.553086 8.370095) (xy 342.47061 8.393562)
			(xy 342.390651 8.424538) (xy 342.313891 8.46276) (xy 342.240985 8.507901) (xy 342.172556 8.559577)
			(xy 342.109186 8.617346) (xy 342.051417 8.680716) (xy 341.999741 8.749145) (xy 341.9546 8.822051)
			(xy 341.916378 8.898811) (xy 341.885402 8.97877) (xy 341.861935 9.061246) (xy 341.846179 9.145536)
			(xy 341.838267 9.230919) (xy 337.343001 9.230919) (xy 337.335089 9.145536) (xy 337.319333 9.061246)
			(xy 337.295866 8.97877) (xy 337.26489 8.898811) (xy 337.226668 8.822051) (xy 337.181527 8.749145)
			(xy 337.129851 8.680716) (xy 337.072082 8.617346) (xy 337.008712 8.559577) (xy 336.940283 8.507901)
			(xy 336.867377 8.46276) (xy 336.790617 8.424538) (xy 336.710658 8.393562) (xy 336.628182 8.370095)
			(xy 336.543892 8.354339) (xy 336.458509 8.346427) (xy 336.372759 8.346427) (xy 336.287376 8.354339)
			(xy 336.203086 8.370095) (xy 336.12061 8.393562) (xy 336.040651 8.424538) (xy 335.963891 8.46276)
			(xy 335.890985 8.507901) (xy 335.822556 8.559577) (xy 335.759186 8.617346) (xy 335.701417 8.680716)
			(xy 335.649741 8.749145) (xy 335.6046 8.822051) (xy 335.566378 8.898811) (xy 335.535402 8.97877)
			(xy 335.511935 9.061246) (xy 335.496179 9.145536) (xy 335.488267 9.230919) (xy 333.050655 9.230919)
			(xy 333.042743 9.145536) (xy 333.026987 9.061246) (xy 333.00352 8.97877) (xy 332.972544 8.898811)
			(xy 332.934322 8.822051) (xy 332.889181 8.749145) (xy 332.837505 8.680716) (xy 332.779736 8.617346)
			(xy 332.716366 8.559577) (xy 332.647937 8.507901) (xy 332.575031 8.46276) (xy 332.498271 8.424538)
			(xy 332.418312 8.393562) (xy 332.335836 8.370095) (xy 332.251546 8.354339) (xy 332.166163 8.346427)
			(xy 332.080413 8.346427) (xy 331.99503 8.354339) (xy 331.91074 8.370095) (xy 331.828264 8.393562)
			(xy 331.748305 8.424538) (xy 331.671545 8.46276) (xy 331.598639 8.507901) (xy 331.53021 8.559577)
			(xy 331.46684 8.617346) (xy 331.409071 8.680716) (xy 331.357395 8.749145) (xy 331.312254 8.822051)
			(xy 331.274032 8.898811) (xy 331.243056 8.97877) (xy 331.219589 9.061246) (xy 331.203833 9.145536)
			(xy 331.195921 9.230919) (xy 326.700655 9.230919) (xy 326.692743 9.145536) (xy 326.676987 9.061246)
			(xy 326.65352 8.97877) (xy 326.622544 8.898811) (xy 326.584322 8.822051) (xy 326.539181 8.749145)
			(xy 326.487505 8.680716) (xy 326.429736 8.617346) (xy 326.366366 8.559577) (xy 326.297937 8.507901)
			(xy 326.225031 8.46276) (xy 326.148271 8.424538) (xy 326.068312 8.393562) (xy 325.985836 8.370095)
			(xy 325.901546 8.354339) (xy 325.816163 8.346427) (xy 325.730413 8.346427) (xy 325.64503 8.354339)
			(xy 325.56074 8.370095) (xy 325.478264 8.393562) (xy 325.398305 8.424538) (xy 325.321545 8.46276)
			(xy 325.248639 8.507901) (xy 325.18021 8.559577) (xy 325.11684 8.617346) (xy 325.059071 8.680716)
			(xy 325.007395 8.749145) (xy 324.962254 8.822051) (xy 324.924032 8.898811) (xy 324.893056 8.97877)
			(xy 324.869589 9.061246) (xy 324.853833 9.145536) (xy 324.845921 9.230919) (xy 265.125975 9.230919)
			(xy 265.118063 9.145536) (xy 265.102307 9.061246) (xy 265.07884 8.97877) (xy 265.047864 8.898811)
			(xy 265.009642 8.822051) (xy 264.964501 8.749145) (xy 264.912825 8.680716) (xy 264.855056 8.617346)
			(xy 264.791686 8.559577) (xy 264.723257 8.507901) (xy 264.650351 8.46276) (xy 264.573591 8.424538)
			(xy 264.493632 8.393562) (xy 264.411156 8.370095) (xy 264.326866 8.354339) (xy 264.241483 8.346427)
			(xy 264.155733 8.346427) (xy 264.07035 8.354339) (xy 263.98606 8.370095) (xy 263.903584 8.393562)
			(xy 263.823625 8.424538) (xy 263.746865 8.46276) (xy 263.673959 8.507901) (xy 263.60553 8.559577)
			(xy 263.54216 8.617346) (xy 263.484391 8.680716) (xy 263.432715 8.749145) (xy 263.387574 8.822051)
			(xy 263.349352 8.898811) (xy 263.318376 8.97877) (xy 263.294909 9.061246) (xy 263.279153 9.145536)
			(xy 263.271241 9.230919) (xy 258.775975 9.230919) (xy 258.768063 9.145536) (xy 258.752307 9.061246)
			(xy 258.72884 8.97877) (xy 258.697864 8.898811) (xy 258.659642 8.822051) (xy 258.614501 8.749145)
			(xy 258.562825 8.680716) (xy 258.505056 8.617346) (xy 258.441686 8.559577) (xy 258.373257 8.507901)
			(xy 258.300351 8.46276) (xy 258.223591 8.424538) (xy 258.143632 8.393562) (xy 258.061156 8.370095)
			(xy 257.976866 8.354339) (xy 257.891483 8.346427) (xy 257.805733 8.346427) (xy 257.72035 8.354339)
			(xy 257.63606 8.370095) (xy 257.553584 8.393562) (xy 257.473625 8.424538) (xy 257.396865 8.46276)
			(xy 257.323959 8.507901) (xy 257.25553 8.559577) (xy 257.19216 8.617346) (xy 257.134391 8.680716)
			(xy 257.082715 8.749145) (xy 257.037574 8.822051) (xy 256.999352 8.898811) (xy 256.968376 8.97877)
			(xy 256.944909 9.061246) (xy 256.929153 9.145536) (xy 256.921241 9.230919) (xy 6.020338 9.230919)
			(xy 6.103792 9.182737) (xy 6.211443 9.111405) (xy 6.314498 9.033581) (xy 6.412568 8.94956) (xy 6.505279 8.859661)
			(xy 6.592279 8.764226) (xy 6.67324 8.663616) (xy 6.747854 8.558213) (xy 6.815837 8.448416) (xy 6.876932 8.334642)
			(xy 6.930907 8.217323) (xy 6.977558 8.096904) (xy 7.016707 7.973841) (xy 7.048206 7.848602) (xy 7.071935 7.721661)
			(xy 7.087805 7.593501) (xy 7.095755 7.464606) (xy 7.096252 7.400036) (xy 7.095755 7.335466) (xy 7.087805 7.206571)
			(xy 7.071935 7.078411) (xy 7.048206 6.95147) (xy 7.016707 6.826231) (xy 6.977558 6.703168) (xy 6.97173 6.688125)
			(xy 178.335673 6.688125) (xy 178.335673 6.773875) (xy 178.343585 6.859258) (xy 178.359341 6.943548)
			(xy 178.382808 7.026024) (xy 178.413784 7.105983) (xy 178.452006 7.182743) (xy 178.497147 7.255649)
			(xy 178.548823 7.324078) (xy 178.606592 7.387448) (xy 178.669962 7.445217) (xy 178.738391 7.496893)
			(xy 178.811297 7.542034) (xy 178.888057 7.580256) (xy 178.968016 7.611232) (xy 179.050492 7.634699)
			(xy 179.134782 7.650455) (xy 179.220165 7.658367) (xy 179.305915 7.658367) (xy 179.391298 7.650455)
			(xy 179.475588 7.634699) (xy 179.558064 7.611232) (xy 179.638023 7.580256) (xy 179.714783 7.542034)
			(xy 179.787689 7.496893) (xy 179.856118 7.445217) (xy 179.919488 7.387448) (xy 179.977257 7.324078)
			(xy 180.028933 7.255649) (xy 180.074074 7.182743) (xy 180.112296 7.105983) (xy 180.143272 7.026024)
			(xy 180.166739 6.943548) (xy 180.182495 6.859258) (xy 180.190407 6.773875) (xy 180.190902 6.731)
			(xy 180.190407 6.688125) (xy 184.685673 6.688125) (xy 184.685673 6.773875) (xy 184.693585 6.859258)
			(xy 184.709341 6.943548) (xy 184.732808 7.026024) (xy 184.763784 7.105983) (xy 184.802006 7.182743)
			(xy 184.847147 7.255649) (xy 184.898823 7.324078) (xy 184.956592 7.387448) (xy 185.019962 7.445217)
			(xy 185.088391 7.496893) (xy 185.161297 7.542034) (xy 185.238057 7.580256) (xy 185.318016 7.611232)
			(xy 185.400492 7.634699) (xy 185.484782 7.650455) (xy 185.570165 7.658367) (xy 185.655915 7.658367)
			(xy 185.741298 7.650455) (xy 185.825588 7.634699) (xy 185.908064 7.611232) (xy 185.988023 7.580256)
			(xy 186.064783 7.542034) (xy 186.137689 7.496893) (xy 186.206118 7.445217) (xy 186.269488 7.387448)
			(xy 186.327257 7.324078) (xy 186.378933 7.255649) (xy 186.424074 7.182743) (xy 186.462296 7.105983)
			(xy 186.493272 7.026024) (xy 186.516739 6.943548) (xy 186.532495 6.859258) (xy 186.540407 6.773875)
			(xy 186.540902 6.731) (xy 186.540407 6.688125) (xy 246.260353 6.688125) (xy 246.260353 6.773875)
			(xy 246.268265 6.859258) (xy 246.284021 6.943548) (xy 246.307488 7.026024) (xy 246.338464 7.105983)
			(xy 246.376686 7.182743) (xy 246.421827 7.255649) (xy 246.473503 7.324078) (xy 246.531272 7.387448)
			(xy 246.594642 7.445217) (xy 246.663071 7.496893) (xy 246.735977 7.542034) (xy 246.812737 7.580256)
			(xy 246.892696 7.611232) (xy 246.975172 7.634699) (xy 247.059462 7.650455) (xy 247.144845 7.658367)
			(xy 247.230595 7.658367) (xy 247.315978 7.650455) (xy 247.400268 7.634699) (xy 247.482744 7.611232)
			(xy 247.562703 7.580256) (xy 247.639463 7.542034) (xy 247.712369 7.496893) (xy 247.780798 7.445217)
			(xy 247.844168 7.387448) (xy 247.901937 7.324078) (xy 247.953613 7.255649) (xy 247.998754 7.182743)
			(xy 248.036976 7.105983) (xy 248.067952 7.026024) (xy 248.091419 6.943548) (xy 248.107175 6.859258)
			(xy 248.115087 6.773875) (xy 248.115582 6.731) (xy 248.115087 6.688125) (xy 252.610353 6.688125)
			(xy 252.610353 6.773875) (xy 252.618265 6.859258) (xy 252.634021 6.943548) (xy 252.657488 7.026024)
			(xy 252.688464 7.105983) (xy 252.726686 7.182743) (xy 252.771827 7.255649) (xy 252.823503 7.324078)
			(xy 252.881272 7.387448) (xy 252.944642 7.445217) (xy 253.013071 7.496893) (xy 253.085977 7.542034)
			(xy 253.162737 7.580256) (xy 253.242696 7.611232) (xy 253.325172 7.634699) (xy 253.409462 7.650455)
			(xy 253.494845 7.658367) (xy 253.580595 7.658367) (xy 253.665978 7.650455) (xy 253.750268 7.634699)
			(xy 253.832744 7.611232) (xy 253.912703 7.580256) (xy 253.989463 7.542034) (xy 254.062369 7.496893)
			(xy 254.130798 7.445217) (xy 254.194168 7.387448) (xy 254.251937 7.324078) (xy 254.303613 7.255649)
			(xy 254.348754 7.182743) (xy 254.386976 7.105983) (xy 254.417952 7.026024) (xy 254.441419 6.943548)
			(xy 254.457175 6.859258) (xy 254.465087 6.773875) (xy 254.465582 6.731) (xy 254.465119 6.690919)
			(xy 256.921241 6.690919) (xy 256.921241 6.776669) (xy 256.929153 6.862052) (xy 256.944909 6.946342)
			(xy 256.968376 7.028818) (xy 256.999352 7.108777) (xy 257.037574 7.185537) (xy 257.082715 7.258443)
			(xy 257.134391 7.326872) (xy 257.19216 7.390242) (xy 257.25553 7.448011) (xy 257.323959 7.499687)
			(xy 257.396865 7.544828) (xy 257.473625 7.58305) (xy 257.553584 7.614026) (xy 257.63606 7.637493)
			(xy 257.72035 7.653249) (xy 257.805733 7.661161) (xy 257.891483 7.661161) (xy 257.976866 7.653249)
			(xy 258.061156 7.637493) (xy 258.143632 7.614026) (xy 258.223591 7.58305) (xy 258.245794 7.571994)
			(xy 261.85622 7.571994) (xy 261.85622 8.435594) (xy 261.856706 8.462863) (xy 261.864468 8.516847)
			(xy 261.879833 8.569177) (xy 261.90249 8.618787) (xy 261.931976 8.664668) (xy 261.967691 8.705885)
			(xy 262.008908 8.7416) (xy 262.054789 8.771086) (xy 262.104399 8.793743) (xy 262.156729 8.809108)
			(xy 262.210713 8.81687) (xy 262.265251 8.81687) (xy 262.319235 8.809108) (xy 262.371565 8.793743)
			(xy 262.421175 8.771086) (xy 262.467056 8.7416) (xy 262.508273 8.705885) (xy 262.543988 8.664668)
			(xy 262.573474 8.618787) (xy 262.596131 8.569177) (xy 262.611496 8.516847) (xy 262.619258 8.462863)
			(xy 262.619744 8.435594) (xy 262.619744 7.571994) (xy 262.619258 7.544725) (xy 262.611496 7.490741)
			(xy 262.596131 7.438411) (xy 262.573474 7.388801) (xy 262.543988 7.34292) (xy 262.508273 7.301703)
			(xy 262.467056 7.265988) (xy 262.421175 7.236502) (xy 262.371565 7.213845) (xy 262.319235 7.19848)
			(xy 262.265251 7.190718) (xy 262.210713 7.190718) (xy 262.156729 7.19848) (xy 262.104399 7.213845)
			(xy 262.054789 7.236502) (xy 262.008908 7.265988) (xy 261.967691 7.301703) (xy 261.931976 7.34292)
			(xy 261.90249 7.388801) (xy 261.879833 7.438411) (xy 261.864468 7.490741) (xy 261.856706 7.544725)
			(xy 261.85622 7.571994) (xy 258.245794 7.571994) (xy 258.300351 7.544828) (xy 258.373257 7.499687)
			(xy 258.441686 7.448011) (xy 258.505056 7.390242) (xy 258.562825 7.326872) (xy 258.614501 7.258443)
			(xy 258.659642 7.185537) (xy 258.697864 7.108777) (xy 258.72884 7.028818) (xy 258.752307 6.946342)
			(xy 258.768063 6.862052) (xy 258.775975 6.776669) (xy 258.77647 6.733794) (xy 258.775975 6.690919)
			(xy 263.271241 6.690919) (xy 263.271241 6.776669) (xy 263.279153 6.862052) (xy 263.294909 6.946342)
			(xy 263.318376 7.028818) (xy 263.349352 7.108777) (xy 263.387574 7.185537) (xy 263.432715 7.258443)
			(xy 263.484391 7.326872) (xy 263.54216 7.390242) (xy 263.60553 7.448011) (xy 263.673959 7.499687)
			(xy 263.746865 7.544828) (xy 263.823625 7.58305) (xy 263.903584 7.614026) (xy 263.98606 7.637493)
			(xy 264.07035 7.653249) (xy 264.155733 7.661161) (xy 264.241483 7.661161) (xy 264.326866 7.653249)
			(xy 264.411156 7.637493) (xy 264.493632 7.614026) (xy 264.573591 7.58305) (xy 264.650351 7.544828)
			(xy 264.723257 7.499687) (xy 264.791686 7.448011) (xy 264.855056 7.390242) (xy 264.912825 7.326872)
			(xy 264.964501 7.258443) (xy 265.009642 7.185537) (xy 265.047864 7.108777) (xy 265.07884 7.028818)
			(xy 265.102307 6.946342) (xy 265.118063 6.862052) (xy 265.125975 6.776669) (xy 265.12647 6.733794)
			(xy 265.125975 6.690919) (xy 324.845921 6.690919) (xy 324.845921 6.776669) (xy 324.853833 6.862052)
			(xy 324.869589 6.946342) (xy 324.893056 7.028818) (xy 324.924032 7.108777) (xy 324.962254 7.185537)
			(xy 325.007395 7.258443) (xy 325.059071 7.326872) (xy 325.11684 7.390242) (xy 325.18021 7.448011)
			(xy 325.248639 7.499687) (xy 325.321545 7.544828) (xy 325.398305 7.58305) (xy 325.478264 7.614026)
			(xy 325.56074 7.637493) (xy 325.64503 7.653249) (xy 325.730413 7.661161) (xy 325.816163 7.661161)
			(xy 325.901546 7.653249) (xy 325.985836 7.637493) (xy 326.068312 7.614026) (xy 326.148271 7.58305)
			(xy 326.170474 7.571994) (xy 327.352152 7.571994) (xy 327.352152 8.435594) (xy 327.352638 8.462863)
			(xy 327.3604 8.516847) (xy 327.375765 8.569177) (xy 327.398422 8.618787) (xy 327.427908 8.664668)
			(xy 327.463623 8.705885) (xy 327.50484 8.7416) (xy 327.550721 8.771086) (xy 327.600331 8.793743)
			(xy 327.652661 8.809108) (xy 327.706645 8.81687) (xy 327.761183 8.81687) (xy 327.815167 8.809108)
			(xy 327.867497 8.793743) (xy 327.917107 8.771086) (xy 327.962988 8.7416) (xy 328.004205 8.705885)
			(xy 328.03992 8.664668) (xy 328.069406 8.618787) (xy 328.092063 8.569177) (xy 328.107428 8.516847)
			(xy 328.11519 8.462863) (xy 328.115676 8.435594) (xy 328.115676 7.571994) (xy 328.11519 7.544725)
			(xy 328.107428 7.490741) (xy 328.092063 7.438411) (xy 328.069406 7.388801) (xy 328.03992 7.34292)
			(xy 328.004205 7.301703) (xy 327.962988 7.265988) (xy 327.917107 7.236502) (xy 327.867497 7.213845)
			(xy 327.815167 7.19848) (xy 327.761183 7.190718) (xy 327.706645 7.190718) (xy 327.652661 7.19848)
			(xy 327.600331 7.213845) (xy 327.550721 7.236502) (xy 327.50484 7.265988) (xy 327.463623 7.301703)
			(xy 327.427908 7.34292) (xy 327.398422 7.388801) (xy 327.375765 7.438411) (xy 327.3604 7.490741)
			(xy 327.352638 7.544725) (xy 327.352152 7.571994) (xy 326.170474 7.571994) (xy 326.225031 7.544828)
			(xy 326.297937 7.499687) (xy 326.366366 7.448011) (xy 326.429736 7.390242) (xy 326.487505 7.326872)
			(xy 326.539181 7.258443) (xy 326.584322 7.185537) (xy 326.622544 7.108777) (xy 326.65352 7.028818)
			(xy 326.676987 6.946342) (xy 326.692743 6.862052) (xy 326.700655 6.776669) (xy 326.70115 6.733794)
			(xy 326.700655 6.690919) (xy 331.195921 6.690919) (xy 331.195921 6.776669) (xy 331.203833 6.862052)
			(xy 331.219589 6.946342) (xy 331.243056 7.028818) (xy 331.274032 7.108777) (xy 331.312254 7.185537)
			(xy 331.357395 7.258443) (xy 331.409071 7.326872) (xy 331.46684 7.390242) (xy 331.53021 7.448011)
			(xy 331.598639 7.499687) (xy 331.671545 7.544828) (xy 331.748305 7.58305) (xy 331.828264 7.614026)
			(xy 331.91074 7.637493) (xy 331.99503 7.653249) (xy 332.080413 7.661161) (xy 332.166163 7.661161)
			(xy 332.251546 7.653249) (xy 332.335836 7.637493) (xy 332.418312 7.614026) (xy 332.498271 7.58305)
			(xy 332.575031 7.544828) (xy 332.647937 7.499687) (xy 332.716366 7.448011) (xy 332.779736 7.390242)
			(xy 332.837505 7.326872) (xy 332.889181 7.258443) (xy 332.934322 7.185537) (xy 332.972544 7.108777)
			(xy 333.00352 7.028818) (xy 333.026987 6.946342) (xy 333.042743 6.862052) (xy 333.050655 6.776669)
			(xy 333.05115 6.733794) (xy 333.050655 6.690919) (xy 335.488267 6.690919) (xy 335.488267 6.776669)
			(xy 335.496179 6.862052) (xy 335.511935 6.946342) (xy 335.535402 7.028818) (xy 335.566378 7.108777)
			(xy 335.6046 7.185537) (xy 335.649741 7.258443) (xy 335.701417 7.326872) (xy 335.759186 7.390242)
			(xy 335.822556 7.448011) (xy 335.890985 7.499687) (xy 335.963891 7.544828) (xy 336.040651 7.58305)
			(xy 336.12061 7.614026) (xy 336.203086 7.637493) (xy 336.287376 7.653249) (xy 336.372759 7.661161)
			(xy 336.458509 7.661161) (xy 336.543892 7.653249) (xy 336.628182 7.637493) (xy 336.710658 7.614026)
			(xy 336.790617 7.58305) (xy 336.81282 7.571994) (xy 340.4235 7.571994) (xy 340.4235 8.435594) (xy 340.423986 8.462845)
			(xy 340.431742 8.516793) (xy 340.447097 8.569088) (xy 340.469739 8.618665) (xy 340.499205 8.664515)
			(xy 340.534896 8.705706) (xy 340.576087 8.741397) (xy 340.621937 8.770863) (xy 340.671514 8.793505)
			(xy 340.723809 8.80886) (xy 340.777757 8.816616) (xy 340.832259 8.816616) (xy 340.886207 8.80886)
			(xy 340.938502 8.793505) (xy 340.988079 8.770863) (xy 341.033929 8.741397) (xy 341.07512 8.705706)
			(xy 341.110811 8.664515) (xy 341.140277 8.618665) (xy 341.162919 8.569088) (xy 341.178274 8.516793)
			(xy 341.18603 8.462845) (xy 341.186516 8.435594) (xy 341.186516 7.571994) (xy 341.18603 7.544743)
			(xy 341.178274 7.490795) (xy 341.162919 7.4385) (xy 341.140277 7.388923) (xy 341.110811 7.343073)
			(xy 341.07512 7.301882) (xy 341.033929 7.266191) (xy 340.988079 7.236725) (xy 340.938502 7.214083)
			(xy 340.886207 7.198728) (xy 340.832259 7.190972) (xy 340.777757 7.190972) (xy 340.723809 7.198728)
			(xy 340.671514 7.214083) (xy 340.621937 7.236725) (xy 340.576087 7.266191) (xy 340.534896 7.301882)
			(xy 340.499205 7.343073) (xy 340.469739 7.388923) (xy 340.447097 7.4385) (xy 340.431742 7.490795)
			(xy 340.423986 7.544743) (xy 340.4235 7.571994) (xy 336.81282 7.571994) (xy 336.867377 7.544828)
			(xy 336.940283 7.499687) (xy 337.008712 7.448011) (xy 337.072082 7.390242) (xy 337.129851 7.326872)
			(xy 337.181527 7.258443) (xy 337.226668 7.185537) (xy 337.26489 7.108777) (xy 337.295866 7.028818)
			(xy 337.319333 6.946342) (xy 337.335089 6.862052) (xy 337.343001 6.776669) (xy 337.343496 6.733794)
			(xy 337.343001 6.690919) (xy 341.838267 6.690919) (xy 341.838267 6.776669) (xy 341.846179 6.862052)
			(xy 341.861935 6.946342) (xy 341.885402 7.028818) (xy 341.916378 7.108777) (xy 341.9546 7.185537)
			(xy 341.999741 7.258443) (xy 342.051417 7.326872) (xy 342.109186 7.390242) (xy 342.172556 7.448011)
			(xy 342.240985 7.499687) (xy 342.313891 7.544828) (xy 342.390651 7.58305) (xy 342.47061 7.614026)
			(xy 342.553086 7.637493) (xy 342.637376 7.653249) (xy 342.722759 7.661161) (xy 342.808509 7.661161)
			(xy 342.893892 7.653249) (xy 342.978182 7.637493) (xy 343.060658 7.614026) (xy 343.140617 7.58305)
			(xy 343.217377 7.544828) (xy 343.290283 7.499687) (xy 343.358712 7.448011) (xy 343.422082 7.390242)
			(xy 343.479851 7.326872) (xy 343.531527 7.258443) (xy 343.576668 7.185537) (xy 343.61489 7.108777)
			(xy 343.645866 7.028818) (xy 343.669333 6.946342) (xy 343.685089 6.862052) (xy 343.693001 6.776669)
			(xy 343.693496 6.733794) (xy 343.693001 6.690919) (xy 373.705107 6.690919) (xy 373.705107 6.776669)
			(xy 373.713019 6.862052) (xy 373.728775 6.946342) (xy 373.752242 7.028818) (xy 373.783218 7.108777)
			(xy 373.82144 7.185537) (xy 373.866581 7.258443) (xy 373.918257 7.326872) (xy 373.976026 7.390242)
			(xy 374.039396 7.448011) (xy 374.107825 7.499687) (xy 374.180731 7.544828) (xy 374.257491 7.58305)
			(xy 374.33745 7.614026) (xy 374.419926 7.637493) (xy 374.504216 7.653249) (xy 374.589599 7.661161)
			(xy 374.675349 7.661161) (xy 374.760732 7.653249) (xy 374.845022 7.637493) (xy 374.927498 7.614026)
			(xy 375.007457 7.58305) (xy 375.02966 7.571994) (xy 376.211592 7.571994) (xy 376.211592 8.435594)
			(xy 376.212078 8.462845) (xy 376.219834 8.516793) (xy 376.235189 8.569088) (xy 376.257831 8.618665)
			(xy 376.287297 8.664515) (xy 376.322988 8.705706) (xy 376.364179 8.741397) (xy 376.410029 8.770863)
			(xy 376.459606 8.793505) (xy 376.511901 8.80886) (xy 376.565849 8.816616) (xy 376.620351 8.816616)
			(xy 376.674299 8.80886) (xy 376.726594 8.793505) (xy 376.776171 8.770863) (xy 376.822021 8.741397)
			(xy 376.863212 8.705706) (xy 376.898903 8.664515) (xy 376.928369 8.618665) (xy 376.951011 8.569088)
			(xy 376.966366 8.516793) (xy 376.974122 8.462845) (xy 376.974608 8.435594) (xy 376.974608 7.571994)
			(xy 376.974122 7.544743) (xy 376.966366 7.490795) (xy 376.951011 7.4385) (xy 376.928369 7.388923)
			(xy 376.898903 7.343073) (xy 376.863212 7.301882) (xy 376.822021 7.266191) (xy 376.776171 7.236725)
			(xy 376.726594 7.214083) (xy 376.674299 7.198728) (xy 376.620351 7.190972) (xy 376.565849 7.190972)
			(xy 376.511901 7.198728) (xy 376.459606 7.214083) (xy 376.410029 7.236725) (xy 376.364179 7.266191)
			(xy 376.322988 7.301882) (xy 376.287297 7.343073) (xy 376.257831 7.388923) (xy 376.235189 7.4385)
			(xy 376.219834 7.490795) (xy 376.212078 7.544743) (xy 376.211592 7.571994) (xy 375.02966 7.571994)
			(xy 375.084217 7.544828) (xy 375.157123 7.499687) (xy 375.225552 7.448011) (xy 375.288922 7.390242)
			(xy 375.346691 7.326872) (xy 375.398367 7.258443) (xy 375.443508 7.185537) (xy 375.48173 7.108777)
			(xy 375.512706 7.028818) (xy 375.536173 6.946342) (xy 375.551929 6.862052) (xy 375.559841 6.776669)
			(xy 375.560336 6.733794) (xy 375.559841 6.690919) (xy 380.055107 6.690919) (xy 380.055107 6.776669)
			(xy 380.063019 6.862052) (xy 380.078775 6.946342) (xy 380.102242 7.028818) (xy 380.133218 7.108777)
			(xy 380.17144 7.185537) (xy 380.216581 7.258443) (xy 380.268257 7.326872) (xy 380.326026 7.390242)
			(xy 380.389396 7.448011) (xy 380.457825 7.499687) (xy 380.530731 7.544828) (xy 380.607491 7.58305)
			(xy 380.68745 7.614026) (xy 380.769926 7.637493) (xy 380.854216 7.653249) (xy 380.939599 7.661161)
			(xy 381.025349 7.661161) (xy 381.110732 7.653249) (xy 381.195022 7.637493) (xy 381.277498 7.614026)
			(xy 381.357457 7.58305) (xy 381.434217 7.544828) (xy 381.507123 7.499687) (xy 381.575552 7.448011)
			(xy 381.638922 7.390242) (xy 381.688857 7.335466) (xy 464.704165 7.335466) (xy 464.704165 7.464606)
			(xy 464.712115 7.593501) (xy 464.727985 7.721661) (xy 464.751714 7.848602) (xy 464.783213 7.973841)
			(xy 464.822362 8.096904) (xy 464.869013 8.217323) (xy 464.922988 8.334642) (xy 464.984083 8.448416)
			(xy 465.052066 8.558213) (xy 465.12668 8.663616) (xy 465.207641 8.764226) (xy 465.294641 8.859661)
			(xy 465.387352 8.94956) (xy 465.485422 9.033581) (xy 465.588477 9.111405) (xy 465.696128 9.182737)
			(xy 465.807967 9.247307) (xy 465.923568 9.304869) (xy 466.042493 9.355206) (xy 466.164292 9.398126)
			(xy 466.288502 9.433467) (xy 466.414651 9.461094) (xy 466.542263 9.480903) (xy 466.670852 9.492819)
			(xy 466.79993 9.496796) (xy 466.929008 9.492819) (xy 467.057597 9.480903) (xy 467.185209 9.461094)
			(xy 467.311358 9.433467) (xy 467.435568 9.398126) (xy 467.557367 9.355206) (xy 467.676292 9.304869)
			(xy 467.791893 9.247307) (xy 467.903732 9.182737) (xy 468.011383 9.111405) (xy 468.114438 9.033581)
			(xy 468.212508 8.94956) (xy 468.305219 8.859661) (xy 468.392219 8.764226) (xy 468.47318 8.663616)
			(xy 468.547794 8.558213) (xy 468.615777 8.448416) (xy 468.676872 8.334642) (xy 468.730847 8.217323)
			(xy 468.777498 8.096904) (xy 468.816647 7.973841) (xy 468.848146 7.848602) (xy 468.871875 7.721661)
			(xy 468.887745 7.593501) (xy 468.895695 7.464606) (xy 468.896192 7.400036) (xy 468.895695 7.335466)
			(xy 468.887745 7.206571) (xy 468.871875 7.078411) (xy 468.848146 6.95147) (xy 468.816647 6.826231)
			(xy 468.777498 6.703168) (xy 468.730847 6.582749) (xy 468.676872 6.46543) (xy 468.615777 6.351656)
			(xy 468.547794 6.241859) (xy 468.47318 6.136456) (xy 468.392219 6.035846) (xy 468.305219 5.940411)
			(xy 468.212508 5.850512) (xy 468.114438 5.766491) (xy 468.011383 5.688667) (xy 467.903732 5.617335)
			(xy 467.791893 5.552765) (xy 467.676292 5.495203) (xy 467.557367 5.444866) (xy 467.435568 5.401946)
			(xy 467.311358 5.366605) (xy 467.185209 5.338978) (xy 467.057597 5.319169) (xy 466.929008 5.307253)
			(xy 466.79993 5.303277) (xy 466.670852 5.307253) (xy 466.542263 5.319169) (xy 466.414651 5.338978)
			(xy 466.288502 5.366605) (xy 466.164292 5.401946) (xy 466.042493 5.444866) (xy 465.923568 5.495203)
			(xy 465.807967 5.552765) (xy 465.696128 5.617335) (xy 465.588477 5.688667) (xy 465.485422 5.766491)
			(xy 465.387352 5.850512) (xy 465.294641 5.940411) (xy 465.207641 6.035846) (xy 465.12668 6.136456)
			(xy 465.052066 6.241859) (xy 464.984083 6.351656) (xy 464.922988 6.46543) (xy 464.869013 6.582749)
			(xy 464.822362 6.703168) (xy 464.783213 6.826231) (xy 464.751714 6.95147) (xy 464.727985 7.078411)
			(xy 464.712115 7.206571) (xy 464.704165 7.335466) (xy 381.688857 7.335466) (xy 381.696691 7.326872)
			(xy 381.748367 7.258443) (xy 381.793508 7.185537) (xy 381.83173 7.108777) (xy 381.862706 7.028818)
			(xy 381.886173 6.946342) (xy 381.901929 6.862052) (xy 381.909841 6.776669) (xy 381.910336 6.733794)
			(xy 381.909841 6.690919) (xy 381.901929 6.605536) (xy 381.886173 6.521246) (xy 381.862706 6.43877)
			(xy 381.83173 6.358811) (xy 381.793508 6.282051) (xy 381.748367 6.209145) (xy 381.696691 6.140716)
			(xy 381.638922 6.077346) (xy 381.575552 6.019577) (xy 381.507123 5.967901) (xy 381.434217 5.92276)
			(xy 381.357457 5.884538) (xy 381.277498 5.853562) (xy 381.195022 5.830095) (xy 381.110732 5.814339)
			(xy 381.025349 5.806427) (xy 380.939599 5.806427) (xy 380.854216 5.814339) (xy 380.769926 5.830095)
			(xy 380.68745 5.853562) (xy 380.607491 5.884538) (xy 380.530731 5.92276) (xy 380.457825 5.967901)
			(xy 380.389396 6.019577) (xy 380.326026 6.077346) (xy 380.268257 6.140716) (xy 380.216581 6.209145)
			(xy 380.17144 6.282051) (xy 380.133218 6.358811) (xy 380.102242 6.43877) (xy 380.078775 6.521246)
			(xy 380.063019 6.605536) (xy 380.055107 6.690919) (xy 375.559841 6.690919) (xy 375.551929 6.605536)
			(xy 375.536173 6.521246) (xy 375.512706 6.43877) (xy 375.48173 6.358811) (xy 375.443508 6.282051)
			(xy 375.398367 6.209145) (xy 375.346691 6.140716) (xy 375.288922 6.077346) (xy 375.225552 6.019577)
			(xy 375.157123 5.967901) (xy 375.084217 5.92276) (xy 375.007457 5.884538) (xy 374.927498 5.853562)
			(xy 374.845022 5.830095) (xy 374.760732 5.814339) (xy 374.675349 5.806427) (xy 374.589599 5.806427)
			(xy 374.504216 5.814339) (xy 374.419926 5.830095) (xy 374.33745 5.853562) (xy 374.257491 5.884538)
			(xy 374.180731 5.92276) (xy 374.107825 5.967901) (xy 374.039396 6.019577) (xy 373.976026 6.077346)
			(xy 373.918257 6.140716) (xy 373.866581 6.209145) (xy 373.82144 6.282051) (xy 373.783218 6.358811)
			(xy 373.752242 6.43877) (xy 373.728775 6.521246) (xy 373.713019 6.605536) (xy 373.705107 6.690919)
			(xy 343.693001 6.690919) (xy 343.685089 6.605536) (xy 343.669333 6.521246) (xy 343.645866 6.43877)
			(xy 343.61489 6.358811) (xy 343.576668 6.282051) (xy 343.531527 6.209145) (xy 343.479851 6.140716)
			(xy 343.422082 6.077346) (xy 343.358712 6.019577) (xy 343.290283 5.967901) (xy 343.217377 5.92276)
			(xy 343.140617 5.884538) (xy 343.060658 5.853562) (xy 342.978182 5.830095) (xy 342.893892 5.814339)
			(xy 342.808509 5.806427) (xy 342.722759 5.806427) (xy 342.637376 5.814339) (xy 342.553086 5.830095)
			(xy 342.47061 5.853562) (xy 342.390651 5.884538) (xy 342.313891 5.92276) (xy 342.240985 5.967901)
			(xy 342.172556 6.019577) (xy 342.109186 6.077346) (xy 342.051417 6.140716) (xy 341.999741 6.209145)
			(xy 341.9546 6.282051) (xy 341.916378 6.358811) (xy 341.885402 6.43877) (xy 341.861935 6.521246)
			(xy 341.846179 6.605536) (xy 341.838267 6.690919) (xy 337.343001 6.690919) (xy 337.335089 6.605536)
			(xy 337.319333 6.521246) (xy 337.295866 6.43877) (xy 337.26489 6.358811) (xy 337.226668 6.282051)
			(xy 337.181527 6.209145) (xy 337.129851 6.140716) (xy 337.072082 6.077346) (xy 337.008712 6.019577)
			(xy 336.940283 5.967901) (xy 336.867377 5.92276) (xy 336.790617 5.884538) (xy 336.710658 5.853562)
			(xy 336.628182 5.830095) (xy 336.543892 5.814339) (xy 336.458509 5.806427) (xy 336.372759 5.806427)
			(xy 336.287376 5.814339) (xy 336.203086 5.830095) (xy 336.12061 5.853562) (xy 336.040651 5.884538)
			(xy 335.963891 5.92276) (xy 335.890985 5.967901) (xy 335.822556 6.019577) (xy 335.759186 6.077346)
			(xy 335.701417 6.140716) (xy 335.649741 6.209145) (xy 335.6046 6.282051) (xy 335.566378 6.358811)
			(xy 335.535402 6.43877) (xy 335.511935 6.521246) (xy 335.496179 6.605536) (xy 335.488267 6.690919)
			(xy 333.050655 6.690919) (xy 333.042743 6.605536) (xy 333.026987 6.521246) (xy 333.00352 6.43877)
			(xy 332.972544 6.358811) (xy 332.934322 6.282051) (xy 332.889181 6.209145) (xy 332.837505 6.140716)
			(xy 332.779736 6.077346) (xy 332.716366 6.019577) (xy 332.647937 5.967901) (xy 332.575031 5.92276)
			(xy 332.498271 5.884538) (xy 332.418312 5.853562) (xy 332.335836 5.830095) (xy 332.251546 5.814339)
			(xy 332.166163 5.806427) (xy 332.080413 5.806427) (xy 331.99503 5.814339) (xy 331.91074 5.830095)
			(xy 331.828264 5.853562) (xy 331.748305 5.884538) (xy 331.671545 5.92276) (xy 331.598639 5.967901)
			(xy 331.53021 6.019577) (xy 331.46684 6.077346) (xy 331.409071 6.140716) (xy 331.357395 6.209145)
			(xy 331.312254 6.282051) (xy 331.274032 6.358811) (xy 331.243056 6.43877) (xy 331.219589 6.521246)
			(xy 331.203833 6.605536) (xy 331.195921 6.690919) (xy 326.700655 6.690919) (xy 326.692743 6.605536)
			(xy 326.676987 6.521246) (xy 326.65352 6.43877) (xy 326.622544 6.358811) (xy 326.584322 6.282051)
			(xy 326.539181 6.209145) (xy 326.487505 6.140716) (xy 326.429736 6.077346) (xy 326.366366 6.019577)
			(xy 326.297937 5.967901) (xy 326.225031 5.92276) (xy 326.148271 5.884538) (xy 326.068312 5.853562)
			(xy 325.985836 5.830095) (xy 325.901546 5.814339) (xy 325.816163 5.806427) (xy 325.730413 5.806427)
			(xy 325.64503 5.814339) (xy 325.56074 5.830095) (xy 325.478264 5.853562) (xy 325.398305 5.884538)
			(xy 325.321545 5.92276) (xy 325.248639 5.967901) (xy 325.18021 6.019577) (xy 325.11684 6.077346)
			(xy 325.059071 6.140716) (xy 325.007395 6.209145) (xy 324.962254 6.282051) (xy 324.924032 6.358811)
			(xy 324.893056 6.43877) (xy 324.869589 6.521246) (xy 324.853833 6.605536) (xy 324.845921 6.690919)
			(xy 265.125975 6.690919) (xy 265.118063 6.605536) (xy 265.102307 6.521246) (xy 265.07884 6.43877)
			(xy 265.047864 6.358811) (xy 265.009642 6.282051) (xy 264.964501 6.209145) (xy 264.912825 6.140716)
			(xy 264.855056 6.077346) (xy 264.791686 6.019577) (xy 264.723257 5.967901) (xy 264.650351 5.92276)
			(xy 264.573591 5.884538) (xy 264.493632 5.853562) (xy 264.411156 5.830095) (xy 264.326866 5.814339)
			(xy 264.241483 5.806427) (xy 264.155733 5.806427) (xy 264.07035 5.814339) (xy 263.98606 5.830095)
			(xy 263.903584 5.853562) (xy 263.823625 5.884538) (xy 263.746865 5.92276) (xy 263.673959 5.967901)
			(xy 263.60553 6.019577) (xy 263.54216 6.077346) (xy 263.484391 6.140716) (xy 263.432715 6.209145)
			(xy 263.387574 6.282051) (xy 263.349352 6.358811) (xy 263.318376 6.43877) (xy 263.294909 6.521246)
			(xy 263.279153 6.605536) (xy 263.271241 6.690919) (xy 258.775975 6.690919) (xy 258.768063 6.605536)
			(xy 258.752307 6.521246) (xy 258.72884 6.43877) (xy 258.697864 6.358811) (xy 258.659642 6.282051)
			(xy 258.614501 6.209145) (xy 258.562825 6.140716) (xy 258.505056 6.077346) (xy 258.441686 6.019577)
			(xy 258.373257 5.967901) (xy 258.300351 5.92276) (xy 258.223591 5.884538) (xy 258.143632 5.853562)
			(xy 258.061156 5.830095) (xy 257.976866 5.814339) (xy 257.891483 5.806427) (xy 257.805733 5.806427)
			(xy 257.72035 5.814339) (xy 257.63606 5.830095) (xy 257.553584 5.853562) (xy 257.473625 5.884538)
			(xy 257.396865 5.92276) (xy 257.323959 5.967901) (xy 257.25553 6.019577) (xy 257.19216 6.077346)
			(xy 257.134391 6.140716) (xy 257.082715 6.209145) (xy 257.037574 6.282051) (xy 256.999352 6.358811)
			(xy 256.968376 6.43877) (xy 256.944909 6.521246) (xy 256.929153 6.605536) (xy 256.921241 6.690919)
			(xy 254.465119 6.690919) (xy 254.465087 6.688125) (xy 254.457175 6.602742) (xy 254.441419 6.518452)
			(xy 254.417952 6.435976) (xy 254.386976 6.356017) (xy 254.348754 6.279257) (xy 254.303613 6.206351)
			(xy 254.251937 6.137922) (xy 254.194168 6.074552) (xy 254.130798 6.016783) (xy 254.062369 5.965107)
			(xy 253.989463 5.919966) (xy 253.912703 5.881744) (xy 253.832744 5.850768) (xy 253.750268 5.827301)
			(xy 253.665978 5.811545) (xy 253.580595 5.803633) (xy 253.494845 5.803633) (xy 253.409462 5.811545)
			(xy 253.325172 5.827301) (xy 253.242696 5.850768) (xy 253.162737 5.881744) (xy 253.085977 5.919966)
			(xy 253.013071 5.965107) (xy 252.944642 6.016783) (xy 252.881272 6.074552) (xy 252.823503 6.137922)
			(xy 252.771827 6.206351) (xy 252.726686 6.279257) (xy 252.688464 6.356017) (xy 252.657488 6.435976)
			(xy 252.634021 6.518452) (xy 252.618265 6.602742) (xy 252.610353 6.688125) (xy 248.115087 6.688125)
			(xy 248.107175 6.602742) (xy 248.091419 6.518452) (xy 248.067952 6.435976) (xy 248.036976 6.356017)
			(xy 247.998754 6.279257) (xy 247.953613 6.206351) (xy 247.901937 6.137922) (xy 247.844168 6.074552)
			(xy 247.780798 6.016783) (xy 247.712369 5.965107) (xy 247.639463 5.919966) (xy 247.562703 5.881744)
			(xy 247.482744 5.850768) (xy 247.400268 5.827301) (xy 247.315978 5.811545) (xy 247.230595 5.803633)
			(xy 247.144845 5.803633) (xy 247.059462 5.811545) (xy 246.975172 5.827301) (xy 246.892696 5.850768)
			(xy 246.812737 5.881744) (xy 246.735977 5.919966) (xy 246.663071 5.965107) (xy 246.594642 6.016783)
			(xy 246.531272 6.074552) (xy 246.473503 6.137922) (xy 246.421827 6.206351) (xy 246.376686 6.279257)
			(xy 246.338464 6.356017) (xy 246.307488 6.435976) (xy 246.284021 6.518452) (xy 246.268265 6.602742)
			(xy 246.260353 6.688125) (xy 186.540407 6.688125) (xy 186.532495 6.602742) (xy 186.516739 6.518452)
			(xy 186.493272 6.435976) (xy 186.462296 6.356017) (xy 186.424074 6.279257) (xy 186.378933 6.206351)
			(xy 186.327257 6.137922) (xy 186.269488 6.074552) (xy 186.206118 6.016783) (xy 186.137689 5.965107)
			(xy 186.064783 5.919966) (xy 185.988023 5.881744) (xy 185.908064 5.850768) (xy 185.825588 5.827301)
			(xy 185.741298 5.811545) (xy 185.655915 5.803633) (xy 185.570165 5.803633) (xy 185.484782 5.811545)
			(xy 185.400492 5.827301) (xy 185.318016 5.850768) (xy 185.238057 5.881744) (xy 185.161297 5.919966)
			(xy 185.088391 5.965107) (xy 185.019962 6.016783) (xy 184.956592 6.074552) (xy 184.898823 6.137922)
			(xy 184.847147 6.206351) (xy 184.802006 6.279257) (xy 184.763784 6.356017) (xy 184.732808 6.435976)
			(xy 184.709341 6.518452) (xy 184.693585 6.602742) (xy 184.685673 6.688125) (xy 180.190407 6.688125)
			(xy 180.182495 6.602742) (xy 180.166739 6.518452) (xy 180.143272 6.435976) (xy 180.112296 6.356017)
			(xy 180.074074 6.279257) (xy 180.028933 6.206351) (xy 179.977257 6.137922) (xy 179.919488 6.074552)
			(xy 179.856118 6.016783) (xy 179.787689 5.965107) (xy 179.714783 5.919966) (xy 179.638023 5.881744)
			(xy 179.558064 5.850768) (xy 179.475588 5.827301) (xy 179.391298 5.811545) (xy 179.305915 5.803633)
			(xy 179.220165 5.803633) (xy 179.134782 5.811545) (xy 179.050492 5.827301) (xy 178.968016 5.850768)
			(xy 178.888057 5.881744) (xy 178.811297 5.919966) (xy 178.738391 5.965107) (xy 178.669962 6.016783)
			(xy 178.606592 6.074552) (xy 178.548823 6.137922) (xy 178.497147 6.206351) (xy 178.452006 6.279257)
			(xy 178.413784 6.356017) (xy 178.382808 6.435976) (xy 178.359341 6.518452) (xy 178.343585 6.602742)
			(xy 178.335673 6.688125) (xy 6.97173 6.688125) (xy 6.930907 6.582749) (xy 6.876932 6.46543) (xy 6.815837 6.351656)
			(xy 6.747854 6.241859) (xy 6.67324 6.136456) (xy 6.592279 6.035846) (xy 6.505279 5.940411) (xy 6.412568 5.850512)
			(xy 6.314498 5.766491) (xy 6.211443 5.688667) (xy 6.103792 5.617335) (xy 5.991953 5.552765) (xy 5.876352 5.495203)
			(xy 5.757427 5.444866) (xy 5.635628 5.401946) (xy 5.511418 5.366605) (xy 5.385269 5.338978) (xy 5.257657 5.319169)
			(xy 5.129068 5.307253) (xy 4.99999 5.303277) (xy 4.870912 5.307253) (xy 4.742323 5.319169) (xy 4.614711 5.338978)
			(xy 4.488562 5.366605) (xy 4.364352 5.401946) (xy 4.242553 5.444866) (xy 4.123628 5.495203) (xy 4.008027 5.552765)
			(xy 3.896188 5.617335) (xy 3.788537 5.688667) (xy 3.685482 5.766491) (xy 3.587412 5.850512) (xy 3.494701 5.940411)
			(xy 3.407701 6.035846) (xy 3.32674 6.136456) (xy 3.252126 6.241859) (xy 3.184143 6.351656) (xy 3.123048 6.46543)
			(xy 3.069073 6.582749) (xy 3.022422 6.703168) (xy 2.983273 6.826231) (xy 2.951774 6.95147) (xy 2.928045 7.078411)
			(xy 2.912175 7.206571) (xy 2.904225 7.335466) (xy 0.508 7.335466) (xy 0.508 4.148125) (xy 178.335673 4.148125)
			(xy 178.335673 4.233875) (xy 178.343585 4.319258) (xy 178.359341 4.403548) (xy 178.382808 4.486024)
			(xy 178.413784 4.565983) (xy 178.452006 4.642743) (xy 178.497147 4.715649) (xy 178.548823 4.784078)
			(xy 178.606592 4.847448) (xy 178.669962 4.905217) (xy 178.738391 4.956893) (xy 178.811297 5.002034)
			(xy 178.888057 5.040256) (xy 178.968016 5.071232) (xy 179.050492 5.094699) (xy 179.134782 5.110455)
			(xy 179.220165 5.118367) (xy 179.305915 5.118367) (xy 179.391298 5.110455) (xy 179.475588 5.094699)
			(xy 179.558064 5.071232) (xy 179.638023 5.040256) (xy 179.660226 5.0292) (xy 183.270652 5.0292) (xy 183.270652 5.8928)
			(xy 183.271138 5.920069) (xy 183.2789 5.974053) (xy 183.294265 6.026383) (xy 183.316922 6.075993)
			(xy 183.346408 6.121874) (xy 183.382123 6.163091) (xy 183.42334 6.198806) (xy 183.469221 6.228292)
			(xy 183.518831 6.250949) (xy 183.571161 6.266314) (xy 183.625145 6.274076) (xy 183.679683 6.274076)
			(xy 183.733667 6.266314) (xy 183.785997 6.250949) (xy 183.835607 6.228292) (xy 183.881488 6.198806)
			(xy 183.922705 6.163091) (xy 183.95842 6.121874) (xy 183.987906 6.075993) (xy 184.010563 6.026383)
			(xy 184.025928 5.974053) (xy 184.03369 5.920069) (xy 184.034176 5.8928) (xy 184.034176 5.0292) (xy 184.03369 5.001931)
			(xy 184.025928 4.947947) (xy 184.010563 4.895617) (xy 183.987906 4.846007) (xy 183.95842 4.800126)
			(xy 183.922705 4.758909) (xy 183.881488 4.723194) (xy 183.835607 4.693708) (xy 183.785997 4.671051)
			(xy 183.733667 4.655686) (xy 183.679683 4.647924) (xy 183.625145 4.647924) (xy 183.571161 4.655686)
			(xy 183.518831 4.671051) (xy 183.469221 4.693708) (xy 183.42334 4.723194) (xy 183.382123 4.758909)
			(xy 183.346408 4.800126) (xy 183.316922 4.846007) (xy 183.294265 4.895617) (xy 183.2789 4.947947)
			(xy 183.271138 5.001931) (xy 183.270652 5.0292) (xy 179.660226 5.0292) (xy 179.714783 5.002034) (xy 179.787689 4.956893)
			(xy 179.856118 4.905217) (xy 179.919488 4.847448) (xy 179.977257 4.784078) (xy 180.028933 4.715649)
			(xy 180.074074 4.642743) (xy 180.112296 4.565983) (xy 180.143272 4.486024) (xy 180.166739 4.403548)
			(xy 180.182495 4.319258) (xy 180.190407 4.233875) (xy 180.190902 4.191) (xy 180.190407 4.148125)
			(xy 184.685673 4.148125) (xy 184.685673 4.233875) (xy 184.693585 4.319258) (xy 184.709341 4.403548)
			(xy 184.732808 4.486024) (xy 184.763784 4.565983) (xy 184.802006 4.642743) (xy 184.847147 4.715649)
			(xy 184.898823 4.784078) (xy 184.956592 4.847448) (xy 185.019962 4.905217) (xy 185.088391 4.956893)
			(xy 185.161297 5.002034) (xy 185.238057 5.040256) (xy 185.318016 5.071232) (xy 185.400492 5.094699)
			(xy 185.484782 5.110455) (xy 185.570165 5.118367) (xy 185.655915 5.118367) (xy 185.741298 5.110455)
			(xy 185.825588 5.094699) (xy 185.908064 5.071232) (xy 185.988023 5.040256) (xy 186.064783 5.002034)
			(xy 186.137689 4.956893) (xy 186.206118 4.905217) (xy 186.269488 4.847448) (xy 186.327257 4.784078)
			(xy 186.378933 4.715649) (xy 186.424074 4.642743) (xy 186.462296 4.565983) (xy 186.493272 4.486024)
			(xy 186.516739 4.403548) (xy 186.532495 4.319258) (xy 186.540407 4.233875) (xy 186.540902 4.191)
			(xy 186.540407 4.148125) (xy 246.260353 4.148125) (xy 246.260353 4.233875) (xy 246.268265 4.319258)
			(xy 246.284021 4.403548) (xy 246.307488 4.486024) (xy 246.338464 4.565983) (xy 246.376686 4.642743)
			(xy 246.421827 4.715649) (xy 246.473503 4.784078) (xy 246.531272 4.847448) (xy 246.594642 4.905217)
			(xy 246.663071 4.956893) (xy 246.735977 5.002034) (xy 246.812737 5.040256) (xy 246.892696 5.071232)
			(xy 246.975172 5.094699) (xy 247.059462 5.110455) (xy 247.144845 5.118367) (xy 247.230595 5.118367)
			(xy 247.315978 5.110455) (xy 247.400268 5.094699) (xy 247.482744 5.071232) (xy 247.562703 5.040256)
			(xy 247.584906 5.0292) (xy 248.766584 5.0292) (xy 248.766584 5.8928) (xy 248.76707 5.920069) (xy 248.774832 5.974053)
			(xy 248.790197 6.026383) (xy 248.812854 6.075993) (xy 248.84234 6.121874) (xy 248.878055 6.163091)
			(xy 248.919272 6.198806) (xy 248.965153 6.228292) (xy 249.014763 6.250949) (xy 249.067093 6.266314)
			(xy 249.121077 6.274076) (xy 249.175615 6.274076) (xy 249.229599 6.266314) (xy 249.281929 6.250949)
			(xy 249.331539 6.228292) (xy 249.37742 6.198806) (xy 249.418637 6.163091) (xy 249.454352 6.121874)
			(xy 249.483838 6.075993) (xy 249.506495 6.026383) (xy 249.52186 5.974053) (xy 249.529622 5.920069)
			(xy 249.530108 5.8928) (xy 249.530108 5.0292) (xy 249.529622 5.001931) (xy 249.52186 4.947947) (xy 249.506495 4.895617)
			(xy 249.483838 4.846007) (xy 249.454352 4.800126) (xy 249.418637 4.758909) (xy 249.37742 4.723194)
			(xy 249.331539 4.693708) (xy 249.281929 4.671051) (xy 249.229599 4.655686) (xy 249.175615 4.647924)
			(xy 249.121077 4.647924) (xy 249.067093 4.655686) (xy 249.014763 4.671051) (xy 248.965153 4.693708)
			(xy 248.919272 4.723194) (xy 248.878055 4.758909) (xy 248.84234 4.800126) (xy 248.812854 4.846007)
			(xy 248.790197 4.895617) (xy 248.774832 4.947947) (xy 248.76707 5.001931) (xy 248.766584 5.0292)
			(xy 247.584906 5.0292) (xy 247.639463 5.002034) (xy 247.712369 4.956893) (xy 247.780798 4.905217)
			(xy 247.844168 4.847448) (xy 247.901937 4.784078) (xy 247.953613 4.715649) (xy 247.998754 4.642743)
			(xy 248.036976 4.565983) (xy 248.067952 4.486024) (xy 248.091419 4.403548) (xy 248.107175 4.319258)
			(xy 248.115087 4.233875) (xy 248.115582 4.191) (xy 248.115087 4.148125) (xy 252.610353 4.148125)
			(xy 252.610353 4.233875) (xy 252.618265 4.319258) (xy 252.634021 4.403548) (xy 252.657488 4.486024)
			(xy 252.688464 4.565983) (xy 252.726686 4.642743) (xy 252.771827 4.715649) (xy 252.823503 4.784078)
			(xy 252.881272 4.847448) (xy 252.944642 4.905217) (xy 253.013071 4.956893) (xy 253.085977 5.002034)
			(xy 253.162737 5.040256) (xy 253.242696 5.071232) (xy 253.325172 5.094699) (xy 253.409462 5.110455)
			(xy 253.494845 5.118367) (xy 253.580595 5.118367) (xy 253.665978 5.110455) (xy 253.750268 5.094699)
			(xy 253.832744 5.071232) (xy 253.912703 5.040256) (xy 253.989463 5.002034) (xy 254.062369 4.956893)
			(xy 254.130798 4.905217) (xy 254.194168 4.847448) (xy 254.251937 4.784078) (xy 254.303613 4.715649)
			(xy 254.348754 4.642743) (xy 254.386976 4.565983) (xy 254.417952 4.486024) (xy 254.441419 4.403548)
			(xy 254.457175 4.319258) (xy 254.465087 4.233875) (xy 254.465582 4.191) (xy 254.465119 4.150919)
			(xy 256.921241 4.150919) (xy 256.921241 4.236669) (xy 256.929153 4.322052) (xy 256.944909 4.406342)
			(xy 256.968376 4.488818) (xy 256.999352 4.568777) (xy 257.037574 4.645537) (xy 257.082715 4.718443)
			(xy 257.134391 4.786872) (xy 257.19216 4.850242) (xy 257.25553 4.908011) (xy 257.323959 4.959687)
			(xy 257.396865 5.004828) (xy 257.473625 5.04305) (xy 257.553584 5.074026) (xy 257.63606 5.097493)
			(xy 257.72035 5.113249) (xy 257.805733 5.121161) (xy 257.891483 5.121161) (xy 257.976866 5.113249)
			(xy 258.061156 5.097493) (xy 258.143632 5.074026) (xy 258.223591 5.04305) (xy 258.245794 5.031994)
			(xy 261.85622 5.031994) (xy 261.85622 5.895594) (xy 261.856706 5.922863) (xy 261.864468 5.976847)
			(xy 261.879833 6.029177) (xy 261.90249 6.078787) (xy 261.931976 6.124668) (xy 261.967691 6.165885)
			(xy 262.008908 6.2016) (xy 262.054789 6.231086) (xy 262.104399 6.253743) (xy 262.156729 6.269108)
			(xy 262.210713 6.27687) (xy 262.265251 6.27687) (xy 262.319235 6.269108) (xy 262.371565 6.253743)
			(xy 262.421175 6.231086) (xy 262.467056 6.2016) (xy 262.508273 6.165885) (xy 262.543988 6.124668)
			(xy 262.573474 6.078787) (xy 262.596131 6.029177) (xy 262.611496 5.976847) (xy 262.619258 5.922863)
			(xy 262.619744 5.895594) (xy 262.619744 5.031994) (xy 262.619258 5.004725) (xy 262.611496 4.950741)
			(xy 262.596131 4.898411) (xy 262.573474 4.848801) (xy 262.543988 4.80292) (xy 262.508273 4.761703)
			(xy 262.467056 4.725988) (xy 262.421175 4.696502) (xy 262.371565 4.673845) (xy 262.319235 4.65848)
			(xy 262.265251 4.650718) (xy 262.210713 4.650718) (xy 262.156729 4.65848) (xy 262.104399 4.673845)
			(xy 262.054789 4.696502) (xy 262.008908 4.725988) (xy 261.967691 4.761703) (xy 261.931976 4.80292)
			(xy 261.90249 4.848801) (xy 261.879833 4.898411) (xy 261.864468 4.950741) (xy 261.856706 5.004725)
			(xy 261.85622 5.031994) (xy 258.245794 5.031994) (xy 258.300351 5.004828) (xy 258.373257 4.959687)
			(xy 258.441686 4.908011) (xy 258.505056 4.850242) (xy 258.562825 4.786872) (xy 258.614501 4.718443)
			(xy 258.659642 4.645537) (xy 258.697864 4.568777) (xy 258.72884 4.488818) (xy 258.752307 4.406342)
			(xy 258.768063 4.322052) (xy 258.775975 4.236669) (xy 258.77647 4.193794) (xy 258.775975 4.150919)
			(xy 263.271241 4.150919) (xy 263.271241 4.236669) (xy 263.279153 4.322052) (xy 263.294909 4.406342)
			(xy 263.318376 4.488818) (xy 263.349352 4.568777) (xy 263.387574 4.645537) (xy 263.432715 4.718443)
			(xy 263.484391 4.786872) (xy 263.54216 4.850242) (xy 263.60553 4.908011) (xy 263.673959 4.959687)
			(xy 263.746865 5.004828) (xy 263.823625 5.04305) (xy 263.903584 5.074026) (xy 263.98606 5.097493)
			(xy 264.07035 5.113249) (xy 264.155733 5.121161) (xy 264.241483 5.121161) (xy 264.326866 5.113249)
			(xy 264.411156 5.097493) (xy 264.493632 5.074026) (xy 264.573591 5.04305) (xy 264.650351 5.004828)
			(xy 264.723257 4.959687) (xy 264.791686 4.908011) (xy 264.855056 4.850242) (xy 264.912825 4.786872)
			(xy 264.964501 4.718443) (xy 265.009642 4.645537) (xy 265.047864 4.568777) (xy 265.07884 4.488818)
			(xy 265.102307 4.406342) (xy 265.118063 4.322052) (xy 265.125975 4.236669) (xy 265.12647 4.193794)
			(xy 265.125975 4.150919) (xy 324.845921 4.150919) (xy 324.845921 4.236669) (xy 324.853833 4.322052)
			(xy 324.869589 4.406342) (xy 324.893056 4.488818) (xy 324.924032 4.568777) (xy 324.962254 4.645537)
			(xy 325.007395 4.718443) (xy 325.059071 4.786872) (xy 325.11684 4.850242) (xy 325.18021 4.908011)
			(xy 325.248639 4.959687) (xy 325.321545 5.004828) (xy 325.398305 5.04305) (xy 325.478264 5.074026)
			(xy 325.56074 5.097493) (xy 325.64503 5.113249) (xy 325.730413 5.121161) (xy 325.816163 5.121161)
			(xy 325.901546 5.113249) (xy 325.985836 5.097493) (xy 326.068312 5.074026) (xy 326.148271 5.04305)
			(xy 326.170474 5.031994) (xy 327.352152 5.031994) (xy 327.352152 5.895594) (xy 327.352638 5.922863)
			(xy 327.3604 5.976847) (xy 327.375765 6.029177) (xy 327.398422 6.078787) (xy 327.427908 6.124668)
			(xy 327.463623 6.165885) (xy 327.50484 6.2016) (xy 327.550721 6.231086) (xy 327.600331 6.253743)
			(xy 327.652661 6.269108) (xy 327.706645 6.27687) (xy 327.761183 6.27687) (xy 327.815167 6.269108)
			(xy 327.867497 6.253743) (xy 327.917107 6.231086) (xy 327.962988 6.2016) (xy 328.004205 6.165885)
			(xy 328.03992 6.124668) (xy 328.069406 6.078787) (xy 328.092063 6.029177) (xy 328.107428 5.976847)
			(xy 328.11519 5.922863) (xy 328.115676 5.895594) (xy 328.115676 5.031994) (xy 328.11519 5.004725)
			(xy 328.107428 4.950741) (xy 328.092063 4.898411) (xy 328.069406 4.848801) (xy 328.03992 4.80292)
			(xy 328.004205 4.761703) (xy 327.962988 4.725988) (xy 327.917107 4.696502) (xy 327.867497 4.673845)
			(xy 327.815167 4.65848) (xy 327.761183 4.650718) (xy 327.706645 4.650718) (xy 327.652661 4.65848)
			(xy 327.600331 4.673845) (xy 327.550721 4.696502) (xy 327.50484 4.725988) (xy 327.463623 4.761703)
			(xy 327.427908 4.80292) (xy 327.398422 4.848801) (xy 327.375765 4.898411) (xy 327.3604 4.950741)
			(xy 327.352638 5.004725) (xy 327.352152 5.031994) (xy 326.170474 5.031994) (xy 326.225031 5.004828)
			(xy 326.297937 4.959687) (xy 326.366366 4.908011) (xy 326.429736 4.850242) (xy 326.487505 4.786872)
			(xy 326.539181 4.718443) (xy 326.584322 4.645537) (xy 326.622544 4.568777) (xy 326.65352 4.488818)
			(xy 326.676987 4.406342) (xy 326.692743 4.322052) (xy 326.700655 4.236669) (xy 326.70115 4.193794)
			(xy 326.700655 4.150919) (xy 331.195921 4.150919) (xy 331.195921 4.236669) (xy 331.203833 4.322052)
			(xy 331.219589 4.406342) (xy 331.243056 4.488818) (xy 331.274032 4.568777) (xy 331.312254 4.645537)
			(xy 331.357395 4.718443) (xy 331.409071 4.786872) (xy 331.46684 4.850242) (xy 331.53021 4.908011)
			(xy 331.598639 4.959687) (xy 331.671545 5.004828) (xy 331.748305 5.04305) (xy 331.828264 5.074026)
			(xy 331.91074 5.097493) (xy 331.99503 5.113249) (xy 332.080413 5.121161) (xy 332.166163 5.121161)
			(xy 332.251546 5.113249) (xy 332.335836 5.097493) (xy 332.418312 5.074026) (xy 332.498271 5.04305)
			(xy 332.575031 5.004828) (xy 332.647937 4.959687) (xy 332.716366 4.908011) (xy 332.779736 4.850242)
			(xy 332.837505 4.786872) (xy 332.889181 4.718443) (xy 332.934322 4.645537) (xy 332.972544 4.568777)
			(xy 333.00352 4.488818) (xy 333.026987 4.406342) (xy 333.042743 4.322052) (xy 333.050655 4.236669)
			(xy 333.05115 4.193794) (xy 333.050655 4.150919) (xy 335.488267 4.150919) (xy 335.488267 4.236669)
			(xy 335.496179 4.322052) (xy 335.511935 4.406342) (xy 335.535402 4.488818) (xy 335.566378 4.568777)
			(xy 335.6046 4.645537) (xy 335.649741 4.718443) (xy 335.701417 4.786872) (xy 335.759186 4.850242)
			(xy 335.822556 4.908011) (xy 335.890985 4.959687) (xy 335.963891 5.004828) (xy 336.040651 5.04305)
			(xy 336.12061 5.074026) (xy 336.203086 5.097493) (xy 336.287376 5.113249) (xy 336.372759 5.121161)
			(xy 336.458509 5.121161) (xy 336.543892 5.113249) (xy 336.628182 5.097493) (xy 336.710658 5.074026)
			(xy 336.790617 5.04305) (xy 336.81282 5.031994) (xy 340.4235 5.031994) (xy 340.4235 5.895594) (xy 340.423986 5.922845)
			(xy 340.431742 5.976793) (xy 340.447097 6.029088) (xy 340.469739 6.078665) (xy 340.499205 6.124515)
			(xy 340.534896 6.165706) (xy 340.576087 6.201397) (xy 340.621937 6.230863) (xy 340.671514 6.253505)
			(xy 340.723809 6.26886) (xy 340.777757 6.276616) (xy 340.832259 6.276616) (xy 340.886207 6.26886)
			(xy 340.938502 6.253505) (xy 340.988079 6.230863) (xy 341.033929 6.201397) (xy 341.07512 6.165706)
			(xy 341.110811 6.124515) (xy 341.140277 6.078665) (xy 341.162919 6.029088) (xy 341.178274 5.976793)
			(xy 341.18603 5.922845) (xy 341.186516 5.895594) (xy 341.186516 5.031994) (xy 341.18603 5.004743)
			(xy 341.178274 4.950795) (xy 341.162919 4.8985) (xy 341.140277 4.848923) (xy 341.110811 4.803073)
			(xy 341.07512 4.761882) (xy 341.033929 4.726191) (xy 340.988079 4.696725) (xy 340.938502 4.674083)
			(xy 340.886207 4.658728) (xy 340.832259 4.650972) (xy 340.777757 4.650972) (xy 340.723809 4.658728)
			(xy 340.671514 4.674083) (xy 340.621937 4.696725) (xy 340.576087 4.726191) (xy 340.534896 4.761882)
			(xy 340.499205 4.803073) (xy 340.469739 4.848923) (xy 340.447097 4.8985) (xy 340.431742 4.950795)
			(xy 340.423986 5.004743) (xy 340.4235 5.031994) (xy 336.81282 5.031994) (xy 336.867377 5.004828)
			(xy 336.940283 4.959687) (xy 337.008712 4.908011) (xy 337.072082 4.850242) (xy 337.129851 4.786872)
			(xy 337.181527 4.718443) (xy 337.226668 4.645537) (xy 337.26489 4.568777) (xy 337.295866 4.488818)
			(xy 337.319333 4.406342) (xy 337.335089 4.322052) (xy 337.343001 4.236669) (xy 337.343496 4.193794)
			(xy 337.343001 4.150919) (xy 341.838267 4.150919) (xy 341.838267 4.236669) (xy 341.846179 4.322052)
			(xy 341.861935 4.406342) (xy 341.885402 4.488818) (xy 341.916378 4.568777) (xy 341.9546 4.645537)
			(xy 341.999741 4.718443) (xy 342.051417 4.786872) (xy 342.109186 4.850242) (xy 342.172556 4.908011)
			(xy 342.240985 4.959687) (xy 342.313891 5.004828) (xy 342.390651 5.04305) (xy 342.47061 5.074026)
			(xy 342.553086 5.097493) (xy 342.637376 5.113249) (xy 342.722759 5.121161) (xy 342.808509 5.121161)
			(xy 342.893892 5.113249) (xy 342.978182 5.097493) (xy 343.060658 5.074026) (xy 343.140617 5.04305)
			(xy 343.217377 5.004828) (xy 343.290283 4.959687) (xy 343.358712 4.908011) (xy 343.422082 4.850242)
			(xy 343.479851 4.786872) (xy 343.531527 4.718443) (xy 343.576668 4.645537) (xy 343.61489 4.568777)
			(xy 343.645866 4.488818) (xy 343.669333 4.406342) (xy 343.685089 4.322052) (xy 343.693001 4.236669)
			(xy 343.693496 4.193794) (xy 343.693001 4.150919) (xy 373.705107 4.150919) (xy 373.705107 4.236669)
			(xy 373.713019 4.322052) (xy 373.728775 4.406342) (xy 373.752242 4.488818) (xy 373.783218 4.568777)
			(xy 373.82144 4.645537) (xy 373.866581 4.718443) (xy 373.918257 4.786872) (xy 373.976026 4.850242)
			(xy 374.039396 4.908011) (xy 374.107825 4.959687) (xy 374.180731 5.004828) (xy 374.257491 5.04305)
			(xy 374.33745 5.074026) (xy 374.419926 5.097493) (xy 374.504216 5.113249) (xy 374.589599 5.121161)
			(xy 374.675349 5.121161) (xy 374.760732 5.113249) (xy 374.845022 5.097493) (xy 374.927498 5.074026)
			(xy 375.007457 5.04305) (xy 375.02966 5.031994) (xy 376.211592 5.031994) (xy 376.211592 5.895594)
			(xy 376.212078 5.922845) (xy 376.219834 5.976793) (xy 376.235189 6.029088) (xy 376.257831 6.078665)
			(xy 376.287297 6.124515) (xy 376.322988 6.165706) (xy 376.364179 6.201397) (xy 376.410029 6.230863)
			(xy 376.459606 6.253505) (xy 376.511901 6.26886) (xy 376.565849 6.276616) (xy 376.620351 6.276616)
			(xy 376.674299 6.26886) (xy 376.726594 6.253505) (xy 376.776171 6.230863) (xy 376.822021 6.201397)
			(xy 376.863212 6.165706) (xy 376.898903 6.124515) (xy 376.928369 6.078665) (xy 376.951011 6.029088)
			(xy 376.966366 5.976793) (xy 376.974122 5.922845) (xy 376.974608 5.895594) (xy 376.974608 5.031994)
			(xy 376.974122 5.004743) (xy 376.966366 4.950795) (xy 376.951011 4.8985) (xy 376.928369 4.848923)
			(xy 376.898903 4.803073) (xy 376.863212 4.761882) (xy 376.822021 4.726191) (xy 376.776171 4.696725)
			(xy 376.726594 4.674083) (xy 376.674299 4.658728) (xy 376.620351 4.650972) (xy 376.565849 4.650972)
			(xy 376.511901 4.658728) (xy 376.459606 4.674083) (xy 376.410029 4.696725) (xy 376.364179 4.726191)
			(xy 376.322988 4.761882) (xy 376.287297 4.803073) (xy 376.257831 4.848923) (xy 376.235189 4.8985)
			(xy 376.219834 4.950795) (xy 376.212078 5.004743) (xy 376.211592 5.031994) (xy 375.02966 5.031994)
			(xy 375.084217 5.004828) (xy 375.157123 4.959687) (xy 375.225552 4.908011) (xy 375.288922 4.850242)
			(xy 375.346691 4.786872) (xy 375.398367 4.718443) (xy 375.443508 4.645537) (xy 375.48173 4.568777)
			(xy 375.512706 4.488818) (xy 375.536173 4.406342) (xy 375.551929 4.322052) (xy 375.559841 4.236669)
			(xy 375.560336 4.193794) (xy 375.559841 4.150919) (xy 380.055107 4.150919) (xy 380.055107 4.236669)
			(xy 380.063019 4.322052) (xy 380.078775 4.406342) (xy 380.102242 4.488818) (xy 380.133218 4.568777)
			(xy 380.17144 4.645537) (xy 380.216581 4.718443) (xy 380.268257 4.786872) (xy 380.326026 4.850242)
			(xy 380.389396 4.908011) (xy 380.457825 4.959687) (xy 380.530731 5.004828) (xy 380.607491 5.04305)
			(xy 380.68745 5.074026) (xy 380.769926 5.097493) (xy 380.854216 5.113249) (xy 380.939599 5.121161)
			(xy 381.025349 5.121161) (xy 381.110732 5.113249) (xy 381.195022 5.097493) (xy 381.277498 5.074026)
			(xy 381.357457 5.04305) (xy 381.434217 5.004828) (xy 381.507123 4.959687) (xy 381.575552 4.908011)
			(xy 381.638922 4.850242) (xy 381.696691 4.786872) (xy 381.748367 4.718443) (xy 381.793508 4.645537)
			(xy 381.83173 4.568777) (xy 381.862706 4.488818) (xy 381.886173 4.406342) (xy 381.901929 4.322052)
			(xy 381.909841 4.236669) (xy 381.910336 4.193794) (xy 381.909841 4.150919) (xy 381.901929 4.065536)
			(xy 381.886173 3.981246) (xy 381.862706 3.89877) (xy 381.83173 3.818811) (xy 381.793508 3.742051)
			(xy 381.748367 3.669145) (xy 381.696691 3.600716) (xy 381.638922 3.537346) (xy 381.575552 3.479577)
			(xy 381.507123 3.427901) (xy 381.434217 3.38276) (xy 381.357457 3.344538) (xy 381.277498 3.313562)
			(xy 381.195022 3.290095) (xy 381.110732 3.274339) (xy 381.025349 3.266427) (xy 380.939599 3.266427)
			(xy 380.854216 3.274339) (xy 380.769926 3.290095) (xy 380.68745 3.313562) (xy 380.607491 3.344538)
			(xy 380.530731 3.38276) (xy 380.457825 3.427901) (xy 380.389396 3.479577) (xy 380.326026 3.537346)
			(xy 380.268257 3.600716) (xy 380.216581 3.669145) (xy 380.17144 3.742051) (xy 380.133218 3.818811)
			(xy 380.102242 3.89877) (xy 380.078775 3.981246) (xy 380.063019 4.065536) (xy 380.055107 4.150919)
			(xy 375.559841 4.150919) (xy 375.551929 4.065536) (xy 375.536173 3.981246) (xy 375.512706 3.89877)
			(xy 375.48173 3.818811) (xy 375.443508 3.742051) (xy 375.398367 3.669145) (xy 375.346691 3.600716)
			(xy 375.288922 3.537346) (xy 375.225552 3.479577) (xy 375.157123 3.427901) (xy 375.084217 3.38276)
			(xy 375.007457 3.344538) (xy 374.927498 3.313562) (xy 374.845022 3.290095) (xy 374.760732 3.274339)
			(xy 374.675349 3.266427) (xy 374.589599 3.266427) (xy 374.504216 3.274339) (xy 374.419926 3.290095)
			(xy 374.33745 3.313562) (xy 374.257491 3.344538) (xy 374.180731 3.38276) (xy 374.107825 3.427901)
			(xy 374.039396 3.479577) (xy 373.976026 3.537346) (xy 373.918257 3.600716) (xy 373.866581 3.669145)
			(xy 373.82144 3.742051) (xy 373.783218 3.818811) (xy 373.752242 3.89877) (xy 373.728775 3.981246)
			(xy 373.713019 4.065536) (xy 373.705107 4.150919) (xy 343.693001 4.150919) (xy 343.685089 4.065536)
			(xy 343.669333 3.981246) (xy 343.645866 3.89877) (xy 343.61489 3.818811) (xy 343.576668 3.742051)
			(xy 343.531527 3.669145) (xy 343.479851 3.600716) (xy 343.422082 3.537346) (xy 343.358712 3.479577)
			(xy 343.290283 3.427901) (xy 343.217377 3.38276) (xy 343.140617 3.344538) (xy 343.060658 3.313562)
			(xy 342.978182 3.290095) (xy 342.893892 3.274339) (xy 342.808509 3.266427) (xy 342.722759 3.266427)
			(xy 342.637376 3.274339) (xy 342.553086 3.290095) (xy 342.47061 3.313562) (xy 342.390651 3.344538)
			(xy 342.313891 3.38276) (xy 342.240985 3.427901) (xy 342.172556 3.479577) (xy 342.109186 3.537346)
			(xy 342.051417 3.600716) (xy 341.999741 3.669145) (xy 341.9546 3.742051) (xy 341.916378 3.818811)
			(xy 341.885402 3.89877) (xy 341.861935 3.981246) (xy 341.846179 4.065536) (xy 341.838267 4.150919)
			(xy 337.343001 4.150919) (xy 337.335089 4.065536) (xy 337.319333 3.981246) (xy 337.295866 3.89877)
			(xy 337.26489 3.818811) (xy 337.226668 3.742051) (xy 337.181527 3.669145) (xy 337.129851 3.600716)
			(xy 337.072082 3.537346) (xy 337.008712 3.479577) (xy 336.940283 3.427901) (xy 336.867377 3.38276)
			(xy 336.790617 3.344538) (xy 336.710658 3.313562) (xy 336.628182 3.290095) (xy 336.543892 3.274339)
			(xy 336.458509 3.266427) (xy 336.372759 3.266427) (xy 336.287376 3.274339) (xy 336.203086 3.290095)
			(xy 336.12061 3.313562) (xy 336.040651 3.344538) (xy 335.963891 3.38276) (xy 335.890985 3.427901)
			(xy 335.822556 3.479577) (xy 335.759186 3.537346) (xy 335.701417 3.600716) (xy 335.649741 3.669145)
			(xy 335.6046 3.742051) (xy 335.566378 3.818811) (xy 335.535402 3.89877) (xy 335.511935 3.981246)
			(xy 335.496179 4.065536) (xy 335.488267 4.150919) (xy 333.050655 4.150919) (xy 333.042743 4.065536)
			(xy 333.026987 3.981246) (xy 333.00352 3.89877) (xy 332.972544 3.818811) (xy 332.934322 3.742051)
			(xy 332.889181 3.669145) (xy 332.837505 3.600716) (xy 332.779736 3.537346) (xy 332.716366 3.479577)
			(xy 332.647937 3.427901) (xy 332.575031 3.38276) (xy 332.498271 3.344538) (xy 332.418312 3.313562)
			(xy 332.335836 3.290095) (xy 332.251546 3.274339) (xy 332.166163 3.266427) (xy 332.080413 3.266427)
			(xy 331.99503 3.274339) (xy 331.91074 3.290095) (xy 331.828264 3.313562) (xy 331.748305 3.344538)
			(xy 331.671545 3.38276) (xy 331.598639 3.427901) (xy 331.53021 3.479577) (xy 331.46684 3.537346)
			(xy 331.409071 3.600716) (xy 331.357395 3.669145) (xy 331.312254 3.742051) (xy 331.274032 3.818811)
			(xy 331.243056 3.89877) (xy 331.219589 3.981246) (xy 331.203833 4.065536) (xy 331.195921 4.150919)
			(xy 326.700655 4.150919) (xy 326.692743 4.065536) (xy 326.676987 3.981246) (xy 326.65352 3.89877)
			(xy 326.622544 3.818811) (xy 326.584322 3.742051) (xy 326.539181 3.669145) (xy 326.487505 3.600716)
			(xy 326.429736 3.537346) (xy 326.366366 3.479577) (xy 326.297937 3.427901) (xy 326.225031 3.38276)
			(xy 326.148271 3.344538) (xy 326.068312 3.313562) (xy 325.985836 3.290095) (xy 325.901546 3.274339)
			(xy 325.816163 3.266427) (xy 325.730413 3.266427) (xy 325.64503 3.274339) (xy 325.56074 3.290095)
			(xy 325.478264 3.313562) (xy 325.398305 3.344538) (xy 325.321545 3.38276) (xy 325.248639 3.427901)
			(xy 325.18021 3.479577) (xy 325.11684 3.537346) (xy 325.059071 3.600716) (xy 325.007395 3.669145)
			(xy 324.962254 3.742051) (xy 324.924032 3.818811) (xy 324.893056 3.89877) (xy 324.869589 3.981246)
			(xy 324.853833 4.065536) (xy 324.845921 4.150919) (xy 265.125975 4.150919) (xy 265.118063 4.065536)
			(xy 265.102307 3.981246) (xy 265.07884 3.89877) (xy 265.047864 3.818811) (xy 265.009642 3.742051)
			(xy 264.964501 3.669145) (xy 264.912825 3.600716) (xy 264.855056 3.537346) (xy 264.791686 3.479577)
			(xy 264.723257 3.427901) (xy 264.650351 3.38276) (xy 264.573591 3.344538) (xy 264.493632 3.313562)
			(xy 264.411156 3.290095) (xy 264.326866 3.274339) (xy 264.241483 3.266427) (xy 264.155733 3.266427)
			(xy 264.07035 3.274339) (xy 263.98606 3.290095) (xy 263.903584 3.313562) (xy 263.823625 3.344538)
			(xy 263.746865 3.38276) (xy 263.673959 3.427901) (xy 263.60553 3.479577) (xy 263.54216 3.537346)
			(xy 263.484391 3.600716) (xy 263.432715 3.669145) (xy 263.387574 3.742051) (xy 263.349352 3.818811)
			(xy 263.318376 3.89877) (xy 263.294909 3.981246) (xy 263.279153 4.065536) (xy 263.271241 4.150919)
			(xy 258.775975 4.150919) (xy 258.768063 4.065536) (xy 258.752307 3.981246) (xy 258.72884 3.89877)
			(xy 258.697864 3.818811) (xy 258.659642 3.742051) (xy 258.614501 3.669145) (xy 258.562825 3.600716)
			(xy 258.505056 3.537346) (xy 258.441686 3.479577) (xy 258.373257 3.427901) (xy 258.300351 3.38276)
			(xy 258.223591 3.344538) (xy 258.143632 3.313562) (xy 258.061156 3.290095) (xy 257.976866 3.274339)
			(xy 257.891483 3.266427) (xy 257.805733 3.266427) (xy 257.72035 3.274339) (xy 257.63606 3.290095)
			(xy 257.553584 3.313562) (xy 257.473625 3.344538) (xy 257.396865 3.38276) (xy 257.323959 3.427901)
			(xy 257.25553 3.479577) (xy 257.19216 3.537346) (xy 257.134391 3.600716) (xy 257.082715 3.669145)
			(xy 257.037574 3.742051) (xy 256.999352 3.818811) (xy 256.968376 3.89877) (xy 256.944909 3.981246)
			(xy 256.929153 4.065536) (xy 256.921241 4.150919) (xy 254.465119 4.150919) (xy 254.465087 4.148125)
			(xy 254.457175 4.062742) (xy 254.441419 3.978452) (xy 254.417952 3.895976) (xy 254.386976 3.816017)
			(xy 254.348754 3.739257) (xy 254.303613 3.666351) (xy 254.251937 3.597922) (xy 254.194168 3.534552)
			(xy 254.130798 3.476783) (xy 254.062369 3.425107) (xy 253.989463 3.379966) (xy 253.912703 3.341744)
			(xy 253.832744 3.310768) (xy 253.750268 3.287301) (xy 253.665978 3.271545) (xy 253.580595 3.263633)
			(xy 253.494845 3.263633) (xy 253.409462 3.271545) (xy 253.325172 3.287301) (xy 253.242696 3.310768)
			(xy 253.162737 3.341744) (xy 253.085977 3.379966) (xy 253.013071 3.425107) (xy 252.944642 3.476783)
			(xy 252.881272 3.534552) (xy 252.823503 3.597922) (xy 252.771827 3.666351) (xy 252.726686 3.739257)
			(xy 252.688464 3.816017) (xy 252.657488 3.895976) (xy 252.634021 3.978452) (xy 252.618265 4.062742)
			(xy 252.610353 4.148125) (xy 248.115087 4.148125) (xy 248.107175 4.062742) (xy 248.091419 3.978452)
			(xy 248.067952 3.895976) (xy 248.036976 3.816017) (xy 247.998754 3.739257) (xy 247.953613 3.666351)
			(xy 247.901937 3.597922) (xy 247.844168 3.534552) (xy 247.780798 3.476783) (xy 247.712369 3.425107)
			(xy 247.639463 3.379966) (xy 247.562703 3.341744) (xy 247.482744 3.310768) (xy 247.400268 3.287301)
			(xy 247.315978 3.271545) (xy 247.230595 3.263633) (xy 247.144845 3.263633) (xy 247.059462 3.271545)
			(xy 246.975172 3.287301) (xy 246.892696 3.310768) (xy 246.812737 3.341744) (xy 246.735977 3.379966)
			(xy 246.663071 3.425107) (xy 246.594642 3.476783) (xy 246.531272 3.534552) (xy 246.473503 3.597922)
			(xy 246.421827 3.666351) (xy 246.376686 3.739257) (xy 246.338464 3.816017) (xy 246.307488 3.895976)
			(xy 246.284021 3.978452) (xy 246.268265 4.062742) (xy 246.260353 4.148125) (xy 186.540407 4.148125)
			(xy 186.532495 4.062742) (xy 186.516739 3.978452) (xy 186.493272 3.895976) (xy 186.462296 3.816017)
			(xy 186.424074 3.739257) (xy 186.378933 3.666351) (xy 186.327257 3.597922) (xy 186.269488 3.534552)
			(xy 186.206118 3.476783) (xy 186.137689 3.425107) (xy 186.064783 3.379966) (xy 185.988023 3.341744)
			(xy 185.908064 3.310768) (xy 185.825588 3.287301) (xy 185.741298 3.271545) (xy 185.655915 3.263633)
			(xy 185.570165 3.263633) (xy 185.484782 3.271545) (xy 185.400492 3.287301) (xy 185.318016 3.310768)
			(xy 185.238057 3.341744) (xy 185.161297 3.379966) (xy 185.088391 3.425107) (xy 185.019962 3.476783)
			(xy 184.956592 3.534552) (xy 184.898823 3.597922) (xy 184.847147 3.666351) (xy 184.802006 3.739257)
			(xy 184.763784 3.816017) (xy 184.732808 3.895976) (xy 184.709341 3.978452) (xy 184.693585 4.062742)
			(xy 184.685673 4.148125) (xy 180.190407 4.148125) (xy 180.182495 4.062742) (xy 180.166739 3.978452)
			(xy 180.143272 3.895976) (xy 180.112296 3.816017) (xy 180.074074 3.739257) (xy 180.028933 3.666351)
			(xy 179.977257 3.597922) (xy 179.919488 3.534552) (xy 179.856118 3.476783) (xy 179.787689 3.425107)
			(xy 179.714783 3.379966) (xy 179.638023 3.341744) (xy 179.558064 3.310768) (xy 179.475588 3.287301)
			(xy 179.391298 3.271545) (xy 179.305915 3.263633) (xy 179.220165 3.263633) (xy 179.134782 3.271545)
			(xy 179.050492 3.287301) (xy 178.968016 3.310768) (xy 178.888057 3.341744) (xy 178.811297 3.379966)
			(xy 178.738391 3.425107) (xy 178.669962 3.476783) (xy 178.606592 3.534552) (xy 178.548823 3.597922)
			(xy 178.497147 3.666351) (xy 178.452006 3.739257) (xy 178.413784 3.816017) (xy 178.382808 3.895976)
			(xy 178.359341 3.978452) (xy 178.343585 4.062742) (xy 178.335673 4.148125) (xy 0.508 4.148125) (xy 0.508 -7.78002)
			(xy 0.508522 -7.835827) (xy 0.516863 -7.947129) (xy 0.533498 -8.057497) (xy 0.558334 -8.166312) (xy 0.591233 -8.272968)
			(xy 0.63201 -8.376867) (xy 0.680438 -8.477428) (xy 0.736245 -8.574088) (xy 0.799119 -8.666308) (xy 0.868709 -8.753572)
			(xy 0.944626 -8.835391) (xy 1.026445 -8.911308) (xy 1.113708 -8.980898) (xy 1.205928 -9.043773) (xy 1.302589 -9.09958)
			(xy 1.40315 -9.148008) (xy 1.507048 -9.188786) (xy 1.613704 -9.221685) (xy 1.722519 -9.246521) (xy 1.832887 -9.263157)
			(xy 1.944189 -9.271498) (xy 1.999996 -9.272016) (xy 9.10209 -9.272016) (xy 9.157898 -9.271495) (xy 9.269201 -9.263154)
			(xy 9.379569 -9.24652) (xy 9.488386 -9.221684) (xy 9.595043 -9.188786) (xy 9.698942 -9.148009) (xy 9.799505 -9.099582)
			(xy 9.896167 -9.043775) (xy 9.988388 -8.980901) (xy 10.075653 -8.911311) (xy 10.157473 -8.835394)
			(xy 10.233392 -8.753575) (xy 10.302983 -8.666312) (xy 10.365859 -8.574092) (xy 10.421668 -8.477431)
			(xy 10.470097 -8.37687) (xy 10.510876 -8.272971) (xy 10.543776 -8.166315) (xy 10.568614 -8.057499)
			(xy 10.585251 -7.94713) (xy 10.593594 -7.835828) (xy 10.594086 -7.78002) (xy 10.594086 0.999998)
			(xy 10.59457 1.070352) (xy 10.60246 1.210839) (xy 10.618214 1.350662) (xy 10.641783 1.489382) (xy 10.673094 1.626562)
			(xy 10.712047 1.761771) (xy 10.758519 1.894583) (xy 10.812366 2.02458) (xy 10.873417 2.151354) (xy 10.94148 2.274505)
			(xy 11.016341 2.393646) (xy 11.097765 2.508402) (xy 11.185495 2.618411) (xy 11.279255 2.723329) (xy 11.378751 2.822825)
			(xy 11.483669 2.916585) (xy 11.593678 3.004315) (xy 11.708434 3.085739) (xy 11.827575 3.1606) (xy 11.950726 3.228663)
			(xy 12.0775 3.289714) (xy 12.207497 3.343561) (xy 12.340309 3.390033) (xy 12.475518 3.428986) (xy 12.612698 3.460297)
			(xy 12.751418 3.483866) (xy 12.891241 3.49962) (xy 13.031728 3.50751) (xy 13.102082 3.507994) (xy 81.701894 3.507994)
			(xy 81.772248 3.50751) (xy 81.912735 3.499621) (xy 82.052558 3.483867) (xy 82.191278 3.460297) (xy 82.328459 3.428987)
			(xy 82.463668 3.390034) (xy 82.59648 3.343562) (xy 82.726477 3.289715) (xy 82.853251 3.228664) (xy 82.976402 3.160601)
			(xy 83.095543 3.08574) (xy 83.2103 3.004317) (xy 83.32031 2.916587) (xy 83.425228 2.822826) (xy 83.524724 2.723331)
			(xy 83.618484 2.618413) (xy 83.706214 2.508403) (xy 83.787638 2.393647) (xy 83.862499 2.274506) (xy 83.930563 2.151355)
			(xy 83.991614 2.024581) (xy 84.04546 1.894584) (xy 84.091933 1.761772) (xy 84.130886 1.626563) (xy 84.135094 1.608125)
			(xy 178.335673 1.608125) (xy 178.335673 1.693875) (xy 178.343585 1.779258) (xy 178.359341 1.863548)
			(xy 178.382808 1.946024) (xy 178.413784 2.025983) (xy 178.452006 2.102743) (xy 178.497147 2.175649)
			(xy 178.548823 2.244078) (xy 178.606592 2.307448) (xy 178.669962 2.365217) (xy 178.738391 2.416893)
			(xy 178.811297 2.462034) (xy 178.888057 2.500256) (xy 178.968016 2.531232) (xy 179.050492 2.554699)
			(xy 179.134782 2.570455) (xy 179.220165 2.578367) (xy 179.305915 2.578367) (xy 179.391298 2.570455)
			(xy 179.475588 2.554699) (xy 179.558064 2.531232) (xy 179.638023 2.500256) (xy 179.660226 2.4892)
			(xy 183.270652 2.4892) (xy 183.270652 3.3528) (xy 183.271138 3.380069) (xy 183.2789 3.434053) (xy 183.294265 3.486383)
			(xy 183.316922 3.535993) (xy 183.346408 3.581874) (xy 183.382123 3.623091) (xy 183.42334 3.658806)
			(xy 183.469221 3.688292) (xy 183.518831 3.710949) (xy 183.571161 3.726314) (xy 183.625145 3.734076)
			(xy 183.679683 3.734076) (xy 183.733667 3.726314) (xy 183.785997 3.710949) (xy 183.835607 3.688292)
			(xy 183.881488 3.658806) (xy 183.922705 3.623091) (xy 183.95842 3.581874) (xy 183.987906 3.535993)
			(xy 184.010563 3.486383) (xy 184.025928 3.434053) (xy 184.03369 3.380069) (xy 184.034176 3.3528)
			(xy 184.034176 2.4892) (xy 184.03369 2.461931) (xy 184.025928 2.407947) (xy 184.010563 2.355617)
			(xy 183.987906 2.306007) (xy 183.95842 2.260126) (xy 183.922705 2.218909) (xy 183.881488 2.183194)
			(xy 183.835607 2.153708) (xy 183.785997 2.131051) (xy 183.733667 2.115686) (xy 183.679683 2.107924)
			(xy 183.625145 2.107924) (xy 183.571161 2.115686) (xy 183.518831 2.131051) (xy 183.469221 2.153708)
			(xy 183.42334 2.183194) (xy 183.382123 2.218909) (xy 183.346408 2.260126) (xy 183.316922 2.306007)
			(xy 183.294265 2.355617) (xy 183.2789 2.407947) (xy 183.271138 2.461931) (xy 183.270652 2.4892) (xy 179.660226 2.4892)
			(xy 179.714783 2.462034) (xy 179.787689 2.416893) (xy 179.856118 2.365217) (xy 179.919488 2.307448)
			(xy 179.977257 2.244078) (xy 180.028933 2.175649) (xy 180.074074 2.102743) (xy 180.112296 2.025983)
			(xy 180.143272 1.946024) (xy 180.166739 1.863548) (xy 180.182495 1.779258) (xy 180.190407 1.693875)
			(xy 180.190902 1.651) (xy 180.190407 1.608125) (xy 184.685673 1.608125) (xy 184.685673 1.693875)
			(xy 184.693585 1.779258) (xy 184.709341 1.863548) (xy 184.732808 1.946024) (xy 184.763784 2.025983)
			(xy 184.802006 2.102743) (xy 184.847147 2.175649) (xy 184.898823 2.244078) (xy 184.956592 2.307448)
			(xy 185.019962 2.365217) (xy 185.088391 2.416893) (xy 185.161297 2.462034) (xy 185.238057 2.500256)
			(xy 185.318016 2.531232) (xy 185.400492 2.554699) (xy 185.484782 2.570455) (xy 185.570165 2.578367)
			(xy 185.655915 2.578367) (xy 185.741298 2.570455) (xy 185.825588 2.554699) (xy 185.908064 2.531232)
			(xy 185.988023 2.500256) (xy 186.064783 2.462034) (xy 186.137689 2.416893) (xy 186.206118 2.365217)
			(xy 186.269488 2.307448) (xy 186.327257 2.244078) (xy 186.378933 2.175649) (xy 186.424074 2.102743)
			(xy 186.462296 2.025983) (xy 186.493272 1.946024) (xy 186.516739 1.863548) (xy 186.532495 1.779258)
			(xy 186.540407 1.693875) (xy 186.540902 1.651) (xy 186.540407 1.608125) (xy 246.260353 1.608125)
			(xy 246.260353 1.693875) (xy 246.268265 1.779258) (xy 246.284021 1.863548) (xy 246.307488 1.946024)
			(xy 246.338464 2.025983) (xy 246.376686 2.102743) (xy 246.421827 2.175649) (xy 246.473503 2.244078)
			(xy 246.531272 2.307448) (xy 246.594642 2.365217) (xy 246.663071 2.416893) (xy 246.735977 2.462034)
			(xy 246.812737 2.500256) (xy 246.892696 2.531232) (xy 246.975172 2.554699) (xy 247.059462 2.570455)
			(xy 247.144845 2.578367) (xy 247.230595 2.578367) (xy 247.315978 2.570455) (xy 247.400268 2.554699)
			(xy 247.482744 2.531232) (xy 247.562703 2.500256) (xy 247.584906 2.4892) (xy 248.766584 2.4892) (xy 248.766584 3.3528)
			(xy 248.76707 3.380069) (xy 248.774832 3.434053) (xy 248.790197 3.486383) (xy 248.812854 3.535993)
			(xy 248.84234 3.581874) (xy 248.878055 3.623091) (xy 248.919272 3.658806) (xy 248.965153 3.688292)
			(xy 249.014763 3.710949) (xy 249.067093 3.726314) (xy 249.121077 3.734076) (xy 249.175615 3.734076)
			(xy 249.229599 3.726314) (xy 249.281929 3.710949) (xy 249.331539 3.688292) (xy 249.37742 3.658806)
			(xy 249.418637 3.623091) (xy 249.454352 3.581874) (xy 249.483838 3.535993) (xy 249.506495 3.486383)
			(xy 249.52186 3.434053) (xy 249.529622 3.380069) (xy 249.530108 3.3528) (xy 249.530108 2.4892) (xy 249.529622 2.461931)
			(xy 249.52186 2.407947) (xy 249.506495 2.355617) (xy 249.483838 2.306007) (xy 249.454352 2.260126)
			(xy 249.418637 2.218909) (xy 249.37742 2.183194) (xy 249.331539 2.153708) (xy 249.281929 2.131051)
			(xy 249.229599 2.115686) (xy 249.175615 2.107924) (xy 249.121077 2.107924) (xy 249.067093 2.115686)
			(xy 249.014763 2.131051) (xy 248.965153 2.153708) (xy 248.919272 2.183194) (xy 248.878055 2.218909)
			(xy 248.84234 2.260126) (xy 248.812854 2.306007) (xy 248.790197 2.355617) (xy 248.774832 2.407947)
			(xy 248.76707 2.461931) (xy 248.766584 2.4892) (xy 247.584906 2.4892) (xy 247.639463 2.462034) (xy 247.712369 2.416893)
			(xy 247.780798 2.365217) (xy 247.844168 2.307448) (xy 247.901937 2.244078) (xy 247.953613 2.175649)
			(xy 247.998754 2.102743) (xy 248.036976 2.025983) (xy 248.067952 1.946024) (xy 248.091419 1.863548)
			(xy 248.107175 1.779258) (xy 248.115087 1.693875) (xy 248.115582 1.651) (xy 248.115087 1.608125)
			(xy 252.610353 1.608125) (xy 252.610353 1.693875) (xy 252.618265 1.779258) (xy 252.634021 1.863548)
			(xy 252.657488 1.946024) (xy 252.688464 2.025983) (xy 252.726686 2.102743) (xy 252.771827 2.175649)
			(xy 252.823503 2.244078) (xy 252.881272 2.307448) (xy 252.944642 2.365217) (xy 253.013071 2.416893)
			(xy 253.085977 2.462034) (xy 253.162737 2.500256) (xy 253.242696 2.531232) (xy 253.325172 2.554699)
			(xy 253.409462 2.570455) (xy 253.494845 2.578367) (xy 253.580595 2.578367) (xy 253.665978 2.570455)
			(xy 253.750268 2.554699) (xy 253.832744 2.531232) (xy 253.912703 2.500256) (xy 253.989463 2.462034)
			(xy 254.062369 2.416893) (xy 254.130798 2.365217) (xy 254.194168 2.307448) (xy 254.251937 2.244078)
			(xy 254.303613 2.175649) (xy 254.348754 2.102743) (xy 254.386976 2.025983) (xy 254.417952 1.946024)
			(xy 254.441419 1.863548) (xy 254.457175 1.779258) (xy 254.465087 1.693875) (xy 254.465582 1.651)
			(xy 254.465119 1.610919) (xy 256.921241 1.610919) (xy 256.921241 1.696669) (xy 256.929153 1.782052)
			(xy 256.944909 1.866342) (xy 256.968376 1.948818) (xy 256.999352 2.028777) (xy 257.037574 2.105537)
			(xy 257.082715 2.178443) (xy 257.134391 2.246872) (xy 257.19216 2.310242) (xy 257.25553 2.368011)
			(xy 257.323959 2.419687) (xy 257.396865 2.464828) (xy 257.473625 2.50305) (xy 257.553584 2.534026)
			(xy 257.63606 2.557493) (xy 257.72035 2.573249) (xy 257.805733 2.581161) (xy 257.891483 2.581161)
			(xy 257.976866 2.573249) (xy 258.061156 2.557493) (xy 258.143632 2.534026) (xy 258.223591 2.50305)
			(xy 258.245794 2.491994) (xy 261.85622 2.491994) (xy 261.85622 3.355594) (xy 261.856706 3.382863)
			(xy 261.864468 3.436847) (xy 261.879833 3.489177) (xy 261.90249 3.538787) (xy 261.931976 3.584668)
			(xy 261.967691 3.625885) (xy 262.008908 3.6616) (xy 262.054789 3.691086) (xy 262.104399 3.713743)
			(xy 262.156729 3.729108) (xy 262.210713 3.73687) (xy 262.265251 3.73687) (xy 262.319235 3.729108)
			(xy 262.371565 3.713743) (xy 262.421175 3.691086) (xy 262.467056 3.6616) (xy 262.508273 3.625885)
			(xy 262.543988 3.584668) (xy 262.573474 3.538787) (xy 262.596131 3.489177) (xy 262.611496 3.436847)
			(xy 262.619258 3.382863) (xy 262.619744 3.355594) (xy 262.619744 2.491994) (xy 262.619258 2.464725)
			(xy 262.611496 2.410741) (xy 262.596131 2.358411) (xy 262.573474 2.308801) (xy 262.543988 2.26292)
			(xy 262.508273 2.221703) (xy 262.467056 2.185988) (xy 262.421175 2.156502) (xy 262.371565 2.133845)
			(xy 262.319235 2.11848) (xy 262.265251 2.110718) (xy 262.210713 2.110718) (xy 262.156729 2.11848)
			(xy 262.104399 2.133845) (xy 262.054789 2.156502) (xy 262.008908 2.185988) (xy 261.967691 2.221703)
			(xy 261.931976 2.26292) (xy 261.90249 2.308801) (xy 261.879833 2.358411) (xy 261.864468 2.410741)
			(xy 261.856706 2.464725) (xy 261.85622 2.491994) (xy 258.245794 2.491994) (xy 258.300351 2.464828)
			(xy 258.373257 2.419687) (xy 258.441686 2.368011) (xy 258.505056 2.310242) (xy 258.562825 2.246872)
			(xy 258.614501 2.178443) (xy 258.659642 2.105537) (xy 258.697864 2.028777) (xy 258.72884 1.948818)
			(xy 258.752307 1.866342) (xy 258.768063 1.782052) (xy 258.775975 1.696669) (xy 258.77647 1.653794)
			(xy 258.775975 1.610919) (xy 263.271241 1.610919) (xy 263.271241 1.696669) (xy 263.279153 1.782052)
			(xy 263.294909 1.866342) (xy 263.318376 1.948818) (xy 263.349352 2.028777) (xy 263.387574 2.105537)
			(xy 263.432715 2.178443) (xy 263.484391 2.246872) (xy 263.54216 2.310242) (xy 263.60553 2.368011)
			(xy 263.673959 2.419687) (xy 263.746865 2.464828) (xy 263.823625 2.50305) (xy 263.903584 2.534026)
			(xy 263.98606 2.557493) (xy 264.07035 2.573249) (xy 264.155733 2.581161) (xy 264.241483 2.581161)
			(xy 264.326866 2.573249) (xy 264.411156 2.557493) (xy 264.493632 2.534026) (xy 264.573591 2.50305)
			(xy 264.650351 2.464828) (xy 264.723257 2.419687) (xy 264.791686 2.368011) (xy 264.855056 2.310242)
			(xy 264.912825 2.246872) (xy 264.964501 2.178443) (xy 265.009642 2.105537) (xy 265.047864 2.028777)
			(xy 265.07884 1.948818) (xy 265.102307 1.866342) (xy 265.118063 1.782052) (xy 265.125975 1.696669)
			(xy 265.12647 1.653794) (xy 265.125975 1.610919) (xy 324.845921 1.610919) (xy 324.845921 1.696669)
			(xy 324.853833 1.782052) (xy 324.869589 1.866342) (xy 324.893056 1.948818) (xy 324.924032 2.028777)
			(xy 324.962254 2.105537) (xy 325.007395 2.178443) (xy 325.059071 2.246872) (xy 325.11684 2.310242)
			(xy 325.18021 2.368011) (xy 325.248639 2.419687) (xy 325.321545 2.464828) (xy 325.398305 2.50305)
			(xy 325.478264 2.534026) (xy 325.56074 2.557493) (xy 325.64503 2.573249) (xy 325.730413 2.581161)
			(xy 325.816163 2.581161) (xy 325.901546 2.573249) (xy 325.985836 2.557493) (xy 326.068312 2.534026)
			(xy 326.148271 2.50305) (xy 326.170474 2.491994) (xy 327.352152 2.491994) (xy 327.352152 3.355594)
			(xy 327.352638 3.382863) (xy 327.3604 3.436847) (xy 327.375765 3.489177) (xy 327.398422 3.538787)
			(xy 327.427908 3.584668) (xy 327.463623 3.625885) (xy 327.50484 3.6616) (xy 327.550721 3.691086)
			(xy 327.600331 3.713743) (xy 327.652661 3.729108) (xy 327.706645 3.73687) (xy 327.761183 3.73687)
			(xy 327.815167 3.729108) (xy 327.867497 3.713743) (xy 327.917107 3.691086) (xy 327.962988 3.6616)
			(xy 328.004205 3.625885) (xy 328.03992 3.584668) (xy 328.069406 3.538787) (xy 328.092063 3.489177)
			(xy 328.107428 3.436847) (xy 328.11519 3.382863) (xy 328.115676 3.355594) (xy 328.115676 2.491994)
			(xy 328.11519 2.464725) (xy 328.107428 2.410741) (xy 328.092063 2.358411) (xy 328.069406 2.308801)
			(xy 328.03992 2.26292) (xy 328.004205 2.221703) (xy 327.962988 2.185988) (xy 327.917107 2.156502)
			(xy 327.867497 2.133845) (xy 327.815167 2.11848) (xy 327.761183 2.110718) (xy 327.706645 2.110718)
			(xy 327.652661 2.11848) (xy 327.600331 2.133845) (xy 327.550721 2.156502) (xy 327.50484 2.185988)
			(xy 327.463623 2.221703) (xy 327.427908 2.26292) (xy 327.398422 2.308801) (xy 327.375765 2.358411)
			(xy 327.3604 2.410741) (xy 327.352638 2.464725) (xy 327.352152 2.491994) (xy 326.170474 2.491994)
			(xy 326.225031 2.464828) (xy 326.297937 2.419687) (xy 326.366366 2.368011) (xy 326.429736 2.310242)
			(xy 326.487505 2.246872) (xy 326.539181 2.178443) (xy 326.584322 2.105537) (xy 326.622544 2.028777)
			(xy 326.65352 1.948818) (xy 326.676987 1.866342) (xy 326.692743 1.782052) (xy 326.700655 1.696669)
			(xy 326.70115 1.653794) (xy 326.700655 1.610919) (xy 331.195921 1.610919) (xy 331.195921 1.696669)
			(xy 331.203833 1.782052) (xy 331.219589 1.866342) (xy 331.243056 1.948818) (xy 331.274032 2.028777)
			(xy 331.312254 2.105537) (xy 331.357395 2.178443) (xy 331.409071 2.246872) (xy 331.46684 2.310242)
			(xy 331.53021 2.368011) (xy 331.598639 2.419687) (xy 331.671545 2.464828) (xy 331.748305 2.50305)
			(xy 331.828264 2.534026) (xy 331.91074 2.557493) (xy 331.99503 2.573249) (xy 332.080413 2.581161)
			(xy 332.166163 2.581161) (xy 332.251546 2.573249) (xy 332.335836 2.557493) (xy 332.418312 2.534026)
			(xy 332.498271 2.50305) (xy 332.575031 2.464828) (xy 332.647937 2.419687) (xy 332.716366 2.368011)
			(xy 332.779736 2.310242) (xy 332.837505 2.246872) (xy 332.889181 2.178443) (xy 332.934322 2.105537)
			(xy 332.972544 2.028777) (xy 333.00352 1.948818) (xy 333.026987 1.866342) (xy 333.042743 1.782052)
			(xy 333.050655 1.696669) (xy 333.05115 1.653794) (xy 333.050655 1.610919) (xy 335.488267 1.610919)
			(xy 335.488267 1.696669) (xy 335.496179 1.782052) (xy 335.511935 1.866342) (xy 335.535402 1.948818)
			(xy 335.566378 2.028777) (xy 335.6046 2.105537) (xy 335.649741 2.178443) (xy 335.701417 2.246872)
			(xy 335.759186 2.310242) (xy 335.822556 2.368011) (xy 335.890985 2.419687) (xy 335.963891 2.464828)
			(xy 336.040651 2.50305) (xy 336.12061 2.534026) (xy 336.203086 2.557493) (xy 336.287376 2.573249)
			(xy 336.372759 2.581161) (xy 336.458509 2.581161) (xy 336.543892 2.573249) (xy 336.628182 2.557493)
			(xy 336.710658 2.534026) (xy 336.790617 2.50305) (xy 336.81282 2.491994) (xy 340.4235 2.491994) (xy 340.4235 3.355594)
			(xy 340.423986 3.382845) (xy 340.431742 3.436793) (xy 340.447097 3.489088) (xy 340.469739 3.538665)
			(xy 340.499205 3.584515) (xy 340.534896 3.625706) (xy 340.576087 3.661397) (xy 340.621937 3.690863)
			(xy 340.671514 3.713505) (xy 340.723809 3.72886) (xy 340.777757 3.736616) (xy 340.832259 3.736616)
			(xy 340.886207 3.72886) (xy 340.938502 3.713505) (xy 340.988079 3.690863) (xy 341.033929 3.661397)
			(xy 341.07512 3.625706) (xy 341.110811 3.584515) (xy 341.140277 3.538665) (xy 341.162919 3.489088)
			(xy 341.178274 3.436793) (xy 341.18603 3.382845) (xy 341.186516 3.355594) (xy 341.186516 2.491994)
			(xy 341.18603 2.464743) (xy 341.178274 2.410795) (xy 341.162919 2.3585) (xy 341.140277 2.308923)
			(xy 341.110811 2.263073) (xy 341.07512 2.221882) (xy 341.033929 2.186191) (xy 340.988079 2.156725)
			(xy 340.938502 2.134083) (xy 340.886207 2.118728) (xy 340.832259 2.110972) (xy 340.777757 2.110972)
			(xy 340.723809 2.118728) (xy 340.671514 2.134083) (xy 340.621937 2.156725) (xy 340.576087 2.186191)
			(xy 340.534896 2.221882) (xy 340.499205 2.263073) (xy 340.469739 2.308923) (xy 340.447097 2.3585)
			(xy 340.431742 2.410795) (xy 340.423986 2.464743) (xy 340.4235 2.491994) (xy 336.81282 2.491994)
			(xy 336.867377 2.464828) (xy 336.940283 2.419687) (xy 337.008712 2.368011) (xy 337.072082 2.310242)
			(xy 337.129851 2.246872) (xy 337.181527 2.178443) (xy 337.226668 2.105537) (xy 337.26489 2.028777)
			(xy 337.295866 1.948818) (xy 337.319333 1.866342) (xy 337.335089 1.782052) (xy 337.343001 1.696669)
			(xy 337.343496 1.653794) (xy 337.343001 1.610919) (xy 341.838267 1.610919) (xy 341.838267 1.696669)
			(xy 341.846179 1.782052) (xy 341.861935 1.866342) (xy 341.885402 1.948818) (xy 341.916378 2.028777)
			(xy 341.9546 2.105537) (xy 341.999741 2.178443) (xy 342.051417 2.246872) (xy 342.109186 2.310242)
			(xy 342.172556 2.368011) (xy 342.240985 2.419687) (xy 342.313891 2.464828) (xy 342.390651 2.50305)
			(xy 342.47061 2.534026) (xy 342.553086 2.557493) (xy 342.637376 2.573249) (xy 342.722759 2.581161)
			(xy 342.808509 2.581161) (xy 342.893892 2.573249) (xy 342.978182 2.557493) (xy 343.060658 2.534026)
			(xy 343.140617 2.50305) (xy 343.217377 2.464828) (xy 343.290283 2.419687) (xy 343.358712 2.368011)
			(xy 343.422082 2.310242) (xy 343.479851 2.246872) (xy 343.531527 2.178443) (xy 343.576668 2.105537)
			(xy 343.61489 2.028777) (xy 343.645866 1.948818) (xy 343.669333 1.866342) (xy 343.685089 1.782052)
			(xy 343.693001 1.696669) (xy 343.693496 1.653794) (xy 343.693001 1.610919) (xy 373.705107 1.610919)
			(xy 373.705107 1.696669) (xy 373.713019 1.782052) (xy 373.728775 1.866342) (xy 373.752242 1.948818)
			(xy 373.783218 2.028777) (xy 373.82144 2.105537) (xy 373.866581 2.178443) (xy 373.918257 2.246872)
			(xy 373.976026 2.310242) (xy 374.039396 2.368011) (xy 374.107825 2.419687) (xy 374.180731 2.464828)
			(xy 374.257491 2.50305) (xy 374.33745 2.534026) (xy 374.419926 2.557493) (xy 374.504216 2.573249)
			(xy 374.589599 2.581161) (xy 374.675349 2.581161) (xy 374.760732 2.573249) (xy 374.845022 2.557493)
			(xy 374.927498 2.534026) (xy 375.007457 2.50305) (xy 375.02966 2.491994) (xy 376.211592 2.491994)
			(xy 376.211592 3.355594) (xy 376.212078 3.382845) (xy 376.219834 3.436793) (xy 376.235189 3.489088)
			(xy 376.257831 3.538665) (xy 376.287297 3.584515) (xy 376.322988 3.625706) (xy 376.364179 3.661397)
			(xy 376.410029 3.690863) (xy 376.459606 3.713505) (xy 376.511901 3.72886) (xy 376.565849 3.736616)
			(xy 376.620351 3.736616) (xy 376.674299 3.72886) (xy 376.726594 3.713505) (xy 376.776171 3.690863)
			(xy 376.822021 3.661397) (xy 376.863212 3.625706) (xy 376.898903 3.584515) (xy 376.928369 3.538665)
			(xy 376.951011 3.489088) (xy 376.966366 3.436793) (xy 376.974122 3.382845) (xy 376.974608 3.355594)
			(xy 376.974608 2.491994) (xy 376.974122 2.464743) (xy 376.966366 2.410795) (xy 376.951011 2.3585)
			(xy 376.928369 2.308923) (xy 376.898903 2.263073) (xy 376.863212 2.221882) (xy 376.822021 2.186191)
			(xy 376.776171 2.156725) (xy 376.726594 2.134083) (xy 376.674299 2.118728) (xy 376.620351 2.110972)
			(xy 376.565849 2.110972) (xy 376.511901 2.118728) (xy 376.459606 2.134083) (xy 376.410029 2.156725)
			(xy 376.364179 2.186191) (xy 376.322988 2.221882) (xy 376.287297 2.263073) (xy 376.257831 2.308923)
			(xy 376.235189 2.3585) (xy 376.219834 2.410795) (xy 376.212078 2.464743) (xy 376.211592 2.491994)
			(xy 375.02966 2.491994) (xy 375.084217 2.464828) (xy 375.157123 2.419687) (xy 375.225552 2.368011)
			(xy 375.288922 2.310242) (xy 375.346691 2.246872) (xy 375.398367 2.178443) (xy 375.443508 2.105537)
			(xy 375.48173 2.028777) (xy 375.512706 1.948818) (xy 375.536173 1.866342) (xy 375.551929 1.782052)
			(xy 375.559841 1.696669) (xy 375.560336 1.653794) (xy 375.559841 1.610919) (xy 380.055107 1.610919)
			(xy 380.055107 1.696669) (xy 380.063019 1.782052) (xy 380.078775 1.866342) (xy 380.102242 1.948818)
			(xy 380.133218 2.028777) (xy 380.17144 2.105537) (xy 380.216581 2.178443) (xy 380.268257 2.246872)
			(xy 380.326026 2.310242) (xy 380.389396 2.368011) (xy 380.457825 2.419687) (xy 380.530731 2.464828)
			(xy 380.607491 2.50305) (xy 380.68745 2.534026) (xy 380.769926 2.557493) (xy 380.854216 2.573249)
			(xy 380.939599 2.581161) (xy 381.025349 2.581161) (xy 381.110732 2.573249) (xy 381.195022 2.557493)
			(xy 381.277498 2.534026) (xy 381.357457 2.50305) (xy 381.434217 2.464828) (xy 381.507123 2.419687)
			(xy 381.575552 2.368011) (xy 381.638922 2.310242) (xy 381.696691 2.246872) (xy 381.748367 2.178443)
			(xy 381.793508 2.105537) (xy 381.83173 2.028777) (xy 381.862706 1.948818) (xy 381.886173 1.866342)
			(xy 381.901929 1.782052) (xy 381.909841 1.696669) (xy 381.910336 1.653794) (xy 381.909841 1.610919)
			(xy 381.901929 1.525536) (xy 381.886173 1.441246) (xy 381.862706 1.35877) (xy 381.83173 1.278811)
			(xy 381.793508 1.202051) (xy 381.748367 1.129145) (xy 381.696691 1.060716) (xy 381.638922 0.997346)
			(xy 381.575552 0.939577) (xy 381.507123 0.887901) (xy 381.434217 0.84276) (xy 381.357457 0.804538)
			(xy 381.277498 0.773562) (xy 381.195022 0.750095) (xy 381.110732 0.734339) (xy 381.025349 0.726427)
			(xy 380.939599 0.726427) (xy 380.854216 0.734339) (xy 380.769926 0.750095) (xy 380.68745 0.773562)
			(xy 380.607491 0.804538) (xy 380.530731 0.84276) (xy 380.457825 0.887901) (xy 380.389396 0.939577)
			(xy 380.326026 0.997346) (xy 380.268257 1.060716) (xy 380.216581 1.129145) (xy 380.17144 1.202051)
			(xy 380.133218 1.278811) (xy 380.102242 1.35877) (xy 380.078775 1.441246) (xy 380.063019 1.525536)
			(xy 380.055107 1.610919) (xy 375.559841 1.610919) (xy 375.551929 1.525536) (xy 375.536173 1.441246)
			(xy 375.512706 1.35877) (xy 375.48173 1.278811) (xy 375.443508 1.202051) (xy 375.398367 1.129145)
			(xy 375.346691 1.060716) (xy 375.288922 0.997346) (xy 375.225552 0.939577) (xy 375.157123 0.887901)
			(xy 375.084217 0.84276) (xy 375.007457 0.804538) (xy 374.927498 0.773562) (xy 374.845022 0.750095)
			(xy 374.760732 0.734339) (xy 374.675349 0.726427) (xy 374.589599 0.726427) (xy 374.504216 0.734339)
			(xy 374.419926 0.750095) (xy 374.33745 0.773562) (xy 374.257491 0.804538) (xy 374.180731 0.84276)
			(xy 374.107825 0.887901) (xy 374.039396 0.939577) (xy 373.976026 0.997346) (xy 373.918257 1.060716)
			(xy 373.866581 1.129145) (xy 373.82144 1.202051) (xy 373.783218 1.278811) (xy 373.752242 1.35877)
			(xy 373.728775 1.441246) (xy 373.713019 1.525536) (xy 373.705107 1.610919) (xy 343.693001 1.610919)
			(xy 343.685089 1.525536) (xy 343.669333 1.441246) (xy 343.645866 1.35877) (xy 343.61489 1.278811)
			(xy 343.576668 1.202051) (xy 343.531527 1.129145) (xy 343.479851 1.060716) (xy 343.422082 0.997346)
			(xy 343.358712 0.939577) (xy 343.290283 0.887901) (xy 343.217377 0.84276) (xy 343.140617 0.804538)
			(xy 343.060658 0.773562) (xy 342.978182 0.750095) (xy 342.893892 0.734339) (xy 342.808509 0.726427)
			(xy 342.722759 0.726427) (xy 342.637376 0.734339) (xy 342.553086 0.750095) (xy 342.47061 0.773562)
			(xy 342.390651 0.804538) (xy 342.313891 0.84276) (xy 342.240985 0.887901) (xy 342.172556 0.939577)
			(xy 342.109186 0.997346) (xy 342.051417 1.060716) (xy 341.999741 1.129145) (xy 341.9546 1.202051)
			(xy 341.916378 1.278811) (xy 341.885402 1.35877) (xy 341.861935 1.441246) (xy 341.846179 1.525536)
			(xy 341.838267 1.610919) (xy 337.343001 1.610919) (xy 337.335089 1.525536) (xy 337.319333 1.441246)
			(xy 337.295866 1.35877) (xy 337.26489 1.278811) (xy 337.226668 1.202051) (xy 337.181527 1.129145)
			(xy 337.129851 1.060716) (xy 337.072082 0.997346) (xy 337.008712 0.939577) (xy 336.940283 0.887901)
			(xy 336.867377 0.84276) (xy 336.790617 0.804538) (xy 336.710658 0.773562) (xy 336.628182 0.750095)
			(xy 336.543892 0.734339) (xy 336.458509 0.726427) (xy 336.372759 0.726427) (xy 336.287376 0.734339)
			(xy 336.203086 0.750095) (xy 336.12061 0.773562) (xy 336.040651 0.804538) (xy 335.963891 0.84276)
			(xy 335.890985 0.887901) (xy 335.822556 0.939577) (xy 335.759186 0.997346) (xy 335.701417 1.060716)
			(xy 335.649741 1.129145) (xy 335.6046 1.202051) (xy 335.566378 1.278811) (xy 335.535402 1.35877)
			(xy 335.511935 1.441246) (xy 335.496179 1.525536) (xy 335.488267 1.610919) (xy 333.050655 1.610919)
			(xy 333.042743 1.525536) (xy 333.026987 1.441246) (xy 333.00352 1.35877) (xy 332.972544 1.278811)
			(xy 332.934322 1.202051) (xy 332.889181 1.129145) (xy 332.837505 1.060716) (xy 332.779736 0.997346)
			(xy 332.716366 0.939577) (xy 332.647937 0.887901) (xy 332.575031 0.84276) (xy 332.498271 0.804538)
			(xy 332.418312 0.773562) (xy 332.335836 0.750095) (xy 332.251546 0.734339) (xy 332.166163 0.726427)
			(xy 332.080413 0.726427) (xy 331.99503 0.734339) (xy 331.91074 0.750095) (xy 331.828264 0.773562)
			(xy 331.748305 0.804538) (xy 331.671545 0.84276) (xy 331.598639 0.887901) (xy 331.53021 0.939577)
			(xy 331.46684 0.997346) (xy 331.409071 1.060716) (xy 331.357395 1.129145) (xy 331.312254 1.202051)
			(xy 331.274032 1.278811) (xy 331.243056 1.35877) (xy 331.219589 1.441246) (xy 331.203833 1.525536)
			(xy 331.195921 1.610919) (xy 326.700655 1.610919) (xy 326.692743 1.525536) (xy 326.676987 1.441246)
			(xy 326.65352 1.35877) (xy 326.622544 1.278811) (xy 326.584322 1.202051) (xy 326.539181 1.129145)
			(xy 326.487505 1.060716) (xy 326.429736 0.997346) (xy 326.366366 0.939577) (xy 326.297937 0.887901)
			(xy 326.225031 0.84276) (xy 326.148271 0.804538) (xy 326.068312 0.773562) (xy 325.985836 0.750095)
			(xy 325.901546 0.734339) (xy 325.816163 0.726427) (xy 325.730413 0.726427) (xy 325.64503 0.734339)
			(xy 325.56074 0.750095) (xy 325.478264 0.773562) (xy 325.398305 0.804538) (xy 325.321545 0.84276)
			(xy 325.248639 0.887901) (xy 325.18021 0.939577) (xy 325.11684 0.997346) (xy 325.059071 1.060716)
			(xy 325.007395 1.129145) (xy 324.962254 1.202051) (xy 324.924032 1.278811) (xy 324.893056 1.35877)
			(xy 324.869589 1.441246) (xy 324.853833 1.525536) (xy 324.845921 1.610919) (xy 265.125975 1.610919)
			(xy 265.118063 1.525536) (xy 265.102307 1.441246) (xy 265.07884 1.35877) (xy 265.047864 1.278811)
			(xy 265.009642 1.202051) (xy 264.964501 1.129145) (xy 264.912825 1.060716) (xy 264.855056 0.997346)
			(xy 264.791686 0.939577) (xy 264.723257 0.887901) (xy 264.650351 0.84276) (xy 264.573591 0.804538)
			(xy 264.493632 0.773562) (xy 264.411156 0.750095) (xy 264.326866 0.734339) (xy 264.241483 0.726427)
			(xy 264.155733 0.726427) (xy 264.07035 0.734339) (xy 263.98606 0.750095) (xy 263.903584 0.773562)
			(xy 263.823625 0.804538) (xy 263.746865 0.84276) (xy 263.673959 0.887901) (xy 263.60553 0.939577)
			(xy 263.54216 0.997346) (xy 263.484391 1.060716) (xy 263.432715 1.129145) (xy 263.387574 1.202051)
			(xy 263.349352 1.278811) (xy 263.318376 1.35877) (xy 263.294909 1.441246) (xy 263.279153 1.525536)
			(xy 263.271241 1.610919) (xy 258.775975 1.610919) (xy 258.768063 1.525536) (xy 258.752307 1.441246)
			(xy 258.72884 1.35877) (xy 258.697864 1.278811) (xy 258.659642 1.202051) (xy 258.614501 1.129145)
			(xy 258.562825 1.060716) (xy 258.505056 0.997346) (xy 258.441686 0.939577) (xy 258.373257 0.887901)
			(xy 258.300351 0.84276) (xy 258.223591 0.804538) (xy 258.143632 0.773562) (xy 258.061156 0.750095)
			(xy 257.976866 0.734339) (xy 257.891483 0.726427) (xy 257.805733 0.726427) (xy 257.72035 0.734339)
			(xy 257.63606 0.750095) (xy 257.553584 0.773562) (xy 257.473625 0.804538) (xy 257.396865 0.84276)
			(xy 257.323959 0.887901) (xy 257.25553 0.939577) (xy 257.19216 0.997346) (xy 257.134391 1.060716)
			(xy 257.082715 1.129145) (xy 257.037574 1.202051) (xy 256.999352 1.278811) (xy 256.968376 1.35877)
			(xy 256.944909 1.441246) (xy 256.929153 1.525536) (xy 256.921241 1.610919) (xy 254.465119 1.610919)
			(xy 254.465087 1.608125) (xy 254.457175 1.522742) (xy 254.441419 1.438452) (xy 254.417952 1.355976)
			(xy 254.386976 1.276017) (xy 254.348754 1.199257) (xy 254.303613 1.126351) (xy 254.251937 1.057922)
			(xy 254.194168 0.994552) (xy 254.130798 0.936783) (xy 254.062369 0.885107) (xy 253.989463 0.839966)
			(xy 253.912703 0.801744) (xy 253.832744 0.770768) (xy 253.750268 0.747301) (xy 253.665978 0.731545)
			(xy 253.580595 0.723633) (xy 253.494845 0.723633) (xy 253.409462 0.731545) (xy 253.325172 0.747301)
			(xy 253.242696 0.770768) (xy 253.162737 0.801744) (xy 253.085977 0.839966) (xy 253.013071 0.885107)
			(xy 252.944642 0.936783) (xy 252.881272 0.994552) (xy 252.823503 1.057922) (xy 252.771827 1.126351)
			(xy 252.726686 1.199257) (xy 252.688464 1.276017) (xy 252.657488 1.355976) (xy 252.634021 1.438452)
			(xy 252.618265 1.522742) (xy 252.610353 1.608125) (xy 248.115087 1.608125) (xy 248.107175 1.522742)
			(xy 248.091419 1.438452) (xy 248.067952 1.355976) (xy 248.036976 1.276017) (xy 247.998754 1.199257)
			(xy 247.953613 1.126351) (xy 247.901937 1.057922) (xy 247.844168 0.994552) (xy 247.780798 0.936783)
			(xy 247.712369 0.885107) (xy 247.639463 0.839966) (xy 247.562703 0.801744) (xy 247.482744 0.770768)
			(xy 247.400268 0.747301) (xy 247.315978 0.731545) (xy 247.230595 0.723633) (xy 247.144845 0.723633)
			(xy 247.059462 0.731545) (xy 246.975172 0.747301) (xy 246.892696 0.770768) (xy 246.812737 0.801744)
			(xy 246.735977 0.839966) (xy 246.663071 0.885107) (xy 246.594642 0.936783) (xy 246.531272 0.994552)
			(xy 246.473503 1.057922) (xy 246.421827 1.126351) (xy 246.376686 1.199257) (xy 246.338464 1.276017)
			(xy 246.307488 1.355976) (xy 246.284021 1.438452) (xy 246.268265 1.522742) (xy 246.260353 1.608125)
			(xy 186.540407 1.608125) (xy 186.532495 1.522742) (xy 186.516739 1.438452) (xy 186.493272 1.355976)
			(xy 186.462296 1.276017) (xy 186.424074 1.199257) (xy 186.378933 1.126351) (xy 186.327257 1.057922)
			(xy 186.269488 0.994552) (xy 186.206118 0.936783) (xy 186.137689 0.885107) (xy 186.064783 0.839966)
			(xy 185.988023 0.801744) (xy 185.908064 0.770768) (xy 185.825588 0.747301) (xy 185.741298 0.731545)
			(xy 185.655915 0.723633) (xy 185.570165 0.723633) (xy 185.484782 0.731545) (xy 185.400492 0.747301)
			(xy 185.318016 0.770768) (xy 185.238057 0.801744) (xy 185.161297 0.839966) (xy 185.088391 0.885107)
			(xy 185.019962 0.936783) (xy 184.956592 0.994552) (xy 184.898823 1.057922) (xy 184.847147 1.126351)
			(xy 184.802006 1.199257) (xy 184.763784 1.276017) (xy 184.732808 1.355976) (xy 184.709341 1.438452)
			(xy 184.693585 1.522742) (xy 184.685673 1.608125) (xy 180.190407 1.608125) (xy 180.182495 1.522742)
			(xy 180.166739 1.438452) (xy 180.143272 1.355976) (xy 180.112296 1.276017) (xy 180.074074 1.199257)
			(xy 180.028933 1.126351) (xy 179.977257 1.057922) (xy 179.919488 0.994552) (xy 179.856118 0.936783)
			(xy 179.787689 0.885107) (xy 179.714783 0.839966) (xy 179.638023 0.801744) (xy 179.558064 0.770768)
			(xy 179.475588 0.747301) (xy 179.391298 0.731545) (xy 179.305915 0.723633) (xy 179.220165 0.723633)
			(xy 179.134782 0.731545) (xy 179.050492 0.747301) (xy 178.968016 0.770768) (xy 178.888057 0.801744)
			(xy 178.811297 0.839966) (xy 178.738391 0.885107) (xy 178.669962 0.936783) (xy 178.606592 0.994552)
			(xy 178.548823 1.057922) (xy 178.497147 1.126351) (xy 178.452006 1.199257) (xy 178.413784 1.276017)
			(xy 178.382808 1.355976) (xy 178.359341 1.438452) (xy 178.343585 1.522742) (xy 178.335673 1.608125)
			(xy 84.135094 1.608125) (xy 84.162197 1.489382) (xy 84.185766 1.350662) (xy 84.20152 1.210839) (xy 84.20941 1.070352)
			(xy 84.20989 0.999998) (xy 84.20989 -0.931875) (xy 208.043513 -0.931875) (xy 208.043513 -0.846125)
			(xy 208.051425 -0.760742) (xy 208.067181 -0.676452) (xy 208.090648 -0.593976) (xy 208.121624 -0.514017)
			(xy 208.159846 -0.437257) (xy 208.204987 -0.364351) (xy 208.256663 -0.295922) (xy 208.314432 -0.232552)
			(xy 208.377802 -0.174783) (xy 208.446231 -0.123107) (xy 208.519137 -0.077966) (xy 208.595897 -0.039744)
			(xy 208.675856 -0.008768) (xy 208.758332 0.014699) (xy 208.842622 0.030455) (xy 208.928005 0.038367)
			(xy 209.013755 0.038367) (xy 209.099138 0.030455) (xy 209.183428 0.014699) (xy 209.265904 -0.008768)
			(xy 209.345863 -0.039744) (xy 209.422623 -0.077966) (xy 209.495529 -0.123107) (xy 209.563958 -0.174783)
			(xy 209.627328 -0.232552) (xy 209.685097 -0.295922) (xy 209.736773 -0.364351) (xy 209.781914 -0.437257)
			(xy 209.820136 -0.514017) (xy 209.851112 -0.593976) (xy 209.874579 -0.676452) (xy 209.890335 -0.760742)
			(xy 209.898247 -0.846125) (xy 209.898742 -0.889) (xy 209.898247 -0.931875) (xy 214.393513 -0.931875)
			(xy 214.393513 -0.846125) (xy 214.401425 -0.760742) (xy 214.417181 -0.676452) (xy 214.440648 -0.593976)
			(xy 214.471624 -0.514017) (xy 214.509846 -0.437257) (xy 214.554987 -0.364351) (xy 214.606663 -0.295922)
			(xy 214.664432 -0.232552) (xy 214.727802 -0.174783) (xy 214.796231 -0.123107) (xy 214.869137 -0.077966)
			(xy 214.945897 -0.039744) (xy 215.025856 -0.008768) (xy 215.108332 0.014699) (xy 215.192622 0.030455)
			(xy 215.278005 0.038367) (xy 215.363755 0.038367) (xy 215.449138 0.030455) (xy 215.533428 0.014699)
			(xy 215.615904 -0.008768) (xy 215.695863 -0.039744) (xy 215.772623 -0.077966) (xy 215.845529 -0.123107)
			(xy 215.913958 -0.174783) (xy 215.977328 -0.232552) (xy 216.035097 -0.295922) (xy 216.086773 -0.364351)
			(xy 216.131914 -0.437257) (xy 216.170136 -0.514017) (xy 216.201112 -0.593976) (xy 216.224579 -0.676452)
			(xy 216.240335 -0.760742) (xy 216.248247 -0.846125) (xy 216.248742 -0.889) (xy 216.248247 -0.931875)
			(xy 246.260353 -0.931875) (xy 246.260353 -0.846125) (xy 246.268265 -0.760742) (xy 246.284021 -0.676452)
			(xy 246.307488 -0.593976) (xy 246.338464 -0.514017) (xy 246.376686 -0.437257) (xy 246.421827 -0.364351)
			(xy 246.473503 -0.295922) (xy 246.531272 -0.232552) (xy 246.594642 -0.174783) (xy 246.663071 -0.123107)
			(xy 246.735977 -0.077966) (xy 246.812737 -0.039744) (xy 246.892696 -0.008768) (xy 246.975172 0.014699)
			(xy 247.059462 0.030455) (xy 247.144845 0.038367) (xy 247.230595 0.038367) (xy 247.315978 0.030455)
			(xy 247.400268 0.014699) (xy 247.482744 -0.008768) (xy 247.562703 -0.039744) (xy 247.639463 -0.077966)
			(xy 247.712369 -0.123107) (xy 247.780798 -0.174783) (xy 247.844168 -0.232552) (xy 247.901937 -0.295922)
			(xy 247.953613 -0.364351) (xy 247.998754 -0.437257) (xy 248.036976 -0.514017) (xy 248.067952 -0.593976)
			(xy 248.091419 -0.676452) (xy 248.107175 -0.760742) (xy 248.115087 -0.846125) (xy 248.115582 -0.889)
			(xy 248.115087 -0.931875) (xy 252.610353 -0.931875) (xy 252.610353 -0.846125) (xy 252.618265 -0.760742)
			(xy 252.634021 -0.676452) (xy 252.657488 -0.593976) (xy 252.688464 -0.514017) (xy 252.726686 -0.437257)
			(xy 252.771827 -0.364351) (xy 252.823503 -0.295922) (xy 252.881272 -0.232552) (xy 252.944642 -0.174783)
			(xy 253.013071 -0.123107) (xy 253.085977 -0.077966) (xy 253.162737 -0.039744) (xy 253.242696 -0.008768)
			(xy 253.325172 0.014699) (xy 253.409462 0.030455) (xy 253.494845 0.038367) (xy 253.580595 0.038367)
			(xy 253.665978 0.030455) (xy 253.750268 0.014699) (xy 253.832744 -0.008768) (xy 253.912703 -0.039744)
			(xy 253.989463 -0.077966) (xy 254.062369 -0.123107) (xy 254.130798 -0.174783) (xy 254.194168 -0.232552)
			(xy 254.251937 -0.295922) (xy 254.303613 -0.364351) (xy 254.348754 -0.437257) (xy 254.386976 -0.514017)
			(xy 254.417952 -0.593976) (xy 254.441419 -0.676452) (xy 254.457175 -0.760742) (xy 254.465087 -0.846125)
			(xy 254.465582 -0.889) (xy 254.465119 -0.929081) (xy 256.921241 -0.929081) (xy 256.921241 -0.843331)
			(xy 256.929153 -0.757948) (xy 256.944909 -0.673658) (xy 256.968376 -0.591182) (xy 256.999352 -0.511223)
			(xy 257.037574 -0.434463) (xy 257.082715 -0.361557) (xy 257.134391 -0.293128) (xy 257.19216 -0.229758)
			(xy 257.25553 -0.171989) (xy 257.323959 -0.120313) (xy 257.396865 -0.075172) (xy 257.473625 -0.03695)
			(xy 257.553584 -0.005974) (xy 257.63606 0.017493) (xy 257.72035 0.033249) (xy 257.805733 0.041161)
			(xy 257.891483 0.041161) (xy 257.976866 0.033249) (xy 258.061156 0.017493) (xy 258.143632 -0.005974)
			(xy 258.223591 -0.03695) (xy 258.245794 -0.048006) (xy 261.85622 -0.048006) (xy 261.85622 0.815594)
			(xy 261.856706 0.842863) (xy 261.864468 0.896847) (xy 261.879833 0.949177) (xy 261.90249 0.998787)
			(xy 261.931976 1.044668) (xy 261.967691 1.085885) (xy 262.008908 1.1216) (xy 262.054789 1.151086)
			(xy 262.104399 1.173743) (xy 262.156729 1.189108) (xy 262.210713 1.19687) (xy 262.265251 1.19687)
			(xy 262.319235 1.189108) (xy 262.371565 1.173743) (xy 262.421175 1.151086) (xy 262.467056 1.1216)
			(xy 262.508273 1.085885) (xy 262.543988 1.044668) (xy 262.573474 0.998787) (xy 262.596131 0.949177)
			(xy 262.611496 0.896847) (xy 262.619258 0.842863) (xy 262.619744 0.815594) (xy 262.619744 -0.048006)
			(xy 262.619258 -0.075275) (xy 262.611496 -0.129259) (xy 262.596131 -0.181589) (xy 262.573474 -0.231199)
			(xy 262.543988 -0.27708) (xy 262.508273 -0.318297) (xy 262.467056 -0.354012) (xy 262.421175 -0.383498)
			(xy 262.371565 -0.406155) (xy 262.319235 -0.42152) (xy 262.265251 -0.429282) (xy 262.210713 -0.429282)
			(xy 262.156729 -0.42152) (xy 262.104399 -0.406155) (xy 262.054789 -0.383498) (xy 262.008908 -0.354012)
			(xy 261.967691 -0.318297) (xy 261.931976 -0.27708) (xy 261.90249 -0.231199) (xy 261.879833 -0.181589)
			(xy 261.864468 -0.129259) (xy 261.856706 -0.075275) (xy 261.85622 -0.048006) (xy 258.245794 -0.048006)
			(xy 258.300351 -0.075172) (xy 258.373257 -0.120313) (xy 258.441686 -0.171989) (xy 258.505056 -0.229758)
			(xy 258.562825 -0.293128) (xy 258.614501 -0.361557) (xy 258.659642 -0.434463) (xy 258.697864 -0.511223)
			(xy 258.72884 -0.591182) (xy 258.752307 -0.673658) (xy 258.768063 -0.757948) (xy 258.775975 -0.843331)
			(xy 258.77647 -0.886206) (xy 258.775975 -0.929081) (xy 263.271241 -0.929081) (xy 263.271241 -0.843331)
			(xy 263.279153 -0.757948) (xy 263.294909 -0.673658) (xy 263.318376 -0.591182) (xy 263.349352 -0.511223)
			(xy 263.387574 -0.434463) (xy 263.432715 -0.361557) (xy 263.484391 -0.293128) (xy 263.54216 -0.229758)
			(xy 263.60553 -0.171989) (xy 263.673959 -0.120313) (xy 263.746865 -0.075172) (xy 263.823625 -0.03695)
			(xy 263.903584 -0.005974) (xy 263.98606 0.017493) (xy 264.07035 0.033249) (xy 264.155733 0.041161)
			(xy 264.241483 0.041161) (xy 264.326866 0.033249) (xy 264.411156 0.017493) (xy 264.493632 -0.005974)
			(xy 264.573591 -0.03695) (xy 264.650351 -0.075172) (xy 264.723257 -0.120313) (xy 264.791686 -0.171989)
			(xy 264.855056 -0.229758) (xy 264.912825 -0.293128) (xy 264.964501 -0.361557) (xy 265.009642 -0.434463)
			(xy 265.047864 -0.511223) (xy 265.07884 -0.591182) (xy 265.102307 -0.673658) (xy 265.118063 -0.757948)
			(xy 265.125975 -0.843331) (xy 265.12647 -0.886206) (xy 265.125975 -0.929081) (xy 324.845921 -0.929081)
			(xy 324.845921 -0.843331) (xy 324.853833 -0.757948) (xy 324.869589 -0.673658) (xy 324.893056 -0.591182)
			(xy 324.924032 -0.511223) (xy 324.962254 -0.434463) (xy 325.007395 -0.361557) (xy 325.059071 -0.293128)
			(xy 325.11684 -0.229758) (xy 325.18021 -0.171989) (xy 325.248639 -0.120313) (xy 325.321545 -0.075172)
			(xy 325.398305 -0.03695) (xy 325.478264 -0.005974) (xy 325.56074 0.017493) (xy 325.64503 0.033249)
			(xy 325.730413 0.041161) (xy 325.816163 0.041161) (xy 325.901546 0.033249) (xy 325.985836 0.017493)
			(xy 326.068312 -0.005974) (xy 326.148271 -0.03695) (xy 326.170474 -0.048006) (xy 327.352152 -0.048006)
			(xy 327.352152 0.815594) (xy 327.352638 0.842863) (xy 327.3604 0.896847) (xy 327.375765 0.949177)
			(xy 327.398422 0.998787) (xy 327.427908 1.044668) (xy 327.463623 1.085885) (xy 327.50484 1.1216)
			(xy 327.550721 1.151086) (xy 327.600331 1.173743) (xy 327.652661 1.189108) (xy 327.706645 1.19687)
			(xy 327.761183 1.19687) (xy 327.815167 1.189108) (xy 327.867497 1.173743) (xy 327.917107 1.151086)
			(xy 327.962988 1.1216) (xy 328.004205 1.085885) (xy 328.03992 1.044668) (xy 328.069406 0.998787)
			(xy 328.092063 0.949177) (xy 328.107428 0.896847) (xy 328.11519 0.842863) (xy 328.115676 0.815594)
			(xy 328.115676 -0.048006) (xy 328.11519 -0.075275) (xy 328.107428 -0.129259) (xy 328.092063 -0.181589)
			(xy 328.069406 -0.231199) (xy 328.03992 -0.27708) (xy 328.004205 -0.318297) (xy 327.962988 -0.354012)
			(xy 327.917107 -0.383498) (xy 327.867497 -0.406155) (xy 327.815167 -0.42152) (xy 327.761183 -0.429282)
			(xy 327.706645 -0.429282) (xy 327.652661 -0.42152) (xy 327.600331 -0.406155) (xy 327.550721 -0.383498)
			(xy 327.50484 -0.354012) (xy 327.463623 -0.318297) (xy 327.427908 -0.27708) (xy 327.398422 -0.231199)
			(xy 327.375765 -0.181589) (xy 327.3604 -0.129259) (xy 327.352638 -0.075275) (xy 327.352152 -0.048006)
			(xy 326.170474 -0.048006) (xy 326.225031 -0.075172) (xy 326.297937 -0.120313) (xy 326.366366 -0.171989)
			(xy 326.429736 -0.229758) (xy 326.487505 -0.293128) (xy 326.539181 -0.361557) (xy 326.584322 -0.434463)
			(xy 326.622544 -0.511223) (xy 326.65352 -0.591182) (xy 326.676987 -0.673658) (xy 326.692743 -0.757948)
			(xy 326.700655 -0.843331) (xy 326.70115 -0.886206) (xy 326.700655 -0.929081) (xy 331.195921 -0.929081)
			(xy 331.195921 -0.843331) (xy 331.203833 -0.757948) (xy 331.219589 -0.673658) (xy 331.243056 -0.591182)
			(xy 331.274032 -0.511223) (xy 331.312254 -0.434463) (xy 331.357395 -0.361557) (xy 331.409071 -0.293128)
			(xy 331.46684 -0.229758) (xy 331.53021 -0.171989) (xy 331.598639 -0.120313) (xy 331.671545 -0.075172)
			(xy 331.748305 -0.03695) (xy 331.828264 -0.005974) (xy 331.91074 0.017493) (xy 331.99503 0.033249)
			(xy 332.080413 0.041161) (xy 332.166163 0.041161) (xy 332.251546 0.033249) (xy 332.335836 0.017493)
			(xy 332.418312 -0.005974) (xy 332.498271 -0.03695) (xy 332.575031 -0.075172) (xy 332.647937 -0.120313)
			(xy 332.716366 -0.171989) (xy 332.779736 -0.229758) (xy 332.837505 -0.293128) (xy 332.889181 -0.361557)
			(xy 332.934322 -0.434463) (xy 332.972544 -0.511223) (xy 333.00352 -0.591182) (xy 333.026987 -0.673658)
			(xy 333.042743 -0.757948) (xy 333.050655 -0.843331) (xy 333.05115 -0.886206) (xy 333.050655 -0.929081)
			(xy 335.488267 -0.929081) (xy 335.488267 -0.843331) (xy 335.496179 -0.757948) (xy 335.511935 -0.673658)
			(xy 335.535402 -0.591182) (xy 335.566378 -0.511223) (xy 335.6046 -0.434463) (xy 335.649741 -0.361557)
			(xy 335.701417 -0.293128) (xy 335.759186 -0.229758) (xy 335.822556 -0.171989) (xy 335.890985 -0.120313)
			(xy 335.963891 -0.075172) (xy 336.040651 -0.03695) (xy 336.12061 -0.005974) (xy 336.203086 0.017493)
			(xy 336.287376 0.033249) (xy 336.372759 0.041161) (xy 336.458509 0.041161) (xy 336.543892 0.033249)
			(xy 336.628182 0.017493) (xy 336.710658 -0.005974) (xy 336.790617 -0.03695) (xy 336.81282 -0.048006)
			(xy 340.4235 -0.048006) (xy 340.4235 0.815594) (xy 340.423986 0.842845) (xy 340.431742 0.896793)
			(xy 340.447097 0.949088) (xy 340.469739 0.998665) (xy 340.499205 1.044515) (xy 340.534896 1.085706)
			(xy 340.576087 1.121397) (xy 340.621937 1.150863) (xy 340.671514 1.173505) (xy 340.723809 1.18886)
			(xy 340.777757 1.196616) (xy 340.832259 1.196616) (xy 340.886207 1.18886) (xy 340.938502 1.173505)
			(xy 340.988079 1.150863) (xy 341.033929 1.121397) (xy 341.07512 1.085706) (xy 341.110811 1.044515)
			(xy 341.140277 0.998665) (xy 341.162919 0.949088) (xy 341.178274 0.896793) (xy 341.18603 0.842845)
			(xy 341.186516 0.815594) (xy 341.186516 -0.048006) (xy 341.18603 -0.075257) (xy 341.178274 -0.129205)
			(xy 341.162919 -0.1815) (xy 341.140277 -0.231077) (xy 341.110811 -0.276927) (xy 341.07512 -0.318118)
			(xy 341.033929 -0.353809) (xy 340.988079 -0.383275) (xy 340.938502 -0.405917) (xy 340.886207 -0.421272)
			(xy 340.832259 -0.429028) (xy 340.777757 -0.429028) (xy 340.723809 -0.421272) (xy 340.671514 -0.405917)
			(xy 340.621937 -0.383275) (xy 340.576087 -0.353809) (xy 340.534896 -0.318118) (xy 340.499205 -0.276927)
			(xy 340.469739 -0.231077) (xy 340.447097 -0.1815) (xy 340.431742 -0.129205) (xy 340.423986 -0.075257)
			(xy 340.4235 -0.048006) (xy 336.81282 -0.048006) (xy 336.867377 -0.075172) (xy 336.940283 -0.120313)
			(xy 337.008712 -0.171989) (xy 337.072082 -0.229758) (xy 337.129851 -0.293128) (xy 337.181527 -0.361557)
			(xy 337.226668 -0.434463) (xy 337.26489 -0.511223) (xy 337.295866 -0.591182) (xy 337.319333 -0.673658)
			(xy 337.335089 -0.757948) (xy 337.343001 -0.843331) (xy 337.343496 -0.886206) (xy 337.343001 -0.929081)
			(xy 341.838267 -0.929081) (xy 341.838267 -0.843331) (xy 341.846179 -0.757948) (xy 341.861935 -0.673658)
			(xy 341.885402 -0.591182) (xy 341.916378 -0.511223) (xy 341.9546 -0.434463) (xy 341.999741 -0.361557)
			(xy 342.051417 -0.293128) (xy 342.109186 -0.229758) (xy 342.172556 -0.171989) (xy 342.240985 -0.120313)
			(xy 342.313891 -0.075172) (xy 342.390651 -0.03695) (xy 342.47061 -0.005974) (xy 342.553086 0.017493)
			(xy 342.637376 0.033249) (xy 342.722759 0.041161) (xy 342.808509 0.041161) (xy 342.893892 0.033249)
			(xy 342.978182 0.017493) (xy 343.060658 -0.005974) (xy 343.140617 -0.03695) (xy 343.217377 -0.075172)
			(xy 343.290283 -0.120313) (xy 343.358712 -0.171989) (xy 343.422082 -0.229758) (xy 343.479851 -0.293128)
			(xy 343.531527 -0.361557) (xy 343.576668 -0.434463) (xy 343.61489 -0.511223) (xy 343.645866 -0.591182)
			(xy 343.669333 -0.673658) (xy 343.685089 -0.757948) (xy 343.693001 -0.843331) (xy 343.693496 -0.886206)
			(xy 343.693001 -0.929081) (xy 373.705107 -0.929081) (xy 373.705107 -0.843331) (xy 373.713019 -0.757948)
			(xy 373.728775 -0.673658) (xy 373.752242 -0.591182) (xy 373.783218 -0.511223) (xy 373.82144 -0.434463)
			(xy 373.866581 -0.361557) (xy 373.918257 -0.293128) (xy 373.976026 -0.229758) (xy 374.039396 -0.171989)
			(xy 374.107825 -0.120313) (xy 374.180731 -0.075172) (xy 374.257491 -0.03695) (xy 374.33745 -0.005974)
			(xy 374.419926 0.017493) (xy 374.504216 0.033249) (xy 374.589599 0.041161) (xy 374.675349 0.041161)
			(xy 374.760732 0.033249) (xy 374.845022 0.017493) (xy 374.927498 -0.005974) (xy 375.007457 -0.03695)
			(xy 375.02966 -0.048006) (xy 376.211592 -0.048006) (xy 376.211592 0.815594) (xy 376.212078 0.842845)
			(xy 376.219834 0.896793) (xy 376.235189 0.949088) (xy 376.257831 0.998665) (xy 376.287297 1.044515)
			(xy 376.322988 1.085706) (xy 376.364179 1.121397) (xy 376.410029 1.150863) (xy 376.459606 1.173505)
			(xy 376.511901 1.18886) (xy 376.565849 1.196616) (xy 376.620351 1.196616) (xy 376.674299 1.18886)
			(xy 376.726594 1.173505) (xy 376.776171 1.150863) (xy 376.822021 1.121397) (xy 376.863212 1.085706)
			(xy 376.898903 1.044515) (xy 376.928369 0.998665) (xy 376.951011 0.949088) (xy 376.966366 0.896793)
			(xy 376.974122 0.842845) (xy 376.974608 0.815594) (xy 376.974608 -0.048006) (xy 376.974122 -0.075257)
			(xy 376.966366 -0.129205) (xy 376.951011 -0.1815) (xy 376.928369 -0.231077) (xy 376.898903 -0.276927)
			(xy 376.863212 -0.318118) (xy 376.822021 -0.353809) (xy 376.776171 -0.383275) (xy 376.726594 -0.405917)
			(xy 376.674299 -0.421272) (xy 376.620351 -0.429028) (xy 376.565849 -0.429028) (xy 376.511901 -0.421272)
			(xy 376.459606 -0.405917) (xy 376.410029 -0.383275) (xy 376.364179 -0.353809) (xy 376.322988 -0.318118)
			(xy 376.287297 -0.276927) (xy 376.257831 -0.231077) (xy 376.235189 -0.1815) (xy 376.219834 -0.129205)
			(xy 376.212078 -0.075257) (xy 376.211592 -0.048006) (xy 375.02966 -0.048006) (xy 375.084217 -0.075172)
			(xy 375.157123 -0.120313) (xy 375.225552 -0.171989) (xy 375.288922 -0.229758) (xy 375.346691 -0.293128)
			(xy 375.398367 -0.361557) (xy 375.443508 -0.434463) (xy 375.48173 -0.511223) (xy 375.512706 -0.591182)
			(xy 375.536173 -0.673658) (xy 375.551929 -0.757948) (xy 375.559841 -0.843331) (xy 375.560336 -0.886206)
			(xy 375.559841 -0.929081) (xy 380.055107 -0.929081) (xy 380.055107 -0.843331) (xy 380.063019 -0.757948)
			(xy 380.078775 -0.673658) (xy 380.102242 -0.591182) (xy 380.133218 -0.511223) (xy 380.17144 -0.434463)
			(xy 380.216581 -0.361557) (xy 380.268257 -0.293128) (xy 380.326026 -0.229758) (xy 380.389396 -0.171989)
			(xy 380.457825 -0.120313) (xy 380.530731 -0.075172) (xy 380.607491 -0.03695) (xy 380.68745 -0.005974)
			(xy 380.769926 0.017493) (xy 380.854216 0.033249) (xy 380.939599 0.041161) (xy 381.025349 0.041161)
			(xy 381.110732 0.033249) (xy 381.195022 0.017493) (xy 381.277498 -0.005974) (xy 381.357457 -0.03695)
			(xy 381.434217 -0.075172) (xy 381.507123 -0.120313) (xy 381.575552 -0.171989) (xy 381.638922 -0.229758)
			(xy 381.696691 -0.293128) (xy 381.748367 -0.361557) (xy 381.793508 -0.434463) (xy 381.83173 -0.511223)
			(xy 381.862706 -0.591182) (xy 381.886173 -0.673658) (xy 381.901929 -0.757948) (xy 381.909841 -0.843331)
			(xy 381.910336 -0.886206) (xy 381.909841 -0.929081) (xy 381.901929 -1.014464) (xy 381.886173 -1.098754)
			(xy 381.862706 -1.18123) (xy 381.83173 -1.261189) (xy 381.793508 -1.337949) (xy 381.748367 -1.410855)
			(xy 381.696691 -1.479284) (xy 381.638922 -1.542654) (xy 381.575552 -1.600423) (xy 381.507123 -1.652099)
			(xy 381.434217 -1.69724) (xy 381.357457 -1.735462) (xy 381.277498 -1.766438) (xy 381.195022 -1.789905)
			(xy 381.110732 -1.805661) (xy 381.025349 -1.813573) (xy 380.939599 -1.813573) (xy 380.854216 -1.805661)
			(xy 380.769926 -1.789905) (xy 380.68745 -1.766438) (xy 380.607491 -1.735462) (xy 380.530731 -1.69724)
			(xy 380.457825 -1.652099) (xy 380.389396 -1.600423) (xy 380.326026 -1.542654) (xy 380.268257 -1.479284)
			(xy 380.216581 -1.410855) (xy 380.17144 -1.337949) (xy 380.133218 -1.261189) (xy 380.102242 -1.18123)
			(xy 380.078775 -1.098754) (xy 380.063019 -1.014464) (xy 380.055107 -0.929081) (xy 375.559841 -0.929081)
			(xy 375.551929 -1.014464) (xy 375.536173 -1.098754) (xy 375.512706 -1.18123) (xy 375.48173 -1.261189)
			(xy 375.443508 -1.337949) (xy 375.398367 -1.410855) (xy 375.346691 -1.479284) (xy 375.288922 -1.542654)
			(xy 375.225552 -1.600423) (xy 375.157123 -1.652099) (xy 375.084217 -1.69724) (xy 375.007457 -1.735462)
			(xy 374.927498 -1.766438) (xy 374.845022 -1.789905) (xy 374.760732 -1.805661) (xy 374.675349 -1.813573)
			(xy 374.589599 -1.813573) (xy 374.504216 -1.805661) (xy 374.419926 -1.789905) (xy 374.33745 -1.766438)
			(xy 374.257491 -1.735462) (xy 374.180731 -1.69724) (xy 374.107825 -1.652099) (xy 374.039396 -1.600423)
			(xy 373.976026 -1.542654) (xy 373.918257 -1.479284) (xy 373.866581 -1.410855) (xy 373.82144 -1.337949)
			(xy 373.783218 -1.261189) (xy 373.752242 -1.18123) (xy 373.728775 -1.098754) (xy 373.713019 -1.014464)
			(xy 373.705107 -0.929081) (xy 343.693001 -0.929081) (xy 343.685089 -1.014464) (xy 343.669333 -1.098754)
			(xy 343.645866 -1.18123) (xy 343.61489 -1.261189) (xy 343.576668 -1.337949) (xy 343.531527 -1.410855)
			(xy 343.479851 -1.479284) (xy 343.422082 -1.542654) (xy 343.358712 -1.600423) (xy 343.290283 -1.652099)
			(xy 343.217377 -1.69724) (xy 343.140617 -1.735462) (xy 343.060658 -1.766438) (xy 342.978182 -1.789905)
			(xy 342.893892 -1.805661) (xy 342.808509 -1.813573) (xy 342.722759 -1.813573) (xy 342.637376 -1.805661)
			(xy 342.553086 -1.789905) (xy 342.47061 -1.766438) (xy 342.390651 -1.735462) (xy 342.313891 -1.69724)
			(xy 342.240985 -1.652099) (xy 342.172556 -1.600423) (xy 342.109186 -1.542654) (xy 342.051417 -1.479284)
			(xy 341.999741 -1.410855) (xy 341.9546 -1.337949) (xy 341.916378 -1.261189) (xy 341.885402 -1.18123)
			(xy 341.861935 -1.098754) (xy 341.846179 -1.014464) (xy 341.838267 -0.929081) (xy 337.343001 -0.929081)
			(xy 337.335089 -1.014464) (xy 337.319333 -1.098754) (xy 337.295866 -1.18123) (xy 337.26489 -1.261189)
			(xy 337.226668 -1.337949) (xy 337.181527 -1.410855) (xy 337.129851 -1.479284) (xy 337.072082 -1.542654)
			(xy 337.008712 -1.600423) (xy 336.940283 -1.652099) (xy 336.867377 -1.69724) (xy 336.790617 -1.735462)
			(xy 336.710658 -1.766438) (xy 336.628182 -1.789905) (xy 336.543892 -1.805661) (xy 336.458509 -1.813573)
			(xy 336.372759 -1.813573) (xy 336.287376 -1.805661) (xy 336.203086 -1.789905) (xy 336.12061 -1.766438)
			(xy 336.040651 -1.735462) (xy 335.963891 -1.69724) (xy 335.890985 -1.652099) (xy 335.822556 -1.600423)
			(xy 335.759186 -1.542654) (xy 335.701417 -1.479284) (xy 335.649741 -1.410855) (xy 335.6046 -1.337949)
			(xy 335.566378 -1.261189) (xy 335.535402 -1.18123) (xy 335.511935 -1.098754) (xy 335.496179 -1.014464)
			(xy 335.488267 -0.929081) (xy 333.050655 -0.929081) (xy 333.042743 -1.014464) (xy 333.026987 -1.098754)
			(xy 333.00352 -1.18123) (xy 332.972544 -1.261189) (xy 332.934322 -1.337949) (xy 332.889181 -1.410855)
			(xy 332.837505 -1.479284) (xy 332.779736 -1.542654) (xy 332.716366 -1.600423) (xy 332.647937 -1.652099)
			(xy 332.575031 -1.69724) (xy 332.498271 -1.735462) (xy 332.418312 -1.766438) (xy 332.335836 -1.789905)
			(xy 332.251546 -1.805661) (xy 332.166163 -1.813573) (xy 332.080413 -1.813573) (xy 331.99503 -1.805661)
			(xy 331.91074 -1.789905) (xy 331.828264 -1.766438) (xy 331.748305 -1.735462) (xy 331.671545 -1.69724)
			(xy 331.598639 -1.652099) (xy 331.53021 -1.600423) (xy 331.46684 -1.542654) (xy 331.409071 -1.479284)
			(xy 331.357395 -1.410855) (xy 331.312254 -1.337949) (xy 331.274032 -1.261189) (xy 331.243056 -1.18123)
			(xy 331.219589 -1.098754) (xy 331.203833 -1.014464) (xy 331.195921 -0.929081) (xy 326.700655 -0.929081)
			(xy 326.692743 -1.014464) (xy 326.676987 -1.098754) (xy 326.65352 -1.18123) (xy 326.622544 -1.261189)
			(xy 326.584322 -1.337949) (xy 326.539181 -1.410855) (xy 326.487505 -1.479284) (xy 326.429736 -1.542654)
			(xy 326.366366 -1.600423) (xy 326.297937 -1.652099) (xy 326.225031 -1.69724) (xy 326.148271 -1.735462)
			(xy 326.068312 -1.766438) (xy 325.985836 -1.789905) (xy 325.901546 -1.805661) (xy 325.816163 -1.813573)
			(xy 325.730413 -1.813573) (xy 325.64503 -1.805661) (xy 325.56074 -1.789905) (xy 325.478264 -1.766438)
			(xy 325.398305 -1.735462) (xy 325.321545 -1.69724) (xy 325.248639 -1.652099) (xy 325.18021 -1.600423)
			(xy 325.11684 -1.542654) (xy 325.059071 -1.479284) (xy 325.007395 -1.410855) (xy 324.962254 -1.337949)
			(xy 324.924032 -1.261189) (xy 324.893056 -1.18123) (xy 324.869589 -1.098754) (xy 324.853833 -1.014464)
			(xy 324.845921 -0.929081) (xy 265.125975 -0.929081) (xy 265.118063 -1.014464) (xy 265.102307 -1.098754)
			(xy 265.07884 -1.18123) (xy 265.047864 -1.261189) (xy 265.009642 -1.337949) (xy 264.964501 -1.410855)
			(xy 264.912825 -1.479284) (xy 264.855056 -1.542654) (xy 264.791686 -1.600423) (xy 264.723257 -1.652099)
			(xy 264.650351 -1.69724) (xy 264.573591 -1.735462) (xy 264.493632 -1.766438) (xy 264.411156 -1.789905)
			(xy 264.326866 -1.805661) (xy 264.241483 -1.813573) (xy 264.155733 -1.813573) (xy 264.07035 -1.805661)
			(xy 263.98606 -1.789905) (xy 263.903584 -1.766438) (xy 263.823625 -1.735462) (xy 263.746865 -1.69724)
			(xy 263.673959 -1.652099) (xy 263.60553 -1.600423) (xy 263.54216 -1.542654) (xy 263.484391 -1.479284)
			(xy 263.432715 -1.410855) (xy 263.387574 -1.337949) (xy 263.349352 -1.261189) (xy 263.318376 -1.18123)
			(xy 263.294909 -1.098754) (xy 263.279153 -1.014464) (xy 263.271241 -0.929081) (xy 258.775975 -0.929081)
			(xy 258.768063 -1.014464) (xy 258.752307 -1.098754) (xy 258.72884 -1.18123) (xy 258.697864 -1.261189)
			(xy 258.659642 -1.337949) (xy 258.614501 -1.410855) (xy 258.562825 -1.479284) (xy 258.505056 -1.542654)
			(xy 258.441686 -1.600423) (xy 258.373257 -1.652099) (xy 258.300351 -1.69724) (xy 258.223591 -1.735462)
			(xy 258.143632 -1.766438) (xy 258.061156 -1.789905) (xy 257.976866 -1.805661) (xy 257.891483 -1.813573)
			(xy 257.805733 -1.813573) (xy 257.72035 -1.805661) (xy 257.63606 -1.789905) (xy 257.553584 -1.766438)
			(xy 257.473625 -1.735462) (xy 257.396865 -1.69724) (xy 257.323959 -1.652099) (xy 257.25553 -1.600423)
			(xy 257.19216 -1.542654) (xy 257.134391 -1.479284) (xy 257.082715 -1.410855) (xy 257.037574 -1.337949)
			(xy 256.999352 -1.261189) (xy 256.968376 -1.18123) (xy 256.944909 -1.098754) (xy 256.929153 -1.014464)
			(xy 256.921241 -0.929081) (xy 254.465119 -0.929081) (xy 254.465087 -0.931875) (xy 254.457175 -1.017258)
			(xy 254.441419 -1.101548) (xy 254.417952 -1.184024) (xy 254.386976 -1.263983) (xy 254.348754 -1.340743)
			(xy 254.303613 -1.413649) (xy 254.251937 -1.482078) (xy 254.194168 -1.545448) (xy 254.130798 -1.603217)
			(xy 254.062369 -1.654893) (xy 253.989463 -1.700034) (xy 253.912703 -1.738256) (xy 253.832744 -1.769232)
			(xy 253.750268 -1.792699) (xy 253.665978 -1.808455) (xy 253.580595 -1.816367) (xy 253.494845 -1.816367)
			(xy 253.409462 -1.808455) (xy 253.325172 -1.792699) (xy 253.242696 -1.769232) (xy 253.162737 -1.738256)
			(xy 253.085977 -1.700034) (xy 253.013071 -1.654893) (xy 252.944642 -1.603217) (xy 252.881272 -1.545448)
			(xy 252.823503 -1.482078) (xy 252.771827 -1.413649) (xy 252.726686 -1.340743) (xy 252.688464 -1.263983)
			(xy 252.657488 -1.184024) (xy 252.634021 -1.101548) (xy 252.618265 -1.017258) (xy 252.610353 -0.931875)
			(xy 248.115087 -0.931875) (xy 248.107175 -1.017258) (xy 248.091419 -1.101548) (xy 248.067952 -1.184024)
			(xy 248.036976 -1.263983) (xy 247.998754 -1.340743) (xy 247.953613 -1.413649) (xy 247.901937 -1.482078)
			(xy 247.844168 -1.545448) (xy 247.780798 -1.603217) (xy 247.712369 -1.654893) (xy 247.639463 -1.700034)
			(xy 247.562703 -1.738256) (xy 247.482744 -1.769232) (xy 247.400268 -1.792699) (xy 247.315978 -1.808455)
			(xy 247.230595 -1.816367) (xy 247.144845 -1.816367) (xy 247.059462 -1.808455) (xy 246.975172 -1.792699)
			(xy 246.892696 -1.769232) (xy 246.812737 -1.738256) (xy 246.735977 -1.700034) (xy 246.663071 -1.654893)
			(xy 246.594642 -1.603217) (xy 246.531272 -1.545448) (xy 246.473503 -1.482078) (xy 246.421827 -1.413649)
			(xy 246.376686 -1.340743) (xy 246.338464 -1.263983) (xy 246.307488 -1.184024) (xy 246.284021 -1.101548)
			(xy 246.268265 -1.017258) (xy 246.260353 -0.931875) (xy 216.248247 -0.931875) (xy 216.240335 -1.017258)
			(xy 216.224579 -1.101548) (xy 216.201112 -1.184024) (xy 216.170136 -1.263983) (xy 216.131914 -1.340743)
			(xy 216.086773 -1.413649) (xy 216.035097 -1.482078) (xy 215.977328 -1.545448) (xy 215.913958 -1.603217)
			(xy 215.845529 -1.654893) (xy 215.772623 -1.700034) (xy 215.695863 -1.738256) (xy 215.615904 -1.769232)
			(xy 215.533428 -1.792699) (xy 215.449138 -1.808455) (xy 215.363755 -1.816367) (xy 215.278005 -1.816367)
			(xy 215.192622 -1.808455) (xy 215.108332 -1.792699) (xy 215.025856 -1.769232) (xy 214.945897 -1.738256)
			(xy 214.869137 -1.700034) (xy 214.796231 -1.654893) (xy 214.727802 -1.603217) (xy 214.664432 -1.545448)
			(xy 214.606663 -1.482078) (xy 214.554987 -1.413649) (xy 214.509846 -1.340743) (xy 214.471624 -1.263983)
			(xy 214.440648 -1.184024) (xy 214.417181 -1.101548) (xy 214.401425 -1.017258) (xy 214.393513 -0.931875)
			(xy 209.898247 -0.931875) (xy 209.890335 -1.017258) (xy 209.874579 -1.101548) (xy 209.851112 -1.184024)
			(xy 209.820136 -1.263983) (xy 209.781914 -1.340743) (xy 209.736773 -1.413649) (xy 209.685097 -1.482078)
			(xy 209.627328 -1.545448) (xy 209.563958 -1.603217) (xy 209.495529 -1.654893) (xy 209.422623 -1.700034)
			(xy 209.345863 -1.738256) (xy 209.265904 -1.769232) (xy 209.183428 -1.792699) (xy 209.099138 -1.808455)
			(xy 209.013755 -1.816367) (xy 208.928005 -1.816367) (xy 208.842622 -1.808455) (xy 208.758332 -1.792699)
			(xy 208.675856 -1.769232) (xy 208.595897 -1.738256) (xy 208.519137 -1.700034) (xy 208.446231 -1.654893)
			(xy 208.377802 -1.603217) (xy 208.314432 -1.545448) (xy 208.256663 -1.482078) (xy 208.204987 -1.413649)
			(xy 208.159846 -1.340743) (xy 208.121624 -1.263983) (xy 208.090648 -1.184024) (xy 208.067181 -1.101548)
			(xy 208.051425 -1.017258) (xy 208.043513 -0.931875) (xy 84.20989 -0.931875) (xy 84.20989 -7.78002)
			(xy 84.210412 -7.835827) (xy 84.218755 -7.947128) (xy 84.235391 -8.057495) (xy 84.260229 -8.16631)
			(xy 84.293128 -8.272964) (xy 84.333906 -8.376862) (xy 84.382334 -8.477422) (xy 84.438141 -8.574082)
			(xy 84.501016 -8.666301) (xy 84.570606 -8.753563) (xy 84.646523 -8.835382) (xy 84.728341 -8.911298)
			(xy 84.815604 -8.980888) (xy 84.907824 -9.043762) (xy 85.004484 -9.099569) (xy 85.105044 -9.147996)
			(xy 85.208942 -9.188774) (xy 85.315596 -9.221673) (xy 85.424411 -9.24651) (xy 85.534778 -9.263146)
			(xy 85.646079 -9.271488) (xy 85.701886 -9.272016) (xy 122.102118 -9.272016) (xy 122.157925 -9.271494)
			(xy 122.269226 -9.263152) (xy 122.379593 -9.246515) (xy 122.488409 -9.221678) (xy 122.595063 -9.188778)
			(xy 122.698961 -9.148001) (xy 122.799522 -9.099573) (xy 122.896182 -9.043766) (xy 122.988401 -8.980891)
			(xy 123.075664 -8.911301) (xy 123.157483 -8.835384) (xy 123.2334 -8.753566) (xy 123.30299 -8.666303)
			(xy 123.365865 -8.574084) (xy 123.421672 -8.477423) (xy 123.4701 -8.376863) (xy 123.510878 -8.272965)
			(xy 123.543777 -8.16631) (xy 123.568615 -8.057495) (xy 123.585251 -7.947128) (xy 123.593594 -7.835827)
			(xy 123.594114 -7.78002) (xy 123.594114 -4.2799) (xy 123.594598 -4.209546) (xy 123.602488 -4.06906)
			(xy 123.618242 -3.929237) (xy 123.641812 -3.790517) (xy 123.673122 -3.653337) (xy 123.712075 -3.518129)
			(xy 123.758548 -3.385317) (xy 123.812395 -3.25532) (xy 123.873446 -3.128547) (xy 123.941509 -3.005396)
			(xy 124.01637 -2.886255) (xy 124.097794 -2.7715) (xy 124.185524 -2.66149) (xy 124.279284 -2.556573)
			(xy 124.37878 -2.457077) (xy 124.483698 -2.363317) (xy 124.593708 -2.275588) (xy 124.708464 -2.194165)
			(xy 124.827605 -2.119304) (xy 124.950755 -2.051241) (xy 125.077529 -1.990191) (xy 125.207526 -1.936345)
			(xy 125.340338 -1.889872) (xy 125.475547 -1.85092) (xy 125.612727 -1.81961) (xy 125.751447 -1.796041)
			(xy 125.89127 -1.780287) (xy 126.031756 -1.772398) (xy 126.10211 -1.771904) (xy 194.701922 -1.771904)
			(xy 194.772275 -1.772398) (xy 194.912761 -1.780289) (xy 195.052582 -1.796044) (xy 195.191301 -1.819614)
			(xy 195.32848 -1.850925) (xy 195.463687 -1.889879) (xy 195.596497 -1.936352) (xy 195.726493 -1.990199)
			(xy 195.853265 -2.05125) (xy 195.976414 -2.119314) (xy 196.095554 -2.194175) (xy 196.210308 -2.275598)
			(xy 196.320316 -2.363328) (xy 196.425233 -2.457088) (xy 196.524727 -2.556583) (xy 196.618486 -2.6615)
			(xy 196.706215 -2.77151) (xy 196.787637 -2.886265) (xy 196.862497 -3.005405) (xy 196.93056 -3.128555)
			(xy 196.99161 -3.255327) (xy 197.045455 -3.385323) (xy 197.075741 -3.471875) (xy 208.043513 -3.471875)
			(xy 208.043513 -3.386125) (xy 208.051425 -3.300742) (xy 208.067181 -3.216452) (xy 208.090648 -3.133976)
			(xy 208.121624 -3.054017) (xy 208.159846 -2.977257) (xy 208.204987 -2.904351) (xy 208.256663 -2.835922)
			(xy 208.314432 -2.772552) (xy 208.377802 -2.714783) (xy 208.446231 -2.663107) (xy 208.519137 -2.617966)
			(xy 208.595897 -2.579744) (xy 208.675856 -2.548768) (xy 208.758332 -2.525301) (xy 208.842622 -2.509545)
			(xy 208.928005 -2.501633) (xy 209.013755 -2.501633) (xy 209.099138 -2.509545) (xy 209.183428 -2.525301)
			(xy 209.265904 -2.548768) (xy 209.345863 -2.579744) (xy 209.368066 -2.5908) (xy 212.978492 -2.5908)
			(xy 212.978492 -1.7272) (xy 212.978978 -1.699931) (xy 212.98674 -1.645947) (xy 213.002105 -1.593617)
			(xy 213.024762 -1.544007) (xy 213.054248 -1.498126) (xy 213.089963 -1.456909) (xy 213.13118 -1.421194)
			(xy 213.177061 -1.391708) (xy 213.226671 -1.369051) (xy 213.279001 -1.353686) (xy 213.332985 -1.345924)
			(xy 213.387523 -1.345924) (xy 213.441507 -1.353686) (xy 213.493837 -1.369051) (xy 213.543447 -1.391708)
			(xy 213.589328 -1.421194) (xy 213.630545 -1.456909) (xy 213.66626 -1.498126) (xy 213.695746 -1.544007)
			(xy 213.718403 -1.593617) (xy 213.733768 -1.645947) (xy 213.74153 -1.699931) (xy 213.742016 -1.7272)
			(xy 213.742016 -2.5908) (xy 213.74153 -2.618069) (xy 213.733768 -2.672053) (xy 213.718403 -2.724383)
			(xy 213.695746 -2.773993) (xy 213.66626 -2.819874) (xy 213.630545 -2.861091) (xy 213.589328 -2.896806)
			(xy 213.543447 -2.926292) (xy 213.493837 -2.948949) (xy 213.441507 -2.964314) (xy 213.387523 -2.972076)
			(xy 213.332985 -2.972076) (xy 213.279001 -2.964314) (xy 213.226671 -2.948949) (xy 213.177061 -2.926292)
			(xy 213.13118 -2.896806) (xy 213.089963 -2.861091) (xy 213.054248 -2.819874) (xy 213.024762 -2.773993)
			(xy 213.002105 -2.724383) (xy 212.98674 -2.672053) (xy 212.978978 -2.618069) (xy 212.978492 -2.5908)
			(xy 209.368066 -2.5908) (xy 209.422623 -2.617966) (xy 209.495529 -2.663107) (xy 209.563958 -2.714783)
			(xy 209.627328 -2.772552) (xy 209.685097 -2.835922) (xy 209.736773 -2.904351) (xy 209.781914 -2.977257)
			(xy 209.820136 -3.054017) (xy 209.851112 -3.133976) (xy 209.874579 -3.216452) (xy 209.890335 -3.300742)
			(xy 209.898247 -3.386125) (xy 209.898742 -3.429) (xy 209.898247 -3.471875) (xy 214.393513 -3.471875)
			(xy 214.393513 -3.386125) (xy 214.401425 -3.300742) (xy 214.417181 -3.216452) (xy 214.440648 -3.133976)
			(xy 214.471624 -3.054017) (xy 214.509846 -2.977257) (xy 214.554987 -2.904351) (xy 214.606663 -2.835922)
			(xy 214.664432 -2.772552) (xy 214.727802 -2.714783) (xy 214.796231 -2.663107) (xy 214.869137 -2.617966)
			(xy 214.945897 -2.579744) (xy 215.025856 -2.548768) (xy 215.108332 -2.525301) (xy 215.192622 -2.509545)
			(xy 215.278005 -2.501633) (xy 215.363755 -2.501633) (xy 215.449138 -2.509545) (xy 215.533428 -2.525301)
			(xy 215.615904 -2.548768) (xy 215.695863 -2.579744) (xy 215.772623 -2.617966) (xy 215.845529 -2.663107)
			(xy 215.913958 -2.714783) (xy 215.977328 -2.772552) (xy 216.035097 -2.835922) (xy 216.086773 -2.904351)
			(xy 216.131914 -2.977257) (xy 216.170136 -3.054017) (xy 216.201112 -3.133976) (xy 216.224579 -3.216452)
			(xy 216.240335 -3.300742) (xy 216.248247 -3.386125) (xy 216.248742 -3.429) (xy 216.248247 -3.471875)
			(xy 246.260353 -3.471875) (xy 246.260353 -3.386125) (xy 246.268265 -3.300742) (xy 246.284021 -3.216452)
			(xy 246.307488 -3.133976) (xy 246.338464 -3.054017) (xy 246.376686 -2.977257) (xy 246.421827 -2.904351)
			(xy 246.473503 -2.835922) (xy 246.531272 -2.772552) (xy 246.594642 -2.714783) (xy 246.663071 -2.663107)
			(xy 246.735977 -2.617966) (xy 246.812737 -2.579744) (xy 246.892696 -2.548768) (xy 246.975172 -2.525301)
			(xy 247.059462 -2.509545) (xy 247.144845 -2.501633) (xy 247.230595 -2.501633) (xy 247.315978 -2.509545)
			(xy 247.400268 -2.525301) (xy 247.482744 -2.548768) (xy 247.562703 -2.579744) (xy 247.584906 -2.5908)
			(xy 248.766584 -2.5908) (xy 248.766584 -1.7272) (xy 248.76707 -1.699931) (xy 248.774832 -1.645947)
			(xy 248.790197 -1.593617) (xy 248.812854 -1.544007) (xy 248.84234 -1.498126) (xy 248.878055 -1.456909)
			(xy 248.919272 -1.421194) (xy 248.965153 -1.391708) (xy 249.014763 -1.369051) (xy 249.067093 -1.353686)
			(xy 249.121077 -1.345924) (xy 249.175615 -1.345924) (xy 249.229599 -1.353686) (xy 249.281929 -1.369051)
			(xy 249.331539 -1.391708) (xy 249.37742 -1.421194) (xy 249.418637 -1.456909) (xy 249.454352 -1.498126)
			(xy 249.483838 -1.544007) (xy 249.506495 -1.593617) (xy 249.52186 -1.645947) (xy 249.529622 -1.699931)
			(xy 249.530108 -1.7272) (xy 249.530108 -2.5908) (xy 249.529622 -2.618069) (xy 249.52186 -2.672053)
			(xy 249.506495 -2.724383) (xy 249.483838 -2.773993) (xy 249.454352 -2.819874) (xy 249.418637 -2.861091)
			(xy 249.37742 -2.896806) (xy 249.331539 -2.926292) (xy 249.281929 -2.948949) (xy 249.229599 -2.964314)
			(xy 249.175615 -2.972076) (xy 249.121077 -2.972076) (xy 249.067093 -2.964314) (xy 249.014763 -2.948949)
			(xy 248.965153 -2.926292) (xy 248.919272 -2.896806) (xy 248.878055 -2.861091) (xy 248.84234 -2.819874)
			(xy 248.812854 -2.773993) (xy 248.790197 -2.724383) (xy 248.774832 -2.672053) (xy 248.76707 -2.618069)
			(xy 248.766584 -2.5908) (xy 247.584906 -2.5908) (xy 247.639463 -2.617966) (xy 247.712369 -2.663107)
			(xy 247.780798 -2.714783) (xy 247.844168 -2.772552) (xy 247.901937 -2.835922) (xy 247.953613 -2.904351)
			(xy 247.998754 -2.977257) (xy 248.036976 -3.054017) (xy 248.067952 -3.133976) (xy 248.091419 -3.216452)
			(xy 248.107175 -3.300742) (xy 248.115087 -3.386125) (xy 248.115582 -3.429) (xy 248.115087 -3.471875)
			(xy 252.610353 -3.471875) (xy 252.610353 -3.386125) (xy 252.618265 -3.300742) (xy 252.634021 -3.216452)
			(xy 252.657488 -3.133976) (xy 252.688464 -3.054017) (xy 252.726686 -2.977257) (xy 252.771827 -2.904351)
			(xy 252.823503 -2.835922) (xy 252.881272 -2.772552) (xy 252.944642 -2.714783) (xy 253.013071 -2.663107)
			(xy 253.085977 -2.617966) (xy 253.162737 -2.579744) (xy 253.242696 -2.548768) (xy 253.325172 -2.525301)
			(xy 253.409462 -2.509545) (xy 253.494845 -2.501633) (xy 253.580595 -2.501633) (xy 253.665978 -2.509545)
			(xy 253.750268 -2.525301) (xy 253.832744 -2.548768) (xy 253.912703 -2.579744) (xy 253.989463 -2.617966)
			(xy 254.062369 -2.663107) (xy 254.130798 -2.714783) (xy 254.194168 -2.772552) (xy 254.251937 -2.835922)
			(xy 254.303613 -2.904351) (xy 254.348754 -2.977257) (xy 254.386976 -3.054017) (xy 254.417952 -3.133976)
			(xy 254.441419 -3.216452) (xy 254.457175 -3.300742) (xy 254.465087 -3.386125) (xy 254.465582 -3.429)
			(xy 254.465119 -3.469081) (xy 256.921241 -3.469081) (xy 256.921241 -3.383331) (xy 256.929153 -3.297948)
			(xy 256.944909 -3.213658) (xy 256.968376 -3.131182) (xy 256.999352 -3.051223) (xy 257.037574 -2.974463)
			(xy 257.082715 -2.901557) (xy 257.134391 -2.833128) (xy 257.19216 -2.769758) (xy 257.25553 -2.711989)
			(xy 257.323959 -2.660313) (xy 257.396865 -2.615172) (xy 257.473625 -2.57695) (xy 257.553584 -2.545974)
			(xy 257.63606 -2.522507) (xy 257.72035 -2.506751) (xy 257.805733 -2.498839) (xy 257.891483 -2.498839)
			(xy 257.976866 -2.506751) (xy 258.061156 -2.522507) (xy 258.143632 -2.545974) (xy 258.223591 -2.57695)
			(xy 258.300351 -2.615172) (xy 258.373257 -2.660313) (xy 258.441686 -2.711989) (xy 258.505056 -2.769758)
			(xy 258.562825 -2.833128) (xy 258.614501 -2.901557) (xy 258.659642 -2.974463) (xy 258.697864 -3.051223)
			(xy 258.72884 -3.131182) (xy 258.752307 -3.213658) (xy 258.768063 -3.297948) (xy 258.775975 -3.383331)
			(xy 258.77647 -3.426206) (xy 258.775975 -3.469081) (xy 263.271241 -3.469081) (xy 263.271241 -3.383331)
			(xy 263.279153 -3.297948) (xy 263.294909 -3.213658) (xy 263.318376 -3.131182) (xy 263.349352 -3.051223)
			(xy 263.387574 -2.974463) (xy 263.432715 -2.901557) (xy 263.484391 -2.833128) (xy 263.54216 -2.769758)
			(xy 263.60553 -2.711989) (xy 263.673959 -2.660313) (xy 263.746865 -2.615172) (xy 263.823625 -2.57695)
			(xy 263.903584 -2.545974) (xy 263.98606 -2.522507) (xy 264.07035 -2.506751) (xy 264.155733 -2.498839)
			(xy 264.241483 -2.498839) (xy 264.326866 -2.506751) (xy 264.411156 -2.522507) (xy 264.493632 -2.545974)
			(xy 264.573591 -2.57695) (xy 264.650351 -2.615172) (xy 264.723257 -2.660313) (xy 264.791686 -2.711989)
			(xy 264.855056 -2.769758) (xy 264.912825 -2.833128) (xy 264.964501 -2.901557) (xy 265.009642 -2.974463)
			(xy 265.047864 -3.051223) (xy 265.07884 -3.131182) (xy 265.102307 -3.213658) (xy 265.118063 -3.297948)
			(xy 265.125975 -3.383331) (xy 265.12647 -3.426206) (xy 265.125975 -3.469081) (xy 324.845921 -3.469081)
			(xy 324.845921 -3.383331) (xy 324.853833 -3.297948) (xy 324.869589 -3.213658) (xy 324.893056 -3.131182)
			(xy 324.924032 -3.051223) (xy 324.962254 -2.974463) (xy 325.007395 -2.901557) (xy 325.059071 -2.833128)
			(xy 325.11684 -2.769758) (xy 325.18021 -2.711989) (xy 325.248639 -2.660313) (xy 325.321545 -2.615172)
			(xy 325.398305 -2.57695) (xy 325.478264 -2.545974) (xy 325.56074 -2.522507) (xy 325.64503 -2.506751)
			(xy 325.730413 -2.498839) (xy 325.816163 -2.498839) (xy 325.901546 -2.506751) (xy 325.985836 -2.522507)
			(xy 326.068312 -2.545974) (xy 326.148271 -2.57695) (xy 326.225031 -2.615172) (xy 326.297937 -2.660313)
			(xy 326.366366 -2.711989) (xy 326.429736 -2.769758) (xy 326.487505 -2.833128) (xy 326.539181 -2.901557)
			(xy 326.584322 -2.974463) (xy 326.622544 -3.051223) (xy 326.65352 -3.131182) (xy 326.676987 -3.213658)
			(xy 326.692743 -3.297948) (xy 326.700655 -3.383331) (xy 326.70115 -3.426206) (xy 326.700655 -3.469081)
			(xy 331.195921 -3.469081) (xy 331.195921 -3.383331) (xy 331.203833 -3.297948) (xy 331.219589 -3.213658)
			(xy 331.243056 -3.131182) (xy 331.274032 -3.051223) (xy 331.312254 -2.974463) (xy 331.357395 -2.901557)
			(xy 331.409071 -2.833128) (xy 331.46684 -2.769758) (xy 331.53021 -2.711989) (xy 331.598639 -2.660313)
			(xy 331.671545 -2.615172) (xy 331.748305 -2.57695) (xy 331.828264 -2.545974) (xy 331.91074 -2.522507)
			(xy 331.99503 -2.506751) (xy 332.080413 -2.498839) (xy 332.166163 -2.498839) (xy 332.251546 -2.506751)
			(xy 332.335836 -2.522507) (xy 332.418312 -2.545974) (xy 332.498271 -2.57695) (xy 332.575031 -2.615172)
			(xy 332.647937 -2.660313) (xy 332.716366 -2.711989) (xy 332.779736 -2.769758) (xy 332.837505 -2.833128)
			(xy 332.889181 -2.901557) (xy 332.934322 -2.974463) (xy 332.972544 -3.051223) (xy 333.00352 -3.131182)
			(xy 333.026987 -3.213658) (xy 333.042743 -3.297948) (xy 333.050655 -3.383331) (xy 333.05115 -3.426206)
			(xy 333.050655 -3.469081) (xy 335.488267 -3.469081) (xy 335.488267 -3.383331) (xy 335.496179 -3.297948)
			(xy 335.511935 -3.213658) (xy 335.535402 -3.131182) (xy 335.566378 -3.051223) (xy 335.6046 -2.974463)
			(xy 335.649741 -2.901557) (xy 335.701417 -2.833128) (xy 335.759186 -2.769758) (xy 335.822556 -2.711989)
			(xy 335.890985 -2.660313) (xy 335.963891 -2.615172) (xy 336.040651 -2.57695) (xy 336.12061 -2.545974)
			(xy 336.203086 -2.522507) (xy 336.287376 -2.506751) (xy 336.372759 -2.498839) (xy 336.458509 -2.498839)
			(xy 336.543892 -2.506751) (xy 336.628182 -2.522507) (xy 336.710658 -2.545974) (xy 336.790617 -2.57695)
			(xy 336.867377 -2.615172) (xy 336.940283 -2.660313) (xy 337.008712 -2.711989) (xy 337.072082 -2.769758)
			(xy 337.129851 -2.833128) (xy 337.181527 -2.901557) (xy 337.226668 -2.974463) (xy 337.26489 -3.051223)
			(xy 337.295866 -3.131182) (xy 337.319333 -3.213658) (xy 337.335089 -3.297948) (xy 337.343001 -3.383331)
			(xy 337.343496 -3.426206) (xy 337.343001 -3.469081) (xy 341.838267 -3.469081) (xy 341.838267 -3.383331)
			(xy 341.846179 -3.297948) (xy 341.861935 -3.213658) (xy 341.885402 -3.131182) (xy 341.916378 -3.051223)
			(xy 341.9546 -2.974463) (xy 341.999741 -2.901557) (xy 342.051417 -2.833128) (xy 342.109186 -2.769758)
			(xy 342.172556 -2.711989) (xy 342.240985 -2.660313) (xy 342.313891 -2.615172) (xy 342.390651 -2.57695)
			(xy 342.47061 -2.545974) (xy 342.553086 -2.522507) (xy 342.637376 -2.506751) (xy 342.722759 -2.498839)
			(xy 342.808509 -2.498839) (xy 342.893892 -2.506751) (xy 342.978182 -2.522507) (xy 343.060658 -2.545974)
			(xy 343.140617 -2.57695) (xy 343.217377 -2.615172) (xy 343.290283 -2.660313) (xy 343.358712 -2.711989)
			(xy 343.422082 -2.769758) (xy 343.479851 -2.833128) (xy 343.531527 -2.901557) (xy 343.576668 -2.974463)
			(xy 343.61489 -3.051223) (xy 343.645866 -3.131182) (xy 343.669333 -3.213658) (xy 343.685089 -3.297948)
			(xy 343.693001 -3.383331) (xy 343.693496 -3.426206) (xy 343.693001 -3.469081) (xy 373.705107 -3.469081)
			(xy 373.705107 -3.383331) (xy 373.713019 -3.297948) (xy 373.728775 -3.213658) (xy 373.752242 -3.131182)
			(xy 373.783218 -3.051223) (xy 373.82144 -2.974463) (xy 373.866581 -2.901557) (xy 373.918257 -2.833128)
			(xy 373.976026 -2.769758) (xy 374.039396 -2.711989) (xy 374.107825 -2.660313) (xy 374.180731 -2.615172)
			(xy 374.257491 -2.57695) (xy 374.33745 -2.545974) (xy 374.419926 -2.522507) (xy 374.504216 -2.506751)
			(xy 374.589599 -2.498839) (xy 374.675349 -2.498839) (xy 374.760732 -2.506751) (xy 374.845022 -2.522507)
			(xy 374.927498 -2.545974) (xy 375.007457 -2.57695) (xy 375.084217 -2.615172) (xy 375.157123 -2.660313)
			(xy 375.225552 -2.711989) (xy 375.288922 -2.769758) (xy 375.346691 -2.833128) (xy 375.398367 -2.901557)
			(xy 375.443508 -2.974463) (xy 375.48173 -3.051223) (xy 375.512706 -3.131182) (xy 375.536173 -3.213658)
			(xy 375.551929 -3.297948) (xy 375.559841 -3.383331) (xy 375.560336 -3.426206) (xy 375.559841 -3.469081)
			(xy 380.055107 -3.469081) (xy 380.055107 -3.383331) (xy 380.063019 -3.297948) (xy 380.078775 -3.213658)
			(xy 380.102242 -3.131182) (xy 380.133218 -3.051223) (xy 380.17144 -2.974463) (xy 380.216581 -2.901557)
			(xy 380.268257 -2.833128) (xy 380.326026 -2.769758) (xy 380.389396 -2.711989) (xy 380.457825 -2.660313)
			(xy 380.530731 -2.615172) (xy 380.607491 -2.57695) (xy 380.68745 -2.545974) (xy 380.769926 -2.522507)
			(xy 380.854216 -2.506751) (xy 380.939599 -2.498839) (xy 381.025349 -2.498839) (xy 381.110732 -2.506751)
			(xy 381.195022 -2.522507) (xy 381.277498 -2.545974) (xy 381.357457 -2.57695) (xy 381.434217 -2.615172)
			(xy 381.507123 -2.660313) (xy 381.575552 -2.711989) (xy 381.638922 -2.769758) (xy 381.696691 -2.833128)
			(xy 381.748367 -2.901557) (xy 381.793508 -2.974463) (xy 381.83173 -3.051223) (xy 381.862706 -3.131182)
			(xy 381.886173 -3.213658) (xy 381.901929 -3.297948) (xy 381.909841 -3.383331) (xy 381.910336 -3.426206)
			(xy 381.909841 -3.469081) (xy 381.901929 -3.554464) (xy 381.886173 -3.638754) (xy 381.862706 -3.72123)
			(xy 381.83173 -3.801189) (xy 381.793508 -3.877949) (xy 381.748367 -3.950855) (xy 381.696691 -4.019284)
			(xy 381.638922 -4.082654) (xy 381.575552 -4.140423) (xy 381.507123 -4.192099) (xy 381.434217 -4.23724)
			(xy 381.357457 -4.275462) (xy 381.277498 -4.306438) (xy 381.195022 -4.329905) (xy 381.110732 -4.345661)
			(xy 381.025349 -4.353573) (xy 380.939599 -4.353573) (xy 380.854216 -4.345661) (xy 380.769926 -4.329905)
			(xy 380.68745 -4.306438) (xy 380.607491 -4.275462) (xy 380.530731 -4.23724) (xy 380.457825 -4.192099)
			(xy 380.389396 -4.140423) (xy 380.326026 -4.082654) (xy 380.268257 -4.019284) (xy 380.216581 -3.950855)
			(xy 380.17144 -3.877949) (xy 380.133218 -3.801189) (xy 380.102242 -3.72123) (xy 380.078775 -3.638754)
			(xy 380.063019 -3.554464) (xy 380.055107 -3.469081) (xy 375.559841 -3.469081) (xy 375.551929 -3.554464)
			(xy 375.536173 -3.638754) (xy 375.512706 -3.72123) (xy 375.48173 -3.801189) (xy 375.443508 -3.877949)
			(xy 375.398367 -3.950855) (xy 375.346691 -4.019284) (xy 375.288922 -4.082654) (xy 375.225552 -4.140423)
			(xy 375.157123 -4.192099) (xy 375.084217 -4.23724) (xy 375.007457 -4.275462) (xy 374.927498 -4.306438)
			(xy 374.845022 -4.329905) (xy 374.760732 -4.345661) (xy 374.675349 -4.353573) (xy 374.589599 -4.353573)
			(xy 374.504216 -4.345661) (xy 374.419926 -4.329905) (xy 374.33745 -4.306438) (xy 374.257491 -4.275462)
			(xy 374.180731 -4.23724) (xy 374.107825 -4.192099) (xy 374.039396 -4.140423) (xy 373.976026 -4.082654)
			(xy 373.918257 -4.019284) (xy 373.866581 -3.950855) (xy 373.82144 -3.877949) (xy 373.783218 -3.801189)
			(xy 373.752242 -3.72123) (xy 373.728775 -3.638754) (xy 373.713019 -3.554464) (xy 373.705107 -3.469081)
			(xy 343.693001 -3.469081) (xy 343.685089 -3.554464) (xy 343.669333 -3.638754) (xy 343.645866 -3.72123)
			(xy 343.61489 -3.801189) (xy 343.576668 -3.877949) (xy 343.531527 -3.950855) (xy 343.479851 -4.019284)
			(xy 343.422082 -4.082654) (xy 343.358712 -4.140423) (xy 343.290283 -4.192099) (xy 343.217377 -4.23724)
			(xy 343.140617 -4.275462) (xy 343.060658 -4.306438) (xy 342.978182 -4.329905) (xy 342.893892 -4.345661)
			(xy 342.808509 -4.353573) (xy 342.722759 -4.353573) (xy 342.637376 -4.345661) (xy 342.553086 -4.329905)
			(xy 342.47061 -4.306438) (xy 342.390651 -4.275462) (xy 342.313891 -4.23724) (xy 342.240985 -4.192099)
			(xy 342.172556 -4.140423) (xy 342.109186 -4.082654) (xy 342.051417 -4.019284) (xy 341.999741 -3.950855)
			(xy 341.9546 -3.877949) (xy 341.916378 -3.801189) (xy 341.885402 -3.72123) (xy 341.861935 -3.638754)
			(xy 341.846179 -3.554464) (xy 341.838267 -3.469081) (xy 337.343001 -3.469081) (xy 337.335089 -3.554464)
			(xy 337.319333 -3.638754) (xy 337.295866 -3.72123) (xy 337.26489 -3.801189) (xy 337.226668 -3.877949)
			(xy 337.181527 -3.950855) (xy 337.129851 -4.019284) (xy 337.072082 -4.082654) (xy 337.008712 -4.140423)
			(xy 336.940283 -4.192099) (xy 336.867377 -4.23724) (xy 336.790617 -4.275462) (xy 336.710658 -4.306438)
			(xy 336.628182 -4.329905) (xy 336.543892 -4.345661) (xy 336.458509 -4.353573) (xy 336.372759 -4.353573)
			(xy 336.287376 -4.345661) (xy 336.203086 -4.329905) (xy 336.12061 -4.306438) (xy 336.040651 -4.275462)
			(xy 335.963891 -4.23724) (xy 335.890985 -4.192099) (xy 335.822556 -4.140423) (xy 335.759186 -4.082654)
			(xy 335.701417 -4.019284) (xy 335.649741 -3.950855) (xy 335.6046 -3.877949) (xy 335.566378 -3.801189)
			(xy 335.535402 -3.72123) (xy 335.511935 -3.638754) (xy 335.496179 -3.554464) (xy 335.488267 -3.469081)
			(xy 333.050655 -3.469081) (xy 333.042743 -3.554464) (xy 333.026987 -3.638754) (xy 333.00352 -3.72123)
			(xy 332.972544 -3.801189) (xy 332.934322 -3.877949) (xy 332.889181 -3.950855) (xy 332.837505 -4.019284)
			(xy 332.779736 -4.082654) (xy 332.716366 -4.140423) (xy 332.647937 -4.192099) (xy 332.575031 -4.23724)
			(xy 332.498271 -4.275462) (xy 332.418312 -4.306438) (xy 332.335836 -4.329905) (xy 332.251546 -4.345661)
			(xy 332.166163 -4.353573) (xy 332.080413 -4.353573) (xy 331.99503 -4.345661) (xy 331.91074 -4.329905)
			(xy 331.828264 -4.306438) (xy 331.748305 -4.275462) (xy 331.671545 -4.23724) (xy 331.598639 -4.192099)
			(xy 331.53021 -4.140423) (xy 331.46684 -4.082654) (xy 331.409071 -4.019284) (xy 331.357395 -3.950855)
			(xy 331.312254 -3.877949) (xy 331.274032 -3.801189) (xy 331.243056 -3.72123) (xy 331.219589 -3.638754)
			(xy 331.203833 -3.554464) (xy 331.195921 -3.469081) (xy 326.700655 -3.469081) (xy 326.692743 -3.554464)
			(xy 326.676987 -3.638754) (xy 326.65352 -3.72123) (xy 326.622544 -3.801189) (xy 326.584322 -3.877949)
			(xy 326.539181 -3.950855) (xy 326.487505 -4.019284) (xy 326.429736 -4.082654) (xy 326.366366 -4.140423)
			(xy 326.297937 -4.192099) (xy 326.225031 -4.23724) (xy 326.148271 -4.275462) (xy 326.068312 -4.306438)
			(xy 325.985836 -4.329905) (xy 325.901546 -4.345661) (xy 325.816163 -4.353573) (xy 325.730413 -4.353573)
			(xy 325.64503 -4.345661) (xy 325.56074 -4.329905) (xy 325.478264 -4.306438) (xy 325.398305 -4.275462)
			(xy 325.321545 -4.23724) (xy 325.248639 -4.192099) (xy 325.18021 -4.140423) (xy 325.11684 -4.082654)
			(xy 325.059071 -4.019284) (xy 325.007395 -3.950855) (xy 324.962254 -3.877949) (xy 324.924032 -3.801189)
			(xy 324.893056 -3.72123) (xy 324.869589 -3.638754) (xy 324.853833 -3.554464) (xy 324.845921 -3.469081)
			(xy 265.125975 -3.469081) (xy 265.118063 -3.554464) (xy 265.102307 -3.638754) (xy 265.07884 -3.72123)
			(xy 265.047864 -3.801189) (xy 265.009642 -3.877949) (xy 264.964501 -3.950855) (xy 264.912825 -4.019284)
			(xy 264.855056 -4.082654) (xy 264.791686 -4.140423) (xy 264.723257 -4.192099) (xy 264.650351 -4.23724)
			(xy 264.573591 -4.275462) (xy 264.493632 -4.306438) (xy 264.411156 -4.329905) (xy 264.326866 -4.345661)
			(xy 264.241483 -4.353573) (xy 264.155733 -4.353573) (xy 264.07035 -4.345661) (xy 263.98606 -4.329905)
			(xy 263.903584 -4.306438) (xy 263.823625 -4.275462) (xy 263.746865 -4.23724) (xy 263.673959 -4.192099)
			(xy 263.60553 -4.140423) (xy 263.54216 -4.082654) (xy 263.484391 -4.019284) (xy 263.432715 -3.950855)
			(xy 263.387574 -3.877949) (xy 263.349352 -3.801189) (xy 263.318376 -3.72123) (xy 263.294909 -3.638754)
			(xy 263.279153 -3.554464) (xy 263.271241 -3.469081) (xy 258.775975 -3.469081) (xy 258.768063 -3.554464)
			(xy 258.752307 -3.638754) (xy 258.72884 -3.72123) (xy 258.697864 -3.801189) (xy 258.659642 -3.877949)
			(xy 258.614501 -3.950855) (xy 258.562825 -4.019284) (xy 258.505056 -4.082654) (xy 258.441686 -4.140423)
			(xy 258.373257 -4.192099) (xy 258.300351 -4.23724) (xy 258.223591 -4.275462) (xy 258.143632 -4.306438)
			(xy 258.061156 -4.329905) (xy 257.976866 -4.345661) (xy 257.891483 -4.353573) (xy 257.805733 -4.353573)
			(xy 257.72035 -4.345661) (xy 257.63606 -4.329905) (xy 257.553584 -4.306438) (xy 257.473625 -4.275462)
			(xy 257.396865 -4.23724) (xy 257.323959 -4.192099) (xy 257.25553 -4.140423) (xy 257.19216 -4.082654)
			(xy 257.134391 -4.019284) (xy 257.082715 -3.950855) (xy 257.037574 -3.877949) (xy 256.999352 -3.801189)
			(xy 256.968376 -3.72123) (xy 256.944909 -3.638754) (xy 256.929153 -3.554464) (xy 256.921241 -3.469081)
			(xy 254.465119 -3.469081) (xy 254.465087 -3.471875) (xy 254.457175 -3.557258) (xy 254.441419 -3.641548)
			(xy 254.417952 -3.724024) (xy 254.386976 -3.803983) (xy 254.348754 -3.880743) (xy 254.303613 -3.953649)
			(xy 254.251937 -4.022078) (xy 254.194168 -4.085448) (xy 254.130798 -4.143217) (xy 254.062369 -4.194893)
			(xy 253.989463 -4.240034) (xy 253.912703 -4.278256) (xy 253.832744 -4.309232) (xy 253.750268 -4.332699)
			(xy 253.665978 -4.348455) (xy 253.580595 -4.356367) (xy 253.494845 -4.356367) (xy 253.409462 -4.348455)
			(xy 253.325172 -4.332699) (xy 253.242696 -4.309232) (xy 253.162737 -4.278256) (xy 253.085977 -4.240034)
			(xy 253.013071 -4.194893) (xy 252.944642 -4.143217) (xy 252.881272 -4.085448) (xy 252.823503 -4.022078)
			(xy 252.771827 -3.953649) (xy 252.726686 -3.880743) (xy 252.688464 -3.803983) (xy 252.657488 -3.724024)
			(xy 252.634021 -3.641548) (xy 252.618265 -3.557258) (xy 252.610353 -3.471875) (xy 248.115087 -3.471875)
			(xy 248.107175 -3.557258) (xy 248.091419 -3.641548) (xy 248.067952 -3.724024) (xy 248.036976 -3.803983)
			(xy 247.998754 -3.880743) (xy 247.953613 -3.953649) (xy 247.901937 -4.022078) (xy 247.844168 -4.085448)
			(xy 247.780798 -4.143217) (xy 247.712369 -4.194893) (xy 247.639463 -4.240034) (xy 247.562703 -4.278256)
			(xy 247.482744 -4.309232) (xy 247.400268 -4.332699) (xy 247.315978 -4.348455) (xy 247.230595 -4.356367)
			(xy 247.144845 -4.356367) (xy 247.059462 -4.348455) (xy 246.975172 -4.332699) (xy 246.892696 -4.309232)
			(xy 246.812737 -4.278256) (xy 246.735977 -4.240034) (xy 246.663071 -4.194893) (xy 246.594642 -4.143217)
			(xy 246.531272 -4.085448) (xy 246.473503 -4.022078) (xy 246.421827 -3.953649) (xy 246.376686 -3.880743)
			(xy 246.338464 -3.803983) (xy 246.307488 -3.724024) (xy 246.284021 -3.641548) (xy 246.268265 -3.557258)
			(xy 246.260353 -3.471875) (xy 216.248247 -3.471875) (xy 216.240335 -3.557258) (xy 216.224579 -3.641548)
			(xy 216.201112 -3.724024) (xy 216.170136 -3.803983) (xy 216.131914 -3.880743) (xy 216.086773 -3.953649)
			(xy 216.035097 -4.022078) (xy 215.977328 -4.085448) (xy 215.913958 -4.143217) (xy 215.845529 -4.194893)
			(xy 215.772623 -4.240034) (xy 215.695863 -4.278256) (xy 215.615904 -4.309232) (xy 215.533428 -4.332699)
			(xy 215.449138 -4.348455) (xy 215.363755 -4.356367) (xy 215.278005 -4.356367) (xy 215.192622 -4.348455)
			(xy 215.108332 -4.332699) (xy 215.025856 -4.309232) (xy 214.945897 -4.278256) (xy 214.869137 -4.240034)
			(xy 214.796231 -4.194893) (xy 214.727802 -4.143217) (xy 214.664432 -4.085448) (xy 214.606663 -4.022078)
			(xy 214.554987 -3.953649) (xy 214.509846 -3.880743) (xy 214.471624 -3.803983) (xy 214.440648 -3.724024)
			(xy 214.417181 -3.641548) (xy 214.401425 -3.557258) (xy 214.393513 -3.471875) (xy 209.898247 -3.471875)
			(xy 209.890335 -3.557258) (xy 209.874579 -3.641548) (xy 209.851112 -3.724024) (xy 209.820136 -3.803983)
			(xy 209.781914 -3.880743) (xy 209.736773 -3.953649) (xy 209.685097 -4.022078) (xy 209.627328 -4.085448)
			(xy 209.563958 -4.143217) (xy 209.495529 -4.194893) (xy 209.422623 -4.240034) (xy 209.345863 -4.278256)
			(xy 209.265904 -4.309232) (xy 209.183428 -4.332699) (xy 209.099138 -4.348455) (xy 209.013755 -4.356367)
			(xy 208.928005 -4.356367) (xy 208.842622 -4.348455) (xy 208.758332 -4.332699) (xy 208.675856 -4.309232)
			(xy 208.595897 -4.278256) (xy 208.519137 -4.240034) (xy 208.446231 -4.194893) (xy 208.377802 -4.143217)
			(xy 208.314432 -4.085448) (xy 208.256663 -4.022078) (xy 208.204987 -3.953649) (xy 208.159846 -3.880743)
			(xy 208.121624 -3.803983) (xy 208.090648 -3.724024) (xy 208.067181 -3.641548) (xy 208.051425 -3.557258)
			(xy 208.043513 -3.471875) (xy 197.075741 -3.471875) (xy 197.091928 -3.518134) (xy 197.13088 -3.653342)
			(xy 197.16219 -3.790521) (xy 197.185759 -3.929239) (xy 197.201513 -4.069061) (xy 197.209403 -4.209547)
			(xy 197.209918 -4.2799) (xy 197.209918 -6.011875) (xy 208.043513 -6.011875) (xy 208.043513 -5.926125)
			(xy 208.051425 -5.840742) (xy 208.067181 -5.756452) (xy 208.090648 -5.673976) (xy 208.121624 -5.594017)
			(xy 208.159846 -5.517257) (xy 208.204987 -5.444351) (xy 208.256663 -5.375922) (xy 208.314432 -5.312552)
			(xy 208.377802 -5.254783) (xy 208.446231 -5.203107) (xy 208.519137 -5.157966) (xy 208.595897 -5.119744)
			(xy 208.675856 -5.088768) (xy 208.758332 -5.065301) (xy 208.842622 -5.049545) (xy 208.928005 -5.041633)
			(xy 209.013755 -5.041633) (xy 209.099138 -5.049545) (xy 209.183428 -5.065301) (xy 209.265904 -5.088768)
			(xy 209.345863 -5.119744) (xy 209.368066 -5.1308) (xy 212.978492 -5.1308) (xy 212.978492 -4.2672)
			(xy 212.978978 -4.239931) (xy 212.98674 -4.185947) (xy 213.002105 -4.133617) (xy 213.024762 -4.084007)
			(xy 213.054248 -4.038126) (xy 213.089963 -3.996909) (xy 213.13118 -3.961194) (xy 213.177061 -3.931708)
			(xy 213.226671 -3.909051) (xy 213.279001 -3.893686) (xy 213.332985 -3.885924) (xy 213.387523 -3.885924)
			(xy 213.441507 -3.893686) (xy 213.493837 -3.909051) (xy 213.543447 -3.931708) (xy 213.589328 -3.961194)
			(xy 213.630545 -3.996909) (xy 213.66626 -4.038126) (xy 213.695746 -4.084007) (xy 213.718403 -4.133617)
			(xy 213.733768 -4.185947) (xy 213.74153 -4.239931) (xy 213.742016 -4.2672) (xy 213.742016 -5.1308)
			(xy 213.74153 -5.158069) (xy 213.733768 -5.212053) (xy 213.718403 -5.264383) (xy 213.695746 -5.313993)
			(xy 213.66626 -5.359874) (xy 213.630545 -5.401091) (xy 213.589328 -5.436806) (xy 213.543447 -5.466292)
			(xy 213.493837 -5.488949) (xy 213.441507 -5.504314) (xy 213.387523 -5.512076) (xy 213.332985 -5.512076)
			(xy 213.279001 -5.504314) (xy 213.226671 -5.488949) (xy 213.177061 -5.466292) (xy 213.13118 -5.436806)
			(xy 213.089963 -5.401091) (xy 213.054248 -5.359874) (xy 213.024762 -5.313993) (xy 213.002105 -5.264383)
			(xy 212.98674 -5.212053) (xy 212.978978 -5.158069) (xy 212.978492 -5.1308) (xy 209.368066 -5.1308)
			(xy 209.422623 -5.157966) (xy 209.495529 -5.203107) (xy 209.563958 -5.254783) (xy 209.627328 -5.312552)
			(xy 209.685097 -5.375922) (xy 209.736773 -5.444351) (xy 209.781914 -5.517257) (xy 209.820136 -5.594017)
			(xy 209.851112 -5.673976) (xy 209.874579 -5.756452) (xy 209.890335 -5.840742) (xy 209.898247 -5.926125)
			(xy 209.898742 -5.969) (xy 209.898247 -6.011875) (xy 214.393513 -6.011875) (xy 214.393513 -5.926125)
			(xy 214.401425 -5.840742) (xy 214.417181 -5.756452) (xy 214.440648 -5.673976) (xy 214.471624 -5.594017)
			(xy 214.509846 -5.517257) (xy 214.554987 -5.444351) (xy 214.606663 -5.375922) (xy 214.664432 -5.312552)
			(xy 214.727802 -5.254783) (xy 214.796231 -5.203107) (xy 214.869137 -5.157966) (xy 214.945897 -5.119744)
			(xy 215.025856 -5.088768) (xy 215.108332 -5.065301) (xy 215.192622 -5.049545) (xy 215.278005 -5.041633)
			(xy 215.363755 -5.041633) (xy 215.449138 -5.049545) (xy 215.533428 -5.065301) (xy 215.615904 -5.088768)
			(xy 215.695863 -5.119744) (xy 215.772623 -5.157966) (xy 215.845529 -5.203107) (xy 215.913958 -5.254783)
			(xy 215.977328 -5.312552) (xy 216.035097 -5.375922) (xy 216.086773 -5.444351) (xy 216.131914 -5.517257)
			(xy 216.170136 -5.594017) (xy 216.201112 -5.673976) (xy 216.224579 -5.756452) (xy 216.240335 -5.840742)
			(xy 216.248247 -5.926125) (xy 216.248742 -5.969) (xy 216.248247 -6.011875) (xy 246.260353 -6.011875)
			(xy 246.260353 -5.926125) (xy 246.268265 -5.840742) (xy 246.284021 -5.756452) (xy 246.307488 -5.673976)
			(xy 246.338464 -5.594017) (xy 246.376686 -5.517257) (xy 246.421827 -5.444351) (xy 246.473503 -5.375922)
			(xy 246.531272 -5.312552) (xy 246.594642 -5.254783) (xy 246.663071 -5.203107) (xy 246.735977 -5.157966)
			(xy 246.812737 -5.119744) (xy 246.892696 -5.088768) (xy 246.975172 -5.065301) (xy 247.059462 -5.049545)
			(xy 247.144845 -5.041633) (xy 247.230595 -5.041633) (xy 247.315978 -5.049545) (xy 247.400268 -5.065301)
			(xy 247.482744 -5.088768) (xy 247.562703 -5.119744) (xy 247.584906 -5.1308) (xy 248.766584 -5.1308)
			(xy 248.766584 -4.2672) (xy 248.76707 -4.239931) (xy 248.774832 -4.185947) (xy 248.790197 -4.133617)
			(xy 248.812854 -4.084007) (xy 248.84234 -4.038126) (xy 248.878055 -3.996909) (xy 248.919272 -3.961194)
			(xy 248.965153 -3.931708) (xy 249.014763 -3.909051) (xy 249.067093 -3.893686) (xy 249.121077 -3.885924)
			(xy 249.175615 -3.885924) (xy 249.229599 -3.893686) (xy 249.281929 -3.909051) (xy 249.331539 -3.931708)
			(xy 249.37742 -3.961194) (xy 249.418637 -3.996909) (xy 249.454352 -4.038126) (xy 249.483838 -4.084007)
			(xy 249.506495 -4.133617) (xy 249.52186 -4.185947) (xy 249.529622 -4.239931) (xy 249.530108 -4.2672)
			(xy 249.530108 -5.1308) (xy 249.529622 -5.158069) (xy 249.52186 -5.212053) (xy 249.506495 -5.264383)
			(xy 249.483838 -5.313993) (xy 249.454352 -5.359874) (xy 249.418637 -5.401091) (xy 249.37742 -5.436806)
			(xy 249.331539 -5.466292) (xy 249.281929 -5.488949) (xy 249.229599 -5.504314) (xy 249.175615 -5.512076)
			(xy 249.121077 -5.512076) (xy 249.067093 -5.504314) (xy 249.014763 -5.488949) (xy 248.965153 -5.466292)
			(xy 248.919272 -5.436806) (xy 248.878055 -5.401091) (xy 248.84234 -5.359874) (xy 248.812854 -5.313993)
			(xy 248.790197 -5.264383) (xy 248.774832 -5.212053) (xy 248.76707 -5.158069) (xy 248.766584 -5.1308)
			(xy 247.584906 -5.1308) (xy 247.639463 -5.157966) (xy 247.712369 -5.203107) (xy 247.780798 -5.254783)
			(xy 247.844168 -5.312552) (xy 247.901937 -5.375922) (xy 247.953613 -5.444351) (xy 247.998754 -5.517257)
			(xy 248.036976 -5.594017) (xy 248.067952 -5.673976) (xy 248.091419 -5.756452) (xy 248.107175 -5.840742)
			(xy 248.115087 -5.926125) (xy 248.115582 -5.969) (xy 248.115087 -6.011875) (xy 252.610353 -6.011875)
			(xy 252.610353 -5.926125) (xy 252.618265 -5.840742) (xy 252.634021 -5.756452) (xy 252.657488 -5.673976)
			(xy 252.688464 -5.594017) (xy 252.726686 -5.517257) (xy 252.771827 -5.444351) (xy 252.823503 -5.375922)
			(xy 252.881272 -5.312552) (xy 252.944642 -5.254783) (xy 253.013071 -5.203107) (xy 253.085977 -5.157966)
			(xy 253.162737 -5.119744) (xy 253.242696 -5.088768) (xy 253.325172 -5.065301) (xy 253.409462 -5.049545)
			(xy 253.494845 -5.041633) (xy 253.580595 -5.041633) (xy 253.665978 -5.049545) (xy 253.750268 -5.065301)
			(xy 253.832744 -5.088768) (xy 253.912703 -5.119744) (xy 253.989463 -5.157966) (xy 254.062369 -5.203107)
			(xy 254.130798 -5.254783) (xy 254.194168 -5.312552) (xy 254.251937 -5.375922) (xy 254.303613 -5.444351)
			(xy 254.348754 -5.517257) (xy 254.386976 -5.594017) (xy 254.417952 -5.673976) (xy 254.441419 -5.756452)
			(xy 254.457175 -5.840742) (xy 254.465087 -5.926125) (xy 254.465582 -5.969) (xy 254.465119 -6.009081)
			(xy 256.921241 -6.009081) (xy 256.921241 -5.923331) (xy 256.929153 -5.837948) (xy 256.944909 -5.753658)
			(xy 256.968376 -5.671182) (xy 256.999352 -5.591223) (xy 257.037574 -5.514463) (xy 257.082715 -5.441557)
			(xy 257.134391 -5.373128) (xy 257.19216 -5.309758) (xy 257.25553 -5.251989) (xy 257.323959 -5.200313)
			(xy 257.396865 -5.155172) (xy 257.473625 -5.11695) (xy 257.553584 -5.085974) (xy 257.63606 -5.062507)
			(xy 257.72035 -5.046751) (xy 257.805733 -5.038839) (xy 257.891483 -5.038839) (xy 257.976866 -5.046751)
			(xy 258.061156 -5.062507) (xy 258.143632 -5.085974) (xy 258.223591 -5.11695) (xy 258.300351 -5.155172)
			(xy 258.373257 -5.200313) (xy 258.441686 -5.251989) (xy 258.505056 -5.309758) (xy 258.562825 -5.373128)
			(xy 258.614501 -5.441557) (xy 258.659642 -5.514463) (xy 258.697864 -5.591223) (xy 258.72884 -5.671182)
			(xy 258.752307 -5.753658) (xy 258.768063 -5.837948) (xy 258.775975 -5.923331) (xy 258.77647 -5.966206)
			(xy 258.775975 -6.009081) (xy 263.271241 -6.009081) (xy 263.271241 -5.923331) (xy 263.279153 -5.837948)
			(xy 263.294909 -5.753658) (xy 263.318376 -5.671182) (xy 263.349352 -5.591223) (xy 263.387574 -5.514463)
			(xy 263.432715 -5.441557) (xy 263.484391 -5.373128) (xy 263.54216 -5.309758) (xy 263.60553 -5.251989)
			(xy 263.673959 -5.200313) (xy 263.746865 -5.155172) (xy 263.823625 -5.11695) (xy 263.903584 -5.085974)
			(xy 263.98606 -5.062507) (xy 264.07035 -5.046751) (xy 264.155733 -5.038839) (xy 264.241483 -5.038839)
			(xy 264.326866 -5.046751) (xy 264.411156 -5.062507) (xy 264.493632 -5.085974) (xy 264.573591 -5.11695)
			(xy 264.650351 -5.155172) (xy 264.723257 -5.200313) (xy 264.791686 -5.251989) (xy 264.855056 -5.309758)
			(xy 264.912825 -5.373128) (xy 264.964501 -5.441557) (xy 265.009642 -5.514463) (xy 265.047864 -5.591223)
			(xy 265.07884 -5.671182) (xy 265.102307 -5.753658) (xy 265.118063 -5.837948) (xy 265.125975 -5.923331)
			(xy 265.12647 -5.966206) (xy 265.125975 -6.009081) (xy 324.845921 -6.009081) (xy 324.845921 -5.923331)
			(xy 324.853833 -5.837948) (xy 324.869589 -5.753658) (xy 324.893056 -5.671182) (xy 324.924032 -5.591223)
			(xy 324.962254 -5.514463) (xy 325.007395 -5.441557) (xy 325.059071 -5.373128) (xy 325.11684 -5.309758)
			(xy 325.18021 -5.251989) (xy 325.248639 -5.200313) (xy 325.321545 -5.155172) (xy 325.398305 -5.11695)
			(xy 325.478264 -5.085974) (xy 325.56074 -5.062507) (xy 325.64503 -5.046751) (xy 325.730413 -5.038839)
			(xy 325.816163 -5.038839) (xy 325.901546 -5.046751) (xy 325.985836 -5.062507) (xy 326.068312 -5.085974)
			(xy 326.148271 -5.11695) (xy 326.225031 -5.155172) (xy 326.297937 -5.200313) (xy 326.366366 -5.251989)
			(xy 326.429736 -5.309758) (xy 326.487505 -5.373128) (xy 326.539181 -5.441557) (xy 326.584322 -5.514463)
			(xy 326.622544 -5.591223) (xy 326.65352 -5.671182) (xy 326.676987 -5.753658) (xy 326.692743 -5.837948)
			(xy 326.700655 -5.923331) (xy 326.70115 -5.966206) (xy 326.700655 -6.009081) (xy 331.195921 -6.009081)
			(xy 331.195921 -5.923331) (xy 331.203833 -5.837948) (xy 331.219589 -5.753658) (xy 331.243056 -5.671182)
			(xy 331.274032 -5.591223) (xy 331.312254 -5.514463) (xy 331.357395 -5.441557) (xy 331.409071 -5.373128)
			(xy 331.46684 -5.309758) (xy 331.53021 -5.251989) (xy 331.598639 -5.200313) (xy 331.671545 -5.155172)
			(xy 331.748305 -5.11695) (xy 331.828264 -5.085974) (xy 331.91074 -5.062507) (xy 331.99503 -5.046751)
			(xy 332.080413 -5.038839) (xy 332.166163 -5.038839) (xy 332.251546 -5.046751) (xy 332.335836 -5.062507)
			(xy 332.418312 -5.085974) (xy 332.498271 -5.11695) (xy 332.575031 -5.155172) (xy 332.647937 -5.200313)
			(xy 332.716366 -5.251989) (xy 332.779736 -5.309758) (xy 332.837505 -5.373128) (xy 332.889181 -5.441557)
			(xy 332.934322 -5.514463) (xy 332.972544 -5.591223) (xy 333.00352 -5.671182) (xy 333.026987 -5.753658)
			(xy 333.042743 -5.837948) (xy 333.050655 -5.923331) (xy 333.05115 -5.966206) (xy 333.050655 -6.009081)
			(xy 335.488267 -6.009081) (xy 335.488267 -5.923331) (xy 335.496179 -5.837948) (xy 335.511935 -5.753658)
			(xy 335.535402 -5.671182) (xy 335.566378 -5.591223) (xy 335.6046 -5.514463) (xy 335.649741 -5.441557)
			(xy 335.701417 -5.373128) (xy 335.759186 -5.309758) (xy 335.822556 -5.251989) (xy 335.890985 -5.200313)
			(xy 335.963891 -5.155172) (xy 336.040651 -5.11695) (xy 336.12061 -5.085974) (xy 336.203086 -5.062507)
			(xy 336.287376 -5.046751) (xy 336.372759 -5.038839) (xy 336.458509 -5.038839) (xy 336.543892 -5.046751)
			(xy 336.628182 -5.062507) (xy 336.710658 -5.085974) (xy 336.790617 -5.11695) (xy 336.867377 -5.155172)
			(xy 336.940283 -5.200313) (xy 337.008712 -5.251989) (xy 337.072082 -5.309758) (xy 337.129851 -5.373128)
			(xy 337.181527 -5.441557) (xy 337.226668 -5.514463) (xy 337.26489 -5.591223) (xy 337.295866 -5.671182)
			(xy 337.319333 -5.753658) (xy 337.335089 -5.837948) (xy 337.343001 -5.923331) (xy 337.343496 -5.966206)
			(xy 337.343001 -6.009081) (xy 341.838267 -6.009081) (xy 341.838267 -5.923331) (xy 341.846179 -5.837948)
			(xy 341.861935 -5.753658) (xy 341.885402 -5.671182) (xy 341.916378 -5.591223) (xy 341.9546 -5.514463)
			(xy 341.999741 -5.441557) (xy 342.051417 -5.373128) (xy 342.109186 -5.309758) (xy 342.172556 -5.251989)
			(xy 342.240985 -5.200313) (xy 342.313891 -5.155172) (xy 342.390651 -5.11695) (xy 342.47061 -5.085974)
			(xy 342.553086 -5.062507) (xy 342.637376 -5.046751) (xy 342.722759 -5.038839) (xy 342.808509 -5.038839)
			(xy 342.893892 -5.046751) (xy 342.978182 -5.062507) (xy 343.060658 -5.085974) (xy 343.140617 -5.11695)
			(xy 343.217377 -5.155172) (xy 343.290283 -5.200313) (xy 343.358712 -5.251989) (xy 343.422082 -5.309758)
			(xy 343.479851 -5.373128) (xy 343.531527 -5.441557) (xy 343.576668 -5.514463) (xy 343.61489 -5.591223)
			(xy 343.645866 -5.671182) (xy 343.669333 -5.753658) (xy 343.685089 -5.837948) (xy 343.693001 -5.923331)
			(xy 343.693496 -5.966206) (xy 343.693001 -6.009081) (xy 373.705107 -6.009081) (xy 373.705107 -5.923331)
			(xy 373.713019 -5.837948) (xy 373.728775 -5.753658) (xy 373.752242 -5.671182) (xy 373.783218 -5.591223)
			(xy 373.82144 -5.514463) (xy 373.866581 -5.441557) (xy 373.918257 -5.373128) (xy 373.976026 -5.309758)
			(xy 374.039396 -5.251989) (xy 374.107825 -5.200313) (xy 374.180731 -5.155172) (xy 374.257491 -5.11695)
			(xy 374.33745 -5.085974) (xy 374.419926 -5.062507) (xy 374.504216 -5.046751) (xy 374.589599 -5.038839)
			(xy 374.675349 -5.038839) (xy 374.760732 -5.046751) (xy 374.845022 -5.062507) (xy 374.927498 -5.085974)
			(xy 375.007457 -5.11695) (xy 375.084217 -5.155172) (xy 375.157123 -5.200313) (xy 375.225552 -5.251989)
			(xy 375.288922 -5.309758) (xy 375.346691 -5.373128) (xy 375.398367 -5.441557) (xy 375.443508 -5.514463)
			(xy 375.48173 -5.591223) (xy 375.512706 -5.671182) (xy 375.536173 -5.753658) (xy 375.551929 -5.837948)
			(xy 375.559841 -5.923331) (xy 375.560336 -5.966206) (xy 375.559841 -6.009081) (xy 380.055107 -6.009081)
			(xy 380.055107 -5.923331) (xy 380.063019 -5.837948) (xy 380.078775 -5.753658) (xy 380.102242 -5.671182)
			(xy 380.133218 -5.591223) (xy 380.17144 -5.514463) (xy 380.216581 -5.441557) (xy 380.268257 -5.373128)
			(xy 380.326026 -5.309758) (xy 380.389396 -5.251989) (xy 380.457825 -5.200313) (xy 380.530731 -5.155172)
			(xy 380.607491 -5.11695) (xy 380.68745 -5.085974) (xy 380.769926 -5.062507) (xy 380.854216 -5.046751)
			(xy 380.939599 -5.038839) (xy 381.025349 -5.038839) (xy 381.110732 -5.046751) (xy 381.195022 -5.062507)
			(xy 381.277498 -5.085974) (xy 381.357457 -5.11695) (xy 381.434217 -5.155172) (xy 381.507123 -5.200313)
			(xy 381.575552 -5.251989) (xy 381.638922 -5.309758) (xy 381.696691 -5.373128) (xy 381.748367 -5.441557)
			(xy 381.793508 -5.514463) (xy 381.83173 -5.591223) (xy 381.862706 -5.671182) (xy 381.886173 -5.753658)
			(xy 381.901929 -5.837948) (xy 381.909841 -5.923331) (xy 381.910336 -5.966206) (xy 381.909841 -6.009081)
			(xy 381.901929 -6.094464) (xy 381.886173 -6.178754) (xy 381.862706 -6.26123) (xy 381.83173 -6.341189)
			(xy 381.793508 -6.417949) (xy 381.748367 -6.490855) (xy 381.696691 -6.559284) (xy 381.638922 -6.622654)
			(xy 381.575552 -6.680423) (xy 381.507123 -6.732099) (xy 381.434217 -6.77724) (xy 381.357457 -6.815462)
			(xy 381.277498 -6.846438) (xy 381.195022 -6.869905) (xy 381.110732 -6.885661) (xy 381.025349 -6.893573)
			(xy 380.939599 -6.893573) (xy 380.854216 -6.885661) (xy 380.769926 -6.869905) (xy 380.68745 -6.846438)
			(xy 380.607491 -6.815462) (xy 380.530731 -6.77724) (xy 380.457825 -6.732099) (xy 380.389396 -6.680423)
			(xy 380.326026 -6.622654) (xy 380.268257 -6.559284) (xy 380.216581 -6.490855) (xy 380.17144 -6.417949)
			(xy 380.133218 -6.341189) (xy 380.102242 -6.26123) (xy 380.078775 -6.178754) (xy 380.063019 -6.094464)
			(xy 380.055107 -6.009081) (xy 375.559841 -6.009081) (xy 375.551929 -6.094464) (xy 375.536173 -6.178754)
			(xy 375.512706 -6.26123) (xy 375.48173 -6.341189) (xy 375.443508 -6.417949) (xy 375.398367 -6.490855)
			(xy 375.346691 -6.559284) (xy 375.288922 -6.622654) (xy 375.225552 -6.680423) (xy 375.157123 -6.732099)
			(xy 375.084217 -6.77724) (xy 375.007457 -6.815462) (xy 374.927498 -6.846438) (xy 374.845022 -6.869905)
			(xy 374.760732 -6.885661) (xy 374.675349 -6.893573) (xy 374.589599 -6.893573) (xy 374.504216 -6.885661)
			(xy 374.419926 -6.869905) (xy 374.33745 -6.846438) (xy 374.257491 -6.815462) (xy 374.180731 -6.77724)
			(xy 374.107825 -6.732099) (xy 374.039396 -6.680423) (xy 373.976026 -6.622654) (xy 373.918257 -6.559284)
			(xy 373.866581 -6.490855) (xy 373.82144 -6.417949) (xy 373.783218 -6.341189) (xy 373.752242 -6.26123)
			(xy 373.728775 -6.178754) (xy 373.713019 -6.094464) (xy 373.705107 -6.009081) (xy 343.693001 -6.009081)
			(xy 343.685089 -6.094464) (xy 343.669333 -6.178754) (xy 343.645866 -6.26123) (xy 343.61489 -6.341189)
			(xy 343.576668 -6.417949) (xy 343.531527 -6.490855) (xy 343.479851 -6.559284) (xy 343.422082 -6.622654)
			(xy 343.358712 -6.680423) (xy 343.290283 -6.732099) (xy 343.217377 -6.77724) (xy 343.140617 -6.815462)
			(xy 343.060658 -6.846438) (xy 342.978182 -6.869905) (xy 342.893892 -6.885661) (xy 342.808509 -6.893573)
			(xy 342.722759 -6.893573) (xy 342.637376 -6.885661) (xy 342.553086 -6.869905) (xy 342.47061 -6.846438)
			(xy 342.390651 -6.815462) (xy 342.313891 -6.77724) (xy 342.240985 -6.732099) (xy 342.172556 -6.680423)
			(xy 342.109186 -6.622654) (xy 342.051417 -6.559284) (xy 341.999741 -6.490855) (xy 341.9546 -6.417949)
			(xy 341.916378 -6.341189) (xy 341.885402 -6.26123) (xy 341.861935 -6.178754) (xy 341.846179 -6.094464)
			(xy 341.838267 -6.009081) (xy 337.343001 -6.009081) (xy 337.335089 -6.094464) (xy 337.319333 -6.178754)
			(xy 337.295866 -6.26123) (xy 337.26489 -6.341189) (xy 337.226668 -6.417949) (xy 337.181527 -6.490855)
			(xy 337.129851 -6.559284) (xy 337.072082 -6.622654) (xy 337.008712 -6.680423) (xy 336.940283 -6.732099)
			(xy 336.867377 -6.77724) (xy 336.790617 -6.815462) (xy 336.710658 -6.846438) (xy 336.628182 -6.869905)
			(xy 336.543892 -6.885661) (xy 336.458509 -6.893573) (xy 336.372759 -6.893573) (xy 336.287376 -6.885661)
			(xy 336.203086 -6.869905) (xy 336.12061 -6.846438) (xy 336.040651 -6.815462) (xy 335.963891 -6.77724)
			(xy 335.890985 -6.732099) (xy 335.822556 -6.680423) (xy 335.759186 -6.622654) (xy 335.701417 -6.559284)
			(xy 335.649741 -6.490855) (xy 335.6046 -6.417949) (xy 335.566378 -6.341189) (xy 335.535402 -6.26123)
			(xy 335.511935 -6.178754) (xy 335.496179 -6.094464) (xy 335.488267 -6.009081) (xy 333.050655 -6.009081)
			(xy 333.042743 -6.094464) (xy 333.026987 -6.178754) (xy 333.00352 -6.26123) (xy 332.972544 -6.341189)
			(xy 332.934322 -6.417949) (xy 332.889181 -6.490855) (xy 332.837505 -6.559284) (xy 332.779736 -6.622654)
			(xy 332.716366 -6.680423) (xy 332.647937 -6.732099) (xy 332.575031 -6.77724) (xy 332.498271 -6.815462)
			(xy 332.418312 -6.846438) (xy 332.335836 -6.869905) (xy 332.251546 -6.885661) (xy 332.166163 -6.893573)
			(xy 332.080413 -6.893573) (xy 331.99503 -6.885661) (xy 331.91074 -6.869905) (xy 331.828264 -6.846438)
			(xy 331.748305 -6.815462) (xy 331.671545 -6.77724) (xy 331.598639 -6.732099) (xy 331.53021 -6.680423)
			(xy 331.46684 -6.622654) (xy 331.409071 -6.559284) (xy 331.357395 -6.490855) (xy 331.312254 -6.417949)
			(xy 331.274032 -6.341189) (xy 331.243056 -6.26123) (xy 331.219589 -6.178754) (xy 331.203833 -6.094464)
			(xy 331.195921 -6.009081) (xy 326.700655 -6.009081) (xy 326.692743 -6.094464) (xy 326.676987 -6.178754)
			(xy 326.65352 -6.26123) (xy 326.622544 -6.341189) (xy 326.584322 -6.417949) (xy 326.539181 -6.490855)
			(xy 326.487505 -6.559284) (xy 326.429736 -6.622654) (xy 326.366366 -6.680423) (xy 326.297937 -6.732099)
			(xy 326.225031 -6.77724) (xy 326.148271 -6.815462) (xy 326.068312 -6.846438) (xy 325.985836 -6.869905)
			(xy 325.901546 -6.885661) (xy 325.816163 -6.893573) (xy 325.730413 -6.893573) (xy 325.64503 -6.885661)
			(xy 325.56074 -6.869905) (xy 325.478264 -6.846438) (xy 325.398305 -6.815462) (xy 325.321545 -6.77724)
			(xy 325.248639 -6.732099) (xy 325.18021 -6.680423) (xy 325.11684 -6.622654) (xy 325.059071 -6.559284)
			(xy 325.007395 -6.490855) (xy 324.962254 -6.417949) (xy 324.924032 -6.341189) (xy 324.893056 -6.26123)
			(xy 324.869589 -6.178754) (xy 324.853833 -6.094464) (xy 324.845921 -6.009081) (xy 265.125975 -6.009081)
			(xy 265.118063 -6.094464) (xy 265.102307 -6.178754) (xy 265.07884 -6.26123) (xy 265.047864 -6.341189)
			(xy 265.009642 -6.417949) (xy 264.964501 -6.490855) (xy 264.912825 -6.559284) (xy 264.855056 -6.622654)
			(xy 264.791686 -6.680423) (xy 264.723257 -6.732099) (xy 264.650351 -6.77724) (xy 264.573591 -6.815462)
			(xy 264.493632 -6.846438) (xy 264.411156 -6.869905) (xy 264.326866 -6.885661) (xy 264.241483 -6.893573)
			(xy 264.155733 -6.893573) (xy 264.07035 -6.885661) (xy 263.98606 -6.869905) (xy 263.903584 -6.846438)
			(xy 263.823625 -6.815462) (xy 263.746865 -6.77724) (xy 263.673959 -6.732099) (xy 263.60553 -6.680423)
			(xy 263.54216 -6.622654) (xy 263.484391 -6.559284) (xy 263.432715 -6.490855) (xy 263.387574 -6.417949)
			(xy 263.349352 -6.341189) (xy 263.318376 -6.26123) (xy 263.294909 -6.178754) (xy 263.279153 -6.094464)
			(xy 263.271241 -6.009081) (xy 258.775975 -6.009081) (xy 258.768063 -6.094464) (xy 258.752307 -6.178754)
			(xy 258.72884 -6.26123) (xy 258.697864 -6.341189) (xy 258.659642 -6.417949) (xy 258.614501 -6.490855)
			(xy 258.562825 -6.559284) (xy 258.505056 -6.622654) (xy 258.441686 -6.680423) (xy 258.373257 -6.732099)
			(xy 258.300351 -6.77724) (xy 258.223591 -6.815462) (xy 258.143632 -6.846438) (xy 258.061156 -6.869905)
			(xy 257.976866 -6.885661) (xy 257.891483 -6.893573) (xy 257.805733 -6.893573) (xy 257.72035 -6.885661)
			(xy 257.63606 -6.869905) (xy 257.553584 -6.846438) (xy 257.473625 -6.815462) (xy 257.396865 -6.77724)
			(xy 257.323959 -6.732099) (xy 257.25553 -6.680423) (xy 257.19216 -6.622654) (xy 257.134391 -6.559284)
			(xy 257.082715 -6.490855) (xy 257.037574 -6.417949) (xy 256.999352 -6.341189) (xy 256.968376 -6.26123)
			(xy 256.944909 -6.178754) (xy 256.929153 -6.094464) (xy 256.921241 -6.009081) (xy 254.465119 -6.009081)
			(xy 254.465087 -6.011875) (xy 254.457175 -6.097258) (xy 254.441419 -6.181548) (xy 254.417952 -6.264024)
			(xy 254.386976 -6.343983) (xy 254.348754 -6.420743) (xy 254.303613 -6.493649) (xy 254.251937 -6.562078)
			(xy 254.194168 -6.625448) (xy 254.130798 -6.683217) (xy 254.062369 -6.734893) (xy 253.989463 -6.780034)
			(xy 253.912703 -6.818256) (xy 253.832744 -6.849232) (xy 253.750268 -6.872699) (xy 253.665978 -6.888455)
			(xy 253.580595 -6.896367) (xy 253.494845 -6.896367) (xy 253.409462 -6.888455) (xy 253.325172 -6.872699)
			(xy 253.242696 -6.849232) (xy 253.162737 -6.818256) (xy 253.085977 -6.780034) (xy 253.013071 -6.734893)
			(xy 252.944642 -6.683217) (xy 252.881272 -6.625448) (xy 252.823503 -6.562078) (xy 252.771827 -6.493649)
			(xy 252.726686 -6.420743) (xy 252.688464 -6.343983) (xy 252.657488 -6.264024) (xy 252.634021 -6.181548)
			(xy 252.618265 -6.097258) (xy 252.610353 -6.011875) (xy 248.115087 -6.011875) (xy 248.107175 -6.097258)
			(xy 248.091419 -6.181548) (xy 248.067952 -6.264024) (xy 248.036976 -6.343983) (xy 247.998754 -6.420743)
			(xy 247.953613 -6.493649) (xy 247.901937 -6.562078) (xy 247.844168 -6.625448) (xy 247.780798 -6.683217)
			(xy 247.712369 -6.734893) (xy 247.639463 -6.780034) (xy 247.562703 -6.818256) (xy 247.482744 -6.849232)
			(xy 247.400268 -6.872699) (xy 247.315978 -6.888455) (xy 247.230595 -6.896367) (xy 247.144845 -6.896367)
			(xy 247.059462 -6.888455) (xy 246.975172 -6.872699) (xy 246.892696 -6.849232) (xy 246.812737 -6.818256)
			(xy 246.735977 -6.780034) (xy 246.663071 -6.734893) (xy 246.594642 -6.683217) (xy 246.531272 -6.625448)
			(xy 246.473503 -6.562078) (xy 246.421827 -6.493649) (xy 246.376686 -6.420743) (xy 246.338464 -6.343983)
			(xy 246.307488 -6.264024) (xy 246.284021 -6.181548) (xy 246.268265 -6.097258) (xy 246.260353 -6.011875)
			(xy 216.248247 -6.011875) (xy 216.240335 -6.097258) (xy 216.224579 -6.181548) (xy 216.201112 -6.264024)
			(xy 216.170136 -6.343983) (xy 216.131914 -6.420743) (xy 216.086773 -6.493649) (xy 216.035097 -6.562078)
			(xy 215.977328 -6.625448) (xy 215.913958 -6.683217) (xy 215.845529 -6.734893) (xy 215.772623 -6.780034)
			(xy 215.695863 -6.818256) (xy 215.615904 -6.849232) (xy 215.533428 -6.872699) (xy 215.449138 -6.888455)
			(xy 215.363755 -6.896367) (xy 215.278005 -6.896367) (xy 215.192622 -6.888455) (xy 215.108332 -6.872699)
			(xy 215.025856 -6.849232) (xy 214.945897 -6.818256) (xy 214.869137 -6.780034) (xy 214.796231 -6.734893)
			(xy 214.727802 -6.683217) (xy 214.664432 -6.625448) (xy 214.606663 -6.562078) (xy 214.554987 -6.493649)
			(xy 214.509846 -6.420743) (xy 214.471624 -6.343983) (xy 214.440648 -6.264024) (xy 214.417181 -6.181548)
			(xy 214.401425 -6.097258) (xy 214.393513 -6.011875) (xy 209.898247 -6.011875) (xy 209.890335 -6.097258)
			(xy 209.874579 -6.181548) (xy 209.851112 -6.264024) (xy 209.820136 -6.343983) (xy 209.781914 -6.420743)
			(xy 209.736773 -6.493649) (xy 209.685097 -6.562078) (xy 209.627328 -6.625448) (xy 209.563958 -6.683217)
			(xy 209.495529 -6.734893) (xy 209.422623 -6.780034) (xy 209.345863 -6.818256) (xy 209.265904 -6.849232)
			(xy 209.183428 -6.872699) (xy 209.099138 -6.888455) (xy 209.013755 -6.896367) (xy 208.928005 -6.896367)
			(xy 208.842622 -6.888455) (xy 208.758332 -6.872699) (xy 208.675856 -6.849232) (xy 208.595897 -6.818256)
			(xy 208.519137 -6.780034) (xy 208.446231 -6.734893) (xy 208.377802 -6.683217) (xy 208.314432 -6.625448)
			(xy 208.256663 -6.562078) (xy 208.204987 -6.493649) (xy 208.159846 -6.420743) (xy 208.121624 -6.343983)
			(xy 208.090648 -6.264024) (xy 208.067181 -6.181548) (xy 208.051425 -6.097258) (xy 208.043513 -6.011875)
			(xy 197.209918 -6.011875) (xy 197.209918 -7.78002) (xy 197.21044 -7.835826) (xy 197.218783 -7.947127)
			(xy 197.235419 -8.057493) (xy 197.260257 -8.166307) (xy 197.293157 -8.27296) (xy 197.333935 -8.376857)
			(xy 197.382363 -8.477416) (xy 197.43817 -8.574075) (xy 197.501045 -8.666293) (xy 197.570635 -8.753555)
			(xy 197.646552 -8.835372) (xy 197.728371 -8.911287) (xy 197.815634 -8.980875) (xy 197.907854 -9.043748)
			(xy 198.004514 -9.099553) (xy 198.105074 -9.147979) (xy 198.208972 -9.188755) (xy 198.315626 -9.221652)
			(xy 198.424441 -9.246487) (xy 198.534807 -9.263121) (xy 198.646108 -9.271461) (xy 198.701914 -9.272016)
			(xy 223.300036 -9.272016) (xy 223.370389 -9.27251) (xy 223.510873 -9.280402) (xy 223.650694 -9.296158)
			(xy 223.789412 -9.319729) (xy 223.92659 -9.35104) (xy 224.061796 -9.389995) (xy 224.194606 -9.436468)
			(xy 224.3246 -9.490316) (xy 224.451371 -9.551367) (xy 224.57452 -9.619431) (xy 224.693658 -9.694292)
			(xy 224.808411 -9.775716) (xy 224.918419 -9.863446) (xy 225.023334 -9.957206) (xy 225.122827 -10.056701)
			(xy 225.216585 -10.161618) (xy 225.304313 -10.271627) (xy 225.385734 -10.386382) (xy 225.460594 -10.505522)
			(xy 225.528655 -10.628671) (xy 225.589704 -10.755444) (xy 225.643549 -10.885439) (xy 225.69002 -11.01825)
			(xy 225.728972 -11.153457) (xy 225.760281 -11.290635) (xy 225.783849 -11.429353) (xy 225.799602 -11.569174)
			(xy 225.807491 -11.709659) (xy 225.808032 -11.780012) (xy 225.808032 -31.197296) (xy 227.377752 -32.767016)
			(xy 254.645668 -32.767016)
		)
		(stroke
			(width 0)
			(type solid)
		)
		(fill yes)
		(layer "In7.Cu")
		(net "DELTA_L_GND_1")
	)
	(gr_poly
		(pts
			(xy 194.495928 -441.17006) (xy 194.49641 -441.126022) (xy 194.50409 -441.03828) (xy 194.519387 -440.951542)
			(xy 194.542185 -440.866466) (xy 194.572311 -440.783702) (xy 194.609536 -440.703878) (xy 194.653576 -440.627602)
			(xy 194.704095 -440.555454) (xy 194.760711 -440.487984) (xy 194.822991 -440.425704) (xy 194.890462 -440.369089)
			(xy 194.96261 -440.31857) (xy 195.038887 -440.274531) (xy 195.118711 -440.237308) (xy 195.201476 -440.207182)
			(xy 195.286551 -440.184385) (xy 195.37329 -440.169088) (xy 195.461032 -440.16141) (xy 195.50507 -440.160918)
			(xy 276.314916 -440.160918) (xy 276.358955 -440.161399) (xy 276.446699 -440.169077) (xy 276.533439 -440.184372)
			(xy 276.618516 -440.207169) (xy 276.701283 -440.237294) (xy 276.781109 -440.274518) (xy 276.857388 -440.318557)
			(xy 276.929538 -440.369076) (xy 276.99701 -440.425692) (xy 277.059292 -440.487972) (xy 277.115909 -440.555443)
			(xy 277.16643 -440.627592) (xy 277.210471 -440.703869) (xy 277.247697 -440.783695) (xy 277.277823 -440.866461)
			(xy 277.300622 -440.951538) (xy 277.31592 -441.038278) (xy 277.3236 -441.126021) (xy 277.324058 -441.17006)
			(xy 277.324058 -441.480956) (xy 463.300064 -441.480956) (xy 463.355834 -441.480449) (xy 463.467062 -441.472116)
			(xy 463.577357 -441.455494) (xy 463.686101 -441.430676) (xy 463.792686 -441.397801) (xy 463.896517 -441.357052)
			(xy 463.997011 -441.308658) (xy 464.093608 -441.252889) (xy 464.185768 -441.190057) (xy 464.272974 -441.120513)
			(xy 464.354739 -441.044647) (xy 464.430606 -440.962883) (xy 464.50015 -440.875677) (xy 464.562982 -440.783519)
			(xy 464.618752 -440.686922) (xy 464.667147 -440.586428) (xy 464.707897 -440.482598) (xy 464.740773 -440.376013)
			(xy 464.765592 -440.267269) (xy 464.782215 -440.156974) (xy 464.790548 -440.045746) (xy 464.791044 -439.989976)
			(xy 464.791044 -419.236652) (xy 464.79206 -419.236652) (xy 464.79206 -419.160198) (xy 464.791806 -419.158674)
			(xy 464.783625 -419.126333) (xy 464.774834 -419.060203) (xy 464.77428 -419.026848) (xy 464.774826 -418.994155)
			(xy 464.783231 -418.929312) (xy 464.791044 -418.897562) (xy 464.791044 -409.528264) (xy 464.791527 -409.457889)
			(xy 464.799416 -409.317359) (xy 464.815173 -409.177493) (xy 464.838748 -409.03873) (xy 464.870067 -408.901508)
			(xy 464.909031 -408.766258) (xy 464.955519 -408.633405) (xy 465.009383 -408.503369) (xy 465.070454 -408.376557)
			(xy 465.138539 -408.25337) (xy 465.213426 -408.134194) (xy 465.294877 -408.019405) (xy 465.382637 -407.909364)
			(xy 465.47643 -407.804418) (xy 465.525866 -407.754328) (xy 467.354412 -405.925782) (xy 467.391723 -405.887821)
			(xy 467.461438 -405.807375) (xy 467.525236 -405.722161) (xy 467.582791 -405.632611) (xy 467.633809 -405.539182)
			(xy 467.678031 -405.442352) (xy 467.715231 -405.342613) (xy 467.74522 -405.240474) (xy 467.767844 -405.136455)
			(xy 467.782988 -405.031087) (xy 467.790575 -404.924907) (xy 467.791038 -404.871682) (xy 467.791038 -82.82813)
			(xy 467.791541 -82.757757) (xy 467.799451 -82.617233) (xy 467.815226 -82.477373) (xy 467.838815 -82.338618)
			(xy 467.870145 -82.201402) (xy 467.909116 -82.066159) (xy 467.955608 -81.933313) (xy 468.009473 -81.803282)
			(xy 468.070541 -81.676474) (xy 468.138622 -81.553289) (xy 468.213501 -81.434114) (xy 468.294942 -81.319323)
			(xy 468.382689 -81.209278) (xy 468.476467 -81.104324) (xy 468.52586 -81.054194) (xy 470.854278 -78.725776)
			(xy 470.891589 -78.687815) (xy 470.961306 -78.60737) (xy 471.025105 -78.522156) (xy 471.082661 -78.432606)
			(xy 471.13368 -78.339178) (xy 471.177903 -78.242348) (xy 471.215103 -78.142608) (xy 471.245092 -78.040469)
			(xy 471.267716 -77.93645) (xy 471.28286 -77.831082) (xy 471.290447 -77.724901) (xy 471.290904 -77.671676)
			(xy 471.290904 -13.780008) (xy 471.290383 -13.724238) (xy 471.282048 -13.613011) (xy 471.265425 -13.502718)
			(xy 471.240606 -13.393975) (xy 471.20773 -13.287391) (xy 471.166981 -13.183562) (xy 471.118587 -13.083068)
			(xy 471.062818 -12.986472) (xy 470.999987 -12.894314) (xy 470.930444 -12.807108) (xy 470.854579 -12.725344)
			(xy 470.772816 -12.649477) (xy 470.685612 -12.579932) (xy 470.593455 -12.517099) (xy 470.49686 -12.461328)
			(xy 470.396367 -12.412932) (xy 470.292539 -12.372181) (xy 470.185956 -12.339303) (xy 470.077214 -12.314481)
			(xy 469.966921 -12.297855) (xy 469.855694 -12.289518) (xy 469.799924 -12.289028) (xy 464.613244 -12.289028)
			(xy 464.613244 -12.288012) (xy 464.272376 -12.288012) (xy 464.272376 -12.289028) (xy 458.20203 -12.289028)
			(xy 458.131647 -12.288544) (xy 457.991102 -12.280653) (xy 457.85122 -12.264894) (xy 457.712443 -12.241316)
			(xy 457.575205 -12.209994) (xy 457.43994 -12.171027) (xy 457.307072 -12.124536) (xy 457.177021 -12.070668)
			(xy 457.050194 -12.009593) (xy 456.926991 -11.941503) (xy 456.8078 -11.866612) (xy 456.692996 -11.785156)
			(xy 456.582939 -11.69739) (xy 456.477977 -11.603592) (xy 456.378439 -11.504056) (xy 456.284639 -11.399096)
			(xy 456.196872 -11.289041) (xy 456.115413 -11.174238) (xy 456.04052 -11.055048) (xy 455.972428 -10.931847)
			(xy 455.911351 -10.805021) (xy 455.857481 -10.674971) (xy 455.810987 -10.542104) (xy 455.772017 -10.406839)
			(xy 455.740693 -10.269603) (xy 455.717113 -10.130825) (xy 455.701351 -9.990944) (xy 455.693457 -9.850399)
			(xy 455.693018 -9.780016) (xy 455.693018 -0.999998) (xy 455.692493 -0.967851) (xy 455.684101 -0.904107)
			(xy 455.667461 -0.842004) (xy 455.642857 -0.782603) (xy 455.610712 -0.726922) (xy 455.571573 -0.675913)
			(xy 455.526112 -0.630449) (xy 455.475106 -0.591307) (xy 455.419427 -0.559158) (xy 455.360029 -0.53455)
			(xy 455.297926 -0.517906) (xy 455.234183 -0.50951) (xy 455.202036 -0.509016) (xy 388.601966 -0.509016)
			(xy 388.569821 -0.509544) (xy 388.506082 -0.517939) (xy 388.443984 -0.534582) (xy 388.384589 -0.559188)
			(xy 388.328914 -0.591335) (xy 388.277911 -0.630474) (xy 388.232453 -0.675936) (xy 388.193318 -0.726941)
			(xy 388.161174 -0.782618) (xy 388.136572 -0.842014) (xy 388.119933 -0.904114) (xy 388.111542 -0.967853)
			(xy 388.110984 -0.999998) (xy 388.110984 -5.169916) (xy 388.850131 -5.169916) (xy 388.854136 -5.082008)
			(xy 388.866119 -4.994828) (xy 388.885979 -4.909099) (xy 388.913554 -4.825531) (xy 388.948613 -4.744817)
			(xy 388.990866 -4.667625) (xy 389.039964 -4.594596) (xy 389.0955 -4.526334) (xy 389.157012 -4.463404)
			(xy 389.223993 -4.40633) (xy 389.295886 -4.355582) (xy 389.372095 -4.311582) (xy 389.45199 -4.274695)
			(xy 389.534909 -4.245226) (xy 389.620164 -4.223419) (xy 389.707048 -4.209455) (xy 389.794842 -4.203449)
			(xy 389.882819 -4.205453) (xy 389.970249 -4.215448) (xy 390.056408 -4.233352) (xy 390.140582 -4.259016)
			(xy 390.222073 -4.292229) (xy 390.300207 -4.332715) (xy 390.374335 -4.380137) (xy 390.443843 -4.434104)
			(xy 390.508157 -4.494169) (xy 390.566741 -4.559833) (xy 390.619112 -4.630552) (xy 390.664835 -4.70574)
			(xy 390.703532 -4.784775) (xy 390.734881 -4.867001) (xy 390.758623 -4.951737) (xy 390.763638 -4.978969)
			(xy 394.947631 -4.978969) (xy 394.947631 -4.924431) (xy 394.955393 -4.870448) (xy 394.970758 -4.81812)
			(xy 394.993414 -4.76851) (xy 395.0229 -4.72263) (xy 395.058614 -4.681413) (xy 395.099832 -4.645698)
			(xy 395.145712 -4.616213) (xy 395.195321 -4.593557) (xy 395.24765 -4.578193) (xy 395.301633 -4.570431)
			(xy 395.328902 -4.569968) (xy 396.192502 -4.569968) (xy 396.219773 -4.570395) (xy 396.273761 -4.578157)
			(xy 396.326094 -4.593524) (xy 396.375708 -4.616182) (xy 396.421593 -4.64567) (xy 396.462813 -4.681388)
			(xy 396.498531 -4.722609) (xy 396.528019 -4.768493) (xy 396.550677 -4.818107) (xy 396.566043 -4.870441)
			(xy 396.573806 -4.924429) (xy 396.573806 -4.978971) (xy 398.547532 -4.978971) (xy 398.547532 -4.924429)
			(xy 398.555294 -4.870443) (xy 398.570661 -4.818111) (xy 398.593321 -4.768498) (xy 398.62281 -4.722616)
			(xy 398.658529 -4.681398) (xy 398.699751 -4.645684) (xy 398.745637 -4.616199) (xy 398.795252 -4.593546)
			(xy 398.847586 -4.578185) (xy 398.901573 -4.570428) (xy 398.928844 -4.569968) (xy 399.792444 -4.569968)
			(xy 399.819713 -4.570398) (xy 399.873697 -4.578165) (xy 399.926025 -4.593535) (xy 399.975633 -4.616196)
			(xy 400.021512 -4.645685) (xy 400.062728 -4.681403) (xy 400.098441 -4.722623) (xy 400.127925 -4.768505)
			(xy 400.15058 -4.818116) (xy 400.165944 -4.870447) (xy 400.173706 -4.92443) (xy 400.173706 -4.978967)
			(xy 402.147554 -4.978967) (xy 402.147554 -4.924433) (xy 402.155315 -4.870455) (xy 402.170678 -4.818131)
			(xy 402.193332 -4.768526) (xy 402.222814 -4.722649) (xy 402.258525 -4.681435) (xy 402.299738 -4.645722)
			(xy 402.345613 -4.616239) (xy 402.395218 -4.593583) (xy 402.447542 -4.578218) (xy 402.501519 -4.570455)
			(xy 402.528786 -4.569968) (xy 403.392386 -4.569968) (xy 403.41966 -4.570371) (xy 403.473652 -4.578132)
			(xy 403.525991 -4.593498) (xy 403.57561 -4.616157) (xy 403.621499 -4.645646) (xy 403.662724 -4.681366)
			(xy 403.698445 -4.72259) (xy 403.727937 -4.768478) (xy 403.750597 -4.818096) (xy 403.765965 -4.870434)
			(xy 403.773728 -4.924426) (xy 403.773728 -4.978966) (xy 405.747754 -4.978966) (xy 405.747754 -4.924434)
			(xy 405.755515 -4.870456) (xy 405.770878 -4.818132) (xy 405.793531 -4.768527) (xy 405.823013 -4.72265)
			(xy 405.858724 -4.681436) (xy 405.899936 -4.645724) (xy 405.945811 -4.61624) (xy 405.995415 -4.593584)
			(xy 406.047738 -4.578219) (xy 406.101716 -4.570456) (xy 406.128982 -4.569968) (xy 406.992582 -4.569968)
			(xy 407.019856 -4.57037) (xy 407.073849 -4.578131) (xy 407.126188 -4.593497) (xy 407.175807 -4.616155)
			(xy 407.221697 -4.645645) (xy 407.262922 -4.681365) (xy 407.298644 -4.722589) (xy 407.328136 -4.768477)
			(xy 407.350797 -4.818095) (xy 407.366165 -4.870433) (xy 407.373928 -4.924426) (xy 407.373928 -4.978971)
			(xy 414.857632 -4.978971) (xy 414.857632 -4.924429) (xy 414.865394 -4.870442) (xy 414.880762 -4.81811)
			(xy 414.903421 -4.768498) (xy 414.93291 -4.722616) (xy 414.96863 -4.681397) (xy 415.009852 -4.645683)
			(xy 415.055738 -4.616199) (xy 415.105353 -4.593546) (xy 415.157687 -4.578184) (xy 415.211675 -4.570428)
			(xy 415.238946 -4.569968) (xy 416.102546 -4.569968) (xy 416.129815 -4.570398) (xy 416.183798 -4.578165)
			(xy 416.236126 -4.593536) (xy 416.285735 -4.616196) (xy 416.331613 -4.645686) (xy 416.372829 -4.681404)
			(xy 416.408542 -4.722624) (xy 416.438026 -4.768506) (xy 416.46068 -4.818117) (xy 416.476045 -4.870447)
			(xy 416.483806 -4.924431) (xy 416.483806 -4.978967) (xy 418.457654 -4.978967) (xy 418.457654 -4.924433)
			(xy 418.465415 -4.870455) (xy 418.480779 -4.818131) (xy 418.503432 -4.768525) (xy 418.532915 -4.722648)
			(xy 418.568626 -4.681434) (xy 418.609839 -4.645722) (xy 418.655715 -4.616238) (xy 418.705319 -4.593583)
			(xy 418.757643 -4.578218) (xy 418.811621 -4.570455) (xy 418.838888 -4.569968) (xy 419.702488 -4.569968)
			(xy 419.729762 -4.570371) (xy 419.783754 -4.578132) (xy 419.836092 -4.593499) (xy 419.885711 -4.616157)
			(xy 419.9316 -4.645647) (xy 419.972824 -4.681367) (xy 420.008546 -4.722591) (xy 420.038037 -4.768479)
			(xy 420.060697 -4.818096) (xy 420.076065 -4.870434) (xy 420.083828 -4.924426) (xy 420.083828 -4.978966)
			(xy 426.067754 -4.978966) (xy 426.067754 -4.924434) (xy 426.075515 -4.870456) (xy 426.090878 -4.818132)
			(xy 426.113531 -4.768527) (xy 426.143013 -4.72265) (xy 426.178724 -4.681436) (xy 426.219936 -4.645724)
			(xy 426.265811 -4.61624) (xy 426.315415 -4.593584) (xy 426.367738 -4.578219) (xy 426.421716 -4.570456)
			(xy 426.448982 -4.569968) (xy 427.312582 -4.569968) (xy 427.339856 -4.57037) (xy 427.393849 -4.578131)
			(xy 427.446188 -4.593497) (xy 427.495807 -4.616155) (xy 427.541697 -4.645645) (xy 427.582922 -4.681365)
			(xy 427.618644 -4.722589) (xy 427.648136 -4.768477) (xy 427.670797 -4.818095) (xy 427.686165 -4.870433)
			(xy 427.693928 -4.924426) (xy 427.693928 -4.97897) (xy 429.667631 -4.97897) (xy 429.667631 -4.92443)
			(xy 429.675394 -4.870445) (xy 429.69076 -4.818115) (xy 429.713417 -4.768504) (xy 429.742905 -4.722623)
			(xy 429.778622 -4.681405) (xy 429.819842 -4.645691) (xy 429.865725 -4.616206) (xy 429.915337 -4.593552)
			(xy 429.967669 -4.578189) (xy 430.021654 -4.57043) (xy 430.048924 -4.569968) (xy 430.912524 -4.569968)
			(xy 430.939794 -4.570396) (xy 430.99378 -4.578161) (xy 431.04611 -4.59353) (xy 431.095721 -4.616189)
			(xy 431.141603 -4.645678) (xy 431.182821 -4.681396) (xy 431.218536 -4.722616) (xy 431.248022 -4.7685)
			(xy 431.270679 -4.818112) (xy 431.286044 -4.870444) (xy 431.293806 -4.92443) (xy 431.293806 -4.97897)
			(xy 431.286044 -5.032956) (xy 431.270679 -5.085288) (xy 431.248022 -5.1349) (xy 431.218536 -5.180784)
			(xy 431.182821 -5.222004) (xy 431.141603 -5.257722) (xy 431.095721 -5.287211) (xy 431.04611 -5.30987)
			(xy 430.99378 -5.325239) (xy 430.939794 -5.333004) (xy 430.912524 -5.333492) (xy 430.048924 -5.333492)
			(xy 430.021654 -5.33297) (xy 429.967669 -5.325211) (xy 429.915337 -5.309848) (xy 429.865725 -5.287194)
			(xy 429.819842 -5.257709) (xy 429.778622 -5.221995) (xy 429.742905 -5.180777) (xy 429.713417 -5.134896)
			(xy 429.69076 -5.085285) (xy 429.675394 -5.032955) (xy 429.667631 -4.97897) (xy 427.693928 -4.97897)
			(xy 427.693928 -4.978974) (xy 427.686165 -5.032967) (xy 427.670797 -5.085305) (xy 427.648136 -5.134923)
			(xy 427.618644 -5.180811) (xy 427.582922 -5.222035) (xy 427.541697 -5.257755) (xy 427.495807 -5.287245)
			(xy 427.446188 -5.309903) (xy 427.393849 -5.325269) (xy 427.339856 -5.33303) (xy 427.312582 -5.333492)
			(xy 426.448982 -5.333492) (xy 426.421716 -5.332944) (xy 426.367738 -5.325181) (xy 426.315415 -5.309816)
			(xy 426.265811 -5.28716) (xy 426.219936 -5.257676) (xy 426.178724 -5.221964) (xy 426.143013 -5.18075)
			(xy 426.113531 -5.134873) (xy 426.090878 -5.085268) (xy 426.075515 -5.032944) (xy 426.067754 -4.978966)
			(xy 420.083828 -4.978966) (xy 420.083828 -4.978974) (xy 420.076065 -5.032966) (xy 420.060697 -5.085304)
			(xy 420.038037 -5.134921) (xy 420.008546 -5.180809) (xy 419.972824 -5.222033) (xy 419.9316 -5.257753)
			(xy 419.885711 -5.287243) (xy 419.836092 -5.309901) (xy 419.783754 -5.325268) (xy 419.729762 -5.333029)
			(xy 419.702488 -5.333492) (xy 418.838888 -5.333492) (xy 418.811621 -5.332945) (xy 418.757643 -5.325182)
			(xy 418.705319 -5.309817) (xy 418.655715 -5.287162) (xy 418.609839 -5.257678) (xy 418.568626 -5.221966)
			(xy 418.532915 -5.180752) (xy 418.503432 -5.134875) (xy 418.480779 -5.085269) (xy 418.465415 -5.032945)
			(xy 418.457654 -4.978967) (xy 416.483806 -4.978967) (xy 416.483806 -4.978969) (xy 416.476045 -5.032953)
			(xy 416.46068 -5.085283) (xy 416.438026 -5.134894) (xy 416.408542 -5.180776) (xy 416.372829 -5.221996)
			(xy 416.331613 -5.257714) (xy 416.285735 -5.287204) (xy 416.236126 -5.309864) (xy 416.183798 -5.325235)
			(xy 416.129815 -5.333002) (xy 416.102546 -5.333492) (xy 415.238946 -5.333492) (xy 415.211675 -5.332972)
			(xy 415.157687 -5.325216) (xy 415.105353 -5.309854) (xy 415.055738 -5.287201) (xy 415.009852 -5.257717)
			(xy 414.96863 -5.222003) (xy 414.93291 -5.180784) (xy 414.903421 -5.134902) (xy 414.880762 -5.08529)
			(xy 414.865394 -5.032958) (xy 414.857632 -4.978971) (xy 407.373928 -4.978971) (xy 407.373928 -4.978974)
			(xy 407.366165 -5.032967) (xy 407.350797 -5.085305) (xy 407.328136 -5.134923) (xy 407.298644 -5.180811)
			(xy 407.262922 -5.222035) (xy 407.221697 -5.257755) (xy 407.175807 -5.287245) (xy 407.126188 -5.309903)
			(xy 407.073849 -5.325269) (xy 407.019856 -5.33303) (xy 406.992582 -5.333492) (xy 406.128982 -5.333492)
			(xy 406.101716 -5.332944) (xy 406.047738 -5.325181) (xy 405.995415 -5.309816) (xy 405.945811 -5.28716)
			(xy 405.899936 -5.257676) (xy 405.858724 -5.221964) (xy 405.823013 -5.18075) (xy 405.793531 -5.134873)
			(xy 405.770878 -5.085268) (xy 405.755515 -5.032944) (xy 405.747754 -4.978966) (xy 403.773728 -4.978966)
			(xy 403.773728 -4.978974) (xy 403.765965 -5.032966) (xy 403.750597 -5.085304) (xy 403.727937 -5.134922)
			(xy 403.698445 -5.18081) (xy 403.662724 -5.222034) (xy 403.621499 -5.257754) (xy 403.57561 -5.287243)
			(xy 403.525991 -5.309902) (xy 403.473652 -5.325268) (xy 403.41966 -5.333029) (xy 403.392386 -5.333492)
			(xy 402.528786 -5.333492) (xy 402.501519 -5.332945) (xy 402.447542 -5.325182) (xy 402.395218 -5.309817)
			(xy 402.345613 -5.287161) (xy 402.299738 -5.257678) (xy 402.258525 -5.221965) (xy 402.222814 -5.180751)
			(xy 402.193332 -5.134874) (xy 402.170678 -5.085269) (xy 402.155315 -5.032945) (xy 402.147554 -4.978967)
			(xy 400.173706 -4.978967) (xy 400.173706 -4.97897) (xy 400.165944 -5.032953) (xy 400.15058 -5.085284)
			(xy 400.127925 -5.134895) (xy 400.098441 -5.180777) (xy 400.062728 -5.221997) (xy 400.021512 -5.257715)
			(xy 399.975633 -5.287204) (xy 399.926025 -5.309865) (xy 399.873697 -5.325235) (xy 399.819713 -5.333002)
			(xy 399.792444 -5.333492) (xy 398.928844 -5.333492) (xy 398.901573 -5.332972) (xy 398.847586 -5.325215)
			(xy 398.795252 -5.309854) (xy 398.745637 -5.287201) (xy 398.699751 -5.257716) (xy 398.658529 -5.222002)
			(xy 398.62281 -5.180784) (xy 398.593321 -5.134902) (xy 398.570661 -5.085289) (xy 398.555294 -5.032957)
			(xy 398.547532 -4.978971) (xy 396.573806 -4.978971) (xy 396.566043 -5.032959) (xy 396.550677 -5.085293)
			(xy 396.528019 -5.134907) (xy 396.498531 -5.180791) (xy 396.462813 -5.222012) (xy 396.421593 -5.25773)
			(xy 396.375708 -5.287218) (xy 396.326094 -5.309876) (xy 396.273761 -5.325243) (xy 396.219773 -5.333005)
			(xy 396.192502 -5.333492) (xy 395.328902 -5.333492) (xy 395.301633 -5.332969) (xy 395.24765 -5.325207)
			(xy 395.195321 -5.309843) (xy 395.145712 -5.287187) (xy 395.099832 -5.257702) (xy 395.058614 -5.221987)
			(xy 395.0229 -5.18077) (xy 394.993414 -5.13489) (xy 394.970758 -5.08528) (xy 394.955393 -5.032952)
			(xy 394.947631 -4.978969) (xy 390.763638 -4.978969) (xy 390.774561 -5.038281) (xy 390.782563 -5.125916)
			(xy 390.783064 -5.169916) (xy 390.782563 -5.213916) (xy 390.774561 -5.301551) (xy 390.758623 -5.388095)
			(xy 390.734881 -5.472831) (xy 390.703532 -5.555057) (xy 390.664835 -5.634092) (xy 390.619112 -5.70928)
			(xy 390.566741 -5.779999) (xy 390.508157 -5.845663) (xy 390.443843 -5.905728) (xy 390.374335 -5.959695)
			(xy 390.300207 -6.007117) (xy 390.222073 -6.047603) (xy 390.140582 -6.080816) (xy 390.056408 -6.10648)
			(xy 389.970249 -6.124384) (xy 389.882819 -6.134379) (xy 389.794842 -6.136383) (xy 389.707048 -6.130377)
			(xy 389.620164 -6.116413) (xy 389.534909 -6.094606) (xy 389.45199 -6.065137) (xy 389.372095 -6.02825)
			(xy 389.295886 -5.98425) (xy 389.223993 -5.933502) (xy 389.157012 -5.876428) (xy 389.0955 -5.813498)
			(xy 389.039964 -5.745236) (xy 388.990866 -5.672207) (xy 388.948613 -5.595015) (xy 388.913554 -5.514301)
			(xy 388.885979 -5.430733) (xy 388.866119 -5.345004) (xy 388.854136 -5.257824) (xy 388.850131 -5.169916)
			(xy 388.110984 -5.169916) (xy 388.110984 -6.169914) (xy 453.015103 -6.169914) (xy 453.019108 -6.082006)
			(xy 453.031091 -5.994826) (xy 453.050951 -5.909097) (xy 453.078526 -5.825529) (xy 453.113585 -5.744815)
			(xy 453.155838 -5.667623) (xy 453.204936 -5.594594) (xy 453.260472 -5.526332) (xy 453.321984 -5.463402)
			(xy 453.388965 -5.406328) (xy 453.460858 -5.35558) (xy 453.537067 -5.31158) (xy 453.616962 -5.274693)
			(xy 453.699881 -5.245224) (xy 453.785136 -5.223417) (xy 453.87202 -5.209453) (xy 453.959814 -5.203447)
			(xy 454.047791 -5.205451) (xy 454.135221 -5.215446) (xy 454.22138 -5.23335) (xy 454.305554 -5.259014)
			(xy 454.387045 -5.292227) (xy 454.465179 -5.332713) (xy 454.539307 -5.380135) (xy 454.608815 -5.434102)
			(xy 454.673129 -5.494167) (xy 454.731713 -5.559831) (xy 454.784084 -5.63055) (xy 454.829807 -5.705738)
			(xy 454.868504 -5.784773) (xy 454.899853 -5.866999) (xy 454.923595 -5.951735) (xy 454.939533 -6.038279)
			(xy 454.947535 -6.125914) (xy 454.948036 -6.169914) (xy 454.947535 -6.213914) (xy 454.939533 -6.301549)
			(xy 454.923595 -6.388093) (xy 454.899853 -6.472829) (xy 454.868504 -6.555055) (xy 454.829807 -6.63409)
			(xy 454.784084 -6.709278) (xy 454.731713 -6.779997) (xy 454.673129 -6.845661) (xy 454.608815 -6.905726)
			(xy 454.539307 -6.959693) (xy 454.465179 -7.007115) (xy 454.387045 -7.047601) (xy 454.305554 -7.080814)
			(xy 454.22138 -7.106478) (xy 454.135221 -7.124382) (xy 454.047791 -7.134377) (xy 453.959814 -7.136381)
			(xy 453.87202 -7.130375) (xy 453.785136 -7.116411) (xy 453.699881 -7.094604) (xy 453.616962 -7.065135)
			(xy 453.537067 -7.028248) (xy 453.460858 -6.984248) (xy 453.388965 -6.9335) (xy 453.321984 -6.876426)
			(xy 453.260472 -6.813496) (xy 453.204936 -6.745234) (xy 453.155838 -6.672205) (xy 453.113585 -6.595013)
			(xy 453.078526 -6.514299) (xy 453.050951 -6.430731) (xy 453.031091 -6.345002) (xy 453.019108 -6.257822)
			(xy 453.015103 -6.169914) (xy 388.110984 -6.169914) (xy 388.110984 -6.740774) (xy 393.142876 -6.740774)
			(xy 393.142876 -6.686226) (xy 393.150639 -6.632232) (xy 393.166008 -6.579894) (xy 393.18867 -6.530275)
			(xy 393.218162 -6.484387) (xy 393.253885 -6.443163) (xy 393.295112 -6.407443) (xy 393.341003 -6.377954)
			(xy 393.390624 -6.355297) (xy 393.442964 -6.339932) (xy 393.496958 -6.332173) (xy 393.524232 -6.331712)
			(xy 394.387832 -6.331712) (xy 394.415098 -6.332253) (xy 394.469074 -6.340017) (xy 394.521397 -6.355384)
			(xy 394.570999 -6.378041) (xy 394.616873 -6.407526) (xy 394.658084 -6.443238) (xy 394.693794 -6.484452)
			(xy 394.723274 -6.530329) (xy 394.745927 -6.579933) (xy 394.761289 -6.632257) (xy 394.76905 -6.686234)
			(xy 394.76905 -6.740766) (xy 394.769049 -6.74077) (xy 396.742898 -6.74077) (xy 396.742898 -6.68623)
			(xy 396.75066 -6.632245) (xy 396.766025 -6.579914) (xy 396.788681 -6.530302) (xy 396.818166 -6.484419)
			(xy 396.853881 -6.4432) (xy 396.895099 -6.407482) (xy 396.940979 -6.377993) (xy 396.99059 -6.355334)
			(xy 397.04292 -6.339965) (xy 397.096904 -6.3322) (xy 397.124174 -6.331712) (xy 397.987774 -6.331712)
			(xy 398.015044 -6.332226) (xy 398.06903 -6.339984) (xy 398.121363 -6.355347) (xy 398.170976 -6.378002)
			(xy 398.216859 -6.407487) (xy 398.25808 -6.443202) (xy 398.293798 -6.48442) (xy 398.323286 -6.530301)
			(xy 398.345944 -6.579913) (xy 398.36131 -6.632244) (xy 398.369072 -6.68623) (xy 398.369072 -6.74077)
			(xy 398.369071 -6.740774) (xy 400.342776 -6.740774) (xy 400.342776 -6.686226) (xy 400.350539 -6.632234)
			(xy 400.365907 -6.579897) (xy 400.388567 -6.530279) (xy 400.418058 -6.484392) (xy 400.45378 -6.443168)
			(xy 400.495005 -6.407449) (xy 400.540893 -6.377959) (xy 400.590512 -6.355301) (xy 400.64285 -6.339935)
			(xy 400.696842 -6.332174) (xy 400.724116 -6.331712) (xy 401.587716 -6.331712) (xy 401.614983 -6.332251)
			(xy 401.668961 -6.340014) (xy 401.721285 -6.35538) (xy 401.77089 -6.378036) (xy 401.816766 -6.40752)
			(xy 401.857978 -6.443233) (xy 401.89369 -6.484447) (xy 401.923172 -6.530324) (xy 401.945825 -6.57993)
			(xy 401.961189 -6.632255) (xy 401.96895 -6.686233) (xy 401.96895 -6.740767) (xy 401.968949 -6.740773)
			(xy 403.942976 -6.740773) (xy 403.942976 -6.686227) (xy 403.950739 -6.632235) (xy 403.966106 -6.579898)
			(xy 403.988766 -6.53028) (xy 404.018257 -6.484393) (xy 404.053978 -6.44317) (xy 404.095203 -6.40745)
			(xy 404.141091 -6.377961) (xy 404.190709 -6.355302) (xy 404.243047 -6.339936) (xy 404.297039 -6.332175)
			(xy 404.324312 -6.331712) (xy 405.187912 -6.331712) (xy 405.215179 -6.332251) (xy 405.269158 -6.340014)
			(xy 405.321482 -6.355379) (xy 405.371087 -6.378034) (xy 405.416964 -6.407519) (xy 405.458177 -6.443231)
			(xy 405.493889 -6.484446) (xy 405.523371 -6.530323) (xy 405.546025 -6.579929) (xy 405.561389 -6.632254)
			(xy 405.56915 -6.686233) (xy 405.56915 -6.740767) (xy 405.56915 -6.74077) (xy 413.052998 -6.74077)
			(xy 413.052998 -6.68623) (xy 413.06076 -6.632245) (xy 413.076125 -6.579914) (xy 413.098781 -6.530302)
			(xy 413.128267 -6.484419) (xy 413.163982 -6.443199) (xy 413.205199 -6.407481) (xy 413.25108 -6.377993)
			(xy 413.300691 -6.355334) (xy 413.353021 -6.339965) (xy 413.407006 -6.3322) (xy 413.434276 -6.331712)
			(xy 414.297876 -6.331712) (xy 414.325146 -6.332226) (xy 414.379132 -6.339985) (xy 414.431464 -6.355348)
			(xy 414.481077 -6.378002) (xy 414.52696 -6.407487) (xy 414.568181 -6.443202) (xy 414.603898 -6.48442)
			(xy 414.633386 -6.530302) (xy 414.656044 -6.579913) (xy 414.67141 -6.632244) (xy 414.679173 -6.68623)
			(xy 414.679173 -6.74077) (xy 414.679172 -6.740774) (xy 416.652876 -6.740774) (xy 416.652876 -6.686226)
			(xy 416.660639 -6.632234) (xy 416.676007 -6.579897) (xy 416.698667 -6.530279) (xy 416.728159 -6.484391)
			(xy 416.763881 -6.443168) (xy 416.805106 -6.407448) (xy 416.850995 -6.377959) (xy 416.900613 -6.355301)
			(xy 416.952952 -6.339935) (xy 417.006944 -6.332174) (xy 417.034218 -6.331712) (xy 417.897818 -6.331712)
			(xy 417.925085 -6.332252) (xy 417.979063 -6.340015) (xy 418.031386 -6.355381) (xy 418.080991 -6.378036)
			(xy 418.126867 -6.407521) (xy 418.168079 -6.443234) (xy 418.20379 -6.484448) (xy 418.233272 -6.530325)
			(xy 418.255926 -6.57993) (xy 418.271289 -6.632255) (xy 418.27905 -6.686233) (xy 418.27905 -6.740767)
			(xy 418.279049 -6.740773) (xy 424.262976 -6.740773) (xy 424.262976 -6.686227) (xy 424.270739 -6.632235)
			(xy 424.286106 -6.579898) (xy 424.308766 -6.53028) (xy 424.338257 -6.484393) (xy 424.373978 -6.44317)
			(xy 424.415203 -6.40745) (xy 424.461091 -6.377961) (xy 424.510709 -6.355302) (xy 424.563047 -6.339936)
			(xy 424.617039 -6.332175) (xy 424.644312 -6.331712) (xy 425.507912 -6.331712) (xy 425.535179 -6.332251)
			(xy 425.589158 -6.340014) (xy 425.641482 -6.355379) (xy 425.691087 -6.378034) (xy 425.736964 -6.407519)
			(xy 425.778177 -6.443231) (xy 425.813889 -6.484446) (xy 425.843371 -6.530323) (xy 425.866025 -6.579929)
			(xy 425.881389 -6.632254) (xy 425.88915 -6.686233) (xy 425.88915 -6.740767) (xy 425.88915 -6.740769)
			(xy 427.862998 -6.740769) (xy 427.862998 -6.686231) (xy 427.870759 -6.632248) (xy 427.886123 -6.579918)
			(xy 427.908778 -6.530308) (xy 427.938261 -6.484426) (xy 427.973974 -6.443207) (xy 428.015189 -6.407489)
			(xy 428.061067 -6.378) (xy 428.110675 -6.35534) (xy 428.163003 -6.339969) (xy 428.216985 -6.332202)
			(xy 428.244254 -6.331712) (xy 429.107854 -6.331712) (xy 429.135125 -6.332224) (xy 429.189113 -6.339981)
			(xy 429.241448 -6.355342) (xy 429.291064 -6.377995) (xy 429.33695 -6.40748) (xy 429.378173 -6.443195)
			(xy 429.413893 -6.484413) (xy 429.443383 -6.530296) (xy 429.466042 -6.579909) (xy 429.48141 -6.632242)
			(xy 429.489172 -6.686229) (xy 429.489172 -6.740771) (xy 429.488151 -6.747873) (xy 431.473788 -6.747873)
			(xy 431.473788 -6.693327) (xy 431.48155 -6.639337) (xy 431.496918 -6.587001) (xy 431.519578 -6.537385)
			(xy 431.549068 -6.491498) (xy 431.584789 -6.450276) (xy 431.626013 -6.414558) (xy 431.6719 -6.385069)
			(xy 431.721518 -6.362412) (xy 431.773854 -6.347047) (xy 431.827845 -6.339286) (xy 431.855118 -6.338824)
			(xy 432.718718 -6.338824) (xy 432.745986 -6.33934) (xy 432.799965 -6.347103) (xy 432.852291 -6.362469)
			(xy 432.901897 -6.385126) (xy 432.947774 -6.414611) (xy 432.988988 -6.450325) (xy 433.0247 -6.491541)
			(xy 433.054183 -6.537419) (xy 433.076837 -6.587026) (xy 433.092201 -6.639352) (xy 433.099962 -6.693332)
			(xy 433.099962 -6.740771) (xy 445.457798 -6.740771) (xy 445.457798 -6.686229) (xy 445.46556 -6.632243)
			(xy 445.480926 -6.579911) (xy 445.503583 -6.530298) (xy 445.53307 -6.484415) (xy 445.568786 -6.443195)
			(xy 445.610005 -6.407477) (xy 445.655888 -6.377989) (xy 445.7055 -6.35533) (xy 445.757831 -6.339963)
			(xy 445.811817 -6.332199) (xy 445.839088 -6.331712) (xy 446.702688 -6.331712) (xy 446.729958 -6.332227)
			(xy 446.783942 -6.339987) (xy 446.836273 -6.355351) (xy 446.885884 -6.378006) (xy 446.931766 -6.407492)
			(xy 446.972985 -6.443207) (xy 447.008701 -6.484424) (xy 447.038188 -6.530305) (xy 447.060845 -6.579916)
			(xy 447.076211 -6.632246) (xy 447.083973 -6.68623) (xy 447.083973 -6.74077) (xy 447.076211 -6.794754)
			(xy 447.060845 -6.847084) (xy 447.038188 -6.896695) (xy 447.008701 -6.942576) (xy 446.972985 -6.983793)
			(xy 446.931766 -7.019508) (xy 446.885884 -7.048994) (xy 446.836273 -7.071649) (xy 446.783942 -7.087013)
			(xy 446.729958 -7.094773) (xy 446.702688 -7.095236) (xy 445.839088 -7.095236) (xy 445.811817 -7.094801)
			(xy 445.757831 -7.087037) (xy 445.7055 -7.07167) (xy 445.655888 -7.049011) (xy 445.610005 -7.019523)
			(xy 445.568786 -6.983805) (xy 445.53307 -6.942585) (xy 445.503583 -6.896702) (xy 445.480926 -6.847089)
			(xy 445.46556 -6.794757) (xy 445.457798 -6.740771) (xy 433.099962 -6.740771) (xy 433.099962 -6.747868)
			(xy 433.092201 -6.801848) (xy 433.076837 -6.854174) (xy 433.054183 -6.903781) (xy 433.0247 -6.949659)
			(xy 432.988988 -6.990875) (xy 432.947774 -7.026589) (xy 432.901897 -7.056074) (xy 432.852291 -7.078731)
			(xy 432.799965 -7.094097) (xy 432.745986 -7.10186) (xy 432.718718 -7.102348) (xy 431.855118 -7.102348)
			(xy 431.827845 -7.101914) (xy 431.773854 -7.094153) (xy 431.721518 -7.078788) (xy 431.6719 -7.056131)
			(xy 431.626013 -7.026642) (xy 431.584789 -6.990924) (xy 431.549068 -6.949702) (xy 431.519578 -6.903815)
			(xy 431.496918 -6.854199) (xy 431.48155 -6.801863) (xy 431.473788 -6.747873) (xy 429.488151 -6.747873)
			(xy 429.48141 -6.794758) (xy 429.466042 -6.847091) (xy 429.443383 -6.896704) (xy 429.413893 -6.942587)
			(xy 429.378173 -6.983805) (xy 429.33695 -7.01952) (xy 429.291064 -7.049005) (xy 429.241448 -7.071658)
			(xy 429.189113 -7.087019) (xy 429.135125 -7.094776) (xy 429.107854 -7.095236) (xy 428.244254 -7.095236)
			(xy 428.216985 -7.094798) (xy 428.163003 -7.087031) (xy 428.110675 -7.07166) (xy 428.061067 -7.049)
			(xy 428.015189 -7.019511) (xy 427.973974 -6.983793) (xy 427.938261 -6.942574) (xy 427.908778 -6.896692)
			(xy 427.886123 -6.847082) (xy 427.870759 -6.794752) (xy 427.862998 -6.740769) (xy 425.88915 -6.740769)
			(xy 425.881389 -6.794746) (xy 425.866025 -6.847071) (xy 425.843371 -6.896677) (xy 425.813889 -6.942554)
			(xy 425.778177 -6.983769) (xy 425.736964 -7.019481) (xy 425.691087 -7.048966) (xy 425.641482 -7.071621)
			(xy 425.589158 -7.086986) (xy 425.535179 -7.094749) (xy 425.507912 -7.095236) (xy 424.644312 -7.095236)
			(xy 424.617039 -7.094825) (xy 424.563047 -7.087064) (xy 424.510709 -7.071698) (xy 424.461091 -7.049039)
			(xy 424.415203 -7.01955) (xy 424.373978 -6.98383) (xy 424.338257 -6.942607) (xy 424.308766 -6.89672)
			(xy 424.286106 -6.847102) (xy 424.270739 -6.794765) (xy 424.262976 -6.740773) (xy 418.279049 -6.740773)
			(xy 418.271289 -6.794745) (xy 418.255926 -6.84707) (xy 418.233272 -6.896675) (xy 418.20379 -6.942552)
			(xy 418.168079 -6.983766) (xy 418.126867 -7.019479) (xy 418.080991 -7.048964) (xy 418.031386 -7.071619)
			(xy 417.979063 -7.086985) (xy 417.925085 -7.094748) (xy 417.897818 -7.095236) (xy 417.034218 -7.095236)
			(xy 417.006944 -7.094826) (xy 416.952952 -7.087065) (xy 416.900613 -7.071699) (xy 416.850995 -7.049041)
			(xy 416.805106 -7.019552) (xy 416.763881 -6.983832) (xy 416.728159 -6.942609) (xy 416.698667 -6.896721)
			(xy 416.676007 -6.847103) (xy 416.660639 -6.794766) (xy 416.652876 -6.740774) (xy 414.679172 -6.740774)
			(xy 414.67141 -6.794756) (xy 414.656044 -6.847087) (xy 414.633386 -6.896698) (xy 414.603898 -6.94258)
			(xy 414.568181 -6.983798) (xy 414.52696 -7.019513) (xy 414.481077 -7.048998) (xy 414.431464 -7.071652)
			(xy 414.379132 -7.087015) (xy 414.325146 -7.094774) (xy 414.297876 -7.095236) (xy 413.434276 -7.095236)
			(xy 413.407006 -7.0948) (xy 413.353021 -7.087035) (xy 413.300691 -7.071666) (xy 413.25108 -7.049007)
			(xy 413.205199 -7.019519) (xy 413.163982 -6.983801) (xy 413.128267 -6.942581) (xy 413.098781 -6.896698)
			(xy 413.076125 -6.847086) (xy 413.06076 -6.794755) (xy 413.052998 -6.74077) (xy 405.56915 -6.74077)
			(xy 405.561389 -6.794746) (xy 405.546025 -6.847071) (xy 405.523371 -6.896677) (xy 405.493889 -6.942554)
			(xy 405.458177 -6.983769) (xy 405.416964 -7.019481) (xy 405.371087 -7.048966) (xy 405.321482 -7.071621)
			(xy 405.269158 -7.086986) (xy 405.215179 -7.094749) (xy 405.187912 -7.095236) (xy 404.324312 -7.095236)
			(xy 404.297039 -7.094825) (xy 404.243047 -7.087064) (xy 404.190709 -7.071698) (xy 404.141091 -7.049039)
			(xy 404.095203 -7.01955) (xy 404.053978 -6.98383) (xy 404.018257 -6.942607) (xy 403.988766 -6.89672)
			(xy 403.966106 -6.847102) (xy 403.950739 -6.794765) (xy 403.942976 -6.740773) (xy 401.968949 -6.740773)
			(xy 401.961189 -6.794745) (xy 401.945825 -6.84707) (xy 401.923172 -6.896676) (xy 401.89369 -6.942553)
			(xy 401.857978 -6.983767) (xy 401.816766 -7.01948) (xy 401.77089 -7.048964) (xy 401.721285 -7.07162)
			(xy 401.668961 -7.086986) (xy 401.614983 -7.094749) (xy 401.587716 -7.095236) (xy 400.724116 -7.095236)
			(xy 400.696842 -7.094826) (xy 400.64285 -7.087065) (xy 400.590512 -7.071699) (xy 400.540893 -7.049041)
			(xy 400.495005 -7.019551) (xy 400.45378 -6.983832) (xy 400.418058 -6.942608) (xy 400.388567 -6.896721)
			(xy 400.365907 -6.847103) (xy 400.350539 -6.794766) (xy 400.342776 -6.740774) (xy 398.369071 -6.740774)
			(xy 398.36131 -6.794756) (xy 398.345944 -6.847087) (xy 398.323286 -6.896699) (xy 398.293798 -6.94258)
			(xy 398.25808 -6.983798) (xy 398.216859 -7.019513) (xy 398.170976 -7.048998) (xy 398.121363 -7.071653)
			(xy 398.06903 -7.087016) (xy 398.015044 -7.094774) (xy 397.987774 -7.095236) (xy 397.124174 -7.095236)
			(xy 397.096904 -7.0948) (xy 397.04292 -7.087035) (xy 396.99059 -7.071666) (xy 396.940979 -7.049007)
			(xy 396.895099 -7.019518) (xy 396.853881 -6.9838) (xy 396.818166 -6.942581) (xy 396.788681 -6.896698)
			(xy 396.766025 -6.847086) (xy 396.75066 -6.794755) (xy 396.742898 -6.74077) (xy 394.769049 -6.74077)
			(xy 394.761289 -6.794743) (xy 394.745927 -6.847067) (xy 394.723274 -6.896671) (xy 394.693794 -6.942548)
			(xy 394.658084 -6.983762) (xy 394.616873 -7.019474) (xy 394.570999 -7.048959) (xy 394.521397 -7.071616)
			(xy 394.469074 -7.086983) (xy 394.415098 -7.094747) (xy 394.387832 -7.095236) (xy 393.524232 -7.095236)
			(xy 393.496958 -7.094827) (xy 393.442964 -7.087068) (xy 393.390624 -7.071703) (xy 393.341003 -7.049046)
			(xy 393.295112 -7.019557) (xy 393.253885 -6.983837) (xy 393.218162 -6.942613) (xy 393.18867 -6.896725)
			(xy 393.166008 -6.847106) (xy 393.150639 -6.794768) (xy 393.142876 -6.740774) (xy 388.110984 -6.740774)
			(xy 388.110984 -9.780016) (xy 388.110499 -9.850398) (xy 388.102605 -9.99094) (xy 388.086844 -10.130819)
			(xy 388.063264 -10.269594) (xy 388.03194 -10.406828) (xy 387.992971 -10.54209) (xy 387.946478 -10.674954)
			(xy 387.892609 -10.805003) (xy 387.831533 -10.931826) (xy 387.763442 -11.055026) (xy 387.68855 -11.174213)
			(xy 387.607093 -11.289014) (xy 387.519328 -11.399067) (xy 387.425529 -11.504025) (xy 387.325993 -11.60356)
			(xy 387.221033 -11.697356) (xy 387.110979 -11.78512) (xy 386.996176 -11.866575) (xy 386.876988 -11.941465)
			(xy 386.753787 -12.009554) (xy 386.626963 -12.070627) (xy 386.496913 -12.124494) (xy 386.364048 -12.170984)
			(xy 386.228785 -12.209951) (xy 386.091551 -12.241273) (xy 385.952775 -12.26485) (xy 385.812896 -12.280609)
			(xy 385.672354 -12.2885) (xy 385.601972 -12.289028) (xy 260.800088 -12.289028) (xy 260.744319 -12.28955)
			(xy 260.633094 -12.297886) (xy 260.522803 -12.314511) (xy 260.414062 -12.339331) (xy 260.30748 -12.372208)
			(xy 260.203654 -12.412958) (xy 260.103162 -12.461353) (xy 260.006569 -12.517122) (xy 259.914413 -12.579954)
			(xy 259.82721 -12.649497) (xy 259.745448 -12.725362) (xy 259.669584 -12.807125) (xy 259.601847 -12.892065)
			(xy 431.46197 -12.892065) (xy 431.46197 -12.837535) (xy 431.46973 -12.783559) (xy 431.485093 -12.731238)
			(xy 431.507745 -12.681635) (xy 431.537225 -12.635761) (xy 431.572934 -12.594548) (xy 431.614145 -12.558837)
			(xy 431.660017 -12.529355) (xy 431.709619 -12.5067) (xy 431.76194 -12.491335) (xy 431.815915 -12.483572)
			(xy 431.84318 -12.483084) (xy 432.70678 -12.483084) (xy 432.734055 -12.483454) (xy 432.788051 -12.491215)
			(xy 432.840392 -12.506581) (xy 432.890014 -12.529241) (xy 432.935905 -12.558731) (xy 432.977133 -12.594453)
			(xy 433.012857 -12.635678) (xy 433.04235 -12.681569) (xy 433.065012 -12.731189) (xy 433.080381 -12.78353)
			(xy 433.088144 -12.837525) (xy 433.088144 -12.864846) (xy 445.45631 -12.864846) (xy 445.45631 -12.864592)
			(xy 445.456564 -12.850622) (xy 445.45717 -12.823469) (xy 445.46523 -12.769758) (xy 445.48082 -12.717731)
			(xy 445.503625 -12.668439) (xy 445.533186 -12.622876) (xy 445.568905 -12.581962) (xy 445.610062 -12.546522)
			(xy 445.655826 -12.517273) (xy 445.705273 -12.494804) (xy 445.757405 -12.47957) (xy 445.81117 -12.471876)
			(xy 445.838326 -12.4714) (xy 446.701926 -12.4714) (xy 446.72908 -12.471883) (xy 446.782838 -12.479582)
			(xy 446.834964 -12.494821) (xy 446.884404 -12.517293) (xy 446.93016 -12.546543) (xy 446.971311 -12.581982)
			(xy 447.007024 -12.622895) (xy 447.03658 -12.668455) (xy 447.059381 -12.717744) (xy 447.074968 -12.769766)
			(xy 447.083027 -12.823472) (xy 447.083688 -12.850622) (xy 447.083942 -12.864592) (xy 447.083942 -12.864846)
			(xy 447.083472 -12.892133) (xy 447.0757 -12.946152) (xy 447.06032 -12.998515) (xy 447.037645 -13.048157)
			(xy 447.008137 -13.094067) (xy 446.972397 -13.135311) (xy 446.931151 -13.171049) (xy 446.885239 -13.200555)
			(xy 446.835597 -13.223227) (xy 446.783233 -13.238604) (xy 446.729214 -13.246374) (xy 446.701926 -13.246862)
			(xy 446.679426 -13.246581) (xy 446.634732 -13.241355) (xy 446.612772 -13.236448) (xy 446.60693 -13.234924)
			(xy 445.933322 -13.234924) (xy 445.92748 -13.236448) (xy 445.905519 -13.241348) (xy 445.860825 -13.246566)
			(xy 445.838326 -13.246862) (xy 445.811041 -13.246305) (xy 445.757027 -13.238543) (xy 445.704666 -13.223173)
			(xy 445.655026 -13.200508) (xy 445.609117 -13.17101) (xy 445.567873 -13.135278) (xy 445.532133 -13.094041)
			(xy 445.502626 -13.048137) (xy 445.479952 -12.998501) (xy 445.464572 -12.946144) (xy 445.4568 -12.892131)
			(xy 445.45631 -12.864846) (xy 433.088144 -12.864846) (xy 433.088144 -12.892075) (xy 433.080381 -12.94607)
			(xy 433.065012 -12.998411) (xy 433.04235 -13.048031) (xy 433.012857 -13.093921) (xy 432.977133 -13.135147)
			(xy 432.935905 -13.170869) (xy 432.890014 -13.200359) (xy 432.840392 -13.223019) (xy 432.788051 -13.238385)
			(xy 432.734055 -13.246146) (xy 432.70678 -13.246608) (xy 431.84318 -13.246608) (xy 431.815915 -13.246028)
			(xy 431.76194 -13.238265) (xy 431.709619 -13.2229) (xy 431.660017 -13.200245) (xy 431.614145 -13.170763)
			(xy 431.572934 -13.135052) (xy 431.537225 -13.093839) (xy 431.507745 -13.047965) (xy 431.485093 -12.998362)
			(xy 431.46973 -12.946041) (xy 431.46197 -12.892065) (xy 259.601847 -12.892065) (xy 259.600042 -12.894329)
			(xy 259.537211 -12.986486) (xy 259.481443 -13.08308) (xy 259.43305 -13.183572) (xy 259.392301 -13.287399)
			(xy 259.359426 -13.393981) (xy 259.334607 -13.502722) (xy 259.317984 -13.613014) (xy 259.309649 -13.724239)
			(xy 259.309108 -13.780008) (xy 259.309108 -17.628666) (xy 389.660162 -17.628666) (xy 389.660162 -17.574134)
			(xy 389.667923 -17.520157) (xy 389.683286 -17.467834) (xy 389.705939 -17.41823) (xy 389.73542 -17.372354)
			(xy 389.77113 -17.331141) (xy 389.812342 -17.29543) (xy 389.858216 -17.265946) (xy 389.907819 -17.243291)
			(xy 389.960142 -17.227926) (xy 390.014118 -17.220163) (xy 390.041384 -17.219676) (xy 390.904984 -17.219676)
			(xy 390.932258 -17.220062) (xy 390.986252 -17.227824) (xy 391.038592 -17.24319) (xy 391.088212 -17.265849)
			(xy 391.134103 -17.295339) (xy 391.175329 -17.33106) (xy 391.211051 -17.372285) (xy 391.240543 -17.418174)
			(xy 391.263204 -17.467793) (xy 391.278573 -17.520132) (xy 391.286336 -17.574126) (xy 391.286336 -17.628666)
			(xy 395.248162 -17.628666) (xy 395.248162 -17.574134) (xy 395.255923 -17.520157) (xy 395.271286 -17.467834)
			(xy 395.293939 -17.41823) (xy 395.32342 -17.372354) (xy 395.35913 -17.331141) (xy 395.400342 -17.29543)
			(xy 395.446216 -17.265946) (xy 395.495819 -17.243291) (xy 395.548142 -17.227926) (xy 395.602118 -17.220163)
			(xy 395.629384 -17.219676) (xy 396.492984 -17.219676) (xy 396.520258 -17.220062) (xy 396.574252 -17.227824)
			(xy 396.626592 -17.24319) (xy 396.676212 -17.265849) (xy 396.722103 -17.295339) (xy 396.763329 -17.33106)
			(xy 396.799051 -17.372285) (xy 396.828543 -17.418174) (xy 396.851204 -17.467793) (xy 396.866573 -17.520132)
			(xy 396.874336 -17.574126) (xy 396.874336 -17.628666) (xy 400.836162 -17.628666) (xy 400.836162 -17.574134)
			(xy 400.843923 -17.520157) (xy 400.859286 -17.467834) (xy 400.881939 -17.41823) (xy 400.91142 -17.372354)
			(xy 400.94713 -17.331141) (xy 400.988342 -17.29543) (xy 401.034216 -17.265946) (xy 401.083819 -17.243291)
			(xy 401.136142 -17.227926) (xy 401.190118 -17.220163) (xy 401.217384 -17.219676) (xy 402.080984 -17.219676)
			(xy 402.108258 -17.220062) (xy 402.162252 -17.227824) (xy 402.214592 -17.24319) (xy 402.264212 -17.265849)
			(xy 402.310103 -17.295339) (xy 402.351329 -17.33106) (xy 402.387051 -17.372285) (xy 402.416543 -17.418174)
			(xy 402.439204 -17.467793) (xy 402.454573 -17.520132) (xy 402.462336 -17.574126) (xy 402.462336 -17.628666)
			(xy 406.424162 -17.628666) (xy 406.424162 -17.574134) (xy 406.431923 -17.520157) (xy 406.447286 -17.467834)
			(xy 406.469939 -17.41823) (xy 406.49942 -17.372354) (xy 406.53513 -17.331141) (xy 406.576342 -17.29543)
			(xy 406.622216 -17.265946) (xy 406.671819 -17.243291) (xy 406.724142 -17.227926) (xy 406.778118 -17.220163)
			(xy 406.805384 -17.219676) (xy 407.668984 -17.219676) (xy 407.696258 -17.220062) (xy 407.750252 -17.227824)
			(xy 407.802592 -17.24319) (xy 407.852212 -17.265849) (xy 407.898103 -17.295339) (xy 407.939329 -17.33106)
			(xy 407.975051 -17.372285) (xy 408.004543 -17.418174) (xy 408.027204 -17.467793) (xy 408.042573 -17.520132)
			(xy 408.050336 -17.574126) (xy 408.050336 -17.628666) (xy 412.012162 -17.628666) (xy 412.012162 -17.574134)
			(xy 412.019923 -17.520157) (xy 412.035286 -17.467834) (xy 412.057939 -17.41823) (xy 412.08742 -17.372354)
			(xy 412.12313 -17.331141) (xy 412.164342 -17.29543) (xy 412.210216 -17.265946) (xy 412.259819 -17.243291)
			(xy 412.312142 -17.227926) (xy 412.366118 -17.220163) (xy 412.393384 -17.219676) (xy 413.256984 -17.219676)
			(xy 413.284258 -17.220062) (xy 413.338252 -17.227824) (xy 413.390592 -17.24319) (xy 413.440212 -17.265849)
			(xy 413.486103 -17.295339) (xy 413.527329 -17.33106) (xy 413.563051 -17.372285) (xy 413.592543 -17.418174)
			(xy 413.615204 -17.467793) (xy 413.630573 -17.520132) (xy 413.638336 -17.574126) (xy 413.638336 -17.628667)
			(xy 417.905962 -17.628667) (xy 417.905962 -17.574133) (xy 417.913723 -17.520155) (xy 417.929087 -17.467831)
			(xy 417.951741 -17.418226) (xy 417.981224 -17.372349) (xy 418.016936 -17.331136) (xy 418.058149 -17.295424)
			(xy 418.104026 -17.265941) (xy 418.153631 -17.243287) (xy 418.205955 -17.227923) (xy 418.259933 -17.220162)
			(xy 418.2872 -17.219676) (xy 419.1508 -17.219676) (xy 419.178072 -17.220087) (xy 419.232061 -17.227849)
			(xy 419.284396 -17.243216) (xy 419.334011 -17.265874) (xy 419.379896 -17.295363) (xy 419.421118 -17.331082)
			(xy 419.456837 -17.372304) (xy 419.486326 -17.418189) (xy 419.508984 -17.467804) (xy 419.524351 -17.520139)
			(xy 419.532113 -17.574128) (xy 419.532113 -17.628667) (xy 423.493962 -17.628667) (xy 423.493962 -17.574133)
			(xy 423.501723 -17.520155) (xy 423.517087 -17.467831) (xy 423.539741 -17.418226) (xy 423.569224 -17.372349)
			(xy 423.604936 -17.331136) (xy 423.646149 -17.295424) (xy 423.692026 -17.265941) (xy 423.741631 -17.243287)
			(xy 423.793955 -17.227923) (xy 423.847933 -17.220162) (xy 423.8752 -17.219676) (xy 424.7388 -17.219676)
			(xy 424.766072 -17.220087) (xy 424.820061 -17.227849) (xy 424.872396 -17.243216) (xy 424.922011 -17.265874)
			(xy 424.967896 -17.295363) (xy 425.009118 -17.331082) (xy 425.044837 -17.372304) (xy 425.074326 -17.418189)
			(xy 425.096984 -17.467804) (xy 425.112351 -17.520139) (xy 425.120113 -17.574128) (xy 425.120113 -17.62867)
			(xy 429.11594 -17.62867) (xy 429.11594 -17.57413) (xy 429.123702 -17.520145) (xy 429.139068 -17.467815)
			(xy 429.161726 -17.418204) (xy 429.191214 -17.372324) (xy 429.226932 -17.331107) (xy 429.268152 -17.295393)
			(xy 429.314036 -17.265909) (xy 429.363649 -17.243256) (xy 429.415981 -17.227894) (xy 429.469966 -17.220137)
			(xy 429.497236 -17.219676) (xy 430.360836 -17.219676) (xy 430.388106 -17.220089) (xy 430.442091 -17.227856)
			(xy 430.494422 -17.243226) (xy 430.544032 -17.265886) (xy 430.589913 -17.295376) (xy 430.631131 -17.331095)
			(xy 430.666846 -17.372315) (xy 430.696331 -17.418199) (xy 430.718987 -17.467812) (xy 430.734352 -17.520144)
			(xy 430.742114 -17.57413) (xy 430.742114 -17.62867) (xy 430.734352 -17.682656) (xy 430.718987 -17.734988)
			(xy 430.696331 -17.784601) (xy 430.666846 -17.830485) (xy 430.631131 -17.871705) (xy 430.589913 -17.907424)
			(xy 430.544032 -17.936914) (xy 430.494422 -17.959574) (xy 430.442091 -17.974944) (xy 430.388106 -17.982711)
			(xy 430.360836 -17.9832) (xy 429.497236 -17.9832) (xy 429.469966 -17.982663) (xy 429.415981 -17.974906)
			(xy 429.363649 -17.959544) (xy 429.314036 -17.936891) (xy 429.268152 -17.907407) (xy 429.226932 -17.871693)
			(xy 429.191214 -17.830476) (xy 429.161726 -17.784596) (xy 429.139068 -17.734985) (xy 429.123702 -17.682655)
			(xy 429.11594 -17.62867) (xy 425.120113 -17.62867) (xy 425.120113 -17.628672) (xy 425.112351 -17.682661)
			(xy 425.096984 -17.734996) (xy 425.074326 -17.784611) (xy 425.044837 -17.830496) (xy 425.009118 -17.871718)
			(xy 424.967896 -17.907437) (xy 424.922011 -17.936926) (xy 424.872396 -17.959584) (xy 424.820061 -17.974951)
			(xy 424.766072 -17.982713) (xy 424.7388 -17.9832) (xy 423.8752 -17.9832) (xy 423.847933 -17.982638)
			(xy 423.793955 -17.974877) (xy 423.741631 -17.959513) (xy 423.692026 -17.936859) (xy 423.646149 -17.907376)
			(xy 423.604936 -17.871664) (xy 423.569224 -17.830451) (xy 423.539741 -17.784574) (xy 423.517087 -17.734969)
			(xy 423.501723 -17.682645) (xy 423.493962 -17.628667) (xy 419.532113 -17.628667) (xy 419.532113 -17.628672)
			(xy 419.524351 -17.682661) (xy 419.508984 -17.734996) (xy 419.486326 -17.784611) (xy 419.456837 -17.830496)
			(xy 419.421118 -17.871718) (xy 419.379896 -17.907437) (xy 419.334011 -17.936926) (xy 419.284396 -17.959584)
			(xy 419.232061 -17.974951) (xy 419.178072 -17.982713) (xy 419.1508 -17.9832) (xy 418.2872 -17.9832)
			(xy 418.259933 -17.982638) (xy 418.205955 -17.974877) (xy 418.153631 -17.959513) (xy 418.104026 -17.936859)
			(xy 418.058149 -17.907376) (xy 418.016936 -17.871664) (xy 417.981224 -17.830451) (xy 417.951741 -17.784574)
			(xy 417.929087 -17.734969) (xy 417.913723 -17.682645) (xy 417.905962 -17.628667) (xy 413.638336 -17.628667)
			(xy 413.638336 -17.628674) (xy 413.630573 -17.682668) (xy 413.615204 -17.735007) (xy 413.592543 -17.784626)
			(xy 413.563051 -17.830515) (xy 413.527329 -17.87174) (xy 413.486103 -17.907461) (xy 413.440212 -17.936951)
			(xy 413.390592 -17.95961) (xy 413.338252 -17.974976) (xy 413.284258 -17.982738) (xy 413.256984 -17.9832)
			(xy 412.393384 -17.9832) (xy 412.366118 -17.982637) (xy 412.312142 -17.974874) (xy 412.259819 -17.959509)
			(xy 412.210216 -17.936854) (xy 412.164342 -17.90737) (xy 412.12313 -17.871659) (xy 412.08742 -17.830446)
			(xy 412.057939 -17.78457) (xy 412.035286 -17.734966) (xy 412.019923 -17.682643) (xy 412.012162 -17.628666)
			(xy 408.050336 -17.628666) (xy 408.050336 -17.628674) (xy 408.042573 -17.682668) (xy 408.027204 -17.735007)
			(xy 408.004543 -17.784626) (xy 407.975051 -17.830515) (xy 407.939329 -17.87174) (xy 407.898103 -17.907461)
			(xy 407.852212 -17.936951) (xy 407.802592 -17.95961) (xy 407.750252 -17.974976) (xy 407.696258 -17.982738)
			(xy 407.668984 -17.9832) (xy 406.805384 -17.9832) (xy 406.778118 -17.982637) (xy 406.724142 -17.974874)
			(xy 406.671819 -17.959509) (xy 406.622216 -17.936854) (xy 406.576342 -17.90737) (xy 406.53513 -17.871659)
			(xy 406.49942 -17.830446) (xy 406.469939 -17.78457) (xy 406.447286 -17.734966) (xy 406.431923 -17.682643)
			(xy 406.424162 -17.628666) (xy 402.462336 -17.628666) (xy 402.462336 -17.628674) (xy 402.454573 -17.682668)
			(xy 402.439204 -17.735007) (xy 402.416543 -17.784626) (xy 402.387051 -17.830515) (xy 402.351329 -17.87174)
			(xy 402.310103 -17.907461) (xy 402.264212 -17.936951) (xy 402.214592 -17.95961) (xy 402.162252 -17.974976)
			(xy 402.108258 -17.982738) (xy 402.080984 -17.9832) (xy 401.217384 -17.9832) (xy 401.190118 -17.982637)
			(xy 401.136142 -17.974874) (xy 401.083819 -17.959509) (xy 401.034216 -17.936854) (xy 400.988342 -17.90737)
			(xy 400.94713 -17.871659) (xy 400.91142 -17.830446) (xy 400.881939 -17.78457) (xy 400.859286 -17.734966)
			(xy 400.843923 -17.682643) (xy 400.836162 -17.628666) (xy 396.874336 -17.628666) (xy 396.874336 -17.628674)
			(xy 396.866573 -17.682668) (xy 396.851204 -17.735007) (xy 396.828543 -17.784626) (xy 396.799051 -17.830515)
			(xy 396.763329 -17.87174) (xy 396.722103 -17.907461) (xy 396.676212 -17.936951) (xy 396.626592 -17.95961)
			(xy 396.574252 -17.974976) (xy 396.520258 -17.982738) (xy 396.492984 -17.9832) (xy 395.629384 -17.9832)
			(xy 395.602118 -17.982637) (xy 395.548142 -17.974874) (xy 395.495819 -17.959509) (xy 395.446216 -17.936854)
			(xy 395.400342 -17.90737) (xy 395.35913 -17.871659) (xy 395.32342 -17.830446) (xy 395.293939 -17.78457)
			(xy 395.271286 -17.734966) (xy 395.255923 -17.682643) (xy 395.248162 -17.628666) (xy 391.286336 -17.628666)
			(xy 391.286336 -17.628674) (xy 391.278573 -17.682668) (xy 391.263204 -17.735007) (xy 391.240543 -17.784626)
			(xy 391.211051 -17.830515) (xy 391.175329 -17.87174) (xy 391.134103 -17.907461) (xy 391.088212 -17.936951)
			(xy 391.038592 -17.95961) (xy 390.986252 -17.974976) (xy 390.932258 -17.982738) (xy 390.904984 -17.9832)
			(xy 390.041384 -17.9832) (xy 390.014118 -17.982637) (xy 389.960142 -17.974874) (xy 389.907819 -17.959509)
			(xy 389.858216 -17.936854) (xy 389.812342 -17.90737) (xy 389.77113 -17.871659) (xy 389.73542 -17.830446)
			(xy 389.705939 -17.78457) (xy 389.683286 -17.734966) (xy 389.667923 -17.682643) (xy 389.660162 -17.628666)
			(xy 259.309108 -17.628666) (xy 259.309108 -19.152666) (xy 392.454162 -19.152666) (xy 392.454162 -19.098134)
			(xy 392.461923 -19.044157) (xy 392.477286 -18.991834) (xy 392.499939 -18.94223) (xy 392.52942 -18.896354)
			(xy 392.56513 -18.855141) (xy 392.606342 -18.81943) (xy 392.652216 -18.789946) (xy 392.701819 -18.767291)
			(xy 392.754142 -18.751926) (xy 392.808118 -18.744163) (xy 392.835384 -18.743676) (xy 393.698984 -18.743676)
			(xy 393.726258 -18.744062) (xy 393.780252 -18.751824) (xy 393.832592 -18.76719) (xy 393.882212 -18.789849)
			(xy 393.928103 -18.819339) (xy 393.969329 -18.85506) (xy 394.005051 -18.896285) (xy 394.034543 -18.942174)
			(xy 394.057204 -18.991793) (xy 394.072573 -19.044132) (xy 394.080336 -19.098126) (xy 394.080336 -19.152666)
			(xy 398.042162 -19.152666) (xy 398.042162 -19.098134) (xy 398.049923 -19.044157) (xy 398.065286 -18.991834)
			(xy 398.087939 -18.94223) (xy 398.11742 -18.896354) (xy 398.15313 -18.855141) (xy 398.194342 -18.81943)
			(xy 398.240216 -18.789946) (xy 398.289819 -18.767291) (xy 398.342142 -18.751926) (xy 398.396118 -18.744163)
			(xy 398.423384 -18.743676) (xy 399.286984 -18.743676) (xy 399.314258 -18.744062) (xy 399.368252 -18.751824)
			(xy 399.420592 -18.76719) (xy 399.470212 -18.789849) (xy 399.516103 -18.819339) (xy 399.557329 -18.85506)
			(xy 399.593051 -18.896285) (xy 399.622543 -18.942174) (xy 399.645204 -18.991793) (xy 399.660573 -19.044132)
			(xy 399.668336 -19.098126) (xy 399.668336 -19.152666) (xy 403.630162 -19.152666) (xy 403.630162 -19.098134)
			(xy 403.637923 -19.044157) (xy 403.653286 -18.991834) (xy 403.675939 -18.94223) (xy 403.70542 -18.896354)
			(xy 403.74113 -18.855141) (xy 403.782342 -18.81943) (xy 403.828216 -18.789946) (xy 403.877819 -18.767291)
			(xy 403.930142 -18.751926) (xy 403.984118 -18.744163) (xy 404.011384 -18.743676) (xy 404.874984 -18.743676)
			(xy 404.902258 -18.744062) (xy 404.956252 -18.751824) (xy 405.008592 -18.76719) (xy 405.058212 -18.789849)
			(xy 405.104103 -18.819339) (xy 405.145329 -18.85506) (xy 405.181051 -18.896285) (xy 405.210543 -18.942174)
			(xy 405.233204 -18.991793) (xy 405.248573 -19.044132) (xy 405.256336 -19.098126) (xy 405.256336 -19.152666)
			(xy 409.218162 -19.152666) (xy 409.218162 -19.098134) (xy 409.225923 -19.044157) (xy 409.241286 -18.991834)
			(xy 409.263939 -18.94223) (xy 409.29342 -18.896354) (xy 409.32913 -18.855141) (xy 409.370342 -18.81943)
			(xy 409.416216 -18.789946) (xy 409.465819 -18.767291) (xy 409.518142 -18.751926) (xy 409.572118 -18.744163)
			(xy 409.599384 -18.743676) (xy 410.462984 -18.743676) (xy 410.490258 -18.744062) (xy 410.544252 -18.751824)
			(xy 410.596592 -18.76719) (xy 410.646212 -18.789849) (xy 410.692103 -18.819339) (xy 410.733329 -18.85506)
			(xy 410.769051 -18.896285) (xy 410.798543 -18.942174) (xy 410.821204 -18.991793) (xy 410.836573 -19.044132)
			(xy 410.844336 -19.098126) (xy 410.844336 -19.152667) (xy 415.111962 -19.152667) (xy 415.111962 -19.098133)
			(xy 415.119723 -19.044155) (xy 415.135087 -18.991831) (xy 415.157741 -18.942226) (xy 415.187224 -18.896349)
			(xy 415.222936 -18.855136) (xy 415.264149 -18.819424) (xy 415.310026 -18.789941) (xy 415.359631 -18.767287)
			(xy 415.411955 -18.751923) (xy 415.465933 -18.744162) (xy 415.4932 -18.743676) (xy 416.3568 -18.743676)
			(xy 416.384072 -18.744087) (xy 416.438061 -18.751849) (xy 416.490396 -18.767216) (xy 416.540011 -18.789874)
			(xy 416.585896 -18.819363) (xy 416.627118 -18.855082) (xy 416.662837 -18.896304) (xy 416.692326 -18.942189)
			(xy 416.714984 -18.991804) (xy 416.730351 -19.044139) (xy 416.738113 -19.098128) (xy 416.738113 -19.152667)
			(xy 420.699962 -19.152667) (xy 420.699962 -19.098133) (xy 420.707723 -19.044155) (xy 420.723087 -18.991831)
			(xy 420.745741 -18.942226) (xy 420.775224 -18.896349) (xy 420.810936 -18.855136) (xy 420.852149 -18.819424)
			(xy 420.898026 -18.789941) (xy 420.947631 -18.767287) (xy 420.999955 -18.751923) (xy 421.053933 -18.744162)
			(xy 421.0812 -18.743676) (xy 421.9448 -18.743676) (xy 421.972072 -18.744087) (xy 422.026061 -18.751849)
			(xy 422.078396 -18.767216) (xy 422.128011 -18.789874) (xy 422.173896 -18.819363) (xy 422.215118 -18.855082)
			(xy 422.250837 -18.896304) (xy 422.280326 -18.942189) (xy 422.302984 -18.991804) (xy 422.318351 -19.044139)
			(xy 422.326113 -19.098128) (xy 422.326113 -19.15267) (xy 426.32194 -19.15267) (xy 426.32194 -19.09813)
			(xy 426.329702 -19.044145) (xy 426.345068 -18.991815) (xy 426.367726 -18.942204) (xy 426.397214 -18.896324)
			(xy 426.432932 -18.855107) (xy 426.474152 -18.819393) (xy 426.520036 -18.789909) (xy 426.569649 -18.767256)
			(xy 426.621981 -18.751894) (xy 426.675966 -18.744137) (xy 426.703236 -18.743676) (xy 427.566836 -18.743676)
			(xy 427.594106 -18.744089) (xy 427.648091 -18.751856) (xy 427.700422 -18.767226) (xy 427.750032 -18.789886)
			(xy 427.795913 -18.819376) (xy 427.837131 -18.855095) (xy 427.872846 -18.896315) (xy 427.902331 -18.942199)
			(xy 427.924987 -18.991812) (xy 427.940352 -19.044144) (xy 427.948114 -19.09813) (xy 427.948114 -19.15267)
			(xy 431.90994 -19.15267) (xy 431.90994 -19.09813) (xy 431.917702 -19.044145) (xy 431.933068 -18.991815)
			(xy 431.955726 -18.942204) (xy 431.985214 -18.896324) (xy 432.020932 -18.855107) (xy 432.062152 -18.819393)
			(xy 432.108036 -18.789909) (xy 432.157649 -18.767256) (xy 432.209981 -18.751894) (xy 432.263966 -18.744137)
			(xy 432.291236 -18.743676) (xy 433.154836 -18.743676) (xy 433.182106 -18.744089) (xy 433.236091 -18.751856)
			(xy 433.288422 -18.767226) (xy 433.338032 -18.789886) (xy 433.383913 -18.819376) (xy 433.425131 -18.855095)
			(xy 433.460846 -18.896315) (xy 433.490331 -18.942199) (xy 433.512987 -18.991812) (xy 433.528352 -19.044144)
			(xy 433.536114 -19.09813) (xy 433.536114 -19.15267) (xy 433.528352 -19.206656) (xy 433.512987 -19.258988)
			(xy 433.490331 -19.308601) (xy 433.460846 -19.354485) (xy 433.425131 -19.395705) (xy 433.383913 -19.431424)
			(xy 433.338032 -19.460914) (xy 433.288422 -19.483574) (xy 433.236091 -19.498944) (xy 433.182106 -19.506711)
			(xy 433.154836 -19.5072) (xy 432.291236 -19.5072) (xy 432.263966 -19.506663) (xy 432.209981 -19.498906)
			(xy 432.157649 -19.483544) (xy 432.108036 -19.460891) (xy 432.062152 -19.431407) (xy 432.020932 -19.395693)
			(xy 431.985214 -19.354476) (xy 431.955726 -19.308596) (xy 431.933068 -19.258985) (xy 431.917702 -19.206655)
			(xy 431.90994 -19.15267) (xy 427.948114 -19.15267) (xy 427.940352 -19.206656) (xy 427.924987 -19.258988)
			(xy 427.902331 -19.308601) (xy 427.872846 -19.354485) (xy 427.837131 -19.395705) (xy 427.795913 -19.431424)
			(xy 427.750032 -19.460914) (xy 427.700422 -19.483574) (xy 427.648091 -19.498944) (xy 427.594106 -19.506711)
			(xy 427.566836 -19.5072) (xy 426.703236 -19.5072) (xy 426.675966 -19.506663) (xy 426.621981 -19.498906)
			(xy 426.569649 -19.483544) (xy 426.520036 -19.460891) (xy 426.474152 -19.431407) (xy 426.432932 -19.395693)
			(xy 426.397214 -19.354476) (xy 426.367726 -19.308596) (xy 426.345068 -19.258985) (xy 426.329702 -19.206655)
			(xy 426.32194 -19.15267) (xy 422.326113 -19.15267) (xy 422.326113 -19.152672) (xy 422.318351 -19.206661)
			(xy 422.302984 -19.258996) (xy 422.280326 -19.308611) (xy 422.250837 -19.354496) (xy 422.215118 -19.395718)
			(xy 422.173896 -19.431437) (xy 422.128011 -19.460926) (xy 422.078396 -19.483584) (xy 422.026061 -19.498951)
			(xy 421.972072 -19.506713) (xy 421.9448 -19.5072) (xy 421.0812 -19.5072) (xy 421.053933 -19.506638)
			(xy 420.999955 -19.498877) (xy 420.947631 -19.483513) (xy 420.898026 -19.460859) (xy 420.852149 -19.431376)
			(xy 420.810936 -19.395664) (xy 420.775224 -19.354451) (xy 420.745741 -19.308574) (xy 420.723087 -19.258969)
			(xy 420.707723 -19.206645) (xy 420.699962 -19.152667) (xy 416.738113 -19.152667) (xy 416.738113 -19.152672)
			(xy 416.730351 -19.206661) (xy 416.714984 -19.258996) (xy 416.692326 -19.308611) (xy 416.662837 -19.354496)
			(xy 416.627118 -19.395718) (xy 416.585896 -19.431437) (xy 416.540011 -19.460926) (xy 416.490396 -19.483584)
			(xy 416.438061 -19.498951) (xy 416.384072 -19.506713) (xy 416.3568 -19.5072) (xy 415.4932 -19.5072)
			(xy 415.465933 -19.506638) (xy 415.411955 -19.498877) (xy 415.359631 -19.483513) (xy 415.310026 -19.460859)
			(xy 415.264149 -19.431376) (xy 415.222936 -19.395664) (xy 415.187224 -19.354451) (xy 415.157741 -19.308574)
			(xy 415.135087 -19.258969) (xy 415.119723 -19.206645) (xy 415.111962 -19.152667) (xy 410.844336 -19.152667)
			(xy 410.844336 -19.152674) (xy 410.836573 -19.206668) (xy 410.821204 -19.259007) (xy 410.798543 -19.308626)
			(xy 410.769051 -19.354515) (xy 410.733329 -19.39574) (xy 410.692103 -19.431461) (xy 410.646212 -19.460951)
			(xy 410.596592 -19.48361) (xy 410.544252 -19.498976) (xy 410.490258 -19.506738) (xy 410.462984 -19.5072)
			(xy 409.599384 -19.5072) (xy 409.572118 -19.506637) (xy 409.518142 -19.498874) (xy 409.465819 -19.483509)
			(xy 409.416216 -19.460854) (xy 409.370342 -19.43137) (xy 409.32913 -19.395659) (xy 409.29342 -19.354446)
			(xy 409.263939 -19.30857) (xy 409.241286 -19.258966) (xy 409.225923 -19.206643) (xy 409.218162 -19.152666)
			(xy 405.256336 -19.152666) (xy 405.256336 -19.152674) (xy 405.248573 -19.206668) (xy 405.233204 -19.259007)
			(xy 405.210543 -19.308626) (xy 405.181051 -19.354515) (xy 405.145329 -19.39574) (xy 405.104103 -19.431461)
			(xy 405.058212 -19.460951) (xy 405.008592 -19.48361) (xy 404.956252 -19.498976) (xy 404.902258 -19.506738)
			(xy 404.874984 -19.5072) (xy 404.011384 -19.5072) (xy 403.984118 -19.506637) (xy 403.930142 -19.498874)
			(xy 403.877819 -19.483509) (xy 403.828216 -19.460854) (xy 403.782342 -19.43137) (xy 403.74113 -19.395659)
			(xy 403.70542 -19.354446) (xy 403.675939 -19.30857) (xy 403.653286 -19.258966) (xy 403.637923 -19.206643)
			(xy 403.630162 -19.152666) (xy 399.668336 -19.152666) (xy 399.668336 -19.152674) (xy 399.660573 -19.206668)
			(xy 399.645204 -19.259007) (xy 399.622543 -19.308626) (xy 399.593051 -19.354515) (xy 399.557329 -19.39574)
			(xy 399.516103 -19.431461) (xy 399.470212 -19.460951) (xy 399.420592 -19.48361) (xy 399.368252 -19.498976)
			(xy 399.314258 -19.506738) (xy 399.286984 -19.5072) (xy 398.423384 -19.5072) (xy 398.396118 -19.506637)
			(xy 398.342142 -19.498874) (xy 398.289819 -19.483509) (xy 398.240216 -19.460854) (xy 398.194342 -19.43137)
			(xy 398.15313 -19.395659) (xy 398.11742 -19.354446) (xy 398.087939 -19.30857) (xy 398.065286 -19.258966)
			(xy 398.049923 -19.206643) (xy 398.042162 -19.152666) (xy 394.080336 -19.152666) (xy 394.080336 -19.152674)
			(xy 394.072573 -19.206668) (xy 394.057204 -19.259007) (xy 394.034543 -19.308626) (xy 394.005051 -19.354515)
			(xy 393.969329 -19.39574) (xy 393.928103 -19.431461) (xy 393.882212 -19.460951) (xy 393.832592 -19.48361)
			(xy 393.780252 -19.498976) (xy 393.726258 -19.506738) (xy 393.698984 -19.5072) (xy 392.835384 -19.5072)
			(xy 392.808118 -19.506637) (xy 392.754142 -19.498874) (xy 392.701819 -19.483509) (xy 392.652216 -19.460854)
			(xy 392.606342 -19.43137) (xy 392.56513 -19.395659) (xy 392.52942 -19.354446) (xy 392.499939 -19.30857)
			(xy 392.477286 -19.258966) (xy 392.461923 -19.206643) (xy 392.454162 -19.152666) (xy 259.309108 -19.152666)
			(xy 259.309108 -25.468351) (xy 388.406603 -25.468351) (xy 388.406603 -25.413849) (xy 388.41436 -25.359901)
			(xy 388.429716 -25.307607) (xy 388.452359 -25.25803) (xy 388.481827 -25.212181) (xy 388.517521 -25.170992)
			(xy 388.558713 -25.135303) (xy 388.604565 -25.10584) (xy 388.654144 -25.083202) (xy 388.70644 -25.067852)
			(xy 388.760389 -25.0601) (xy 388.78764 -25.05964) (xy 389.65124 -25.05964) (xy 389.678493 -25.060033)
			(xy 389.732443 -25.067795) (xy 389.78474 -25.083155) (xy 389.834318 -25.105802) (xy 389.880169 -25.135273)
			(xy 389.92136 -25.170969) (xy 389.957051 -25.212163) (xy 389.986518 -25.258017) (xy 390.009159 -25.307598)
			(xy 390.024514 -25.359896) (xy 390.03227 -25.413847) (xy 390.03227 -25.468353) (xy 390.024514 -25.522304)
			(xy 390.009159 -25.574602) (xy 389.986518 -25.624183) (xy 389.957051 -25.670037) (xy 389.92136 -25.711231)
			(xy 389.880169 -25.746927) (xy 389.834318 -25.776398) (xy 389.78474 -25.799045) (xy 389.732443 -25.814405)
			(xy 389.678493 -25.822167) (xy 389.65124 -25.822656) (xy 388.78764 -25.822656) (xy 388.760389 -25.8221)
			(xy 388.70644 -25.814348) (xy 388.654144 -25.798998) (xy 388.604565 -25.77636) (xy 388.558713 -25.746897)
			(xy 388.517521 -25.711208) (xy 388.481827 -25.670019) (xy 388.452359 -25.62417) (xy 388.429716 -25.574593)
			(xy 388.41436 -25.522299) (xy 388.406603 -25.468351) (xy 259.309108 -25.468351) (xy 259.309108 -28.450032)
			(xy 354.840804 -28.450032) (xy 354.844787 -28.322014) (xy 354.856722 -28.194492) (xy 354.876561 -28.067958)
			(xy 354.904228 -27.942902) (xy 354.939617 -27.819809) (xy 354.98259 -27.699153) (xy 355.032981 -27.581403)
			(xy 355.090595 -27.467013) (xy 355.155209 -27.356426) (xy 355.226573 -27.25007) (xy 355.304411 -27.148357)
			(xy 355.388422 -27.051679) (xy 355.478281 -26.960412) (xy 355.57364 -26.874907) (xy 355.674131 -26.795497)
			(xy 355.779364 -26.722487) (xy 355.888933 -26.656161) (xy 356.002413 -26.596775) (xy 356.119365 -26.544559)
			(xy 356.239338 -26.499715) (xy 356.361866 -26.462417) (xy 356.486477 -26.432808) (xy 356.612686 -26.411003)
			(xy 356.740008 -26.397087) (xy 356.867948 -26.391113) (xy 356.996012 -26.393105) (xy 357.123705 -26.403055)
			(xy 357.250532 -26.420924) (xy 357.376003 -26.446643) (xy 357.499632 -26.480113) (xy 357.620941 -26.521204)
			(xy 357.739461 -26.569758) (xy 357.854733 -26.625586) (xy 357.966311 -26.688472) (xy 358.073764 -26.758174)
			(xy 358.176676 -26.834421) (xy 358.274648 -26.916918) (xy 358.367302 -27.005347) (xy 358.454279 -27.099365)
			(xy 358.535243 -27.198608) (xy 358.60988 -27.302693) (xy 358.677902 -27.411217) (xy 358.739046 -27.52376)
			(xy 358.793074 -27.639886) (xy 358.839779 -27.759147) (xy 358.878979 -27.88108) (xy 358.910522 -28.005215)
			(xy 358.934287 -28.131071) (xy 358.950181 -28.25816) (xy 358.958144 -28.385992) (xy 358.958642 -28.450032)
			(xy 358.958144 -28.514072) (xy 358.950181 -28.641904) (xy 358.934287 -28.768993) (xy 358.910522 -28.894849)
			(xy 358.878979 -29.018984) (xy 358.839779 -29.140917) (xy 358.793074 -29.260178) (xy 358.739046 -29.376304)
			(xy 358.677902 -29.488847) (xy 358.60988 -29.597371) (xy 358.535243 -29.701456) (xy 358.454279 -29.800699)
			(xy 358.367302 -29.894717) (xy 358.274648 -29.983146) (xy 358.176676 -30.065643) (xy 358.073764 -30.14189)
			(xy 357.966311 -30.211592) (xy 357.854733 -30.274478) (xy 357.739461 -30.330306) (xy 357.620941 -30.37886)
			(xy 357.499632 -30.419951) (xy 357.376003 -30.453421) (xy 357.250532 -30.47914) (xy 357.123705 -30.497009)
			(xy 356.996012 -30.506959) (xy 356.867948 -30.508951) (xy 356.740008 -30.502977) (xy 356.612686 -30.489061)
			(xy 356.486477 -30.467256) (xy 356.361866 -30.437647) (xy 356.239338 -30.400349) (xy 356.119365 -30.355505)
			(xy 356.002413 -30.303289) (xy 355.888933 -30.243903) (xy 355.779364 -30.177577) (xy 355.674131 -30.104567)
			(xy 355.57364 -30.025157) (xy 355.478281 -29.939652) (xy 355.388422 -29.848385) (xy 355.304411 -29.751707)
			(xy 355.226573 -29.649994) (xy 355.155209 -29.543638) (xy 355.090595 -29.433051) (xy 355.032981 -29.318661)
			(xy 354.98259 -29.200911) (xy 354.939617 -29.080255) (xy 354.904228 -28.957162) (xy 354.876561 -28.832106)
			(xy 354.856722 -28.705572) (xy 354.844787 -28.57805) (xy 354.840804 -28.450032) (xy 259.309108 -28.450032)
			(xy 259.309108 -33.275016) (xy 259.308614 -33.345398) (xy 259.30072 -33.48594) (xy 259.284959 -33.625819)
			(xy 259.261379 -33.764594) (xy 259.230448 -33.90011) (xy 462.69148 -33.90011) (xy 462.69148 -32.29991)
			(xy 462.691988 -32.23523) (xy 462.700111 -32.106124) (xy 462.716324 -31.977784) (xy 462.740564 -31.850714)
			(xy 462.772734 -31.725418) (xy 462.812709 -31.602388) (xy 462.86033 -31.482112) (xy 462.915409 -31.365063)
			(xy 462.977729 -31.251703) (xy 463.047044 -31.14248) (xy 463.12308 -31.037825) (xy 463.205538 -30.938151)
			(xy 463.294091 -30.843851) (xy 463.388391 -30.755298) (xy 463.488065 -30.67284) (xy 463.59272 -30.596804)
			(xy 463.701943 -30.527489) (xy 463.815303 -30.465169) (xy 463.932352 -30.41009) (xy 464.052628 -30.362469)
			(xy 464.175658 -30.322494) (xy 464.300954 -30.290324) (xy 464.428024 -30.266084) (xy 464.556364 -30.249871)
			(xy 464.68547 -30.241748) (xy 464.81483 -30.241748) (xy 464.943936 -30.249871) (xy 465.072276 -30.266084)
			(xy 465.199346 -30.290324) (xy 465.324642 -30.322494) (xy 465.447672 -30.362469) (xy 465.567948 -30.41009)
			(xy 465.684997 -30.465169) (xy 465.798357 -30.527489) (xy 465.90758 -30.596804) (xy 466.012235 -30.67284)
			(xy 466.111909 -30.755298) (xy 466.206209 -30.843851) (xy 466.294762 -30.938151) (xy 466.37722 -31.037825)
			(xy 466.453256 -31.14248) (xy 466.522571 -31.251703) (xy 466.584891 -31.365063) (xy 466.63997 -31.482112)
			(xy 466.687591 -31.602388) (xy 466.727566 -31.725418) (xy 466.759736 -31.850714) (xy 466.783976 -31.977784)
			(xy 466.800189 -32.106124) (xy 466.808312 -32.23523) (xy 466.80882 -32.29991) (xy 466.80882 -33.90011)
			(xy 466.808312 -33.96479) (xy 466.800189 -34.093896) (xy 466.783976 -34.222236) (xy 466.759736 -34.349306)
			(xy 466.727566 -34.474602) (xy 466.687591 -34.597632) (xy 466.63997 -34.717908) (xy 466.584891 -34.834957)
			(xy 466.522571 -34.948317) (xy 466.453256 -35.05754) (xy 466.37722 -35.162195) (xy 466.294762 -35.261869)
			(xy 466.206209 -35.356169) (xy 466.111909 -35.444722) (xy 466.012235 -35.52718) (xy 465.90758 -35.603216)
			(xy 465.798357 -35.672531) (xy 465.684997 -35.734851) (xy 465.567948 -35.78993) (xy 465.447672 -35.837551)
			(xy 465.324642 -35.877526) (xy 465.199346 -35.909696) (xy 465.072276 -35.933936) (xy 464.943936 -35.950149)
			(xy 464.81483 -35.958272) (xy 464.68547 -35.958272) (xy 464.556364 -35.950149) (xy 464.428024 -35.933936)
			(xy 464.300954 -35.909696) (xy 464.175658 -35.877526) (xy 464.052628 -35.837551) (xy 463.932352 -35.78993)
			(xy 463.815303 -35.734851) (xy 463.701943 -35.672531) (xy 463.59272 -35.603216) (xy 463.488065 -35.52718)
			(xy 463.388391 -35.444722) (xy 463.294091 -35.356169) (xy 463.205538 -35.261869) (xy 463.12308 -35.162195)
			(xy 463.047044 -35.05754) (xy 462.977729 -34.948317) (xy 462.915409 -34.834957) (xy 462.86033 -34.717908)
			(xy 462.812709 -34.597632) (xy 462.772734 -34.474602) (xy 462.740564 -34.349306) (xy 462.716324 -34.222236)
			(xy 462.700111 -34.093896) (xy 462.691988 -33.96479) (xy 462.69148 -33.90011) (xy 259.230448 -33.90011)
			(xy 259.230056 -33.901828) (xy 259.191086 -34.03709) (xy 259.144594 -34.169955) (xy 259.090726 -34.300003)
			(xy 259.02965 -34.426827) (xy 258.961559 -34.550026) (xy 258.886668 -34.669214) (xy 258.805211 -34.784015)
			(xy 258.717446 -34.894068) (xy 258.623648 -34.999027) (xy 258.524113 -35.098562) (xy 258.419153 -35.192359)
			(xy 258.324611 -35.267753) (xy 356.989346 -35.267753) (xy 356.989346 -35.213247) (xy 356.997102 -35.159297)
			(xy 357.012458 -35.106999) (xy 357.035099 -35.057419) (xy 357.064566 -35.011566) (xy 357.100259 -34.970373)
			(xy 357.14145 -34.934678) (xy 357.187302 -34.905209) (xy 357.236881 -34.882565) (xy 357.289177 -34.867207)
			(xy 357.343127 -34.859447) (xy 357.37038 -34.85896) (xy 358.23398 -34.85896) (xy 358.261232 -34.859486)
			(xy 358.31518 -34.86724) (xy 358.367476 -34.882593) (xy 358.417054 -34.905232) (xy 358.462906 -34.934697)
			(xy 358.504098 -34.970388) (xy 358.539791 -35.011578) (xy 358.569258 -35.057428) (xy 358.5919 -35.107005)
			(xy 358.607256 -35.1593) (xy 358.615013 -35.213249) (xy 358.615013 -35.267751) (xy 358.607256 -35.3217)
			(xy 358.5919 -35.373995) (xy 358.569258 -35.423572) (xy 358.539791 -35.469422) (xy 358.504098 -35.510612)
			(xy 358.462906 -35.546303) (xy 358.417054 -35.575768) (xy 358.367476 -35.598407) (xy 358.31518 -35.61376)
			(xy 358.261232 -35.621514) (xy 358.23398 -35.621976) (xy 357.37038 -35.621976) (xy 357.343127 -35.621553)
			(xy 357.289177 -35.613793) (xy 357.236881 -35.598435) (xy 357.187302 -35.575791) (xy 357.14145 -35.546322)
			(xy 357.100259 -35.510627) (xy 357.064566 -35.469434) (xy 357.035099 -35.423581) (xy 357.012458 -35.374001)
			(xy 356.997102 -35.321703) (xy 356.989346 -35.267753) (xy 258.324611 -35.267753) (xy 258.309099 -35.280123)
			(xy 258.194297 -35.361579) (xy 258.075109 -35.436469) (xy 257.951909 -35.504559) (xy 257.825085 -35.565634)
			(xy 257.695036 -35.619502) (xy 257.562171 -35.665993) (xy 257.426909 -35.704961) (xy 257.289674 -35.736283)
			(xy 257.150899 -35.759862) (xy 257.01102 -35.775622) (xy 256.870478 -35.783514) (xy 256.800096 -35.784028)
			(xy 225.300032 -35.784028) (xy 225.229649 -35.783544) (xy 225.089104 -35.775653) (xy 224.949222 -35.759894)
			(xy 224.810444 -35.736316) (xy 224.673207 -35.704995) (xy 224.537941 -35.666027) (xy 224.405074 -35.619536)
			(xy 224.275022 -35.565669) (xy 224.148195 -35.504594) (xy 224.024992 -35.436504) (xy 223.905801 -35.361613)
			(xy 223.790997 -35.280156) (xy 223.68094 -35.192391) (xy 223.575978 -35.098593) (xy 223.47644 -34.999057)
			(xy 223.38264 -34.894096) (xy 223.294872 -34.784042) (xy 223.213414 -34.669239) (xy 223.138521 -34.550049)
			(xy 223.070428 -34.426848) (xy 223.009351 -34.300022) (xy 222.955481 -34.169971) (xy 222.908988 -34.037104)
			(xy 222.870017 -33.90184) (xy 222.838693 -33.764603) (xy 222.815113 -33.625825) (xy 222.799351 -33.485944)
			(xy 222.791457 -33.345399) (xy 222.79102 -33.275016) (xy 222.79102 -13.780008) (xy 222.790499 -13.724238)
			(xy 222.782164 -13.613011) (xy 222.765541 -13.502717) (xy 222.740722 -13.393974) (xy 222.707846 -13.287389)
			(xy 222.667097 -13.183559) (xy 222.618703 -13.083065) (xy 222.562935 -12.986469) (xy 222.500103 -12.894309)
			(xy 222.430561 -12.807103) (xy 222.354696 -12.725338) (xy 222.272933 -12.64947) (xy 222.185729 -12.579925)
			(xy 222.093572 -12.517091) (xy 221.996977 -12.461319) (xy 221.896485 -12.412922) (xy 221.792656 -12.37217)
			(xy 221.686073 -12.339291) (xy 221.57733 -12.314468) (xy 221.467037 -12.297841) (xy 221.35581 -12.289503)
			(xy 221.30004 -12.289028) (xy 196.701918 -12.289028) (xy 196.631535 -12.288544) (xy 196.49099 -12.280652)
			(xy 196.35111 -12.264892) (xy 196.212332 -12.241314) (xy 196.075095 -12.209992) (xy 195.939831 -12.171024)
			(xy 195.806964 -12.124532) (xy 195.676913 -12.070665) (xy 195.550086 -12.009589) (xy 195.426884 -11.941499)
			(xy 195.307694 -11.866608) (xy 195.19289 -11.785152) (xy 195.082834 -11.697386) (xy 194.977873 -11.603588)
			(xy 194.878335 -11.504052) (xy 194.784536 -11.399092) (xy 194.696769 -11.289037) (xy 194.615311 -11.174234)
			(xy 194.540418 -11.055045) (xy 194.472326 -10.931844) (xy 194.411249 -10.805018) (xy 194.35738 -10.674968)
			(xy 194.310887 -10.542102) (xy 194.271917 -10.406837) (xy 194.240593 -10.269601) (xy 194.217013 -10.130824)
			(xy 194.201251 -9.990943) (xy 194.193357 -9.850399) (xy 194.192906 -9.780016) (xy 194.192906 -6.279896)
			(xy 194.19238 -6.247749) (xy 194.183988 -6.184006) (xy 194.167348 -6.121904) (xy 194.142744 -6.062504)
			(xy 194.110598 -6.006824) (xy 194.07146 -5.955816) (xy 194.025999 -5.910353) (xy 193.974992 -5.871213)
			(xy 193.919314 -5.839064) (xy 193.859915 -5.814458) (xy 193.797813 -5.797816) (xy 193.734071 -5.789421)
			(xy 193.701924 -5.788914) (xy 127.102108 -5.788914) (xy 127.06996 -5.789416) (xy 127.006214 -5.797808)
			(xy 126.944108 -5.814448) (xy 126.884706 -5.839052) (xy 126.829023 -5.8712) (xy 126.778013 -5.91034)
			(xy 126.732548 -5.955804) (xy 126.693406 -6.006813) (xy 126.661257 -6.062495) (xy 126.636652 -6.121897)
			(xy 126.62001 -6.184002) (xy 126.611617 -6.247748) (xy 126.611126 -6.279896) (xy 126.611126 -9.780016)
			(xy 126.610632 -9.850398) (xy 126.602738 -9.990941) (xy 126.586977 -10.13082) (xy 126.563397 -10.269595)
			(xy 126.532074 -10.40683) (xy 126.519617 -10.450068) (xy 127.350273 -10.450068) (xy 127.354278 -10.36216)
			(xy 127.366261 -10.27498) (xy 127.386121 -10.189251) (xy 127.413696 -10.105683) (xy 127.448755 -10.024969)
			(xy 127.491008 -9.947777) (xy 127.540106 -9.874748) (xy 127.595642 -9.806486) (xy 127.657154 -9.743556)
			(xy 127.724135 -9.686482) (xy 127.796028 -9.635734) (xy 127.872237 -9.591734) (xy 127.952132 -9.554847)
			(xy 128.035051 -9.525378) (xy 128.120306 -9.503571) (xy 128.20719 -9.489607) (xy 128.294984 -9.483601)
			(xy 128.382961 -9.485605) (xy 128.470391 -9.4956) (xy 128.55655 -9.513504) (xy 128.640724 -9.539168)
			(xy 128.722215 -9.572381) (xy 128.800349 -9.612867) (xy 128.874477 -9.660289) (xy 128.943985 -9.714256)
			(xy 129.008299 -9.774321) (xy 129.066883 -9.839985) (xy 129.119254 -9.910704) (xy 129.164977 -9.985892)
			(xy 129.203674 -10.064927) (xy 129.235023 -10.147153) (xy 129.258765 -10.231889) (xy 129.265884 -10.270548)
			(xy 131.63909 -10.270548) (xy 131.63909 -10.216052) (xy 131.646845 -10.16211) (xy 131.662198 -10.10982)
			(xy 131.684835 -10.060247) (xy 131.714296 -10.014401) (xy 131.749982 -9.973213) (xy 131.791165 -9.937522)
			(xy 131.837009 -9.908056) (xy 131.886579 -9.885413) (xy 131.938866 -9.870055) (xy 131.992808 -9.862293)
			(xy 132.020056 -9.861804) (xy 132.883656 -9.861804) (xy 132.910912 -9.86224) (xy 132.964869 -9.869992)
			(xy 133.017174 -9.885345) (xy 133.066761 -9.907985) (xy 133.112622 -9.937453) (xy 133.153821 -9.973148)
			(xy 133.18952 -10.014343) (xy 133.218993 -10.0602) (xy 133.24164 -10.109785) (xy 133.256999 -10.162088)
			(xy 133.264757 -10.216044) (xy 133.264757 -10.270556) (xy 133.256999 -10.324512) (xy 133.24164 -10.376815)
			(xy 133.218993 -10.4264) (xy 133.18952 -10.472257) (xy 133.153821 -10.513452) (xy 133.112622 -10.549147)
			(xy 133.066761 -10.578615) (xy 133.017174 -10.601255) (xy 132.964869 -10.616608) (xy 132.910912 -10.62436)
			(xy 132.883656 -10.62482) (xy 132.020056 -10.62482) (xy 131.992808 -10.624307) (xy 131.938866 -10.616545)
			(xy 131.886579 -10.601187) (xy 131.837009 -10.578544) (xy 131.791165 -10.549078) (xy 131.749982 -10.513387)
			(xy 131.714296 -10.472199) (xy 131.684835 -10.426353) (xy 131.662198 -10.37678) (xy 131.646845 -10.32449)
			(xy 131.63909 -10.270548) (xy 129.265884 -10.270548) (xy 129.274703 -10.318433) (xy 129.282705 -10.406068)
			(xy 129.283206 -10.450068) (xy 129.282705 -10.494068) (xy 129.274703 -10.581703) (xy 129.258765 -10.668247)
			(xy 129.235023 -10.752983) (xy 129.203674 -10.835209) (xy 129.164977 -10.914244) (xy 129.119254 -10.989432)
			(xy 129.087321 -11.032553) (xy 168.158867 -11.032553) (xy 168.158867 -10.978047) (xy 168.166625 -10.924096)
			(xy 168.181981 -10.871798) (xy 168.204625 -10.822218) (xy 168.234094 -10.776365) (xy 168.269789 -10.735173)
			(xy 168.310983 -10.699481) (xy 168.356837 -10.670014) (xy 168.406419 -10.647374) (xy 168.458717 -10.63202)
			(xy 168.512669 -10.624266) (xy 168.539922 -10.623804) (xy 169.403522 -10.623804) (xy 169.430773 -10.624267)
			(xy 169.48472 -10.632027) (xy 169.537014 -10.647384) (xy 169.58659 -10.670027) (xy 169.632439 -10.699495)
			(xy 169.673628 -10.735188) (xy 169.709318 -10.776379) (xy 169.738783 -10.822229) (xy 169.761424 -10.871807)
			(xy 169.776778 -10.924101) (xy 169.784534 -10.978049) (xy 169.784534 -11.032551) (xy 169.776778 -11.086499)
			(xy 169.761424 -11.138793) (xy 169.738783 -11.188371) (xy 169.709318 -11.234221) (xy 169.673628 -11.275412)
			(xy 169.632439 -11.311105) (xy 169.58659 -11.340573) (xy 169.537014 -11.363216) (xy 169.48472 -11.378573)
			(xy 169.430773 -11.386333) (xy 169.403522 -11.38682) (xy 168.539922 -11.38682) (xy 168.512669 -11.386334)
			(xy 168.458717 -11.37858) (xy 168.406419 -11.363226) (xy 168.356837 -11.340586) (xy 168.310983 -11.311119)
			(xy 168.269789 -11.275427) (xy 168.234094 -11.234235) (xy 168.204625 -11.188382) (xy 168.181981 -11.138802)
			(xy 168.166625 -11.086504) (xy 168.158867 -11.032553) (xy 129.087321 -11.032553) (xy 129.066883 -11.060151)
			(xy 129.008299 -11.125815) (xy 128.943985 -11.18588) (xy 128.874477 -11.239847) (xy 128.800349 -11.287269)
			(xy 128.722215 -11.327755) (xy 128.640724 -11.360968) (xy 128.55655 -11.386632) (xy 128.470391 -11.404536)
			(xy 128.382961 -11.414531) (xy 128.294984 -11.416535) (xy 128.20719 -11.410529) (xy 128.120306 -11.396565)
			(xy 128.035051 -11.374758) (xy 127.952132 -11.345289) (xy 127.872237 -11.308402) (xy 127.796028 -11.264402)
			(xy 127.724135 -11.213654) (xy 127.657154 -11.15658) (xy 127.595642 -11.09365) (xy 127.540106 -11.025388)
			(xy 127.491008 -10.952359) (xy 127.448755 -10.875167) (xy 127.413696 -10.794453) (xy 127.386121 -10.710885)
			(xy 127.366261 -10.625156) (xy 127.354278 -10.537976) (xy 127.350273 -10.450068) (xy 126.519617 -10.450068)
			(xy 126.493105 -10.542092) (xy 126.446613 -10.674957) (xy 126.392744 -10.805006) (xy 126.331668 -10.93183)
			(xy 126.263578 -11.05503) (xy 126.188687 -11.174218) (xy 126.10723 -11.28902) (xy 126.019465 -11.399074)
			(xy 125.973895 -11.450066) (xy 191.515245 -11.450066) (xy 191.51925 -11.362158) (xy 191.531233 -11.274978)
			(xy 191.551093 -11.189249) (xy 191.578668 -11.105681) (xy 191.613727 -11.024967) (xy 191.65598 -10.947775)
			(xy 191.705078 -10.874746) (xy 191.760614 -10.806484) (xy 191.822126 -10.743554) (xy 191.889107 -10.68648)
			(xy 191.961 -10.635732) (xy 192.037209 -10.591732) (xy 192.117104 -10.554845) (xy 192.200023 -10.525376)
			(xy 192.285278 -10.503569) (xy 192.372162 -10.489605) (xy 192.459956 -10.483599) (xy 192.547933 -10.485603)
			(xy 192.635363 -10.495598) (xy 192.721522 -10.513502) (xy 192.805696 -10.539166) (xy 192.887187 -10.572379)
			(xy 192.965321 -10.612865) (xy 193.039449 -10.660287) (xy 193.108957 -10.714254) (xy 193.173271 -10.774319)
			(xy 193.231855 -10.839983) (xy 193.284226 -10.910702) (xy 193.329949 -10.98589) (xy 193.368646 -11.064925)
			(xy 193.399995 -11.147151) (xy 193.423737 -11.231887) (xy 193.439675 -11.318431) (xy 193.447677 -11.406066)
			(xy 193.448178 -11.450066) (xy 193.447677 -11.494066) (xy 193.439675 -11.581701) (xy 193.423737 -11.668245)
			(xy 193.399995 -11.752981) (xy 193.368646 -11.835207) (xy 193.329949 -11.914242) (xy 193.284226 -11.98943)
			(xy 193.231855 -12.060149) (xy 193.173271 -12.125813) (xy 193.108957 -12.185878) (xy 193.039449 -12.239845)
			(xy 192.965321 -12.287267) (xy 192.887187 -12.327753) (xy 192.805696 -12.360966) (xy 192.721522 -12.38663)
			(xy 192.635363 -12.404534) (xy 192.547933 -12.414529) (xy 192.459956 -12.416533) (xy 192.372162 -12.410527)
			(xy 192.285278 -12.396563) (xy 192.200023 -12.374756) (xy 192.117104 -12.345287) (xy 192.037209 -12.3084)
			(xy 191.961 -12.2644) (xy 191.889107 -12.213652) (xy 191.822126 -12.156578) (xy 191.760614 -12.093648)
			(xy 191.705078 -12.025386) (xy 191.65598 -11.952357) (xy 191.613727 -11.875165) (xy 191.578668 -11.794451)
			(xy 191.551093 -11.710883) (xy 191.531233 -11.625154) (xy 191.51925 -11.537974) (xy 191.515245 -11.450066)
			(xy 125.973895 -11.450066) (xy 125.925667 -11.504033) (xy 125.826132 -11.603569) (xy 125.721172 -11.697366)
			(xy 125.611118 -11.785131) (xy 125.496317 -11.866588) (xy 125.377128 -11.941479) (xy 125.253928 -12.009569)
			(xy 125.206611 -12.032356) (xy 166.354411 -12.032356) (xy 166.354411 -11.977844) (xy 166.362169 -11.923886)
			(xy 166.377527 -11.871582) (xy 166.400173 -11.821995) (xy 166.429645 -11.776137) (xy 166.465343 -11.734939)
			(xy 166.506541 -11.699241) (xy 166.552401 -11.66977) (xy 166.601987 -11.647125) (xy 166.654292 -11.631768)
			(xy 166.70825 -11.624011) (xy 166.735506 -11.623548) (xy 167.599106 -11.623548) (xy 167.626354 -11.624123)
			(xy 167.680295 -11.631879) (xy 167.732583 -11.647233) (xy 167.782153 -11.669872) (xy 167.827998 -11.699335)
			(xy 167.869182 -11.735022) (xy 167.904869 -11.776207) (xy 167.934331 -11.822052) (xy 167.956969 -11.871623)
			(xy 167.972322 -11.923911) (xy 167.980078 -11.977852) (xy 167.980078 -12.032348) (xy 167.980077 -12.032358)
			(xy 169.954311 -12.032358) (xy 169.954311 -11.977842) (xy 169.96207 -11.92388) (xy 169.97743 -11.871573)
			(xy 170.000079 -11.821984) (xy 170.029555 -11.776123) (xy 170.065258 -11.734924) (xy 170.106461 -11.699226)
			(xy 170.152326 -11.669756) (xy 170.201918 -11.647114) (xy 170.254227 -11.63176) (xy 170.30819 -11.624008)
			(xy 170.335448 -11.623548) (xy 171.199048 -11.623548) (xy 171.226294 -11.624125) (xy 171.28023 -11.631887)
			(xy 171.332513 -11.647244) (xy 171.382078 -11.669885) (xy 171.427917 -11.699349) (xy 171.469097 -11.735037)
			(xy 171.504779 -11.776221) (xy 171.534238 -11.822064) (xy 171.556873 -11.871632) (xy 171.572224 -11.923917)
			(xy 171.579978 -11.977854) (xy 171.579978 -12.032346) (xy 171.572224 -12.086283) (xy 171.556873 -12.138568)
			(xy 171.534238 -12.188136) (xy 171.504779 -12.233979) (xy 171.469097 -12.275163) (xy 171.427917 -12.310851)
			(xy 171.382078 -12.340315) (xy 171.332513 -12.362956) (xy 171.28023 -12.378313) (xy 171.226294 -12.386075)
			(xy 171.199048 -12.386564) (xy 170.335448 -12.386564) (xy 170.30819 -12.386192) (xy 170.254227 -12.37844)
			(xy 170.201918 -12.363086) (xy 170.152326 -12.340444) (xy 170.106461 -12.310974) (xy 170.065258 -12.275276)
			(xy 170.029555 -12.234077) (xy 170.000079 -12.188216) (xy 169.97743 -12.138627) (xy 169.96207 -12.08632)
			(xy 169.954311 -12.032358) (xy 167.980077 -12.032358) (xy 167.972322 -12.086289) (xy 167.956969 -12.138577)
			(xy 167.934331 -12.188148) (xy 167.904869 -12.233993) (xy 167.869182 -12.275178) (xy 167.827998 -12.310865)
			(xy 167.782153 -12.340328) (xy 167.732583 -12.362967) (xy 167.680295 -12.378321) (xy 167.626354 -12.386077)
			(xy 167.599106 -12.386564) (xy 166.735506 -12.386564) (xy 166.70825 -12.386189) (xy 166.654292 -12.378432)
			(xy 166.601987 -12.363075) (xy 166.552401 -12.34043) (xy 166.506541 -12.310959) (xy 166.465343 -12.275261)
			(xy 166.429645 -12.234063) (xy 166.400173 -12.188205) (xy 166.377527 -12.138618) (xy 166.362169 -12.086314)
			(xy 166.354411 -12.032356) (xy 125.206611 -12.032356) (xy 125.127104 -12.070645) (xy 124.997055 -12.124513)
			(xy 124.86419 -12.171005) (xy 124.728928 -12.209974) (xy 124.591693 -12.241298) (xy 124.452918 -12.264877)
			(xy 124.313039 -12.280639) (xy 124.172496 -12.288532) (xy 124.102114 -12.289028) (xy 83.70189 -12.289028)
			(xy 83.631508 -12.288534) (xy 83.490965 -12.280641) (xy 83.351086 -12.26488) (xy 83.21231 -12.2413)
			(xy 83.075075 -12.209977) (xy 82.939812 -12.171008) (xy 82.806947 -12.124516) (xy 82.676898 -12.070648)
			(xy 82.550073 -12.009572) (xy 82.426873 -11.941482) (xy 82.307684 -11.866591) (xy 82.192882 -11.785134)
			(xy 82.082828 -11.697369) (xy 81.977868 -11.603571) (xy 81.878333 -11.504036) (xy 81.784535 -11.399076)
			(xy 81.696769 -11.289022) (xy 81.615313 -11.174221) (xy 81.540421 -11.055032) (xy 81.47233 -10.931832)
			(xy 81.411254 -10.805008) (xy 81.357386 -10.674959) (xy 81.310894 -10.542094) (xy 81.271924 -10.406831)
			(xy 81.240601 -10.269596) (xy 81.217021 -10.13082) (xy 81.20126 -9.990941) (xy 81.193366 -9.850398)
			(xy 81.192878 -9.780016) (xy 81.192878 -0.999998) (xy 81.192375 -0.96785) (xy 81.183982 -0.904106)
			(xy 81.167341 -0.842001) (xy 81.142736 -0.782601) (xy 81.110589 -0.72692) (xy 81.071448 -0.675911)
			(xy 81.025984 -0.630448) (xy 80.974975 -0.591308) (xy 80.919294 -0.559161) (xy 80.859893 -0.534557)
			(xy 80.797789 -0.517916) (xy 80.734044 -0.509525) (xy 80.701896 -0.509016) (xy 14.10208 -0.509016)
			(xy 14.069935 -0.509543) (xy 14.006194 -0.517937) (xy 13.944095 -0.534579) (xy 13.884698 -0.559184)
			(xy 13.829022 -0.59133) (xy 13.778017 -0.630469) (xy 13.732558 -0.675931) (xy 13.69342 -0.726937)
			(xy 13.661276 -0.782614) (xy 13.636673 -0.842012) (xy 13.620034 -0.904112) (xy 13.611642 -0.967853)
			(xy 13.611098 -0.999998) (xy 13.611098 -5.184498) (xy 14.350702 -5.184498) (xy 14.35331 -5.097781)
			(xy 14.363685 -5.011647) (xy 14.381743 -4.926791) (xy 14.40734 -4.843896) (xy 14.440268 -4.763631)
			(xy 14.480262 -4.686643) (xy 14.526999 -4.613552) (xy 14.580104 -4.544948) (xy 14.639148 -4.481383)
			(xy 14.703655 -4.42337) (xy 14.738096 -4.396994) (xy 14.773029 -4.371293) (xy 14.846784 -4.325653)
			(xy 14.924335 -4.28681) (xy 15.005056 -4.255076) (xy 15.088297 -4.230709) (xy 15.173387 -4.213903)
			(xy 15.259642 -4.204794) (xy 15.346366 -4.203455) (xy 15.432861 -4.209898) (xy 15.518429 -4.224071)
			(xy 15.602382 -4.245858) (xy 15.684044 -4.275086) (xy 15.762756 -4.311517) (xy 15.837884 -4.35486)
			(xy 15.908824 -4.404764) (xy 15.975003 -4.460828) (xy 16.035889 -4.5226) (xy 16.090991 -4.589582)
			(xy 16.139865 -4.661235) (xy 16.182118 -4.736981) (xy 16.217409 -4.816211) (xy 16.245454 -4.898286)
			(xy 16.266027 -4.982545) (xy 16.267136 -4.989901) (xy 20.44038 -4.989901) (xy 20.44038 -4.935399)
			(xy 20.448136 -4.881452) (xy 20.463491 -4.829158) (xy 20.486132 -4.779581) (xy 20.515597 -4.733731)
			(xy 20.551288 -4.692541) (xy 20.592478 -4.65685) (xy 20.638328 -4.627384) (xy 20.687904 -4.604742)
			(xy 20.740198 -4.589387) (xy 20.794145 -4.58163) (xy 20.821396 -4.581144) (xy 21.684996 -4.581144)
			(xy 21.712249 -4.581603) (xy 21.766201 -4.58936) (xy 21.818499 -4.604715) (xy 21.86808 -4.627358)
			(xy 21.913934 -4.656826) (xy 21.955128 -4.69252) (xy 21.990822 -4.733713) (xy 22.02029 -4.779566)
			(xy 22.042933 -4.829147) (xy 22.05829 -4.881445) (xy 22.066047 -4.935397) (xy 22.066047 -4.989901)
			(xy 24.04032 -4.989901) (xy 24.04032 -4.935399) (xy 24.048076 -4.881452) (xy 24.063431 -4.829157)
			(xy 24.086072 -4.779581) (xy 24.115538 -4.73373) (xy 24.151229 -4.692541) (xy 24.192419 -4.656849)
			(xy 24.238269 -4.627383) (xy 24.287846 -4.604742) (xy 24.34014 -4.589387) (xy 24.394087 -4.58163)
			(xy 24.421338 -4.581144) (xy 25.284938 -4.581144) (xy 25.312191 -4.581603) (xy 25.366143 -4.58936)
			(xy 25.418441 -4.604716) (xy 25.468021 -4.627358) (xy 25.513875 -4.656827) (xy 25.555068 -4.69252)
			(xy 25.590762 -4.733713) (xy 25.620231 -4.779567) (xy 25.642873 -4.829147) (xy 25.65823 -4.881446)
			(xy 25.665987 -4.935397) (xy 25.665987 -4.989903) (xy 25.66598 -4.989954) (xy 27.64023 -4.989954)
			(xy 27.64023 -4.935446) (xy 27.647987 -4.881493) (xy 27.663343 -4.829194) (xy 27.685985 -4.779612)
			(xy 27.715454 -4.733756) (xy 27.751147 -4.692562) (xy 27.79234 -4.656866) (xy 27.838194 -4.627395)
			(xy 27.887775 -4.60475) (xy 27.940074 -4.589391) (xy 27.994026 -4.581631) (xy 28.02128 -4.581144)
			(xy 28.88488 -4.581144) (xy 28.91213 -4.581702) (xy 28.966077 -4.589456) (xy 29.01837 -4.604808)
			(xy 29.067947 -4.627446) (xy 29.113797 -4.65691) (xy 29.154986 -4.692599) (xy 29.190678 -4.733787)
			(xy 29.220144 -4.779636) (xy 29.242785 -4.829211) (xy 29.25814 -4.881504) (xy 29.265897 -4.93545)
			(xy 29.265897 -4.98995) (xy 29.265896 -4.989954) (xy 31.24043 -4.989954) (xy 31.24043 -4.935446)
			(xy 31.248187 -4.881494) (xy 31.263543 -4.829195) (xy 31.286185 -4.779613) (xy 31.315653 -4.733758)
			(xy 31.351346 -4.692563) (xy 31.392538 -4.656867) (xy 31.438392 -4.627396) (xy 31.487972 -4.604751)
			(xy 31.540271 -4.589392) (xy 31.594222 -4.581632) (xy 31.621476 -4.581144) (xy 32.485076 -4.581144)
			(xy 32.512327 -4.581702) (xy 32.566273 -4.589455) (xy 32.618567 -4.604807) (xy 32.668144 -4.627445)
			(xy 32.713995 -4.656909) (xy 32.755185 -4.692598) (xy 32.790877 -4.733786) (xy 32.820343 -4.779635)
			(xy 32.842985 -4.82921) (xy 32.85834 -4.881503) (xy 32.866097 -4.935449) (xy 32.866097 -4.989951)
			(xy 32.866096 -4.989958) (xy 40.350307 -4.989958) (xy 40.350307 -4.935442) (xy 40.358066 -4.881481)
			(xy 40.373426 -4.829173) (xy 40.396074 -4.779584) (xy 40.42555 -4.733723) (xy 40.461252 -4.692524)
			(xy 40.502455 -4.656826) (xy 40.548319 -4.627355) (xy 40.59791 -4.604712) (xy 40.65022 -4.589358)
			(xy 40.704182 -4.581604) (xy 40.73144 -4.581144) (xy 41.59504 -4.581144) (xy 41.622286 -4.581729)
			(xy 41.676222 -4.589489) (xy 41.728506 -4.604846) (xy 41.778072 -4.627486) (xy 41.823911 -4.65695)
			(xy 41.865091 -4.692637) (xy 41.900774 -4.733821) (xy 41.930233 -4.779663) (xy 41.952868 -4.829232)
			(xy 41.968219 -4.881517) (xy 41.975974 -4.935454) (xy 41.975974 -4.989946) (xy 41.975973 -4.989954)
			(xy 43.95033 -4.989954) (xy 43.95033 -4.935446) (xy 43.958087 -4.881493) (xy 43.973443 -4.829193)
			(xy 43.996086 -4.779611) (xy 44.025554 -4.733756) (xy 44.061248 -4.692561) (xy 44.102441 -4.656865)
			(xy 44.148295 -4.627394) (xy 44.197876 -4.604749) (xy 44.250176 -4.589391) (xy 44.304128 -4.581631)
			(xy 44.331382 -4.581144) (xy 45.194982 -4.581144) (xy 45.222232 -4.581702) (xy 45.276178 -4.589456)
			(xy 45.328472 -4.604808) (xy 45.378048 -4.627447) (xy 45.423898 -4.656911) (xy 45.465087 -4.6926)
			(xy 45.500778 -4.733788) (xy 45.530244 -4.779636) (xy 45.552885 -4.829211) (xy 45.56824 -4.881504)
			(xy 45.575997 -4.93545) (xy 45.575997 -4.98995) (xy 45.575996 -4.989954) (xy 51.56043 -4.989954)
			(xy 51.56043 -4.935446) (xy 51.568187 -4.881494) (xy 51.583543 -4.829195) (xy 51.606185 -4.779613)
			(xy 51.635653 -4.733758) (xy 51.671346 -4.692563) (xy 51.712538 -4.656867) (xy 51.758392 -4.627396)
			(xy 51.807972 -4.604751) (xy 51.860271 -4.589392) (xy 51.914222 -4.581632) (xy 51.941476 -4.581144)
			(xy 52.805076 -4.581144) (xy 52.832327 -4.581702) (xy 52.886273 -4.589455) (xy 52.938567 -4.604807)
			(xy 52.988144 -4.627445) (xy 53.033995 -4.656909) (xy 53.075185 -4.692598) (xy 53.110877 -4.733786)
			(xy 53.140343 -4.779635) (xy 53.162985 -4.82921) (xy 53.17834 -4.881503) (xy 53.186097 -4.935449)
			(xy 53.186097 -4.989951) (xy 53.186096 -4.989957) (xy 55.160307 -4.989957) (xy 55.160307 -4.935443)
			(xy 55.168065 -4.881484) (xy 55.183424 -4.829178) (xy 55.206071 -4.77959) (xy 55.235544 -4.73373)
			(xy 55.271245 -4.692532) (xy 55.312445 -4.656834) (xy 55.358306 -4.627362) (xy 55.407894 -4.604718)
			(xy 55.460201 -4.589362) (xy 55.514161 -4.581606) (xy 55.541418 -4.581144) (xy 56.405018 -4.581144)
			(xy 56.432265 -4.581727) (xy 56.486204 -4.589485) (xy 56.53849 -4.60484) (xy 56.588058 -4.627479)
			(xy 56.633901 -4.656942) (xy 56.675084 -4.692629) (xy 56.710769 -4.733814) (xy 56.74023 -4.779657)
			(xy 56.762867 -4.829227) (xy 56.778219 -4.881514) (xy 56.785974 -4.935453) (xy 56.785974 -4.989947)
			(xy 56.778219 -5.043886) (xy 56.762867 -5.096173) (xy 56.74023 -5.145743) (xy 56.710769 -5.191586)
			(xy 56.675084 -5.232771) (xy 56.633901 -5.268458) (xy 56.588058 -5.297921) (xy 56.53849 -5.32056)
			(xy 56.486204 -5.335915) (xy 56.432265 -5.343673) (xy 56.405018 -5.34416) (xy 55.541418 -5.34416)
			(xy 55.514161 -5.343794) (xy 55.460201 -5.336038) (xy 55.407894 -5.320682) (xy 55.358306 -5.298038)
			(xy 55.312445 -5.268566) (xy 55.271245 -5.232868) (xy 55.235544 -5.19167) (xy 55.206071 -5.14581)
			(xy 55.183424 -5.096222) (xy 55.168065 -5.043916) (xy 55.160307 -4.989957) (xy 53.186096 -4.989957)
			(xy 53.17834 -5.043897) (xy 53.162985 -5.09619) (xy 53.140343 -5.145765) (xy 53.110877 -5.191614)
			(xy 53.075185 -5.232802) (xy 53.033995 -5.268491) (xy 52.988144 -5.297955) (xy 52.938567 -5.320593)
			(xy 52.886273 -5.335945) (xy 52.832327 -5.343698) (xy 52.805076 -5.34416) (xy 51.941476 -5.34416)
			(xy 51.914222 -5.343768) (xy 51.860271 -5.336008) (xy 51.807972 -5.320649) (xy 51.758392 -5.298004)
			(xy 51.712538 -5.268533) (xy 51.671346 -5.232837) (xy 51.635653 -5.191642) (xy 51.606185 -5.145787)
			(xy 51.583543 -5.096205) (xy 51.568187 -5.043906) (xy 51.56043 -4.989954) (xy 45.575996 -4.989954)
			(xy 45.56824 -5.043896) (xy 45.552885 -5.096189) (xy 45.530244 -5.145764) (xy 45.500778 -5.191612)
			(xy 45.465087 -5.2328) (xy 45.423898 -5.268489) (xy 45.378048 -5.297953) (xy 45.328472 -5.320592)
			(xy 45.276178 -5.335944) (xy 45.222232 -5.343698) (xy 45.194982 -5.34416) (xy 44.331382 -5.34416)
			(xy 44.304128 -5.343769) (xy 44.250176 -5.336009) (xy 44.197876 -5.320651) (xy 44.148295 -5.298006)
			(xy 44.102441 -5.268535) (xy 44.061248 -5.232839) (xy 44.025554 -5.191644) (xy 43.996086 -5.145789)
			(xy 43.973443 -5.096207) (xy 43.958087 -5.043907) (xy 43.95033 -4.989954) (xy 41.975973 -4.989954)
			(xy 41.968219 -5.043883) (xy 41.952868 -5.096168) (xy 41.930233 -5.145737) (xy 41.900774 -5.191579)
			(xy 41.865091 -5.232763) (xy 41.823911 -5.26845) (xy 41.778072 -5.297914) (xy 41.728506 -5.320554)
			(xy 41.676222 -5.335911) (xy 41.622286 -5.343671) (xy 41.59504 -5.34416) (xy 40.73144 -5.34416) (xy 40.704182 -5.343796)
			(xy 40.65022 -5.336042) (xy 40.59791 -5.320688) (xy 40.548319 -5.298045) (xy 40.502455 -5.268574)
			(xy 40.461252 -5.232876) (xy 40.42555 -5.191677) (xy 40.396074 -5.145816) (xy 40.373426 -5.096227)
			(xy 40.358066 -5.043919) (xy 40.350307 -4.989958) (xy 32.866096 -4.989958) (xy 32.85834 -5.043897)
			(xy 32.842985 -5.09619) (xy 32.820343 -5.145765) (xy 32.790877 -5.191614) (xy 32.755185 -5.232802)
			(xy 32.713995 -5.268491) (xy 32.668144 -5.297955) (xy 32.618567 -5.320593) (xy 32.566273 -5.335945)
			(xy 32.512327 -5.343698) (xy 32.485076 -5.34416) (xy 31.621476 -5.34416) (xy 31.594222 -5.343768)
			(xy 31.540271 -5.336008) (xy 31.487972 -5.320649) (xy 31.438392 -5.298004) (xy 31.392538 -5.268533)
			(xy 31.351346 -5.232837) (xy 31.315653 -5.191642) (xy 31.286185 -5.145787) (xy 31.263543 -5.096205)
			(xy 31.248187 -5.043906) (xy 31.24043 -4.989954) (xy 29.265896 -4.989954) (xy 29.25814 -5.043896)
			(xy 29.242785 -5.096189) (xy 29.220144 -5.145764) (xy 29.190678 -5.191613) (xy 29.154986 -5.232801)
			(xy 29.113797 -5.26849) (xy 29.067947 -5.297954) (xy 29.01837 -5.320592) (xy 28.966077 -5.335944)
			(xy 28.91213 -5.343698) (xy 28.88488 -5.34416) (xy 28.02128 -5.34416) (xy 27.994026 -5.343769) (xy 27.940074 -5.336009)
			(xy 27.887775 -5.32065) (xy 27.838194 -5.298005) (xy 27.79234 -5.268534) (xy 27.751147 -5.232838)
			(xy 27.715454 -5.191644) (xy 27.685985 -5.145788) (xy 27.663343 -5.096206) (xy 27.647987 -5.043907)
			(xy 27.64023 -4.989954) (xy 25.66598 -4.989954) (xy 25.65823 -5.043854) (xy 25.642873 -5.096153)
			(xy 25.620231 -5.145733) (xy 25.590762 -5.191587) (xy 25.555068 -5.23278) (xy 25.513875 -5.268473)
			(xy 25.468021 -5.297942) (xy 25.418441 -5.320584) (xy 25.366143 -5.33594) (xy 25.312191 -5.343697)
			(xy 25.284938 -5.34416) (xy 24.421338 -5.34416) (xy 24.394087 -5.34367) (xy 24.34014 -5.335913) (xy 24.287846 -5.320558)
			(xy 24.238269 -5.297917) (xy 24.192419 -5.268451) (xy 24.151229 -5.232759) (xy 24.115538 -5.19157)
			(xy 24.086072 -5.145719) (xy 24.063431 -5.096143) (xy 24.048076 -5.043848) (xy 24.04032 -4.989901)
			(xy 22.066047 -4.989901) (xy 22.066047 -4.989903) (xy 22.05829 -5.043855) (xy 22.042933 -5.096153)
			(xy 22.02029 -5.145734) (xy 21.990822 -5.191587) (xy 21.955128 -5.23278) (xy 21.913934 -5.268474)
			(xy 21.86808 -5.297942) (xy 21.818499 -5.320585) (xy 21.766201 -5.33594) (xy 21.712249 -5.343697)
			(xy 21.684996 -5.34416) (xy 20.821396 -5.34416) (xy 20.794145 -5.34367) (xy 20.740198 -5.335913)
			(xy 20.687904 -5.320558) (xy 20.638328 -5.297916) (xy 20.592478 -5.26845) (xy 20.551288 -5.232759)
			(xy 20.515597 -5.191569) (xy 20.486132 -5.145719) (xy 20.463491 -5.096142) (xy 20.448136 -5.043848)
			(xy 20.44038 -4.989901) (xy 16.267136 -4.989901) (xy 16.278962 -5.06831) (xy 16.284155 -5.154889)
			(xy 16.281564 -5.241584) (xy 16.27121 -5.327698) (xy 16.253177 -5.412537) (xy 16.22761 -5.495418)
			(xy 16.194714 -5.575672) (xy 16.154755 -5.652653) (xy 16.108054 -5.725741) (xy 16.054988 -5.794348)
			(xy 15.995985 -5.85792) (xy 15.931519 -5.915946) (xy 15.897098 -5.94233) (xy 15.862132 -5.968006)
			(xy 15.788377 -6.013689) (xy 15.710822 -6.052572) (xy 15.630093 -6.084344) (xy 15.546839 -6.108746)
			(xy 15.461732 -6.125584) (xy 15.375458 -6.13472) (xy 15.288712 -6.136082) (xy 15.202194 -6.129659)
			(xy 15.116601 -6.115502) (xy 15.032622 -6.093724) (xy 14.950935 -6.064503) (xy 14.872197 -6.028073)
			(xy 14.797045 -5.984729) (xy 14.726083 -5.934818) (xy 14.659883 -5.878744) (xy 14.598979 -5.816959)
			(xy 14.543862 -5.749961) (xy 14.494977 -5.678289) (xy 14.452716 -5.602521) (xy 14.417421 -5.523269)
			(xy 14.389376 -5.44117) (xy 14.368808 -5.356887) (xy 14.355882 -5.271099) (xy 14.350702 -5.184498)
			(xy 13.611098 -5.184498) (xy 13.611098 -6.169914) (xy 78.515217 -6.169914) (xy 78.519222 -6.082006)
			(xy 78.531205 -5.994826) (xy 78.551065 -5.909097) (xy 78.57864 -5.825529) (xy 78.613699 -5.744815)
			(xy 78.655952 -5.667623) (xy 78.70505 -5.594594) (xy 78.760586 -5.526332) (xy 78.822098 -5.463402)
			(xy 78.889079 -5.406328) (xy 78.960972 -5.35558) (xy 79.037181 -5.31158) (xy 79.117076 -5.274693)
			(xy 79.199995 -5.245224) (xy 79.28525 -5.223417) (xy 79.372134 -5.209453) (xy 79.459928 -5.203447)
			(xy 79.547905 -5.205451) (xy 79.635335 -5.215446) (xy 79.721494 -5.23335) (xy 79.805668 -5.259014)
			(xy 79.887159 -5.292227) (xy 79.965293 -5.332713) (xy 80.039421 -5.380135) (xy 80.108929 -5.434102)
			(xy 80.173243 -5.494167) (xy 80.231827 -5.559831) (xy 80.284198 -5.63055) (xy 80.329921 -5.705738)
			(xy 80.368618 -5.784773) (xy 80.399967 -5.866999) (xy 80.423709 -5.951735) (xy 80.439647 -6.038279)
			(xy 80.447649 -6.125914) (xy 80.44815 -6.169914) (xy 80.447649 -6.213914) (xy 80.439647 -6.301549)
			(xy 80.423709 -6.388093) (xy 80.399967 -6.472829) (xy 80.368618 -6.555055) (xy 80.329921 -6.63409)
			(xy 80.284198 -6.709278) (xy 80.231827 -6.779997) (xy 80.173243 -6.845661) (xy 80.108929 -6.905726)
			(xy 80.039421 -6.959693) (xy 79.965293 -7.007115) (xy 79.887159 -7.047601) (xy 79.805668 -7.080814)
			(xy 79.721494 -7.106478) (xy 79.635335 -7.124382) (xy 79.547905 -7.134377) (xy 79.459928 -7.136381)
			(xy 79.372134 -7.130375) (xy 79.28525 -7.116411) (xy 79.199995 -7.094604) (xy 79.117076 -7.065135)
			(xy 79.037181 -7.028248) (xy 78.960972 -6.984248) (xy 78.889079 -6.9335) (xy 78.822098 -6.876426)
			(xy 78.760586 -6.813496) (xy 78.70505 -6.745234) (xy 78.655952 -6.672205) (xy 78.613699 -6.595013)
			(xy 78.57864 -6.514299) (xy 78.551065 -6.430731) (xy 78.531205 -6.345002) (xy 78.519222 -6.257822)
			(xy 78.515217 -6.169914) (xy 13.611098 -6.169914) (xy 13.611098 -6.751654) (xy 18.635651 -6.751654)
			(xy 18.635651 -6.697146) (xy 18.643409 -6.643192) (xy 18.658767 -6.590891) (xy 18.681411 -6.541309)
			(xy 18.710882 -6.495454) (xy 18.746579 -6.45426) (xy 18.787775 -6.418566) (xy 18.833632 -6.389099)
			(xy 18.883216 -6.366458) (xy 18.935517 -6.351104) (xy 18.989472 -6.34335) (xy 19.016726 -6.342888)
			(xy 19.880326 -6.342888) (xy 19.907576 -6.343384) (xy 19.96152 -6.351143) (xy 20.013811 -6.3665)
			(xy 20.063385 -6.389143) (xy 20.109231 -6.418609) (xy 20.150418 -6.4543) (xy 20.186106 -6.49549)
			(xy 20.21557 -6.541338) (xy 20.238209 -6.590913) (xy 20.253563 -6.643205) (xy 20.261318 -6.69715)
			(xy 20.261318 -6.75165) (xy 22.235674 -6.75165) (xy 22.235674 -6.69715) (xy 22.243429 -6.643204)
			(xy 22.258783 -6.590912) (xy 22.281422 -6.541336) (xy 22.310886 -6.495487) (xy 22.346574 -6.454297)
			(xy 22.387761 -6.418605) (xy 22.433608 -6.389138) (xy 22.483182 -6.366494) (xy 22.535473 -6.351136)
			(xy 22.589418 -6.343376) (xy 22.616668 -6.342888) (xy 23.480268 -6.342888) (xy 23.507522 -6.343357)
			(xy 23.561476 -6.35111) (xy 23.613777 -6.366463) (xy 23.663361 -6.389104) (xy 23.709217 -6.418571)
			(xy 23.750413 -6.454264) (xy 23.78611 -6.495457) (xy 23.815581 -6.541311) (xy 23.838225 -6.590893)
			(xy 23.853583 -6.643193) (xy 23.861341 -6.697146) (xy 23.861341 -6.751654) (xy 25.835551 -6.751654)
			(xy 25.835551 -6.697146) (xy 25.843309 -6.643194) (xy 25.858665 -6.590895) (xy 25.881309 -6.541314)
			(xy 25.910778 -6.495459) (xy 25.946473 -6.454266) (xy 25.987667 -6.418572) (xy 26.033522 -6.389104)
			(xy 26.083104 -6.366462) (xy 26.135404 -6.351107) (xy 26.189356 -6.343351) (xy 26.21661 -6.342888)
			(xy 27.08021 -6.342888) (xy 27.10746 -6.343382) (xy 27.161407 -6.35114) (xy 27.2137 -6.366496) (xy 27.263275 -6.389137)
			(xy 27.309124 -6.418604) (xy 27.350312 -6.454295) (xy 27.386002 -6.495484) (xy 27.415467 -6.541334)
			(xy 27.438108 -6.59091) (xy 27.453462 -6.643203) (xy 27.461218 -6.697149) (xy 27.461218 -6.751651)
			(xy 27.461218 -6.751653) (xy 29.435751 -6.751653) (xy 29.435751 -6.697147) (xy 29.443509 -6.643195)
			(xy 29.458865 -6.590896) (xy 29.481508 -6.541315) (xy 29.510977 -6.495461) (xy 29.546672 -6.454268)
			(xy 29.587866 -6.418574) (xy 29.63372 -6.389105) (xy 29.683301 -6.366463) (xy 29.7356 -6.351107)
			(xy 29.789553 -6.343351) (xy 29.816806 -6.342888) (xy 30.680406 -6.342888) (xy 30.707657 -6.343382)
			(xy 30.761603 -6.351139) (xy 30.813897 -6.366495) (xy 30.863473 -6.389136) (xy 30.909322 -6.418602)
			(xy 30.950511 -6.454293) (xy 30.986201 -6.495483) (xy 31.015667 -6.541333) (xy 31.038307 -6.590909)
			(xy 31.053662 -6.643203) (xy 31.061418 -6.697149) (xy 31.061418 -6.75165) (xy 38.545774 -6.75165)
			(xy 38.545774 -6.69715) (xy 38.55353 -6.643204) (xy 38.568883 -6.590911) (xy 38.591522 -6.541336)
			(xy 38.620986 -6.495486) (xy 38.656675 -6.454296) (xy 38.697862 -6.418604) (xy 38.743709 -6.389137)
			(xy 38.793283 -6.366494) (xy 38.845575 -6.351136) (xy 38.89952 -6.343376) (xy 38.92677 -6.342888)
			(xy 39.79037 -6.342888) (xy 39.817624 -6.343357) (xy 39.871578 -6.351111) (xy 39.923878 -6.366464)
			(xy 39.973462 -6.389105) (xy 40.019318 -6.418571) (xy 40.060514 -6.454265) (xy 40.096211 -6.495458)
			(xy 40.125681 -6.541312) (xy 40.148326 -6.590893) (xy 40.163683 -6.643193) (xy 40.171441 -6.697146)
			(xy 40.171441 -6.751654) (xy 42.145651 -6.751654) (xy 42.145651 -6.697146) (xy 42.153409 -6.643194)
			(xy 42.168766 -6.590894) (xy 42.191409 -6.541313) (xy 42.220879 -6.495459) (xy 42.256574 -6.454265)
			(xy 42.297768 -6.418571) (xy 42.343624 -6.389103) (xy 42.393206 -6.366461) (xy 42.445506 -6.351106)
			(xy 42.499458 -6.343351) (xy 42.526712 -6.342888) (xy 43.390312 -6.342888) (xy 43.417562 -6.343383)
			(xy 43.471508 -6.35114) (xy 43.523801 -6.366496) (xy 43.573376 -6.389138) (xy 43.619225 -6.418604)
			(xy 43.660413 -6.454295) (xy 43.696103 -6.495485) (xy 43.725568 -6.541334) (xy 43.748208 -6.59091)
			(xy 43.763562 -6.643203) (xy 43.771318 -6.69715) (xy 43.771318 -6.75165) (xy 43.771318 -6.751653)
			(xy 49.755751 -6.751653) (xy 49.755751 -6.697147) (xy 49.763509 -6.643195) (xy 49.778865 -6.590896)
			(xy 49.801508 -6.541315) (xy 49.830977 -6.495461) (xy 49.866672 -6.454268) (xy 49.907866 -6.418574)
			(xy 49.95372 -6.389105) (xy 50.003301 -6.366463) (xy 50.0556 -6.351107) (xy 50.109553 -6.343351)
			(xy 50.136806 -6.342888) (xy 51.000406 -6.342888) (xy 51.027657 -6.343382) (xy 51.081603 -6.351139)
			(xy 51.133897 -6.366495) (xy 51.183473 -6.389136) (xy 51.229322 -6.418602) (xy 51.270511 -6.454293)
			(xy 51.306201 -6.495483) (xy 51.335667 -6.541333) (xy 51.358307 -6.590909) (xy 51.373662 -6.643203)
			(xy 51.381418 -6.697149) (xy 51.381418 -6.751651) (xy 51.381417 -6.751655) (xy 53.355652 -6.751655)
			(xy 53.355652 -6.697145) (xy 53.36341 -6.643189) (xy 53.378768 -6.590887) (xy 53.401415 -6.541303)
			(xy 53.430887 -6.495447) (xy 53.466587 -6.454253) (xy 53.507785 -6.418559) (xy 53.553645 -6.389092)
			(xy 53.603232 -6.366452) (xy 53.655536 -6.3511) (xy 53.709493 -6.343348) (xy 53.736748 -6.342888)
			(xy 54.600348 -6.342888) (xy 54.627597 -6.343385) (xy 54.681539 -6.351147) (xy 54.733827 -6.366506)
			(xy 54.783398 -6.38915) (xy 54.829242 -6.418617) (xy 54.870426 -6.454308) (xy 54.906112 -6.495497)
			(xy 54.935573 -6.541344) (xy 54.958211 -6.590918) (xy 54.973563 -6.643208) (xy 54.981318 -6.697151)
			(xy 54.981318 -6.751649) (xy 54.981318 -6.751651) (xy 56.955674 -6.751651) (xy 56.955674 -6.697149)
			(xy 56.96343 -6.643201) (xy 56.978785 -6.590907) (xy 57.001426 -6.54133) (xy 57.030891 -6.49548)
			(xy 57.066582 -6.454289) (xy 57.107771 -6.418597) (xy 57.153621 -6.38913) (xy 57.203198 -6.366488)
			(xy 57.255492 -6.351132) (xy 57.309439 -6.343374) (xy 57.33669 -6.342888) (xy 58.20029 -6.342888)
			(xy 58.227543 -6.343359) (xy 58.281494 -6.351114) (xy 58.333793 -6.366469) (xy 58.383374 -6.389111)
			(xy 58.429228 -6.418578) (xy 58.470421 -6.454272) (xy 58.506116 -6.495464) (xy 58.535584 -6.541317)
			(xy 58.558227 -6.590898) (xy 58.573583 -6.643196) (xy 58.581341 -6.697147) (xy 58.581341 -6.751651)
			(xy 70.950574 -6.751651) (xy 70.950574 -6.697149) (xy 70.95833 -6.643203) (xy 70.973684 -6.590909)
			(xy 70.996324 -6.541332) (xy 71.025789 -6.495482) (xy 71.061479 -6.454292) (xy 71.102668 -6.4186)
			(xy 71.148516 -6.389133) (xy 71.198092 -6.366491) (xy 71.250385 -6.351134) (xy 71.304331 -6.343375)
			(xy 71.331582 -6.342888) (xy 72.195182 -6.342888) (xy 72.222435 -6.343358) (xy 72.276388 -6.351113)
			(xy 72.328687 -6.366467) (xy 72.378269 -6.389108) (xy 72.424124 -6.418576) (xy 72.465318 -6.454269)
			(xy 72.501014 -6.495462) (xy 72.530483 -6.541315) (xy 72.553126 -6.590896) (xy 72.568483 -6.643195)
			(xy 72.576241 -6.697147) (xy 72.576241 -6.751653) (xy 72.568483 -6.805605) (xy 72.553126 -6.857904)
			(xy 72.530483 -6.907485) (xy 72.501014 -6.953338) (xy 72.465318 -6.994531) (xy 72.424124 -7.030224)
			(xy 72.378269 -7.059692) (xy 72.328687 -7.082333) (xy 72.276388 -7.097687) (xy 72.222435 -7.105442)
			(xy 72.195182 -7.105904) (xy 71.331582 -7.105904) (xy 71.304331 -7.105425) (xy 71.250385 -7.097666)
			(xy 71.198092 -7.082309) (xy 71.148516 -7.059667) (xy 71.102668 -7.0302) (xy 71.061479 -6.994508)
			(xy 71.025789 -6.953318) (xy 70.996324 -6.907468) (xy 70.973684 -6.857891) (xy 70.95833 -6.805597)
			(xy 70.950574 -6.751651) (xy 58.581341 -6.751651) (xy 58.581341 -6.751653) (xy 58.573583 -6.805604)
			(xy 58.558227 -6.857902) (xy 58.535584 -6.907483) (xy 58.506116 -6.953336) (xy 58.470421 -6.994528)
			(xy 58.429228 -7.030222) (xy 58.383374 -7.059689) (xy 58.333793 -7.082331) (xy 58.281494 -7.097686)
			(xy 58.227543 -7.105441) (xy 58.20029 -7.105904) (xy 57.33669 -7.105904) (xy 57.309439 -7.105426)
			(xy 57.255492 -7.097668) (xy 57.203198 -7.082312) (xy 57.153621 -7.05967) (xy 57.107771 -7.030203)
			(xy 57.066582 -6.994511) (xy 57.030891 -6.95332) (xy 57.001426 -6.90747) (xy 56.978785 -6.857893)
			(xy 56.96343 -6.805599) (xy 56.955674 -6.751651) (xy 54.981318 -6.751651) (xy 54.973563 -6.805592)
			(xy 54.958211 -6.857882) (xy 54.935573 -6.907456) (xy 54.906112 -6.953303) (xy 54.870426 -6.994492)
			(xy 54.829242 -7.030183) (xy 54.783398 -7.05965) (xy 54.733827 -7.082294) (xy 54.681539 -7.097653)
			(xy 54.627597 -7.105415) (xy 54.600348 -7.105904) (xy 53.736748 -7.105904) (xy 53.709493 -7.105452)
			(xy 53.655536 -7.0977) (xy 53.603232 -7.082348) (xy 53.553645 -7.059708) (xy 53.507785 -7.030241)
			(xy 53.466587 -6.994547) (xy 53.430887 -6.953353) (xy 53.401415 -6.907497) (xy 53.378768 -6.857913)
			(xy 53.36341 -6.805611) (xy 53.355652 -6.751655) (xy 51.381417 -6.751655) (xy 51.373662 -6.805597)
			(xy 51.358307 -6.857891) (xy 51.335667 -6.907467) (xy 51.306201 -6.953317) (xy 51.270511 -6.994507)
			(xy 51.229322 -7.030198) (xy 51.183473 -7.059664) (xy 51.133897 -7.082305) (xy 51.081603 -7.097661)
			(xy 51.027657 -7.105418) (xy 51.000406 -7.105904) (xy 50.136806 -7.105904) (xy 50.109553 -7.105449)
			(xy 50.0556 -7.097693) (xy 50.003301 -7.082337) (xy 49.95372 -7.059695) (xy 49.907866 -7.030226)
			(xy 49.866672 -6.994532) (xy 49.830977 -6.953339) (xy 49.801508 -6.907485) (xy 49.778865 -6.857904)
			(xy 49.763509 -6.805605) (xy 49.755751 -6.751653) (xy 43.771318 -6.751653) (xy 43.763562 -6.805597)
			(xy 43.748208 -6.85789) (xy 43.725568 -6.907466) (xy 43.696103 -6.953315) (xy 43.660413 -6.994505)
			(xy 43.619225 -7.030196) (xy 43.573376 -7.059662) (xy 43.523801 -7.082304) (xy 43.471508 -7.09766)
			(xy 43.417562 -7.105417) (xy 43.390312 -7.105904) (xy 42.526712 -7.105904) (xy 42.499458 -7.105449)
			(xy 42.445506 -7.097694) (xy 42.393206 -7.082339) (xy 42.343624 -7.059697) (xy 42.297768 -7.030229)
			(xy 42.256574 -6.994535) (xy 42.220879 -6.953341) (xy 42.191409 -6.907487) (xy 42.168766 -6.857906)
			(xy 42.153409 -6.805606) (xy 42.145651 -6.751654) (xy 40.171441 -6.751654) (xy 40.163683 -6.805607)
			(xy 40.148326 -6.857907) (xy 40.125681 -6.907488) (xy 40.096211 -6.953342) (xy 40.060514 -6.994535)
			(xy 40.019318 -7.030229) (xy 39.973462 -7.059695) (xy 39.923878 -7.082336) (xy 39.871578 -7.097689)
			(xy 39.817624 -7.105443) (xy 39.79037 -7.105904) (xy 38.92677 -7.105904) (xy 38.89952 -7.105424)
			(xy 38.845575 -7.097664) (xy 38.793283 -7.082306) (xy 38.743709 -7.059663) (xy 38.697862 -7.030196)
			(xy 38.656675 -6.994504) (xy 38.620986 -6.953314) (xy 38.591522 -6.907464) (xy 38.568883 -6.857889)
			(xy 38.55353 -6.805596) (xy 38.545774 -6.75165) (xy 31.061418 -6.75165) (xy 31.061418 -6.751651)
			(xy 31.053662 -6.805597) (xy 31.038307 -6.857891) (xy 31.015667 -6.907467) (xy 30.986201 -6.953317)
			(xy 30.950511 -6.994507) (xy 30.909322 -7.030198) (xy 30.863473 -7.059664) (xy 30.813897 -7.082305)
			(xy 30.761603 -7.097661) (xy 30.707657 -7.105418) (xy 30.680406 -7.105904) (xy 29.816806 -7.105904)
			(xy 29.789553 -7.105449) (xy 29.7356 -7.097693) (xy 29.683301 -7.082337) (xy 29.63372 -7.059695)
			(xy 29.587866 -7.030226) (xy 29.546672 -6.994532) (xy 29.510977 -6.953339) (xy 29.481508 -6.907485)
			(xy 29.458865 -6.857904) (xy 29.443509 -6.805605) (xy 29.435751 -6.751653) (xy 27.461218 -6.751653)
			(xy 27.453462 -6.805597) (xy 27.438108 -6.85789) (xy 27.415467 -6.907466) (xy 27.386002 -6.953316)
			(xy 27.350312 -6.994505) (xy 27.309124 -7.030196) (xy 27.263275 -7.059663) (xy 27.2137 -7.082304)
			(xy 27.161407 -7.09766) (xy 27.10746 -7.105418) (xy 27.08021 -7.105904) (xy 26.21661 -7.105904) (xy 26.189356 -7.105449)
			(xy 26.135404 -7.097693) (xy 26.083104 -7.082338) (xy 26.033522 -7.059696) (xy 25.987667 -7.030228)
			(xy 25.946473 -6.994534) (xy 25.910778 -6.953341) (xy 25.881309 -6.907486) (xy 25.858665 -6.857905)
			(xy 25.843309 -6.805606) (xy 25.835551 -6.751654) (xy 23.861341 -6.751654) (xy 23.853583 -6.805607)
			(xy 23.838225 -6.857907) (xy 23.815581 -6.907489) (xy 23.78611 -6.953343) (xy 23.750413 -6.994536)
			(xy 23.709217 -7.030229) (xy 23.663361 -7.059696) (xy 23.613777 -7.082337) (xy 23.561476 -7.09769)
			(xy 23.507522 -7.105443) (xy 23.480268 -7.105904) (xy 22.616668 -7.105904) (xy 22.589418 -7.105424)
			(xy 22.535473 -7.097664) (xy 22.483182 -7.082306) (xy 22.433608 -7.059662) (xy 22.387761 -7.030195)
			(xy 22.346574 -6.994503) (xy 22.310886 -6.953313) (xy 22.281422 -6.907464) (xy 22.258783 -6.857888)
			(xy 22.243429 -6.805596) (xy 22.235674 -6.75165) (xy 20.261318 -6.75165) (xy 20.253563 -6.805595)
			(xy 20.238209 -6.857887) (xy 20.21557 -6.907462) (xy 20.186106 -6.95331) (xy 20.150418 -6.9945) (xy 20.109231 -7.030191)
			(xy 20.063385 -7.059657) (xy 20.013811 -7.0823) (xy 19.96152 -7.097657) (xy 19.907576 -7.105416)
			(xy 19.880326 -7.105904) (xy 19.016726 -7.105904) (xy 18.989472 -7.10545) (xy 18.935517 -7.097696)
			(xy 18.883216 -7.082342) (xy 18.833632 -7.059701) (xy 18.787775 -7.030234) (xy 18.746579 -6.99454)
			(xy 18.710882 -6.953346) (xy 18.681411 -6.907491) (xy 18.658767 -6.857909) (xy 18.643409 -6.805608)
			(xy 18.635651 -6.751654) (xy 13.611098 -6.751654) (xy 13.611098 -9.780016) (xy 13.610604 -9.850398)
			(xy 13.602711 -9.990941) (xy 13.58695 -10.13082) (xy 13.563371 -10.269596) (xy 13.532048 -10.406831)
			(xy 13.493079 -10.542094) (xy 13.446587 -10.674959) (xy 13.392719 -10.805008) (xy 13.331643 -10.931832)
			(xy 13.263553 -11.055033) (xy 13.188662 -11.174221) (xy 13.107205 -11.289023) (xy 13.01944 -11.399077)
			(xy 12.925642 -11.504037) (xy 12.826107 -11.603572) (xy 12.721147 -11.69737) (xy 12.611093 -11.785135)
			(xy 12.496291 -11.866592) (xy 12.377103 -11.941483) (xy 12.253902 -12.009573) (xy 12.127078 -12.070649)
			(xy 11.997029 -12.124517) (xy 11.864164 -12.171009) (xy 11.728901 -12.209978) (xy 11.591666 -12.241301)
			(xy 11.45289 -12.26488) (xy 11.313011 -12.280641) (xy 11.172468 -12.288534) (xy 11.102086 -12.289028)
			(xy 1.999996 -12.289028) (xy 1.944227 -12.289537) (xy 1.833 -12.297872) (xy 1.722707 -12.314497)
			(xy 1.613965 -12.339317) (xy 1.507382 -12.372193) (xy 1.403554 -12.412943) (xy 1.303061 -12.461339)
			(xy 1.206466 -12.517108) (xy 1.114309 -12.579941) (xy 1.027105 -12.649484) (xy 0.945341 -12.72535)
			(xy 0.869476 -12.807114) (xy 0.802299 -12.891351) (xy 56.954662 -12.891351) (xy 56.954662 -12.836849)
			(xy 56.962418 -12.782901) (xy 56.977772 -12.730606) (xy 57.000413 -12.681029) (xy 57.029878 -12.635178)
			(xy 57.065568 -12.593986) (xy 57.106757 -12.558293) (xy 57.152606 -12.528825) (xy 57.202182 -12.506181)
			(xy 57.254476 -12.490823) (xy 57.308423 -12.483064) (xy 57.335674 -12.482576) (xy 58.199274 -12.482576)
			(xy 58.226527 -12.48307) (xy 58.280478 -12.490823) (xy 58.332777 -12.506176) (xy 58.382358 -12.528816)
			(xy 58.428213 -12.558282) (xy 58.469407 -12.593975) (xy 58.505102 -12.635166) (xy 58.534571 -12.681019)
			(xy 58.557215 -12.730598) (xy 58.572571 -12.782896) (xy 58.580329 -12.836847) (xy 58.580329 -12.891353)
			(xy 58.580329 -12.891355) (xy 70.949739 -12.891355) (xy 70.949739 -12.836845) (xy 70.957497 -12.78289)
			(xy 70.972854 -12.730588) (xy 70.995499 -12.681005) (xy 71.024971 -12.635149) (xy 71.060668 -12.593954)
			(xy 71.101865 -12.558259) (xy 71.147722 -12.52879) (xy 71.197307 -12.506147) (xy 71.24961 -12.490793)
			(xy 71.303565 -12.483038) (xy 71.33082 -12.482576) (xy 72.19442 -12.482576) (xy 72.221669 -12.483096)
			(xy 72.275612 -12.490854) (xy 72.327902 -12.50621) (xy 72.377475 -12.528852) (xy 72.423321 -12.558317)
			(xy 72.464507 -12.594007) (xy 72.500195 -12.635195) (xy 72.529658 -12.681043) (xy 72.552297 -12.730616)
			(xy 72.56765 -12.782907) (xy 72.575406 -12.836851) (xy 72.575406 -12.891349) (xy 72.56765 -12.945293)
			(xy 72.552297 -12.997584) (xy 72.529658 -13.047157) (xy 72.500195 -13.093005) (xy 72.464507 -13.134193)
			(xy 72.423321 -13.169883) (xy 72.377475 -13.199348) (xy 72.327902 -13.22199) (xy 72.275612 -13.237346)
			(xy 72.221669 -13.245104) (xy 72.19442 -13.245592) (xy 71.33082 -13.245592) (xy 71.303565 -13.245162)
			(xy 71.24961 -13.237407) (xy 71.197307 -13.222053) (xy 71.147722 -13.19941) (xy 71.101865 -13.169941)
			(xy 71.060668 -13.134246) (xy 71.024971 -13.093051) (xy 70.995499 -13.047195) (xy 70.972854 -12.997612)
			(xy 70.957497 -12.94531) (xy 70.949739 -12.891355) (xy 58.580329 -12.891355) (xy 58.572571 -12.945304)
			(xy 58.557215 -12.997602) (xy 58.534571 -13.047181) (xy 58.505102 -13.093034) (xy 58.469407 -13.134225)
			(xy 58.428213 -13.169918) (xy 58.382358 -13.199384) (xy 58.332777 -13.222024) (xy 58.280478 -13.237377)
			(xy 58.226527 -13.24513) (xy 58.199274 -13.245592) (xy 57.335674 -13.245592) (xy 57.308423 -13.245136)
			(xy 57.254476 -13.237377) (xy 57.202182 -13.222019) (xy 57.152606 -13.199375) (xy 57.106757 -13.169907)
			(xy 57.065568 -13.134214) (xy 57.029878 -13.093022) (xy 57.000413 -13.047171) (xy 56.977772 -12.997594)
			(xy 56.962418 -12.945299) (xy 56.954662 -12.891351) (xy 0.802299 -12.891351) (xy 0.799933 -12.894318)
			(xy 0.737102 -12.986476) (xy 0.681333 -13.083072) (xy 0.632939 -13.183565) (xy 0.59219 -13.287393)
			(xy 0.559313 -13.393977) (xy 0.534494 -13.502719) (xy 0.517871 -13.613012) (xy 0.509536 -13.724239)
			(xy 0.509016 -13.780008) (xy 0.509016 -15.222054) (xy 135.233343 -15.222054) (xy 135.233343 -15.167546)
			(xy 135.2411 -15.113592) (xy 135.256457 -15.061292) (xy 135.279101 -15.011709) (xy 135.308571 -14.965854)
			(xy 135.344267 -14.92466) (xy 135.385462 -14.888965) (xy 135.431318 -14.859497) (xy 135.480901 -14.836854)
			(xy 135.533202 -14.821498) (xy 135.587156 -14.813742) (xy 135.61441 -14.81328) (xy 136.47801 -14.81328)
			(xy 136.50526 -14.813791) (xy 136.559205 -14.821548) (xy 136.611497 -14.836904) (xy 136.661071 -14.859545)
			(xy 136.706919 -14.88901) (xy 136.748106 -14.924701) (xy 136.783796 -14.965889) (xy 136.81326 -15.011738)
			(xy 136.8359 -15.061313) (xy 136.851254 -15.113605) (xy 136.85901 -15.16755) (xy 136.85901 -15.22205)
			(xy 136.851254 -15.275995) (xy 136.8359 -15.328287) (xy 136.81326 -15.377862) (xy 136.783796 -15.423711)
			(xy 136.748106 -15.464899) (xy 136.706919 -15.50059) (xy 136.661071 -15.530055) (xy 136.611497 -15.552696)
			(xy 136.559205 -15.568052) (xy 136.50526 -15.575809) (xy 136.47801 -15.576296) (xy 135.61441 -15.576296)
			(xy 135.587156 -15.575858) (xy 135.533202 -15.568102) (xy 135.480901 -15.552746) (xy 135.431318 -15.530103)
			(xy 135.385462 -15.500635) (xy 135.344267 -15.46494) (xy 135.308571 -15.423746) (xy 135.279101 -15.377891)
			(xy 135.256457 -15.328308) (xy 135.2411 -15.276008) (xy 135.233343 -15.222054) (xy 0.509016 -15.222054)
			(xy 0.509016 -17.639611) (xy 15.152858 -17.639611) (xy 15.152858 -17.585109) (xy 15.160614 -17.531161)
			(xy 15.175969 -17.478867) (xy 15.19861 -17.42929) (xy 15.228076 -17.383439) (xy 15.263768 -17.342249)
			(xy 15.304958 -17.306558) (xy 15.350808 -17.277091) (xy 15.400385 -17.25445) (xy 15.452679 -17.239095)
			(xy 15.506627 -17.231338) (xy 15.533878 -17.230852) (xy 16.397478 -17.230852) (xy 16.424731 -17.231315)
			(xy 16.478682 -17.239072) (xy 16.53098 -17.254428) (xy 16.580561 -17.27707) (xy 16.626414 -17.306538)
			(xy 16.667607 -17.342232) (xy 16.703301 -17.383424) (xy 16.732769 -17.429278) (xy 16.755412 -17.478858)
			(xy 16.770768 -17.531156) (xy 16.778525 -17.585107) (xy 16.778525 -17.639611) (xy 20.740858 -17.639611)
			(xy 20.740858 -17.585109) (xy 20.748614 -17.531161) (xy 20.763969 -17.478867) (xy 20.78661 -17.42929)
			(xy 20.816076 -17.383439) (xy 20.851768 -17.342249) (xy 20.892958 -17.306558) (xy 20.938808 -17.277091)
			(xy 20.988385 -17.25445) (xy 21.040679 -17.239095) (xy 21.094627 -17.231338) (xy 21.121878 -17.230852)
			(xy 21.985478 -17.230852) (xy 22.012729 -17.231394) (xy 22.066677 -17.239147) (xy 22.118972 -17.2545)
			(xy 22.168549 -17.277139) (xy 22.2144 -17.306603) (xy 22.255591 -17.342293) (xy 22.291284 -17.383482)
			(xy 22.320751 -17.429331) (xy 22.343392 -17.478908) (xy 22.358748 -17.531202) (xy 22.366505 -17.585149)
			(xy 22.366505 -17.639651) (xy 22.366505 -17.639653) (xy 26.328838 -17.639653) (xy 26.328838 -17.585147)
			(xy 26.336595 -17.531195) (xy 26.35195 -17.478897) (xy 26.374592 -17.429316) (xy 26.404059 -17.383462)
			(xy 26.439752 -17.342268) (xy 26.480944 -17.306573) (xy 26.526797 -17.277103) (xy 26.576376 -17.254458)
			(xy 26.628674 -17.239099) (xy 26.682625 -17.231339) (xy 26.709878 -17.230852) (xy 27.573478 -17.230852)
			(xy 27.600729 -17.231394) (xy 27.654677 -17.239147) (xy 27.706972 -17.2545) (xy 27.756549 -17.277139)
			(xy 27.8024 -17.306603) (xy 27.843591 -17.342293) (xy 27.879284 -17.383482) (xy 27.908751 -17.429331)
			(xy 27.931392 -17.478908) (xy 27.946748 -17.531202) (xy 27.954505 -17.585149) (xy 27.954505 -17.639651)
			(xy 27.954505 -17.639653) (xy 31.916838 -17.639653) (xy 31.916838 -17.585147) (xy 31.924595 -17.531195)
			(xy 31.93995 -17.478897) (xy 31.962592 -17.429316) (xy 31.992059 -17.383462) (xy 32.027752 -17.342268)
			(xy 32.068944 -17.306573) (xy 32.114797 -17.277103) (xy 32.164376 -17.254458) (xy 32.216674 -17.239099)
			(xy 32.270625 -17.231339) (xy 32.297878 -17.230852) (xy 33.161478 -17.230852) (xy 33.188729 -17.231394)
			(xy 33.242677 -17.239147) (xy 33.294972 -17.2545) (xy 33.344549 -17.277139) (xy 33.3904 -17.306603)
			(xy 33.431591 -17.342293) (xy 33.467284 -17.383482) (xy 33.496751 -17.429331) (xy 33.519392 -17.478908)
			(xy 33.534748 -17.531202) (xy 33.542505 -17.585149) (xy 33.542505 -17.639651) (xy 33.542505 -17.639653)
			(xy 37.504838 -17.639653) (xy 37.504838 -17.585147) (xy 37.512595 -17.531195) (xy 37.52795 -17.478897)
			(xy 37.550592 -17.429316) (xy 37.580059 -17.383462) (xy 37.615752 -17.342268) (xy 37.656944 -17.306573)
			(xy 37.702797 -17.277103) (xy 37.752376 -17.254458) (xy 37.804674 -17.239099) (xy 37.858625 -17.231339)
			(xy 37.885878 -17.230852) (xy 38.749478 -17.230852) (xy 38.776729 -17.231394) (xy 38.830677 -17.239147)
			(xy 38.882972 -17.2545) (xy 38.932549 -17.277139) (xy 38.9784 -17.306603) (xy 39.019591 -17.342293)
			(xy 39.055284 -17.383482) (xy 39.084751 -17.429331) (xy 39.107392 -17.478908) (xy 39.122748 -17.531202)
			(xy 39.130505 -17.585149) (xy 39.130505 -17.639651) (xy 39.130505 -17.639654) (xy 43.398638 -17.639654)
			(xy 43.398638 -17.585146) (xy 43.406395 -17.531193) (xy 43.421751 -17.478894) (xy 43.444395 -17.429312)
			(xy 43.473863 -17.383457) (xy 43.509558 -17.342262) (xy 43.550752 -17.306567) (xy 43.596606 -17.277097)
			(xy 43.646188 -17.254454) (xy 43.698487 -17.239096) (xy 43.75244 -17.231338) (xy 43.779694 -17.230852)
			(xy 44.643294 -17.230852) (xy 44.670544 -17.231395) (xy 44.72449 -17.23915) (xy 44.776783 -17.254504)
			(xy 44.826359 -17.277144) (xy 44.872208 -17.306609) (xy 44.913397 -17.342299) (xy 44.949088 -17.383487)
			(xy 44.978553 -17.429336) (xy 45.001194 -17.478911) (xy 45.016548 -17.531204) (xy 45.024305 -17.58515)
			(xy 45.024305 -17.63965) (xy 45.024304 -17.639654) (xy 48.986638 -17.639654) (xy 48.986638 -17.585146)
			(xy 48.994395 -17.531193) (xy 49.009751 -17.478894) (xy 49.032395 -17.429312) (xy 49.061863 -17.383457)
			(xy 49.097558 -17.342262) (xy 49.138752 -17.306567) (xy 49.184606 -17.277097) (xy 49.234188 -17.254454)
			(xy 49.286487 -17.239096) (xy 49.34044 -17.231338) (xy 49.367694 -17.230852) (xy 50.231294 -17.230852)
			(xy 50.258544 -17.231395) (xy 50.31249 -17.23915) (xy 50.364783 -17.254504) (xy 50.414359 -17.277144)
			(xy 50.460208 -17.306609) (xy 50.501397 -17.342299) (xy 50.537088 -17.383487) (xy 50.566553 -17.429336)
			(xy 50.589194 -17.478911) (xy 50.604548 -17.531204) (xy 50.612305 -17.58515) (xy 50.612305 -17.63965)
			(xy 50.612304 -17.639657) (xy 54.608615 -17.639657) (xy 54.608615 -17.585143) (xy 54.616374 -17.531184)
			(xy 54.631733 -17.478878) (xy 54.65438 -17.42929) (xy 54.683854 -17.383431) (xy 54.719554 -17.342233)
			(xy 54.760755 -17.306536) (xy 54.806617 -17.277065) (xy 54.856206 -17.254422) (xy 54.908513 -17.239067)
			(xy 54.962473 -17.231313) (xy 54.98973 -17.230852) (xy 55.85333 -17.230852) (xy 55.880577 -17.23142)
			(xy 55.934516 -17.239179) (xy 55.986801 -17.254535) (xy 56.03637 -17.277176) (xy 56.082211 -17.30664)
			(xy 56.123394 -17.342328) (xy 56.159078 -17.383513) (xy 56.188538 -17.429357) (xy 56.211175 -17.478927)
			(xy 56.226527 -17.531214) (xy 56.234282 -17.585153) (xy 56.234282 -17.639647) (xy 56.226527 -17.693586)
			(xy 56.211175 -17.745873) (xy 56.188538 -17.795443) (xy 56.159078 -17.841287) (xy 56.123394 -17.882472)
			(xy 56.082211 -17.91816) (xy 56.03637 -17.947624) (xy 55.986801 -17.970265) (xy 55.934516 -17.985621)
			(xy 55.880577 -17.99338) (xy 55.85333 -17.993868) (xy 54.98973 -17.993868) (xy 54.962473 -17.993487)
			(xy 54.908513 -17.985733) (xy 54.856206 -17.970378) (xy 54.806617 -17.947735) (xy 54.760755 -17.918264)
			(xy 54.719554 -17.882567) (xy 54.683854 -17.841369) (xy 54.65438 -17.79551) (xy 54.631733 -17.745922)
			(xy 54.616374 -17.693616) (xy 54.608615 -17.639657) (xy 50.612304 -17.639657) (xy 50.604548 -17.693596)
			(xy 50.589194 -17.745889) (xy 50.566553 -17.795464) (xy 50.537088 -17.841313) (xy 50.501397 -17.882501)
			(xy 50.460208 -17.918191) (xy 50.414359 -17.947656) (xy 50.364783 -17.970296) (xy 50.31249 -17.98565)
			(xy 50.258544 -17.993405) (xy 50.231294 -17.993868) (xy 49.367694 -17.993868) (xy 49.34044 -17.993462)
			(xy 49.286487 -17.985704) (xy 49.234188 -17.970346) (xy 49.184606 -17.947703) (xy 49.138752 -17.918233)
			(xy 49.097558 -17.882538) (xy 49.061863 -17.841343) (xy 49.032395 -17.795488) (xy 49.009751 -17.745906)
			(xy 48.994395 -17.693607) (xy 48.986638 -17.639654) (xy 45.024304 -17.639654) (xy 45.016548 -17.693596)
			(xy 45.001194 -17.745889) (xy 44.978553 -17.795464) (xy 44.949088 -17.841313) (xy 44.913397 -17.882501)
			(xy 44.872208 -17.918191) (xy 44.826359 -17.947656) (xy 44.776783 -17.970296) (xy 44.72449 -17.98565)
			(xy 44.670544 -17.993405) (xy 44.643294 -17.993868) (xy 43.779694 -17.993868) (xy 43.75244 -17.993462)
			(xy 43.698487 -17.985704) (xy 43.646188 -17.970346) (xy 43.596606 -17.947703) (xy 43.550752 -17.918233)
			(xy 43.509558 -17.882538) (xy 43.473863 -17.841343) (xy 43.444395 -17.795488) (xy 43.421751 -17.745906)
			(xy 43.406395 -17.693607) (xy 43.398638 -17.639654) (xy 39.130505 -17.639654) (xy 39.122748 -17.693598)
			(xy 39.107392 -17.745892) (xy 39.084751 -17.795469) (xy 39.055284 -17.841318) (xy 39.019591 -17.882507)
			(xy 38.9784 -17.918197) (xy 38.932549 -17.947661) (xy 38.882972 -17.9703) (xy 38.830677 -17.985653)
			(xy 38.776729 -17.993406) (xy 38.749478 -17.993868) (xy 37.885878 -17.993868) (xy 37.858625 -17.993461)
			(xy 37.804674 -17.985701) (xy 37.752376 -17.970342) (xy 37.702797 -17.947697) (xy 37.656944 -17.918227)
			(xy 37.615752 -17.882532) (xy 37.580059 -17.841338) (xy 37.550592 -17.795484) (xy 37.52795 -17.745903)
			(xy 37.512595 -17.693605) (xy 37.504838 -17.639653) (xy 33.542505 -17.639653) (xy 33.534748 -17.693598)
			(xy 33.519392 -17.745892) (xy 33.496751 -17.795469) (xy 33.467284 -17.841318) (xy 33.431591 -17.882507)
			(xy 33.3904 -17.918197) (xy 33.344549 -17.947661) (xy 33.294972 -17.9703) (xy 33.242677 -17.985653)
			(xy 33.188729 -17.993406) (xy 33.161478 -17.993868) (xy 32.297878 -17.993868) (xy 32.270625 -17.993461)
			(xy 32.216674 -17.985701) (xy 32.164376 -17.970342) (xy 32.114797 -17.947697) (xy 32.068944 -17.918227)
			(xy 32.027752 -17.882532) (xy 31.992059 -17.841338) (xy 31.962592 -17.795484) (xy 31.93995 -17.745903)
			(xy 31.924595 -17.693605) (xy 31.916838 -17.639653) (xy 27.954505 -17.639653) (xy 27.946748 -17.693598)
			(xy 27.931392 -17.745892) (xy 27.908751 -17.795469) (xy 27.879284 -17.841318) (xy 27.843591 -17.882507)
			(xy 27.8024 -17.918197) (xy 27.756549 -17.947661) (xy 27.706972 -17.9703) (xy 27.654677 -17.985653)
			(xy 27.600729 -17.993406) (xy 27.573478 -17.993868) (xy 26.709878 -17.993868) (xy 26.682625 -17.993461)
			(xy 26.628674 -17.985701) (xy 26.576376 -17.970342) (xy 26.526797 -17.947697) (xy 26.480944 -17.918227)
			(xy 26.439752 -17.882532) (xy 26.404059 -17.841338) (xy 26.374592 -17.795484) (xy 26.35195 -17.745903)
			(xy 26.336595 -17.693605) (xy 26.328838 -17.639653) (xy 22.366505 -17.639653) (xy 22.358748 -17.693598)
			(xy 22.343392 -17.745892) (xy 22.320751 -17.795469) (xy 22.291284 -17.841318) (xy 22.255591 -17.882507)
			(xy 22.2144 -17.918197) (xy 22.168549 -17.947661) (xy 22.118972 -17.9703) (xy 22.066677 -17.985653)
			(xy 22.012729 -17.993406) (xy 21.985478 -17.993868) (xy 21.121878 -17.993868) (xy 21.094627 -17.993382)
			(xy 21.040679 -17.985625) (xy 20.988385 -17.97027) (xy 20.938808 -17.947629) (xy 20.892958 -17.918162)
			(xy 20.851768 -17.882471) (xy 20.816076 -17.841281) (xy 20.78661 -17.79543) (xy 20.763969 -17.745853)
			(xy 20.748614 -17.693559) (xy 20.740858 -17.639611) (xy 16.778525 -17.639611) (xy 16.778525 -17.639613)
			(xy 16.770768 -17.693564) (xy 16.755412 -17.745862) (xy 16.732769 -17.795442) (xy 16.703301 -17.841296)
			(xy 16.667607 -17.882488) (xy 16.626414 -17.918182) (xy 16.580561 -17.94765) (xy 16.53098 -17.970292)
			(xy 16.478682 -17.985648) (xy 16.424731 -17.993405) (xy 16.397478 -17.993868) (xy 15.533878 -17.993868)
			(xy 15.506627 -17.993382) (xy 15.452679 -17.985625) (xy 15.400385 -17.97027) (xy 15.350808 -17.947629)
			(xy 15.304958 -17.918162) (xy 15.263768 -17.882471) (xy 15.228076 -17.841281) (xy 15.19861 -17.79543)
			(xy 15.175969 -17.745853) (xy 15.160614 -17.693559) (xy 15.152858 -17.639611) (xy 0.509016 -17.639611)
			(xy 0.509016 -18.171947) (xy 131.633522 -18.171947) (xy 131.633522 -18.117453) (xy 131.641277 -18.063515)
			(xy 131.656629 -18.011229) (xy 131.679265 -17.961659) (xy 131.708725 -17.915816) (xy 131.744409 -17.874631)
			(xy 131.78559 -17.838944) (xy 131.831431 -17.80948) (xy 131.880999 -17.78684) (xy 131.933283 -17.771484)
			(xy 131.987221 -17.763724) (xy 132.014468 -17.763236) (xy 132.878068 -17.763236) (xy 132.905326 -17.763609)
			(xy 132.959286 -17.771363) (xy 133.011594 -17.786718) (xy 133.061184 -17.809361) (xy 133.107046 -17.838832)
			(xy 133.148248 -17.87453) (xy 133.183949 -17.915728) (xy 133.213423 -17.961588) (xy 133.236071 -18.011176)
			(xy 133.25143 -18.063483) (xy 133.259189 -18.117443) (xy 133.259189 -18.17195) (xy 137.033499 -18.17195)
			(xy 137.033499 -18.11745) (xy 137.041256 -18.063505) (xy 137.05661 -18.011212) (xy 137.079251 -17.961637)
			(xy 137.108716 -17.915789) (xy 137.144406 -17.874601) (xy 137.185595 -17.838911) (xy 137.231444 -17.809447)
			(xy 137.28102 -17.786807) (xy 137.333312 -17.771454) (xy 137.387258 -17.763699) (xy 137.414508 -17.763236)
			(xy 138.278108 -17.763236) (xy 138.305362 -17.763634) (xy 138.359315 -17.771393) (xy 138.411615 -17.78675)
			(xy 138.461197 -17.809395) (xy 138.507052 -17.838864) (xy 138.548246 -17.87456) (xy 138.58394 -17.915755)
			(xy 138.613409 -17.96161) (xy 138.636052 -18.011193) (xy 138.651409 -18.063493) (xy 138.659166 -18.117446)
			(xy 138.659166 -18.171946) (xy 140.633522 -18.171946) (xy 140.633522 -18.117454) (xy 140.641276 -18.063517)
			(xy 140.656627 -18.011232) (xy 140.679262 -17.961664) (xy 140.70872 -17.915822) (xy 140.744402 -17.874638)
			(xy 140.785582 -17.83895) (xy 140.83142 -17.809486) (xy 140.880986 -17.786845) (xy 140.933268 -17.771487)
			(xy 140.987204 -17.763726) (xy 141.01445 -17.763236) (xy 141.87805 -17.763236) (xy 141.905308 -17.763608)
			(xy 141.959271 -17.77136) (xy 142.011581 -17.786713) (xy 142.061173 -17.809355) (xy 142.107038 -17.838825)
			(xy 142.148241 -17.874523) (xy 142.183945 -17.915722) (xy 142.213421 -17.961583) (xy 142.236069 -18.011172)
			(xy 142.25143 -18.06348) (xy 142.259189 -18.117442) (xy 142.259189 -18.171951) (xy 185.748399 -18.171951)
			(xy 185.748399 -18.117449) (xy 185.756156 -18.063503) (xy 185.771511 -18.011209) (xy 185.794153 -17.961633)
			(xy 185.823619 -17.915784) (xy 185.859311 -17.874596) (xy 185.900502 -17.838906) (xy 185.946353 -17.809442)
			(xy 185.99593 -17.786804) (xy 186.048224 -17.771451) (xy 186.102171 -17.763698) (xy 186.129422 -17.763236)
			(xy 186.993022 -17.763236) (xy 187.020275 -17.763635) (xy 187.074227 -17.771395) (xy 187.126525 -17.786754)
			(xy 187.176105 -17.809399) (xy 187.201242 -17.825555) (xy 218.803143 -17.825555) (xy 218.803143 -17.771045)
			(xy 218.810901 -17.717091) (xy 218.826258 -17.66479) (xy 218.848903 -17.615207) (xy 218.878374 -17.569351)
			(xy 218.914071 -17.528157) (xy 218.955267 -17.492462) (xy 219.001124 -17.462993) (xy 219.050709 -17.440351)
			(xy 219.10301 -17.424996) (xy 219.156965 -17.417242) (xy 219.18422 -17.41678) (xy 220.04782 -17.41678)
			(xy 220.075069 -17.417292) (xy 220.129013 -17.42505) (xy 220.181304 -17.440407) (xy 220.230877 -17.463048)
			(xy 220.276723 -17.492514) (xy 220.31791 -17.528204) (xy 220.353598 -17.569393) (xy 220.383062 -17.615241)
			(xy 220.4057 -17.664815) (xy 220.421054 -17.717106) (xy 220.42881 -17.771051) (xy 220.42881 -17.825549)
			(xy 220.421054 -17.879494) (xy 220.4057 -17.931785) (xy 220.383062 -17.981359) (xy 220.353598 -18.027207)
			(xy 220.31791 -18.068396) (xy 220.276723 -18.104086) (xy 220.230877 -18.133552) (xy 220.181304 -18.156193)
			(xy 220.129013 -18.17155) (xy 220.075069 -18.179308) (xy 220.04782 -18.179796) (xy 219.18422 -18.179796)
			(xy 219.156965 -18.179358) (xy 219.10301 -18.171604) (xy 219.050709 -18.156249) (xy 219.001124 -18.133607)
			(xy 218.955267 -18.104138) (xy 218.914071 -18.068443) (xy 218.878374 -18.027249) (xy 218.848903 -17.981393)
			(xy 218.826258 -17.93181) (xy 218.810901 -17.879509) (xy 218.803143 -17.825555) (xy 187.201242 -17.825555)
			(xy 187.221958 -17.838869) (xy 187.263151 -17.874565) (xy 187.298844 -17.915759) (xy 187.328311 -17.961614)
			(xy 187.350954 -18.011196) (xy 187.366309 -18.063495) (xy 187.374066 -18.117447) (xy 187.374066 -18.171953)
			(xy 187.366309 -18.225905) (xy 187.350954 -18.278204) (xy 187.328311 -18.327786) (xy 187.298844 -18.373641)
			(xy 187.263151 -18.414835) (xy 187.221958 -18.450531) (xy 187.176105 -18.480001) (xy 187.126525 -18.502646)
			(xy 187.074227 -18.518005) (xy 187.020275 -18.525765) (xy 186.993022 -18.526252) (xy 186.129422 -18.526252)
			(xy 186.102171 -18.525702) (xy 186.048224 -18.517949) (xy 185.99593 -18.502596) (xy 185.946353 -18.479958)
			(xy 185.900502 -18.450494) (xy 185.859311 -18.414804) (xy 185.823619 -18.373616) (xy 185.794153 -18.327767)
			(xy 185.771511 -18.278191) (xy 185.756156 -18.225897) (xy 185.748399 -18.171951) (xy 142.259189 -18.171951)
			(xy 142.259189 -18.171958) (xy 142.25143 -18.22592) (xy 142.236069 -18.278228) (xy 142.213421 -18.327817)
			(xy 142.183945 -18.373678) (xy 142.148241 -18.414877) (xy 142.107038 -18.450575) (xy 142.061173 -18.480045)
			(xy 142.011581 -18.502687) (xy 141.959271 -18.51804) (xy 141.905308 -18.525792) (xy 141.87805 -18.526252)
			(xy 141.01445 -18.526252) (xy 140.987204 -18.525674) (xy 140.933268 -18.517913) (xy 140.880986 -18.502555)
			(xy 140.83142 -18.479914) (xy 140.785582 -18.45045) (xy 140.744402 -18.414762) (xy 140.70872 -18.373578)
			(xy 140.679262 -18.327736) (xy 140.656627 -18.278168) (xy 140.641276 -18.225883) (xy 140.633522 -18.171946)
			(xy 138.659166 -18.171946) (xy 138.659166 -18.171954) (xy 138.651409 -18.225907) (xy 138.636052 -18.278207)
			(xy 138.613409 -18.32779) (xy 138.58394 -18.373645) (xy 138.548246 -18.41484) (xy 138.507052 -18.450536)
			(xy 138.461197 -18.480005) (xy 138.411615 -18.50265) (xy 138.359315 -18.518007) (xy 138.305362 -18.525766)
			(xy 138.278108 -18.526252) (xy 137.414508 -18.526252) (xy 137.387258 -18.525701) (xy 137.333312 -18.517946)
			(xy 137.28102 -18.502593) (xy 137.231444 -18.479953) (xy 137.185595 -18.450489) (xy 137.144406 -18.414799)
			(xy 137.108716 -18.373611) (xy 137.079251 -18.327763) (xy 137.05661 -18.278188) (xy 137.041256 -18.225895)
			(xy 137.033499 -18.17195) (xy 133.259189 -18.17195) (xy 133.259189 -18.171957) (xy 133.25143 -18.225917)
			(xy 133.236071 -18.278224) (xy 133.213423 -18.327812) (xy 133.183949 -18.373672) (xy 133.148248 -18.41487)
			(xy 133.107046 -18.450568) (xy 133.061184 -18.480039) (xy 133.011594 -18.502682) (xy 132.959286 -18.518037)
			(xy 132.905326 -18.525791) (xy 132.878068 -18.526252) (xy 132.014468 -18.526252) (xy 131.987221 -18.525676)
			(xy 131.933283 -18.517916) (xy 131.880999 -18.50256) (xy 131.831431 -18.47992) (xy 131.78559 -18.450456)
			(xy 131.744409 -18.414769) (xy 131.708725 -18.373584) (xy 131.679265 -18.327741) (xy 131.656629 -18.278171)
			(xy 131.641277 -18.225885) (xy 131.633522 -18.171947) (xy 0.509016 -18.171947) (xy 0.509016 -19.163611)
			(xy 17.946858 -19.163611) (xy 17.946858 -19.109109) (xy 17.954614 -19.055161) (xy 17.969969 -19.002867)
			(xy 17.99261 -18.95329) (xy 18.022076 -18.907439) (xy 18.057768 -18.866249) (xy 18.098958 -18.830558)
			(xy 18.144808 -18.801091) (xy 18.194385 -18.77845) (xy 18.246679 -18.763095) (xy 18.300627 -18.755338)
			(xy 18.327878 -18.754852) (xy 19.191478 -18.754852) (xy 19.218731 -18.755315) (xy 19.272682 -18.763072)
			(xy 19.32498 -18.778428) (xy 19.374561 -18.80107) (xy 19.420414 -18.830538) (xy 19.461607 -18.866232)
			(xy 19.497301 -18.907424) (xy 19.526769 -18.953278) (xy 19.549412 -19.002858) (xy 19.564768 -19.055156)
			(xy 19.572525 -19.109107) (xy 19.572525 -19.163613) (xy 19.572519 -19.163653) (xy 23.534838 -19.163653)
			(xy 23.534838 -19.109147) (xy 23.542595 -19.055195) (xy 23.55795 -19.002897) (xy 23.580592 -18.953316)
			(xy 23.610059 -18.907462) (xy 23.645752 -18.866268) (xy 23.686944 -18.830573) (xy 23.732797 -18.801103)
			(xy 23.782376 -18.778458) (xy 23.834674 -18.763099) (xy 23.888625 -18.755339) (xy 23.915878 -18.754852)
			(xy 24.779478 -18.754852) (xy 24.806729 -18.755394) (xy 24.860677 -18.763147) (xy 24.912972 -18.7785)
			(xy 24.962549 -18.801139) (xy 25.0084 -18.830603) (xy 25.049591 -18.866293) (xy 25.085284 -18.907482)
			(xy 25.114751 -18.953331) (xy 25.137392 -19.002908) (xy 25.152748 -19.055202) (xy 25.160505 -19.109149)
			(xy 25.160505 -19.163651) (xy 25.160505 -19.163653) (xy 29.122838 -19.163653) (xy 29.122838 -19.109147)
			(xy 29.130595 -19.055195) (xy 29.14595 -19.002897) (xy 29.168592 -18.953316) (xy 29.198059 -18.907462)
			(xy 29.233752 -18.866268) (xy 29.274944 -18.830573) (xy 29.320797 -18.801103) (xy 29.370376 -18.778458)
			(xy 29.422674 -18.763099) (xy 29.476625 -18.755339) (xy 29.503878 -18.754852) (xy 30.367478 -18.754852)
			(xy 30.394729 -18.755394) (xy 30.448677 -18.763147) (xy 30.500972 -18.7785) (xy 30.550549 -18.801139)
			(xy 30.5964 -18.830603) (xy 30.637591 -18.866293) (xy 30.673284 -18.907482) (xy 30.702751 -18.953331)
			(xy 30.725392 -19.002908) (xy 30.740748 -19.055202) (xy 30.748505 -19.109149) (xy 30.748505 -19.163651)
			(xy 30.748505 -19.163653) (xy 34.710838 -19.163653) (xy 34.710838 -19.109147) (xy 34.718595 -19.055195)
			(xy 34.73395 -19.002897) (xy 34.756592 -18.953316) (xy 34.786059 -18.907462) (xy 34.821752 -18.866268)
			(xy 34.862944 -18.830573) (xy 34.908797 -18.801103) (xy 34.958376 -18.778458) (xy 35.010674 -18.763099)
			(xy 35.064625 -18.755339) (xy 35.091878 -18.754852) (xy 35.955478 -18.754852) (xy 35.982729 -18.755394)
			(xy 36.036677 -18.763147) (xy 36.088972 -18.7785) (xy 36.138549 -18.801139) (xy 36.1844 -18.830603)
			(xy 36.225591 -18.866293) (xy 36.261284 -18.907482) (xy 36.290751 -18.953331) (xy 36.313392 -19.002908)
			(xy 36.328748 -19.055202) (xy 36.336505 -19.109149) (xy 36.336505 -19.163651) (xy 36.336505 -19.163654)
			(xy 40.604638 -19.163654) (xy 40.604638 -19.109146) (xy 40.612395 -19.055193) (xy 40.627751 -19.002894)
			(xy 40.650395 -18.953312) (xy 40.679863 -18.907457) (xy 40.715558 -18.866262) (xy 40.756752 -18.830567)
			(xy 40.802606 -18.801097) (xy 40.852188 -18.778454) (xy 40.904487 -18.763096) (xy 40.95844 -18.755338)
			(xy 40.985694 -18.754852) (xy 41.849294 -18.754852) (xy 41.876544 -18.755395) (xy 41.93049 -18.76315)
			(xy 41.982783 -18.778504) (xy 42.032359 -18.801144) (xy 42.078208 -18.830609) (xy 42.119397 -18.866299)
			(xy 42.155088 -18.907487) (xy 42.184553 -18.953336) (xy 42.207194 -19.002911) (xy 42.222548 -19.055204)
			(xy 42.230305 -19.10915) (xy 42.230305 -19.16365) (xy 42.230304 -19.163654) (xy 46.192638 -19.163654)
			(xy 46.192638 -19.109146) (xy 46.200395 -19.055193) (xy 46.215751 -19.002894) (xy 46.238395 -18.953312)
			(xy 46.267863 -18.907457) (xy 46.303558 -18.866262) (xy 46.344752 -18.830567) (xy 46.390606 -18.801097)
			(xy 46.440188 -18.778454) (xy 46.492487 -18.763096) (xy 46.54644 -18.755338) (xy 46.573694 -18.754852)
			(xy 47.437294 -18.754852) (xy 47.464544 -18.755395) (xy 47.51849 -18.76315) (xy 47.570783 -18.778504)
			(xy 47.620359 -18.801144) (xy 47.666208 -18.830609) (xy 47.707397 -18.866299) (xy 47.743088 -18.907487)
			(xy 47.772553 -18.953336) (xy 47.795194 -19.002911) (xy 47.810548 -19.055204) (xy 47.818305 -19.10915)
			(xy 47.818305 -19.16365) (xy 47.818304 -19.163657) (xy 51.814615 -19.163657) (xy 51.814615 -19.109143)
			(xy 51.822374 -19.055184) (xy 51.837733 -19.002878) (xy 51.86038 -18.95329) (xy 51.889854 -18.907431)
			(xy 51.925554 -18.866233) (xy 51.966755 -18.830536) (xy 52.012617 -18.801065) (xy 52.062206 -18.778422)
			(xy 52.114513 -18.763067) (xy 52.168473 -18.755313) (xy 52.19573 -18.754852) (xy 53.05933 -18.754852)
			(xy 53.086577 -18.75542) (xy 53.140516 -18.763179) (xy 53.192801 -18.778535) (xy 53.24237 -18.801176)
			(xy 53.288211 -18.83064) (xy 53.329394 -18.866328) (xy 53.365078 -18.907513) (xy 53.394538 -18.953357)
			(xy 53.417175 -19.002927) (xy 53.432527 -19.055214) (xy 53.440282 -19.109153) (xy 53.440282 -19.163647)
			(xy 53.440281 -19.163657) (xy 57.402615 -19.163657) (xy 57.402615 -19.109143) (xy 57.410374 -19.055184)
			(xy 57.425733 -19.002878) (xy 57.44838 -18.95329) (xy 57.477854 -18.907431) (xy 57.513554 -18.866233)
			(xy 57.554755 -18.830536) (xy 57.600617 -18.801065) (xy 57.650206 -18.778422) (xy 57.702513 -18.763067)
			(xy 57.756473 -18.755313) (xy 57.78373 -18.754852) (xy 58.64733 -18.754852) (xy 58.674577 -18.75542)
			(xy 58.728516 -18.763179) (xy 58.780801 -18.778535) (xy 58.83037 -18.801176) (xy 58.876211 -18.83064)
			(xy 58.917394 -18.866328) (xy 58.953078 -18.907513) (xy 58.982538 -18.953357) (xy 59.005175 -19.002927)
			(xy 59.020527 -19.055214) (xy 59.028282 -19.109153) (xy 59.028282 -19.163647) (xy 59.020527 -19.217586)
			(xy 59.005175 -19.269873) (xy 58.982538 -19.319443) (xy 58.953078 -19.365287) (xy 58.917394 -19.406472)
			(xy 58.876211 -19.44216) (xy 58.83037 -19.471624) (xy 58.780801 -19.494265) (xy 58.728516 -19.509621)
			(xy 58.674577 -19.51738) (xy 58.64733 -19.517868) (xy 57.78373 -19.517868) (xy 57.756473 -19.517487)
			(xy 57.702513 -19.509733) (xy 57.650206 -19.494378) (xy 57.600617 -19.471735) (xy 57.554755 -19.442264)
			(xy 57.513554 -19.406567) (xy 57.477854 -19.365369) (xy 57.44838 -19.31951) (xy 57.425733 -19.269922)
			(xy 57.410374 -19.217616) (xy 57.402615 -19.163657) (xy 53.440281 -19.163657) (xy 53.432527 -19.217586)
			(xy 53.417175 -19.269873) (xy 53.394538 -19.319443) (xy 53.365078 -19.365287) (xy 53.329394 -19.406472)
			(xy 53.288211 -19.44216) (xy 53.24237 -19.471624) (xy 53.192801 -19.494265) (xy 53.140516 -19.509621)
			(xy 53.086577 -19.51738) (xy 53.05933 -19.517868) (xy 52.19573 -19.517868) (xy 52.168473 -19.517487)
			(xy 52.114513 -19.509733) (xy 52.062206 -19.494378) (xy 52.012617 -19.471735) (xy 51.966755 -19.442264)
			(xy 51.925554 -19.406567) (xy 51.889854 -19.365369) (xy 51.86038 -19.31951) (xy 51.837733 -19.269922)
			(xy 51.822374 -19.217616) (xy 51.814615 -19.163657) (xy 47.818304 -19.163657) (xy 47.810548 -19.217596)
			(xy 47.795194 -19.269889) (xy 47.772553 -19.319464) (xy 47.743088 -19.365313) (xy 47.707397 -19.406501)
			(xy 47.666208 -19.442191) (xy 47.620359 -19.471656) (xy 47.570783 -19.494296) (xy 47.51849 -19.50965)
			(xy 47.464544 -19.517405) (xy 47.437294 -19.517868) (xy 46.573694 -19.517868) (xy 46.54644 -19.517462)
			(xy 46.492487 -19.509704) (xy 46.440188 -19.494346) (xy 46.390606 -19.471703) (xy 46.344752 -19.442233)
			(xy 46.303558 -19.406538) (xy 46.267863 -19.365343) (xy 46.238395 -19.319488) (xy 46.215751 -19.269906)
			(xy 46.200395 -19.217607) (xy 46.192638 -19.163654) (xy 42.230304 -19.163654) (xy 42.222548 -19.217596)
			(xy 42.207194 -19.269889) (xy 42.184553 -19.319464) (xy 42.155088 -19.365313) (xy 42.119397 -19.406501)
			(xy 42.078208 -19.442191) (xy 42.032359 -19.471656) (xy 41.982783 -19.494296) (xy 41.93049 -19.50965)
			(xy 41.876544 -19.517405) (xy 41.849294 -19.517868) (xy 40.985694 -19.517868) (xy 40.95844 -19.517462)
			(xy 40.904487 -19.509704) (xy 40.852188 -19.494346) (xy 40.802606 -19.471703) (xy 40.756752 -19.442233)
			(xy 40.715558 -19.406538) (xy 40.679863 -19.365343) (xy 40.650395 -19.319488) (xy 40.627751 -19.269906)
			(xy 40.612395 -19.217607) (xy 40.604638 -19.163654) (xy 36.336505 -19.163654) (xy 36.328748 -19.217598)
			(xy 36.313392 -19.269892) (xy 36.290751 -19.319469) (xy 36.261284 -19.365318) (xy 36.225591 -19.406507)
			(xy 36.1844 -19.442197) (xy 36.138549 -19.471661) (xy 36.088972 -19.4943) (xy 36.036677 -19.509653)
			(xy 35.982729 -19.517406) (xy 35.955478 -19.517868) (xy 35.091878 -19.517868) (xy 35.064625 -19.517461)
			(xy 35.010674 -19.509701) (xy 34.958376 -19.494342) (xy 34.908797 -19.471697) (xy 34.862944 -19.442227)
			(xy 34.821752 -19.406532) (xy 34.786059 -19.365338) (xy 34.756592 -19.319484) (xy 34.73395 -19.269903)
			(xy 34.718595 -19.217605) (xy 34.710838 -19.163653) (xy 30.748505 -19.163653) (xy 30.740748 -19.217598)
			(xy 30.725392 -19.269892) (xy 30.702751 -19.319469) (xy 30.673284 -19.365318) (xy 30.637591 -19.406507)
			(xy 30.5964 -19.442197) (xy 30.550549 -19.471661) (xy 30.500972 -19.4943) (xy 30.448677 -19.509653)
			(xy 30.394729 -19.517406) (xy 30.367478 -19.517868) (xy 29.503878 -19.517868) (xy 29.476625 -19.517461)
			(xy 29.422674 -19.509701) (xy 29.370376 -19.494342) (xy 29.320797 -19.471697) (xy 29.274944 -19.442227)
			(xy 29.233752 -19.406532) (xy 29.198059 -19.365338) (xy 29.168592 -19.319484) (xy 29.14595 -19.269903)
			(xy 29.130595 -19.217605) (xy 29.122838 -19.163653) (xy 25.160505 -19.163653) (xy 25.152748 -19.217598)
			(xy 25.137392 -19.269892) (xy 25.114751 -19.319469) (xy 25.085284 -19.365318) (xy 25.049591 -19.406507)
			(xy 25.0084 -19.442197) (xy 24.962549 -19.471661) (xy 24.912972 -19.4943) (xy 24.860677 -19.509653)
			(xy 24.806729 -19.517406) (xy 24.779478 -19.517868) (xy 23.915878 -19.517868) (xy 23.888625 -19.517461)
			(xy 23.834674 -19.509701) (xy 23.782376 -19.494342) (xy 23.732797 -19.471697) (xy 23.686944 -19.442227)
			(xy 23.645752 -19.406532) (xy 23.610059 -19.365338) (xy 23.580592 -19.319484) (xy 23.55795 -19.269903)
			(xy 23.542595 -19.217605) (xy 23.534838 -19.163653) (xy 19.572519 -19.163653) (xy 19.564768 -19.217564)
			(xy 19.549412 -19.269862) (xy 19.526769 -19.319442) (xy 19.497301 -19.365296) (xy 19.461607 -19.406488)
			(xy 19.420414 -19.442182) (xy 19.374561 -19.47165) (xy 19.32498 -19.494292) (xy 19.272682 -19.509648)
			(xy 19.218731 -19.517405) (xy 19.191478 -19.517868) (xy 18.327878 -19.517868) (xy 18.300627 -19.517382)
			(xy 18.246679 -19.509625) (xy 18.194385 -19.49427) (xy 18.144808 -19.471629) (xy 18.098958 -19.442162)
			(xy 18.057768 -19.406471) (xy 18.022076 -19.365281) (xy 17.99261 -19.31943) (xy 17.969969 -19.269853)
			(xy 17.954614 -19.217559) (xy 17.946858 -19.163611) (xy 0.509016 -19.163611) (xy 0.509016 -20.187751)
			(xy 138.828766 -20.187751) (xy 138.828766 -20.133249) (xy 138.836522 -20.079301) (xy 138.851877 -20.027006)
			(xy 138.874517 -19.977429) (xy 138.903982 -19.931578) (xy 138.939673 -19.890387) (xy 138.980862 -19.854694)
			(xy 139.026711 -19.825227) (xy 139.076288 -19.802584) (xy 139.128582 -19.787226) (xy 139.182529 -19.779467)
			(xy 139.20978 -19.77898) (xy 140.07338 -19.77898) (xy 140.100633 -19.779466) (xy 140.154584 -19.78722)
			(xy 140.206883 -19.802574) (xy 140.256464 -19.825215) (xy 140.302318 -19.854681) (xy 140.343512 -19.890374)
			(xy 140.379207 -19.931566) (xy 140.408676 -19.977418) (xy 140.431319 -20.026998) (xy 140.446675 -20.079296)
			(xy 140.454433 -20.133247) (xy 140.454433 -20.187753) (xy 140.446675 -20.241704) (xy 140.431319 -20.294002)
			(xy 140.408676 -20.343582) (xy 140.379207 -20.389434) (xy 140.343512 -20.430626) (xy 140.302318 -20.466319)
			(xy 140.256464 -20.495785) (xy 140.206883 -20.518426) (xy 140.154584 -20.53378) (xy 140.100633 -20.541534)
			(xy 140.07338 -20.541996) (xy 139.20978 -20.541996) (xy 139.182529 -20.541533) (xy 139.128582 -20.533774)
			(xy 139.076288 -20.518416) (xy 139.026711 -20.495773) (xy 138.980862 -20.466306) (xy 138.939673 -20.430613)
			(xy 138.903982 -20.389422) (xy 138.874517 -20.343571) (xy 138.851877 -20.293994) (xy 138.836522 -20.241699)
			(xy 138.828766 -20.187751) (xy 0.509016 -20.187751) (xy 0.509016 -21.521251) (xy 15.232366 -21.521251)
			(xy 15.232366 -21.466749) (xy 15.240122 -21.412801) (xy 15.255477 -21.360506) (xy 15.278117 -21.310929)
			(xy 15.307582 -21.265078) (xy 15.343273 -21.223887) (xy 15.384462 -21.188194) (xy 15.430311 -21.158727)
			(xy 15.479888 -21.136084) (xy 15.532182 -21.120726) (xy 15.586129 -21.112967) (xy 15.61338 -21.11248)
			(xy 16.47698 -21.11248) (xy 16.504233 -21.112966) (xy 16.558184 -21.12072) (xy 16.610483 -21.136074)
			(xy 16.660064 -21.158715) (xy 16.705918 -21.188181) (xy 16.747112 -21.223874) (xy 16.782807 -21.265066)
			(xy 16.812276 -21.310918) (xy 16.834919 -21.360498) (xy 16.850275 -21.412796) (xy 16.858033 -21.466747)
			(xy 16.858033 -21.521253) (xy 16.850275 -21.575204) (xy 16.834919 -21.627502) (xy 16.812276 -21.677082)
			(xy 16.782807 -21.722934) (xy 16.747112 -21.764126) (xy 16.705918 -21.799819) (xy 16.660064 -21.829285)
			(xy 16.610483 -21.851926) (xy 16.558184 -21.86728) (xy 16.504233 -21.875034) (xy 16.47698 -21.875496)
			(xy 15.61338 -21.875496) (xy 15.586129 -21.875033) (xy 15.532182 -21.867274) (xy 15.479888 -21.851916)
			(xy 15.430311 -21.829273) (xy 15.384462 -21.799806) (xy 15.343273 -21.764113) (xy 15.307582 -21.722922)
			(xy 15.278117 -21.677071) (xy 15.255477 -21.627494) (xy 15.240122 -21.575199) (xy 15.232366 -21.521251)
			(xy 0.509016 -21.521251) (xy 0.509016 -24.929338) (xy 133.555232 -24.929338) (xy 133.555232 -24.065738)
			(xy 133.555718 -24.038487) (xy 133.563474 -23.984539) (xy 133.578829 -23.932244) (xy 133.601471 -23.882667)
			(xy 133.630937 -23.836817) (xy 133.666628 -23.795626) (xy 133.707819 -23.759935) (xy 133.753669 -23.730469)
			(xy 133.803246 -23.707827) (xy 133.855541 -23.692472) (xy 133.909489 -23.684716) (xy 133.963991 -23.684716)
			(xy 134.017939 -23.692472) (xy 134.070234 -23.707827) (xy 134.119811 -23.730469) (xy 134.165661 -23.759935)
			(xy 134.206852 -23.795626) (xy 134.242543 -23.836817) (xy 134.272009 -23.882667) (xy 134.294651 -23.932244)
			(xy 134.310006 -23.984539) (xy 134.317762 -24.038487) (xy 134.318248 -24.065738) (xy 134.318248 -24.929338)
			(xy 134.317762 -24.956589) (xy 134.310006 -25.010537) (xy 134.294651 -25.062832) (xy 134.272009 -25.112409)
			(xy 134.242543 -25.158259) (xy 134.206852 -25.19945) (xy 134.165661 -25.235141) (xy 134.119811 -25.264607)
			(xy 134.070234 -25.287249) (xy 134.017939 -25.302604) (xy 133.963991 -25.31036) (xy 133.909489 -25.31036)
			(xy 133.855541 -25.302604) (xy 133.803246 -25.287249) (xy 133.753669 -25.264607) (xy 133.707819 -25.235141)
			(xy 133.666628 -25.19945) (xy 133.630937 -25.158259) (xy 133.601471 -25.112409) (xy 133.578829 -25.062832)
			(xy 133.563474 -25.010537) (xy 133.555718 -24.956589) (xy 133.555232 -24.929338) (xy 0.509016 -24.929338)
			(xy 0.509016 -29.070615) (xy 12.244307 -29.070615) (xy 12.252198 -28.941486) (xy 12.268182 -28.813107)
			(xy 12.292195 -28.685984) (xy 12.324144 -28.560621) (xy 12.363901 -28.437511) (xy 12.41131 -28.31714)
			(xy 12.466183 -28.199984) (xy 12.528305 -28.086504) (xy 12.59743 -27.97715) (xy 12.673285 -27.872351)
			(xy 12.75557 -27.772522) (xy 12.843962 -27.678057) (xy 12.938111 -27.589329) (xy 13.037646 -27.506688)
			(xy 13.142173 -27.43046) (xy 13.25128 -27.360945) (xy 13.364537 -27.298419) (xy 13.481497 -27.243128)
			(xy 13.601698 -27.19529) (xy 13.724665 -27.155093) (xy 13.849914 -27.122698) (xy 13.97695 -27.098231)
			(xy 14.105271 -27.081789) (xy 14.234372 -27.073437) (xy 14.363742 -27.073208) (xy 14.492871 -27.081103)
			(xy 14.62125 -27.097091) (xy 14.748372 -27.121108) (xy 14.873734 -27.15306) (xy 14.996843 -27.19282)
			(xy 15.117212 -27.240232) (xy 15.234367 -27.295109) (xy 15.347845 -27.357234) (xy 15.457198 -27.426362)
			(xy 15.561994 -27.50222) (xy 15.661821 -27.584508) (xy 15.709392 -27.628342) (xy 16.877792 -28.721304)
			(xy 16.92464 -28.765906) (xy 17.013363 -28.860052) (xy 17.096 -28.959584) (xy 17.172224 -29.064107)
			(xy 17.241734 -29.17321) (xy 17.304257 -29.286463) (xy 17.359545 -29.403418) (xy 17.407381 -29.523614)
			(xy 17.447575 -29.646576) (xy 17.479969 -29.771819) (xy 17.504435 -29.898849) (xy 17.520877 -30.027165)
			(xy 17.529229 -30.15626) (xy 17.529459 -30.285624) (xy 17.521566 -30.414748) (xy 17.50558 -30.543122)
			(xy 17.481566 -30.670238) (xy 17.449617 -30.795596) (xy 17.40986 -30.9187) (xy 17.362452 -31.039065)
			(xy 17.30758 -31.156215) (xy 17.24546 -31.26969) (xy 17.176338 -31.379039) (xy 17.100486 -31.483833)
			(xy 17.018204 -31.583657) (xy 16.929816 -31.678118) (xy 16.835671 -31.766843) (xy 16.736141 -31.849481)
			(xy 16.631619 -31.925706) (xy 16.522517 -31.995218) (xy 16.409265 -32.057743) (xy 16.292311 -32.113033)
			(xy 16.172116 -32.16087) (xy 16.049154 -32.201066) (xy 15.923911 -32.233462) (xy 15.796882 -32.25793)
			(xy 15.668566 -32.274374) (xy 15.539471 -32.282728) (xy 15.410107 -32.28296) (xy 15.280983 -32.275069)
			(xy 15.152609 -32.259085) (xy 15.025493 -32.235073) (xy 14.900134 -32.203126) (xy 14.77703 -32.163371)
			(xy 14.656664 -32.115965) (xy 14.539512 -32.061094) (xy 14.426037 -31.998976) (xy 14.316687 -31.929855)
			(xy 14.211892 -31.854005) (xy 14.112066 -31.771724) (xy 14.064488 -31.727902) (xy 12.896088 -30.63494)
			(xy 12.849198 -30.590378) (xy 12.760467 -30.496232) (xy 12.677823 -30.3967) (xy 12.601592 -30.292174)
			(xy 12.532074 -30.183069) (xy 12.469545 -30.069814) (xy 12.41425 -29.952855) (xy 12.366409 -29.832656)
			(xy 12.32621 -29.70969) (xy 12.293811 -29.584442) (xy 12.26934 -29.457407) (xy 12.252895 -29.329086)
			(xy 12.244539 -29.199985) (xy 12.244307 -29.070615) (xy 0.509016 -29.070615) (xy 0.509016 -37.099629)
			(xy 170.600616 -37.099629) (xy 170.600616 -37.000299) (xy 170.608608 -36.901292) (xy 170.624542 -36.803249)
			(xy 170.648313 -36.706806) (xy 170.679768 -36.612588) (xy 170.718701 -36.521208) (xy 170.764862 -36.433256)
			(xy 170.81795 -36.349304) (xy 170.877621 -36.269895) (xy 170.943489 -36.195546) (xy 171.015126 -36.126738)
			(xy 171.092067 -36.063918) (xy 171.173813 -36.007493) (xy 171.259835 -35.957828) (xy 171.349574 -35.915246)
			(xy 171.442448 -35.880024) (xy 171.537856 -35.852388) (xy 171.635178 -35.83252) (xy 171.733783 -35.820547)
			(xy 171.833032 -35.816548) (xy 171.932281 -35.820547) (xy 172.030886 -35.83252) (xy 172.128208 -35.852388)
			(xy 172.223616 -35.880024) (xy 172.31649 -35.915246) (xy 172.406229 -35.957828) (xy 172.492251 -36.007493)
			(xy 172.573997 -36.063918) (xy 172.650938 -36.126738) (xy 172.722575 -36.195546) (xy 172.788443 -36.269895)
			(xy 172.848114 -36.349304) (xy 172.901202 -36.433256) (xy 172.947363 -36.521208) (xy 172.986296 -36.612588)
			(xy 173.017751 -36.706806) (xy 173.041522 -36.803249) (xy 173.057456 -36.901292) (xy 173.065448 -37.000299)
			(xy 173.065948 -37.049964) (xy 173.065448 -37.099629) (xy 173.057456 -37.198636) (xy 173.041522 -37.296679)
			(xy 173.017751 -37.393122) (xy 172.986296 -37.48734) (xy 172.947363 -37.57872) (xy 172.901202 -37.666672)
			(xy 172.848114 -37.750624) (xy 172.788443 -37.830033) (xy 172.722575 -37.904382) (xy 172.650938 -37.97319)
			(xy 172.573997 -38.03601) (xy 172.492251 -38.092435) (xy 172.406229 -38.1421) (xy 172.31649 -38.184682)
			(xy 172.223616 -38.219904) (xy 172.128208 -38.24754) (xy 172.030886 -38.267408) (xy 171.932281 -38.279381)
			(xy 171.833032 -38.283381) (xy 171.733783 -38.279381) (xy 171.635178 -38.267408) (xy 171.537856 -38.24754)
			(xy 171.442448 -38.219904) (xy 171.349574 -38.184682) (xy 171.259835 -38.1421) (xy 171.173813 -38.092435)
			(xy 171.092067 -38.03601) (xy 171.015126 -37.97319) (xy 170.943489 -37.904382) (xy 170.877621 -37.830033)
			(xy 170.81795 -37.750624) (xy 170.764862 -37.666672) (xy 170.718701 -37.57872) (xy 170.679768 -37.48734)
			(xy 170.648313 -37.393122) (xy 170.624542 -37.296679) (xy 170.608608 -37.198636) (xy 170.600616 -37.099629)
			(xy 0.509016 -37.099629) (xy 0.509016 -39.657528) (xy 357.003604 -39.657528) (xy 357.003604 -38.793928)
			(xy 357.00409 -38.766659) (xy 357.011852 -38.712675) (xy 357.027217 -38.660345) (xy 357.049874 -38.610735)
			(xy 357.07936 -38.564854) (xy 357.115075 -38.523637) (xy 357.156292 -38.487922) (xy 357.202173 -38.458436)
			(xy 357.251783 -38.435779) (xy 357.304113 -38.420414) (xy 357.358097 -38.412652) (xy 357.412635 -38.412652)
			(xy 357.466619 -38.420414) (xy 357.518949 -38.435779) (xy 357.568559 -38.458436) (xy 357.61444 -38.487922)
			(xy 357.655657 -38.523637) (xy 357.691372 -38.564854) (xy 357.720858 -38.610735) (xy 357.743515 -38.660345)
			(xy 357.75888 -38.712675) (xy 357.766642 -38.766659) (xy 357.767128 -38.793928) (xy 357.767128 -39.657528)
			(xy 357.766642 -39.684797) (xy 357.75888 -39.738781) (xy 357.743515 -39.791111) (xy 357.720858 -39.840721)
			(xy 357.691372 -39.886602) (xy 357.655657 -39.927819) (xy 357.61444 -39.963534) (xy 357.568559 -39.99302)
			(xy 357.518949 -40.015677) (xy 357.466619 -40.031042) (xy 357.412635 -40.038804) (xy 357.358097 -40.038804)
			(xy 357.304113 -40.031042) (xy 357.251783 -40.015677) (xy 357.202173 -39.99302) (xy 357.156292 -39.963534)
			(xy 357.115075 -39.927819) (xy 357.07936 -39.886602) (xy 357.049874 -39.840721) (xy 357.027217 -39.791111)
			(xy 357.011852 -39.738781) (xy 357.00409 -39.684797) (xy 357.003604 -39.657528) (xy 0.509016 -39.657528)
			(xy 0.509016 -40.744902) (xy 235.083357 -40.744902) (xy 235.087362 -40.656994) (xy 235.099345 -40.569814)
			(xy 235.119205 -40.484085) (xy 235.14678 -40.400517) (xy 235.181839 -40.319803) (xy 235.224092 -40.242611)
			(xy 235.27319 -40.169582) (xy 235.328726 -40.10132) (xy 235.390238 -40.03839) (xy 235.457219 -39.981316)
			(xy 235.529112 -39.930568) (xy 235.605321 -39.886568) (xy 235.685216 -39.849681) (xy 235.768135 -39.820212)
			(xy 235.85339 -39.798405) (xy 235.940274 -39.784441) (xy 236.028068 -39.778435) (xy 236.116045 -39.780439)
			(xy 236.203475 -39.790434) (xy 236.289634 -39.808338) (xy 236.373808 -39.834002) (xy 236.455299 -39.867215)
			(xy 236.533433 -39.907701) (xy 236.607561 -39.955123) (xy 236.677069 -40.00909) (xy 236.741383 -40.069155)
			(xy 236.799967 -40.134819) (xy 236.852338 -40.205538) (xy 236.898061 -40.280726) (xy 236.936758 -40.359761)
			(xy 236.968107 -40.441987) (xy 236.991849 -40.526723) (xy 237.007787 -40.613267) (xy 237.015789 -40.700902)
			(xy 237.01629 -40.744902) (xy 237.015789 -40.788902) (xy 237.007787 -40.876537) (xy 236.991849 -40.963081)
			(xy 236.968107 -41.047817) (xy 236.936758 -41.130043) (xy 236.898061 -41.209078) (xy 236.852338 -41.284266)
			(xy 236.799967 -41.354985) (xy 236.741383 -41.420649) (xy 236.677069 -41.480714) (xy 236.607561 -41.534681)
			(xy 236.533433 -41.582103) (xy 236.455299 -41.622589) (xy 236.373808 -41.655802) (xy 236.289634 -41.681466)
			(xy 236.203475 -41.69937) (xy 236.116045 -41.709365) (xy 236.028068 -41.711369) (xy 235.940274 -41.705363)
			(xy 235.85339 -41.691399) (xy 235.768135 -41.669592) (xy 235.685216 -41.640123) (xy 235.605321 -41.603236)
			(xy 235.529112 -41.559236) (xy 235.457219 -41.508488) (xy 235.390238 -41.451414) (xy 235.328726 -41.388484)
			(xy 235.27319 -41.320222) (xy 235.224092 -41.247193) (xy 235.181839 -41.170001) (xy 235.14678 -41.089287)
			(xy 235.119205 -41.005719) (xy 235.099345 -40.91999) (xy 235.087362 -40.83281) (xy 235.083357 -40.744902)
			(xy 0.509016 -40.744902) (xy 0.509016 -43.999912) (xy 16.983969 -43.999912) (xy 16.987993 -43.914144)
			(xy 17.000031 -43.82913) (xy 17.019978 -43.745616) (xy 17.047657 -43.664337) (xy 17.082825 -43.586008)
			(xy 17.125174 -43.511315) (xy 17.174331 -43.440917) (xy 17.229864 -43.375431) (xy 17.291286 -43.315433)
			(xy 17.358055 -43.26145) (xy 17.429587 -43.213957) (xy 17.505251 -43.173371) (xy 17.584384 -43.140048)
			(xy 17.666289 -43.114282) (xy 17.750247 -43.096299) (xy 17.835521 -43.086257) (xy 17.92136 -43.084244)
			(xy 18.00701 -43.090278) (xy 18.091718 -43.104306) (xy 18.174741 -43.126205) (xy 18.255349 -43.155782)
			(xy 18.332833 -43.192777) (xy 18.406512 -43.236865) (xy 18.475738 -43.287659) (xy 18.539905 -43.344712)
			(xy 18.598446 -43.407523) (xy 18.650849 -43.47554) (xy 18.696652 -43.548165) (xy 18.735453 -43.62476)
			(xy 18.766912 -43.704652) (xy 18.790751 -43.787139) (xy 18.806761 -43.871496) (xy 18.814801 -43.956981)
			(xy 18.815304 -43.999912) (xy 18.814801 -44.042843) (xy 18.806761 -44.128328) (xy 18.790751 -44.212685)
			(xy 18.766912 -44.295172) (xy 18.735453 -44.375064) (xy 18.696652 -44.451659) (xy 18.650849 -44.524284)
			(xy 18.598446 -44.592301) (xy 18.539905 -44.655112) (xy 18.475738 -44.712165) (xy 18.406512 -44.762959)
			(xy 18.332833 -44.807047) (xy 18.255349 -44.844042) (xy 18.174741 -44.873619) (xy 18.091718 -44.895518)
			(xy 18.00701 -44.909546) (xy 17.92136 -44.91558) (xy 17.835521 -44.913567) (xy 17.750247 -44.903525)
			(xy 17.666289 -44.885542) (xy 17.584384 -44.859776) (xy 17.505251 -44.826453) (xy 17.429587 -44.785867)
			(xy 17.358055 -44.738374) (xy 17.291286 -44.684391) (xy 17.229864 -44.624393) (xy 17.174331 -44.558907)
			(xy 17.125174 -44.488509) (xy 17.082825 -44.413816) (xy 17.047657 -44.335487) (xy 17.019978 -44.254208)
			(xy 17.000031 -44.170694) (xy 16.987993 -44.08568) (xy 16.983969 -43.999912) (xy 0.509016 -43.999912)
			(xy 0.509016 -47.049813) (xy 59.781451 -47.049813) (xy 59.785436 -46.895317) (xy 59.79737 -46.74123)
			(xy 59.817219 -46.587962) (xy 59.844933 -46.43592) (xy 59.880436 -46.285505) (xy 59.923635 -46.137118)
			(xy 59.974415 -45.991151) (xy 60.032642 -45.847991) (xy 60.098162 -45.708019) (xy 60.1708 -45.571605)
			(xy 60.250363 -45.439111) (xy 60.336642 -45.310889) (xy 60.429407 -45.187278) (xy 60.528412 -45.068606)
			(xy 60.633395 -44.955188) (xy 60.744077 -44.847324) (xy 60.860165 -44.745302) (xy 60.981351 -44.64939)
			(xy 61.107313 -44.559844) (xy 61.237718 -44.476901) (xy 61.37222 -44.400781) (xy 61.510462 -44.331685)
			(xy 61.652077 -44.269798) (xy 61.796691 -44.215282) (xy 61.943919 -44.168283) (xy 62.093371 -44.128926)
			(xy 62.244652 -44.097314) (xy 62.397358 -44.073531) (xy 62.551087 -44.057641) (xy 62.70543 -44.049685)
			(xy 62.782704 -44.049188) (xy 64.383158 -44.049188) (xy 64.460432 -44.049684) (xy 64.614774 -44.057653)
			(xy 64.768502 -44.073557) (xy 64.921207 -44.097353) (xy 65.072484 -44.128978) (xy 65.221933 -44.168349)
			(xy 65.369158 -44.21536) (xy 65.513767 -44.269888) (xy 65.655377 -44.331788) (xy 65.793613 -44.400896)
			(xy 65.928108 -44.477028) (xy 66.058506 -44.559982) (xy 66.184461 -44.649539) (xy 66.305639 -44.745461)
			(xy 66.421718 -44.847494) (xy 66.532391 -44.955367) (xy 66.637364 -45.068794) (xy 66.736359 -45.187475)
			(xy 66.829113 -45.311094) (xy 66.915381 -45.439324) (xy 66.994934 -45.571824) (xy 67.06756 -45.708245)
			(xy 67.133068 -45.848223) (xy 67.191283 -45.991387) (xy 67.242051 -46.137359) (xy 67.285237 -46.28575)
			(xy 67.320727 -46.436168) (xy 67.348428 -46.588213) (xy 67.368264 -46.741483) (xy 67.380185 -46.89557)
			(xy 67.384154 -47.04994) (xy 89.78165 -47.04994) (xy 89.78563 -46.895439) (xy 89.797557 -46.741349)
			(xy 89.817402 -46.588076) (xy 89.84511 -46.436028) (xy 89.880608 -46.285609) (xy 89.923803 -46.137216)
			(xy 89.97458 -45.991243) (xy 90.032804 -45.848078) (xy 90.098321 -45.708101) (xy 90.170957 -45.571681)
			(xy 90.250519 -45.439181) (xy 90.336796 -45.310953) (xy 90.42956 -45.187337) (xy 90.528565 -45.068659)
			(xy 90.633548 -44.955236) (xy 90.74423 -44.847368) (xy 90.860319 -44.74534) (xy 90.981506 -44.649424)
			(xy 91.10747 -44.559873) (xy 91.237877 -44.476926) (xy 91.372381 -44.400801) (xy 91.510626 -44.331702)
			(xy 91.652244 -44.269811) (xy 91.796861 -44.215293) (xy 91.944092 -44.168291) (xy 92.093548 -44.128931)
			(xy 92.244832 -44.097317) (xy 92.397543 -44.073533) (xy 92.551275 -44.057642) (xy 92.705622 -44.049686)
			(xy 92.782898 -44.049188) (xy 94.383098 -44.049188) (xy 94.460374 -44.049669) (xy 94.614722 -44.057625)
			(xy 94.768456 -44.073516) (xy 94.921168 -44.0973) (xy 95.072452 -44.128914) (xy 95.221909 -44.168274)
			(xy 95.369142 -44.215276) (xy 95.513759 -44.269795) (xy 95.655379 -44.331686) (xy 95.793624 -44.400785)
			(xy 95.928129 -44.47691) (xy 96.058537 -44.559858) (xy 96.184502 -44.649409) (xy 96.30569 -44.745326)
			(xy 96.421779 -44.847354) (xy 96.532463 -44.955223) (xy 96.637446 -45.068647) (xy 96.736452 -45.187325)
			(xy 96.829216 -45.310943) (xy 96.915495 -45.439171) (xy 96.995057 -45.571672) (xy 97.038059 -45.652436)
			(xy 155.97378 -45.652436) (xy 155.97378 -44.788836) (xy 155.974266 -44.761567) (xy 155.982028 -44.707583)
			(xy 155.997393 -44.655253) (xy 156.02005 -44.605643) (xy 156.049536 -44.559762) (xy 156.085251 -44.518545)
			(xy 156.126468 -44.48283) (xy 156.172349 -44.453344) (xy 156.221959 -44.430687) (xy 156.274289 -44.415322)
			(xy 156.328273 -44.40756) (xy 156.382811 -44.40756) (xy 156.436795 -44.415322) (xy 156.489125 -44.430687)
			(xy 156.538735 -44.453344) (xy 156.584616 -44.48283) (xy 156.625833 -44.518545) (xy 156.661548 -44.559762)
			(xy 156.691034 -44.605643) (xy 156.713691 -44.655253) (xy 156.72159 -44.682156) (xy 159.179768 -44.682156)
			(xy 159.179768 -43.818556) (xy 159.180254 -43.791287) (xy 159.188016 -43.737303) (xy 159.203381 -43.684973)
			(xy 159.226038 -43.635363) (xy 159.255524 -43.589482) (xy 159.291239 -43.548265) (xy 159.332456 -43.51255)
			(xy 159.378337 -43.483064) (xy 159.427947 -43.460407) (xy 159.480277 -43.445042) (xy 159.534261 -43.43728)
			(xy 159.588799 -43.43728) (xy 159.642783 -43.445042) (xy 159.695113 -43.460407) (xy 159.74185 -43.481752)
			(xy 178.891692 -43.481752) (xy 178.891692 -42.618152) (xy 178.892178 -42.590901) (xy 178.899934 -42.536953)
			(xy 178.915289 -42.484658) (xy 178.937931 -42.435081) (xy 178.967397 -42.389231) (xy 179.003088 -42.34804)
			(xy 179.044279 -42.312349) (xy 179.090129 -42.282883) (xy 179.139706 -42.260241) (xy 179.192001 -42.244886)
			(xy 179.245949 -42.23713) (xy 179.300451 -42.23713) (xy 179.354399 -42.244886) (xy 179.406694 -42.260241)
			(xy 179.456271 -42.282883) (xy 179.502121 -42.312349) (xy 179.543312 -42.34804) (xy 179.579003 -42.389231)
			(xy 179.608469 -42.435081) (xy 179.631111 -42.484658) (xy 179.646466 -42.536953) (xy 179.654222 -42.590901)
			(xy 179.654708 -42.618152) (xy 179.654708 -43.481752) (xy 179.654222 -43.509003) (xy 179.647839 -43.5534)
			(xy 353.767583 -43.5534) (xy 353.771544 -43.500544) (xy 353.783339 -43.44887) (xy 353.802705 -43.39953)
			(xy 353.829208 -43.353628) (xy 353.862256 -43.312189) (xy 353.901112 -43.276139) (xy 353.944908 -43.246283)
			(xy 353.992664 -43.223289) (xy 354.043314 -43.207669) (xy 354.095726 -43.199773) (xy 354.122228 -43.199304)
			(xy 354.122736 -43.199304) (xy 354.153713 -43.199978) (xy 354.214715 -43.210807) (xy 354.272905 -43.232077)
			(xy 354.300028 -43.247056) (xy 354.328004 -43.238767) (xy 354.385663 -43.229845) (xy 354.414836 -43.229276)
			(xy 354.99548 -43.229276) (xy 355.004624 -43.225466) (xy 355.025917 -43.217194) (xy 355.070087 -43.205543)
			(xy 355.115388 -43.199665) (xy 355.138228 -43.199304) (xy 355.162681 -43.199729) (xy 355.211118 -43.206478)
			(xy 355.25817 -43.219815) (xy 355.280722 -43.229276) (xy 355.307866 -43.229907) (xy 355.361565 -43.237931)
			(xy 355.413585 -43.253486) (xy 355.462874 -43.276259) (xy 355.508436 -43.305789) (xy 355.549352 -43.341481)
			(xy 355.584795 -43.382612) (xy 355.61405 -43.428352) (xy 355.636524 -43.477777) (xy 355.651765 -43.52989)
			(xy 355.659465 -43.583636) (xy 355.659944 -43.610784) (xy 355.659468 -43.634951) (xy 356.178591 -43.634951)
			(xy 356.178591 -43.580449) (xy 356.186348 -43.526502) (xy 356.201703 -43.474208) (xy 356.224344 -43.424632)
			(xy 356.253811 -43.378783) (xy 356.289502 -43.337594) (xy 356.330692 -43.301903) (xy 356.376543 -43.272438)
			(xy 356.42612 -43.249799) (xy 356.478414 -43.234445) (xy 356.532361 -43.22669) (xy 356.559612 -43.226228)
			(xy 357.423212 -43.226228) (xy 357.450465 -43.226643) (xy 357.504417 -43.234401) (xy 357.556715 -43.249759)
			(xy 357.606295 -43.272403) (xy 357.652149 -43.301872) (xy 357.693341 -43.337567) (xy 357.729035 -43.378761)
			(xy 357.758503 -43.424615) (xy 357.781145 -43.474196) (xy 357.796501 -43.526495) (xy 357.804258 -43.580447)
			(xy 357.804258 -43.634953) (xy 357.803812 -43.638056) (xy 358.339039 -43.638056) (xy 358.339039 -43.583544)
			(xy 358.346797 -43.529588) (xy 358.362156 -43.477285) (xy 358.384802 -43.4277) (xy 358.414274 -43.381843)
			(xy 358.449974 -43.340648) (xy 358.491172 -43.304953) (xy 358.537032 -43.275485) (xy 358.586619 -43.252843)
			(xy 358.638923 -43.23749) (xy 358.69288 -43.229736) (xy 358.720136 -43.229276) (xy 359.583736 -43.229276)
			(xy 359.610984 -43.229797) (xy 359.664926 -43.237557) (xy 359.717214 -43.252915) (xy 359.766785 -43.275557)
			(xy 359.812629 -43.305023) (xy 359.853813 -43.340713) (xy 359.889499 -43.3819) (xy 359.91896 -43.427747)
			(xy 359.941598 -43.47732) (xy 359.956951 -43.529609) (xy 359.964706 -43.583552) (xy 359.964706 -43.638048)
			(xy 359.956951 -43.691991) (xy 359.941598 -43.74428) (xy 359.91896 -43.793853) (xy 359.889499 -43.8397)
			(xy 359.853813 -43.880887) (xy 359.812629 -43.916577) (xy 359.766785 -43.946043) (xy 359.717214 -43.968685)
			(xy 359.664926 -43.984043) (xy 359.610984 -43.991803) (xy 359.583736 -43.992292) (xy 358.720136 -43.992292)
			(xy 358.69288 -43.991864) (xy 358.638923 -43.98411) (xy 358.586619 -43.968757) (xy 358.537032 -43.946115)
			(xy 358.491172 -43.916647) (xy 358.449974 -43.880952) (xy 358.414274 -43.839757) (xy 358.384802 -43.7939)
			(xy 358.362156 -43.744315) (xy 358.346797 -43.692012) (xy 358.339039 -43.638056) (xy 357.803812 -43.638056)
			(xy 357.796501 -43.688905) (xy 357.781145 -43.741204) (xy 357.758503 -43.790785) (xy 357.729035 -43.836639)
			(xy 357.693341 -43.877833) (xy 357.652149 -43.913528) (xy 357.606295 -43.942997) (xy 357.556715 -43.965641)
			(xy 357.504417 -43.980999) (xy 357.450465 -43.988757) (xy 357.423212 -43.989244) (xy 356.559612 -43.989244)
			(xy 356.532361 -43.98871) (xy 356.478414 -43.980955) (xy 356.42612 -43.965601) (xy 356.376543 -43.942962)
			(xy 356.330692 -43.913497) (xy 356.289502 -43.877806) (xy 356.253811 -43.836617) (xy 356.224344 -43.790768)
			(xy 356.201703 -43.741192) (xy 356.186348 -43.688898) (xy 356.178591 -43.634951) (xy 355.659468 -43.634951)
			(xy 355.659407 -43.638033) (xy 355.651654 -43.691977) (xy 355.636302 -43.744269) (xy 355.613666 -43.793843)
			(xy 355.584204 -43.839692) (xy 355.548518 -43.880882) (xy 355.507334 -43.916573) (xy 355.461489 -43.946041)
			(xy 355.411917 -43.968684) (xy 355.359628 -43.984043) (xy 355.305685 -43.991803) (xy 355.278436 -43.992292)
			(xy 354.414836 -43.992292) (xy 354.388369 -43.991825) (xy 354.335944 -43.984518) (xy 354.285033 -43.970025)
			(xy 354.236619 -43.948625) (xy 354.191633 -43.920731) (xy 354.170996 -43.904154) (xy 354.158864 -43.905712)
			(xy 354.134459 -43.907367) (xy 354.122228 -43.907456) (xy 354.095726 -43.907027) (xy 354.043314 -43.899131)
			(xy 353.992664 -43.883511) (xy 353.944908 -43.860517) (xy 353.901112 -43.830661) (xy 353.862256 -43.794611)
			(xy 353.829208 -43.753172) (xy 353.802705 -43.70727) (xy 353.783339 -43.65793) (xy 353.771544 -43.606256)
			(xy 353.767583 -43.5534) (xy 179.647839 -43.5534) (xy 179.646466 -43.562951) (xy 179.631111 -43.615246)
			(xy 179.608469 -43.664823) (xy 179.579003 -43.710673) (xy 179.543312 -43.751864) (xy 179.502121 -43.787555)
			(xy 179.456271 -43.817021) (xy 179.406694 -43.839663) (xy 179.354399 -43.855018) (xy 179.300451 -43.862774)
			(xy 179.245949 -43.862774) (xy 179.192001 -43.855018) (xy 179.139706 -43.839663) (xy 179.090129 -43.817021)
			(xy 179.044279 -43.787555) (xy 179.003088 -43.751864) (xy 178.967397 -43.710673) (xy 178.937931 -43.664823)
			(xy 178.915289 -43.615246) (xy 178.899934 -43.562951) (xy 178.892178 -43.509003) (xy 178.891692 -43.481752)
			(xy 159.74185 -43.481752) (xy 159.744723 -43.483064) (xy 159.790604 -43.51255) (xy 159.831821 -43.548265)
			(xy 159.867536 -43.589482) (xy 159.897022 -43.635363) (xy 159.919679 -43.684973) (xy 159.935044 -43.737303)
			(xy 159.942806 -43.791287) (xy 159.943292 -43.818556) (xy 159.943292 -44.682156) (xy 159.942806 -44.709425)
			(xy 159.935044 -44.763409) (xy 159.919679 -44.815739) (xy 159.897022 -44.865349) (xy 159.867536 -44.91123)
			(xy 159.831821 -44.952447) (xy 159.79991 -44.980098) (xy 181.659784 -44.980098) (xy 181.659784 -44.116498)
			(xy 181.66027 -44.089247) (xy 181.668026 -44.035299) (xy 181.683381 -43.983004) (xy 181.706023 -43.933427)
			(xy 181.735489 -43.887577) (xy 181.77118 -43.846386) (xy 181.812371 -43.810695) (xy 181.858221 -43.781229)
			(xy 181.907798 -43.758587) (xy 181.960093 -43.743232) (xy 182.014041 -43.735476) (xy 182.068543 -43.735476)
			(xy 182.122491 -43.743232) (xy 182.174786 -43.758587) (xy 182.224363 -43.781229) (xy 182.270213 -43.810695)
			(xy 182.311404 -43.846386) (xy 182.347095 -43.887577) (xy 182.376561 -43.933427) (xy 182.399203 -43.983004)
			(xy 182.414558 -44.035299) (xy 182.422314 -44.089247) (xy 182.4228 -44.116498) (xy 182.4228 -44.840452)
			(xy 348.511075 -44.840452) (xy 348.511075 -44.785948) (xy 348.518832 -44.731999) (xy 348.534188 -44.679702)
			(xy 348.556831 -44.630124) (xy 348.586298 -44.584273) (xy 348.621992 -44.543082) (xy 348.663184 -44.50739)
			(xy 348.709036 -44.477924) (xy 348.758616 -44.455283) (xy 348.810912 -44.439929) (xy 348.864862 -44.432174)
			(xy 348.892114 -44.431712) (xy 349.755714 -44.431712) (xy 349.782966 -44.432159) (xy 349.836915 -44.439917)
			(xy 349.889211 -44.455274) (xy 349.938789 -44.477918) (xy 349.98464 -44.507386) (xy 350.025831 -44.543079)
			(xy 350.061523 -44.584271) (xy 350.090989 -44.630123) (xy 350.11363 -44.679702) (xy 350.128986 -44.731999)
			(xy 350.136742 -44.785948) (xy 350.136742 -44.840452) (xy 350.128986 -44.894401) (xy 350.11363 -44.946698)
			(xy 350.090989 -44.996277) (xy 350.072098 -45.025673) (xy 355.559288 -45.025673) (xy 355.559288 -44.971127)
			(xy 355.56705 -44.917137) (xy 355.582418 -44.864802) (xy 355.605077 -44.815186) (xy 355.634567 -44.7693)
			(xy 355.670288 -44.728078) (xy 355.711511 -44.692359) (xy 355.757398 -44.662871) (xy 355.807015 -44.640213)
			(xy 355.859351 -44.624847) (xy 355.913341 -44.617087) (xy 355.940614 -44.616624) (xy 356.804214 -44.616624)
			(xy 356.831482 -44.617139) (xy 356.885462 -44.624902) (xy 356.937788 -44.640268) (xy 356.987394 -44.662925)
			(xy 357.033272 -44.69241) (xy 357.074486 -44.728124) (xy 357.110199 -44.769339) (xy 357.139682 -44.815218)
			(xy 357.162337 -44.864825) (xy 357.177701 -44.917152) (xy 357.185462 -44.971132) (xy 357.185462 -45.025668)
			(xy 357.177701 -45.079648) (xy 357.162337 -45.131975) (xy 357.139682 -45.181582) (xy 357.110199 -45.227461)
			(xy 357.074486 -45.268676) (xy 357.033272 -45.30439) (xy 356.987394 -45.333875) (xy 356.937788 -45.356532)
			(xy 356.885462 -45.371898) (xy 356.831482 -45.379661) (xy 356.804214 -45.380148) (xy 355.940614 -45.380148)
			(xy 355.913341 -45.379713) (xy 355.859351 -45.371953) (xy 355.807015 -45.356587) (xy 355.757398 -45.333929)
			(xy 355.711511 -45.304441) (xy 355.670288 -45.268722) (xy 355.634567 -45.2275) (xy 355.605077 -45.181614)
			(xy 355.582418 -45.131998) (xy 355.56705 -45.079663) (xy 355.559288 -45.025673) (xy 350.072098 -45.025673)
			(xy 350.061523 -45.042129) (xy 350.025831 -45.083321) (xy 349.98464 -45.119014) (xy 349.938789 -45.148482)
			(xy 349.889211 -45.171126) (xy 349.836915 -45.186483) (xy 349.782966 -45.194241) (xy 349.755714 -45.194728)
			(xy 348.892114 -45.194728) (xy 348.864862 -45.194226) (xy 348.810912 -45.186471) (xy 348.758616 -45.171117)
			(xy 348.709036 -45.148476) (xy 348.663184 -45.11901) (xy 348.621992 -45.083318) (xy 348.586298 -45.042127)
			(xy 348.556831 -44.996276) (xy 348.534188 -44.946698) (xy 348.518832 -44.894401) (xy 348.511075 -44.840452)
			(xy 182.4228 -44.840452) (xy 182.4228 -44.980098) (xy 182.422314 -45.007349) (xy 182.414558 -45.061297)
			(xy 182.399203 -45.113592) (xy 182.376561 -45.163169) (xy 182.347095 -45.209019) (xy 182.311404 -45.25021)
			(xy 182.270213 -45.285901) (xy 182.224363 -45.315367) (xy 182.174786 -45.338009) (xy 182.122491 -45.353364)
			(xy 182.068543 -45.36112) (xy 182.014041 -45.36112) (xy 181.960093 -45.353364) (xy 181.907798 -45.338009)
			(xy 181.858221 -45.315367) (xy 181.812371 -45.285901) (xy 181.77118 -45.25021) (xy 181.735489 -45.209019)
			(xy 181.706023 -45.163169) (xy 181.683381 -45.113592) (xy 181.668026 -45.061297) (xy 181.66027 -45.007349)
			(xy 181.659784 -44.980098) (xy 159.79991 -44.980098) (xy 159.790604 -44.988162) (xy 159.744723 -45.017648)
			(xy 159.695113 -45.040305) (xy 159.642783 -45.05567) (xy 159.588799 -45.063432) (xy 159.534261 -45.063432)
			(xy 159.480277 -45.05567) (xy 159.427947 -45.040305) (xy 159.378337 -45.017648) (xy 159.332456 -44.988162)
			(xy 159.291239 -44.952447) (xy 159.255524 -44.91123) (xy 159.226038 -44.865349) (xy 159.203381 -44.815739)
			(xy 159.188016 -44.763409) (xy 159.180254 -44.709425) (xy 159.179768 -44.682156) (xy 156.72159 -44.682156)
			(xy 156.729056 -44.707583) (xy 156.736818 -44.761567) (xy 156.737304 -44.788836) (xy 156.737304 -45.652436)
			(xy 156.736818 -45.679705) (xy 156.729056 -45.733689) (xy 156.713691 -45.786019) (xy 156.691034 -45.835629)
			(xy 156.661548 -45.88151) (xy 156.625833 -45.922727) (xy 156.584616 -45.958442) (xy 156.538735 -45.987928)
			(xy 156.489125 -46.010585) (xy 156.436795 -46.02595) (xy 156.382811 -46.033712) (xy 156.328273 -46.033712)
			(xy 156.274289 -46.02595) (xy 156.221959 -46.010585) (xy 156.172349 -45.987928) (xy 156.126468 -45.958442)
			(xy 156.085251 -45.922727) (xy 156.049536 -45.88151) (xy 156.02005 -45.835629) (xy 155.997393 -45.786019)
			(xy 155.982028 -45.733689) (xy 155.974266 -45.679705) (xy 155.97378 -45.652436) (xy 97.038059 -45.652436)
			(xy 97.067693 -45.708092) (xy 97.133211 -45.848071) (xy 97.191435 -45.991237) (xy 97.242212 -46.13721)
			(xy 97.285407 -46.285604) (xy 97.320906 -46.436025) (xy 97.329238 -46.481746) (xy 178.630072 -46.481746)
			(xy 178.630072 -45.618146) (xy 178.630558 -45.590895) (xy 178.638314 -45.536947) (xy 178.653669 -45.484652)
			(xy 178.676311 -45.435075) (xy 178.705777 -45.389225) (xy 178.741468 -45.348034) (xy 178.782659 -45.312343)
			(xy 178.828509 -45.282877) (xy 178.878086 -45.260235) (xy 178.930381 -45.24488) (xy 178.984329 -45.237124)
			(xy 179.038831 -45.237124) (xy 179.092779 -45.24488) (xy 179.145074 -45.260235) (xy 179.194651 -45.282877)
			(xy 179.240501 -45.312343) (xy 179.281692 -45.348034) (xy 179.317383 -45.389225) (xy 179.346849 -45.435075)
			(xy 179.369491 -45.484652) (xy 179.384846 -45.536947) (xy 179.392602 -45.590895) (xy 179.393088 -45.618146)
			(xy 179.393088 -46.481746) (xy 179.392602 -46.508997) (xy 179.384846 -46.562945) (xy 179.369491 -46.61524)
			(xy 179.346849 -46.664817) (xy 179.317383 -46.710667) (xy 179.281692 -46.751858) (xy 179.240501 -46.787549)
			(xy 179.194651 -46.817015) (xy 179.145074 -46.839657) (xy 179.092779 -46.855012) (xy 179.038831 -46.862768)
			(xy 178.984329 -46.862768) (xy 178.930381 -46.855012) (xy 178.878086 -46.839657) (xy 178.828509 -46.817015)
			(xy 178.782659 -46.787549) (xy 178.741468 -46.751858) (xy 178.705777 -46.710667) (xy 178.676311 -46.664817)
			(xy 178.653669 -46.61524) (xy 178.638314 -46.562945) (xy 178.630558 -46.508997) (xy 178.630072 -46.481746)
			(xy 97.329238 -46.481746) (xy 97.348615 -46.588073) (xy 97.368459 -46.741347) (xy 97.380387 -46.895438)
			(xy 97.384366 -47.04994) (xy 97.380387 -47.204442) (xy 97.368459 -47.358533) (xy 97.348615 -47.511807)
			(xy 97.320906 -47.663855) (xy 97.285407 -47.814276) (xy 97.242212 -47.96267) (xy 97.239575 -47.97025)
			(xy 155.567386 -47.97025) (xy 155.567386 -47.91575) (xy 155.575142 -47.861805) (xy 155.590495 -47.809513)
			(xy 155.613135 -47.759938) (xy 155.642598 -47.71409) (xy 155.678287 -47.672901) (xy 155.719474 -47.63721)
			(xy 155.765321 -47.607744) (xy 155.814895 -47.585102) (xy 155.867186 -47.569746) (xy 155.92113 -47.561987)
			(xy 155.94838 -47.5615) (xy 156.81198 -47.5615) (xy 156.839234 -47.561946) (xy 156.893189 -47.569701)
			(xy 156.94549 -47.585055) (xy 156.995074 -47.607697) (xy 157.04093 -47.637165) (xy 157.082126 -47.67286)
			(xy 157.117823 -47.714054) (xy 157.147293 -47.759909) (xy 157.169938 -47.809491) (xy 157.185295 -47.861792)
			(xy 157.193053 -47.915746) (xy 157.193053 -47.970249) (xy 158.785586 -47.970249) (xy 158.785586 -47.915751)
			(xy 158.793341 -47.861808) (xy 158.808694 -47.809518) (xy 158.831331 -47.759944) (xy 158.860793 -47.714097)
			(xy 158.89648 -47.672908) (xy 158.937664 -47.637217) (xy 158.983509 -47.607751) (xy 159.03308 -47.585108)
			(xy 159.085369 -47.569749) (xy 159.139311 -47.561988) (xy 159.16656 -47.5615) (xy 160.03016 -47.5615)
			(xy 160.057415 -47.561945) (xy 160.111372 -47.569697) (xy 160.163675 -47.58505) (xy 160.213262 -47.607691)
			(xy 160.259121 -47.637158) (xy 160.300319 -47.672853) (xy 160.336018 -47.714047) (xy 160.36549 -47.759903)
			(xy 160.388136 -47.809487) (xy 160.403494 -47.861789) (xy 160.411253 -47.915745) (xy 160.411253 -47.970255)
			(xy 160.403494 -48.024211) (xy 160.402353 -48.028098) (xy 181.659784 -48.028098) (xy 181.659784 -47.164498)
			(xy 181.66027 -47.137247) (xy 181.668026 -47.083299) (xy 181.683381 -47.031004) (xy 181.706023 -46.981427)
			(xy 181.735489 -46.935577) (xy 181.77118 -46.894386) (xy 181.812371 -46.858695) (xy 181.858221 -46.829229)
			(xy 181.907798 -46.806587) (xy 181.960093 -46.791232) (xy 182.014041 -46.783476) (xy 182.068543 -46.783476)
			(xy 182.122491 -46.791232) (xy 182.174786 -46.806587) (xy 182.224363 -46.829229) (xy 182.225669 -46.830068)
			(xy 356.445326 -46.830068) (xy 356.445326 -46.775532) (xy 356.453087 -46.721552) (xy 356.468451 -46.669225)
			(xy 356.491104 -46.619618) (xy 356.520587 -46.573739) (xy 356.556298 -46.532522) (xy 356.597512 -46.496807)
			(xy 356.643388 -46.467321) (xy 356.692994 -46.444663) (xy 356.745319 -46.429294) (xy 356.799298 -46.421529)
			(xy 356.826566 -46.42104) (xy 357.690166 -46.42104) (xy 357.717439 -46.421497) (xy 357.77143 -46.429255)
			(xy 357.823767 -46.444619) (xy 357.873384 -46.467275) (xy 357.919272 -46.496761) (xy 357.960497 -46.532479)
			(xy 357.996218 -46.5737) (xy 358.025709 -46.619586) (xy 358.048369 -46.669202) (xy 358.063737 -46.721537)
			(xy 358.0715 -46.775527) (xy 358.0715 -46.830069) (xy 358.762026 -46.830069) (xy 358.762026 -46.775531)
			(xy 358.769788 -46.721547) (xy 358.785153 -46.669218) (xy 358.807809 -46.619608) (xy 358.837295 -46.573728)
			(xy 358.87301 -46.53251) (xy 358.914228 -46.496795) (xy 358.960108 -46.467309) (xy 359.009718 -46.444653)
			(xy 359.062047 -46.429288) (xy 359.116031 -46.421526) (xy 359.1433 -46.42104) (xy 360.0069 -46.42104)
			(xy 360.03417 -46.421522) (xy 360.088153 -46.429284) (xy 360.140483 -46.44465) (xy 360.190094 -46.467306)
			(xy 360.235975 -46.496792) (xy 360.277193 -46.532507) (xy 360.312908 -46.573725) (xy 360.342394 -46.619606)
			(xy 360.36505 -46.669217) (xy 360.380416 -46.721547) (xy 360.388178 -46.77553) (xy 360.388178 -46.83007)
			(xy 360.388178 -46.830073) (xy 361.088604 -46.830073) (xy 361.088604 -46.775527) (xy 361.096367 -46.721537)
			(xy 361.111735 -46.669202) (xy 361.134395 -46.619586) (xy 361.163887 -46.573701) (xy 361.199608 -46.53248)
			(xy 361.240833 -46.496763) (xy 361.286721 -46.467276) (xy 361.336339 -46.444621) (xy 361.388676 -46.429258)
			(xy 361.442667 -46.421501) (xy 361.46994 -46.42104) (xy 362.33354 -46.42104) (xy 362.360808 -46.421525)
			(xy 362.414787 -46.429291) (xy 362.467112 -46.44466) (xy 362.516718 -46.467319) (xy 362.562594 -46.496806)
			(xy 362.603807 -46.532522) (xy 362.639518 -46.573738) (xy 362.669 -46.619618) (xy 362.691654 -46.669225)
			(xy 362.707017 -46.721552) (xy 362.714778 -46.775532) (xy 362.714778 -46.830068) (xy 362.707017 -46.884048)
			(xy 362.691654 -46.936375) (xy 362.672751 -46.977768) (xy 396.642323 -46.977768) (xy 396.642323 -46.891996)
			(xy 396.650237 -46.806588) (xy 396.665998 -46.722276) (xy 396.689471 -46.639777) (xy 396.720456 -46.559796)
			(xy 396.758688 -46.483015) (xy 396.803842 -46.41009) (xy 396.855532 -46.341642) (xy 396.913317 -46.278255)
			(xy 396.976704 -46.22047) (xy 397.045152 -46.16878) (xy 397.118077 -46.123626) (xy 397.194858 -46.085394)
			(xy 397.274839 -46.054409) (xy 397.357338 -46.030936) (xy 397.44165 -46.015175) (xy 397.527058 -46.007261)
			(xy 397.61283 -46.007261) (xy 397.698238 -46.015175) (xy 397.78255 -46.030936) (xy 397.865049 -46.054409)
			(xy 397.94503 -46.085394) (xy 398.021811 -46.123626) (xy 398.094736 -46.16878) (xy 398.163184 -46.22047)
			(xy 398.226571 -46.278255) (xy 398.284356 -46.341642) (xy 398.336046 -46.41009) (xy 398.3812 -46.483015)
			(xy 398.419432 -46.559796) (xy 398.450417 -46.639777) (xy 398.47389 -46.722276) (xy 398.489651 -46.806588)
			(xy 398.497565 -46.891996) (xy 398.49806 -46.934882) (xy 398.497565 -46.977768) (xy 398.489651 -47.063176)
			(xy 398.47389 -47.147488) (xy 398.450417 -47.229987) (xy 398.419432 -47.309968) (xy 398.3812 -47.386749)
			(xy 398.336046 -47.459674) (xy 398.284356 -47.528122) (xy 398.226571 -47.591509) (xy 398.163184 -47.649294)
			(xy 398.094736 -47.700984) (xy 398.021811 -47.746138) (xy 397.94503 -47.78437) (xy 397.865049 -47.815355)
			(xy 397.78255 -47.838828) (xy 397.698238 -47.854589) (xy 397.61283 -47.862503) (xy 397.527058 -47.862503)
			(xy 397.44165 -47.854589) (xy 397.357338 -47.838828) (xy 397.274839 -47.815355) (xy 397.194858 -47.78437)
			(xy 397.118077 -47.746138) (xy 397.045152 -47.700984) (xy 396.976704 -47.649294) (xy 396.913317 -47.591509)
			(xy 396.855532 -47.528122) (xy 396.803842 -47.459674) (xy 396.758688 -47.386749) (xy 396.720456 -47.309968)
			(xy 396.689471 -47.229987) (xy 396.665998 -47.147488) (xy 396.650237 -47.063176) (xy 396.642323 -46.977768)
			(xy 362.672751 -46.977768) (xy 362.669 -46.985982) (xy 362.639518 -47.031862) (xy 362.603807 -47.073078)
			(xy 362.562594 -47.108794) (xy 362.516718 -47.138281) (xy 362.467112 -47.16094) (xy 362.414787 -47.176309)
			(xy 362.360808 -47.184075) (xy 362.33354 -47.184564) (xy 361.46994 -47.184564) (xy 361.442667 -47.184099)
			(xy 361.388676 -47.176342) (xy 361.336339 -47.160979) (xy 361.286721 -47.138324) (xy 361.240833 -47.108837)
			(xy 361.199608 -47.07312) (xy 361.163887 -47.031899) (xy 361.134395 -46.986014) (xy 361.111735 -46.936398)
			(xy 361.096367 -46.884063) (xy 361.088604 -46.830073) (xy 360.388178 -46.830073) (xy 360.380416 -46.884053)
			(xy 360.36505 -46.936383) (xy 360.342394 -46.985994) (xy 360.312908 -47.031875) (xy 360.277193 -47.073093)
			(xy 360.235975 -47.108808) (xy 360.190094 -47.138294) (xy 360.140483 -47.16095) (xy 360.088153 -47.176316)
			(xy 360.03417 -47.184078) (xy 360.0069 -47.184564) (xy 359.1433 -47.184564) (xy 359.116031 -47.184074)
			(xy 359.062047 -47.176312) (xy 359.009718 -47.160947) (xy 358.960108 -47.138291) (xy 358.914228 -47.108805)
			(xy 358.87301 -47.07309) (xy 358.837295 -47.031872) (xy 358.807809 -46.985992) (xy 358.785153 -46.936382)
			(xy 358.769788 -46.884053) (xy 358.762026 -46.830069) (xy 358.0715 -46.830069) (xy 358.0715 -46.830073)
			(xy 358.063737 -46.884063) (xy 358.048369 -46.936398) (xy 358.025709 -46.986014) (xy 357.996218 -47.0319)
			(xy 357.960497 -47.073121) (xy 357.919272 -47.108839) (xy 357.873384 -47.138325) (xy 357.823767 -47.160981)
			(xy 357.77143 -47.176345) (xy 357.717439 -47.184103) (xy 357.690166 -47.184564) (xy 356.826566 -47.184564)
			(xy 356.799298 -47.184071) (xy 356.745319 -47.176306) (xy 356.692994 -47.160937) (xy 356.643388 -47.138279)
			(xy 356.597512 -47.108793) (xy 356.556298 -47.073078) (xy 356.520587 -47.031861) (xy 356.491104 -46.985982)
			(xy 356.468451 -46.936375) (xy 356.453087 -46.884048) (xy 356.445326 -46.830068) (xy 182.225669 -46.830068)
			(xy 182.270213 -46.858695) (xy 182.311404 -46.894386) (xy 182.347095 -46.935577) (xy 182.376561 -46.981427)
			(xy 182.399203 -47.031004) (xy 182.414558 -47.083299) (xy 182.422314 -47.137247) (xy 182.4228 -47.164498)
			(xy 182.4228 -48.028098) (xy 182.422314 -48.055349) (xy 182.414558 -48.109297) (xy 182.399203 -48.161592)
			(xy 182.376561 -48.211169) (xy 182.347095 -48.257019) (xy 182.311404 -48.29821) (xy 182.270213 -48.333901)
			(xy 182.224363 -48.363367) (xy 182.174786 -48.386009) (xy 182.122491 -48.401364) (xy 182.068543 -48.40912)
			(xy 182.014041 -48.40912) (xy 181.960093 -48.401364) (xy 181.907798 -48.386009) (xy 181.858221 -48.363367)
			(xy 181.812371 -48.333901) (xy 181.77118 -48.29821) (xy 181.735489 -48.257019) (xy 181.706023 -48.211169)
			(xy 181.683381 -48.161592) (xy 181.668026 -48.109297) (xy 181.66027 -48.055349) (xy 181.659784 -48.028098)
			(xy 160.402353 -48.028098) (xy 160.388136 -48.076513) (xy 160.36549 -48.126097) (xy 160.336018 -48.171953)
			(xy 160.300319 -48.213147) (xy 160.259121 -48.248842) (xy 160.213262 -48.278309) (xy 160.163675 -48.30095)
			(xy 160.111372 -48.316303) (xy 160.057415 -48.324055) (xy 160.03016 -48.324516) (xy 159.16656 -48.324516)
			(xy 159.139311 -48.324012) (xy 159.085369 -48.316251) (xy 159.03308 -48.300892) (xy 158.983509 -48.278249)
			(xy 158.937664 -48.248783) (xy 158.89648 -48.213092) (xy 158.860793 -48.171903) (xy 158.831331 -48.126056)
			(xy 158.808694 -48.076482) (xy 158.793341 -48.024192) (xy 158.785586 -47.970249) (xy 157.193053 -47.970249)
			(xy 157.193053 -47.970254) (xy 157.185295 -48.024208) (xy 157.169938 -48.076509) (xy 157.147293 -48.126091)
			(xy 157.117823 -48.171946) (xy 157.082126 -48.21314) (xy 157.04093 -48.248835) (xy 156.995074 -48.278303)
			(xy 156.94549 -48.300945) (xy 156.893189 -48.316299) (xy 156.839234 -48.324054) (xy 156.81198 -48.324516)
			(xy 155.94838 -48.324516) (xy 155.92113 -48.324013) (xy 155.867186 -48.316254) (xy 155.814895 -48.300898)
			(xy 155.765321 -48.278256) (xy 155.719474 -48.24879) (xy 155.678287 -48.213099) (xy 155.642598 -48.17191)
			(xy 155.613135 -48.126062) (xy 155.590495 -48.076487) (xy 155.575142 -48.024195) (xy 155.567386 -47.97025)
			(xy 97.239575 -47.97025) (xy 97.191435 -48.108643) (xy 97.133211 -48.251809) (xy 97.067693 -48.391788)
			(xy 96.995057 -48.528208) (xy 96.915495 -48.660709) (xy 96.829216 -48.788937) (xy 96.736452 -48.912555)
			(xy 96.637446 -49.031233) (xy 96.532463 -49.144657) (xy 96.421779 -49.252526) (xy 96.30569 -49.354554)
			(xy 96.184502 -49.450471) (xy 96.140518 -49.48174) (xy 178.630072 -49.48174) (xy 178.630072 -48.61814)
			(xy 178.630558 -48.590889) (xy 178.638314 -48.536941) (xy 178.653669 -48.484646) (xy 178.676311 -48.435069)
			(xy 178.705777 -48.389219) (xy 178.741468 -48.348028) (xy 178.782659 -48.312337) (xy 178.828509 -48.282871)
			(xy 178.878086 -48.260229) (xy 178.930381 -48.244874) (xy 178.984329 -48.237118) (xy 179.038831 -48.237118)
			(xy 179.092779 -48.244874) (xy 179.145074 -48.260229) (xy 179.194651 -48.282871) (xy 179.240501 -48.312337)
			(xy 179.281692 -48.348028) (xy 179.317383 -48.389219) (xy 179.346849 -48.435069) (xy 179.369491 -48.484646)
			(xy 179.384846 -48.536941) (xy 179.392602 -48.590889) (xy 179.393088 -48.61814) (xy 179.393088 -49.48174)
			(xy 179.392602 -49.508991) (xy 179.384846 -49.562939) (xy 179.369491 -49.615234) (xy 179.346849 -49.664811)
			(xy 179.317383 -49.710661) (xy 179.281692 -49.751852) (xy 179.240501 -49.787543) (xy 179.194651 -49.817009)
			(xy 179.145074 -49.839651) (xy 179.092779 -49.855006) (xy 179.038831 -49.862762) (xy 178.984329 -49.862762)
			(xy 178.930381 -49.855006) (xy 178.878086 -49.839651) (xy 178.828509 -49.817009) (xy 178.782659 -49.787543)
			(xy 178.741468 -49.751852) (xy 178.705777 -49.710661) (xy 178.676311 -49.664811) (xy 178.653669 -49.615234)
			(xy 178.638314 -49.562939) (xy 178.630558 -49.508991) (xy 178.630072 -49.48174) (xy 96.140518 -49.48174)
			(xy 96.058537 -49.540022) (xy 95.928129 -49.62297) (xy 95.793624 -49.699095) (xy 95.655379 -49.768194)
			(xy 95.513759 -49.830085) (xy 95.369142 -49.884604) (xy 95.221909 -49.931606) (xy 95.072452 -49.970966)
			(xy 94.921168 -50.00258) (xy 94.768456 -50.026364) (xy 94.614722 -50.042255) (xy 94.460374 -50.050211)
			(xy 94.383098 -50.0507) (xy 92.782898 -50.0507) (xy 92.705622 -50.050194) (xy 92.551275 -50.042238)
			(xy 92.397543 -50.026347) (xy 92.244832 -50.002563) (xy 92.093548 -49.970949) (xy 91.944092 -49.931589)
			(xy 91.796861 -49.884587) (xy 91.652244 -49.830069) (xy 91.510626 -49.768178) (xy 91.372381 -49.699079)
			(xy 91.237877 -49.622954) (xy 91.10747 -49.540007) (xy 90.981506 -49.450456) (xy 90.860319 -49.35454)
			(xy 90.74423 -49.252512) (xy 90.633548 -49.144644) (xy 90.528565 -49.031221) (xy 90.42956 -48.912543)
			(xy 90.336796 -48.788927) (xy 90.250519 -48.660699) (xy 90.170957 -48.528199) (xy 90.098321 -48.391779)
			(xy 90.032804 -48.251802) (xy 89.97458 -48.108637) (xy 89.923803 -47.962664) (xy 89.880608 -47.814271)
			(xy 89.84511 -47.663852) (xy 89.817402 -47.511804) (xy 89.797557 -47.358531) (xy 89.78563 -47.204441)
			(xy 89.78165 -47.04994) (xy 67.384154 -47.04994) (xy 67.384157 -47.050067) (xy 67.380172 -47.204564)
			(xy 67.368238 -47.35865) (xy 67.348389 -47.511918) (xy 67.320675 -47.663961) (xy 67.285172 -47.814376)
			(xy 67.241973 -47.962763) (xy 67.191193 -48.108731) (xy 67.132966 -48.25189) (xy 67.067447 -48.391863)
			(xy 66.994809 -48.528277) (xy 66.915245 -48.660771) (xy 66.828966 -48.788993) (xy 66.736201 -48.912605)
			(xy 66.637196 -49.031277) (xy 66.532213 -49.144695) (xy 66.421531 -49.252559) (xy 66.305444 -49.354582)
			(xy 66.184258 -49.450493) (xy 66.058295 -49.54004) (xy 65.927891 -49.622983) (xy 65.793389 -49.699104)
			(xy 65.655147 -49.768199) (xy 65.513531 -49.830087) (xy 65.368918 -49.884603) (xy 65.22169 -49.931602)
			(xy 65.072237 -49.970961) (xy 64.920957 -50.002573) (xy 64.76825 -50.026356) (xy 64.614521 -50.042247)
			(xy 64.460178 -50.050202) (xy 64.382904 -50.0507) (xy 62.78245 -50.0507) (xy 62.705176 -50.050188)
			(xy 62.550834 -50.04222) (xy 62.397107 -50.026316) (xy 62.244402 -50.002521) (xy 62.093124 -49.970896)
			(xy 61.943675 -49.931526) (xy 61.796451 -49.884514) (xy 61.651842 -49.829987) (xy 61.510232 -49.768087)
			(xy 61.371996 -49.69898) (xy 61.2375 -49.622848) (xy 61.107102 -49.539894) (xy 60.981148 -49.450337)
			(xy 60.85997 -49.354416) (xy 60.743891 -49.252383) (xy 60.633218 -49.14451) (xy 60.528245 -49.031083)
			(xy 60.429249 -48.912403) (xy 60.336495 -48.788784) (xy 60.250227 -48.660555) (xy 60.170674 -48.528054)
			(xy 60.098048 -48.391634) (xy 60.032541 -48.251656) (xy 59.974326 -48.108492) (xy 59.923558 -47.96252)
			(xy 59.880371 -47.814129) (xy 59.844881 -47.663712) (xy 59.81718 -47.511667) (xy 59.797344 -47.358397)
			(xy 59.785423 -47.20431) (xy 59.781451 -47.049813) (xy 0.509016 -47.049813) (xy 0.509016 -50.949098)
			(xy 181.659784 -50.949098) (xy 181.659784 -50.085498) (xy 181.66027 -50.058247) (xy 181.668026 -50.004299)
			(xy 181.683381 -49.952004) (xy 181.706023 -49.902427) (xy 181.735489 -49.856577) (xy 181.77118 -49.815386)
			(xy 181.812371 -49.779695) (xy 181.858221 -49.750229) (xy 181.907798 -49.727587) (xy 181.960093 -49.712232)
			(xy 182.014041 -49.704476) (xy 182.068543 -49.704476) (xy 182.122491 -49.712232) (xy 182.174786 -49.727587)
			(xy 182.224363 -49.750229) (xy 182.270213 -49.779695) (xy 182.311404 -49.815386) (xy 182.347095 -49.856577)
			(xy 182.376561 -49.902427) (xy 182.399203 -49.952004) (xy 182.414558 -50.004299) (xy 182.422314 -50.058247)
			(xy 182.4228 -50.085498) (xy 182.4228 -50.949098) (xy 182.422314 -50.976349) (xy 182.414558 -51.030297)
			(xy 182.399203 -51.082592) (xy 182.376561 -51.132169) (xy 182.347095 -51.178019) (xy 182.311404 -51.21921)
			(xy 182.270213 -51.254901) (xy 182.224363 -51.284367) (xy 182.174786 -51.307009) (xy 182.122491 -51.322364)
			(xy 182.068543 -51.33012) (xy 182.014041 -51.33012) (xy 181.960093 -51.322364) (xy 181.907798 -51.307009)
			(xy 181.858221 -51.284367) (xy 181.812371 -51.254901) (xy 181.77118 -51.21921) (xy 181.735489 -51.178019)
			(xy 181.706023 -51.132169) (xy 181.683381 -51.082592) (xy 181.668026 -51.030297) (xy 181.66027 -50.976349)
			(xy 181.659784 -50.949098) (xy 0.509016 -50.949098) (xy 0.509016 -52.481734) (xy 178.630072 -52.481734)
			(xy 178.630072 -51.618134) (xy 178.630558 -51.590883) (xy 178.638314 -51.536935) (xy 178.653669 -51.48464)
			(xy 178.676311 -51.435063) (xy 178.705777 -51.389213) (xy 178.741468 -51.348022) (xy 178.782659 -51.312331)
			(xy 178.828509 -51.282865) (xy 178.878086 -51.260223) (xy 178.930381 -51.244868) (xy 178.984329 -51.237112)
			(xy 179.038831 -51.237112) (xy 179.092779 -51.244868) (xy 179.145074 -51.260223) (xy 179.194651 -51.282865)
			(xy 179.240501 -51.312331) (xy 179.281692 -51.348022) (xy 179.317383 -51.389213) (xy 179.346849 -51.435063)
			(xy 179.369491 -51.48464) (xy 179.384846 -51.536935) (xy 179.392602 -51.590883) (xy 179.393088 -51.618134)
			(xy 179.393088 -51.999896) (xy 201.367397 -51.999896) (xy 201.371407 -51.837793) (xy 201.38343 -51.676088)
			(xy 201.403434 -51.515174) (xy 201.431372 -51.355447) (xy 201.467175 -51.197297) (xy 201.510755 -51.041111)
			(xy 201.562006 -50.887271) (xy 201.620802 -50.736154) (xy 201.687 -50.58813) (xy 201.760436 -50.44356)
			(xy 201.840933 -50.302799) (xy 201.928292 -50.166191) (xy 202.0223 -50.034071) (xy 202.122727 -49.906761)
			(xy 202.229327 -49.784573) (xy 202.341839 -49.667807) (xy 202.459987 -49.556748) (xy 202.583484 -49.451667)
			(xy 202.712026 -49.352823) (xy 202.845299 -49.260456) (xy 202.982977 -49.174793) (xy 203.124723 -49.096044)
			(xy 203.27019 -49.024401) (xy 203.419022 -48.960039) (xy 203.570854 -48.903117) (xy 203.725316 -48.853773)
			(xy 203.882029 -48.812128) (xy 204.04061 -48.778283) (xy 204.200671 -48.752323) (xy 204.361819 -48.73431)
			(xy 204.523661 -48.724289) (xy 204.685801 -48.722283) (xy 204.847842 -48.728299) (xy 205.009386 -48.74232)
			(xy 205.17004 -48.764313) (xy 205.32941 -48.794225) (xy 205.487105 -48.831981) (xy 205.64274 -48.877489)
			(xy 205.795934 -48.930639) (xy 205.946312 -48.9913) (xy 206.093507 -49.059323) (xy 206.237157 -49.134542)
			(xy 206.376912 -49.216773) (xy 206.512428 -49.305815) (xy 206.643376 -49.40145) (xy 206.769434 -49.503444)
			(xy 206.890294 -49.611547) (xy 207.00566 -49.725494) (xy 207.115249 -49.845008) (xy 207.218794 -49.969795)
			(xy 207.316041 -50.09955) (xy 207.406753 -50.233955) (xy 207.424818 -50.263806) (xy 239.457992 -50.263806)
			(xy 239.457992 -49.400206) (xy 239.458478 -49.372955) (xy 239.466234 -49.319007) (xy 239.481589 -49.266712)
			(xy 239.504231 -49.217135) (xy 239.533697 -49.171285) (xy 239.569388 -49.130094) (xy 239.610579 -49.094403)
			(xy 239.656429 -49.064937) (xy 239.706006 -49.042295) (xy 239.758301 -49.02694) (xy 239.812249 -49.019184)
			(xy 239.866751 -49.019184) (xy 239.920699 -49.02694) (xy 239.972994 -49.042295) (xy 240.022571 -49.064937)
			(xy 240.068421 -49.094403) (xy 240.109612 -49.130094) (xy 240.145303 -49.171285) (xy 240.174769 -49.217135)
			(xy 240.197411 -49.266712) (xy 240.212766 -49.319007) (xy 240.220522 -49.372955) (xy 240.221008 -49.400206)
			(xy 240.221008 -50.263806) (xy 240.220522 -50.291057) (xy 240.212766 -50.345005) (xy 240.197411 -50.3973)
			(xy 240.174769 -50.446877) (xy 240.145303 -50.492727) (xy 240.109612 -50.533918) (xy 240.068421 -50.569609)
			(xy 240.022571 -50.599075) (xy 239.972994 -50.621717) (xy 239.920699 -50.637072) (xy 239.866751 -50.644828)
			(xy 239.812249 -50.644828) (xy 239.758301 -50.637072) (xy 239.706006 -50.621717) (xy 239.656429 -50.599075)
			(xy 239.610579 -50.569609) (xy 239.569388 -50.533918) (xy 239.533697 -50.492727) (xy 239.504231 -50.446877)
			(xy 239.481589 -50.3973) (xy 239.466234 -50.345005) (xy 239.458478 -50.291057) (xy 239.457992 -50.263806)
			(xy 207.424818 -50.263806) (xy 207.490706 -50.372682) (xy 207.567696 -50.515391) (xy 207.637535 -50.661732)
			(xy 207.70005 -50.811349) (xy 207.755091 -50.963874) (xy 207.802521 -51.118934) (xy 207.842224 -51.27615)
			(xy 207.874105 -51.435138) (xy 207.898083 -51.595507) (xy 207.914102 -51.756866) (xy 207.922121 -51.91882)
			(xy 207.922622 -51.999896) (xy 207.922121 -52.080972) (xy 207.914102 -52.242926) (xy 207.898083 -52.404285)
			(xy 207.874105 -52.564654) (xy 207.842224 -52.723642) (xy 207.802521 -52.880858) (xy 207.794624 -52.906676)
			(xy 228.815392 -52.906676) (xy 228.815392 -52.043076) (xy 228.815878 -52.015825) (xy 228.823634 -51.961877)
			(xy 228.838989 -51.909582) (xy 228.861631 -51.860005) (xy 228.891097 -51.814155) (xy 228.926788 -51.772964)
			(xy 228.967979 -51.737273) (xy 229.013829 -51.707807) (xy 229.063406 -51.685165) (xy 229.115701 -51.66981)
			(xy 229.169649 -51.662054) (xy 229.224151 -51.662054) (xy 229.278099 -51.66981) (xy 229.330394 -51.685165)
			(xy 229.379971 -51.707807) (xy 229.425821 -51.737273) (xy 229.467012 -51.772964) (xy 229.502703 -51.814155)
			(xy 229.532169 -51.860005) (xy 229.554811 -51.909582) (xy 229.570166 -51.961877) (xy 229.577922 -52.015825)
			(xy 229.578408 -52.043076) (xy 229.578408 -52.90185) (xy 241.926872 -52.90185) (xy 241.926872 -52.03825)
			(xy 241.927358 -52.010999) (xy 241.935114 -51.957051) (xy 241.950469 -51.904756) (xy 241.973111 -51.855179)
			(xy 242.002577 -51.809329) (xy 242.038268 -51.768138) (xy 242.079459 -51.732447) (xy 242.125309 -51.702981)
			(xy 242.174886 -51.680339) (xy 242.227181 -51.664984) (xy 242.281129 -51.657228) (xy 242.335631 -51.657228)
			(xy 242.389579 -51.664984) (xy 242.441874 -51.680339) (xy 242.491451 -51.702981) (xy 242.537301 -51.732447)
			(xy 242.578492 -51.768138) (xy 242.614183 -51.809329) (xy 242.643649 -51.855179) (xy 242.666291 -51.904756)
			(xy 242.681646 -51.957051) (xy 242.687806 -51.999896) (xy 265.367269 -51.999896) (xy 265.371279 -51.837793)
			(xy 265.383302 -51.676088) (xy 265.403306 -51.515174) (xy 265.431244 -51.355447) (xy 265.467047 -51.197297)
			(xy 265.510627 -51.041111) (xy 265.561878 -50.887271) (xy 265.620674 -50.736154) (xy 265.686872 -50.58813)
			(xy 265.760308 -50.44356) (xy 265.840805 -50.302799) (xy 265.928164 -50.166191) (xy 266.022172 -50.034071)
			(xy 266.122599 -49.906761) (xy 266.229199 -49.784573) (xy 266.341711 -49.667807) (xy 266.459859 -49.556748)
			(xy 266.583356 -49.451667) (xy 266.711898 -49.352823) (xy 266.845171 -49.260456) (xy 266.982849 -49.174793)
			(xy 267.124595 -49.096044) (xy 267.270062 -49.024401) (xy 267.418894 -48.960039) (xy 267.570726 -48.903117)
			(xy 267.725188 -48.853773) (xy 267.881901 -48.812128) (xy 268.040482 -48.778283) (xy 268.200543 -48.752323)
			(xy 268.361691 -48.73431) (xy 268.523533 -48.724289) (xy 268.685673 -48.722283) (xy 268.847714 -48.728299)
			(xy 269.009258 -48.74232) (xy 269.169912 -48.764313) (xy 269.329282 -48.794225) (xy 269.486977 -48.831981)
			(xy 269.642612 -48.877489) (xy 269.795806 -48.930639) (xy 269.946184 -48.9913) (xy 270.093379 -49.059323)
			(xy 270.237029 -49.134542) (xy 270.376784 -49.216773) (xy 270.5123 -49.305815) (xy 270.643248 -49.40145)
			(xy 270.769306 -49.503444) (xy 270.890166 -49.611547) (xy 271.005532 -49.725494) (xy 271.115121 -49.845008)
			(xy 271.218666 -49.969795) (xy 271.315913 -50.09955) (xy 271.406625 -50.233955) (xy 271.40723 -50.234955)
			(xy 350.291827 -50.234955) (xy 350.291827 -50.180445) (xy 350.299585 -50.126489) (xy 350.314942 -50.074187)
			(xy 350.337587 -50.024602) (xy 350.367058 -49.978745) (xy 350.402755 -49.937549) (xy 350.443952 -49.901853)
			(xy 350.489809 -49.872383) (xy 350.539394 -49.849739) (xy 350.591697 -49.834383) (xy 350.645653 -49.826626)
			(xy 350.672908 -49.826164) (xy 351.536508 -49.826164) (xy 351.563757 -49.826707) (xy 351.6177 -49.834464)
			(xy 351.66999 -49.849818) (xy 351.719562 -49.872458) (xy 351.765408 -49.901922) (xy 351.806594 -49.937611)
			(xy 351.842282 -49.978798) (xy 351.871746 -50.024645) (xy 351.894385 -50.074218) (xy 351.909738 -50.126508)
			(xy 351.917494 -50.180451) (xy 351.917494 -50.234949) (xy 351.917493 -50.234956) (xy 352.489927 -50.234956)
			(xy 352.489927 -50.180444) (xy 352.497685 -50.126487) (xy 352.513044 -50.074183) (xy 352.535689 -50.024598)
			(xy 352.565162 -49.97874) (xy 352.600861 -49.937544) (xy 352.642059 -49.901848) (xy 352.687919 -49.872378)
			(xy 352.737506 -49.849735) (xy 352.78981 -49.83438) (xy 352.843768 -49.826625) (xy 352.871024 -49.826164)
			(xy 353.734624 -49.826164) (xy 353.761872 -49.826708) (xy 353.815813 -49.834467) (xy 353.868101 -49.849823)
			(xy 353.917672 -49.872463) (xy 353.963516 -49.901928) (xy 354.0047 -49.937617) (xy 354.040386 -49.978804)
			(xy 354.069848 -50.024649) (xy 354.092486 -50.074221) (xy 354.107839 -50.12651) (xy 354.115594 -50.180452)
			(xy 354.115594 -50.234948) (xy 354.115593 -50.234956) (xy 354.712427 -50.234956) (xy 354.712427 -50.180444)
			(xy 354.720185 -50.126487) (xy 354.735544 -50.074183) (xy 354.758189 -50.024598) (xy 354.787662 -49.97874)
			(xy 354.823361 -49.937544) (xy 354.864559 -49.901848) (xy 354.910419 -49.872378) (xy 354.960006 -49.849735)
			(xy 355.01231 -49.83438) (xy 355.066268 -49.826625) (xy 355.093524 -49.826164) (xy 355.957124 -49.826164)
			(xy 355.984372 -49.826708) (xy 356.038313 -49.834467) (xy 356.090601 -49.849823) (xy 356.140172 -49.872463)
			(xy 356.186016 -49.901928) (xy 356.2272 -49.937617) (xy 356.262886 -49.978804) (xy 356.292348 -50.024649)
			(xy 356.314986 -50.074221) (xy 356.330339 -50.12651) (xy 356.338094 -50.180452) (xy 356.338094 -50.234948)
			(xy 356.338093 -50.234957) (xy 356.942527 -50.234957) (xy 356.942527 -50.180443) (xy 356.950286 -50.126484)
			(xy 356.965645 -50.074179) (xy 356.988293 -50.024592) (xy 357.017767 -49.978734) (xy 357.053468 -49.937537)
			(xy 357.094669 -49.90184) (xy 357.140531 -49.872371) (xy 357.19012 -49.84973) (xy 357.242427 -49.834376)
			(xy 357.296387 -49.826624) (xy 357.323644 -49.826164) (xy 358.187244 -49.826164) (xy 358.214491 -49.826709)
			(xy 358.26843 -49.83447) (xy 358.320716 -49.849828) (xy 358.370284 -49.87247) (xy 358.416125 -49.901935)
			(xy 358.457307 -49.937624) (xy 358.492991 -49.97881) (xy 358.522451 -50.024655) (xy 358.545087 -50.074226)
			(xy 358.560439 -50.126513) (xy 358.568194 -50.180453) (xy 358.568194 -50.234947) (xy 358.560439 -50.288887)
			(xy 358.545087 -50.341174) (xy 358.522451 -50.390745) (xy 358.492991 -50.43659) (xy 358.457307 -50.477776)
			(xy 358.416125 -50.513465) (xy 358.370284 -50.54293) (xy 358.320716 -50.565572) (xy 358.26843 -50.58093)
			(xy 358.214491 -50.588691) (xy 358.187244 -50.58918) (xy 357.323644 -50.58918) (xy 357.296387 -50.588776)
			(xy 357.242427 -50.581024) (xy 357.19012 -50.56567) (xy 357.140531 -50.543029) (xy 357.094669 -50.51356)
			(xy 357.053468 -50.477863) (xy 357.017767 -50.436666) (xy 356.988293 -50.390808) (xy 356.965645 -50.341221)
			(xy 356.950286 -50.288916) (xy 356.942527 -50.234957) (xy 356.338093 -50.234957) (xy 356.330339 -50.28889)
			(xy 356.314986 -50.341179) (xy 356.292348 -50.390751) (xy 356.262886 -50.436596) (xy 356.2272 -50.477783)
			(xy 356.186016 -50.513472) (xy 356.140172 -50.542937) (xy 356.090601 -50.565577) (xy 356.038313 -50.580933)
			(xy 355.984372 -50.588692) (xy 355.957124 -50.58918) (xy 355.093524 -50.58918) (xy 355.066268 -50.588775)
			(xy 355.01231 -50.58102) (xy 354.960006 -50.565665) (xy 354.910419 -50.543022) (xy 354.864559 -50.513552)
			(xy 354.823361 -50.477856) (xy 354.787662 -50.43666) (xy 354.758189 -50.390802) (xy 354.735544 -50.341217)
			(xy 354.720185 -50.288913) (xy 354.712427 -50.234956) (xy 354.115593 -50.234956) (xy 354.107839 -50.28889)
			(xy 354.092486 -50.341179) (xy 354.069848 -50.390751) (xy 354.040386 -50.436596) (xy 354.0047 -50.477783)
			(xy 353.963516 -50.513472) (xy 353.917672 -50.542937) (xy 353.868101 -50.565577) (xy 353.815813 -50.580933)
			(xy 353.761872 -50.588692) (xy 353.734624 -50.58918) (xy 352.871024 -50.58918) (xy 352.843768 -50.588775)
			(xy 352.78981 -50.58102) (xy 352.737506 -50.565665) (xy 352.687919 -50.543022) (xy 352.642059 -50.513552)
			(xy 352.600861 -50.477856) (xy 352.565162 -50.43666) (xy 352.535689 -50.390802) (xy 352.513044 -50.341217)
			(xy 352.497685 -50.288913) (xy 352.489927 -50.234956) (xy 351.917493 -50.234956) (xy 351.909738 -50.288892)
			(xy 351.894385 -50.341182) (xy 351.871746 -50.390755) (xy 351.842282 -50.436602) (xy 351.806594 -50.477789)
			(xy 351.765408 -50.513477) (xy 351.719562 -50.542942) (xy 351.66999 -50.565582) (xy 351.6177 -50.580936)
			(xy 351.563757 -50.588693) (xy 351.536508 -50.58918) (xy 350.672908 -50.58918) (xy 350.645653 -50.588774)
			(xy 350.591697 -50.581017) (xy 350.539394 -50.565661) (xy 350.489809 -50.543017) (xy 350.443952 -50.513547)
			(xy 350.402755 -50.477851) (xy 350.367058 -50.436655) (xy 350.337587 -50.390798) (xy 350.314942 -50.341213)
			(xy 350.299585 -50.288911) (xy 350.291827 -50.234955) (xy 271.40723 -50.234955) (xy 271.490578 -50.372682)
			(xy 271.567568 -50.515391) (xy 271.637407 -50.661732) (xy 271.699922 -50.811349) (xy 271.754963 -50.963874)
			(xy 271.802393 -51.118934) (xy 271.842096 -51.27615) (xy 271.873977 -51.435138) (xy 271.897955 -51.595507)
			(xy 271.913974 -51.756866) (xy 271.921993 -51.91882) (xy 271.922494 -51.999896) (xy 271.921993 -52.080972)
			(xy 271.913974 -52.242926) (xy 271.897955 -52.404285) (xy 271.873977 -52.564654) (xy 271.842096 -52.723642)
			(xy 271.802393 -52.880858) (xy 271.754963 -53.035918) (xy 271.699922 -53.188443) (xy 271.637407 -53.33806)
			(xy 271.567568 -53.484401) (xy 271.490578 -53.62711) (xy 271.406625 -53.765837) (xy 271.315913 -53.900242)
			(xy 271.218666 -54.029997) (xy 271.115121 -54.154784) (xy 271.005532 -54.274298) (xy 270.890166 -54.388245)
			(xy 270.769306 -54.496348) (xy 270.643248 -54.598342) (xy 270.5123 -54.693977) (xy 270.376784 -54.783019)
			(xy 270.237029 -54.86525) (xy 270.093379 -54.940469) (xy 269.946184 -55.008492) (xy 269.795806 -55.069153)
			(xy 269.642612 -55.122303) (xy 269.486977 -55.167811) (xy 269.329282 -55.205567) (xy 269.169912 -55.235479)
			(xy 269.009258 -55.257472) (xy 268.847714 -55.271493) (xy 268.685673 -55.277509) (xy 268.523533 -55.275503)
			(xy 268.361691 -55.265482) (xy 268.200543 -55.247469) (xy 268.040482 -55.221509) (xy 267.881901 -55.187664)
			(xy 267.725188 -55.146019) (xy 267.570726 -55.096675) (xy 267.418894 -55.039753) (xy 267.270062 -54.975391)
			(xy 267.124595 -54.903748) (xy 266.982849 -54.824999) (xy 266.845171 -54.739336) (xy 266.711898 -54.646969)
			(xy 266.583356 -54.548125) (xy 266.459859 -54.443044) (xy 266.341711 -54.331985) (xy 266.229199 -54.215219)
			(xy 266.122599 -54.093031) (xy 266.022172 -53.965721) (xy 265.928164 -53.833601) (xy 265.840805 -53.696993)
			(xy 265.760308 -53.556232) (xy 265.686872 -53.411662) (xy 265.620674 -53.263638) (xy 265.561878 -53.112521)
			(xy 265.510627 -52.958681) (xy 265.467047 -52.802495) (xy 265.431244 -52.644345) (xy 265.403306 -52.484618)
			(xy 265.383302 -52.323704) (xy 265.371279 -52.161999) (xy 265.367269 -51.999896) (xy 242.687806 -51.999896)
			(xy 242.689402 -52.010999) (xy 242.689888 -52.03825) (xy 242.689888 -52.90185) (xy 242.689402 -52.929101)
			(xy 242.681646 -52.983049) (xy 242.666291 -53.035344) (xy 242.643649 -53.084921) (xy 242.614183 -53.130771)
			(xy 242.578492 -53.171962) (xy 242.537301 -53.207653) (xy 242.491451 -53.237119) (xy 242.441874 -53.259761)
			(xy 242.389579 -53.275116) (xy 242.335631 -53.282872) (xy 242.281129 -53.282872) (xy 242.227181 -53.275116)
			(xy 242.174886 -53.259761) (xy 242.125309 -53.237119) (xy 242.079459 -53.207653) (xy 242.038268 -53.171962)
			(xy 242.002577 -53.130771) (xy 241.973111 -53.084921) (xy 241.950469 -53.035344) (xy 241.935114 -52.983049)
			(xy 241.927358 -52.929101) (xy 241.926872 -52.90185) (xy 229.578408 -52.90185) (xy 229.578408 -52.906676)
			(xy 229.577922 -52.933927) (xy 229.570166 -52.987875) (xy 229.554811 -53.04017) (xy 229.532169 -53.089747)
			(xy 229.502703 -53.135597) (xy 229.467012 -53.176788) (xy 229.425821 -53.212479) (xy 229.379971 -53.241945)
			(xy 229.330394 -53.264587) (xy 229.278099 -53.279942) (xy 229.224151 -53.287698) (xy 229.169649 -53.287698)
			(xy 229.115701 -53.279942) (xy 229.063406 -53.264587) (xy 229.013829 -53.241945) (xy 228.967979 -53.212479)
			(xy 228.926788 -53.176788) (xy 228.891097 -53.135597) (xy 228.861631 -53.089747) (xy 228.838989 -53.04017)
			(xy 228.823634 -52.987875) (xy 228.815878 -52.933927) (xy 228.815392 -52.906676) (xy 207.794624 -52.906676)
			(xy 207.755091 -53.035918) (xy 207.70005 -53.188443) (xy 207.637535 -53.33806) (xy 207.567696 -53.484401)
			(xy 207.490706 -53.62711) (xy 207.406753 -53.765837) (xy 207.316041 -53.900242) (xy 207.218794 -54.029997)
			(xy 207.115249 -54.154784) (xy 207.00566 -54.274298) (xy 206.890294 -54.388245) (xy 206.769434 -54.496348)
			(xy 206.643376 -54.598342) (xy 206.512428 -54.693977) (xy 206.493338 -54.70652) (xy 230.115872 -54.70652)
			(xy 230.115872 -53.84292) (xy 230.116358 -53.815669) (xy 230.124114 -53.761721) (xy 230.139469 -53.709426)
			(xy 230.162111 -53.659849) (xy 230.191577 -53.613999) (xy 230.227268 -53.572808) (xy 230.268459 -53.537117)
			(xy 230.314309 -53.507651) (xy 230.363886 -53.485009) (xy 230.416181 -53.469654) (xy 230.470129 -53.461898)
			(xy 230.524631 -53.461898) (xy 230.578579 -53.469654) (xy 230.630874 -53.485009) (xy 230.680451 -53.507651)
			(xy 230.726301 -53.537117) (xy 230.767492 -53.572808) (xy 230.803183 -53.613999) (xy 230.832649 -53.659849)
			(xy 230.855291 -53.709426) (xy 230.870646 -53.761721) (xy 230.878402 -53.815669) (xy 230.878888 -53.84292)
			(xy 230.878888 -54.70652) (xy 230.878811 -54.710838) (xy 240.282476 -54.710838) (xy 240.282476 -53.847238)
			(xy 240.282962 -53.819987) (xy 240.290718 -53.766039) (xy 240.306073 -53.713744) (xy 240.328715 -53.664167)
			(xy 240.358181 -53.618317) (xy 240.393872 -53.577126) (xy 240.435063 -53.541435) (xy 240.480913 -53.511969)
			(xy 240.53049 -53.489327) (xy 240.582785 -53.473972) (xy 240.636733 -53.466216) (xy 240.691235 -53.466216)
			(xy 240.745183 -53.473972) (xy 240.797478 -53.489327) (xy 240.847055 -53.511969) (xy 240.892905 -53.541435)
			(xy 240.934096 -53.577126) (xy 240.969787 -53.618317) (xy 240.999253 -53.664167) (xy 241.021895 -53.713744)
			(xy 241.03725 -53.766039) (xy 241.045006 -53.819987) (xy 241.045492 -53.847238) (xy 241.045492 -54.710838)
			(xy 241.045006 -54.738089) (xy 241.03725 -54.792037) (xy 241.021895 -54.844332) (xy 240.999253 -54.893909)
			(xy 240.969787 -54.939759) (xy 240.934096 -54.98095) (xy 240.892905 -55.016641) (xy 240.847055 -55.046107)
			(xy 240.797478 -55.068749) (xy 240.745183 -55.084104) (xy 240.691235 -55.09186) (xy 240.636733 -55.09186)
			(xy 240.582785 -55.084104) (xy 240.53049 -55.068749) (xy 240.480913 -55.046107) (xy 240.435063 -55.016641)
			(xy 240.393872 -54.98095) (xy 240.358181 -54.939759) (xy 240.328715 -54.893909) (xy 240.306073 -54.844332)
			(xy 240.290718 -54.792037) (xy 240.282962 -54.738089) (xy 240.282476 -54.710838) (xy 230.878811 -54.710838)
			(xy 230.878402 -54.733771) (xy 230.870646 -54.787719) (xy 230.855291 -54.840014) (xy 230.832649 -54.889591)
			(xy 230.803183 -54.935441) (xy 230.767492 -54.976632) (xy 230.726301 -55.012323) (xy 230.680451 -55.041789)
			(xy 230.630874 -55.064431) (xy 230.578579 -55.079786) (xy 230.524631 -55.087542) (xy 230.470129 -55.087542)
			(xy 230.416181 -55.079786) (xy 230.363886 -55.064431) (xy 230.314309 -55.041789) (xy 230.268459 -55.012323)
			(xy 230.227268 -54.976632) (xy 230.191577 -54.935441) (xy 230.162111 -54.889591) (xy 230.139469 -54.840014)
			(xy 230.124114 -54.787719) (xy 230.116358 -54.733771) (xy 230.115872 -54.70652) (xy 206.493338 -54.70652)
			(xy 206.376912 -54.783019) (xy 206.237157 -54.86525) (xy 206.093507 -54.940469) (xy 205.946312 -55.008492)
			(xy 205.795934 -55.069153) (xy 205.64274 -55.122303) (xy 205.487105 -55.167811) (xy 205.32941 -55.205567)
			(xy 205.17004 -55.235479) (xy 205.009386 -55.257472) (xy 204.847842 -55.271493) (xy 204.685801 -55.277509)
			(xy 204.523661 -55.275503) (xy 204.361819 -55.265482) (xy 204.200671 -55.247469) (xy 204.04061 -55.221509)
			(xy 203.882029 -55.187664) (xy 203.725316 -55.146019) (xy 203.570854 -55.096675) (xy 203.419022 -55.039753)
			(xy 203.27019 -54.975391) (xy 203.124723 -54.903748) (xy 202.982977 -54.824999) (xy 202.845299 -54.739336)
			(xy 202.712026 -54.646969) (xy 202.583484 -54.548125) (xy 202.459987 -54.443044) (xy 202.341839 -54.331985)
			(xy 202.229327 -54.215219) (xy 202.122727 -54.093031) (xy 202.0223 -53.965721) (xy 201.928292 -53.833601)
			(xy 201.840933 -53.696993) (xy 201.760436 -53.556232) (xy 201.687 -53.411662) (xy 201.620802 -53.263638)
			(xy 201.562006 -53.112521) (xy 201.510755 -52.958681) (xy 201.467175 -52.802495) (xy 201.431372 -52.644345)
			(xy 201.403434 -52.484618) (xy 201.38343 -52.323704) (xy 201.371407 -52.161999) (xy 201.367397 -51.999896)
			(xy 179.393088 -51.999896) (xy 179.393088 -52.481734) (xy 179.392602 -52.508985) (xy 179.384846 -52.562933)
			(xy 179.369491 -52.615228) (xy 179.346849 -52.664805) (xy 179.317383 -52.710655) (xy 179.281692 -52.751846)
			(xy 179.240501 -52.787537) (xy 179.194651 -52.817003) (xy 179.145074 -52.839645) (xy 179.092779 -52.855)
			(xy 179.038831 -52.862756) (xy 178.984329 -52.862756) (xy 178.930381 -52.855) (xy 178.878086 -52.839645)
			(xy 178.828509 -52.817003) (xy 178.782659 -52.787537) (xy 178.741468 -52.751846) (xy 178.705777 -52.710655)
			(xy 178.676311 -52.664805) (xy 178.653669 -52.615228) (xy 178.638314 -52.562933) (xy 178.630558 -52.508985)
			(xy 178.630072 -52.481734) (xy 0.509016 -52.481734) (xy 0.509016 -53.954934) (xy 181.659784 -53.954934)
			(xy 181.659784 -53.091334) (xy 181.66027 -53.064083) (xy 181.668026 -53.010135) (xy 181.683381 -52.95784)
			(xy 181.706023 -52.908263) (xy 181.735489 -52.862413) (xy 181.77118 -52.821222) (xy 181.812371 -52.785531)
			(xy 181.858221 -52.756065) (xy 181.907798 -52.733423) (xy 181.960093 -52.718068) (xy 182.014041 -52.710312)
			(xy 182.068543 -52.710312) (xy 182.122491 -52.718068) (xy 182.174786 -52.733423) (xy 182.224363 -52.756065)
			(xy 182.270213 -52.785531) (xy 182.311404 -52.821222) (xy 182.347095 -52.862413) (xy 182.376561 -52.908263)
			(xy 182.399203 -52.95784) (xy 182.414558 -53.010135) (xy 182.422314 -53.064083) (xy 182.4228 -53.091334)
			(xy 182.4228 -53.954934) (xy 182.422314 -53.982185) (xy 182.414558 -54.036133) (xy 182.399203 -54.088428)
			(xy 182.376561 -54.138005) (xy 182.347095 -54.183855) (xy 182.311404 -54.225046) (xy 182.270213 -54.260737)
			(xy 182.224363 -54.290203) (xy 182.174786 -54.312845) (xy 182.122491 -54.3282) (xy 182.068543 -54.335956)
			(xy 182.014041 -54.335956) (xy 181.960093 -54.3282) (xy 181.907798 -54.312845) (xy 181.858221 -54.290203)
			(xy 181.812371 -54.260737) (xy 181.77118 -54.225046) (xy 181.735489 -54.183855) (xy 181.706023 -54.138005)
			(xy 181.683381 -54.088428) (xy 181.668026 -54.036133) (xy 181.66027 -53.982185) (xy 181.659784 -53.954934)
			(xy 0.509016 -53.954934) (xy 0.509016 -55.481728) (xy 178.630072 -55.481728) (xy 178.630072 -54.618128)
			(xy 178.630558 -54.590877) (xy 178.638314 -54.536929) (xy 178.653669 -54.484634) (xy 178.676311 -54.435057)
			(xy 178.705777 -54.389207) (xy 178.741468 -54.348016) (xy 178.782659 -54.312325) (xy 178.828509 -54.282859)
			(xy 178.878086 -54.260217) (xy 178.930381 -54.244862) (xy 178.984329 -54.237106) (xy 179.038831 -54.237106)
			(xy 179.092779 -54.244862) (xy 179.145074 -54.260217) (xy 179.194651 -54.282859) (xy 179.240501 -54.312325)
			(xy 179.281692 -54.348016) (xy 179.317383 -54.389207) (xy 179.346849 -54.435057) (xy 179.369491 -54.484634)
			(xy 179.384846 -54.536929) (xy 179.392602 -54.590877) (xy 179.393088 -54.618128) (xy 179.393088 -55.481728)
			(xy 179.392602 -55.508979) (xy 179.384846 -55.562927) (xy 179.369491 -55.615222) (xy 179.346849 -55.664799)
			(xy 179.317383 -55.710649) (xy 179.281692 -55.75184) (xy 179.240501 -55.787531) (xy 179.194651 -55.816997)
			(xy 179.145074 -55.839639) (xy 179.092779 -55.854994) (xy 179.038831 -55.86275) (xy 178.984329 -55.86275)
			(xy 178.930381 -55.854994) (xy 178.878086 -55.839639) (xy 178.828509 -55.816997) (xy 178.782659 -55.787531)
			(xy 178.741468 -55.75184) (xy 178.705777 -55.710649) (xy 178.676311 -55.664799) (xy 178.653669 -55.615222)
			(xy 178.638314 -55.562927) (xy 178.630558 -55.508979) (xy 178.630072 -55.481728) (xy 0.509016 -55.481728)
			(xy 0.509016 -57.094435) (xy 170.841915 -57.094435) (xy 170.841915 -57.005413) (xy 170.849895 -56.916749)
			(xy 170.865791 -56.829158) (xy 170.889474 -56.743343) (xy 170.920754 -56.659998) (xy 170.95938 -56.579792)
			(xy 171.005039 -56.503371) (xy 171.057365 -56.43135) (xy 171.115936 -56.36431) (xy 171.180281 -56.30279)
			(xy 171.249881 -56.247286) (xy 171.324177 -56.198244) (xy 171.402569 -56.156059) (xy 171.484428 -56.121071)
			(xy 171.569093 -56.093562) (xy 171.655883 -56.073752) (xy 171.744099 -56.061802) (xy 171.833032 -56.057809)
			(xy 171.921965 -56.061802) (xy 172.010181 -56.073752) (xy 172.096971 -56.093562) (xy 172.181636 -56.121071)
			(xy 172.263495 -56.156059) (xy 172.341887 -56.198244) (xy 172.416183 -56.247286) (xy 172.485783 -56.30279)
			(xy 172.550128 -56.36431) (xy 172.608699 -56.43135) (xy 172.661025 -56.503371) (xy 172.663117 -56.506872)
			(xy 228.815392 -56.506872) (xy 228.815392 -55.643272) (xy 228.815878 -55.616021) (xy 228.823634 -55.562073)
			(xy 228.838989 -55.509778) (xy 228.861631 -55.460201) (xy 228.891097 -55.414351) (xy 228.926788 -55.37316)
			(xy 228.967979 -55.337469) (xy 229.013829 -55.308003) (xy 229.063406 -55.285361) (xy 229.115701 -55.270006)
			(xy 229.169649 -55.26225) (xy 229.224151 -55.26225) (xy 229.278099 -55.270006) (xy 229.330394 -55.285361)
			(xy 229.379971 -55.308003) (xy 229.425821 -55.337469) (xy 229.467012 -55.37316) (xy 229.502703 -55.414351)
			(xy 229.532169 -55.460201) (xy 229.554811 -55.509778) (xy 229.570166 -55.562073) (xy 229.577922 -55.616021)
			(xy 229.578408 -55.643272) (xy 229.578408 -55.911852) (xy 357.10365 -55.911852) (xy 357.10365 -55.857348)
			(xy 357.111406 -55.803398) (xy 357.126762 -55.751101) (xy 357.149403 -55.701521) (xy 357.17887 -55.655668)
			(xy 357.214562 -55.614476) (xy 357.255752 -55.578782) (xy 357.301604 -55.549313) (xy 357.351182 -55.526669)
			(xy 357.403478 -55.511311) (xy 357.457428 -55.503551) (xy 357.48468 -55.503064) (xy 358.34828 -55.503064)
			(xy 358.375532 -55.503582) (xy 358.429481 -55.511336) (xy 358.481777 -55.526689) (xy 358.531356 -55.549329)
			(xy 358.577209 -55.578794) (xy 358.618401 -55.614485) (xy 358.654094 -55.655675) (xy 358.683562 -55.701526)
			(xy 358.706204 -55.751104) (xy 358.72156 -55.8034) (xy 358.729317 -55.857348) (xy 358.729317 -55.911852)
			(xy 358.729316 -55.911856) (xy 359.950927 -55.911856) (xy 359.950927 -55.857344) (xy 359.958685 -55.803388)
			(xy 359.974043 -55.751084) (xy 359.996689 -55.701499) (xy 360.026161 -55.655642) (xy 360.061859 -55.614445)
			(xy 360.103058 -55.578749) (xy 360.148917 -55.549279) (xy 360.198503 -55.526636) (xy 360.250807 -55.511281)
			(xy 360.304764 -55.503526) (xy 360.33202 -55.503064) (xy 361.19562 -55.503064) (xy 361.222868 -55.503608)
			(xy 361.27681 -55.511366) (xy 361.329098 -55.526722) (xy 361.378669 -55.549362) (xy 361.424514 -55.578827)
			(xy 361.465699 -55.614516) (xy 361.501385 -55.655702) (xy 361.530847 -55.701548) (xy 361.553485 -55.75112)
			(xy 361.568838 -55.80341) (xy 361.576594 -55.857352) (xy 361.576594 -55.911848) (xy 361.576593 -55.911857)
			(xy 363.514527 -55.911857) (xy 363.514527 -55.857343) (xy 363.522286 -55.803385) (xy 363.537645 -55.75108)
			(xy 363.560292 -55.701493) (xy 363.589766 -55.655635) (xy 363.625466 -55.614438) (xy 363.666667 -55.578742)
			(xy 363.712529 -55.549273) (xy 363.762117 -55.526631) (xy 363.814424 -55.511277) (xy 363.868383 -55.503524)
			(xy 363.89564 -55.503064) (xy 364.75924 -55.503064) (xy 364.786487 -55.503609) (xy 364.840427 -55.511369)
			(xy 364.892713 -55.526727) (xy 364.942281 -55.549369) (xy 364.988123 -55.578834) (xy 365.029306 -55.614523)
			(xy 365.06499 -55.655709) (xy 365.094451 -55.701554) (xy 365.117087 -55.751125) (xy 365.132439 -55.803412)
			(xy 365.140194 -55.857353) (xy 365.140194 -55.911847) (xy 365.132439 -55.965788) (xy 365.117087 -56.018075)
			(xy 365.094451 -56.067646) (xy 365.06499 -56.113491) (xy 365.029306 -56.154677) (xy 364.988123 -56.190366)
			(xy 364.942281 -56.219831) (xy 364.892713 -56.242473) (xy 364.840427 -56.257831) (xy 364.786487 -56.265591)
			(xy 364.75924 -56.26608) (xy 363.89564 -56.26608) (xy 363.868383 -56.265676) (xy 363.814424 -56.257923)
			(xy 363.762117 -56.242569) (xy 363.712529 -56.219927) (xy 363.666667 -56.190458) (xy 363.625466 -56.154762)
			(xy 363.589766 -56.113565) (xy 363.560292 -56.067707) (xy 363.537645 -56.01812) (xy 363.522286 -55.965815)
			(xy 363.514527 -55.911857) (xy 361.576593 -55.911857) (xy 361.568838 -55.96579) (xy 361.553485 -56.01808)
			(xy 361.530847 -56.067652) (xy 361.501385 -56.113498) (xy 361.465699 -56.154684) (xy 361.424514 -56.190373)
			(xy 361.378669 -56.219838) (xy 361.329098 -56.242478) (xy 361.27681 -56.257834) (xy 361.222868 -56.265592)
			(xy 361.19562 -56.26608) (xy 360.33202 -56.26608) (xy 360.304764 -56.265674) (xy 360.250807 -56.257919)
			(xy 360.198503 -56.242564) (xy 360.148917 -56.219921) (xy 360.103058 -56.190451) (xy 360.061859 -56.154755)
			(xy 360.026161 -56.113558) (xy 359.996689 -56.067701) (xy 359.974043 -56.018116) (xy 359.958685 -55.965812)
			(xy 359.950927 -55.911856) (xy 358.729316 -55.911856) (xy 358.72156 -55.9658) (xy 358.706204 -56.018096)
			(xy 358.683562 -56.067674) (xy 358.654094 -56.113525) (xy 358.618401 -56.154715) (xy 358.577209 -56.190406)
			(xy 358.531356 -56.219871) (xy 358.481777 -56.242511) (xy 358.429481 -56.257864) (xy 358.375532 -56.265618)
			(xy 358.34828 -56.26608) (xy 357.48468 -56.26608) (xy 357.457428 -56.265649) (xy 357.403478 -56.257889)
			(xy 357.351182 -56.242531) (xy 357.301604 -56.219887) (xy 357.255752 -56.190418) (xy 357.214562 -56.154724)
			(xy 357.17887 -56.113532) (xy 357.149403 -56.067679) (xy 357.126762 -56.018099) (xy 357.111406 -55.965802)
			(xy 357.10365 -55.911852) (xy 229.578408 -55.911852) (xy 229.578408 -56.506872) (xy 229.577922 -56.534123)
			(xy 229.570166 -56.588071) (xy 229.554811 -56.640366) (xy 229.532169 -56.689943) (xy 229.502703 -56.735793)
			(xy 229.467012 -56.776984) (xy 229.425821 -56.812675) (xy 229.379971 -56.842141) (xy 229.330394 -56.864783)
			(xy 229.278099 -56.880138) (xy 229.224151 -56.887894) (xy 229.169649 -56.887894) (xy 229.115701 -56.880138)
			(xy 229.063406 -56.864783) (xy 229.013829 -56.842141) (xy 228.967979 -56.812675) (xy 228.926788 -56.776984)
			(xy 228.891097 -56.735793) (xy 228.861631 -56.689943) (xy 228.838989 -56.640366) (xy 228.823634 -56.588071)
			(xy 228.815878 -56.534123) (xy 228.815392 -56.506872) (xy 172.663117 -56.506872) (xy 172.706684 -56.579792)
			(xy 172.74531 -56.659998) (xy 172.77659 -56.743343) (xy 172.800273 -56.829158) (xy 172.816169 -56.916749)
			(xy 172.824149 -57.005413) (xy 172.824648 -57.049924) (xy 172.824149 -57.094435) (xy 172.816169 -57.183099)
			(xy 172.800273 -57.27069) (xy 172.77659 -57.356505) (xy 172.74531 -57.43985) (xy 172.706684 -57.520056)
			(xy 172.661025 -57.596477) (xy 172.608699 -57.668498) (xy 172.550128 -57.735538) (xy 172.485783 -57.797058)
			(xy 172.416183 -57.852562) (xy 172.341887 -57.901604) (xy 172.263495 -57.943789) (xy 172.181636 -57.978777)
			(xy 172.096971 -58.006286) (xy 172.010181 -58.026096) (xy 171.921965 -58.038046) (xy 171.833032 -58.04204)
			(xy 171.744099 -58.038046) (xy 171.655883 -58.026096) (xy 171.569093 -58.006286) (xy 171.484428 -57.978777)
			(xy 171.402569 -57.943789) (xy 171.324177 -57.901604) (xy 171.249881 -57.852562) (xy 171.180281 -57.797058)
			(xy 171.115936 -57.735538) (xy 171.057365 -57.668498) (xy 171.005039 -57.596477) (xy 170.95938 -57.520056)
			(xy 170.920754 -57.43985) (xy 170.889474 -57.356505) (xy 170.865791 -57.27069) (xy 170.849895 -57.183099)
			(xy 170.841915 -57.094435) (xy 0.509016 -57.094435) (xy 0.509016 -58.306716) (xy 230.115872 -58.306716)
			(xy 230.115872 -57.443116) (xy 230.116358 -57.415865) (xy 230.124114 -57.361917) (xy 230.139469 -57.309622)
			(xy 230.162111 -57.260045) (xy 230.191577 -57.214195) (xy 230.227268 -57.173004) (xy 230.268459 -57.137313)
			(xy 230.314309 -57.107847) (xy 230.363886 -57.085205) (xy 230.416181 -57.06985) (xy 230.470129 -57.062094)
			(xy 230.524631 -57.062094) (xy 230.578579 -57.06985) (xy 230.630874 -57.085205) (xy 230.680451 -57.107847)
			(xy 230.726301 -57.137313) (xy 230.767492 -57.173004) (xy 230.803183 -57.214195) (xy 230.832649 -57.260045)
			(xy 230.855291 -57.309622) (xy 230.870646 -57.361917) (xy 230.878402 -57.415865) (xy 230.878888 -57.443116)
			(xy 230.878888 -58.30189) (xy 240.282476 -58.30189) (xy 240.282476 -57.43829) (xy 240.282962 -57.411039)
			(xy 240.290718 -57.357091) (xy 240.306073 -57.304796) (xy 240.328715 -57.255219) (xy 240.358181 -57.209369)
			(xy 240.393872 -57.168178) (xy 240.435063 -57.132487) (xy 240.480913 -57.103021) (xy 240.53049 -57.080379)
			(xy 240.582785 -57.065024) (xy 240.636733 -57.057268) (xy 240.691235 -57.057268) (xy 240.745183 -57.065024)
			(xy 240.797478 -57.080379) (xy 240.847055 -57.103021) (xy 240.892905 -57.132487) (xy 240.934096 -57.168178)
			(xy 240.969787 -57.209369) (xy 240.999253 -57.255219) (xy 241.021895 -57.304796) (xy 241.03725 -57.357091)
			(xy 241.045006 -57.411039) (xy 241.045492 -57.43829) (xy 241.045492 -58.30189) (xy 241.045006 -58.329141)
			(xy 241.03725 -58.383089) (xy 241.021895 -58.435384) (xy 240.999253 -58.484961) (xy 240.969787 -58.530811)
			(xy 240.941894 -58.563002) (xy 242.736116 -58.563002) (xy 242.736116 -57.699402) (xy 242.736602 -57.672151)
			(xy 242.744358 -57.618203) (xy 242.759713 -57.565908) (xy 242.782355 -57.516331) (xy 242.811821 -57.470481)
			(xy 242.847512 -57.42929) (xy 242.888703 -57.393599) (xy 242.934553 -57.364133) (xy 242.98413 -57.341491)
			(xy 243.036425 -57.326136) (xy 243.090373 -57.31838) (xy 243.144875 -57.31838) (xy 243.198823 -57.326136)
			(xy 243.251118 -57.341491) (xy 243.300695 -57.364133) (xy 243.346545 -57.393599) (xy 243.387736 -57.42929)
			(xy 243.423427 -57.470481) (xy 243.452893 -57.516331) (xy 243.475535 -57.565908) (xy 243.49089 -57.618203)
			(xy 243.498646 -57.672151) (xy 243.499132 -57.699402) (xy 243.499132 -58.563002) (xy 243.498646 -58.590253)
			(xy 243.49089 -58.644201) (xy 243.475535 -58.696496) (xy 243.452893 -58.746073) (xy 243.423427 -58.791923)
			(xy 243.387736 -58.833114) (xy 243.346545 -58.868805) (xy 243.300695 -58.898271) (xy 243.251118 -58.920913)
			(xy 243.198823 -58.936268) (xy 243.144875 -58.944024) (xy 243.090373 -58.944024) (xy 243.036425 -58.936268)
			(xy 242.98413 -58.920913) (xy 242.934553 -58.898271) (xy 242.888703 -58.868805) (xy 242.847512 -58.833114)
			(xy 242.811821 -58.791923) (xy 242.782355 -58.746073) (xy 242.759713 -58.696496) (xy 242.744358 -58.644201)
			(xy 242.736602 -58.590253) (xy 242.736116 -58.563002) (xy 240.941894 -58.563002) (xy 240.934096 -58.572002)
			(xy 240.892905 -58.607693) (xy 240.847055 -58.637159) (xy 240.797478 -58.659801) (xy 240.745183 -58.675156)
			(xy 240.691235 -58.682912) (xy 240.636733 -58.682912) (xy 240.582785 -58.675156) (xy 240.53049 -58.659801)
			(xy 240.480913 -58.637159) (xy 240.435063 -58.607693) (xy 240.393872 -58.572002) (xy 240.358181 -58.530811)
			(xy 240.328715 -58.484961) (xy 240.306073 -58.435384) (xy 240.290718 -58.383089) (xy 240.282962 -58.329141)
			(xy 240.282476 -58.30189) (xy 230.878888 -58.30189) (xy 230.878888 -58.306716) (xy 230.878402 -58.333967)
			(xy 230.870646 -58.387915) (xy 230.855291 -58.44021) (xy 230.832649 -58.489787) (xy 230.803183 -58.535637)
			(xy 230.767492 -58.576828) (xy 230.726301 -58.612519) (xy 230.680451 -58.641985) (xy 230.630874 -58.664627)
			(xy 230.578579 -58.679982) (xy 230.524631 -58.687738) (xy 230.470129 -58.687738) (xy 230.416181 -58.679982)
			(xy 230.363886 -58.664627) (xy 230.314309 -58.641985) (xy 230.268459 -58.612519) (xy 230.227268 -58.576828)
			(xy 230.191577 -58.535637) (xy 230.162111 -58.489787) (xy 230.139469 -58.44021) (xy 230.124114 -58.387915)
			(xy 230.116358 -58.333967) (xy 230.115872 -58.306716) (xy 0.509016 -58.306716) (xy 0.509016 -59.99988)
			(xy 16.983969 -59.99988) (xy 16.987993 -59.914112) (xy 17.000031 -59.829098) (xy 17.019978 -59.745584)
			(xy 17.047657 -59.664305) (xy 17.082825 -59.585976) (xy 17.125174 -59.511283) (xy 17.174331 -59.440885)
			(xy 17.229864 -59.375399) (xy 17.291286 -59.315401) (xy 17.358055 -59.261418) (xy 17.429587 -59.213925)
			(xy 17.505251 -59.173339) (xy 17.584384 -59.140016) (xy 17.666289 -59.11425) (xy 17.750247 -59.096267)
			(xy 17.835521 -59.086225) (xy 17.92136 -59.084212) (xy 18.00701 -59.090246) (xy 18.091718 -59.104274)
			(xy 18.174741 -59.126173) (xy 18.255349 -59.15575) (xy 18.332833 -59.192745) (xy 18.406512 -59.236833)
			(xy 18.475738 -59.287627) (xy 18.539905 -59.34468) (xy 18.598446 -59.407491) (xy 18.650849 -59.475508)
			(xy 18.696652 -59.548133) (xy 18.735453 -59.624728) (xy 18.766912 -59.70462) (xy 18.790751 -59.787107)
			(xy 18.806761 -59.871464) (xy 18.814801 -59.956949) (xy 18.815304 -59.99988) (xy 18.814801 -60.042811)
			(xy 18.806761 -60.128296) (xy 18.790751 -60.212653) (xy 18.766912 -60.29514) (xy 18.735453 -60.375032)
			(xy 18.73545 -60.375038) (xy 233.333297 -60.375038) (xy 233.337302 -60.28713) (xy 233.349285 -60.19995)
			(xy 233.369145 -60.114221) (xy 233.39672 -60.030653) (xy 233.431779 -59.949939) (xy 233.474032 -59.872747)
			(xy 233.52313 -59.799718) (xy 233.578666 -59.731456) (xy 233.640178 -59.668526) (xy 233.707159 -59.611452)
			(xy 233.779052 -59.560704) (xy 233.855261 -59.516704) (xy 233.935156 -59.479817) (xy 234.018075 -59.450348)
			(xy 234.10333 -59.428541) (xy 234.190214 -59.414577) (xy 234.278008 -59.408571) (xy 234.365985 -59.410575)
			(xy 234.453415 -59.42057) (xy 234.539574 -59.438474) (xy 234.623748 -59.464138) (xy 234.705239 -59.497351)
			(xy 234.783373 -59.537837) (xy 234.857501 -59.585259) (xy 234.927009 -59.639226) (xy 234.991323 -59.699291)
			(xy 235.049907 -59.764955) (xy 235.102278 -59.835674) (xy 235.148001 -59.910862) (xy 235.186698 -59.989897)
			(xy 235.218047 -60.072123) (xy 235.241789 -60.156859) (xy 235.257727 -60.243403) (xy 235.265729 -60.331038)
			(xy 235.26623 -60.375038) (xy 235.265729 -60.419038) (xy 235.257727 -60.506673) (xy 235.241789 -60.593217)
			(xy 235.218047 -60.677953) (xy 235.186698 -60.760179) (xy 235.148001 -60.839214) (xy 235.102278 -60.914402)
			(xy 235.049907 -60.985121) (xy 234.991323 -61.050785) (xy 234.927009 -61.11085) (xy 234.857501 -61.164817)
			(xy 234.783373 -61.212239) (xy 234.705239 -61.252725) (xy 234.623748 -61.285938) (xy 234.539574 -61.311602)
			(xy 234.453415 -61.329506) (xy 234.365985 -61.339501) (xy 234.278008 -61.341505) (xy 234.190214 -61.335499)
			(xy 234.10333 -61.321535) (xy 234.018075 -61.299728) (xy 233.935156 -61.270259) (xy 233.855261 -61.233372)
			(xy 233.779052 -61.189372) (xy 233.707159 -61.138624) (xy 233.640178 -61.08155) (xy 233.578666 -61.01862)
			(xy 233.52313 -60.950358) (xy 233.474032 -60.877329) (xy 233.431779 -60.800137) (xy 233.39672 -60.719423)
			(xy 233.369145 -60.635855) (xy 233.349285 -60.550126) (xy 233.337302 -60.462946) (xy 233.333297 -60.375038)
			(xy 18.73545 -60.375038) (xy 18.696652 -60.451627) (xy 18.650849 -60.524252) (xy 18.598446 -60.592269)
			(xy 18.539905 -60.65508) (xy 18.475738 -60.712133) (xy 18.406512 -60.762927) (xy 18.332833 -60.807015)
			(xy 18.255349 -60.84401) (xy 18.174741 -60.873587) (xy 18.091718 -60.895486) (xy 18.00701 -60.909514)
			(xy 17.92136 -60.915548) (xy 17.835521 -60.913535) (xy 17.750247 -60.903493) (xy 17.666289 -60.88551)
			(xy 17.584384 -60.859744) (xy 17.505251 -60.826421) (xy 17.429587 -60.785835) (xy 17.358055 -60.738342)
			(xy 17.291286 -60.684359) (xy 17.229864 -60.624361) (xy 17.174331 -60.558875) (xy 17.125174 -60.488477)
			(xy 17.082825 -60.413784) (xy 17.047657 -60.335455) (xy 17.019978 -60.254176) (xy 17.000031 -60.170662)
			(xy 16.987993 -60.085648) (xy 16.983969 -59.99988) (xy 0.509016 -59.99988) (xy 0.509016 -74.760836)
			(xy 39.554404 -74.760836) (xy 39.554404 -66.060828) (xy 39.554909 -65.955304) (xy 39.562993 -65.74441)
			(xy 39.579149 -65.533981) (xy 39.603352 -65.324324) (xy 39.635569 -65.115749) (xy 39.675751 -64.908561)
			(xy 39.723839 -64.703064) (xy 39.779763 -64.49956) (xy 39.84344 -64.298347) (xy 39.914778 -64.09972)
			(xy 39.993672 -63.903972) (xy 40.080005 -63.71139) (xy 40.173652 -63.522255) (xy 40.274474 -63.336846)
			(xy 40.382324 -63.155435) (xy 40.497043 -62.978288) (xy 40.618463 -62.805666) (xy 40.746406 -62.63782)
			(xy 40.880684 -62.474998) (xy 41.0211 -62.317439) (xy 41.167448 -62.165374) (xy 41.319513 -62.019026)
			(xy 41.477072 -61.87861) (xy 41.639894 -61.744332) (xy 41.80774 -61.616389) (xy 41.980362 -61.494969)
			(xy 42.157509 -61.38025) (xy 42.33892 -61.2724) (xy 42.524329 -61.171578) (xy 42.713464 -61.077931)
			(xy 42.906046 -60.991598) (xy 43.101794 -60.912704) (xy 43.300421 -60.841366) (xy 43.501634 -60.777689)
			(xy 43.705138 -60.721765) (xy 43.910635 -60.673677) (xy 44.117823 -60.633495) (xy 44.326398 -60.601278)
			(xy 44.536055 -60.577075) (xy 44.746484 -60.560919) (xy 44.957378 -60.552835) (xy 45.168426 -60.552835)
			(xy 45.37932 -60.560919) (xy 45.589749 -60.577075) (xy 45.799406 -60.601278) (xy 46.007981 -60.633495)
			(xy 46.215169 -60.673677) (xy 46.420666 -60.721765) (xy 46.62417 -60.777689) (xy 46.825383 -60.841366)
			(xy 47.02401 -60.912704) (xy 47.219758 -60.991598) (xy 47.41234 -61.077931) (xy 47.601475 -61.171578)
			(xy 47.786884 -61.2724) (xy 47.968295 -61.38025) (xy 48.145442 -61.494969) (xy 48.318064 -61.616389)
			(xy 48.48591 -61.744332) (xy 48.648732 -61.87861) (xy 48.806291 -62.019026) (xy 48.958356 -62.165374)
			(xy 49.104704 -62.317439) (xy 49.24512 -62.474998) (xy 49.379398 -62.63782) (xy 49.507341 -62.805666)
			(xy 49.628761 -62.978288) (xy 49.74348 -63.155435) (xy 49.85133 -63.336846) (xy 49.952152 -63.522255)
			(xy 50.045799 -63.71139) (xy 50.132132 -63.903972) (xy 50.211026 -64.09972) (xy 50.282364 -64.298347)
			(xy 50.346041 -64.49956) (xy 50.401965 -64.703064) (xy 50.450053 -64.908561) (xy 50.490235 -65.115749)
			(xy 50.522452 -65.324324) (xy 50.546655 -65.533981) (xy 50.562811 -65.74441) (xy 50.570895 -65.955304)
			(xy 50.5714 -66.060828) (xy 50.5714 -74.760836) (xy 50.571366 -74.767948) (xy 173.354492 -74.767948)
			(xy 173.354492 -66.06794) (xy 173.354997 -65.962416) (xy 173.363081 -65.751522) (xy 173.379237 -65.541093)
			(xy 173.40344 -65.331436) (xy 173.435657 -65.122861) (xy 173.475839 -64.915673) (xy 173.523927 -64.710176)
			(xy 173.579851 -64.506672) (xy 173.643528 -64.305459) (xy 173.714866 -64.106832) (xy 173.79376 -63.911084)
			(xy 173.880093 -63.718502) (xy 173.97374 -63.529367) (xy 174.074562 -63.343958) (xy 174.182412 -63.162547)
			(xy 174.297131 -62.9854) (xy 174.418551 -62.812778) (xy 174.546494 -62.644932) (xy 174.680772 -62.48211)
			(xy 174.821188 -62.324551) (xy 174.967536 -62.172486) (xy 175.119601 -62.026138) (xy 175.27716 -61.885722)
			(xy 175.439982 -61.751444) (xy 175.607828 -61.623501) (xy 175.78045 -61.502081) (xy 175.957597 -61.387362)
			(xy 176.139008 -61.279512) (xy 176.324417 -61.17869) (xy 176.513552 -61.085043) (xy 176.706134 -60.99871)
			(xy 176.901882 -60.919816) (xy 177.100509 -60.848478) (xy 177.301722 -60.784801) (xy 177.505226 -60.728877)
			(xy 177.710723 -60.680789) (xy 177.917911 -60.640607) (xy 178.126486 -60.60839) (xy 178.336143 -60.584187)
			(xy 178.546572 -60.568031) (xy 178.757466 -60.559947) (xy 178.968514 -60.559947) (xy 179.179408 -60.568031)
			(xy 179.389837 -60.584187) (xy 179.599494 -60.60839) (xy 179.808069 -60.640607) (xy 180.015257 -60.680789)
			(xy 180.220754 -60.728877) (xy 180.424258 -60.784801) (xy 180.625471 -60.848478) (xy 180.824098 -60.919816)
			(xy 181.019846 -60.99871) (xy 181.212428 -61.085043) (xy 181.401563 -61.17869) (xy 181.586972 -61.279512)
			(xy 181.768383 -61.387362) (xy 181.94553 -61.502081) (xy 182.118152 -61.623501) (xy 182.285998 -61.751444)
			(xy 182.44882 -61.885722) (xy 182.606379 -62.026138) (xy 182.758444 -62.172486) (xy 182.904792 -62.324551)
			(xy 183.045208 -62.48211) (xy 183.179486 -62.644932) (xy 183.307429 -62.812778) (xy 183.428849 -62.9854)
			(xy 183.543568 -63.162547) (xy 183.651418 -63.343958) (xy 183.75224 -63.529367) (xy 183.845887 -63.718502)
			(xy 183.93222 -63.911084) (xy 184.011114 -64.106832) (xy 184.082452 -64.305459) (xy 184.146129 -64.506672)
			(xy 184.202053 -64.710176) (xy 184.250141 -64.915673) (xy 184.290323 -65.122861) (xy 184.32254 -65.331436)
			(xy 184.346743 -65.541093) (xy 184.362899 -65.751522) (xy 184.370983 -65.962416) (xy 184.371488 -66.06794)
			(xy 184.371488 -74.760836) (xy 287.494472 -74.760836) (xy 287.494472 -66.060828) (xy 287.494977 -65.955304)
			(xy 287.503061 -65.74441) (xy 287.519217 -65.533981) (xy 287.54342 -65.324324) (xy 287.575637 -65.115749)
			(xy 287.615819 -64.908561) (xy 287.663907 -64.703064) (xy 287.719831 -64.49956) (xy 287.783508 -64.298347)
			(xy 287.854846 -64.09972) (xy 287.93374 -63.903972) (xy 288.020073 -63.71139) (xy 288.11372 -63.522255)
			(xy 288.214542 -63.336846) (xy 288.322392 -63.155435) (xy 288.437111 -62.978288) (xy 288.558531 -62.805666)
			(xy 288.686474 -62.63782) (xy 288.820752 -62.474998) (xy 288.961168 -62.317439) (xy 289.107516 -62.165374)
			(xy 289.259581 -62.019026) (xy 289.41714 -61.87861) (xy 289.579962 -61.744332) (xy 289.747808 -61.616389)
			(xy 289.92043 -61.494969) (xy 290.097577 -61.38025) (xy 290.278988 -61.2724) (xy 290.464397 -61.171578)
			(xy 290.653532 -61.077931) (xy 290.846114 -60.991598) (xy 291.041862 -60.912704) (xy 291.240489 -60.841366)
			(xy 291.441702 -60.777689) (xy 291.645206 -60.721765) (xy 291.850703 -60.673677) (xy 292.057891 -60.633495)
			(xy 292.266466 -60.601278) (xy 292.476123 -60.577075) (xy 292.686552 -60.560919) (xy 292.897446 -60.552835)
			(xy 293.108494 -60.552835) (xy 293.319388 -60.560919) (xy 293.529817 -60.577075) (xy 293.739474 -60.601278)
			(xy 293.948049 -60.633495) (xy 294.155237 -60.673677) (xy 294.360734 -60.721765) (xy 294.564238 -60.777689)
			(xy 294.765451 -60.841366) (xy 294.964078 -60.912704) (xy 295.159826 -60.991598) (xy 295.352408 -61.077931)
			(xy 295.541543 -61.171578) (xy 295.726952 -61.2724) (xy 295.908363 -61.38025) (xy 296.063868 -61.480954)
			(xy 351.822512 -61.480954) (xy 351.822512 -60.617354) (xy 351.822998 -60.590103) (xy 351.830754 -60.536155)
			(xy 351.846109 -60.48386) (xy 351.868751 -60.434283) (xy 351.898217 -60.388433) (xy 351.933908 -60.347242)
			(xy 351.975099 -60.311551) (xy 352.020949 -60.282085) (xy 352.070526 -60.259443) (xy 352.122821 -60.244088)
			(xy 352.176769 -60.236332) (xy 352.231271 -60.236332) (xy 352.285219 -60.244088) (xy 352.337514 -60.259443)
			(xy 352.387091 -60.282085) (xy 352.432941 -60.311551) (xy 352.474132 -60.347242) (xy 352.509823 -60.388433)
			(xy 352.539289 -60.434283) (xy 352.561931 -60.48386) (xy 352.577286 -60.536155) (xy 352.585042 -60.590103)
			(xy 352.585528 -60.617354) (xy 352.585528 -61.223271) (xy 355.46889 -61.223271) (xy 355.46889 -61.168729)
			(xy 355.476653 -61.114741) (xy 355.492019 -61.062408) (xy 355.514676 -61.012794) (xy 355.544164 -60.966909)
			(xy 355.579881 -60.925688) (xy 355.621101 -60.88997) (xy 355.666985 -60.860481) (xy 355.716598 -60.837822)
			(xy 355.768931 -60.822455) (xy 355.822919 -60.814691) (xy 355.85019 -60.814204) (xy 356.71379 -60.814204)
			(xy 356.741059 -60.814735) (xy 356.795042 -60.822495) (xy 356.847371 -60.837859) (xy 356.896981 -60.860514)
			(xy 356.942862 -60.889999) (xy 356.98408 -60.925713) (xy 357.019795 -60.96693) (xy 357.049281 -61.01281)
			(xy 357.071937 -61.062419) (xy 357.087303 -61.114748) (xy 357.095065 -61.168731) (xy 357.095065 -61.223269)
			(xy 357.087303 -61.277252) (xy 357.071937 -61.329581) (xy 357.049281 -61.37919) (xy 357.019795 -61.42507)
			(xy 356.98408 -61.466287) (xy 356.942862 -61.502001) (xy 356.896981 -61.531486) (xy 356.847371 -61.554141)
			(xy 356.795042 -61.569505) (xy 356.741059 -61.577265) (xy 356.71379 -61.577728) (xy 355.85019 -61.577728)
			(xy 355.822919 -61.577309) (xy 355.768931 -61.569545) (xy 355.716598 -61.554178) (xy 355.666985 -61.531519)
			(xy 355.621101 -61.50203) (xy 355.579881 -61.466312) (xy 355.544164 -61.425091) (xy 355.514676 -61.379206)
			(xy 355.492019 -61.329592) (xy 355.476653 -61.277259) (xy 355.46889 -61.223271) (xy 352.585528 -61.223271)
			(xy 352.585528 -61.480954) (xy 352.585042 -61.508205) (xy 352.577286 -61.562153) (xy 352.561931 -61.614448)
			(xy 352.539289 -61.664025) (xy 352.509823 -61.709875) (xy 352.474132 -61.751066) (xy 352.432941 -61.786757)
			(xy 352.387091 -61.816223) (xy 352.337514 -61.838865) (xy 352.285219 -61.85422) (xy 352.231271 -61.861976)
			(xy 352.176769 -61.861976) (xy 352.122821 -61.85422) (xy 352.070526 -61.838865) (xy 352.020949 -61.816223)
			(xy 351.975099 -61.786757) (xy 351.933908 -61.751066) (xy 351.898217 -61.709875) (xy 351.868751 -61.664025)
			(xy 351.846109 -61.614448) (xy 351.830754 -61.562153) (xy 351.822998 -61.508205) (xy 351.822512 -61.480954)
			(xy 296.063868 -61.480954) (xy 296.08551 -61.494969) (xy 296.258132 -61.616389) (xy 296.425978 -61.744332)
			(xy 296.5888 -61.87861) (xy 296.746359 -62.019026) (xy 296.898424 -62.165374) (xy 297.044772 -62.317439)
			(xy 297.185188 -62.474998) (xy 297.319466 -62.63782) (xy 297.447409 -62.805666) (xy 297.568829 -62.978288)
			(xy 297.683548 -63.155435) (xy 297.751584 -63.269876) (xy 350.300544 -63.269876) (xy 350.300544 -62.406276)
			(xy 350.30103 -62.379025) (xy 350.308786 -62.325077) (xy 350.324141 -62.272782) (xy 350.346783 -62.223205)
			(xy 350.376249 -62.177355) (xy 350.41194 -62.136164) (xy 350.453131 -62.100473) (xy 350.498981 -62.071007)
			(xy 350.548558 -62.048365) (xy 350.600853 -62.03301) (xy 350.654801 -62.025254) (xy 350.709303 -62.025254)
			(xy 350.763251 -62.03301) (xy 350.815546 -62.048365) (xy 350.865123 -62.071007) (xy 350.910973 -62.100473)
			(xy 350.952164 -62.136164) (xy 350.987855 -62.177355) (xy 351.017321 -62.223205) (xy 351.039963 -62.272782)
			(xy 351.055318 -62.325077) (xy 351.063074 -62.379025) (xy 351.06356 -62.406276) (xy 351.06356 -63.269876)
			(xy 351.063074 -63.297127) (xy 351.055318 -63.351075) (xy 351.039963 -63.40337) (xy 351.017321 -63.452947)
			(xy 350.987855 -63.498797) (xy 350.952164 -63.539988) (xy 350.910973 -63.575679) (xy 350.865123 -63.605145)
			(xy 350.815546 -63.627787) (xy 350.763251 -63.643142) (xy 350.709303 -63.650898) (xy 350.654801 -63.650898)
			(xy 350.600853 -63.643142) (xy 350.548558 -63.627787) (xy 350.498981 -63.605145) (xy 350.453131 -63.575679)
			(xy 350.41194 -63.539988) (xy 350.376249 -63.498797) (xy 350.346783 -63.452947) (xy 350.324141 -63.40337)
			(xy 350.308786 -63.351075) (xy 350.30103 -63.297127) (xy 350.300544 -63.269876) (xy 297.751584 -63.269876)
			(xy 297.791398 -63.336846) (xy 297.89222 -63.522255) (xy 297.985867 -63.71139) (xy 298.0722 -63.903972)
			(xy 298.151094 -64.09972) (xy 298.222432 -64.298347) (xy 298.286109 -64.49956) (xy 298.342033 -64.703064)
			(xy 298.390121 -64.908561) (xy 298.396302 -64.940434) (xy 325.410068 -64.940434) (xy 325.410068 -64.076834)
			(xy 325.410554 -64.049565) (xy 325.418316 -63.995581) (xy 325.433681 -63.943251) (xy 325.456338 -63.893641)
			(xy 325.485824 -63.84776) (xy 325.521539 -63.806543) (xy 325.562756 -63.770828) (xy 325.608637 -63.741342)
			(xy 325.658247 -63.718685) (xy 325.710577 -63.70332) (xy 325.764561 -63.695558) (xy 325.819099 -63.695558)
			(xy 325.873083 -63.70332) (xy 325.925413 -63.718685) (xy 325.975023 -63.741342) (xy 326.020904 -63.770828)
			(xy 326.062121 -63.806543) (xy 326.097836 -63.84776) (xy 326.127322 -63.893641) (xy 326.149979 -63.943251)
			(xy 326.165344 -63.995581) (xy 326.173106 -64.049565) (xy 326.173592 -64.076834) (xy 326.173592 -64.940434)
			(xy 326.173106 -64.967703) (xy 326.165344 -65.021687) (xy 326.149979 -65.074017) (xy 326.127322 -65.123627)
			(xy 326.097836 -65.169508) (xy 326.062121 -65.210725) (xy 326.020904 -65.24644) (xy 325.975023 -65.275926)
			(xy 325.925413 -65.298583) (xy 325.873083 -65.313948) (xy 325.819099 -65.32171) (xy 325.764561 -65.32171)
			(xy 325.710577 -65.313948) (xy 325.658247 -65.298583) (xy 325.608637 -65.275926) (xy 325.562756 -65.24644)
			(xy 325.521539 -65.210725) (xy 325.485824 -65.169508) (xy 325.456338 -65.123627) (xy 325.433681 -65.074017)
			(xy 325.418316 -65.021687) (xy 325.410554 -64.967703) (xy 325.410068 -64.940434) (xy 298.396302 -64.940434)
			(xy 298.430303 -65.115749) (xy 298.46252 -65.324324) (xy 298.463125 -65.329562) (xy 352.362008 -65.329562)
			(xy 352.362008 -64.465962) (xy 352.362494 -64.438711) (xy 352.37025 -64.384763) (xy 352.385605 -64.332468)
			(xy 352.408247 -64.282891) (xy 352.437713 -64.237041) (xy 352.473404 -64.19585) (xy 352.514595 -64.160159)
			(xy 352.560445 -64.130693) (xy 352.610022 -64.108051) (xy 352.662317 -64.092696) (xy 352.716265 -64.08494)
			(xy 352.770767 -64.08494) (xy 352.824715 -64.092696) (xy 352.87701 -64.108051) (xy 352.926587 -64.130693)
			(xy 352.972437 -64.160159) (xy 353.013628 -64.19585) (xy 353.049319 -64.237041) (xy 353.078785 -64.282891)
			(xy 353.101427 -64.332468) (xy 353.116782 -64.384763) (xy 353.124538 -64.438711) (xy 353.125024 -64.465962)
			(xy 353.125024 -65.329562) (xy 353.124538 -65.356813) (xy 353.116782 -65.410761) (xy 353.101427 -65.463056)
			(xy 353.078785 -65.512633) (xy 353.049319 -65.558483) (xy 353.013628 -65.599674) (xy 352.972437 -65.635365)
			(xy 352.926587 -65.664831) (xy 352.87701 -65.687473) (xy 352.824715 -65.702828) (xy 352.770767 -65.710584)
			(xy 352.716265 -65.710584) (xy 352.662317 -65.702828) (xy 352.610022 -65.687473) (xy 352.560445 -65.664831)
			(xy 352.514595 -65.635365) (xy 352.473404 -65.599674) (xy 352.437713 -65.558483) (xy 352.408247 -65.512633)
			(xy 352.385605 -65.463056) (xy 352.37025 -65.410761) (xy 352.362494 -65.356813) (xy 352.362008 -65.329562)
			(xy 298.463125 -65.329562) (xy 298.486723 -65.533981) (xy 298.502879 -65.74441) (xy 298.510963 -65.955304)
			(xy 298.511468 -66.060828) (xy 298.511468 -68.449952) (xy 314.840884 -68.449952) (xy 314.844867 -68.321934)
			(xy 314.856802 -68.194412) (xy 314.876641 -68.067878) (xy 314.904308 -67.942822) (xy 314.939697 -67.819729)
			(xy 314.98267 -67.699073) (xy 315.033061 -67.581323) (xy 315.090675 -67.466933) (xy 315.155289 -67.356346)
			(xy 315.226653 -67.24999) (xy 315.304491 -67.148277) (xy 315.388502 -67.051599) (xy 315.478361 -66.960332)
			(xy 315.57372 -66.874827) (xy 315.674211 -66.795417) (xy 315.779444 -66.722407) (xy 315.889013 -66.656081)
			(xy 316.002493 -66.596695) (xy 316.119445 -66.544479) (xy 316.239418 -66.499635) (xy 316.361946 -66.462337)
			(xy 316.486557 -66.432728) (xy 316.612766 -66.410923) (xy 316.740088 -66.397007) (xy 316.868028 -66.391033)
			(xy 316.996092 -66.393025) (xy 317.123785 -66.402975) (xy 317.250612 -66.420844) (xy 317.376083 -66.446563)
			(xy 317.499712 -66.480033) (xy 317.621021 -66.521124) (xy 317.739541 -66.569678) (xy 317.854813 -66.625506)
			(xy 317.966391 -66.688392) (xy 318.073844 -66.758094) (xy 318.176756 -66.834341) (xy 318.274728 -66.916838)
			(xy 318.323666 -66.963544) (xy 350.27108 -66.963544) (xy 350.27108 -66.099944) (xy 350.271566 -66.072693)
			(xy 350.279322 -66.018745) (xy 350.294677 -65.96645) (xy 350.317319 -65.916873) (xy 350.346785 -65.871023)
			(xy 350.382476 -65.829832) (xy 350.423667 -65.794141) (xy 350.469517 -65.764675) (xy 350.519094 -65.742033)
			(xy 350.571389 -65.726678) (xy 350.625337 -65.718922) (xy 350.679839 -65.718922) (xy 350.733787 -65.726678)
			(xy 350.786082 -65.742033) (xy 350.835659 -65.764675) (xy 350.881509 -65.794141) (xy 350.9227 -65.829832)
			(xy 350.958391 -65.871023) (xy 350.987857 -65.916873) (xy 351.010499 -65.96645) (xy 351.025854 -66.018745)
			(xy 351.03361 -66.072693) (xy 351.034096 -66.099944) (xy 351.034096 -66.963544) (xy 351.03361 -66.990795)
			(xy 351.025854 -67.044743) (xy 351.010499 -67.097038) (xy 351.005595 -67.107776) (xy 396.642323 -67.107776)
			(xy 396.642323 -67.022004) (xy 396.650237 -66.936596) (xy 396.665998 -66.852284) (xy 396.689471 -66.769785)
			(xy 396.720456 -66.689804) (xy 396.758688 -66.613023) (xy 396.803842 -66.540098) (xy 396.855532 -66.47165)
			(xy 396.913317 -66.408263) (xy 396.976704 -66.350478) (xy 397.045152 -66.298788) (xy 397.118077 -66.253634)
			(xy 397.194858 -66.215402) (xy 397.274839 -66.184417) (xy 397.357338 -66.160944) (xy 397.44165 -66.145183)
			(xy 397.527058 -66.137269) (xy 397.61283 -66.137269) (xy 397.698238 -66.145183) (xy 397.78255 -66.160944)
			(xy 397.865049 -66.184417) (xy 397.94503 -66.215402) (xy 398.021811 -66.253634) (xy 398.094736 -66.298788)
			(xy 398.163184 -66.350478) (xy 398.226571 -66.408263) (xy 398.284356 -66.47165) (xy 398.336046 -66.540098)
			(xy 398.3812 -66.613023) (xy 398.419432 -66.689804) (xy 398.450417 -66.769785) (xy 398.47389 -66.852284)
			(xy 398.489651 -66.936596) (xy 398.497565 -67.022004) (xy 398.49806 -67.06489) (xy 398.497565 -67.107776)
			(xy 398.489651 -67.193184) (xy 398.47389 -67.277496) (xy 398.450417 -67.359995) (xy 398.419432 -67.439976)
			(xy 398.3812 -67.516757) (xy 398.336046 -67.589682) (xy 398.284356 -67.65813) (xy 398.226571 -67.721517)
			(xy 398.163184 -67.779302) (xy 398.094736 -67.830992) (xy 398.021811 -67.876146) (xy 397.94503 -67.914378)
			(xy 397.865049 -67.945363) (xy 397.78255 -67.968836) (xy 397.698238 -67.984597) (xy 397.61283 -67.992511)
			(xy 397.527058 -67.992511) (xy 397.44165 -67.984597) (xy 397.357338 -67.968836) (xy 397.274839 -67.945363)
			(xy 397.194858 -67.914378) (xy 397.118077 -67.876146) (xy 397.045152 -67.830992) (xy 396.976704 -67.779302)
			(xy 396.913317 -67.721517) (xy 396.855532 -67.65813) (xy 396.803842 -67.589682) (xy 396.758688 -67.516757)
			(xy 396.720456 -67.439976) (xy 396.689471 -67.359995) (xy 396.665998 -67.277496) (xy 396.650237 -67.193184)
			(xy 396.642323 -67.107776) (xy 351.005595 -67.107776) (xy 350.987857 -67.146615) (xy 350.958391 -67.192465)
			(xy 350.9227 -67.233656) (xy 350.881509 -67.269347) (xy 350.835659 -67.298813) (xy 350.786082 -67.321455)
			(xy 350.733787 -67.33681) (xy 350.679839 -67.344566) (xy 350.625337 -67.344566) (xy 350.571389 -67.33681)
			(xy 350.519094 -67.321455) (xy 350.469517 -67.298813) (xy 350.423667 -67.269347) (xy 350.382476 -67.233656)
			(xy 350.346785 -67.192465) (xy 350.317319 -67.146615) (xy 350.294677 -67.097038) (xy 350.279322 -67.044743)
			(xy 350.271566 -66.990795) (xy 350.27108 -66.963544) (xy 318.323666 -66.963544) (xy 318.367382 -67.005267)
			(xy 318.454359 -67.099285) (xy 318.535323 -67.198528) (xy 318.60996 -67.302613) (xy 318.677982 -67.411137)
			(xy 318.739126 -67.52368) (xy 318.793154 -67.639806) (xy 318.839859 -67.759067) (xy 318.879059 -67.881)
			(xy 318.910602 -68.005135) (xy 318.934367 -68.130991) (xy 318.950261 -68.25808) (xy 318.958224 -68.385912)
			(xy 318.958722 -68.449952) (xy 318.958224 -68.513992) (xy 318.950261 -68.641824) (xy 318.934367 -68.768913)
			(xy 318.910602 -68.894769) (xy 318.879059 -69.018904) (xy 318.851129 -69.10578) (xy 351.73158 -69.10578)
			(xy 351.73158 -68.24218) (xy 351.732066 -68.214911) (xy 351.739828 -68.160927) (xy 351.755193 -68.108597)
			(xy 351.77785 -68.058987) (xy 351.807336 -68.013106) (xy 351.843051 -67.971889) (xy 351.884268 -67.936174)
			(xy 351.930149 -67.906688) (xy 351.979759 -67.884031) (xy 352.032089 -67.868666) (xy 352.086073 -67.860904)
			(xy 352.140611 -67.860904) (xy 352.194595 -67.868666) (xy 352.246925 -67.884031) (xy 352.296535 -67.906688)
			(xy 352.342416 -67.936174) (xy 352.383633 -67.971889) (xy 352.419348 -68.013106) (xy 352.448834 -68.058987)
			(xy 352.471491 -68.108597) (xy 352.486856 -68.160927) (xy 352.494618 -68.214911) (xy 352.495104 -68.24218)
			(xy 352.495104 -69.10578) (xy 352.494618 -69.133049) (xy 352.486856 -69.187033) (xy 352.471491 -69.239363)
			(xy 352.448834 -69.288973) (xy 352.419348 -69.334854) (xy 352.383633 -69.376071) (xy 352.342416 -69.411786)
			(xy 352.296535 -69.441272) (xy 352.246925 -69.463929) (xy 352.194595 -69.479294) (xy 352.140611 -69.487056)
			(xy 352.086073 -69.487056) (xy 352.032089 -69.479294) (xy 351.979759 -69.463929) (xy 351.930149 -69.441272)
			(xy 351.884268 -69.411786) (xy 351.843051 -69.376071) (xy 351.807336 -69.334854) (xy 351.77785 -69.288973)
			(xy 351.755193 -69.239363) (xy 351.739828 -69.187033) (xy 351.732066 -69.133049) (xy 351.73158 -69.10578)
			(xy 318.851129 -69.10578) (xy 318.839859 -69.140837) (xy 318.793154 -69.260098) (xy 318.739126 -69.376224)
			(xy 318.677982 -69.488767) (xy 318.60996 -69.597291) (xy 318.535323 -69.701376) (xy 318.454359 -69.800619)
			(xy 318.367382 -69.894637) (xy 318.274728 -69.983066) (xy 318.176756 -70.065563) (xy 318.073844 -70.14181)
			(xy 317.966391 -70.211512) (xy 317.854813 -70.274398) (xy 317.739541 -70.330226) (xy 317.621021 -70.37878)
			(xy 317.499712 -70.419871) (xy 317.376083 -70.453341) (xy 317.250612 -70.47906) (xy 317.123785 -70.496929)
			(xy 316.996092 -70.506879) (xy 316.868028 -70.508871) (xy 316.740088 -70.502897) (xy 316.612766 -70.488981)
			(xy 316.486557 -70.467176) (xy 316.361946 -70.437567) (xy 316.239418 -70.400269) (xy 316.119445 -70.355425)
			(xy 316.002493 -70.303209) (xy 315.889013 -70.243823) (xy 315.779444 -70.177497) (xy 315.674211 -70.104487)
			(xy 315.57372 -70.025077) (xy 315.478361 -69.939572) (xy 315.388502 -69.848305) (xy 315.304491 -69.751627)
			(xy 315.226653 -69.649914) (xy 315.155289 -69.543558) (xy 315.090675 -69.432971) (xy 315.033061 -69.318581)
			(xy 314.98267 -69.200831) (xy 314.939697 -69.080175) (xy 314.904308 -68.957082) (xy 314.876641 -68.832026)
			(xy 314.856802 -68.705492) (xy 314.844867 -68.57797) (xy 314.840884 -68.449952) (xy 298.511468 -68.449952)
			(xy 298.511468 -71.213074) (xy 341.168388 -71.213074) (xy 341.168388 -71.158526) (xy 341.176151 -71.104534)
			(xy 341.19152 -71.052197) (xy 341.214181 -71.00258) (xy 341.243673 -70.956692) (xy 341.279395 -70.91547)
			(xy 341.320621 -70.879751) (xy 341.366511 -70.850263) (xy 341.416131 -70.827607) (xy 341.46847 -70.812243)
			(xy 341.522462 -70.804485) (xy 341.549736 -70.804024) (xy 342.413336 -70.804024) (xy 342.440603 -70.804541)
			(xy 342.49458 -70.812306) (xy 342.546904 -70.827674) (xy 342.596508 -70.850332) (xy 342.642382 -70.879817)
			(xy 342.683594 -70.915531) (xy 342.719304 -70.956747) (xy 342.748786 -71.002624) (xy 342.771438 -71.05223)
			(xy 342.786801 -71.104555) (xy 342.794562 -71.158533) (xy 342.794562 -71.213067) (xy 342.786801 -71.267045)
			(xy 342.771438 -71.31937) (xy 342.748786 -71.368976) (xy 342.719304 -71.414853) (xy 342.683594 -71.456069)
			(xy 342.642382 -71.491783) (xy 342.596508 -71.521268) (xy 342.546904 -71.543926) (xy 342.49458 -71.559294)
			(xy 342.440603 -71.567059) (xy 342.413336 -71.567548) (xy 341.549736 -71.567548) (xy 341.522462 -71.567115)
			(xy 341.46847 -71.559357) (xy 341.416131 -71.543993) (xy 341.366511 -71.521337) (xy 341.320621 -71.491849)
			(xy 341.279395 -71.45613) (xy 341.243673 -71.414908) (xy 341.214181 -71.36902) (xy 341.19152 -71.319403)
			(xy 341.176151 -71.267066) (xy 341.168388 -71.213074) (xy 298.511468 -71.213074) (xy 298.511468 -71.844253)
			(xy 346.360454 -71.844253) (xy 346.360454 -71.789747) (xy 346.368211 -71.735796) (xy 346.383567 -71.683499)
			(xy 346.406209 -71.633919) (xy 346.435677 -71.588066) (xy 346.47137 -71.546873) (xy 346.512562 -71.511179)
			(xy 346.558415 -71.481711) (xy 346.607995 -71.459068) (xy 346.660293 -71.443712) (xy 346.714243 -71.435954)
			(xy 346.741496 -71.435468) (xy 347.605096 -71.435468) (xy 347.632347 -71.435979) (xy 347.686295 -71.443735)
			(xy 347.73859 -71.45909) (xy 347.788168 -71.481731) (xy 347.834019 -71.511197) (xy 347.875209 -71.546888)
			(xy 347.910901 -71.588078) (xy 347.940367 -71.633929) (xy 347.963009 -71.683506) (xy 347.978364 -71.735801)
			(xy 347.986121 -71.789749) (xy 347.986121 -71.844251) (xy 347.978364 -71.898199) (xy 347.963009 -71.950494)
			(xy 347.940367 -72.000071) (xy 347.910901 -72.045922) (xy 347.875209 -72.087112) (xy 347.834019 -72.122803)
			(xy 347.788168 -72.152269) (xy 347.73859 -72.17491) (xy 347.686295 -72.190265) (xy 347.632347 -72.198021)
			(xy 347.605096 -72.198484) (xy 346.741496 -72.198484) (xy 346.714243 -72.198046) (xy 346.660293 -72.190288)
			(xy 346.607995 -72.174932) (xy 346.558415 -72.152289) (xy 346.512562 -72.122821) (xy 346.47137 -72.087127)
			(xy 346.435677 -72.045934) (xy 346.406209 -72.000081) (xy 346.383567 -71.950501) (xy 346.368211 -71.898204)
			(xy 346.360454 -71.844253) (xy 298.511468 -71.844253) (xy 298.511468 -72.404055) (xy 332.037847 -72.404055)
			(xy 332.037847 -72.349545) (xy 332.045606 -72.295589) (xy 332.060964 -72.243286) (xy 332.083611 -72.193702)
			(xy 332.113083 -72.147846) (xy 332.148782 -72.106651) (xy 332.189981 -72.070957) (xy 332.235841 -72.041489)
			(xy 332.285427 -72.018849) (xy 332.337732 -72.003496) (xy 332.391689 -71.995744) (xy 332.418944 -71.995284)
			(xy 333.282544 -71.995284) (xy 333.309793 -71.995789) (xy 333.363734 -72.00355) (xy 333.416023 -72.018909)
			(xy 333.465593 -72.041552) (xy 333.511437 -72.071019) (xy 333.552622 -72.10671) (xy 333.588308 -72.147898)
			(xy 333.617769 -72.193745) (xy 333.640407 -72.243318) (xy 333.655759 -72.295609) (xy 333.660251 -72.326853)
			(xy 343.845854 -72.326853) (xy 343.845854 -72.272347) (xy 343.853611 -72.218396) (xy 343.868967 -72.166099)
			(xy 343.891609 -72.116519) (xy 343.921077 -72.070666) (xy 343.95677 -72.029473) (xy 343.997962 -71.993779)
			(xy 344.043815 -71.964311) (xy 344.093395 -71.941668) (xy 344.145693 -71.926312) (xy 344.199643 -71.918554)
			(xy 344.226896 -71.918068) (xy 345.090496 -71.918068) (xy 345.117747 -71.918579) (xy 345.171695 -71.926335)
			(xy 345.22399 -71.94169) (xy 345.273568 -71.964331) (xy 345.319419 -71.993797) (xy 345.360609 -72.029488)
			(xy 345.396301 -72.070678) (xy 345.425767 -72.116529) (xy 345.448409 -72.166106) (xy 345.463764 -72.218401)
			(xy 345.471521 -72.272349) (xy 345.471521 -72.326851) (xy 345.463764 -72.380799) (xy 345.448409 -72.433094)
			(xy 345.425767 -72.482671) (xy 345.396301 -72.528522) (xy 345.360609 -72.569712) (xy 345.319419 -72.605403)
			(xy 345.273568 -72.634869) (xy 345.22399 -72.65751) (xy 345.171695 -72.672865) (xy 345.117747 -72.680621)
			(xy 345.090496 -72.681084) (xy 344.226896 -72.681084) (xy 344.199643 -72.680646) (xy 344.145693 -72.672888)
			(xy 344.093395 -72.657532) (xy 344.043815 -72.634889) (xy 343.997962 -72.605421) (xy 343.95677 -72.569727)
			(xy 343.921077 -72.528534) (xy 343.891609 -72.482681) (xy 343.868967 -72.433101) (xy 343.853611 -72.380804)
			(xy 343.845854 -72.326853) (xy 333.660251 -72.326853) (xy 333.663514 -72.349551) (xy 333.663514 -72.404049)
			(xy 333.655759 -72.457991) (xy 333.640407 -72.510282) (xy 333.617769 -72.559855) (xy 333.588308 -72.605702)
			(xy 333.552622 -72.64689) (xy 333.511437 -72.682581) (xy 333.465593 -72.712048) (xy 333.416023 -72.734691)
			(xy 333.363734 -72.75005) (xy 333.309793 -72.757811) (xy 333.282544 -72.7583) (xy 332.418944 -72.7583)
			(xy 332.391689 -72.757856) (xy 332.337732 -72.750104) (xy 332.285427 -72.734751) (xy 332.235841 -72.712111)
			(xy 332.189981 -72.682643) (xy 332.148782 -72.646949) (xy 332.113083 -72.605754) (xy 332.083611 -72.559898)
			(xy 332.060964 -72.510314) (xy 332.045606 -72.458011) (xy 332.037847 -72.404055) (xy 298.511468 -72.404055)
			(xy 298.511468 -74.617072) (xy 327.277726 -74.617072) (xy 327.281813 -74.561227) (xy 327.293988 -74.506573)
			(xy 327.31399 -74.454274) (xy 327.341395 -74.405445) (xy 327.375617 -74.361126) (xy 327.415927 -74.322262)
			(xy 327.461466 -74.289681) (xy 327.511264 -74.264078) (xy 327.564259 -74.245999) (xy 327.619321 -74.235828)
			(xy 327.675278 -74.233783) (xy 327.730936 -74.239908) (xy 327.785109 -74.25407) (xy 327.836643 -74.27597)
			(xy 327.884439 -74.305139) (xy 327.927478 -74.340957) (xy 327.941626 -74.356747) (xy 330.744122 -74.356747)
			(xy 330.744122 -74.302253) (xy 330.751877 -74.248315) (xy 330.767229 -74.196029) (xy 330.789865 -74.146459)
			(xy 330.819325 -74.100616) (xy 330.855009 -74.059431) (xy 330.89619 -74.023744) (xy 330.942031 -73.99428)
			(xy 330.991599 -73.97164) (xy 331.043883 -73.956284) (xy 331.097821 -73.948524) (xy 331.125068 -73.948036)
			(xy 331.988668 -73.948036) (xy 332.015926 -73.948409) (xy 332.069886 -73.956163) (xy 332.122194 -73.971518)
			(xy 332.171784 -73.994161) (xy 332.217646 -74.023632) (xy 332.258848 -74.05933) (xy 332.294549 -74.100528)
			(xy 332.324023 -74.146388) (xy 332.346671 -74.195976) (xy 332.36203 -74.248283) (xy 332.369789 -74.302243)
			(xy 332.369789 -74.356757) (xy 332.36203 -74.410717) (xy 332.346671 -74.463024) (xy 332.324023 -74.512612)
			(xy 332.294549 -74.558472) (xy 332.26684 -74.590448) (xy 336.274202 -74.590448) (xy 336.274202 -74.535953)
			(xy 336.281957 -74.482012) (xy 336.297309 -74.429724) (xy 336.319945 -74.380153) (xy 336.349406 -74.334308)
			(xy 336.38509 -74.293121) (xy 336.426272 -74.257432) (xy 336.472114 -74.227966) (xy 336.521683 -74.205324)
			(xy 336.573969 -74.189966) (xy 336.627909 -74.182205) (xy 336.655156 -74.181716) (xy 337.518756 -74.181716)
			(xy 337.546013 -74.182128) (xy 337.599972 -74.18988) (xy 337.652278 -74.205233) (xy 337.701867 -74.227875)
			(xy 337.747729 -74.257344) (xy 337.788929 -74.29304) (xy 337.82463 -74.334236) (xy 337.854104 -74.380094)
			(xy 337.876751 -74.42968) (xy 337.89211 -74.481985) (xy 337.899869 -74.535943) (xy 337.899869 -74.55185)
			(xy 339.156294 -74.55185) (xy 339.156294 -74.49735) (xy 339.16405 -74.443405) (xy 339.179404 -74.391113)
			(xy 339.202044 -74.341539) (xy 339.231509 -74.29569) (xy 339.267198 -74.254502) (xy 339.308386 -74.218812)
			(xy 339.354233 -74.189347) (xy 339.403808 -74.166707) (xy 339.456099 -74.151352) (xy 339.510044 -74.143595)
			(xy 339.537294 -74.143108) (xy 340.400894 -74.143108) (xy 340.428148 -74.143538) (xy 340.482102 -74.151295)
			(xy 340.534403 -74.166651) (xy 340.583986 -74.189294) (xy 340.629842 -74.218763) (xy 340.671037 -74.254459)
			(xy 340.706733 -74.295653) (xy 340.736203 -74.341509) (xy 340.758847 -74.391091) (xy 340.774204 -74.443392)
			(xy 340.781961 -74.497346) (xy 340.781961 -74.551854) (xy 340.774204 -74.605808) (xy 340.758847 -74.658109)
			(xy 340.736203 -74.707691) (xy 340.706733 -74.753547) (xy 340.694254 -74.767948) (xy 421.29456 -74.767948)
			(xy 421.29456 -66.06794) (xy 421.295065 -65.962416) (xy 421.303149 -65.751522) (xy 421.319305 -65.541093)
			(xy 421.343508 -65.331436) (xy 421.375725 -65.122861) (xy 421.415907 -64.915673) (xy 421.463995 -64.710176)
			(xy 421.519919 -64.506672) (xy 421.583596 -64.305459) (xy 421.654934 -64.106832) (xy 421.733828 -63.911084)
			(xy 421.820161 -63.718502) (xy 421.913808 -63.529367) (xy 422.01463 -63.343958) (xy 422.12248 -63.162547)
			(xy 422.237199 -62.9854) (xy 422.358619 -62.812778) (xy 422.486562 -62.644932) (xy 422.62084 -62.48211)
			(xy 422.761256 -62.324551) (xy 422.907604 -62.172486) (xy 423.059669 -62.026138) (xy 423.217228 -61.885722)
			(xy 423.38005 -61.751444) (xy 423.547896 -61.623501) (xy 423.720518 -61.502081) (xy 423.897665 -61.387362)
			(xy 424.079076 -61.279512) (xy 424.264485 -61.17869) (xy 424.45362 -61.085043) (xy 424.646202 -60.99871)
			(xy 424.84195 -60.919816) (xy 425.040577 -60.848478) (xy 425.24179 -60.784801) (xy 425.445294 -60.728877)
			(xy 425.650791 -60.680789) (xy 425.857979 -60.640607) (xy 426.066554 -60.60839) (xy 426.276211 -60.584187)
			(xy 426.48664 -60.568031) (xy 426.697534 -60.559947) (xy 426.908582 -60.559947) (xy 427.119476 -60.568031)
			(xy 427.329905 -60.584187) (xy 427.539562 -60.60839) (xy 427.748137 -60.640607) (xy 427.955325 -60.680789)
			(xy 428.160822 -60.728877) (xy 428.364326 -60.784801) (xy 428.565539 -60.848478) (xy 428.764166 -60.919816)
			(xy 428.959914 -60.99871) (xy 429.152496 -61.085043) (xy 429.341631 -61.17869) (xy 429.52704 -61.279512)
			(xy 429.708451 -61.387362) (xy 429.885598 -61.502081) (xy 430.05822 -61.623501) (xy 430.226066 -61.751444)
			(xy 430.388888 -61.885722) (xy 430.546447 -62.026138) (xy 430.698512 -62.172486) (xy 430.84486 -62.324551)
			(xy 430.985276 -62.48211) (xy 431.119554 -62.644932) (xy 431.247497 -62.812778) (xy 431.368917 -62.9854)
			(xy 431.483636 -63.162547) (xy 431.591486 -63.343958) (xy 431.692308 -63.529367) (xy 431.785955 -63.718502)
			(xy 431.872288 -63.911084) (xy 431.951182 -64.106832) (xy 432.02252 -64.305459) (xy 432.086197 -64.506672)
			(xy 432.142121 -64.710176) (xy 432.190209 -64.915673) (xy 432.230391 -65.122861) (xy 432.262608 -65.331436)
			(xy 432.286811 -65.541093) (xy 432.302967 -65.751522) (xy 432.311051 -65.962416) (xy 432.311556 -66.06794)
			(xy 432.311556 -74.767948) (xy 432.311051 -74.873472) (xy 432.302967 -75.084366) (xy 432.286811 -75.294795)
			(xy 432.262608 -75.504452) (xy 432.230391 -75.713027) (xy 432.190209 -75.920215) (xy 432.142121 -76.125712)
			(xy 432.086197 -76.329216) (xy 432.02252 -76.530429) (xy 431.951182 -76.729056) (xy 431.872288 -76.924804)
			(xy 431.785955 -77.117386) (xy 431.692308 -77.306521) (xy 431.591486 -77.49193) (xy 431.483636 -77.673341)
			(xy 431.368917 -77.850488) (xy 431.247497 -78.02311) (xy 431.119554 -78.190956) (xy 430.985276 -78.353778)
			(xy 430.84486 -78.511337) (xy 430.698512 -78.663402) (xy 430.546447 -78.80975) (xy 430.388888 -78.950166)
			(xy 430.226066 -79.084444) (xy 430.05822 -79.212387) (xy 429.885598 -79.333807) (xy 429.708451 -79.448526)
			(xy 429.52704 -79.556376) (xy 429.341631 -79.657198) (xy 429.152496 -79.750845) (xy 428.959914 -79.837178)
			(xy 428.764166 -79.916072) (xy 428.565539 -79.98741) (xy 428.364326 -80.051087) (xy 428.160822 -80.107011)
			(xy 427.955325 -80.155099) (xy 427.748137 -80.195281) (xy 427.539562 -80.227498) (xy 427.329905 -80.251701)
			(xy 427.119476 -80.267857) (xy 426.908582 -80.275941) (xy 426.697534 -80.275941) (xy 426.48664 -80.267857)
			(xy 426.276211 -80.251701) (xy 426.066554 -80.227498) (xy 425.857979 -80.195281) (xy 425.650791 -80.155099)
			(xy 425.445294 -80.107011) (xy 425.24179 -80.051087) (xy 425.040577 -79.98741) (xy 424.84195 -79.916072)
			(xy 424.646202 -79.837178) (xy 424.45362 -79.750845) (xy 424.264485 -79.657198) (xy 424.079076 -79.556376)
			(xy 423.897665 -79.448526) (xy 423.720518 -79.333807) (xy 423.547896 -79.212387) (xy 423.38005 -79.084444)
			(xy 423.217228 -78.950166) (xy 423.059669 -78.80975) (xy 422.907604 -78.663402) (xy 422.761256 -78.511337)
			(xy 422.62084 -78.353778) (xy 422.486562 -78.190956) (xy 422.358619 -78.02311) (xy 422.237199 -77.850488)
			(xy 422.12248 -77.673341) (xy 422.01463 -77.49193) (xy 421.913808 -77.306521) (xy 421.820161 -77.117386)
			(xy 421.733828 -76.924804) (xy 421.654934 -76.729056) (xy 421.583596 -76.530429) (xy 421.519919 -76.329216)
			(xy 421.463995 -76.125712) (xy 421.415907 -75.920215) (xy 421.375725 -75.713027) (xy 421.343508 -75.504452)
			(xy 421.319305 -75.294795) (xy 421.303149 -75.084366) (xy 421.295065 -74.873472) (xy 421.29456 -74.767948)
			(xy 340.694254 -74.767948) (xy 340.671037 -74.794741) (xy 340.629842 -74.830437) (xy 340.583986 -74.859906)
			(xy 340.534403 -74.882549) (xy 340.482102 -74.897905) (xy 340.428148 -74.905662) (xy 340.400894 -74.906124)
			(xy 339.537294 -74.906124) (xy 339.510044 -74.905605) (xy 339.456099 -74.897848) (xy 339.403808 -74.882493)
			(xy 339.354233 -74.859853) (xy 339.308386 -74.830388) (xy 339.267198 -74.794698) (xy 339.231509 -74.75351)
			(xy 339.202044 -74.707661) (xy 339.179404 -74.658087) (xy 339.16405 -74.605795) (xy 339.156294 -74.55185)
			(xy 337.899869 -74.55185) (xy 337.899869 -74.590457) (xy 337.89211 -74.644415) (xy 337.876751 -74.69672)
			(xy 337.854104 -74.746306) (xy 337.82463 -74.792164) (xy 337.788929 -74.83336) (xy 337.747729 -74.869056)
			(xy 337.701867 -74.898525) (xy 337.652278 -74.921167) (xy 337.599972 -74.93652) (xy 337.546013 -74.944272)
			(xy 337.518756 -74.944732) (xy 336.655156 -74.944732) (xy 336.627909 -74.944195) (xy 336.573969 -74.936434)
			(xy 336.521683 -74.921076) (xy 336.472114 -74.898434) (xy 336.426272 -74.868968) (xy 336.38509 -74.833279)
			(xy 336.349406 -74.792092) (xy 336.319945 -74.746247) (xy 336.297309 -74.696676) (xy 336.281957 -74.644388)
			(xy 336.274202 -74.590448) (xy 332.26684 -74.590448) (xy 332.258848 -74.59967) (xy 332.217646 -74.635368)
			(xy 332.171784 -74.664839) (xy 332.122194 -74.687482) (xy 332.069886 -74.702837) (xy 332.015926 -74.710591)
			(xy 331.988668 -74.711052) (xy 331.125068 -74.711052) (xy 331.097821 -74.710476) (xy 331.043883 -74.702716)
			(xy 330.991599 -74.68736) (xy 330.942031 -74.66472) (xy 330.89619 -74.635256) (xy 330.855009 -74.599569)
			(xy 330.819325 -74.558384) (xy 330.789865 -74.512541) (xy 330.767229 -74.462971) (xy 330.751877 -74.410685)
			(xy 330.744122 -74.356747) (xy 327.941626 -74.356747) (xy 327.964844 -74.38266) (xy 327.99574 -74.429358)
			(xy 328.019507 -74.480058) (xy 328.035639 -74.533678) (xy 328.043791 -74.589075) (xy 328.044302 -74.617072)
			(xy 328.043791 -74.645069) (xy 328.035639 -74.700466) (xy 328.019507 -74.754086) (xy 327.99574 -74.804786)
			(xy 327.964844 -74.851484) (xy 327.927478 -74.893187) (xy 327.884439 -74.929005) (xy 327.836643 -74.958174)
			(xy 327.785109 -74.980074) (xy 327.730936 -74.994236) (xy 327.675278 -75.000361) (xy 327.619321 -74.998316)
			(xy 327.564259 -74.988145) (xy 327.511264 -74.970066) (xy 327.461466 -74.944463) (xy 327.415927 -74.911882)
			(xy 327.375617 -74.873018) (xy 327.341395 -74.828699) (xy 327.31399 -74.77987) (xy 327.293988 -74.727571)
			(xy 327.281813 -74.672917) (xy 327.277726 -74.617072) (xy 298.511468 -74.617072) (xy 298.511468 -74.760836)
			(xy 298.510963 -74.86636) (xy 298.502879 -75.077254) (xy 298.486723 -75.287683) (xy 298.46252 -75.49734)
			(xy 298.430303 -75.705915) (xy 298.390121 -75.913103) (xy 298.342033 -76.1186) (xy 298.333664 -76.149054)
			(xy 327.558346 -76.149054) (xy 327.558346 -76.094546) (xy 327.566103 -76.040594) (xy 327.581459 -75.988295)
			(xy 327.604102 -75.938714) (xy 327.633571 -75.892859) (xy 327.669266 -75.851666) (xy 327.710459 -75.815971)
			(xy 327.756314 -75.786502) (xy 327.805895 -75.763859) (xy 327.858194 -75.748503) (xy 327.912146 -75.740746)
			(xy 327.9394 -75.74026) (xy 328.803 -75.74026) (xy 328.830249 -75.74081) (xy 328.884192 -75.748566)
			(xy 328.936482 -75.76392) (xy 328.986055 -75.786559) (xy 329.031902 -75.816023) (xy 329.073089 -75.851711)
			(xy 329.108777 -75.892898) (xy 329.138241 -75.938745) (xy 329.16088 -75.988318) (xy 329.169581 -76.017949)
			(xy 334.874382 -76.017949) (xy 334.874382 -75.963451) (xy 334.882137 -75.909507) (xy 334.89749 -75.857216)
			(xy 334.920128 -75.807642) (xy 334.949591 -75.761793) (xy 334.985278 -75.720605) (xy 335.026463 -75.684914)
			(xy 335.072308 -75.655447) (xy 335.12188 -75.632803) (xy 335.17417 -75.617445) (xy 335.228113 -75.609684)
			(xy 335.255362 -75.609196) (xy 336.118962 -75.609196) (xy 336.146217 -75.609649) (xy 336.200173 -75.617401)
			(xy 336.252475 -75.632754) (xy 336.302061 -75.655395) (xy 336.347919 -75.684862) (xy 336.389117 -75.720556)
			(xy 336.424815 -75.76175) (xy 336.454287 -75.807606) (xy 336.476932 -75.857189) (xy 336.49229 -75.90949)
			(xy 336.500049 -75.963445) (xy 336.500049 -76.017955) (xy 336.49229 -76.07191) (xy 336.476932 -76.124211)
			(xy 336.454287 -76.173794) (xy 336.424815 -76.21965) (xy 336.389117 -76.260844) (xy 336.347919 -76.296538)
			(xy 336.302061 -76.326005) (xy 336.252475 -76.348646) (xy 336.200173 -76.363999) (xy 336.146217 -76.371751)
			(xy 336.118962 -76.372212) (xy 335.255362 -76.372212) (xy 335.228113 -76.371716) (xy 335.17417 -76.363955)
			(xy 335.12188 -76.348597) (xy 335.072308 -76.325953) (xy 335.026463 -76.296486) (xy 334.985278 -76.260795)
			(xy 334.949591 -76.219607) (xy 334.920128 -76.173758) (xy 334.89749 -76.124184) (xy 334.882137 -76.071893)
			(xy 334.874382 -76.017949) (xy 329.169581 -76.017949) (xy 329.176234 -76.040608) (xy 329.18399 -76.094551)
			(xy 329.18399 -76.149049) (xy 329.176234 -76.202992) (xy 329.16088 -76.255282) (xy 329.138241 -76.304855)
			(xy 329.108777 -76.350702) (xy 329.073089 -76.391889) (xy 329.031902 -76.427577) (xy 328.986055 -76.457041)
			(xy 328.936482 -76.47968) (xy 328.884192 -76.495034) (xy 328.830249 -76.50279) (xy 328.803 -76.503276)
			(xy 327.9394 -76.503276) (xy 327.912146 -76.502854) (xy 327.858194 -76.495097) (xy 327.805895 -76.479741)
			(xy 327.756314 -76.457098) (xy 327.710459 -76.427629) (xy 327.669266 -76.391934) (xy 327.633571 -76.350741)
			(xy 327.604102 -76.304886) (xy 327.581459 -76.255305) (xy 327.566103 -76.203006) (xy 327.558346 -76.149054)
			(xy 298.333664 -76.149054) (xy 298.286109 -76.322104) (xy 298.222432 -76.523317) (xy 298.151094 -76.721944)
			(xy 298.0722 -76.917692) (xy 297.985867 -77.110274) (xy 297.89222 -77.299409) (xy 297.791398 -77.484818)
			(xy 297.683548 -77.666229) (xy 297.568829 -77.843376) (xy 297.455321 -78.00475) (xy 330.84567 -78.00475)
			(xy 330.84567 -77.95025) (xy 330.853426 -77.896304) (xy 330.868779 -77.84401) (xy 330.891419 -77.794434)
			(xy 330.920883 -77.748584) (xy 330.956571 -77.707394) (xy 330.997759 -77.671702) (xy 331.043606 -77.642234)
			(xy 331.09318 -77.619591) (xy 331.145472 -77.604232) (xy 331.199418 -77.596472) (xy 331.226668 -77.595984)
			(xy 332.090268 -77.595984) (xy 332.117522 -77.596461) (xy 332.171475 -77.604214) (xy 332.223776 -77.619567)
			(xy 332.273359 -77.642207) (xy 332.319215 -77.671674) (xy 332.360411 -77.707367) (xy 332.396107 -77.748559)
			(xy 332.425577 -77.794413) (xy 332.448222 -77.843994) (xy 332.463579 -77.896294) (xy 332.471337 -77.950246)
			(xy 332.471337 -78.004754) (xy 332.463579 -78.058706) (xy 332.448222 -78.111006) (xy 332.425577 -78.160587)
			(xy 332.396107 -78.206441) (xy 332.360411 -78.247633) (xy 332.319215 -78.283326) (xy 332.273359 -78.312793)
			(xy 332.223776 -78.335433) (xy 332.171475 -78.350786) (xy 332.117522 -78.358539) (xy 332.090268 -78.359)
			(xy 331.226668 -78.359) (xy 331.199418 -78.358528) (xy 331.145472 -78.350768) (xy 331.09318 -78.335409)
			(xy 331.043606 -78.312766) (xy 330.997759 -78.283298) (xy 330.956571 -78.247606) (xy 330.920883 -78.206416)
			(xy 330.891419 -78.160566) (xy 330.868779 -78.11099) (xy 330.853426 -78.058696) (xy 330.84567 -78.00475)
			(xy 297.455321 -78.00475) (xy 297.447409 -78.015998) (xy 297.319466 -78.183844) (xy 297.185188 -78.346666)
			(xy 297.044772 -78.504225) (xy 296.898424 -78.65629) (xy 296.746359 -78.802638) (xy 296.5888 -78.943054)
			(xy 296.425978 -79.077332) (xy 296.258132 -79.205275) (xy 296.08551 -79.326695) (xy 295.908363 -79.441414)
			(xy 295.726952 -79.549264) (xy 295.541543 -79.650086) (xy 295.352408 -79.743733) (xy 295.159826 -79.830066)
			(xy 294.964078 -79.90896) (xy 294.765451 -79.980298) (xy 294.564238 -80.043975) (xy 294.360734 -80.099899)
			(xy 294.155237 -80.147987) (xy 293.948049 -80.188169) (xy 293.739474 -80.220386) (xy 293.529817 -80.244589)
			(xy 293.319388 -80.260745) (xy 293.108494 -80.268829) (xy 292.897446 -80.268829) (xy 292.686552 -80.260745)
			(xy 292.476123 -80.244589) (xy 292.266466 -80.220386) (xy 292.057891 -80.188169) (xy 291.850703 -80.147987)
			(xy 291.645206 -80.099899) (xy 291.441702 -80.043975) (xy 291.240489 -79.980298) (xy 291.041862 -79.90896)
			(xy 290.846114 -79.830066) (xy 290.653532 -79.743733) (xy 290.464397 -79.650086) (xy 290.278988 -79.549264)
			(xy 290.097577 -79.441414) (xy 289.92043 -79.326695) (xy 289.747808 -79.205275) (xy 289.579962 -79.077332)
			(xy 289.41714 -78.943054) (xy 289.259581 -78.802638) (xy 289.107516 -78.65629) (xy 288.961168 -78.504225)
			(xy 288.820752 -78.346666) (xy 288.686474 -78.183844) (xy 288.558531 -78.015998) (xy 288.437111 -77.843376)
			(xy 288.322392 -77.666229) (xy 288.214542 -77.484818) (xy 288.11372 -77.299409) (xy 288.020073 -77.110274)
			(xy 287.93374 -76.917692) (xy 287.854846 -76.721944) (xy 287.783508 -76.523317) (xy 287.719831 -76.322104)
			(xy 287.663907 -76.1186) (xy 287.615819 -75.913103) (xy 287.575637 -75.705915) (xy 287.54342 -75.49734)
			(xy 287.519217 -75.287683) (xy 287.503061 -75.077254) (xy 287.494977 -74.86636) (xy 287.494472 -74.760836)
			(xy 184.371488 -74.760836) (xy 184.371488 -74.767948) (xy 184.370983 -74.873472) (xy 184.362899 -75.084366)
			(xy 184.346743 -75.294795) (xy 184.32254 -75.504452) (xy 184.290323 -75.713027) (xy 184.250141 -75.920215)
			(xy 184.202053 -76.125712) (xy 184.146129 -76.329216) (xy 184.082452 -76.530429) (xy 184.011114 -76.729056)
			(xy 183.93222 -76.924804) (xy 183.845887 -77.117386) (xy 183.75224 -77.306521) (xy 183.651418 -77.49193)
			(xy 183.543568 -77.673341) (xy 183.428849 -77.850488) (xy 183.307429 -78.02311) (xy 183.179486 -78.190956)
			(xy 183.045208 -78.353778) (xy 182.904792 -78.511337) (xy 182.758444 -78.663402) (xy 182.606379 -78.80975)
			(xy 182.44882 -78.950166) (xy 182.285998 -79.084444) (xy 182.118152 -79.212387) (xy 181.94553 -79.333807)
			(xy 181.768383 -79.448526) (xy 181.586972 -79.556376) (xy 181.401563 -79.657198) (xy 181.212428 -79.750845)
			(xy 181.019846 -79.837178) (xy 180.824098 -79.916072) (xy 180.625471 -79.98741) (xy 180.424258 -80.051087)
			(xy 180.220754 -80.107011) (xy 180.015257 -80.155099) (xy 179.808069 -80.195281) (xy 179.599494 -80.227498)
			(xy 179.389837 -80.251701) (xy 179.179408 -80.267857) (xy 178.968514 -80.275941) (xy 178.757466 -80.275941)
			(xy 178.546572 -80.267857) (xy 178.336143 -80.251701) (xy 178.126486 -80.227498) (xy 177.917911 -80.195281)
			(xy 177.710723 -80.155099) (xy 177.505226 -80.107011) (xy 177.301722 -80.051087) (xy 177.100509 -79.98741)
			(xy 176.901882 -79.916072) (xy 176.706134 -79.837178) (xy 176.513552 -79.750845) (xy 176.324417 -79.657198)
			(xy 176.139008 -79.556376) (xy 175.957597 -79.448526) (xy 175.78045 -79.333807) (xy 175.607828 -79.212387)
			(xy 175.439982 -79.084444) (xy 175.27716 -78.950166) (xy 175.119601 -78.80975) (xy 174.967536 -78.663402)
			(xy 174.821188 -78.511337) (xy 174.680772 -78.353778) (xy 174.546494 -78.190956) (xy 174.418551 -78.02311)
			(xy 174.297131 -77.850488) (xy 174.182412 -77.673341) (xy 174.074562 -77.49193) (xy 173.97374 -77.306521)
			(xy 173.880093 -77.117386) (xy 173.79376 -76.924804) (xy 173.714866 -76.729056) (xy 173.643528 -76.530429)
			(xy 173.579851 -76.329216) (xy 173.523927 -76.125712) (xy 173.475839 -75.920215) (xy 173.435657 -75.713027)
			(xy 173.40344 -75.504452) (xy 173.379237 -75.294795) (xy 173.363081 -75.084366) (xy 173.354997 -74.873472)
			(xy 173.354492 -74.767948) (xy 50.571366 -74.767948) (xy 50.570895 -74.86636) (xy 50.562811 -75.077254)
			(xy 50.546655 -75.287683) (xy 50.522452 -75.49734) (xy 50.490235 -75.705915) (xy 50.450053 -75.913103)
			(xy 50.401965 -76.1186) (xy 50.346041 -76.322104) (xy 50.282364 -76.523317) (xy 50.211026 -76.721944)
			(xy 50.132132 -76.917692) (xy 50.045799 -77.110274) (xy 49.952152 -77.299409) (xy 49.85133 -77.484818)
			(xy 49.74348 -77.666229) (xy 49.628761 -77.843376) (xy 49.507341 -78.015998) (xy 49.379398 -78.183844)
			(xy 49.24512 -78.346666) (xy 49.104704 -78.504225) (xy 48.958356 -78.65629) (xy 48.806291 -78.802638)
			(xy 48.648732 -78.943054) (xy 48.48591 -79.077332) (xy 48.318064 -79.205275) (xy 48.145442 -79.326695)
			(xy 47.968295 -79.441414) (xy 47.786884 -79.549264) (xy 47.601475 -79.650086) (xy 47.41234 -79.743733)
			(xy 47.219758 -79.830066) (xy 47.02401 -79.90896) (xy 46.825383 -79.980298) (xy 46.62417 -80.043975)
			(xy 46.420666 -80.099899) (xy 46.215169 -80.147987) (xy 46.007981 -80.188169) (xy 45.799406 -80.220386)
			(xy 45.589749 -80.244589) (xy 45.37932 -80.260745) (xy 45.168426 -80.268829) (xy 44.957378 -80.268829)
			(xy 44.746484 -80.260745) (xy 44.536055 -80.244589) (xy 44.326398 -80.220386) (xy 44.117823 -80.188169)
			(xy 43.910635 -80.147987) (xy 43.705138 -80.099899) (xy 43.501634 -80.043975) (xy 43.300421 -79.980298)
			(xy 43.101794 -79.90896) (xy 42.906046 -79.830066) (xy 42.713464 -79.743733) (xy 42.524329 -79.650086)
			(xy 42.33892 -79.549264) (xy 42.157509 -79.441414) (xy 41.980362 -79.326695) (xy 41.80774 -79.205275)
			(xy 41.639894 -79.077332) (xy 41.477072 -78.943054) (xy 41.319513 -78.802638) (xy 41.167448 -78.65629)
			(xy 41.0211 -78.504225) (xy 40.880684 -78.346666) (xy 40.746406 -78.183844) (xy 40.618463 -78.015998)
			(xy 40.497043 -77.843376) (xy 40.382324 -77.666229) (xy 40.274474 -77.484818) (xy 40.173652 -77.299409)
			(xy 40.080005 -77.110274) (xy 39.993672 -76.917692) (xy 39.914778 -76.721944) (xy 39.84344 -76.523317)
			(xy 39.779763 -76.322104) (xy 39.723839 -76.1186) (xy 39.675751 -75.913103) (xy 39.635569 -75.705915)
			(xy 39.603352 -75.49734) (xy 39.579149 -75.287683) (xy 39.562993 -75.077254) (xy 39.554909 -74.86636)
			(xy 39.554404 -74.760836) (xy 0.509016 -74.760836) (xy 0.509016 -77.671676) (xy 0.509504 -77.724899)
			(xy 0.51712 -77.831071) (xy 0.532286 -77.93643) (xy 0.554925 -78.04044) (xy 0.584921 -78.142572)
			(xy 0.622123 -78.242305) (xy 0.666339 -78.339132) (xy 0.717347 -78.43256) (xy 0.774885 -78.522114)
			(xy 0.838661 -78.607338) (xy 0.908351 -78.687799) (xy 0.945642 -78.725776) (xy 1.77419 -79.554324)
			(xy 1.823602 -79.604436) (xy 1.917388 -79.709385) (xy 2.005143 -79.819428) (xy 2.08659 -79.934217)
			(xy 2.161473 -80.053392) (xy 2.229556 -80.176578) (xy 2.290626 -80.303388) (xy 2.344491 -80.433422)
			(xy 2.39098 -80.566271) (xy 2.429948 -80.701518) (xy 2.461272 -80.838737) (xy 2.484853 -80.977496)
			(xy 2.500618 -81.117359) (xy 2.508516 -81.257886) (xy 2.509012 -81.32826) (xy 2.509012 -81.69181)
			(xy 232.140667 -81.69181) (xy 232.145062 -81.517977) (xy 232.15749 -81.344533) (xy 232.177927 -81.171849)
			(xy 232.206328 -81.000295) (xy 232.242632 -80.830238) (xy 232.286762 -80.662042) (xy 232.338623 -80.496067)
			(xy 232.398104 -80.332668) (xy 232.465078 -80.172194) (xy 232.539402 -80.01499) (xy 232.620917 -79.86139)
			(xy 232.709448 -79.711725) (xy 232.804805 -79.566315) (xy 232.906785 -79.425469) (xy 233.01517 -79.289491)
			(xy 233.129727 -79.158671) (xy 233.250212 -79.033288) (xy 233.376366 -78.913612) (xy 233.50792 -78.799897)
			(xy 233.644592 -78.692389) (xy 233.715052 -78.641448) (xy 238.08436 -78.641448) (xy 238.15482 -78.692389)
			(xy 238.291492 -78.799897) (xy 238.423046 -78.913612) (xy 238.5492 -79.033288) (xy 238.669685 -79.158671)
			(xy 238.784242 -79.289491) (xy 238.892627 -79.425469) (xy 238.994607 -79.566315) (xy 239.089964 -79.711725)
			(xy 239.178495 -79.86139) (xy 239.26001 -80.01499) (xy 239.334334 -80.172194) (xy 239.401308 -80.332668)
			(xy 239.460789 -80.496067) (xy 239.51265 -80.662042) (xy 239.553507 -80.817765) (xy 333.938166 -80.817765)
			(xy 333.938166 -80.763235) (xy 333.945926 -80.70926) (xy 333.961289 -80.656938) (xy 333.98394 -80.607335)
			(xy 334.01342 -80.561461) (xy 334.049129 -80.520248) (xy 334.090338 -80.484537) (xy 334.136211 -80.455054)
			(xy 334.185812 -80.432398) (xy 334.238132 -80.417032) (xy 334.292107 -80.409268) (xy 334.319372 -80.40878)
			(xy 335.182972 -80.40878) (xy 335.210247 -80.409158) (xy 335.264243 -80.416917) (xy 335.316585 -80.432283)
			(xy 335.366207 -80.454941) (xy 335.412099 -80.484432) (xy 335.453327 -80.520153) (xy 335.489052 -80.561378)
			(xy 335.518545 -80.607268) (xy 335.541207 -80.656889) (xy 335.556577 -80.709229) (xy 335.56434 -80.763225)
			(xy 335.56434 -80.817775) (xy 335.556577 -80.871771) (xy 335.541207 -80.924111) (xy 335.518545 -80.973732)
			(xy 335.489052 -81.019622) (xy 335.453327 -81.060847) (xy 335.412099 -81.096568) (xy 335.366207 -81.126059)
			(xy 335.316585 -81.148717) (xy 335.264243 -81.164083) (xy 335.210247 -81.171842) (xy 335.182972 -81.172304)
			(xy 334.319372 -81.172304) (xy 334.292107 -81.171732) (xy 334.238132 -81.163968) (xy 334.185812 -81.148602)
			(xy 334.136211 -81.125946) (xy 334.090338 -81.096463) (xy 334.049129 -81.060752) (xy 334.01342 -81.019539)
			(xy 333.98394 -80.973665) (xy 333.961289 -80.924062) (xy 333.945926 -80.87174) (xy 333.938166 -80.817765)
			(xy 239.553507 -80.817765) (xy 239.55678 -80.830238) (xy 239.593084 -81.000295) (xy 239.621485 -81.171849)
			(xy 239.641922 -81.344533) (xy 239.65435 -81.517977) (xy 239.658745 -81.69181) (xy 239.655095 -81.865661)
			(xy 239.643409 -82.039157) (xy 239.640092 -82.06825) (xy 331.768962 -82.06825) (xy 331.768962 -82.01375)
			(xy 331.776717 -81.959803) (xy 331.792071 -81.90751) (xy 331.81471 -81.857933) (xy 331.844174 -81.812083)
			(xy 331.879862 -81.770892) (xy 331.921049 -81.735199) (xy 331.966896 -81.70573) (xy 332.01647 -81.683086)
			(xy 332.068762 -81.667726) (xy 332.122708 -81.659965) (xy 332.149958 -81.659476) (xy 333.013558 -81.659476)
			(xy 333.040812 -81.659968) (xy 333.094765 -81.66772) (xy 333.147066 -81.683072) (xy 333.196649 -81.705711)
			(xy 333.242505 -81.735177) (xy 333.283701 -81.770869) (xy 333.319398 -81.812061) (xy 333.348869 -81.857914)
			(xy 333.371513 -81.907495) (xy 333.386871 -81.959794) (xy 333.394629 -82.013746) (xy 333.394629 -82.068254)
			(xy 333.386871 -82.122206) (xy 333.371513 -82.174505) (xy 333.348869 -82.224086) (xy 333.319398 -82.269939)
			(xy 333.294774 -82.298353) (xy 336.189263 -82.298353) (xy 336.189263 -82.243847) (xy 336.197021 -82.189895)
			(xy 336.212377 -82.137597) (xy 336.235021 -82.088017) (xy 336.26449 -82.042163) (xy 336.300185 -82.000971)
			(xy 336.341379 -81.965278) (xy 336.387234 -81.935811) (xy 336.436816 -81.91317) (xy 336.489115 -81.897816)
			(xy 336.543067 -81.890062) (xy 336.57032 -81.8896) (xy 337.43392 -81.8896) (xy 337.461171 -81.890071)
			(xy 337.515118 -81.89783) (xy 337.567411 -81.913187) (xy 337.616987 -81.93583) (xy 337.662836 -81.965298)
			(xy 337.692804 -81.991267) (xy 339.478646 -81.991267) (xy 339.478646 -81.936733) (xy 339.486407 -81.882755)
			(xy 339.50177 -81.830431) (xy 339.524423 -81.780825) (xy 339.553905 -81.734948) (xy 339.589615 -81.693734)
			(xy 339.630827 -81.65802) (xy 339.676702 -81.628535) (xy 339.726306 -81.605879) (xy 339.77863 -81.590512)
			(xy 339.832607 -81.582748) (xy 339.859874 -81.58226) (xy 340.723474 -81.58226) (xy 340.750748 -81.582678)
			(xy 340.804741 -81.590437) (xy 340.857079 -81.605802) (xy 340.906699 -81.62846) (xy 340.952588 -81.657948)
			(xy 340.993814 -81.693668) (xy 341.029536 -81.734891) (xy 341.059028 -81.780778) (xy 341.081689 -81.830396)
			(xy 341.097057 -81.882734) (xy 341.10482 -81.936726) (xy 341.10482 -81.991274) (xy 341.097057 -82.045266)
			(xy 341.081689 -82.097604) (xy 341.059028 -82.147222) (xy 341.029536 -82.193109) (xy 340.993814 -82.234332)
			(xy 340.952588 -82.270052) (xy 340.906699 -82.29954) (xy 340.857079 -82.322198) (xy 340.804741 -82.337563)
			(xy 340.750748 -82.345322) (xy 340.723474 -82.345784) (xy 339.859874 -82.345784) (xy 339.832607 -82.345252)
			(xy 339.77863 -82.337488) (xy 339.726306 -82.322121) (xy 339.676702 -82.299465) (xy 339.630827 -82.26998)
			(xy 339.589615 -82.234266) (xy 339.553905 -82.193052) (xy 339.524423 -82.147175) (xy 339.50177 -82.097569)
			(xy 339.486407 -82.045245) (xy 339.478646 -81.991267) (xy 337.692804 -81.991267) (xy 337.704024 -82.00099)
			(xy 337.739714 -82.04218) (xy 337.76918 -82.088031) (xy 337.79182 -82.137608) (xy 337.807174 -82.189902)
			(xy 337.81493 -82.243849) (xy 337.81493 -82.298351) (xy 337.807174 -82.352298) (xy 337.79182 -82.404592)
			(xy 337.769179 -82.454169) (xy 337.739714 -82.50002) (xy 337.704024 -82.54121) (xy 337.662836 -82.576902)
			(xy 337.616987 -82.60637) (xy 337.567411 -82.629013) (xy 337.515118 -82.64437) (xy 337.461171 -82.652129)
			(xy 337.43392 -82.652616) (xy 336.57032 -82.652616) (xy 336.543067 -82.652138) (xy 336.489115 -82.644384)
			(xy 336.436816 -82.62903) (xy 336.387234 -82.606389) (xy 336.341379 -82.576922) (xy 336.300185 -82.541229)
			(xy 336.26449 -82.500037) (xy 336.235021 -82.454183) (xy 336.212377 -82.404603) (xy 336.197021 -82.352305)
			(xy 336.189263 -82.298353) (xy 333.294774 -82.298353) (xy 333.283701 -82.311131) (xy 333.242505 -82.346823)
			(xy 333.196649 -82.376289) (xy 333.147066 -82.398928) (xy 333.094765 -82.41428) (xy 333.040812 -82.422032)
			(xy 333.013558 -82.422492) (xy 332.149958 -82.422492) (xy 332.122708 -82.422035) (xy 332.068762 -82.414274)
			(xy 332.01647 -82.398914) (xy 331.966896 -82.37627) (xy 331.921049 -82.346801) (xy 331.879862 -82.311108)
			(xy 331.844174 -82.269917) (xy 331.81471 -82.224067) (xy 331.792071 -82.17449) (xy 331.776717 -82.122197)
			(xy 331.768962 -82.06825) (xy 239.640092 -82.06825) (xy 239.623713 -82.211927) (xy 239.596047 -82.383601)
			(xy 239.560472 -82.553811) (xy 239.517063 -82.722195) (xy 239.465913 -82.888391) (xy 239.407133 -83.052043)
			(xy 239.340846 -83.212802) (xy 239.267197 -83.370324) (xy 239.186341 -83.524271) (xy 239.148735 -83.588471)
			(xy 341.356398 -83.588471) (xy 341.356398 -83.533929) (xy 341.364161 -83.479942) (xy 341.379527 -83.427609)
			(xy 341.402184 -83.377996) (xy 341.431672 -83.332112) (xy 341.467389 -83.290892) (xy 341.508609 -83.255174)
			(xy 341.554492 -83.225686) (xy 341.604106 -83.203028) (xy 341.656438 -83.187661) (xy 341.710425 -83.179899)
			(xy 341.737696 -83.179412) (xy 342.601296 -83.179412) (xy 342.628565 -83.179927) (xy 342.682549 -83.187688)
			(xy 342.734879 -83.203053) (xy 342.784489 -83.225709) (xy 342.83037 -83.255194) (xy 342.871588 -83.290909)
			(xy 342.907303 -83.332127) (xy 342.936789 -83.378008) (xy 342.959445 -83.427618) (xy 342.974811 -83.479947)
			(xy 342.982573 -83.533931) (xy 342.982573 -83.588469) (xy 342.974811 -83.642453) (xy 342.959445 -83.694782)
			(xy 342.936789 -83.744392) (xy 342.907303 -83.790273) (xy 342.871588 -83.831491) (xy 342.83037 -83.867206)
			(xy 342.784489 -83.896691) (xy 342.734879 -83.919347) (xy 342.682549 -83.934712) (xy 342.628565 -83.942473)
			(xy 342.601296 -83.942936) (xy 341.737696 -83.942936) (xy 341.710425 -83.942501) (xy 341.656438 -83.934739)
			(xy 341.604106 -83.919372) (xy 341.554492 -83.896714) (xy 341.508609 -83.867226) (xy 341.467389 -83.831508)
			(xy 341.431672 -83.790288) (xy 341.402184 -83.744404) (xy 341.379527 -83.694791) (xy 341.364161 -83.642458)
			(xy 341.356398 -83.588471) (xy 239.148735 -83.588471) (xy 239.098452 -83.674314) (xy 239.003718 -83.820132)
			(xy 238.902342 -83.961413) (xy 238.794541 -84.097854) (xy 238.680545 -84.229164) (xy 238.560599 -84.355062)
			(xy 238.434958 -84.475277) (xy 238.393119 -84.511757) (xy 337.882119 -84.511757) (xy 337.882119 -84.457243)
			(xy 337.889878 -84.403284) (xy 337.905237 -84.350979) (xy 337.927883 -84.301392) (xy 337.957357 -84.255533)
			(xy 337.993057 -84.214336) (xy 338.034257 -84.178639) (xy 338.080119 -84.149169) (xy 338.129707 -84.126526)
			(xy 338.182014 -84.111171) (xy 338.235973 -84.103417) (xy 338.26323 -84.102956) (xy 339.12683 -84.102956)
			(xy 339.154077 -84.103516) (xy 339.208017 -84.111275) (xy 339.260303 -84.126632) (xy 339.309871 -84.149272)
			(xy 339.355714 -84.178737) (xy 339.396896 -84.214425) (xy 339.432581 -84.25561) (xy 339.462042 -84.301455)
			(xy 339.484679 -84.351025) (xy 339.500031 -84.403313) (xy 339.503159 -84.425069) (xy 344.644951 -84.425069)
			(xy 344.644951 -84.370531) (xy 344.652713 -84.316548) (xy 344.668079 -84.26422) (xy 344.690737 -84.214611)
			(xy 344.720223 -84.168731) (xy 344.75594 -84.127516) (xy 344.797159 -84.091803) (xy 344.843041 -84.06232)
			(xy 344.892652 -84.039668) (xy 344.944981 -84.024306) (xy 344.998965 -84.016549) (xy 345.026234 -84.016088)
			(xy 345.889834 -84.016088) (xy 345.917105 -84.016477) (xy 345.971092 -84.024243) (xy 346.023425 -84.039614)
			(xy 346.073037 -84.062275) (xy 346.11892 -84.091766) (xy 346.160139 -84.127485) (xy 346.195855 -84.168708)
			(xy 346.225341 -84.214593) (xy 346.247998 -84.264207) (xy 346.263364 -84.316541) (xy 346.271126 -84.370529)
			(xy 346.271126 -84.425071) (xy 346.263364 -84.479059) (xy 346.247998 -84.531393) (xy 346.225341 -84.581007)
			(xy 346.195855 -84.626892) (xy 346.160139 -84.668115) (xy 346.11892 -84.703834) (xy 346.073037 -84.733325)
			(xy 346.023425 -84.755986) (xy 345.971092 -84.771357) (xy 345.917105 -84.779123) (xy 345.889834 -84.779612)
			(xy 345.026234 -84.779612) (xy 344.998965 -84.779051) (xy 344.944981 -84.771294) (xy 344.892652 -84.755932)
			(xy 344.843041 -84.73328) (xy 344.797159 -84.703797) (xy 344.75594 -84.668084) (xy 344.720223 -84.626869)
			(xy 344.690737 -84.580989) (xy 344.668079 -84.53138) (xy 344.652713 -84.479052) (xy 344.644951 -84.425069)
			(xy 339.503159 -84.425069) (xy 339.507786 -84.457253) (xy 339.507786 -84.511747) (xy 339.500031 -84.565687)
			(xy 339.484679 -84.617975) (xy 339.462042 -84.667545) (xy 339.432581 -84.71339) (xy 339.396896 -84.754575)
			(xy 339.355714 -84.790263) (xy 339.309871 -84.819728) (xy 339.260303 -84.842368) (xy 339.208017 -84.857725)
			(xy 339.154077 -84.865484) (xy 339.12683 -84.865972) (xy 338.26323 -84.865972) (xy 338.235973 -84.865583)
			(xy 338.182014 -84.857829) (xy 338.129707 -84.842474) (xy 338.080119 -84.819831) (xy 338.034257 -84.790361)
			(xy 337.993057 -84.754664) (xy 337.957357 -84.713467) (xy 337.927883 -84.667608) (xy 337.905237 -84.618021)
			(xy 337.889878 -84.565716) (xy 337.882119 -84.511757) (xy 238.393119 -84.511757) (xy 238.303893 -84.589554)
			(xy 238.167683 -84.697647) (xy 238.02662 -84.799326) (xy 237.881005 -84.894371) (xy 237.73115 -84.982581)
			(xy 237.577377 -85.063767) (xy 237.420014 -85.137754) (xy 237.259397 -85.204384) (xy 237.095871 -85.263515)
			(xy 236.929785 -85.315021) (xy 236.761494 -85.35879) (xy 236.59136 -85.39473) (xy 236.419746 -85.422763)
			(xy 236.247019 -85.44283) (xy 236.073548 -85.454887) (xy 235.899706 -85.458909) (xy 235.725864 -85.454887)
			(xy 235.552393 -85.44283) (xy 235.379666 -85.422763) (xy 235.208052 -85.39473) (xy 235.037918 -85.35879)
			(xy 234.869627 -85.315021) (xy 234.703541 -85.263515) (xy 234.540015 -85.204384) (xy 234.379398 -85.137754)
			(xy 234.222035 -85.063767) (xy 234.068262 -84.982581) (xy 233.918407 -84.894371) (xy 233.772792 -84.799326)
			(xy 233.631729 -84.697647) (xy 233.495519 -84.589554) (xy 233.364454 -84.475277) (xy 233.238813 -84.355062)
			(xy 233.118867 -84.229164) (xy 233.004871 -84.097854) (xy 232.89707 -83.961413) (xy 232.795694 -83.820132)
			(xy 232.70096 -83.674314) (xy 232.613071 -83.524271) (xy 232.532215 -83.370324) (xy 232.458566 -83.212802)
			(xy 232.392279 -83.052043) (xy 232.333499 -82.888391) (xy 232.282349 -82.722195) (xy 232.23894 -82.553811)
			(xy 232.203365 -82.383601) (xy 232.175699 -82.211927) (xy 232.156003 -82.039157) (xy 232.144317 -81.865661)
			(xy 232.140667 -81.69181) (xy 2.509012 -81.69181) (xy 2.509012 -85.764678) (xy 10.421355 -85.764678)
			(xy 10.421355 -85.635538) (xy 10.429305 -85.506643) (xy 10.445175 -85.378483) (xy 10.468904 -85.251542)
			(xy 10.500403 -85.126303) (xy 10.539552 -85.00324) (xy 10.586203 -84.882821) (xy 10.640178 -84.765502)
			(xy 10.701273 -84.651728) (xy 10.769256 -84.541931) (xy 10.84387 -84.436528) (xy 10.924831 -84.335918)
			(xy 11.011831 -84.240483) (xy 11.104542 -84.150584) (xy 11.202612 -84.066563) (xy 11.305667 -83.988739)
			(xy 11.413318 -83.917407) (xy 11.525157 -83.852837) (xy 11.640758 -83.795275) (xy 11.759683 -83.744938)
			(xy 11.881482 -83.702018) (xy 12.005692 -83.666677) (xy 12.131841 -83.63905) (xy 12.259453 -83.619241)
			(xy 12.388042 -83.607325) (xy 12.51712 -83.603349) (xy 12.646198 -83.607325) (xy 12.774787 -83.619241)
			(xy 12.902399 -83.63905) (xy 13.028548 -83.666677) (xy 13.152758 -83.702018) (xy 13.274557 -83.744938)
			(xy 13.393482 -83.795275) (xy 13.509083 -83.852837) (xy 13.620922 -83.917407) (xy 13.728573 -83.988739)
			(xy 13.831628 -84.066563) (xy 13.929698 -84.150584) (xy 14.022409 -84.240483) (xy 14.109409 -84.335918)
			(xy 14.19037 -84.436528) (xy 14.264984 -84.541931) (xy 14.332967 -84.651728) (xy 14.394062 -84.765502)
			(xy 14.448037 -84.882821) (xy 14.494688 -85.00324) (xy 14.533837 -85.126303) (xy 14.565336 -85.251542)
			(xy 14.589065 -85.378483) (xy 14.604935 -85.506643) (xy 14.612885 -85.635538) (xy 14.613382 -85.700108)
			(xy 14.612885 -85.764678) (xy 14.608278 -85.839368) (xy 342.975946 -85.839368) (xy 342.975946 -85.784832)
			(xy 342.983708 -85.730852) (xy 342.999072 -85.678525) (xy 343.021727 -85.628918) (xy 343.051211 -85.58304)
			(xy 343.086924 -85.541824) (xy 343.12814 -85.506111) (xy 343.174018 -85.476627) (xy 343.223625 -85.453972)
			(xy 343.275952 -85.438608) (xy 343.329932 -85.430846) (xy 343.3572 -85.43036) (xy 344.2208 -85.43036)
			(xy 344.248071 -85.430802) (xy 344.302058 -85.438565) (xy 344.35439 -85.453931) (xy 344.404003 -85.476588)
			(xy 344.449887 -85.506076) (xy 344.491107 -85.541793) (xy 344.526824 -85.583013) (xy 344.556312 -85.628897)
			(xy 344.578969 -85.67851) (xy 344.594335 -85.730842) (xy 344.602098 -85.784829) (xy 344.602098 -85.839371)
			(xy 344.594335 -85.893358) (xy 344.578969 -85.94569) (xy 344.556312 -85.995303) (xy 344.526824 -86.041187)
			(xy 344.491107 -86.082407) (xy 344.449887 -86.118124) (xy 344.404003 -86.147612) (xy 344.35439 -86.170269)
			(xy 344.302058 -86.185635) (xy 344.248071 -86.193398) (xy 344.2208 -86.193884) (xy 343.3572 -86.193884)
			(xy 343.329932 -86.193354) (xy 343.275952 -86.185592) (xy 343.223625 -86.170228) (xy 343.174018 -86.147573)
			(xy 343.12814 -86.118089) (xy 343.086924 -86.082376) (xy 343.051211 -86.04116) (xy 343.021727 -85.995282)
			(xy 342.999072 -85.945675) (xy 342.983708 -85.893348) (xy 342.975946 -85.839368) (xy 14.608278 -85.839368)
			(xy 14.604935 -85.893573) (xy 14.589065 -86.021733) (xy 14.565336 -86.148674) (xy 14.533837 -86.273913)
			(xy 14.494688 -86.396976) (xy 14.448037 -86.517395) (xy 14.394062 -86.634714) (xy 14.332967 -86.748488)
			(xy 14.264984 -86.858285) (xy 14.19037 -86.963688) (xy 14.109409 -87.064298) (xy 14.022409 -87.159733)
			(xy 13.929698 -87.249632) (xy 13.831628 -87.333653) (xy 13.728573 -87.411477) (xy 13.620922 -87.482809)
			(xy 13.509083 -87.547379) (xy 13.393482 -87.604941) (xy 13.274557 -87.655278) (xy 13.152758 -87.698198)
			(xy 13.028548 -87.733539) (xy 12.902399 -87.761166) (xy 12.774787 -87.780975) (xy 12.646198 -87.792891)
			(xy 12.51712 -87.796868) (xy 12.388042 -87.792891) (xy 12.259453 -87.780975) (xy 12.131841 -87.761166)
			(xy 12.005692 -87.733539) (xy 11.881482 -87.698198) (xy 11.759683 -87.655278) (xy 11.640758 -87.604941)
			(xy 11.525157 -87.547379) (xy 11.413318 -87.482809) (xy 11.305667 -87.411477) (xy 11.202612 -87.333653)
			(xy 11.104542 -87.249632) (xy 11.011831 -87.159733) (xy 10.924831 -87.064298) (xy 10.84387 -86.963688)
			(xy 10.769256 -86.858285) (xy 10.701273 -86.748488) (xy 10.640178 -86.634714) (xy 10.586203 -86.517395)
			(xy 10.539552 -86.396976) (xy 10.500403 -86.273913) (xy 10.468904 -86.148674) (xy 10.445175 -86.021733)
			(xy 10.429305 -85.893573) (xy 10.421355 -85.764678) (xy 2.509012 -85.764678) (xy 2.509012 -98.341434)
			(xy 261.733792 -98.341434) (xy 261.733792 -97.477834) (xy 261.734278 -97.450583) (xy 261.742034 -97.396635)
			(xy 261.757389 -97.34434) (xy 261.780031 -97.294763) (xy 261.809497 -97.248913) (xy 261.845188 -97.207722)
			(xy 261.886379 -97.172031) (xy 261.932229 -97.142565) (xy 261.981806 -97.119923) (xy 262.034101 -97.104568)
			(xy 262.088049 -97.096812) (xy 262.142551 -97.096812) (xy 262.196499 -97.104568) (xy 262.248794 -97.119923)
			(xy 262.298371 -97.142565) (xy 262.344221 -97.172031) (xy 262.385412 -97.207722) (xy 262.421103 -97.248913)
			(xy 262.450569 -97.294763) (xy 262.473211 -97.34434) (xy 262.488566 -97.396635) (xy 262.496322 -97.450583)
			(xy 262.496808 -97.477834) (xy 262.496808 -98.341434) (xy 262.496322 -98.368685) (xy 262.488566 -98.422633)
			(xy 262.473211 -98.474928) (xy 262.450569 -98.524505) (xy 262.421103 -98.570355) (xy 262.385412 -98.611546)
			(xy 262.344221 -98.647237) (xy 262.298371 -98.676703) (xy 262.248794 -98.699345) (xy 262.196499 -98.7147)
			(xy 262.142551 -98.722456) (xy 262.088049 -98.722456) (xy 262.034101 -98.7147) (xy 261.981806 -98.699345)
			(xy 261.932229 -98.676703) (xy 261.886379 -98.647237) (xy 261.845188 -98.611546) (xy 261.809497 -98.570355)
			(xy 261.780031 -98.524505) (xy 261.757389 -98.474928) (xy 261.742034 -98.422633) (xy 261.734278 -98.368685)
			(xy 261.733792 -98.341434) (xy 2.509012 -98.341434) (xy 2.509012 -106.40187) (xy 11.713464 -106.40187)
			(xy 11.713464 -105.53827) (xy 11.71395 -105.511001) (xy 11.721712 -105.457017) (xy 11.737077 -105.404687)
			(xy 11.759734 -105.355077) (xy 11.78922 -105.309196) (xy 11.824935 -105.267979) (xy 11.866152 -105.232264)
			(xy 11.912033 -105.202778) (xy 11.961643 -105.180121) (xy 12.013973 -105.164756) (xy 12.067957 -105.156994)
			(xy 12.122495 -105.156994) (xy 12.176479 -105.164756) (xy 12.228809 -105.180121) (xy 12.278419 -105.202778)
			(xy 12.3243 -105.232264) (xy 12.365517 -105.267979) (xy 12.401232 -105.309196) (xy 12.430718 -105.355077)
			(xy 12.453375 -105.404687) (xy 12.46874 -105.457017) (xy 12.476502 -105.511001) (xy 12.476988 -105.53827)
			(xy 12.476988 -105.664) (xy 15.57274 -105.664) (xy 15.57274 -104.8004) (xy 15.573226 -104.773131)
			(xy 15.580988 -104.719147) (xy 15.596353 -104.666817) (xy 15.61901 -104.617207) (xy 15.648496 -104.571326)
			(xy 15.684211 -104.530109) (xy 15.725428 -104.494394) (xy 15.771309 -104.464908) (xy 15.820919 -104.442251)
			(xy 15.873249 -104.426886) (xy 15.927233 -104.419124) (xy 15.981771 -104.419124) (xy 16.035755 -104.426886)
			(xy 16.088085 -104.442251) (xy 16.137695 -104.464908) (xy 16.183576 -104.494394) (xy 16.224793 -104.530109)
			(xy 16.260508 -104.571326) (xy 16.289994 -104.617207) (xy 16.312651 -104.666817) (xy 16.328016 -104.719147)
			(xy 16.335778 -104.773131) (xy 16.336264 -104.8004) (xy 16.336264 -105.664) (xy 16.335778 -105.691269)
			(xy 16.328016 -105.745253) (xy 16.312651 -105.797583) (xy 16.289994 -105.847193) (xy 16.260508 -105.893074)
			(xy 16.224793 -105.934291) (xy 16.183576 -105.970006) (xy 16.137695 -105.999492) (xy 16.088085 -106.022149)
			(xy 16.035755 -106.037514) (xy 15.981771 -106.045276) (xy 15.927233 -106.045276) (xy 15.873249 -106.037514)
			(xy 15.820919 -106.022149) (xy 15.771309 -105.999492) (xy 15.725428 -105.970006) (xy 15.684211 -105.934291)
			(xy 15.648496 -105.893074) (xy 15.61901 -105.847193) (xy 15.596353 -105.797583) (xy 15.580988 -105.745253)
			(xy 15.573226 -105.691269) (xy 15.57274 -105.664) (xy 12.476988 -105.664) (xy 12.476988 -106.40187)
			(xy 12.476502 -106.429139) (xy 12.46874 -106.483123) (xy 12.453375 -106.535453) (xy 12.430718 -106.585063)
			(xy 12.401232 -106.630944) (xy 12.365517 -106.672161) (xy 12.3243 -106.707876) (xy 12.278419 -106.737362)
			(xy 12.228809 -106.760019) (xy 12.176479 -106.775384) (xy 12.122495 -106.783146) (xy 12.067957 -106.783146)
			(xy 12.013973 -106.775384) (xy 11.961643 -106.760019) (xy 11.912033 -106.737362) (xy 11.866152 -106.707876)
			(xy 11.824935 -106.672161) (xy 11.78922 -106.630944) (xy 11.759734 -106.585063) (xy 11.737077 -106.535453)
			(xy 11.721712 -106.483123) (xy 11.71395 -106.429139) (xy 11.713464 -106.40187) (xy 2.509012 -106.40187)
			(xy 2.509012 -108.943971) (xy 11.292822 -108.943971) (xy 11.292822 -108.889469) (xy 11.300578 -108.835522)
			(xy 11.315933 -108.783228) (xy 11.338574 -108.733651) (xy 11.36804 -108.687801) (xy 11.403731 -108.646611)
			(xy 11.444921 -108.61092) (xy 11.490771 -108.581454) (xy 11.540348 -108.558813) (xy 11.592642 -108.543458)
			(xy 11.646589 -108.535702) (xy 11.67384 -108.535216) (xy 12.53744 -108.535216) (xy 12.564692 -108.535694)
			(xy 12.61864 -108.54345) (xy 12.670935 -108.558806) (xy 12.720513 -108.581447) (xy 12.766364 -108.610914)
			(xy 12.807554 -108.646606) (xy 12.843246 -108.687796) (xy 12.872713 -108.733647) (xy 12.895354 -108.783225)
			(xy 12.91071 -108.83552) (xy 12.918466 -108.889468) (xy 12.918466 -108.943972) (xy 12.918466 -108.943973)
			(xy 15.156389 -108.943973) (xy 15.156389 -108.889467) (xy 15.164146 -108.835517) (xy 15.179502 -108.783219)
			(xy 15.202145 -108.733639) (xy 15.231613 -108.687786) (xy 15.267307 -108.646594) (xy 15.308499 -108.610901)
			(xy 15.354353 -108.581433) (xy 15.403933 -108.558791) (xy 15.45623 -108.543435) (xy 15.510181 -108.535679)
			(xy 15.537434 -108.535216) (xy 16.401034 -108.535216) (xy 16.428285 -108.535694) (xy 16.482233 -108.543451)
			(xy 16.534528 -108.558807) (xy 16.584105 -108.581448) (xy 16.629956 -108.610915) (xy 16.671146 -108.646607)
			(xy 16.706837 -108.687798) (xy 16.707863 -108.689394) (xy 238.647224 -108.689394) (xy 238.647224 -107.825794)
			(xy 238.64771 -107.798525) (xy 238.655472 -107.744541) (xy 238.670837 -107.692211) (xy 238.693494 -107.642601)
			(xy 238.72298 -107.59672) (xy 238.758695 -107.555503) (xy 238.799912 -107.519788) (xy 238.845793 -107.490302)
			(xy 238.895403 -107.467645) (xy 238.947733 -107.45228) (xy 239.001717 -107.444518) (xy 239.056255 -107.444518)
			(xy 239.110239 -107.45228) (xy 239.162569 -107.467645) (xy 239.212179 -107.490302) (xy 239.25806 -107.519788)
			(xy 239.299277 -107.555503) (xy 239.334992 -107.59672) (xy 239.364478 -107.642601) (xy 239.387135 -107.692211)
			(xy 239.4025 -107.744541) (xy 239.410262 -107.798525) (xy 239.410748 -107.825794) (xy 239.410748 -108.689394)
			(xy 239.410262 -108.716663) (xy 239.4025 -108.770647) (xy 239.387135 -108.822977) (xy 239.364478 -108.872587)
			(xy 239.334992 -108.918468) (xy 239.299277 -108.959685) (xy 239.25806 -108.9954) (xy 239.212179 -109.024886)
			(xy 239.162569 -109.047543) (xy 239.110239 -109.062908) (xy 239.056255 -109.07067) (xy 239.001717 -109.07067)
			(xy 238.947733 -109.062908) (xy 238.895403 -109.047543) (xy 238.845793 -109.024886) (xy 238.799912 -108.9954)
			(xy 238.758695 -108.959685) (xy 238.72298 -108.918468) (xy 238.693494 -108.872587) (xy 238.670837 -108.822977)
			(xy 238.655472 -108.770647) (xy 238.64771 -108.716663) (xy 238.647224 -108.689394) (xy 16.707863 -108.689394)
			(xy 16.736304 -108.733648) (xy 16.758945 -108.783226) (xy 16.7743 -108.835521) (xy 16.782056 -108.889469)
			(xy 16.782056 -108.943971) (xy 16.7743 -108.997919) (xy 16.758945 -109.050214) (xy 16.736304 -109.099792)
			(xy 16.706837 -109.145642) (xy 16.671146 -109.186833) (xy 16.629956 -109.222525) (xy 16.584105 -109.251992)
			(xy 16.534528 -109.274633) (xy 16.482233 -109.289989) (xy 16.428285 -109.297746) (xy 16.401034 -109.298232)
			(xy 15.537434 -109.298232) (xy 15.510181 -109.297761) (xy 15.45623 -109.290005) (xy 15.403933 -109.274649)
			(xy 15.354353 -109.252007) (xy 15.308499 -109.222539) (xy 15.267307 -109.186846) (xy 15.231613 -109.145654)
			(xy 15.202145 -109.099801) (xy 15.179502 -109.050221) (xy 15.164146 -108.997923) (xy 15.156389 -108.943973)
			(xy 12.918466 -108.943973) (xy 12.91071 -108.99792) (xy 12.895354 -109.050215) (xy 12.872713 -109.099793)
			(xy 12.843246 -109.145644) (xy 12.807554 -109.186834) (xy 12.766364 -109.222526) (xy 12.720513 -109.251993)
			(xy 12.670935 -109.274634) (xy 12.61864 -109.28999) (xy 12.564692 -109.297746) (xy 12.53744 -109.298232)
			(xy 11.67384 -109.298232) (xy 11.646589 -109.297738) (xy 11.592642 -109.289982) (xy 11.540348 -109.274627)
			(xy 11.490771 -109.251986) (xy 11.444921 -109.22252) (xy 11.403731 -109.186829) (xy 11.36804 -109.145639)
			(xy 11.338574 -109.099789) (xy 11.315933 -109.050212) (xy 11.300578 -108.997918) (xy 11.292822 -108.943971)
			(xy 2.509012 -108.943971) (xy 2.509012 -109.550266) (xy 250.428546 -109.550266) (xy 250.428546 -109.495734)
			(xy 250.436306 -109.441757) (xy 250.451669 -109.389434) (xy 250.474321 -109.339829) (xy 250.503801 -109.293953)
			(xy 250.53951 -109.252739) (xy 250.580721 -109.217025) (xy 250.626594 -109.18754) (xy 250.676196 -109.164883)
			(xy 250.728518 -109.149515) (xy 250.782494 -109.141749) (xy 250.80976 -109.14126) (xy 251.67336 -109.14126)
			(xy 251.700634 -109.141677) (xy 251.754629 -109.149435) (xy 251.806969 -109.164798) (xy 251.85659 -109.187455)
			(xy 251.902482 -109.216943) (xy 251.943709 -109.252663) (xy 251.979433 -109.293886) (xy 252.008926 -109.339775)
			(xy 252.031588 -109.389393) (xy 252.046957 -109.441732) (xy 252.05472 -109.495726) (xy 252.05472 -109.550274)
			(xy 252.046957 -109.604268) (xy 252.031588 -109.656607) (xy 252.008926 -109.706225) (xy 251.979433 -109.752114)
			(xy 251.943709 -109.793337) (xy 251.902482 -109.829057) (xy 251.85659 -109.858545) (xy 251.806969 -109.881202)
			(xy 251.754629 -109.896565) (xy 251.700634 -109.904323) (xy 251.67336 -109.904784) (xy 250.80976 -109.904784)
			(xy 250.782494 -109.904251) (xy 250.728518 -109.896485) (xy 250.676196 -109.881117) (xy 250.626594 -109.85846)
			(xy 250.580721 -109.828975) (xy 250.53951 -109.793262) (xy 250.503801 -109.752047) (xy 250.474321 -109.706171)
			(xy 250.451669 -109.656566) (xy 250.436306 -109.604243) (xy 250.428546 -109.550266) (xy 2.509012 -109.550266)
			(xy 2.509012 -111.158274) (xy 239.40262 -111.158274) (xy 239.40262 -110.294674) (xy 239.403106 -110.267423)
			(xy 239.410862 -110.213475) (xy 239.426217 -110.16118) (xy 239.448859 -110.111603) (xy 239.478325 -110.065753)
			(xy 239.514016 -110.024562) (xy 239.555207 -109.988871) (xy 239.601057 -109.959405) (xy 239.650634 -109.936763)
			(xy 239.702929 -109.921408) (xy 239.756877 -109.913652) (xy 239.811379 -109.913652) (xy 239.865327 -109.921408)
			(xy 239.917622 -109.936763) (xy 239.967199 -109.959405) (xy 240.000574 -109.980854) (xy 256.88563 -109.980854)
			(xy 256.88563 -109.926346) (xy 256.893387 -109.872392) (xy 256.908744 -109.820091) (xy 256.931388 -109.770508)
			(xy 256.960857 -109.724652) (xy 256.996552 -109.683457) (xy 257.037747 -109.647761) (xy 257.083602 -109.61829)
			(xy 257.133185 -109.595646) (xy 257.185486 -109.580288) (xy 257.23944 -109.57253) (xy 257.266694 -109.572044)
			(xy 258.130294 -109.572044) (xy 258.157544 -109.572603) (xy 258.211488 -109.580358) (xy 258.26378 -109.595712)
			(xy 258.313355 -109.618351) (xy 258.359203 -109.647815) (xy 258.400391 -109.683504) (xy 258.436081 -109.724692)
			(xy 258.465546 -109.77054) (xy 258.488186 -109.820114) (xy 258.503541 -109.872406) (xy 258.511297 -109.92635)
			(xy 258.511297 -109.98085) (xy 258.503541 -110.034794) (xy 258.488186 -110.087086) (xy 258.465546 -110.13666)
			(xy 258.436081 -110.182508) (xy 258.400391 -110.223696) (xy 258.359203 -110.259385) (xy 258.313355 -110.288849)
			(xy 258.26378 -110.311488) (xy 258.211488 -110.326842) (xy 258.157544 -110.334597) (xy 258.130294 -110.33506)
			(xy 257.266694 -110.33506) (xy 257.23944 -110.33467) (xy 257.185486 -110.326912) (xy 257.133185 -110.311554)
			(xy 257.083602 -110.28891) (xy 257.037747 -110.259439) (xy 256.996552 -110.223743) (xy 256.960857 -110.182548)
			(xy 256.931388 -110.136692) (xy 256.908744 -110.087109) (xy 256.893387 -110.034808) (xy 256.88563 -109.980854)
			(xy 240.000574 -109.980854) (xy 240.013049 -109.988871) (xy 240.05424 -110.024562) (xy 240.089931 -110.065753)
			(xy 240.119397 -110.111603) (xy 240.142039 -110.16118) (xy 240.157394 -110.213475) (xy 240.16515 -110.267423)
			(xy 240.165636 -110.294674) (xy 240.165636 -111.158274) (xy 240.16515 -111.185525) (xy 240.157394 -111.239473)
			(xy 240.142039 -111.291768) (xy 240.119397 -111.341345) (xy 240.089931 -111.387195) (xy 240.05424 -111.428386)
			(xy 240.013049 -111.464077) (xy 239.967199 -111.493543) (xy 239.917622 -111.516185) (xy 239.865327 -111.53154)
			(xy 239.811379 -111.539296) (xy 239.756877 -111.539296) (xy 239.702929 -111.53154) (xy 239.650634 -111.516185)
			(xy 239.601057 -111.493543) (xy 239.555207 -111.464077) (xy 239.514016 -111.428386) (xy 239.478325 -111.387195)
			(xy 239.448859 -111.341345) (xy 239.426217 -111.291768) (xy 239.410862 -111.239473) (xy 239.403106 -111.185525)
			(xy 239.40262 -111.158274) (xy 2.509012 -111.158274) (xy 2.509012 -114.734161) (xy 11.255226 -114.734161)
			(xy 11.255226 -114.679659) (xy 11.262982 -114.625711) (xy 11.278337 -114.573416) (xy 11.300979 -114.523839)
			(xy 11.330445 -114.477988) (xy 11.366136 -114.436798) (xy 11.407326 -114.401106) (xy 11.453177 -114.371639)
			(xy 11.502754 -114.348998) (xy 11.555049 -114.333643) (xy 11.608997 -114.325886) (xy 11.636248 -114.3254)
			(xy 12.499848 -114.3254) (xy 12.527101 -114.325867) (xy 12.581052 -114.333624) (xy 12.633349 -114.34898)
			(xy 12.68293 -114.371622) (xy 12.728783 -114.40109) (xy 12.769975 -114.436783) (xy 12.805669 -114.477976)
			(xy 12.835137 -114.523829) (xy 12.85778 -114.573409) (xy 12.873136 -114.625706) (xy 12.880893 -114.679657)
			(xy 12.880893 -114.734163) (xy 12.873136 -114.788114) (xy 12.85778 -114.840411) (xy 12.835137 -114.889991)
			(xy 12.805669 -114.935844) (xy 12.769975 -114.977037) (xy 12.728783 -115.01273) (xy 12.68293 -115.042198)
			(xy 12.633349 -115.06484) (xy 12.581052 -115.080196) (xy 12.527101 -115.087953) (xy 12.499848 -115.088416)
			(xy 11.636248 -115.088416) (xy 11.608997 -115.087934) (xy 11.555049 -115.080177) (xy 11.502754 -115.064822)
			(xy 11.453177 -115.042181) (xy 11.407326 -115.012714) (xy 11.366136 -114.977022) (xy 11.330445 -114.935832)
			(xy 11.300979 -114.889981) (xy 11.278337 -114.840404) (xy 11.262982 -114.788109) (xy 11.255226 -114.734161)
			(xy 2.509012 -114.734161) (xy 2.509012 -116.393573) (xy 230.652992 -116.393573) (xy 230.652992 -116.339027)
			(xy 230.660755 -116.285035) (xy 230.676123 -116.232698) (xy 230.698784 -116.183081) (xy 230.728276 -116.137195)
			(xy 230.763998 -116.095973) (xy 230.805224 -116.060254) (xy 230.851113 -116.030767) (xy 230.900732 -116.008111)
			(xy 230.95307 -115.992747) (xy 231.007063 -115.984989) (xy 231.034336 -115.984528) (xy 231.897936 -115.984528)
			(xy 231.925203 -115.985037) (xy 231.979181 -115.992802) (xy 232.031505 -116.008171) (xy 232.081109 -116.030828)
			(xy 232.126985 -116.060314) (xy 232.168197 -116.096029) (xy 232.203907 -116.137244) (xy 232.233389 -116.183122)
			(xy 232.256042 -116.232729) (xy 232.271405 -116.285054) (xy 232.277026 -116.324151) (xy 236.866903 -116.324151)
			(xy 236.866903 -116.269649) (xy 236.87466 -116.215701) (xy 236.890016 -116.163407) (xy 236.912659 -116.113831)
			(xy 236.942127 -116.067981) (xy 236.97782 -116.026793) (xy 237.019012 -115.991104) (xy 237.064864 -115.961641)
			(xy 237.114443 -115.939003) (xy 237.166739 -115.923652) (xy 237.220687 -115.915901) (xy 237.247938 -115.91544)
			(xy 238.111538 -115.91544) (xy 238.138791 -115.915832) (xy 238.192741 -115.923594) (xy 238.245038 -115.938955)
			(xy 238.294617 -115.961601) (xy 238.340468 -115.991072) (xy 238.381659 -116.026768) (xy 238.417351 -116.067962)
			(xy 238.446817 -116.113817) (xy 238.469459 -116.163398) (xy 238.484814 -116.215696) (xy 238.49257 -116.269647)
			(xy 238.49257 -116.324153) (xy 238.484814 -116.378104) (xy 238.469459 -116.430402) (xy 238.446817 -116.479983)
			(xy 238.417351 -116.525838) (xy 238.381659 -116.567032) (xy 238.340468 -116.602728) (xy 238.294617 -116.632199)
			(xy 238.245038 -116.654845) (xy 238.192741 -116.670206) (xy 238.138791 -116.677968) (xy 238.111538 -116.678456)
			(xy 237.247938 -116.678456) (xy 237.220687 -116.677899) (xy 237.166739 -116.670148) (xy 237.114443 -116.654797)
			(xy 237.064864 -116.632159) (xy 237.019012 -116.602696) (xy 236.97782 -116.567007) (xy 236.942127 -116.525819)
			(xy 236.912659 -116.479969) (xy 236.890016 -116.430393) (xy 236.87466 -116.378099) (xy 236.866903 -116.324151)
			(xy 232.277026 -116.324151) (xy 232.279166 -116.339033) (xy 232.279166 -116.393567) (xy 232.271405 -116.447546)
			(xy 232.256042 -116.499871) (xy 232.233389 -116.549478) (xy 232.203907 -116.595356) (xy 232.168197 -116.636571)
			(xy 232.126985 -116.672286) (xy 232.081109 -116.701772) (xy 232.031505 -116.724429) (xy 231.979181 -116.739798)
			(xy 231.925203 -116.747563) (xy 231.897936 -116.748052) (xy 231.034336 -116.748052) (xy 231.007063 -116.747611)
			(xy 230.95307 -116.739853) (xy 230.900732 -116.724489) (xy 230.851113 -116.701833) (xy 230.805224 -116.672346)
			(xy 230.763998 -116.636627) (xy 230.728276 -116.595405) (xy 230.698784 -116.549519) (xy 230.676123 -116.499902)
			(xy 230.660755 -116.447565) (xy 230.652992 -116.393573) (xy 2.509012 -116.393573) (xy 2.509012 -117.632251)
			(xy 233.564903 -117.632251) (xy 233.564903 -117.577749) (xy 233.57266 -117.523801) (xy 233.588016 -117.471507)
			(xy 233.610659 -117.421931) (xy 233.640127 -117.376081) (xy 233.67582 -117.334893) (xy 233.717012 -117.299204)
			(xy 233.762864 -117.269741) (xy 233.812443 -117.247103) (xy 233.864739 -117.231752) (xy 233.918687 -117.224001)
			(xy 233.945938 -117.22354) (xy 234.809538 -117.22354) (xy 234.836791 -117.223932) (xy 234.890741 -117.231694)
			(xy 234.943038 -117.247055) (xy 234.992617 -117.269701) (xy 235.038468 -117.299172) (xy 235.079659 -117.334868)
			(xy 235.115351 -117.376062) (xy 235.144817 -117.421917) (xy 235.167459 -117.471498) (xy 235.182814 -117.523796)
			(xy 235.19057 -117.577747) (xy 235.19057 -117.632251) (xy 238.898903 -117.632251) (xy 238.898903 -117.577749)
			(xy 238.90666 -117.523801) (xy 238.922016 -117.471507) (xy 238.944659 -117.421931) (xy 238.974127 -117.376081)
			(xy 239.00982 -117.334893) (xy 239.051012 -117.299204) (xy 239.096864 -117.269741) (xy 239.146443 -117.247103)
			(xy 239.198739 -117.231752) (xy 239.252687 -117.224001) (xy 239.279938 -117.22354) (xy 240.143538 -117.22354)
			(xy 240.170791 -117.223932) (xy 240.224741 -117.231694) (xy 240.277038 -117.247055) (xy 240.326617 -117.269701)
			(xy 240.372468 -117.299172) (xy 240.413659 -117.334868) (xy 240.449351 -117.376062) (xy 240.478817 -117.421917)
			(xy 240.501459 -117.471498) (xy 240.516814 -117.523796) (xy 240.52457 -117.577747) (xy 240.52457 -117.632253)
			(xy 240.516814 -117.686204) (xy 240.501459 -117.738502) (xy 240.478817 -117.788083) (xy 240.449351 -117.833938)
			(xy 240.413659 -117.875132) (xy 240.372468 -117.910828) (xy 240.326617 -117.940299) (xy 240.277038 -117.962945)
			(xy 240.224741 -117.978306) (xy 240.170791 -117.986068) (xy 240.143538 -117.986556) (xy 239.279938 -117.986556)
			(xy 239.252687 -117.985999) (xy 239.198739 -117.978248) (xy 239.146443 -117.962897) (xy 239.096864 -117.940259)
			(xy 239.051012 -117.910796) (xy 239.00982 -117.875107) (xy 238.974127 -117.833919) (xy 238.944659 -117.788069)
			(xy 238.922016 -117.738493) (xy 238.90666 -117.686199) (xy 238.898903 -117.632251) (xy 235.19057 -117.632251)
			(xy 235.19057 -117.632253) (xy 235.182814 -117.686204) (xy 235.167459 -117.738502) (xy 235.144817 -117.788083)
			(xy 235.115351 -117.833938) (xy 235.079659 -117.875132) (xy 235.038468 -117.910828) (xy 234.992617 -117.940299)
			(xy 234.943038 -117.962945) (xy 234.890741 -117.978306) (xy 234.836791 -117.986068) (xy 234.809538 -117.986556)
			(xy 233.945938 -117.986556) (xy 233.918687 -117.985999) (xy 233.864739 -117.978248) (xy 233.812443 -117.962897)
			(xy 233.762864 -117.940259) (xy 233.717012 -117.910796) (xy 233.67582 -117.875107) (xy 233.640127 -117.833919)
			(xy 233.610659 -117.788069) (xy 233.588016 -117.738493) (xy 233.57266 -117.686199) (xy 233.564903 -117.632251)
			(xy 2.509012 -117.632251) (xy 2.509012 -123.093988) (xy 227.217732 -123.093988) (xy 227.217732 -122.230388)
			(xy 227.218218 -122.203137) (xy 227.225974 -122.149189) (xy 227.241329 -122.096894) (xy 227.263971 -122.047317)
			(xy 227.293437 -122.001467) (xy 227.329128 -121.960276) (xy 227.370319 -121.924585) (xy 227.416169 -121.895119)
			(xy 227.465746 -121.872477) (xy 227.518041 -121.857122) (xy 227.571989 -121.849366) (xy 227.626491 -121.849366)
			(xy 227.680439 -121.857122) (xy 227.732734 -121.872477) (xy 227.782311 -121.895119) (xy 227.828161 -121.924585)
			(xy 227.869352 -121.960276) (xy 227.905043 -122.001467) (xy 227.934509 -122.047317) (xy 227.957151 -122.096894)
			(xy 227.972506 -122.149189) (xy 227.980262 -122.203137) (xy 227.980748 -122.230388) (xy 227.980748 -122.921014)
			(xy 245.563136 -122.921014) (xy 245.563136 -122.057414) (xy 245.563622 -122.030163) (xy 245.571378 -121.976215)
			(xy 245.586733 -121.92392) (xy 245.609375 -121.874343) (xy 245.638841 -121.828493) (xy 245.674532 -121.787302)
			(xy 245.715723 -121.751611) (xy 245.761573 -121.722145) (xy 245.81115 -121.699503) (xy 245.863445 -121.684148)
			(xy 245.917393 -121.676392) (xy 245.971895 -121.676392) (xy 246.025843 -121.684148) (xy 246.078138 -121.699503)
			(xy 246.127715 -121.722145) (xy 246.173565 -121.751611) (xy 246.214756 -121.787302) (xy 246.250447 -121.828493)
			(xy 246.279913 -121.874343) (xy 246.302555 -121.92392) (xy 246.31791 -121.976215) (xy 246.325666 -122.030163)
			(xy 246.326152 -122.057414) (xy 246.326152 -122.921014) (xy 246.325666 -122.948265) (xy 246.31791 -123.002213)
			(xy 246.302555 -123.054508) (xy 246.279913 -123.104085) (xy 246.250447 -123.149935) (xy 246.214756 -123.191126)
			(xy 246.173565 -123.226817) (xy 246.127715 -123.256283) (xy 246.078138 -123.278925) (xy 246.025843 -123.29428)
			(xy 245.971895 -123.302036) (xy 245.917393 -123.302036) (xy 245.863445 -123.29428) (xy 245.81115 -123.278925)
			(xy 245.761573 -123.256283) (xy 245.715723 -123.226817) (xy 245.674532 -123.191126) (xy 245.638841 -123.149935)
			(xy 245.609375 -123.104085) (xy 245.586733 -123.054508) (xy 245.571378 -123.002213) (xy 245.563622 -122.948265)
			(xy 245.563136 -122.921014) (xy 227.980748 -122.921014) (xy 227.980748 -123.093988) (xy 227.980262 -123.121239)
			(xy 227.972506 -123.175187) (xy 227.957151 -123.227482) (xy 227.934509 -123.277059) (xy 227.905043 -123.322909)
			(xy 227.869352 -123.3641) (xy 227.828161 -123.399791) (xy 227.782311 -123.429257) (xy 227.732734 -123.451899)
			(xy 227.680439 -123.467254) (xy 227.626491 -123.47501) (xy 227.571989 -123.47501) (xy 227.518041 -123.467254)
			(xy 227.465746 -123.451899) (xy 227.416169 -123.429257) (xy 227.370319 -123.399791) (xy 227.329128 -123.3641)
			(xy 227.293437 -123.322909) (xy 227.263971 -123.277059) (xy 227.241329 -123.227482) (xy 227.225974 -123.175187)
			(xy 227.218218 -123.121239) (xy 227.217732 -123.093988) (xy 2.509012 -123.093988) (xy 2.509012 -125.221746)
			(xy 225.535744 -125.221746) (xy 225.535744 -124.358146) (xy 225.53623 -124.330877) (xy 225.543992 -124.276893)
			(xy 225.559357 -124.224563) (xy 225.582014 -124.174953) (xy 225.6115 -124.129072) (xy 225.647215 -124.087855)
			(xy 225.688432 -124.05214) (xy 225.734313 -124.022654) (xy 225.783923 -123.999997) (xy 225.836253 -123.984632)
			(xy 225.890237 -123.97687) (xy 225.944775 -123.97687) (xy 225.998759 -123.984632) (xy 226.051089 -123.999997)
			(xy 226.100699 -124.022654) (xy 226.14658 -124.05214) (xy 226.187797 -124.087855) (xy 226.223512 -124.129072)
			(xy 226.252998 -124.174953) (xy 226.275655 -124.224563) (xy 226.29102 -124.276893) (xy 226.298782 -124.330877)
			(xy 226.299268 -124.358146) (xy 226.299268 -125.221746) (xy 226.298782 -125.249015) (xy 226.29102 -125.302999)
			(xy 226.275655 -125.355329) (xy 226.252998 -125.404939) (xy 226.223512 -125.45082) (xy 226.187797 -125.492037)
			(xy 226.14658 -125.527752) (xy 226.100699 -125.557238) (xy 226.051089 -125.579895) (xy 225.998759 -125.59526)
			(xy 225.944775 -125.603022) (xy 225.890237 -125.603022) (xy 225.836253 -125.59526) (xy 225.783923 -125.579895)
			(xy 225.734313 -125.557238) (xy 225.688432 -125.527752) (xy 225.647215 -125.492037) (xy 225.6115 -125.45082)
			(xy 225.582014 -125.404939) (xy 225.559357 -125.355329) (xy 225.543992 -125.302999) (xy 225.53623 -125.249015)
			(xy 225.535744 -125.221746) (xy 2.509012 -125.221746) (xy 2.509012 -127.325628) (xy 227.034852 -127.325628)
			(xy 227.034852 -126.462028) (xy 227.035338 -126.434777) (xy 227.043094 -126.380829) (xy 227.058449 -126.328534)
			(xy 227.081091 -126.278957) (xy 227.110557 -126.233107) (xy 227.146248 -126.191916) (xy 227.187439 -126.156225)
			(xy 227.233289 -126.126759) (xy 227.282866 -126.104117) (xy 227.335161 -126.088762) (xy 227.389109 -126.081006)
			(xy 227.443611 -126.081006) (xy 227.497559 -126.088762) (xy 227.549854 -126.104117) (xy 227.599431 -126.126759)
			(xy 227.645281 -126.156225) (xy 227.686472 -126.191916) (xy 227.722163 -126.233107) (xy 227.751629 -126.278957)
			(xy 227.774271 -126.328534) (xy 227.789626 -126.380829) (xy 227.797382 -126.434777) (xy 227.797868 -126.462028)
			(xy 227.797868 -127.140208) (xy 242.041172 -127.140208) (xy 242.041172 -126.276608) (xy 242.041658 -126.249357)
			(xy 242.049414 -126.195409) (xy 242.064769 -126.143114) (xy 242.087411 -126.093537) (xy 242.116877 -126.047687)
			(xy 242.152568 -126.006496) (xy 242.193759 -125.970805) (xy 242.239609 -125.941339) (xy 242.289186 -125.918697)
			(xy 242.341481 -125.903342) (xy 242.395429 -125.895586) (xy 242.449931 -125.895586) (xy 242.503879 -125.903342)
			(xy 242.556174 -125.918697) (xy 242.605751 -125.941339) (xy 242.651601 -125.970805) (xy 242.692792 -126.006496)
			(xy 242.728483 -126.047687) (xy 242.757949 -126.093537) (xy 242.780591 -126.143114) (xy 242.795946 -126.195409)
			(xy 242.803702 -126.249357) (xy 242.804188 -126.276608) (xy 242.804188 -127.140208) (xy 242.803702 -127.167459)
			(xy 242.795946 -127.221407) (xy 242.780591 -127.273702) (xy 242.757949 -127.323279) (xy 242.728483 -127.369129)
			(xy 242.692792 -127.41032) (xy 242.651601 -127.446011) (xy 242.605751 -127.475477) (xy 242.556174 -127.498119)
			(xy 242.503879 -127.513474) (xy 242.449931 -127.52123) (xy 242.395429 -127.52123) (xy 242.341481 -127.513474)
			(xy 242.289186 -127.498119) (xy 242.239609 -127.475477) (xy 242.193759 -127.446011) (xy 242.152568 -127.41032)
			(xy 242.116877 -127.369129) (xy 242.087411 -127.323279) (xy 242.064769 -127.273702) (xy 242.049414 -127.221407)
			(xy 242.041658 -127.167459) (xy 242.041172 -127.140208) (xy 227.797868 -127.140208) (xy 227.797868 -127.325628)
			(xy 227.797382 -127.352879) (xy 227.789626 -127.406827) (xy 227.774271 -127.459122) (xy 227.751629 -127.508699)
			(xy 227.722163 -127.554549) (xy 227.686472 -127.59574) (xy 227.645281 -127.631431) (xy 227.599431 -127.660897)
			(xy 227.549854 -127.683539) (xy 227.519478 -127.692458) (xy 458.401155 -127.692458) (xy 458.401155 -127.563318)
			(xy 458.409105 -127.434423) (xy 458.424975 -127.306263) (xy 458.448704 -127.179322) (xy 458.480203 -127.054083)
			(xy 458.519352 -126.93102) (xy 458.566003 -126.810601) (xy 458.619978 -126.693282) (xy 458.681073 -126.579508)
			(xy 458.749056 -126.469711) (xy 458.82367 -126.364308) (xy 458.904631 -126.263698) (xy 458.991631 -126.168263)
			(xy 459.084342 -126.078364) (xy 459.182412 -125.994343) (xy 459.285467 -125.916519) (xy 459.393118 -125.845187)
			(xy 459.504957 -125.780617) (xy 459.620558 -125.723055) (xy 459.739483 -125.672718) (xy 459.861282 -125.629798)
			(xy 459.985492 -125.594457) (xy 460.111641 -125.56683) (xy 460.239253 -125.547021) (xy 460.367842 -125.535105)
			(xy 460.49692 -125.531129) (xy 460.625998 -125.535105) (xy 460.754587 -125.547021) (xy 460.882199 -125.56683)
			(xy 461.008348 -125.594457) (xy 461.132558 -125.629798) (xy 461.254357 -125.672718) (xy 461.373282 -125.723055)
			(xy 461.488883 -125.780617) (xy 461.600722 -125.845187) (xy 461.708373 -125.916519) (xy 461.811428 -125.994343)
			(xy 461.909498 -126.078364) (xy 462.002209 -126.168263) (xy 462.089209 -126.263698) (xy 462.17017 -126.364308)
			(xy 462.244784 -126.469711) (xy 462.312767 -126.579508) (xy 462.373862 -126.693282) (xy 462.427837 -126.810601)
			(xy 462.474488 -126.93102) (xy 462.513637 -127.054083) (xy 462.545136 -127.179322) (xy 462.568865 -127.306263)
			(xy 462.584735 -127.434423) (xy 462.592685 -127.563318) (xy 462.593182 -127.627888) (xy 462.592685 -127.692458)
			(xy 462.584735 -127.821353) (xy 462.568865 -127.949513) (xy 462.545136 -128.076454) (xy 462.513637 -128.201693)
			(xy 462.474488 -128.324756) (xy 462.427837 -128.445175) (xy 462.373862 -128.562494) (xy 462.312767 -128.676268)
			(xy 462.244784 -128.786065) (xy 462.17017 -128.891468) (xy 462.089209 -128.992078) (xy 462.002209 -129.087513)
			(xy 461.909498 -129.177412) (xy 461.811428 -129.261433) (xy 461.708373 -129.339257) (xy 461.600722 -129.410589)
			(xy 461.488883 -129.475159) (xy 461.373282 -129.532721) (xy 461.254357 -129.583058) (xy 461.132558 -129.625978)
			(xy 461.008348 -129.661319) (xy 460.882199 -129.688946) (xy 460.754587 -129.708755) (xy 460.625998 -129.720671)
			(xy 460.49692 -129.724648) (xy 460.367842 -129.720671) (xy 460.239253 -129.708755) (xy 460.111641 -129.688946)
			(xy 459.985492 -129.661319) (xy 459.861282 -129.625978) (xy 459.739483 -129.583058) (xy 459.620558 -129.532721)
			(xy 459.504957 -129.475159) (xy 459.393118 -129.410589) (xy 459.285467 -129.339257) (xy 459.182412 -129.261433)
			(xy 459.084342 -129.177412) (xy 458.991631 -129.087513) (xy 458.904631 -128.992078) (xy 458.82367 -128.891468)
			(xy 458.749056 -128.786065) (xy 458.681073 -128.676268) (xy 458.619978 -128.562494) (xy 458.566003 -128.445175)
			(xy 458.519352 -128.324756) (xy 458.480203 -128.201693) (xy 458.448704 -128.076454) (xy 458.424975 -127.949513)
			(xy 458.409105 -127.821353) (xy 458.401155 -127.692458) (xy 227.519478 -127.692458) (xy 227.497559 -127.698894)
			(xy 227.443611 -127.70665) (xy 227.389109 -127.70665) (xy 227.335161 -127.698894) (xy 227.282866 -127.683539)
			(xy 227.233289 -127.660897) (xy 227.187439 -127.631431) (xy 227.146248 -127.59574) (xy 227.110557 -127.554549)
			(xy 227.081091 -127.508699) (xy 227.058449 -127.459122) (xy 227.043094 -127.406827) (xy 227.035338 -127.352879)
			(xy 227.034852 -127.325628) (xy 2.509012 -127.325628) (xy 2.509012 -129.073148) (xy 223.562672 -129.073148)
			(xy 223.562672 -128.209548) (xy 223.563115 -128.182788) (xy 223.570596 -128.129795) (xy 223.585403 -128.078365)
			(xy 223.607247 -128.029506) (xy 223.621092 -128.006602) (xy 223.636032 -127.983032) (xy 223.671662 -127.940084)
			(xy 223.713174 -127.902792) (xy 223.759681 -127.871951) (xy 223.810187 -127.848221) (xy 223.863614 -127.832109)
			(xy 223.918819 -127.823961) (xy 223.94672 -127.823468) (xy 223.973934 -127.823967) (xy 224.027808 -127.831715)
			(xy 224.080031 -127.84705) (xy 224.12954 -127.869661) (xy 224.175327 -127.899088) (xy 224.216462 -127.93473)
			(xy 224.252105 -127.975863) (xy 224.281533 -128.02165) (xy 224.304145 -128.071158) (xy 224.319483 -128.123381)
			(xy 224.327232 -128.177254) (xy 224.32772 -128.204468) (xy 224.32772 -128.204722) (xy 224.325942 -128.241552)
			(xy 224.325688 -128.243838) (xy 224.325688 -129.019808) (xy 240.086896 -129.019808) (xy 240.086896 -128.156208)
			(xy 240.087382 -128.128939) (xy 240.095144 -128.074955) (xy 240.110509 -128.022625) (xy 240.133166 -127.973015)
			(xy 240.162652 -127.927134) (xy 240.198367 -127.885917) (xy 240.239584 -127.850202) (xy 240.285465 -127.820716)
			(xy 240.335075 -127.798059) (xy 240.387405 -127.782694) (xy 240.441389 -127.774932) (xy 240.495927 -127.774932)
			(xy 240.549911 -127.782694) (xy 240.602241 -127.798059) (xy 240.651851 -127.820716) (xy 240.697732 -127.850202)
			(xy 240.738949 -127.885917) (xy 240.774664 -127.927134) (xy 240.80415 -127.973015) (xy 240.826807 -128.022625)
			(xy 240.842172 -128.074955) (xy 240.849934 -128.128939) (xy 240.85042 -128.156208) (xy 240.85042 -129.019808)
			(xy 240.849934 -129.047077) (xy 240.842172 -129.101061) (xy 240.826807 -129.153391) (xy 240.80415 -129.203001)
			(xy 240.774664 -129.248882) (xy 240.738949 -129.290099) (xy 240.697732 -129.325814) (xy 240.651851 -129.3553)
			(xy 240.602241 -129.377957) (xy 240.549911 -129.393322) (xy 240.495927 -129.401084) (xy 240.441389 -129.401084)
			(xy 240.387405 -129.393322) (xy 240.335075 -129.377957) (xy 240.285465 -129.3553) (xy 240.239584 -129.325814)
			(xy 240.198367 -129.290099) (xy 240.162652 -129.248882) (xy 240.133166 -129.203001) (xy 240.110509 -129.153391)
			(xy 240.095144 -129.101061) (xy 240.087382 -129.047077) (xy 240.086896 -129.019808) (xy 224.325688 -129.019808)
			(xy 224.325942 -129.022602) (xy 224.327226 -129.033861) (xy 224.328622 -129.056482) (xy 224.328736 -129.067814)
			(xy 224.328736 -129.068068) (xy 224.328226 -129.095352) (xy 224.320425 -129.14936) (xy 224.305035 -129.201713)
			(xy 224.282367 -129.251351) (xy 224.26803 -129.27457) (xy 224.253042 -129.297814) (xy 224.217376 -129.340083)
			(xy 224.175977 -129.376756) (xy 224.129714 -129.407061) (xy 224.079557 -129.430365) (xy 224.026559 -129.446176)
			(xy 223.971833 -129.454165) (xy 223.94418 -129.454656) (xy 223.91693 -129.454141) (xy 223.862986 -129.446383)
			(xy 223.810695 -129.431028) (xy 223.761121 -129.408388) (xy 223.715273 -129.378924) (xy 223.674084 -129.343236)
			(xy 223.638393 -129.30205) (xy 223.608926 -129.256204) (xy 223.586282 -129.206631) (xy 223.570923 -129.154341)
			(xy 223.563161 -129.100398) (xy 223.562672 -129.073148) (xy 2.509012 -129.073148) (xy 2.509012 -131.09702)
			(xy 228.682804 -131.09702) (xy 228.682804 -130.23342) (xy 228.68329 -130.206151) (xy 228.691052 -130.152167)
			(xy 228.706417 -130.099837) (xy 228.729074 -130.050227) (xy 228.75856 -130.004346) (xy 228.794275 -129.963129)
			(xy 228.835492 -129.927414) (xy 228.881373 -129.897928) (xy 228.930983 -129.875271) (xy 228.983313 -129.859906)
			(xy 229.037297 -129.852144) (xy 229.091835 -129.852144) (xy 229.145819 -129.859906) (xy 229.198149 -129.875271)
			(xy 229.247759 -129.897928) (xy 229.29364 -129.927414) (xy 229.334857 -129.963129) (xy 229.370572 -130.004346)
			(xy 229.400058 -130.050227) (xy 229.422715 -130.099837) (xy 229.43808 -130.152167) (xy 229.445842 -130.206151)
			(xy 229.446328 -130.23342) (xy 229.446328 -130.721608) (xy 242.041172 -130.721608) (xy 242.041172 -129.858008)
			(xy 242.041658 -129.830757) (xy 242.049414 -129.776809) (xy 242.064769 -129.724514) (xy 242.087411 -129.674937)
			(xy 242.116877 -129.629087) (xy 242.152568 -129.587896) (xy 242.193759 -129.552205) (xy 242.239609 -129.522739)
			(xy 242.289186 -129.500097) (xy 242.341481 -129.484742) (xy 242.395429 -129.476986) (xy 242.449931 -129.476986)
			(xy 242.503879 -129.484742) (xy 242.556174 -129.500097) (xy 242.605751 -129.522739) (xy 242.651601 -129.552205)
			(xy 242.692792 -129.587896) (xy 242.728483 -129.629087) (xy 242.757949 -129.674937) (xy 242.780591 -129.724514)
			(xy 242.795946 -129.776809) (xy 242.803702 -129.830757) (xy 242.804188 -129.858008) (xy 242.804188 -130.721608)
			(xy 242.803702 -130.748859) (xy 242.795946 -130.802807) (xy 242.780591 -130.855102) (xy 242.757949 -130.904679)
			(xy 242.728483 -130.950529) (xy 242.692792 -130.99172) (xy 242.651601 -131.027411) (xy 242.605751 -131.056877)
			(xy 242.556174 -131.079519) (xy 242.503879 -131.094874) (xy 242.449931 -131.10263) (xy 242.395429 -131.10263)
			(xy 242.341481 -131.094874) (xy 242.289186 -131.079519) (xy 242.239609 -131.056877) (xy 242.193759 -131.027411)
			(xy 242.152568 -130.99172) (xy 242.116877 -130.950529) (xy 242.087411 -130.904679) (xy 242.064769 -130.855102)
			(xy 242.049414 -130.802807) (xy 242.041658 -130.748859) (xy 242.041172 -130.721608) (xy 229.446328 -130.721608)
			(xy 229.446328 -131.09702) (xy 229.445842 -131.124289) (xy 229.43808 -131.178273) (xy 229.422715 -131.230603)
			(xy 229.400058 -131.280213) (xy 229.370572 -131.326094) (xy 229.334857 -131.367311) (xy 229.29364 -131.403026)
			(xy 229.247759 -131.432512) (xy 229.198149 -131.455169) (xy 229.145819 -131.470534) (xy 229.091835 -131.478296)
			(xy 229.037297 -131.478296) (xy 228.983313 -131.470534) (xy 228.930983 -131.455169) (xy 228.881373 -131.432512)
			(xy 228.835492 -131.403026) (xy 228.794275 -131.367311) (xy 228.75856 -131.326094) (xy 228.729074 -131.280213)
			(xy 228.706417 -131.230603) (xy 228.691052 -131.178273) (xy 228.68329 -131.124289) (xy 228.682804 -131.09702)
			(xy 2.509012 -131.09702) (xy 2.509012 -132.529347) (xy 231.621126 -132.529347) (xy 231.621126 -132.474853)
			(xy 231.628881 -132.420915) (xy 231.644233 -132.368628) (xy 231.666869 -132.319059) (xy 231.69633 -132.273216)
			(xy 231.732014 -132.232031) (xy 231.773196 -132.196344) (xy 231.819038 -132.166881) (xy 231.868606 -132.144241)
			(xy 231.920891 -132.128886) (xy 231.974829 -132.121128) (xy 232.002076 -132.12064) (xy 232.865676 -132.12064)
			(xy 232.892933 -132.121005) (xy 232.946894 -132.128761) (xy 232.999201 -132.144116) (xy 233.048791 -132.16676)
			(xy 233.094653 -132.196231) (xy 233.135853 -132.23193) (xy 233.171554 -132.273128) (xy 233.201028 -132.318988)
			(xy 233.223675 -132.368576) (xy 233.239034 -132.420883) (xy 233.246793 -132.474843) (xy 233.246793 -132.529357)
			(xy 233.239034 -132.583317) (xy 233.223675 -132.635624) (xy 233.201028 -132.685212) (xy 233.171554 -132.731072)
			(xy 233.135853 -132.77227) (xy 233.094653 -132.807968) (xy 233.048791 -132.83744) (xy 232.999201 -132.860084)
			(xy 232.946894 -132.875439) (xy 232.892933 -132.883195) (xy 232.865676 -132.883656) (xy 232.002076 -132.883656)
			(xy 231.974829 -132.883072) (xy 231.920891 -132.875314) (xy 231.868606 -132.859959) (xy 231.819038 -132.837319)
			(xy 231.773196 -132.807856) (xy 231.732014 -132.772169) (xy 231.69633 -132.730984) (xy 231.666869 -132.685141)
			(xy 231.644233 -132.635572) (xy 231.628881 -132.583285) (xy 231.621126 -132.529347) (xy 2.509012 -132.529347)
			(xy 2.509012 -135.31065) (xy 225.204003 -135.31065) (xy 225.204003 -135.25615) (xy 225.21176 -135.202204)
			(xy 225.227115 -135.149911) (xy 225.249756 -135.100336) (xy 225.279222 -135.054487) (xy 225.314914 -135.013299)
			(xy 225.356103 -134.97761) (xy 225.401953 -134.948146) (xy 225.45153 -134.925508) (xy 225.503823 -134.910156)
			(xy 225.55777 -134.902402) (xy 225.58502 -134.90194) (xy 226.44862 -134.90194) (xy 226.475874 -134.902331)
			(xy 226.529826 -134.910091) (xy 226.582125 -134.92545) (xy 226.631706 -134.948095) (xy 226.67756 -134.977566)
			(xy 226.718753 -135.013262) (xy 226.754446 -135.054456) (xy 226.755856 -135.05665) (xy 228.531403 -135.05665)
			(xy 228.531403 -135.00215) (xy 228.53916 -134.948204) (xy 228.554515 -134.895911) (xy 228.577156 -134.846336)
			(xy 228.606622 -134.800487) (xy 228.642314 -134.759299) (xy 228.683503 -134.72361) (xy 228.729353 -134.694146)
			(xy 228.77893 -134.671508) (xy 228.831223 -134.656156) (xy 228.88517 -134.648402) (xy 228.91242 -134.64794)
			(xy 229.77602 -134.64794) (xy 229.803274 -134.648331) (xy 229.857226 -134.656091) (xy 229.909525 -134.67145)
			(xy 229.959106 -134.694095) (xy 230.00496 -134.723566) (xy 230.046153 -134.759262) (xy 230.081846 -134.800456)
			(xy 230.111315 -134.846312) (xy 230.133957 -134.895894) (xy 230.149313 -134.948193) (xy 230.15707 -135.002146)
			(xy 230.15707 -135.056654) (xy 230.149313 -135.110607) (xy 230.145996 -135.121904) (xy 234.029504 -135.121904)
			(xy 234.029504 -134.258304) (xy 234.02999 -134.231035) (xy 234.037752 -134.177051) (xy 234.053117 -134.124721)
			(xy 234.075774 -134.075111) (xy 234.10526 -134.02923) (xy 234.140975 -133.988013) (xy 234.182192 -133.952298)
			(xy 234.228073 -133.922812) (xy 234.277683 -133.900155) (xy 234.330013 -133.88479) (xy 234.383997 -133.877028)
			(xy 234.438535 -133.877028) (xy 234.492519 -133.88479) (xy 234.544849 -133.900155) (xy 234.594459 -133.922812)
			(xy 234.64034 -133.952298) (xy 234.681557 -133.988013) (xy 234.717272 -134.02923) (xy 234.746758 -134.075111)
			(xy 234.769415 -134.124721) (xy 234.78478 -134.177051) (xy 234.792542 -134.231035) (xy 234.793028 -134.258304)
			(xy 234.793028 -134.768971) (xy 236.02439 -134.768971) (xy 236.02439 -134.714429) (xy 236.032152 -134.660443)
			(xy 236.047518 -134.608111) (xy 236.070174 -134.558498) (xy 236.09966 -134.512615) (xy 236.135376 -134.471394)
			(xy 236.176594 -134.435676) (xy 236.222475 -134.406186) (xy 236.272087 -134.383527) (xy 236.324418 -134.368158)
			(xy 236.378403 -134.360392) (xy 236.405674 -134.359904) (xy 237.178342 -134.359904) (xy 237.205607 -134.360461)
			(xy 237.259581 -134.368227) (xy 237.311901 -134.383595) (xy 237.361502 -134.406251) (xy 237.407373 -134.435736)
			(xy 237.448582 -134.471448) (xy 237.48429 -134.512661) (xy 237.513769 -134.558535) (xy 237.53642 -134.608138)
			(xy 237.551782 -134.66046) (xy 237.559542 -134.714435) (xy 237.559542 -134.768965) (xy 237.551782 -134.82294)
			(xy 237.53642 -134.875262) (xy 237.513769 -134.924865) (xy 237.48429 -134.970739) (xy 237.448582 -135.011952)
			(xy 237.407373 -135.047664) (xy 237.361502 -135.077149) (xy 237.311901 -135.099805) (xy 237.259581 -135.115173)
			(xy 237.205607 -135.122939) (xy 237.178342 -135.123428) (xy 236.405674 -135.123428) (xy 236.378403 -135.123008)
			(xy 236.324418 -135.115242) (xy 236.272087 -135.099873) (xy 236.222475 -135.077214) (xy 236.176594 -135.047724)
			(xy 236.135376 -135.012006) (xy 236.09966 -134.970785) (xy 236.070174 -134.924902) (xy 236.047518 -134.875289)
			(xy 236.032152 -134.822957) (xy 236.02439 -134.768971) (xy 234.793028 -134.768971) (xy 234.793028 -135.121904)
			(xy 234.792542 -135.149173) (xy 234.786383 -135.192008) (xy 238.645192 -135.192008) (xy 238.645192 -134.328408)
			(xy 238.645678 -134.301157) (xy 238.653434 -134.247209) (xy 238.668789 -134.194914) (xy 238.691431 -134.145337)
			(xy 238.720897 -134.099487) (xy 238.756588 -134.058296) (xy 238.797779 -134.022605) (xy 238.843629 -133.993139)
			(xy 238.893206 -133.970497) (xy 238.945501 -133.955142) (xy 238.999449 -133.947386) (xy 239.053951 -133.947386)
			(xy 239.107899 -133.955142) (xy 239.160194 -133.970497) (xy 239.209771 -133.993139) (xy 239.255621 -134.022605)
			(xy 239.271831 -134.036651) (xy 242.034062 -134.036651) (xy 242.034062 -133.982149) (xy 242.041817 -133.928203)
			(xy 242.057171 -133.875909) (xy 242.07981 -133.826333) (xy 242.109274 -133.780482) (xy 242.144963 -133.739291)
			(xy 242.18615 -133.703598) (xy 242.231997 -133.67413) (xy 242.281572 -133.651485) (xy 242.333864 -133.636126)
			(xy 242.387809 -133.628365) (xy 242.41506 -133.627876) (xy 243.27866 -133.627876) (xy 243.305914 -133.628369)
			(xy 243.359867 -133.636121) (xy 243.412167 -133.651473) (xy 243.46175 -133.674112) (xy 243.507606 -133.703577)
			(xy 243.548802 -133.73927) (xy 243.584499 -133.780462) (xy 243.613969 -133.826315) (xy 243.636613 -133.875895)
			(xy 243.651971 -133.928194) (xy 243.659729 -133.982146) (xy 243.659729 -134.036654) (xy 243.651971 -134.090606)
			(xy 243.636613 -134.142905) (xy 243.613969 -134.192485) (xy 243.584499 -134.238338) (xy 243.548802 -134.27953)
			(xy 243.507606 -134.315223) (xy 243.46175 -134.344688) (xy 243.412167 -134.367327) (xy 243.359867 -134.382679)
			(xy 243.305914 -134.390431) (xy 243.27866 -134.390892) (xy 242.41506 -134.390892) (xy 242.387809 -134.390435)
			(xy 242.333864 -134.382674) (xy 242.281572 -134.367315) (xy 242.231997 -134.34467) (xy 242.18615 -134.315202)
			(xy 242.144963 -134.279509) (xy 242.109274 -134.238318) (xy 242.07981 -134.192467) (xy 242.057171 -134.142891)
			(xy 242.041817 -134.090597) (xy 242.034062 -134.036651) (xy 239.271831 -134.036651) (xy 239.296812 -134.058296)
			(xy 239.332503 -134.099487) (xy 239.361969 -134.145337) (xy 239.384611 -134.194914) (xy 239.399966 -134.247209)
			(xy 239.407722 -134.301157) (xy 239.408208 -134.328408) (xy 239.408208 -135.192008) (xy 239.407722 -135.219259)
			(xy 239.399966 -135.273207) (xy 239.384611 -135.325502) (xy 239.361969 -135.375079) (xy 239.332503 -135.420929)
			(xy 239.296812 -135.46212) (xy 239.255621 -135.497811) (xy 239.250425 -135.50115) (xy 244.457203 -135.50115)
			(xy 244.457203 -135.44665) (xy 244.46496 -135.392704) (xy 244.480315 -135.340411) (xy 244.502956 -135.290836)
			(xy 244.532422 -135.244987) (xy 244.568114 -135.203799) (xy 244.609303 -135.16811) (xy 244.655153 -135.138646)
			(xy 244.70473 -135.116008) (xy 244.757023 -135.100656) (xy 244.81097 -135.092902) (xy 244.83822 -135.09244)
			(xy 245.70182 -135.09244) (xy 245.729074 -135.092831) (xy 245.783026 -135.100591) (xy 245.835325 -135.11595)
			(xy 245.884906 -135.138595) (xy 245.93076 -135.168066) (xy 245.971953 -135.203762) (xy 246.007646 -135.244956)
			(xy 246.037115 -135.290812) (xy 246.059757 -135.340394) (xy 246.075113 -135.392693) (xy 246.08287 -135.446646)
			(xy 246.08287 -135.501154) (xy 246.075113 -135.555107) (xy 246.059757 -135.607406) (xy 246.037115 -135.656988)
			(xy 246.007646 -135.702844) (xy 245.971953 -135.744038) (xy 245.93076 -135.779734) (xy 245.884906 -135.809205)
			(xy 245.835325 -135.83185) (xy 245.783026 -135.847209) (xy 245.729074 -135.854969) (xy 245.70182 -135.855456)
			(xy 244.83822 -135.855456) (xy 244.81097 -135.854898) (xy 244.757023 -135.847144) (xy 244.70473 -135.831792)
			(xy 244.655153 -135.809154) (xy 244.609303 -135.77969) (xy 244.568114 -135.744001) (xy 244.532422 -135.702813)
			(xy 244.502956 -135.656964) (xy 244.480315 -135.607389) (xy 244.46496 -135.555096) (xy 244.457203 -135.50115)
			(xy 239.250425 -135.50115) (xy 239.209771 -135.527277) (xy 239.160194 -135.549919) (xy 239.107899 -135.565274)
			(xy 239.053951 -135.57303) (xy 238.999449 -135.57303) (xy 238.945501 -135.565274) (xy 238.893206 -135.549919)
			(xy 238.843629 -135.527277) (xy 238.797779 -135.497811) (xy 238.756588 -135.46212) (xy 238.720897 -135.420929)
			(xy 238.691431 -135.375079) (xy 238.668789 -135.325502) (xy 238.653434 -135.273207) (xy 238.645678 -135.219259)
			(xy 238.645192 -135.192008) (xy 234.786383 -135.192008) (xy 234.78478 -135.203157) (xy 234.769415 -135.255487)
			(xy 234.746758 -135.305097) (xy 234.717272 -135.350978) (xy 234.681557 -135.392195) (xy 234.64034 -135.42791)
			(xy 234.594459 -135.457396) (xy 234.544849 -135.480053) (xy 234.492519 -135.495418) (xy 234.438535 -135.50318)
			(xy 234.383997 -135.50318) (xy 234.330013 -135.495418) (xy 234.277683 -135.480053) (xy 234.228073 -135.457396)
			(xy 234.182192 -135.42791) (xy 234.140975 -135.392195) (xy 234.10526 -135.350978) (xy 234.075774 -135.305097)
			(xy 234.053117 -135.255487) (xy 234.037752 -135.203157) (xy 234.02999 -135.149173) (xy 234.029504 -135.121904)
			(xy 230.145996 -135.121904) (xy 230.133957 -135.162906) (xy 230.111315 -135.212488) (xy 230.081846 -135.258344)
			(xy 230.046153 -135.299538) (xy 230.00496 -135.335234) (xy 229.959106 -135.364705) (xy 229.909525 -135.38735)
			(xy 229.857226 -135.402709) (xy 229.803274 -135.410469) (xy 229.77602 -135.410956) (xy 228.91242 -135.410956)
			(xy 228.88517 -135.410398) (xy 228.831223 -135.402644) (xy 228.77893 -135.387292) (xy 228.729353 -135.364654)
			(xy 228.683503 -135.33519) (xy 228.642314 -135.299501) (xy 228.606622 -135.258313) (xy 228.577156 -135.212464)
			(xy 228.554515 -135.162889) (xy 228.53916 -135.110596) (xy 228.531403 -135.05665) (xy 226.755856 -135.05665)
			(xy 226.783915 -135.100312) (xy 226.806557 -135.149894) (xy 226.821913 -135.202193) (xy 226.82967 -135.256146)
			(xy 226.82967 -135.310654) (xy 226.821913 -135.364607) (xy 226.806557 -135.416906) (xy 226.783915 -135.466488)
			(xy 226.754446 -135.512344) (xy 226.718753 -135.553538) (xy 226.67756 -135.589234) (xy 226.631706 -135.618705)
			(xy 226.582125 -135.64135) (xy 226.529826 -135.656709) (xy 226.475874 -135.664469) (xy 226.44862 -135.664956)
			(xy 225.58502 -135.664956) (xy 225.55777 -135.664398) (xy 225.503823 -135.656644) (xy 225.45153 -135.641292)
			(xy 225.401953 -135.618654) (xy 225.356103 -135.58919) (xy 225.314914 -135.553501) (xy 225.279222 -135.512313)
			(xy 225.249756 -135.466464) (xy 225.227115 -135.416889) (xy 225.21176 -135.364596) (xy 225.204003 -135.31065)
			(xy 2.509012 -135.31065) (xy 2.509012 -137.199664) (xy 337.46447 -137.199664) (xy 337.46447 -137.145136)
			(xy 337.47223 -137.091163) (xy 337.487591 -137.038843) (xy 337.510241 -136.989242) (xy 337.539719 -136.943369)
			(xy 337.575425 -136.902158) (xy 337.616632 -136.866447) (xy 337.662502 -136.836963) (xy 337.7121 -136.814307)
			(xy 337.764418 -136.79894) (xy 337.81839 -136.791173) (xy 337.845654 -136.790684) (xy 338.618322 -136.790684)
			(xy 338.645594 -136.79108) (xy 338.699581 -136.798845) (xy 338.751915 -136.814214) (xy 338.801528 -136.836874)
			(xy 338.847412 -136.866364) (xy 338.888632 -136.902084) (xy 338.924349 -136.943306) (xy 338.953836 -136.989191)
			(xy 338.976493 -137.038806) (xy 338.991859 -137.09114) (xy 338.999622 -137.145128) (xy 338.999622 -137.199672)
			(xy 338.991859 -137.25366) (xy 338.976493 -137.305994) (xy 338.953836 -137.355609) (xy 338.924349 -137.401494)
			(xy 338.888632 -137.442716) (xy 338.847412 -137.478436) (xy 338.801528 -137.507926) (xy 338.751915 -137.530586)
			(xy 338.699581 -137.545955) (xy 338.645594 -137.55372) (xy 338.618322 -137.554208) (xy 337.845654 -137.554208)
			(xy 337.81839 -137.553627) (xy 337.764418 -137.54586) (xy 337.7121 -137.530493) (xy 337.662502 -137.507837)
			(xy 337.616632 -137.478353) (xy 337.575425 -137.442642) (xy 337.539719 -137.401431) (xy 337.510241 -137.355558)
			(xy 337.487591 -137.305957) (xy 337.47223 -137.253637) (xy 337.46447 -137.199664) (xy 2.509012 -137.199664)
			(xy 2.509012 -137.622788) (xy 340.085172 -137.622788) (xy 340.085172 -136.759188) (xy 340.085658 -136.731937)
			(xy 340.093414 -136.677989) (xy 340.108769 -136.625694) (xy 340.131411 -136.576117) (xy 340.160877 -136.530267)
			(xy 340.196568 -136.489076) (xy 340.237759 -136.453385) (xy 340.283609 -136.423919) (xy 340.333186 -136.401277)
			(xy 340.385481 -136.385922) (xy 340.439429 -136.378166) (xy 340.493931 -136.378166) (xy 340.547879 -136.385922)
			(xy 340.600174 -136.401277) (xy 340.649751 -136.423919) (xy 340.695601 -136.453385) (xy 340.736792 -136.489076)
			(xy 340.772483 -136.530267) (xy 340.801949 -136.576117) (xy 340.824591 -136.625694) (xy 340.839946 -136.677989)
			(xy 340.847702 -136.731937) (xy 340.848188 -136.759188) (xy 340.848188 -137.622788) (xy 340.847702 -137.650039)
			(xy 340.839946 -137.703987) (xy 340.824591 -137.756282) (xy 340.801949 -137.805859) (xy 340.772483 -137.851709)
			(xy 340.736792 -137.8929) (xy 340.695601 -137.928591) (xy 340.649751 -137.958057) (xy 340.600174 -137.980699)
			(xy 340.547879 -137.996054) (xy 340.493931 -138.00381) (xy 340.439429 -138.00381) (xy 340.385481 -137.996054)
			(xy 340.333186 -137.980699) (xy 340.283609 -137.958057) (xy 340.237759 -137.928591) (xy 340.196568 -137.8929)
			(xy 340.160877 -137.851709) (xy 340.131411 -137.805859) (xy 340.108769 -137.756282) (xy 340.093414 -137.703987)
			(xy 340.085658 -137.650039) (xy 340.085172 -137.622788) (xy 2.509012 -137.622788) (xy 2.509012 -153.766012)
			(xy 24.445731 -153.766012) (xy 24.449724 -153.556271) (xy 24.4617 -153.346834) (xy 24.481641 -153.138005)
			(xy 24.509518 -152.930086) (xy 24.54529 -152.723379) (xy 24.588905 -152.518184) (xy 24.640301 -152.314799)
			(xy 24.699403 -152.113517) (xy 24.766125 -151.914631) (xy 24.84037 -151.71843) (xy 24.92203 -151.525198)
			(xy 25.010988 -151.335214) (xy 25.107115 -151.148755) (xy 25.21027 -150.966091) (xy 25.320305 -150.787486)
			(xy 25.437059 -150.6132) (xy 25.560364 -150.443485) (xy 25.690041 -150.278587) (xy 25.825902 -150.118746)
			(xy 25.967749 -149.964193) (xy 26.115378 -149.815153) (xy 26.268573 -149.67184) (xy 26.427114 -149.534464)
			(xy 26.590769 -149.403223) (xy 26.759303 -149.278308) (xy 26.932469 -149.1599) (xy 27.110019 -149.04817)
			(xy 27.291693 -148.94328) (xy 27.477228 -148.845383) (xy 27.666356 -148.754621) (xy 27.858803 -148.671124)
			(xy 28.054288 -148.595014) (xy 28.25253 -148.526402) (xy 28.45324 -148.465387) (xy 28.656127 -148.412058)
			(xy 28.860897 -148.366491) (xy 29.067254 -148.328752) (xy 29.274898 -148.298898) (xy 29.483528 -148.27697)
			(xy 29.692841 -148.263001) (xy 29.902535 -148.25701) (xy 30.112304 -148.259007) (xy 30.321846 -148.268989)
			(xy 30.530856 -148.286941) (xy 30.73903 -148.312837) (xy 30.946068 -148.346639) (xy 31.151669 -148.388299)
			(xy 31.355535 -148.437757) (xy 31.55737 -148.49494) (xy 31.756882 -148.559765) (xy 31.953781 -148.632139)
			(xy 32.147782 -148.711956) (xy 32.338604 -148.799102) (xy 32.52597 -148.893449) (xy 32.709608 -148.99486)
			(xy 32.889252 -149.10319) (xy 33.064642 -149.21828) (xy 33.235523 -149.339964) (xy 33.401647 -149.468065)
			(xy 33.562774 -149.602398) (xy 33.718671 -149.742767) (xy 33.86911 -149.88897) (xy 34.013874 -150.040794)
			(xy 34.152753 -150.19802) (xy 34.285546 -150.360419) (xy 34.41206 -150.527755) (xy 34.532112 -150.699787)
			(xy 34.645527 -150.876264) (xy 34.752141 -151.056932) (xy 34.8518 -151.241527) (xy 34.944359 -151.429782)
			(xy 35.029684 -151.621425) (xy 35.107651 -151.816177) (xy 35.178147 -152.013757) (xy 35.24107 -152.213876)
			(xy 35.296329 -152.416247) (xy 35.343843 -152.620574) (xy 35.383544 -152.826562) (xy 35.415374 -153.033913)
			(xy 35.439287 -153.242324) (xy 35.455248 -153.451495) (xy 35.463235 -153.661122) (xy 35.463734 -153.766012)
			(xy 35.463235 -153.870902) (xy 35.455248 -154.080529) (xy 35.44312 -154.239468) (xy 186.742832 -154.239468)
			(xy 186.742832 -153.375868) (xy 186.743318 -153.348617) (xy 186.751074 -153.294669) (xy 186.766429 -153.242374)
			(xy 186.789071 -153.192797) (xy 186.818537 -153.146947) (xy 186.854228 -153.105756) (xy 186.895419 -153.070065)
			(xy 186.941269 -153.040599) (xy 186.990846 -153.017957) (xy 187.043141 -153.002602) (xy 187.097089 -152.994846)
			(xy 187.151591 -152.994846) (xy 187.205539 -153.002602) (xy 187.257834 -153.017957) (xy 187.307411 -153.040599)
			(xy 187.353261 -153.070065) (xy 187.394452 -153.105756) (xy 187.430143 -153.146947) (xy 187.459609 -153.192797)
			(xy 187.482251 -153.242374) (xy 187.497606 -153.294669) (xy 187.505362 -153.348617) (xy 187.505848 -153.375868)
			(xy 187.505848 -153.774902) (xy 188.445657 -153.774902) (xy 188.44965 -153.565161) (xy 188.461626 -153.355724)
			(xy 188.481567 -153.146895) (xy 188.509444 -152.938976) (xy 188.545216 -152.732269) (xy 188.588831 -152.527074)
			(xy 188.640227 -152.323689) (xy 188.699329 -152.122407) (xy 188.766051 -151.923521) (xy 188.840296 -151.72732)
			(xy 188.921956 -151.534088) (xy 189.010914 -151.344104) (xy 189.107041 -151.157645) (xy 189.210196 -150.974981)
			(xy 189.320231 -150.796376) (xy 189.436985 -150.62209) (xy 189.56029 -150.452375) (xy 189.689967 -150.287477)
			(xy 189.825828 -150.127636) (xy 189.967675 -149.973083) (xy 190.115304 -149.824043) (xy 190.268499 -149.68073)
			(xy 190.42704 -149.543354) (xy 190.590695 -149.412113) (xy 190.759229 -149.287198) (xy 190.932395 -149.16879)
			(xy 191.109945 -149.05706) (xy 191.291619 -148.95217) (xy 191.477154 -148.854273) (xy 191.666282 -148.763511)
			(xy 191.858729 -148.680014) (xy 192.054214 -148.603904) (xy 192.252456 -148.535292) (xy 192.453166 -148.474277)
			(xy 192.656053 -148.420948) (xy 192.860823 -148.375381) (xy 193.06718 -148.337642) (xy 193.274824 -148.307788)
			(xy 193.483454 -148.28586) (xy 193.692767 -148.271891) (xy 193.902461 -148.2659) (xy 194.11223 -148.267897)
			(xy 194.321772 -148.277879) (xy 194.530782 -148.295831) (xy 194.738956 -148.321727) (xy 194.945994 -148.355529)
			(xy 195.151595 -148.397189) (xy 195.355461 -148.446647) (xy 195.557296 -148.50383) (xy 195.756808 -148.568655)
			(xy 195.953707 -148.641029) (xy 196.147708 -148.720846) (xy 196.33853 -148.807992) (xy 196.525896 -148.902339)
			(xy 196.709534 -149.00375) (xy 196.889178 -149.11208) (xy 197.064568 -149.22717) (xy 197.235449 -149.348854)
			(xy 197.401573 -149.476955) (xy 197.5627 -149.611288) (xy 197.718597 -149.751657) (xy 197.869036 -149.89786)
			(xy 198.0138 -150.049684) (xy 198.152679 -150.20691) (xy 198.285472 -150.369309) (xy 198.411986 -150.536645)
			(xy 198.532038 -150.708677) (xy 198.645453 -150.885154) (xy 198.752067 -151.065822) (xy 198.851726 -151.250417)
			(xy 198.944285 -151.438672) (xy 199.02961 -151.630315) (xy 199.107577 -151.825067) (xy 199.178073 -152.022647)
			(xy 199.240996 -152.222766) (xy 199.296255 -152.425137) (xy 199.343769 -152.629464) (xy 199.38347 -152.835452)
			(xy 199.4153 -153.042803) (xy 199.439213 -153.251214) (xy 199.455174 -153.460385) (xy 199.463161 -153.670012)
			(xy 199.463618 -153.766012) (xy 272.385799 -153.766012) (xy 272.389792 -153.556271) (xy 272.401768 -153.346834)
			(xy 272.421709 -153.138005) (xy 272.449586 -152.930086) (xy 272.485358 -152.723379) (xy 272.528973 -152.518184)
			(xy 272.580369 -152.314799) (xy 272.639471 -152.113517) (xy 272.706193 -151.914631) (xy 272.780438 -151.71843)
			(xy 272.862098 -151.525198) (xy 272.951056 -151.335214) (xy 273.047183 -151.148755) (xy 273.150338 -150.966091)
			(xy 273.260373 -150.787486) (xy 273.377127 -150.6132) (xy 273.500432 -150.443485) (xy 273.630109 -150.278587)
			(xy 273.76597 -150.118746) (xy 273.907817 -149.964193) (xy 274.055446 -149.815153) (xy 274.208641 -149.67184)
			(xy 274.367182 -149.534464) (xy 274.530837 -149.403223) (xy 274.699371 -149.278308) (xy 274.872537 -149.1599)
			(xy 275.050087 -149.04817) (xy 275.231761 -148.94328) (xy 275.417296 -148.845383) (xy 275.606424 -148.754621)
			(xy 275.798871 -148.671124) (xy 275.994356 -148.595014) (xy 276.192598 -148.526402) (xy 276.393308 -148.465387)
			(xy 276.596195 -148.412058) (xy 276.800965 -148.366491) (xy 277.007322 -148.328752) (xy 277.214966 -148.298898)
			(xy 277.423596 -148.27697) (xy 277.632909 -148.263001) (xy 277.842603 -148.25701) (xy 278.052372 -148.259007)
			(xy 278.261914 -148.268989) (xy 278.470924 -148.286941) (xy 278.679098 -148.312837) (xy 278.886136 -148.346639)
			(xy 279.091737 -148.388299) (xy 279.295603 -148.437757) (xy 279.497438 -148.49494) (xy 279.69695 -148.559765)
			(xy 279.893849 -148.632139) (xy 280.08785 -148.711956) (xy 280.278672 -148.799102) (xy 280.466038 -148.893449)
			(xy 280.649676 -148.99486) (xy 280.82932 -149.10319) (xy 281.00471 -149.21828) (xy 281.175591 -149.339964)
			(xy 281.341715 -149.468065) (xy 281.502842 -149.602398) (xy 281.658739 -149.742767) (xy 281.809178 -149.88897)
			(xy 281.953942 -150.040794) (xy 282.092821 -150.19802) (xy 282.225614 -150.360419) (xy 282.352128 -150.527755)
			(xy 282.47218 -150.699787) (xy 282.585595 -150.876264) (xy 282.692209 -151.056932) (xy 282.791868 -151.241527)
			(xy 282.884427 -151.429782) (xy 282.969752 -151.621425) (xy 283.047719 -151.816177) (xy 283.118215 -152.013757)
			(xy 283.181138 -152.213876) (xy 283.236397 -152.416247) (xy 283.283911 -152.620574) (xy 283.323612 -152.826562)
			(xy 283.355442 -153.033913) (xy 283.379355 -153.242324) (xy 283.395316 -153.451495) (xy 283.403303 -153.661122)
			(xy 283.403802 -153.766012) (xy 283.40376 -153.774902) (xy 436.385725 -153.774902) (xy 436.389718 -153.565161)
			(xy 436.401694 -153.355724) (xy 436.421635 -153.146895) (xy 436.449512 -152.938976) (xy 436.485284 -152.732269)
			(xy 436.528899 -152.527074) (xy 436.580295 -152.323689) (xy 436.639397 -152.122407) (xy 436.706119 -151.923521)
			(xy 436.780364 -151.72732) (xy 436.862024 -151.534088) (xy 436.950982 -151.344104) (xy 437.047109 -151.157645)
			(xy 437.150264 -150.974981) (xy 437.260299 -150.796376) (xy 437.377053 -150.62209) (xy 437.500358 -150.452375)
			(xy 437.630035 -150.287477) (xy 437.765896 -150.127636) (xy 437.907743 -149.973083) (xy 438.055372 -149.824043)
			(xy 438.208567 -149.68073) (xy 438.367108 -149.543354) (xy 438.530763 -149.412113) (xy 438.699297 -149.287198)
			(xy 438.872463 -149.16879) (xy 439.050013 -149.05706) (xy 439.231687 -148.95217) (xy 439.417222 -148.854273)
			(xy 439.60635 -148.763511) (xy 439.798797 -148.680014) (xy 439.994282 -148.603904) (xy 440.192524 -148.535292)
			(xy 440.393234 -148.474277) (xy 440.596121 -148.420948) (xy 440.800891 -148.375381) (xy 441.007248 -148.337642)
			(xy 441.214892 -148.307788) (xy 441.423522 -148.28586) (xy 441.632835 -148.271891) (xy 441.842529 -148.2659)
			(xy 442.052298 -148.267897) (xy 442.26184 -148.277879) (xy 442.47085 -148.295831) (xy 442.679024 -148.321727)
			(xy 442.886062 -148.355529) (xy 443.091663 -148.397189) (xy 443.295529 -148.446647) (xy 443.497364 -148.50383)
			(xy 443.696876 -148.568655) (xy 443.893775 -148.641029) (xy 444.087776 -148.720846) (xy 444.278598 -148.807992)
			(xy 444.465964 -148.902339) (xy 444.649602 -149.00375) (xy 444.829246 -149.11208) (xy 445.004636 -149.22717)
			(xy 445.175517 -149.348854) (xy 445.341641 -149.476955) (xy 445.502768 -149.611288) (xy 445.658665 -149.751657)
			(xy 445.809104 -149.89786) (xy 445.953868 -150.049684) (xy 446.092747 -150.20691) (xy 446.22554 -150.369309)
			(xy 446.352054 -150.536645) (xy 446.472106 -150.708677) (xy 446.585521 -150.885154) (xy 446.692135 -151.065822)
			(xy 446.791794 -151.250417) (xy 446.884353 -151.438672) (xy 446.969678 -151.630315) (xy 447.047645 -151.825067)
			(xy 447.118141 -152.022647) (xy 447.181064 -152.222766) (xy 447.236323 -152.425137) (xy 447.283837 -152.629464)
			(xy 447.323538 -152.835452) (xy 447.355368 -153.042803) (xy 447.379281 -153.251214) (xy 447.395242 -153.460385)
			(xy 447.403229 -153.670012) (xy 447.403728 -153.774902) (xy 447.403229 -153.879792) (xy 447.395242 -154.089419)
			(xy 447.379281 -154.29859) (xy 447.355368 -154.507001) (xy 447.323538 -154.714352) (xy 447.283837 -154.92034)
			(xy 447.236323 -155.124667) (xy 447.181064 -155.327038) (xy 447.118141 -155.527157) (xy 447.047645 -155.724737)
			(xy 446.969678 -155.919489) (xy 446.884353 -156.111132) (xy 446.791794 -156.299387) (xy 446.692135 -156.483982)
			(xy 446.585521 -156.66465) (xy 446.472106 -156.841127) (xy 446.352054 -157.013159) (xy 446.22554 -157.180495)
			(xy 446.092747 -157.342894) (xy 445.953868 -157.50012) (xy 445.809104 -157.651944) (xy 445.658665 -157.798147)
			(xy 445.502768 -157.938516) (xy 445.341641 -158.072849) (xy 445.175517 -158.20095) (xy 445.004636 -158.322634)
			(xy 444.829246 -158.437724) (xy 444.649602 -158.546054) (xy 444.465964 -158.647465) (xy 444.278598 -158.741812)
			(xy 444.087776 -158.828958) (xy 443.893775 -158.908775) (xy 443.696876 -158.981149) (xy 443.497364 -159.045974)
			(xy 443.295529 -159.103157) (xy 443.091663 -159.152615) (xy 442.886062 -159.194275) (xy 442.679024 -159.228077)
			(xy 442.47085 -159.253973) (xy 442.26184 -159.271925) (xy 442.052298 -159.281907) (xy 441.842529 -159.283904)
			(xy 441.632835 -159.277913) (xy 441.423522 -159.263944) (xy 441.214892 -159.242016) (xy 441.007248 -159.212162)
			(xy 440.800891 -159.174423) (xy 440.596121 -159.128856) (xy 440.393234 -159.075527) (xy 440.192524 -159.014512)
			(xy 439.994282 -158.9459) (xy 439.798797 -158.86979) (xy 439.60635 -158.786293) (xy 439.417222 -158.695531)
			(xy 439.231687 -158.597634) (xy 439.050013 -158.492744) (xy 438.872463 -158.381014) (xy 438.699297 -158.262606)
			(xy 438.530763 -158.137691) (xy 438.367108 -158.00645) (xy 438.208567 -157.869074) (xy 438.055372 -157.725761)
			(xy 437.907743 -157.576721) (xy 437.765896 -157.422168) (xy 437.630035 -157.262327) (xy 437.500358 -157.097429)
			(xy 437.377053 -156.927714) (xy 437.260299 -156.753428) (xy 437.150264 -156.574823) (xy 437.047109 -156.392159)
			(xy 436.950982 -156.2057) (xy 436.862024 -156.015716) (xy 436.780364 -155.822484) (xy 436.706119 -155.626283)
			(xy 436.639397 -155.427397) (xy 436.580295 -155.226115) (xy 436.528899 -155.02273) (xy 436.485284 -154.817535)
			(xy 436.449512 -154.610828) (xy 436.421635 -154.402909) (xy 436.401694 -154.19408) (xy 436.389718 -153.984643)
			(xy 436.385725 -153.774902) (xy 283.40376 -153.774902) (xy 283.403303 -153.870902) (xy 283.395316 -154.080529)
			(xy 283.379355 -154.2897) (xy 283.355442 -154.498111) (xy 283.323612 -154.705462) (xy 283.283911 -154.91145)
			(xy 283.236397 -155.115777) (xy 283.181138 -155.318148) (xy 283.118215 -155.518267) (xy 283.047719 -155.715847)
			(xy 282.969752 -155.910599) (xy 282.884427 -156.102242) (xy 282.791868 -156.290497) (xy 282.692209 -156.475092)
			(xy 282.585595 -156.65576) (xy 282.47218 -156.832237) (xy 282.352128 -157.004269) (xy 282.225614 -157.171605)
			(xy 282.092821 -157.334004) (xy 281.953942 -157.49123) (xy 281.809178 -157.643054) (xy 281.658739 -157.789257)
			(xy 281.502842 -157.929626) (xy 281.341715 -158.063959) (xy 281.175591 -158.19206) (xy 281.00471 -158.313744)
			(xy 280.82932 -158.428834) (xy 280.649676 -158.537164) (xy 280.466038 -158.638575) (xy 280.278672 -158.732922)
			(xy 280.08785 -158.820068) (xy 279.893849 -158.899885) (xy 279.69695 -158.972259) (xy 279.497438 -159.037084)
			(xy 279.295603 -159.094267) (xy 279.091737 -159.143725) (xy 278.886136 -159.185385) (xy 278.679098 -159.219187)
			(xy 278.470924 -159.245083) (xy 278.261914 -159.263035) (xy 278.052372 -159.273017) (xy 277.842603 -159.275014)
			(xy 277.632909 -159.269023) (xy 277.423596 -159.255054) (xy 277.214966 -159.233126) (xy 277.007322 -159.203272)
			(xy 276.800965 -159.165533) (xy 276.596195 -159.119966) (xy 276.393308 -159.066637) (xy 276.192598 -159.005622)
			(xy 275.994356 -158.93701) (xy 275.798871 -158.8609) (xy 275.606424 -158.777403) (xy 275.417296 -158.686641)
			(xy 275.231761 -158.588744) (xy 275.050087 -158.483854) (xy 274.872537 -158.372124) (xy 274.699371 -158.253716)
			(xy 274.530837 -158.128801) (xy 274.367182 -157.99756) (xy 274.208641 -157.860184) (xy 274.055446 -157.716871)
			(xy 273.907817 -157.567831) (xy 273.76597 -157.413278) (xy 273.630109 -157.253437) (xy 273.500432 -157.088539)
			(xy 273.377127 -156.918824) (xy 273.260373 -156.744538) (xy 273.150338 -156.565933) (xy 273.047183 -156.383269)
			(xy 272.951056 -156.19681) (xy 272.862098 -156.006826) (xy 272.780438 -155.813594) (xy 272.706193 -155.617393)
			(xy 272.639471 -155.418507) (xy 272.580369 -155.217225) (xy 272.528973 -155.01384) (xy 272.485358 -154.808645)
			(xy 272.449586 -154.601938) (xy 272.421709 -154.394019) (xy 272.401768 -154.18519) (xy 272.389792 -153.975753)
			(xy 272.385799 -153.766012) (xy 199.463618 -153.766012) (xy 199.46366 -153.774902) (xy 199.463161 -153.879792)
			(xy 199.455174 -154.089419) (xy 199.439213 -154.29859) (xy 199.4153 -154.507001) (xy 199.38347 -154.714352)
			(xy 199.343769 -154.92034) (xy 199.296255 -155.124667) (xy 199.240996 -155.327038) (xy 199.178073 -155.527157)
			(xy 199.107577 -155.724737) (xy 199.02961 -155.919489) (xy 198.944285 -156.111132) (xy 198.851726 -156.299387)
			(xy 198.752067 -156.483982) (xy 198.645453 -156.66465) (xy 198.532038 -156.841127) (xy 198.411986 -157.013159)
			(xy 198.285472 -157.180495) (xy 198.152679 -157.342894) (xy 198.0138 -157.50012) (xy 197.869036 -157.651944)
			(xy 197.718597 -157.798147) (xy 197.5627 -157.938516) (xy 197.401573 -158.072849) (xy 197.235449 -158.20095)
			(xy 197.064568 -158.322634) (xy 196.889178 -158.437724) (xy 196.709534 -158.546054) (xy 196.525896 -158.647465)
			(xy 196.33853 -158.741812) (xy 196.147708 -158.828958) (xy 195.953707 -158.908775) (xy 195.756808 -158.981149)
			(xy 195.557296 -159.045974) (xy 195.355461 -159.103157) (xy 195.151595 -159.152615) (xy 194.945994 -159.194275)
			(xy 194.738956 -159.228077) (xy 194.530782 -159.253973) (xy 194.321772 -159.271925) (xy 194.11223 -159.281907)
			(xy 193.902461 -159.283904) (xy 193.692767 -159.277913) (xy 193.483454 -159.263944) (xy 193.274824 -159.242016)
			(xy 193.06718 -159.212162) (xy 192.860823 -159.174423) (xy 192.656053 -159.128856) (xy 192.453166 -159.075527)
			(xy 192.252456 -159.014512) (xy 192.054214 -158.9459) (xy 191.858729 -158.86979) (xy 191.666282 -158.786293)
			(xy 191.477154 -158.695531) (xy 191.291619 -158.597634) (xy 191.109945 -158.492744) (xy 190.932395 -158.381014)
			(xy 190.759229 -158.262606) (xy 190.590695 -158.137691) (xy 190.42704 -158.00645) (xy 190.268499 -157.869074)
			(xy 190.115304 -157.725761) (xy 189.967675 -157.576721) (xy 189.825828 -157.422168) (xy 189.689967 -157.262327)
			(xy 189.56029 -157.097429) (xy 189.436985 -156.927714) (xy 189.320231 -156.753428) (xy 189.210196 -156.574823)
			(xy 189.107041 -156.392159) (xy 189.010914 -156.2057) (xy 188.921956 -156.015716) (xy 188.840296 -155.822484)
			(xy 188.766051 -155.626283) (xy 188.699329 -155.427397) (xy 188.640227 -155.226115) (xy 188.588831 -155.02273)
			(xy 188.545216 -154.817535) (xy 188.509444 -154.610828) (xy 188.481567 -154.402909) (xy 188.461626 -154.19408)
			(xy 188.44965 -153.984643) (xy 188.445657 -153.774902) (xy 187.505848 -153.774902) (xy 187.505848 -154.239468)
			(xy 187.505362 -154.266719) (xy 187.497606 -154.320667) (xy 187.482251 -154.372962) (xy 187.459609 -154.422539)
			(xy 187.430143 -154.468389) (xy 187.394452 -154.50958) (xy 187.353261 -154.545271) (xy 187.307411 -154.574737)
			(xy 187.257834 -154.597379) (xy 187.205539 -154.612734) (xy 187.151591 -154.62049) (xy 187.097089 -154.62049)
			(xy 187.043141 -154.612734) (xy 186.990846 -154.597379) (xy 186.941269 -154.574737) (xy 186.895419 -154.545271)
			(xy 186.854228 -154.50958) (xy 186.818537 -154.468389) (xy 186.789071 -154.422539) (xy 186.766429 -154.372962)
			(xy 186.751074 -154.320667) (xy 186.743318 -154.266719) (xy 186.742832 -154.239468) (xy 35.44312 -154.239468)
			(xy 35.439287 -154.2897) (xy 35.415374 -154.498111) (xy 35.383544 -154.705462) (xy 35.343843 -154.91145)
			(xy 35.296329 -155.115777) (xy 35.24107 -155.318148) (xy 35.178147 -155.518267) (xy 35.107651 -155.715847)
			(xy 35.029684 -155.910599) (xy 34.944359 -156.102242) (xy 34.8518 -156.290497) (xy 34.752141 -156.475092)
			(xy 34.645527 -156.65576) (xy 34.532112 -156.832237) (xy 34.41206 -157.004269) (xy 34.285546 -157.171605)
			(xy 34.152753 -157.334004) (xy 34.013874 -157.49123) (xy 33.86911 -157.643054) (xy 33.718671 -157.789257)
			(xy 33.562774 -157.929626) (xy 33.401647 -158.063959) (xy 33.235523 -158.19206) (xy 33.064642 -158.313744)
			(xy 32.889252 -158.428834) (xy 32.709608 -158.537164) (xy 32.52597 -158.638575) (xy 32.338604 -158.732922)
			(xy 32.147782 -158.820068) (xy 31.953781 -158.899885) (xy 31.756882 -158.972259) (xy 31.55737 -159.037084)
			(xy 31.355535 -159.094267) (xy 31.151669 -159.143725) (xy 30.946068 -159.185385) (xy 30.73903 -159.219187)
			(xy 30.530856 -159.245083) (xy 30.321846 -159.263035) (xy 30.112304 -159.273017) (xy 29.902535 -159.275014)
			(xy 29.692841 -159.269023) (xy 29.483528 -159.255054) (xy 29.274898 -159.233126) (xy 29.067254 -159.203272)
			(xy 28.860897 -159.165533) (xy 28.656127 -159.119966) (xy 28.45324 -159.066637) (xy 28.25253 -159.005622)
			(xy 28.054288 -158.93701) (xy 27.858803 -158.8609) (xy 27.666356 -158.777403) (xy 27.477228 -158.686641)
			(xy 27.291693 -158.588744) (xy 27.110019 -158.483854) (xy 26.932469 -158.372124) (xy 26.759303 -158.253716)
			(xy 26.590769 -158.128801) (xy 26.427114 -157.99756) (xy 26.268573 -157.860184) (xy 26.115378 -157.716871)
			(xy 25.967749 -157.567831) (xy 25.825902 -157.413278) (xy 25.690041 -157.253437) (xy 25.560364 -157.088539)
			(xy 25.437059 -156.918824) (xy 25.320305 -156.744538) (xy 25.21027 -156.565933) (xy 25.107115 -156.383269)
			(xy 25.010988 -156.19681) (xy 24.92203 -156.006826) (xy 24.84037 -155.813594) (xy 24.766125 -155.617393)
			(xy 24.699403 -155.418507) (xy 24.640301 -155.217225) (xy 24.588905 -155.01384) (xy 24.54529 -154.808645)
			(xy 24.509518 -154.601938) (xy 24.481641 -154.394019) (xy 24.4617 -154.18519) (xy 24.449724 -153.975753)
			(xy 24.445731 -153.766012) (xy 2.509012 -153.766012) (xy 2.509012 -160.911354) (xy 372.506163 -160.911354)
			(xy 372.506163 -160.856846) (xy 372.513921 -160.802893) (xy 372.529279 -160.750593) (xy 372.551924 -160.701011)
			(xy 372.581395 -160.655157) (xy 372.617092 -160.613964) (xy 372.658289 -160.578271) (xy 372.704146 -160.548805)
			(xy 372.75373 -160.526165) (xy 372.806032 -160.510813) (xy 372.859986 -160.503061) (xy 372.88724 -160.5026)
			(xy 373.75084 -160.5026) (xy 373.77809 -160.503073) (xy 373.832034 -160.510834) (xy 373.884326 -160.526193)
			(xy 373.933899 -160.548837) (xy 373.979745 -160.578305) (xy 374.020931 -160.613997) (xy 374.056619 -160.655187)
			(xy 374.086083 -160.701036) (xy 374.108721 -160.750612) (xy 374.124075 -160.802905) (xy 374.13183 -160.85685)
			(xy 374.13183 -160.91135) (xy 374.124075 -160.965295) (xy 374.108721 -161.017588) (xy 374.086083 -161.067164)
			(xy 374.056619 -161.113013) (xy 374.020931 -161.154203) (xy 373.979745 -161.189895) (xy 373.933899 -161.219363)
			(xy 373.884326 -161.242007) (xy 373.832034 -161.257366) (xy 373.77809 -161.265127) (xy 373.75084 -161.265616)
			(xy 372.88724 -161.265616) (xy 372.859986 -161.265139) (xy 372.806032 -161.257387) (xy 372.75373 -161.242035)
			(xy 372.704146 -161.219395) (xy 372.658289 -161.189929) (xy 372.617092 -161.154236) (xy 372.581395 -161.113043)
			(xy 372.551924 -161.067189) (xy 372.529279 -161.017607) (xy 372.513921 -160.965307) (xy 372.506163 -160.911354)
			(xy 2.509012 -160.911354) (xy 2.509012 -161.58445) (xy 296.753286 -161.58445) (xy 296.753286 -161.52995)
			(xy 296.761042 -161.476005) (xy 296.776395 -161.423713) (xy 296.799035 -161.374138) (xy 296.828498 -161.32829)
			(xy 296.864187 -161.287101) (xy 296.905374 -161.25141) (xy 296.951221 -161.221944) (xy 297.000795 -161.199302)
			(xy 297.053086 -161.183946) (xy 297.10703 -161.176187) (xy 297.13428 -161.1757) (xy 297.99788 -161.1757)
			(xy 298.025134 -161.176146) (xy 298.079089 -161.183901) (xy 298.13139 -161.199255) (xy 298.180974 -161.221897)
			(xy 298.22683 -161.251365) (xy 298.268026 -161.28706) (xy 298.303723 -161.328254) (xy 298.333193 -161.374109)
			(xy 298.355838 -161.423691) (xy 298.371195 -161.475992) (xy 298.378953 -161.529946) (xy 298.378953 -161.584454)
			(xy 298.371195 -161.638408) (xy 298.355838 -161.690709) (xy 298.333193 -161.740291) (xy 298.303723 -161.786146)
			(xy 298.268026 -161.82734) (xy 298.22683 -161.863035) (xy 298.180974 -161.892503) (xy 298.13139 -161.915145)
			(xy 298.079089 -161.930499) (xy 298.025134 -161.938254) (xy 297.99788 -161.938716) (xy 297.13428 -161.938716)
			(xy 297.10703 -161.938213) (xy 297.053086 -161.930454) (xy 297.000795 -161.915098) (xy 296.951221 -161.892456)
			(xy 296.905374 -161.86299) (xy 296.864187 -161.827299) (xy 296.828498 -161.78611) (xy 296.799035 -161.740262)
			(xy 296.776395 -161.690687) (xy 296.761042 -161.638395) (xy 296.753286 -161.58445) (xy 2.509012 -161.58445)
			(xy 2.509012 -162.128053) (xy 292.574946 -162.128053) (xy 292.574946 -162.073547) (xy 292.582702 -162.019597)
			(xy 292.598058 -161.967299) (xy 292.620699 -161.917719) (xy 292.650166 -161.871866) (xy 292.685859 -161.830673)
			(xy 292.72705 -161.794978) (xy 292.772902 -161.765509) (xy 292.822481 -161.742865) (xy 292.874777 -161.727507)
			(xy 292.928727 -161.719747) (xy 292.95598 -161.71926) (xy 293.81958 -161.71926) (xy 293.846832 -161.719786)
			(xy 293.90078 -161.72754) (xy 293.953076 -161.742893) (xy 294.002654 -161.765532) (xy 294.048506 -161.794997)
			(xy 294.089698 -161.830688) (xy 294.125391 -161.871878) (xy 294.154858 -161.917728) (xy 294.1775 -161.967305)
			(xy 294.192856 -162.0196) (xy 294.200613 -162.073549) (xy 294.200613 -162.128051) (xy 294.192856 -162.182)
			(xy 294.1775 -162.234295) (xy 294.154858 -162.283872) (xy 294.125391 -162.329722) (xy 294.089698 -162.370912)
			(xy 294.048506 -162.406603) (xy 294.002654 -162.436068) (xy 293.953076 -162.458707) (xy 293.90078 -162.47406)
			(xy 293.846832 -162.481814) (xy 293.81958 -162.482276) (xy 292.95598 -162.482276) (xy 292.928727 -162.481853)
			(xy 292.874777 -162.474093) (xy 292.822481 -162.458735) (xy 292.772902 -162.436091) (xy 292.72705 -162.406622)
			(xy 292.685859 -162.370927) (xy 292.650166 -162.329734) (xy 292.620699 -162.283881) (xy 292.598058 -162.234301)
			(xy 292.582702 -162.182003) (xy 292.574946 -162.128053) (xy 2.509012 -162.128053) (xy 2.509012 -163.123651)
			(xy 294.731403 -163.123651) (xy 294.731403 -163.069149) (xy 294.73916 -163.015201) (xy 294.754516 -162.962907)
			(xy 294.777159 -162.91333) (xy 294.806627 -162.867481) (xy 294.842321 -162.826292) (xy 294.883513 -162.790603)
			(xy 294.929365 -162.76114) (xy 294.978944 -162.738502) (xy 295.03124 -162.723152) (xy 295.085189 -162.7154)
			(xy 295.11244 -162.71494) (xy 295.97604 -162.71494) (xy 296.003293 -162.715333) (xy 296.057243 -162.723095)
			(xy 296.10954 -162.738455) (xy 296.159118 -162.761102) (xy 296.204969 -162.790573) (xy 296.24616 -162.826269)
			(xy 296.281851 -162.867463) (xy 296.311318 -162.913317) (xy 296.333959 -162.962898) (xy 296.349314 -163.015196)
			(xy 296.35707 -163.069147) (xy 296.35707 -163.110951) (xy 300.192403 -163.110951) (xy 300.192403 -163.056449)
			(xy 300.20016 -163.002501) (xy 300.215516 -162.950207) (xy 300.238159 -162.90063) (xy 300.267627 -162.854781)
			(xy 300.303321 -162.813592) (xy 300.344513 -162.777903) (xy 300.390365 -162.74844) (xy 300.439944 -162.725802)
			(xy 300.49224 -162.710452) (xy 300.546189 -162.7027) (xy 300.57344 -162.70224) (xy 301.43704 -162.70224)
			(xy 301.464293 -162.702633) (xy 301.518243 -162.710395) (xy 301.57054 -162.725755) (xy 301.620118 -162.748402)
			(xy 301.665969 -162.777873) (xy 301.70716 -162.813569) (xy 301.742851 -162.854763) (xy 301.772318 -162.900617)
			(xy 301.794959 -162.950198) (xy 301.810314 -163.002496) (xy 301.81807 -163.056447) (xy 301.81807 -163.110953)
			(xy 301.810314 -163.164904) (xy 301.794959 -163.217202) (xy 301.772318 -163.266783) (xy 301.742851 -163.312637)
			(xy 301.70716 -163.353831) (xy 301.665969 -163.389527) (xy 301.620118 -163.418998) (xy 301.57054 -163.441645)
			(xy 301.518243 -163.457005) (xy 301.464293 -163.464767) (xy 301.43704 -163.465256) (xy 300.57344 -163.465256)
			(xy 300.546189 -163.4647) (xy 300.49224 -163.456948) (xy 300.439944 -163.441598) (xy 300.390365 -163.41896)
			(xy 300.344513 -163.389497) (xy 300.303321 -163.353808) (xy 300.267627 -163.312619) (xy 300.238159 -163.26677)
			(xy 300.215516 -163.217193) (xy 300.20016 -163.164899) (xy 300.192403 -163.110951) (xy 296.35707 -163.110951)
			(xy 296.35707 -163.123653) (xy 296.349314 -163.177604) (xy 296.333959 -163.229902) (xy 296.311318 -163.279483)
			(xy 296.281851 -163.325337) (xy 296.24616 -163.366531) (xy 296.204969 -163.402227) (xy 296.159118 -163.431698)
			(xy 296.10954 -163.454345) (xy 296.057243 -163.469705) (xy 296.003293 -163.477467) (xy 295.97604 -163.477956)
			(xy 295.11244 -163.477956) (xy 295.085189 -163.4774) (xy 295.03124 -163.469648) (xy 294.978944 -163.454298)
			(xy 294.929365 -163.43166) (xy 294.883513 -163.402197) (xy 294.842321 -163.366508) (xy 294.806627 -163.325319)
			(xy 294.777159 -163.27947) (xy 294.754516 -163.229893) (xy 294.73916 -163.177599) (xy 294.731403 -163.123651)
			(xy 2.509012 -163.123651) (xy 2.509012 -167.565832) (xy 348.657164 -167.565832) (xy 348.657658 -167.532531)
			(xy 348.666337 -167.466499) (xy 348.683566 -167.402165) (xy 348.709048 -167.340632) (xy 348.742347 -167.282953)
			(xy 348.782893 -167.230117) (xy 348.829992 -167.183027) (xy 348.882836 -167.142492) (xy 348.911418 -167.125396)
			(xy 349.83547 -166.591742) (xy 349.864533 -166.575642) (xy 349.925937 -166.550271) (xy 349.990123 -166.533114)
			(xy 350.055996 -166.524463) (xy 350.089216 -166.523924) (xy 350.089724 -166.523924) (xy 350.120458 -166.524315)
			(xy 350.181477 -166.531727) (xy 350.241158 -166.54644) (xy 350.29863 -166.56824) (xy 350.353056 -166.596808)
			(xy 350.403641 -166.631729) (xy 350.449648 -166.672492) (xy 350.490406 -166.718503) (xy 350.525321 -166.769092)
			(xy 350.553883 -166.823521) (xy 350.57377 -166.875968) (xy 369.614196 -166.875968) (xy 369.614752 -166.84267)
			(xy 369.623426 -166.776641) (xy 369.640648 -166.71231) (xy 369.666122 -166.650779) (xy 369.699412 -166.593101)
			(xy 369.739949 -166.540263) (xy 369.787038 -166.493171) (xy 369.839873 -166.452631) (xy 369.86845 -166.435532)
			(xy 370.792502 -165.901878) (xy 370.82156 -165.885769) (xy 370.882966 -165.8604) (xy 370.947153 -165.843245)
			(xy 371.013028 -165.834597) (xy 371.046248 -165.83406) (xy 371.046756 -165.83406) (xy 371.077486 -165.834579)
			(xy 371.138498 -165.841982) (xy 371.198173 -165.856685) (xy 371.255641 -165.878475) (xy 371.310063 -165.907032)
			(xy 371.360647 -165.941941) (xy 371.406653 -165.982693) (xy 371.447412 -166.028694) (xy 371.482329 -166.079272)
			(xy 371.510894 -166.133689) (xy 371.532692 -166.191154) (xy 371.547404 -166.250827) (xy 371.554816 -166.311838)
			(xy 371.555264 -166.342568) (xy 371.554757 -166.375868) (xy 371.546077 -166.4419) (xy 371.52885 -166.506232)
			(xy 371.503369 -166.567765) (xy 371.470072 -166.625443) (xy 371.429528 -166.67828) (xy 371.382432 -166.72537)
			(xy 371.329591 -166.765907) (xy 371.30101 -166.783004) (xy 370.964111 -166.977568) (xy 373.398796 -166.977568)
			(xy 373.399226 -166.946836) (xy 373.406638 -166.885821) (xy 373.421351 -166.826144) (xy 373.443149 -166.768676)
			(xy 373.471715 -166.714254) (xy 373.506633 -166.663671) (xy 373.547392 -166.617667) (xy 373.5934 -166.57691)
			(xy 373.643984 -166.541996) (xy 373.698409 -166.513434) (xy 373.755879 -166.49164) (xy 373.815556 -166.476932)
			(xy 373.876572 -166.469524) (xy 373.907304 -166.46906) (xy 373.907812 -166.46906) (xy 373.941031 -166.469606)
			(xy 374.006903 -166.478264) (xy 374.071088 -166.495419) (xy 374.132496 -166.520778) (xy 374.161558 -166.536878)
			(xy 375.08561 -167.070532) (xy 375.114171 -167.087654) (xy 375.166997 -167.128201) (xy 375.214079 -167.175295)
			(xy 375.254613 -167.22813) (xy 375.287906 -167.285802) (xy 375.313388 -167.347326) (xy 375.330623 -167.411649)
			(xy 375.339318 -167.477672) (xy 375.339864 -167.510968) (xy 375.339432 -167.541701) (xy 375.332026 -167.60272)
			(xy 375.317319 -167.6624) (xy 375.295524 -167.719873) (xy 375.266961 -167.774299) (xy 375.232044 -167.824885)
			(xy 375.191284 -167.870893) (xy 375.145275 -167.911651) (xy 375.094689 -167.946567) (xy 375.040262 -167.975129)
			(xy 374.982789 -167.996923) (xy 374.923108 -168.011629) (xy 374.862089 -168.019033) (xy 374.831356 -168.019476)
			(xy 374.830848 -168.019476) (xy 374.797629 -168.018942) (xy 374.731757 -168.01028) (xy 374.667571 -167.993122)
			(xy 374.606164 -167.967759) (xy 374.577102 -167.951658) (xy 373.65305 -167.418004) (xy 373.624495 -167.400872)
			(xy 373.571672 -167.360325) (xy 373.524591 -167.313232) (xy 373.484057 -167.260398) (xy 373.450764 -167.202727)
			(xy 373.42528 -167.141205) (xy 373.408042 -167.076884) (xy 373.399344 -167.010863) (xy 373.398796 -166.977568)
			(xy 370.964111 -166.977568) (xy 370.376958 -167.316658) (xy 370.34791 -167.332786) (xy 370.2865 -167.35815)
			(xy 370.22231 -167.375299) (xy 370.156433 -167.383942) (xy 370.123212 -167.384476) (xy 370.122704 -167.384476)
			(xy 370.091971 -167.384059) (xy 370.030952 -167.37665) (xy 369.971272 -167.36194) (xy 369.9138 -167.340143)
			(xy 369.859375 -167.311577) (xy 369.808789 -167.276659) (xy 369.762782 -167.235898) (xy 369.722023 -167.189889)
			(xy 369.687108 -167.139301) (xy 369.658546 -167.084874) (xy 369.636752 -167.027401) (xy 369.622045 -166.96772)
			(xy 369.61464 -166.906701) (xy 369.614196 -166.875968) (xy 350.57377 -166.875968) (xy 350.575676 -166.880996)
			(xy 350.590383 -166.940678) (xy 350.597788 -167.001698) (xy 350.598232 -167.032432) (xy 350.597712 -167.065732)
			(xy 350.589036 -167.131763) (xy 350.571812 -167.196097) (xy 350.546334 -167.25763) (xy 350.513038 -167.315309)
			(xy 350.472496 -167.368145) (xy 350.4254 -167.415235) (xy 350.372559 -167.455772) (xy 350.343978 -167.472868)
			(xy 349.419926 -168.006522) (xy 349.390862 -168.02262) (xy 349.329459 -168.047992) (xy 349.265273 -168.06515)
			(xy 349.1994 -168.073802) (xy 349.16618 -168.07434) (xy 349.165672 -168.07434) (xy 349.134942 -168.07387)
			(xy 349.073929 -168.066459) (xy 349.014255 -168.051748) (xy 348.956789 -168.029953) (xy 348.902369 -168.001389)
			(xy 348.851788 -167.966475) (xy 348.805784 -167.925719) (xy 348.765027 -167.879715) (xy 348.730113 -167.829135)
			(xy 348.701549 -167.774715) (xy 348.679753 -167.717249) (xy 348.665041 -167.657575) (xy 348.65763 -167.596562)
			(xy 348.657164 -167.565832) (xy 2.509012 -167.565832) (xy 2.509012 -168.302432) (xy 352.441764 -168.302432)
			(xy 352.442268 -168.271702) (xy 352.449672 -168.210689) (xy 352.464377 -168.151013) (xy 352.486168 -168.093545)
			(xy 352.514727 -168.039122) (xy 352.549637 -167.988539) (xy 352.59039 -167.942533) (xy 352.636392 -167.901774)
			(xy 352.686971 -167.866858) (xy 352.74139 -167.838292) (xy 352.798856 -167.816495) (xy 352.85853 -167.801783)
			(xy 352.919542 -167.794371) (xy 352.950272 -167.793924) (xy 352.95078 -167.793924) (xy 352.983998 -167.794489)
			(xy 353.049869 -167.803142) (xy 353.114055 -167.820291) (xy 353.175463 -167.845645) (xy 353.204526 -167.861742)
			(xy 354.128578 -168.395396) (xy 354.157139 -168.412518) (xy 354.209962 -168.453067) (xy 354.257042 -168.500162)
			(xy 354.297574 -168.552998) (xy 354.330866 -168.61067) (xy 354.356349 -168.672193) (xy 354.373586 -168.736515)
			(xy 354.382284 -168.802536) (xy 354.382832 -168.835832) (xy 354.382374 -168.866563) (xy 354.374962 -168.927576)
			(xy 354.360251 -168.987251) (xy 354.338454 -169.044717) (xy 354.30989 -169.099138) (xy 354.274975 -169.149719)
			(xy 354.234218 -169.195723) (xy 354.188213 -169.23648) (xy 354.137631 -169.271394) (xy 354.08321 -169.299957)
			(xy 354.025743 -169.321753) (xy 353.966068 -169.336464) (xy 353.905055 -169.343875) (xy 353.874324 -169.34434)
			(xy 353.873816 -169.34434) (xy 353.840597 -169.343782) (xy 353.774726 -169.335127) (xy 353.710541 -169.317976)
			(xy 353.649132 -169.292621) (xy 353.62007 -169.276522) (xy 352.696018 -168.742868) (xy 352.667463 -168.725735)
			(xy 352.614637 -168.685191) (xy 352.567553 -168.638099) (xy 352.527018 -168.585266) (xy 352.493724 -168.527595)
			(xy 352.468241 -168.466072) (xy 352.451005 -168.40175) (xy 352.44231 -168.335728) (xy 352.441764 -168.302432)
			(xy 2.509012 -168.302432) (xy 2.509012 -170.613832) (xy 348.657164 -170.613832) (xy 348.657658 -170.580531)
			(xy 348.666337 -170.514499) (xy 348.683566 -170.450165) (xy 348.709048 -170.388632) (xy 348.742347 -170.330953)
			(xy 348.782893 -170.278117) (xy 348.829992 -170.231027) (xy 348.882836 -170.190492) (xy 348.911418 -170.173396)
			(xy 349.83547 -169.639742) (xy 349.864533 -169.623642) (xy 349.925937 -169.598271) (xy 349.990123 -169.581114)
			(xy 350.055996 -169.572463) (xy 350.089216 -169.571924) (xy 350.089724 -169.571924) (xy 350.120458 -169.572315)
			(xy 350.181477 -169.579727) (xy 350.241158 -169.59444) (xy 350.29863 -169.61624) (xy 350.353056 -169.644808)
			(xy 350.403641 -169.679729) (xy 350.449648 -169.720492) (xy 350.490406 -169.766503) (xy 350.525321 -169.817092)
			(xy 350.553883 -169.871521) (xy 350.57377 -169.923968) (xy 369.614196 -169.923968) (xy 369.614752 -169.89067)
			(xy 369.623426 -169.824641) (xy 369.640648 -169.76031) (xy 369.666122 -169.698779) (xy 369.699412 -169.641101)
			(xy 369.739949 -169.588263) (xy 369.787038 -169.541171) (xy 369.839873 -169.500631) (xy 369.86845 -169.483532)
			(xy 370.792502 -168.949878) (xy 370.82156 -168.933769) (xy 370.882966 -168.9084) (xy 370.947153 -168.891245)
			(xy 371.013028 -168.882597) (xy 371.046248 -168.88206) (xy 371.046756 -168.88206) (xy 371.077486 -168.882579)
			(xy 371.138498 -168.889982) (xy 371.198173 -168.904685) (xy 371.255641 -168.926475) (xy 371.310063 -168.955032)
			(xy 371.360647 -168.989941) (xy 371.406653 -169.030693) (xy 371.447412 -169.076694) (xy 371.482329 -169.127272)
			(xy 371.510894 -169.181689) (xy 371.532692 -169.239154) (xy 371.547404 -169.298827) (xy 371.554816 -169.359838)
			(xy 371.555264 -169.390568) (xy 371.554757 -169.423868) (xy 371.546077 -169.4899) (xy 371.52885 -169.554232)
			(xy 371.503369 -169.615765) (xy 371.470072 -169.673443) (xy 371.429528 -169.72628) (xy 371.382432 -169.77337)
			(xy 371.329591 -169.813907) (xy 371.30101 -169.831004) (xy 370.376958 -170.364658) (xy 370.34791 -170.380786)
			(xy 370.2865 -170.40615) (xy 370.22231 -170.423299) (xy 370.156433 -170.431942) (xy 370.123212 -170.432476)
			(xy 370.122704 -170.432476) (xy 370.091971 -170.432059) (xy 370.030952 -170.42465) (xy 369.971272 -170.40994)
			(xy 369.9138 -170.388143) (xy 369.859375 -170.359577) (xy 369.808789 -170.324659) (xy 369.762782 -170.283898)
			(xy 369.722023 -170.237889) (xy 369.687108 -170.187301) (xy 369.658546 -170.132874) (xy 369.636752 -170.075401)
			(xy 369.622045 -170.01572) (xy 369.61464 -169.954701) (xy 369.614196 -169.923968) (xy 350.57377 -169.923968)
			(xy 350.575676 -169.928996) (xy 350.590383 -169.988678) (xy 350.597788 -170.049698) (xy 350.598232 -170.080432)
			(xy 350.597712 -170.113732) (xy 350.589036 -170.179763) (xy 350.571812 -170.244097) (xy 350.546334 -170.30563)
			(xy 350.513038 -170.363309) (xy 350.472496 -170.416145) (xy 350.4254 -170.463235) (xy 350.372559 -170.503772)
			(xy 350.343978 -170.520868) (xy 350.10208 -170.660568) (xy 373.398796 -170.660568) (xy 373.399226 -170.629836)
			(xy 373.406638 -170.568821) (xy 373.421351 -170.509144) (xy 373.443149 -170.451676) (xy 373.471715 -170.397254)
			(xy 373.506633 -170.346671) (xy 373.547392 -170.300667) (xy 373.5934 -170.25991) (xy 373.643984 -170.224996)
			(xy 373.698409 -170.196434) (xy 373.755879 -170.17464) (xy 373.815556 -170.159932) (xy 373.876572 -170.152524)
			(xy 373.907304 -170.15206) (xy 373.907812 -170.15206) (xy 373.941031 -170.152606) (xy 374.006903 -170.161264)
			(xy 374.071088 -170.178419) (xy 374.132496 -170.203778) (xy 374.161558 -170.219878) (xy 375.08561 -170.753532)
			(xy 375.114171 -170.770654) (xy 375.166997 -170.811201) (xy 375.214079 -170.858295) (xy 375.254613 -170.91113)
			(xy 375.287906 -170.968802) (xy 375.313388 -171.030326) (xy 375.330623 -171.094649) (xy 375.339318 -171.160672)
			(xy 375.339864 -171.193968) (xy 375.339432 -171.224701) (xy 375.332026 -171.28572) (xy 375.317319 -171.3454)
			(xy 375.295524 -171.402873) (xy 375.266961 -171.457299) (xy 375.232044 -171.507885) (xy 375.191284 -171.553893)
			(xy 375.145275 -171.594651) (xy 375.094689 -171.629567) (xy 375.040262 -171.658129) (xy 374.982789 -171.679923)
			(xy 374.923108 -171.694629) (xy 374.862089 -171.702033) (xy 374.831356 -171.702476) (xy 374.830848 -171.702476)
			(xy 374.797629 -171.701942) (xy 374.731757 -171.69328) (xy 374.667571 -171.676122) (xy 374.606164 -171.650759)
			(xy 374.577102 -171.634658) (xy 373.65305 -171.101004) (xy 373.624495 -171.083872) (xy 373.571672 -171.043325)
			(xy 373.524591 -170.996232) (xy 373.484057 -170.943398) (xy 373.450764 -170.885727) (xy 373.42528 -170.824205)
			(xy 373.408042 -170.759884) (xy 373.399344 -170.693863) (xy 373.398796 -170.660568) (xy 350.10208 -170.660568)
			(xy 349.419926 -171.054522) (xy 349.390862 -171.07062) (xy 349.329459 -171.095992) (xy 349.265273 -171.11315)
			(xy 349.1994 -171.121802) (xy 349.16618 -171.12234) (xy 349.165672 -171.12234) (xy 349.134942 -171.12187)
			(xy 349.073929 -171.114459) (xy 349.014255 -171.099748) (xy 348.956789 -171.077953) (xy 348.902369 -171.049389)
			(xy 348.851788 -171.014475) (xy 348.805784 -170.973719) (xy 348.765027 -170.927715) (xy 348.730113 -170.877135)
			(xy 348.701549 -170.822715) (xy 348.679753 -170.765249) (xy 348.665041 -170.705575) (xy 348.65763 -170.644562)
			(xy 348.657164 -170.613832) (xy 2.509012 -170.613832) (xy 2.509012 -171.985432) (xy 352.441764 -171.985432)
			(xy 352.442268 -171.954702) (xy 352.449672 -171.893689) (xy 352.464377 -171.834013) (xy 352.486168 -171.776545)
			(xy 352.514727 -171.722122) (xy 352.549637 -171.671539) (xy 352.59039 -171.625533) (xy 352.636392 -171.584774)
			(xy 352.686971 -171.549858) (xy 352.74139 -171.521292) (xy 352.798856 -171.499495) (xy 352.85853 -171.484783)
			(xy 352.919542 -171.477371) (xy 352.950272 -171.476924) (xy 352.95078 -171.476924) (xy 352.983998 -171.477489)
			(xy 353.049869 -171.486142) (xy 353.114055 -171.503291) (xy 353.175463 -171.528645) (xy 353.204526 -171.544742)
			(xy 354.128578 -172.078396) (xy 354.157139 -172.095518) (xy 354.209962 -172.136067) (xy 354.257042 -172.183162)
			(xy 354.297574 -172.235998) (xy 354.330866 -172.29367) (xy 354.356349 -172.355193) (xy 354.373586 -172.419515)
			(xy 354.382284 -172.485536) (xy 354.382832 -172.518832) (xy 354.382374 -172.549563) (xy 354.374962 -172.610576)
			(xy 354.360251 -172.670251) (xy 354.338454 -172.727717) (xy 354.30989 -172.782138) (xy 354.274975 -172.832719)
			(xy 354.234218 -172.878723) (xy 354.188213 -172.91948) (xy 354.137631 -172.954394) (xy 354.104147 -172.971968)
			(xy 369.614196 -172.971968) (xy 369.614752 -172.93867) (xy 369.623426 -172.872641) (xy 369.640648 -172.80831)
			(xy 369.666122 -172.746779) (xy 369.699412 -172.689101) (xy 369.739949 -172.636263) (xy 369.787038 -172.589171)
			(xy 369.839873 -172.548631) (xy 369.86845 -172.531532) (xy 370.792502 -171.997878) (xy 370.82156 -171.981769)
			(xy 370.882966 -171.9564) (xy 370.947153 -171.939245) (xy 371.013028 -171.930597) (xy 371.046248 -171.93006)
			(xy 371.046756 -171.93006) (xy 371.077486 -171.930579) (xy 371.138498 -171.937982) (xy 371.198173 -171.952685)
			(xy 371.255641 -171.974475) (xy 371.310063 -172.003032) (xy 371.360647 -172.037941) (xy 371.406653 -172.078693)
			(xy 371.447412 -172.124694) (xy 371.482329 -172.175272) (xy 371.510894 -172.229689) (xy 371.532692 -172.287154)
			(xy 371.547404 -172.346827) (xy 371.554816 -172.407838) (xy 371.555264 -172.438568) (xy 371.554757 -172.471868)
			(xy 371.546077 -172.5379) (xy 371.52885 -172.602232) (xy 371.503369 -172.663765) (xy 371.470072 -172.721443)
			(xy 371.429528 -172.77428) (xy 371.382432 -172.82137) (xy 371.329591 -172.861907) (xy 371.30101 -172.879004)
			(xy 370.376958 -173.412658) (xy 370.34791 -173.428786) (xy 370.2865 -173.45415) (xy 370.22231 -173.471299)
			(xy 370.156433 -173.479942) (xy 370.123212 -173.480476) (xy 370.122704 -173.480476) (xy 370.091971 -173.480059)
			(xy 370.030952 -173.47265) (xy 369.971272 -173.45794) (xy 369.9138 -173.436143) (xy 369.859375 -173.407577)
			(xy 369.808789 -173.372659) (xy 369.762782 -173.331898) (xy 369.722023 -173.285889) (xy 369.687108 -173.235301)
			(xy 369.658546 -173.180874) (xy 369.636752 -173.123401) (xy 369.622045 -173.06372) (xy 369.61464 -173.002701)
			(xy 369.614196 -172.971968) (xy 354.104147 -172.971968) (xy 354.08321 -172.982957) (xy 354.025743 -173.004753)
			(xy 353.966068 -173.019464) (xy 353.905055 -173.026875) (xy 353.874324 -173.02734) (xy 353.873816 -173.02734)
			(xy 353.840597 -173.026782) (xy 353.774726 -173.018127) (xy 353.710541 -173.000976) (xy 353.649132 -172.975621)
			(xy 353.62007 -172.959522) (xy 352.696018 -172.425868) (xy 352.667463 -172.408735) (xy 352.614637 -172.368191)
			(xy 352.567553 -172.321099) (xy 352.527018 -172.268266) (xy 352.493724 -172.210595) (xy 352.468241 -172.149072)
			(xy 352.451005 -172.08475) (xy 352.44231 -172.018728) (xy 352.441764 -171.985432) (xy 2.509012 -171.985432)
			(xy 2.509012 -173.661832) (xy 348.657164 -173.661832) (xy 348.657658 -173.628531) (xy 348.666337 -173.562499)
			(xy 348.683566 -173.498165) (xy 348.709048 -173.436632) (xy 348.742347 -173.378953) (xy 348.782893 -173.326117)
			(xy 348.829992 -173.279027) (xy 348.882836 -173.238492) (xy 348.911418 -173.221396) (xy 349.83547 -172.687742)
			(xy 349.864533 -172.671642) (xy 349.925937 -172.646271) (xy 349.990123 -172.629114) (xy 350.055996 -172.620463)
			(xy 350.089216 -172.619924) (xy 350.089724 -172.619924) (xy 350.120458 -172.620315) (xy 350.181477 -172.627727)
			(xy 350.241158 -172.64244) (xy 350.29863 -172.66424) (xy 350.353056 -172.692808) (xy 350.403641 -172.727729)
			(xy 350.449648 -172.768492) (xy 350.490406 -172.814503) (xy 350.525321 -172.865092) (xy 350.553883 -172.919521)
			(xy 350.575676 -172.976996) (xy 350.590383 -173.036678) (xy 350.597788 -173.097698) (xy 350.598232 -173.128432)
			(xy 350.597712 -173.161732) (xy 350.589036 -173.227763) (xy 350.571812 -173.292097) (xy 350.546334 -173.35363)
			(xy 350.513038 -173.411309) (xy 350.472496 -173.464145) (xy 350.4254 -173.511235) (xy 350.372559 -173.551772)
			(xy 350.343978 -173.568868) (xy 349.419926 -174.102522) (xy 349.390862 -174.11862) (xy 349.329459 -174.143992)
			(xy 349.265273 -174.16115) (xy 349.1994 -174.169802) (xy 349.16618 -174.17034) (xy 349.165672 -174.17034)
			(xy 349.134942 -174.16987) (xy 349.073929 -174.162459) (xy 349.014255 -174.147748) (xy 348.956789 -174.125953)
			(xy 348.902369 -174.097389) (xy 348.851788 -174.062475) (xy 348.805784 -174.021719) (xy 348.765027 -173.975715)
			(xy 348.730113 -173.925135) (xy 348.701549 -173.870715) (xy 348.679753 -173.813249) (xy 348.665041 -173.753575)
			(xy 348.65763 -173.692562) (xy 348.657164 -173.661832) (xy 2.509012 -173.661832) (xy 2.509012 -174.343568)
			(xy 373.398796 -174.343568) (xy 373.399226 -174.312836) (xy 373.406638 -174.251821) (xy 373.421351 -174.192144)
			(xy 373.443149 -174.134676) (xy 373.471715 -174.080254) (xy 373.506633 -174.029671) (xy 373.547392 -173.983667)
			(xy 373.5934 -173.94291) (xy 373.643984 -173.907996) (xy 373.698409 -173.879434) (xy 373.755879 -173.85764)
			(xy 373.815556 -173.842932) (xy 373.876572 -173.835524) (xy 373.907304 -173.83506) (xy 373.907812 -173.83506)
			(xy 373.941031 -173.835606) (xy 374.006903 -173.844264) (xy 374.071088 -173.861419) (xy 374.132496 -173.886778)
			(xy 374.161558 -173.902878) (xy 375.08561 -174.436532) (xy 375.114171 -174.453654) (xy 375.166997 -174.494201)
			(xy 375.214079 -174.541295) (xy 375.254613 -174.59413) (xy 375.287906 -174.651802) (xy 375.313388 -174.713326)
			(xy 375.330623 -174.777649) (xy 375.339318 -174.843672) (xy 375.339864 -174.876968) (xy 375.339432 -174.907701)
			(xy 375.332026 -174.96872) (xy 375.317319 -175.0284) (xy 375.295524 -175.085873) (xy 375.266961 -175.140299)
			(xy 375.232044 -175.190885) (xy 375.191284 -175.236893) (xy 375.145275 -175.277651) (xy 375.094689 -175.312567)
			(xy 375.040262 -175.341129) (xy 374.982789 -175.362923) (xy 374.923108 -175.377629) (xy 374.862089 -175.385033)
			(xy 374.831356 -175.385476) (xy 374.830848 -175.385476) (xy 374.797629 -175.384942) (xy 374.731757 -175.37628)
			(xy 374.667571 -175.359122) (xy 374.606164 -175.333759) (xy 374.577102 -175.317658) (xy 373.65305 -174.784004)
			(xy 373.624495 -174.766872) (xy 373.571672 -174.726325) (xy 373.524591 -174.679232) (xy 373.484057 -174.626398)
			(xy 373.450764 -174.568727) (xy 373.42528 -174.507205) (xy 373.408042 -174.442884) (xy 373.399344 -174.376863)
			(xy 373.398796 -174.343568) (xy 2.509012 -174.343568) (xy 2.509012 -175.83404) (xy 23.37714 -175.83404)
			(xy 23.381229 -175.778158) (xy 23.393412 -175.723468) (xy 23.413428 -175.671134) (xy 23.440851 -175.622272)
			(xy 23.475096 -175.577924) (xy 23.515432 -175.539034) (xy 23.561002 -175.506432) (xy 23.610833 -175.480813)
			(xy 23.663863 -175.462721) (xy 23.718961 -175.452544) (xy 23.774955 -175.450498) (xy 23.83065 -175.456626)
			(xy 23.884859 -175.470798) (xy 23.936427 -175.492712) (xy 23.984255 -175.521901) (xy 24.027323 -175.557742)
			(xy 24.064713 -175.599472) (xy 24.095629 -175.646202) (xy 24.119412 -175.696935) (xy 24.135554 -175.750591)
			(xy 24.143713 -175.806025) (xy 24.144224 -175.83404) (xy 24.143713 -175.862055) (xy 24.135554 -175.917489)
			(xy 24.119412 -175.971145) (xy 24.095629 -176.021878) (xy 24.064713 -176.068608) (xy 24.027323 -176.110338)
			(xy 23.984255 -176.146179) (xy 23.936427 -176.175368) (xy 23.884859 -176.197282) (xy 23.83065 -176.211454)
			(xy 23.774955 -176.217582) (xy 23.718961 -176.215536) (xy 23.663863 -176.205359) (xy 23.610833 -176.187267)
			(xy 23.561002 -176.161648) (xy 23.515432 -176.129046) (xy 23.475096 -176.090156) (xy 23.440851 -176.045808)
			(xy 23.413428 -175.996946) (xy 23.393412 -175.944612) (xy 23.381229 -175.889922) (xy 23.37714 -175.83404)
			(xy 2.509012 -175.83404) (xy 2.509012 -176.709832) (xy 348.657164 -176.709832) (xy 348.657658 -176.676531)
			(xy 348.666337 -176.610499) (xy 348.683566 -176.546165) (xy 348.709048 -176.484632) (xy 348.742347 -176.426953)
			(xy 348.782893 -176.374117) (xy 348.829992 -176.327027) (xy 348.882836 -176.286492) (xy 348.911418 -176.269396)
			(xy 349.83547 -175.735742) (xy 349.864533 -175.719642) (xy 349.925937 -175.694271) (xy 349.990123 -175.677114)
			(xy 350.055996 -175.668463) (xy 350.089216 -175.667924) (xy 350.089724 -175.667924) (xy 350.120458 -175.668315)
			(xy 350.121421 -175.668432) (xy 352.441764 -175.668432) (xy 352.442268 -175.637702) (xy 352.449672 -175.576689)
			(xy 352.464377 -175.517013) (xy 352.486168 -175.459545) (xy 352.514727 -175.405122) (xy 352.549637 -175.354539)
			(xy 352.59039 -175.308533) (xy 352.636392 -175.267774) (xy 352.686971 -175.232858) (xy 352.74139 -175.204292)
			(xy 352.798856 -175.182495) (xy 352.85853 -175.167783) (xy 352.919542 -175.160371) (xy 352.950272 -175.159924)
			(xy 352.95078 -175.159924) (xy 352.983998 -175.160489) (xy 353.049869 -175.169142) (xy 353.114055 -175.186291)
			(xy 353.175463 -175.211645) (xy 353.204526 -175.227742) (xy 354.128578 -175.761396) (xy 354.157139 -175.778518)
			(xy 354.209962 -175.819067) (xy 354.257042 -175.866162) (xy 354.297574 -175.918998) (xy 354.330866 -175.97667)
			(xy 354.3488 -176.019968) (xy 369.614196 -176.019968) (xy 369.614752 -175.98667) (xy 369.623426 -175.920641)
			(xy 369.640648 -175.85631) (xy 369.666122 -175.794779) (xy 369.699412 -175.737101) (xy 369.739949 -175.684263)
			(xy 369.787038 -175.637171) (xy 369.839873 -175.596631) (xy 369.86845 -175.579532) (xy 370.792502 -175.045878)
			(xy 370.82156 -175.029769) (xy 370.882966 -175.0044) (xy 370.947153 -174.987245) (xy 371.013028 -174.978597)
			(xy 371.046248 -174.97806) (xy 371.046756 -174.97806) (xy 371.077486 -174.978579) (xy 371.138498 -174.985982)
			(xy 371.198173 -175.000685) (xy 371.255641 -175.022475) (xy 371.310063 -175.051032) (xy 371.360647 -175.085941)
			(xy 371.406653 -175.126693) (xy 371.447412 -175.172694) (xy 371.482329 -175.223272) (xy 371.510894 -175.277689)
			(xy 371.532692 -175.335154) (xy 371.547404 -175.394827) (xy 371.554816 -175.455838) (xy 371.555264 -175.486568)
			(xy 371.554757 -175.519868) (xy 371.546077 -175.5859) (xy 371.543089 -175.597058) (xy 434.095902 -175.597058)
			(xy 434.099991 -175.541176) (xy 434.112174 -175.486486) (xy 434.13219 -175.434152) (xy 434.159613 -175.38529)
			(xy 434.193858 -175.340942) (xy 434.234194 -175.302052) (xy 434.279764 -175.26945) (xy 434.329595 -175.243831)
			(xy 434.382625 -175.225739) (xy 434.437723 -175.215562) (xy 434.493717 -175.213516) (xy 434.549412 -175.219644)
			(xy 434.603621 -175.233816) (xy 434.655189 -175.25573) (xy 434.703017 -175.284919) (xy 434.746085 -175.32076)
			(xy 434.783475 -175.36249) (xy 434.814391 -175.40922) (xy 434.838174 -175.459953) (xy 434.854316 -175.513609)
			(xy 434.862475 -175.569043) (xy 434.862986 -175.597058) (xy 434.862475 -175.625073) (xy 434.854316 -175.680507)
			(xy 434.838174 -175.734163) (xy 434.814391 -175.784896) (xy 434.783475 -175.831626) (xy 434.746085 -175.873356)
			(xy 434.703017 -175.909197) (xy 434.655189 -175.938386) (xy 434.603621 -175.9603) (xy 434.549412 -175.974472)
			(xy 434.493717 -175.9806) (xy 434.437723 -175.978554) (xy 434.382625 -175.968377) (xy 434.329595 -175.950285)
			(xy 434.279764 -175.924666) (xy 434.234194 -175.892064) (xy 434.193858 -175.853174) (xy 434.159613 -175.808826)
			(xy 434.13219 -175.759964) (xy 434.112174 -175.70763) (xy 434.099991 -175.65294) (xy 434.095902 -175.597058)
			(xy 371.543089 -175.597058) (xy 371.52885 -175.650232) (xy 371.503369 -175.711765) (xy 371.470072 -175.769443)
			(xy 371.429528 -175.82228) (xy 371.382432 -175.86937) (xy 371.329591 -175.909907) (xy 371.30101 -175.927004)
			(xy 370.376958 -176.460658) (xy 370.34791 -176.476786) (xy 370.2865 -176.50215) (xy 370.22231 -176.519299)
			(xy 370.156433 -176.527942) (xy 370.123212 -176.528476) (xy 370.122704 -176.528476) (xy 370.091971 -176.528059)
			(xy 370.030952 -176.52065) (xy 369.971272 -176.50594) (xy 369.9138 -176.484143) (xy 369.859375 -176.455577)
			(xy 369.808789 -176.420659) (xy 369.762782 -176.379898) (xy 369.722023 -176.333889) (xy 369.687108 -176.283301)
			(xy 369.658546 -176.228874) (xy 369.636752 -176.171401) (xy 369.622045 -176.11172) (xy 369.61464 -176.050701)
			(xy 369.614196 -176.019968) (xy 354.3488 -176.019968) (xy 354.356349 -176.038193) (xy 354.373586 -176.102515)
			(xy 354.382284 -176.168536) (xy 354.382832 -176.201832) (xy 354.382374 -176.232563) (xy 354.374962 -176.293576)
			(xy 354.360251 -176.353251) (xy 354.338454 -176.410717) (xy 354.30989 -176.465138) (xy 354.274975 -176.515719)
			(xy 354.234218 -176.561723) (xy 354.188213 -176.60248) (xy 354.137631 -176.637394) (xy 354.08321 -176.665957)
			(xy 354.025743 -176.687753) (xy 353.966068 -176.702464) (xy 353.905055 -176.709875) (xy 353.874324 -176.71034)
			(xy 353.873816 -176.71034) (xy 353.840597 -176.709782) (xy 353.774726 -176.701127) (xy 353.710541 -176.683976)
			(xy 353.649132 -176.658621) (xy 353.62007 -176.642522) (xy 352.696018 -176.108868) (xy 352.667463 -176.091735)
			(xy 352.614637 -176.051191) (xy 352.567553 -176.004099) (xy 352.527018 -175.951266) (xy 352.493724 -175.893595)
			(xy 352.468241 -175.832072) (xy 352.451005 -175.76775) (xy 352.44231 -175.701728) (xy 352.441764 -175.668432)
			(xy 350.121421 -175.668432) (xy 350.181477 -175.675727) (xy 350.241158 -175.69044) (xy 350.29863 -175.71224)
			(xy 350.353056 -175.740808) (xy 350.403641 -175.775729) (xy 350.449648 -175.816492) (xy 350.490406 -175.862503)
			(xy 350.525321 -175.913092) (xy 350.553883 -175.967521) (xy 350.575676 -176.024996) (xy 350.590383 -176.084678)
			(xy 350.597788 -176.145698) (xy 350.598232 -176.176432) (xy 350.597712 -176.209732) (xy 350.589036 -176.275763)
			(xy 350.571812 -176.340097) (xy 350.546334 -176.40163) (xy 350.513038 -176.459309) (xy 350.472496 -176.512145)
			(xy 350.4254 -176.559235) (xy 350.372559 -176.599772) (xy 350.343978 -176.616868) (xy 349.419926 -177.150522)
			(xy 349.390862 -177.16662) (xy 349.329459 -177.191992) (xy 349.265273 -177.20915) (xy 349.1994 -177.217802)
			(xy 349.16618 -177.21834) (xy 349.165672 -177.21834) (xy 349.134942 -177.21787) (xy 349.073929 -177.210459)
			(xy 349.014255 -177.195748) (xy 348.956789 -177.173953) (xy 348.902369 -177.145389) (xy 348.851788 -177.110475)
			(xy 348.805784 -177.069719) (xy 348.765027 -177.023715) (xy 348.730113 -176.973135) (xy 348.701549 -176.918715)
			(xy 348.679753 -176.861249) (xy 348.665041 -176.801575) (xy 348.65763 -176.740562) (xy 348.657164 -176.709832)
			(xy 2.509012 -176.709832) (xy 2.509012 -179.757832) (xy 348.657164 -179.757832) (xy 348.657658 -179.724531)
			(xy 348.666337 -179.658499) (xy 348.683566 -179.594165) (xy 348.709048 -179.532632) (xy 348.742347 -179.474953)
			(xy 348.782893 -179.422117) (xy 348.829992 -179.375027) (xy 348.882836 -179.334492) (xy 348.911418 -179.317396)
			(xy 349.83547 -178.783742) (xy 349.864533 -178.767642) (xy 349.925937 -178.742271) (xy 349.990123 -178.725114)
			(xy 350.055996 -178.716463) (xy 350.089216 -178.715924) (xy 350.089724 -178.715924) (xy 350.120458 -178.716315)
			(xy 350.181477 -178.723727) (xy 350.241158 -178.73844) (xy 350.29863 -178.76024) (xy 350.353056 -178.788808)
			(xy 350.403641 -178.823729) (xy 350.449648 -178.864492) (xy 350.490406 -178.910503) (xy 350.525321 -178.961092)
			(xy 350.553883 -179.015521) (xy 350.575676 -179.072996) (xy 350.590383 -179.132678) (xy 350.597788 -179.193698)
			(xy 350.598232 -179.224432) (xy 350.597712 -179.257732) (xy 350.589036 -179.323763) (xy 350.581628 -179.351432)
			(xy 352.441764 -179.351432) (xy 352.442268 -179.320702) (xy 352.449672 -179.259689) (xy 352.464377 -179.200013)
			(xy 352.486168 -179.142545) (xy 352.514727 -179.088122) (xy 352.549637 -179.037539) (xy 352.59039 -178.991533)
			(xy 352.636392 -178.950774) (xy 352.686971 -178.915858) (xy 352.74139 -178.887292) (xy 352.798856 -178.865495)
			(xy 352.85853 -178.850783) (xy 352.919542 -178.843371) (xy 352.950272 -178.842924) (xy 352.95078 -178.842924)
			(xy 352.983998 -178.843489) (xy 353.049869 -178.852142) (xy 353.114055 -178.869291) (xy 353.175463 -178.894645)
			(xy 353.204526 -178.910742) (xy 353.476772 -179.067968) (xy 369.614196 -179.067968) (xy 369.614752 -179.03467)
			(xy 369.623426 -178.968641) (xy 369.640648 -178.90431) (xy 369.666122 -178.842779) (xy 369.699412 -178.785101)
			(xy 369.739949 -178.732263) (xy 369.787038 -178.685171) (xy 369.839873 -178.644631) (xy 369.86845 -178.627532)
			(xy 370.792502 -178.093878) (xy 370.82156 -178.077769) (xy 370.882966 -178.0524) (xy 370.947153 -178.035245)
			(xy 371.013028 -178.026597) (xy 371.046248 -178.02606) (xy 371.046756 -178.02606) (xy 371.076835 -178.026568)
			(xy 373.398796 -178.026568) (xy 373.399226 -177.995836) (xy 373.406638 -177.934821) (xy 373.421351 -177.875144)
			(xy 373.443149 -177.817676) (xy 373.471715 -177.763254) (xy 373.506633 -177.712671) (xy 373.547392 -177.666667)
			(xy 373.5934 -177.62591) (xy 373.643984 -177.590996) (xy 373.698409 -177.562434) (xy 373.755879 -177.54064)
			(xy 373.815556 -177.525932) (xy 373.876572 -177.518524) (xy 373.907304 -177.51806) (xy 373.907812 -177.51806)
			(xy 373.941031 -177.518606) (xy 374.006903 -177.527264) (xy 374.071088 -177.544419) (xy 374.132496 -177.569778)
			(xy 374.161558 -177.585878) (xy 375.08561 -178.119532) (xy 375.114171 -178.136654) (xy 375.166997 -178.177201)
			(xy 375.214079 -178.224295) (xy 375.254613 -178.27713) (xy 375.287906 -178.334802) (xy 375.313388 -178.396326)
			(xy 375.330623 -178.460649) (xy 375.339318 -178.526672) (xy 375.339864 -178.559968) (xy 375.339432 -178.590701)
			(xy 375.332026 -178.65172) (xy 375.317319 -178.7114) (xy 375.295524 -178.768873) (xy 375.266961 -178.823299)
			(xy 375.232044 -178.873885) (xy 375.191284 -178.919893) (xy 375.145275 -178.960651) (xy 375.094689 -178.995567)
			(xy 375.040262 -179.024129) (xy 374.982789 -179.045923) (xy 374.923108 -179.060629) (xy 374.862089 -179.068033)
			(xy 374.831356 -179.068476) (xy 374.830848 -179.068476) (xy 374.797629 -179.067942) (xy 374.731757 -179.05928)
			(xy 374.667571 -179.042122) (xy 374.606164 -179.016759) (xy 374.577102 -179.000658) (xy 373.65305 -178.467004)
			(xy 373.624495 -178.449872) (xy 373.571672 -178.409325) (xy 373.524591 -178.362232) (xy 373.484057 -178.309398)
			(xy 373.450764 -178.251727) (xy 373.42528 -178.190205) (xy 373.408042 -178.125884) (xy 373.399344 -178.059863)
			(xy 373.398796 -178.026568) (xy 371.076835 -178.026568) (xy 371.077486 -178.026579) (xy 371.138498 -178.033982)
			(xy 371.198173 -178.048685) (xy 371.255641 -178.070475) (xy 371.310063 -178.099032) (xy 371.360647 -178.133941)
			(xy 371.406653 -178.174693) (xy 371.447412 -178.220694) (xy 371.482329 -178.271272) (xy 371.510894 -178.325689)
			(xy 371.532692 -178.383154) (xy 371.547404 -178.442827) (xy 371.554816 -178.503838) (xy 371.555264 -178.534568)
			(xy 371.554757 -178.567868) (xy 371.546077 -178.6339) (xy 371.52885 -178.698232) (xy 371.503369 -178.759765)
			(xy 371.470072 -178.817443) (xy 371.429528 -178.87028) (xy 371.382432 -178.91737) (xy 371.329591 -178.957907)
			(xy 371.30101 -178.975004) (xy 370.376958 -179.508658) (xy 370.34791 -179.524786) (xy 370.2865 -179.55015)
			(xy 370.22231 -179.567299) (xy 370.156433 -179.575942) (xy 370.123212 -179.576476) (xy 370.122704 -179.576476)
			(xy 370.091971 -179.576059) (xy 370.030952 -179.56865) (xy 369.971272 -179.55394) (xy 369.9138 -179.532143)
			(xy 369.859375 -179.503577) (xy 369.808789 -179.468659) (xy 369.762782 -179.427898) (xy 369.722023 -179.381889)
			(xy 369.687108 -179.331301) (xy 369.658546 -179.276874) (xy 369.636752 -179.219401) (xy 369.622045 -179.15972)
			(xy 369.61464 -179.098701) (xy 369.614196 -179.067968) (xy 353.476772 -179.067968) (xy 354.128578 -179.444396)
			(xy 354.157139 -179.461518) (xy 354.209962 -179.502067) (xy 354.257042 -179.549162) (xy 354.297574 -179.601998)
			(xy 354.330866 -179.65967) (xy 354.356349 -179.721193) (xy 354.373586 -179.785515) (xy 354.382284 -179.851536)
			(xy 354.382832 -179.884832) (xy 354.382374 -179.915563) (xy 354.374962 -179.976576) (xy 354.360251 -180.036251)
			(xy 354.338454 -180.093717) (xy 354.30989 -180.148138) (xy 354.274975 -180.198719) (xy 354.234218 -180.244723)
			(xy 354.188213 -180.28548) (xy 354.137631 -180.320394) (xy 354.08321 -180.348957) (xy 354.025743 -180.370753)
			(xy 353.966068 -180.385464) (xy 353.905055 -180.392875) (xy 353.874324 -180.39334) (xy 353.873816 -180.39334)
			(xy 353.840597 -180.392782) (xy 353.774726 -180.384127) (xy 353.710541 -180.366976) (xy 353.649132 -180.341621)
			(xy 353.62007 -180.325522) (xy 352.696018 -179.791868) (xy 352.667463 -179.774735) (xy 352.614637 -179.734191)
			(xy 352.567553 -179.687099) (xy 352.527018 -179.634266) (xy 352.493724 -179.576595) (xy 352.468241 -179.515072)
			(xy 352.451005 -179.45075) (xy 352.44231 -179.384728) (xy 352.441764 -179.351432) (xy 350.581628 -179.351432)
			(xy 350.571812 -179.388097) (xy 350.546334 -179.44963) (xy 350.513038 -179.507309) (xy 350.472496 -179.560145)
			(xy 350.4254 -179.607235) (xy 350.372559 -179.647772) (xy 350.343978 -179.664868) (xy 349.419926 -180.198522)
			(xy 349.390862 -180.21462) (xy 349.329459 -180.239992) (xy 349.265273 -180.25715) (xy 349.1994 -180.265802)
			(xy 349.16618 -180.26634) (xy 349.165672 -180.26634) (xy 349.134942 -180.26587) (xy 349.073929 -180.258459)
			(xy 349.014255 -180.243748) (xy 348.956789 -180.221953) (xy 348.902369 -180.193389) (xy 348.851788 -180.158475)
			(xy 348.805784 -180.117719) (xy 348.765027 -180.071715) (xy 348.730113 -180.021135) (xy 348.701549 -179.966715)
			(xy 348.679753 -179.909249) (xy 348.665041 -179.849575) (xy 348.65763 -179.788562) (xy 348.657164 -179.757832)
			(xy 2.509012 -179.757832) (xy 2.509012 -182.805832) (xy 348.657164 -182.805832) (xy 348.657658 -182.772531)
			(xy 348.666337 -182.706499) (xy 348.683566 -182.642165) (xy 348.709048 -182.580632) (xy 348.742347 -182.522953)
			(xy 348.782893 -182.470117) (xy 348.829992 -182.423027) (xy 348.882836 -182.382492) (xy 348.911418 -182.365396)
			(xy 349.83547 -181.831742) (xy 349.864533 -181.815642) (xy 349.925937 -181.790271) (xy 349.990123 -181.773114)
			(xy 350.055996 -181.764463) (xy 350.089216 -181.763924) (xy 350.089724 -181.763924) (xy 350.120458 -181.764315)
			(xy 350.181477 -181.771727) (xy 350.241158 -181.78644) (xy 350.29863 -181.80824) (xy 350.353056 -181.836808)
			(xy 350.403641 -181.871729) (xy 350.449648 -181.912492) (xy 350.490406 -181.958503) (xy 350.525321 -182.009092)
			(xy 350.553883 -182.063521) (xy 350.57377 -182.115968) (xy 369.614196 -182.115968) (xy 369.614752 -182.08267)
			(xy 369.623426 -182.016641) (xy 369.640648 -181.95231) (xy 369.666122 -181.890779) (xy 369.699412 -181.833101)
			(xy 369.739949 -181.780263) (xy 369.787038 -181.733171) (xy 369.839873 -181.692631) (xy 369.86845 -181.675532)
			(xy 370.792502 -181.141878) (xy 370.82156 -181.125769) (xy 370.882966 -181.1004) (xy 370.947153 -181.083245)
			(xy 371.013028 -181.074597) (xy 371.046248 -181.07406) (xy 371.046756 -181.07406) (xy 371.077486 -181.074579)
			(xy 371.138498 -181.081982) (xy 371.198173 -181.096685) (xy 371.255641 -181.118475) (xy 371.310063 -181.147032)
			(xy 371.360647 -181.181941) (xy 371.406653 -181.222693) (xy 371.447412 -181.268694) (xy 371.482329 -181.319272)
			(xy 371.510894 -181.373689) (xy 371.532692 -181.431154) (xy 371.547404 -181.490827) (xy 371.554816 -181.551838)
			(xy 371.555264 -181.582568) (xy 371.554757 -181.615868) (xy 371.546077 -181.6819) (xy 371.538668 -181.709568)
			(xy 373.398796 -181.709568) (xy 373.399226 -181.678836) (xy 373.406638 -181.617821) (xy 373.421351 -181.558144)
			(xy 373.443149 -181.500676) (xy 373.471715 -181.446254) (xy 373.506633 -181.395671) (xy 373.547392 -181.349667)
			(xy 373.5934 -181.30891) (xy 373.643984 -181.273996) (xy 373.698409 -181.245434) (xy 373.755879 -181.22364)
			(xy 373.815556 -181.208932) (xy 373.876572 -181.201524) (xy 373.907304 -181.20106) (xy 373.907812 -181.20106)
			(xy 373.941031 -181.201606) (xy 374.006903 -181.210264) (xy 374.071088 -181.227419) (xy 374.132496 -181.252778)
			(xy 374.161558 -181.268878) (xy 375.08561 -181.802532) (xy 375.114171 -181.819654) (xy 375.166997 -181.860201)
			(xy 375.214079 -181.907295) (xy 375.254613 -181.96013) (xy 375.287906 -182.017802) (xy 375.313388 -182.079326)
			(xy 375.330623 -182.143649) (xy 375.339318 -182.209672) (xy 375.339864 -182.242968) (xy 375.339432 -182.273701)
			(xy 375.332026 -182.33472) (xy 375.317319 -182.3944) (xy 375.295524 -182.451873) (xy 375.266961 -182.506299)
			(xy 375.232044 -182.556885) (xy 375.191284 -182.602893) (xy 375.145275 -182.643651) (xy 375.094689 -182.678567)
			(xy 375.040262 -182.707129) (xy 374.982789 -182.728923) (xy 374.923108 -182.743629) (xy 374.862089 -182.751033)
			(xy 374.831356 -182.751476) (xy 374.830848 -182.751476) (xy 374.797629 -182.750942) (xy 374.731757 -182.74228)
			(xy 374.667571 -182.725122) (xy 374.606164 -182.699759) (xy 374.577102 -182.683658) (xy 373.65305 -182.150004)
			(xy 373.624495 -182.132872) (xy 373.571672 -182.092325) (xy 373.524591 -182.045232) (xy 373.484057 -181.992398)
			(xy 373.450764 -181.934727) (xy 373.42528 -181.873205) (xy 373.408042 -181.808884) (xy 373.399344 -181.742863)
			(xy 373.398796 -181.709568) (xy 371.538668 -181.709568) (xy 371.52885 -181.746232) (xy 371.503369 -181.807765)
			(xy 371.470072 -181.865443) (xy 371.429528 -181.91828) (xy 371.382432 -181.96537) (xy 371.329591 -182.005907)
			(xy 371.30101 -182.023004) (xy 370.376958 -182.556658) (xy 370.34791 -182.572786) (xy 370.2865 -182.59815)
			(xy 370.22231 -182.615299) (xy 370.156433 -182.623942) (xy 370.123212 -182.624476) (xy 370.122704 -182.624476)
			(xy 370.091971 -182.624059) (xy 370.030952 -182.61665) (xy 369.971272 -182.60194) (xy 369.9138 -182.580143)
			(xy 369.859375 -182.551577) (xy 369.808789 -182.516659) (xy 369.762782 -182.475898) (xy 369.722023 -182.429889)
			(xy 369.687108 -182.379301) (xy 369.658546 -182.324874) (xy 369.636752 -182.267401) (xy 369.622045 -182.20772)
			(xy 369.61464 -182.146701) (xy 369.614196 -182.115968) (xy 350.57377 -182.115968) (xy 350.575676 -182.120996)
			(xy 350.590383 -182.180678) (xy 350.597788 -182.241698) (xy 350.598232 -182.272432) (xy 350.597712 -182.305732)
			(xy 350.589036 -182.371763) (xy 350.571812 -182.436097) (xy 350.546334 -182.49763) (xy 350.513038 -182.555309)
			(xy 350.472496 -182.608145) (xy 350.4254 -182.655235) (xy 350.372559 -182.695772) (xy 350.343978 -182.712868)
			(xy 349.775297 -183.04129) (xy 352.441764 -183.04129) (xy 352.442192 -183.010552) (xy 352.449601 -182.949525)
			(xy 352.46431 -182.889835) (xy 352.486105 -182.832352) (xy 352.514667 -182.777914) (xy 352.549581 -182.727315)
			(xy 352.590338 -182.681292) (xy 352.636344 -182.640516) (xy 352.686928 -182.60558) (xy 352.741353 -182.576994)
			(xy 352.798826 -182.555175) (xy 352.85851 -182.540441) (xy 352.919534 -182.533005) (xy 352.950272 -182.532528)
			(xy 352.95078 -182.532528) (xy 352.984007 -182.533118) (xy 353.049889 -182.541823) (xy 353.114077 -182.559036)
			(xy 353.175475 -182.584464) (xy 353.204526 -182.6006) (xy 354.128578 -183.134254) (xy 354.157165 -183.151335)
			(xy 354.209988 -183.19189) (xy 354.257067 -183.238991) (xy 354.297597 -183.291832) (xy 354.330886 -183.34951)
			(xy 354.356365 -183.411039) (xy 354.373597 -183.475367) (xy 354.382288 -183.541392) (xy 354.382832 -183.57469)
			(xy 354.382389 -183.605428) (xy 354.374982 -183.666455) (xy 354.360275 -183.726145) (xy 354.338483 -183.783627)
			(xy 354.309922 -183.838065) (xy 354.275009 -183.888665) (xy 354.234254 -183.934688) (xy 354.188249 -183.975465)
			(xy 354.137666 -184.010401) (xy 354.083241 -184.038987) (xy 354.025768 -184.060806) (xy 353.966085 -184.07554)
			(xy 353.905061 -184.082975) (xy 353.874324 -184.083452) (xy 353.873816 -184.083452) (xy 353.840589 -184.082867)
			(xy 353.774706 -184.07416) (xy 353.710519 -184.056946) (xy 353.649121 -184.031517) (xy 353.62007 -184.01538)
			(xy 352.696018 -183.481726) (xy 352.667489 -183.464552) (xy 352.614663 -183.424014) (xy 352.567578 -183.376928)
			(xy 352.527041 -183.324101) (xy 352.493744 -183.266436) (xy 352.468257 -183.204918) (xy 352.451015 -183.140601)
			(xy 352.442314 -183.074584) (xy 352.441764 -183.04129) (xy 349.775297 -183.04129) (xy 349.419926 -183.246522)
			(xy 349.390862 -183.26262) (xy 349.329459 -183.287992) (xy 349.265273 -183.30515) (xy 349.1994 -183.313802)
			(xy 349.16618 -183.31434) (xy 349.165672 -183.31434) (xy 349.134942 -183.31387) (xy 349.073929 -183.306459)
			(xy 349.014255 -183.291748) (xy 348.956789 -183.269953) (xy 348.902369 -183.241389) (xy 348.851788 -183.206475)
			(xy 348.805784 -183.165719) (xy 348.765027 -183.119715) (xy 348.730113 -183.069135) (xy 348.701549 -183.014715)
			(xy 348.679753 -182.957249) (xy 348.665041 -182.897575) (xy 348.65763 -182.836562) (xy 348.657164 -182.805832)
			(xy 2.509012 -182.805832) (xy 2.509012 -185.011568) (xy 372.585996 -185.011568) (xy 372.586426 -184.980836)
			(xy 372.593838 -184.919821) (xy 372.608551 -184.860144) (xy 372.630349 -184.802676) (xy 372.658915 -184.748254)
			(xy 372.693833 -184.697671) (xy 372.734592 -184.651667) (xy 372.7806 -184.61091) (xy 372.831184 -184.575996)
			(xy 372.885609 -184.547434) (xy 372.943079 -184.52564) (xy 373.002756 -184.510932) (xy 373.063772 -184.503524)
			(xy 373.094504 -184.50306) (xy 373.095012 -184.50306) (xy 373.128231 -184.503606) (xy 373.194103 -184.512264)
			(xy 373.258288 -184.529419) (xy 373.319696 -184.554778) (xy 373.348758 -184.570878) (xy 374.27281 -185.104532)
			(xy 374.301371 -185.121654) (xy 374.354197 -185.162201) (xy 374.401279 -185.209295) (xy 374.441813 -185.26213)
			(xy 374.475106 -185.319802) (xy 374.500588 -185.381326) (xy 374.517823 -185.445649) (xy 374.526518 -185.511672)
			(xy 374.527064 -185.544968) (xy 374.526632 -185.575701) (xy 374.519226 -185.63672) (xy 374.504519 -185.6964)
			(xy 374.482724 -185.753873) (xy 374.454161 -185.808299) (xy 374.419244 -185.858885) (xy 374.378484 -185.904893)
			(xy 374.332475 -185.945651) (xy 374.281889 -185.980567) (xy 374.227462 -186.009129) (xy 374.169989 -186.030923)
			(xy 374.110308 -186.045629) (xy 374.049289 -186.053033) (xy 374.018556 -186.053476) (xy 374.018048 -186.053476)
			(xy 373.984829 -186.052942) (xy 373.918957 -186.04428) (xy 373.854771 -186.027122) (xy 373.793364 -186.001759)
			(xy 373.764302 -185.985658) (xy 372.84025 -185.452004) (xy 372.811695 -185.434872) (xy 372.758872 -185.394325)
			(xy 372.711791 -185.347232) (xy 372.671257 -185.294398) (xy 372.637964 -185.236727) (xy 372.61248 -185.175205)
			(xy 372.595242 -185.110884) (xy 372.586544 -185.044863) (xy 372.585996 -185.011568) (xy 2.509012 -185.011568)
			(xy 2.509012 -186.714892) (xy 351.367344 -186.714892) (xy 351.367848 -186.684163) (xy 351.375257 -186.623152)
			(xy 351.389965 -186.563479) (xy 351.411758 -186.506014) (xy 351.440318 -186.451595) (xy 351.475229 -186.401014)
			(xy 351.515982 -186.355011) (xy 351.561983 -186.314254) (xy 351.612561 -186.279339) (xy 351.666978 -186.250774)
			(xy 351.724441 -186.228977) (xy 351.784113 -186.214264) (xy 351.845123 -186.206851) (xy 351.875852 -186.206384)
			(xy 351.87636 -186.206384) (xy 351.90958 -186.206906) (xy 351.975453 -186.215571) (xy 352.039638 -186.232732)
			(xy 352.101045 -186.258098) (xy 352.130106 -186.274202) (xy 353.054158 -186.807856) (xy 353.082741 -186.824943)
			(xy 353.135565 -186.865496) (xy 353.182645 -186.912596) (xy 353.223176 -186.965436) (xy 353.256466 -187.023114)
			(xy 353.281945 -187.084642) (xy 353.299177 -187.148969) (xy 353.307868 -187.214995) (xy 353.308412 -187.248292)
			(xy 353.307955 -187.279024) (xy 353.300547 -187.340039) (xy 353.285839 -187.399717) (xy 353.264044 -187.457187)
			(xy 353.235482 -187.51161) (xy 353.200567 -187.562194) (xy 353.15981 -187.608201) (xy 353.113804 -187.648959)
			(xy 353.063221 -187.683875) (xy 353.008798 -187.712439) (xy 352.951329 -187.734235) (xy 352.891651 -187.748945)
			(xy 352.830636 -187.756354) (xy 352.799904 -187.7568) (xy 352.799396 -187.7568) (xy 352.766177 -187.756256)
			(xy 352.700305 -187.747598) (xy 352.636119 -187.730443) (xy 352.574711 -187.705083) (xy 352.54565 -187.688982)
			(xy 351.621598 -187.155328) (xy 351.593065 -187.13816) (xy 351.54024 -187.09762) (xy 351.493156 -187.050533)
			(xy 351.45262 -186.997705) (xy 351.419323 -186.940039) (xy 351.393837 -186.878521) (xy 351.376595 -186.814204)
			(xy 351.367894 -186.748186) (xy 351.367344 -186.714892) (xy 2.509012 -186.714892) (xy 2.509012 -206.024988)
			(xy 86.700624 -206.024988) (xy 86.704605 -205.891968) (xy 86.716534 -205.759423) (xy 86.736369 -205.62783)
			(xy 86.764038 -205.497658) (xy 86.799442 -205.369373) (xy 86.842455 -205.243436) (xy 86.892922 -205.120297)
			(xy 86.950663 -205.000396) (xy 87.015472 -204.884163) (xy 87.087116 -204.772013) (xy 87.165338 -204.664349)
			(xy 87.249859 -204.561556) (xy 87.340377 -204.464001) (xy 87.436566 -204.372035) (xy 87.538084 -204.285985)
			(xy 87.644565 -204.206161) (xy 87.75563 -204.132848) (xy 87.870881 -204.066308) (xy 87.989905 -204.006779)
			(xy 88.112276 -203.954475) (xy 88.237555 -203.909583) (xy 88.365296 -203.872264) (xy 88.495039 -203.842651)
			(xy 88.626321 -203.82085) (xy 88.758672 -203.80694) (xy 88.891618 -203.800969) (xy 89.024683 -203.80296)
			(xy 89.157391 -203.812905) (xy 89.289267 -203.830769) (xy 89.419838 -203.856487) (xy 89.548638 -203.889968)
			(xy 89.675204 -203.931092) (xy 89.799085 -203.979712) (xy 89.919836 -204.035653) (xy 90.037026 -204.098715)
			(xy 90.150235 -204.168673) (xy 90.259057 -204.245277) (xy 90.363103 -204.328251) (xy 90.462001 -204.417299)
			(xy 90.555396 -204.512102) (xy 90.642954 -204.61232) (xy 90.724363 -204.717596) (xy 90.799329 -204.827552)
			(xy 90.867586 -204.941794) (xy 90.928888 -205.059914) (xy 90.983017 -205.181489) (xy 91.029778 -205.306083)
			(xy 91.069004 -205.433251) (xy 91.100554 -205.562537) (xy 91.124317 -205.693478) (xy 91.140206 -205.825606)
			(xy 91.148164 -205.958448) (xy 91.148662 -206.024988) (xy 132.710692 -206.024988) (xy 132.714673 -205.891968)
			(xy 132.726602 -205.759423) (xy 132.746437 -205.62783) (xy 132.774106 -205.497658) (xy 132.80951 -205.369373)
			(xy 132.852523 -205.243436) (xy 132.90299 -205.120297) (xy 132.960731 -205.000396) (xy 133.02554 -204.884163)
			(xy 133.097184 -204.772013) (xy 133.175406 -204.664349) (xy 133.259927 -204.561556) (xy 133.350445 -204.464001)
			(xy 133.446634 -204.372035) (xy 133.548152 -204.285985) (xy 133.654633 -204.206161) (xy 133.765698 -204.132848)
			(xy 133.880949 -204.066308) (xy 133.999973 -204.006779) (xy 134.122344 -203.954475) (xy 134.247623 -203.909583)
			(xy 134.375364 -203.872264) (xy 134.505107 -203.842651) (xy 134.636389 -203.82085) (xy 134.76874 -203.80694)
			(xy 134.901686 -203.800969) (xy 135.034751 -203.80296) (xy 135.167459 -203.812905) (xy 135.299335 -203.830769)
			(xy 135.429906 -203.856487) (xy 135.558706 -203.889968) (xy 135.685272 -203.931092) (xy 135.809153 -203.979712)
			(xy 135.929904 -204.035653) (xy 136.047094 -204.098715) (xy 136.160303 -204.168673) (xy 136.269125 -204.245277)
			(xy 136.373171 -204.328251) (xy 136.472069 -204.417299) (xy 136.565464 -204.512102) (xy 136.653022 -204.61232)
			(xy 136.734431 -204.717596) (xy 136.809397 -204.827552) (xy 136.877654 -204.941794) (xy 136.938956 -205.059914)
			(xy 136.993085 -205.181489) (xy 137.039846 -205.306083) (xy 137.079072 -205.433251) (xy 137.110622 -205.562537)
			(xy 137.134385 -205.693478) (xy 137.150274 -205.825606) (xy 137.158232 -205.958448) (xy 137.15873 -206.024988)
			(xy 334.640692 -206.024988) (xy 334.644673 -205.891968) (xy 334.656602 -205.759423) (xy 334.676437 -205.62783)
			(xy 334.704106 -205.497658) (xy 334.73951 -205.369373) (xy 334.782523 -205.243436) (xy 334.83299 -205.120297)
			(xy 334.890731 -205.000396) (xy 334.95554 -204.884163) (xy 335.027184 -204.772013) (xy 335.105406 -204.664349)
			(xy 335.189927 -204.561556) (xy 335.280445 -204.464001) (xy 335.376634 -204.372035) (xy 335.478152 -204.285985)
			(xy 335.584633 -204.206161) (xy 335.695698 -204.132848) (xy 335.810949 -204.066308) (xy 335.929973 -204.006779)
			(xy 336.052344 -203.954475) (xy 336.177623 -203.909583) (xy 336.305364 -203.872264) (xy 336.435107 -203.842651)
			(xy 336.566389 -203.82085) (xy 336.69874 -203.80694) (xy 336.831686 -203.800969) (xy 336.964751 -203.80296)
			(xy 337.097459 -203.812905) (xy 337.229335 -203.830769) (xy 337.359906 -203.856487) (xy 337.488706 -203.889968)
			(xy 337.615272 -203.931092) (xy 337.739153 -203.979712) (xy 337.859904 -204.035653) (xy 337.977094 -204.098715)
			(xy 338.090303 -204.168673) (xy 338.199125 -204.245277) (xy 338.303171 -204.328251) (xy 338.402069 -204.417299)
			(xy 338.495464 -204.512102) (xy 338.583022 -204.61232) (xy 338.664431 -204.717596) (xy 338.739397 -204.827552)
			(xy 338.807654 -204.941794) (xy 338.868956 -205.059914) (xy 338.923085 -205.181489) (xy 338.969846 -205.306083)
			(xy 339.009072 -205.433251) (xy 339.040622 -205.562537) (xy 339.064385 -205.693478) (xy 339.080274 -205.825606)
			(xy 339.088232 -205.958448) (xy 339.08873 -206.024988) (xy 380.650506 -206.024988) (xy 380.654487 -205.891968)
			(xy 380.666416 -205.759423) (xy 380.686251 -205.62783) (xy 380.71392 -205.497658) (xy 380.749324 -205.369373)
			(xy 380.792337 -205.243436) (xy 380.842804 -205.120297) (xy 380.900545 -205.000396) (xy 380.965354 -204.884163)
			(xy 381.036998 -204.772013) (xy 381.11522 -204.664349) (xy 381.199741 -204.561556) (xy 381.290259 -204.464001)
			(xy 381.386448 -204.372035) (xy 381.487966 -204.285985) (xy 381.594447 -204.206161) (xy 381.705512 -204.132848)
			(xy 381.820763 -204.066308) (xy 381.939787 -204.006779) (xy 382.062158 -203.954475) (xy 382.187437 -203.909583)
			(xy 382.315178 -203.872264) (xy 382.444921 -203.842651) (xy 382.576203 -203.82085) (xy 382.708554 -203.80694)
			(xy 382.8415 -203.800969) (xy 382.974565 -203.80296) (xy 383.107273 -203.812905) (xy 383.239149 -203.830769)
			(xy 383.36972 -203.856487) (xy 383.49852 -203.889968) (xy 383.625086 -203.931092) (xy 383.748967 -203.979712)
			(xy 383.869718 -204.035653) (xy 383.986908 -204.098715) (xy 384.100117 -204.168673) (xy 384.208939 -204.245277)
			(xy 384.312985 -204.328251) (xy 384.411883 -204.417299) (xy 384.505278 -204.512102) (xy 384.592836 -204.61232)
			(xy 384.674245 -204.717596) (xy 384.749211 -204.827552) (xy 384.817468 -204.941794) (xy 384.87877 -205.059914)
			(xy 384.932899 -205.181489) (xy 384.97966 -205.306083) (xy 385.018886 -205.433251) (xy 385.050436 -205.562537)
			(xy 385.074199 -205.693478) (xy 385.090088 -205.825606) (xy 385.098046 -205.958448) (xy 385.098544 -206.024988)
			(xy 385.098046 -206.091528) (xy 385.090088 -206.22437) (xy 385.074199 -206.356498) (xy 385.050436 -206.487439)
			(xy 385.018886 -206.616725) (xy 384.97966 -206.743893) (xy 384.932899 -206.868487) (xy 384.87877 -206.990062)
			(xy 384.817468 -207.108182) (xy 384.749211 -207.222424) (xy 384.674245 -207.33238) (xy 384.592836 -207.437656)
			(xy 384.505278 -207.537874) (xy 384.411883 -207.632677) (xy 384.312985 -207.721725) (xy 384.208939 -207.804699)
			(xy 384.100117 -207.881303) (xy 383.986908 -207.951261) (xy 383.869718 -208.014323) (xy 383.748967 -208.070264)
			(xy 383.625086 -208.118884) (xy 383.49852 -208.160008) (xy 383.36972 -208.193489) (xy 383.239149 -208.219207)
			(xy 383.107273 -208.237071) (xy 382.974565 -208.247016) (xy 382.8415 -208.249007) (xy 382.708554 -208.243036)
			(xy 382.576203 -208.229126) (xy 382.444921 -208.207325) (xy 382.315178 -208.177712) (xy 382.187437 -208.140393)
			(xy 382.062158 -208.095501) (xy 381.939787 -208.043197) (xy 381.820763 -207.983668) (xy 381.705512 -207.917128)
			(xy 381.594447 -207.843815) (xy 381.487966 -207.763991) (xy 381.386448 -207.677941) (xy 381.290259 -207.585975)
			(xy 381.199741 -207.48842) (xy 381.11522 -207.385627) (xy 381.036998 -207.277963) (xy 380.965354 -207.165813)
			(xy 380.900545 -207.04958) (xy 380.842804 -206.929679) (xy 380.792337 -206.80654) (xy 380.749324 -206.680603)
			(xy 380.71392 -206.552318) (xy 380.686251 -206.422146) (xy 380.666416 -206.290553) (xy 380.654487 -206.158008)
			(xy 380.650506 -206.024988) (xy 339.08873 -206.024988) (xy 339.088232 -206.091528) (xy 339.080274 -206.22437)
			(xy 339.064385 -206.356498) (xy 339.040622 -206.487439) (xy 339.009072 -206.616725) (xy 338.969846 -206.743893)
			(xy 338.923085 -206.868487) (xy 338.868956 -206.990062) (xy 338.807654 -207.108182) (xy 338.739397 -207.222424)
			(xy 338.664431 -207.33238) (xy 338.583022 -207.437656) (xy 338.495464 -207.537874) (xy 338.402069 -207.632677)
			(xy 338.303171 -207.721725) (xy 338.199125 -207.804699) (xy 338.090303 -207.881303) (xy 337.977094 -207.951261)
			(xy 337.859904 -208.014323) (xy 337.739153 -208.070264) (xy 337.615272 -208.118884) (xy 337.488706 -208.160008)
			(xy 337.359906 -208.193489) (xy 337.229335 -208.219207) (xy 337.097459 -208.237071) (xy 336.964751 -208.247016)
			(xy 336.831686 -208.249007) (xy 336.69874 -208.243036) (xy 336.566389 -208.229126) (xy 336.435107 -208.207325)
			(xy 336.305364 -208.177712) (xy 336.177623 -208.140393) (xy 336.052344 -208.095501) (xy 335.929973 -208.043197)
			(xy 335.810949 -207.983668) (xy 335.695698 -207.917128) (xy 335.584633 -207.843815) (xy 335.478152 -207.763991)
			(xy 335.376634 -207.677941) (xy 335.280445 -207.585975) (xy 335.189927 -207.48842) (xy 335.105406 -207.385627)
			(xy 335.027184 -207.277963) (xy 334.95554 -207.165813) (xy 334.890731 -207.04958) (xy 334.83299 -206.929679)
			(xy 334.782523 -206.80654) (xy 334.73951 -206.680603) (xy 334.704106 -206.552318) (xy 334.676437 -206.422146)
			(xy 334.656602 -206.290553) (xy 334.644673 -206.158008) (xy 334.640692 -206.024988) (xy 137.15873 -206.024988)
			(xy 137.158232 -206.091528) (xy 137.150274 -206.22437) (xy 137.134385 -206.356498) (xy 137.110622 -206.487439)
			(xy 137.079072 -206.616725) (xy 137.039846 -206.743893) (xy 136.993085 -206.868487) (xy 136.938956 -206.990062)
			(xy 136.877654 -207.108182) (xy 136.809397 -207.222424) (xy 136.734431 -207.33238) (xy 136.653022 -207.437656)
			(xy 136.565464 -207.537874) (xy 136.472069 -207.632677) (xy 136.373171 -207.721725) (xy 136.269125 -207.804699)
			(xy 136.160303 -207.881303) (xy 136.047094 -207.951261) (xy 135.929904 -208.014323) (xy 135.809153 -208.070264)
			(xy 135.685272 -208.118884) (xy 135.558706 -208.160008) (xy 135.429906 -208.193489) (xy 135.299335 -208.219207)
			(xy 135.167459 -208.237071) (xy 135.034751 -208.247016) (xy 134.901686 -208.249007) (xy 134.76874 -208.243036)
			(xy 134.636389 -208.229126) (xy 134.505107 -208.207325) (xy 134.375364 -208.177712) (xy 134.247623 -208.140393)
			(xy 134.122344 -208.095501) (xy 133.999973 -208.043197) (xy 133.880949 -207.983668) (xy 133.765698 -207.917128)
			(xy 133.654633 -207.843815) (xy 133.548152 -207.763991) (xy 133.446634 -207.677941) (xy 133.350445 -207.585975)
			(xy 133.259927 -207.48842) (xy 133.175406 -207.385627) (xy 133.097184 -207.277963) (xy 133.02554 -207.165813)
			(xy 132.960731 -207.04958) (xy 132.90299 -206.929679) (xy 132.852523 -206.80654) (xy 132.80951 -206.680603)
			(xy 132.774106 -206.552318) (xy 132.746437 -206.422146) (xy 132.726602 -206.290553) (xy 132.714673 -206.158008)
			(xy 132.710692 -206.024988) (xy 91.148662 -206.024988) (xy 91.148164 -206.091528) (xy 91.140206 -206.22437)
			(xy 91.124317 -206.356498) (xy 91.100554 -206.487439) (xy 91.069004 -206.616725) (xy 91.029778 -206.743893)
			(xy 90.983017 -206.868487) (xy 90.928888 -206.990062) (xy 90.867586 -207.108182) (xy 90.799329 -207.222424)
			(xy 90.724363 -207.33238) (xy 90.642954 -207.437656) (xy 90.555396 -207.537874) (xy 90.462001 -207.632677)
			(xy 90.363103 -207.721725) (xy 90.259057 -207.804699) (xy 90.150235 -207.881303) (xy 90.037026 -207.951261)
			(xy 89.919836 -208.014323) (xy 89.799085 -208.070264) (xy 89.675204 -208.118884) (xy 89.548638 -208.160008)
			(xy 89.419838 -208.193489) (xy 89.289267 -208.219207) (xy 89.157391 -208.237071) (xy 89.024683 -208.247016)
			(xy 88.891618 -208.249007) (xy 88.758672 -208.243036) (xy 88.626321 -208.229126) (xy 88.495039 -208.207325)
			(xy 88.365296 -208.177712) (xy 88.237555 -208.140393) (xy 88.112276 -208.095501) (xy 87.989905 -208.043197)
			(xy 87.870881 -207.983668) (xy 87.75563 -207.917128) (xy 87.644565 -207.843815) (xy 87.538084 -207.763991)
			(xy 87.436566 -207.677941) (xy 87.340377 -207.585975) (xy 87.249859 -207.48842) (xy 87.165338 -207.385627)
			(xy 87.087116 -207.277963) (xy 87.015472 -207.165813) (xy 86.950663 -207.04958) (xy 86.892922 -206.929679)
			(xy 86.842455 -206.80654) (xy 86.799442 -206.680603) (xy 86.764038 -206.552318) (xy 86.736369 -206.422146)
			(xy 86.716534 -206.290553) (xy 86.704605 -206.158008) (xy 86.700624 -206.024988) (xy 2.509012 -206.024988)
			(xy 2.509012 -213.732618) (xy 90.13825 -213.732618) (xy 90.138749 -213.705931) (xy 90.146704 -213.653152)
			(xy 90.162436 -213.602149) (xy 90.185594 -213.55406) (xy 90.215661 -213.50996) (xy 90.251965 -213.470833)
			(xy 90.293695 -213.437555) (xy 90.339919 -213.410868) (xy 90.389604 -213.391368) (xy 90.441641 -213.379491)
			(xy 90.494866 -213.375502) (xy 90.548091 -213.379491) (xy 90.600128 -213.391368) (xy 90.649813 -213.410868)
			(xy 90.696037 -213.437555) (xy 90.737767 -213.470833) (xy 90.774071 -213.50996) (xy 90.804138 -213.55406)
			(xy 90.827296 -213.602149) (xy 90.843028 -213.653152) (xy 90.850983 -213.705931) (xy 90.851482 -213.732618)
			(xy 92.01785 -213.732618) (xy 92.018349 -213.705931) (xy 92.026304 -213.653152) (xy 92.042036 -213.602149)
			(xy 92.065194 -213.55406) (xy 92.095261 -213.50996) (xy 92.131565 -213.470833) (xy 92.173295 -213.437555)
			(xy 92.219519 -213.410868) (xy 92.269204 -213.391368) (xy 92.321241 -213.379491) (xy 92.374466 -213.375502)
			(xy 92.427691 -213.379491) (xy 92.479728 -213.391368) (xy 92.529413 -213.410868) (xy 92.575637 -213.437555)
			(xy 92.617367 -213.470833) (xy 92.653671 -213.50996) (xy 92.683738 -213.55406) (xy 92.706896 -213.602149)
			(xy 92.722628 -213.653152) (xy 92.730583 -213.705931) (xy 92.731082 -213.732618) (xy 93.89745 -213.732618)
			(xy 93.897949 -213.705931) (xy 93.905904 -213.653152) (xy 93.921636 -213.602149) (xy 93.944794 -213.55406)
			(xy 93.974861 -213.50996) (xy 94.011165 -213.470833) (xy 94.052895 -213.437555) (xy 94.099119 -213.410868)
			(xy 94.148804 -213.391368) (xy 94.200841 -213.379491) (xy 94.254066 -213.375502) (xy 94.307291 -213.379491)
			(xy 94.359328 -213.391368) (xy 94.409013 -213.410868) (xy 94.455237 -213.437555) (xy 94.496967 -213.470833)
			(xy 94.533271 -213.50996) (xy 94.563338 -213.55406) (xy 94.586496 -213.602149) (xy 94.602228 -213.653152)
			(xy 94.610183 -213.705931) (xy 94.610682 -213.732618) (xy 95.77705 -213.732618) (xy 95.777549 -213.705931)
			(xy 95.785504 -213.653152) (xy 95.801236 -213.602149) (xy 95.824394 -213.55406) (xy 95.854461 -213.50996)
			(xy 95.890765 -213.470833) (xy 95.932495 -213.437555) (xy 95.978719 -213.410868) (xy 96.028404 -213.391368)
			(xy 96.080441 -213.379491) (xy 96.133666 -213.375502) (xy 96.186891 -213.379491) (xy 96.238928 -213.391368)
			(xy 96.288613 -213.410868) (xy 96.334837 -213.437555) (xy 96.376567 -213.470833) (xy 96.412871 -213.50996)
			(xy 96.442938 -213.55406) (xy 96.466096 -213.602149) (xy 96.481828 -213.653152) (xy 96.489783 -213.705931)
			(xy 96.490282 -213.732618) (xy 97.65665 -213.732618) (xy 97.657149 -213.705931) (xy 97.665104 -213.653152)
			(xy 97.680836 -213.602149) (xy 97.703994 -213.55406) (xy 97.734061 -213.50996) (xy 97.770365 -213.470833)
			(xy 97.812095 -213.437555) (xy 97.858319 -213.410868) (xy 97.908004 -213.391368) (xy 97.960041 -213.379491)
			(xy 98.013266 -213.375502) (xy 98.066491 -213.379491) (xy 98.118528 -213.391368) (xy 98.168213 -213.410868)
			(xy 98.214437 -213.437555) (xy 98.256167 -213.470833) (xy 98.292471 -213.50996) (xy 98.322538 -213.55406)
			(xy 98.345696 -213.602149) (xy 98.361428 -213.653152) (xy 98.369383 -213.705931) (xy 98.369882 -213.732618)
			(xy 99.53625 -213.732618) (xy 99.536749 -213.705931) (xy 99.544704 -213.653152) (xy 99.560436 -213.602149)
			(xy 99.583594 -213.55406) (xy 99.613661 -213.50996) (xy 99.649965 -213.470833) (xy 99.691695 -213.437555)
			(xy 99.737919 -213.410868) (xy 99.787604 -213.391368) (xy 99.839641 -213.379491) (xy 99.892866 -213.375502)
			(xy 99.946091 -213.379491) (xy 99.998128 -213.391368) (xy 100.047813 -213.410868) (xy 100.094037 -213.437555)
			(xy 100.135767 -213.470833) (xy 100.172071 -213.50996) (xy 100.202138 -213.55406) (xy 100.225296 -213.602149)
			(xy 100.241028 -213.653152) (xy 100.248983 -213.705931) (xy 100.249482 -213.732618) (xy 101.41585 -213.732618)
			(xy 101.416349 -213.705931) (xy 101.424304 -213.653152) (xy 101.440036 -213.602149) (xy 101.463194 -213.55406)
			(xy 101.493261 -213.50996) (xy 101.529565 -213.470833) (xy 101.571295 -213.437555) (xy 101.617519 -213.410868)
			(xy 101.667204 -213.391368) (xy 101.719241 -213.379491) (xy 101.772466 -213.375502) (xy 101.825691 -213.379491)
			(xy 101.877728 -213.391368) (xy 101.927413 -213.410868) (xy 101.973637 -213.437555) (xy 102.015367 -213.470833)
			(xy 102.051671 -213.50996) (xy 102.081738 -213.55406) (xy 102.104896 -213.602149) (xy 102.120628 -213.653152)
			(xy 102.128583 -213.705931) (xy 102.129082 -213.732618) (xy 103.29545 -213.732618) (xy 103.295949 -213.705931)
			(xy 103.303904 -213.653152) (xy 103.319636 -213.602149) (xy 103.342794 -213.55406) (xy 103.372861 -213.50996)
			(xy 103.409165 -213.470833) (xy 103.450895 -213.437555) (xy 103.497119 -213.410868) (xy 103.546804 -213.391368)
			(xy 103.598841 -213.379491) (xy 103.652066 -213.375502) (xy 103.705291 -213.379491) (xy 103.757328 -213.391368)
			(xy 103.807013 -213.410868) (xy 103.853237 -213.437555) (xy 103.894967 -213.470833) (xy 103.931271 -213.50996)
			(xy 103.961338 -213.55406) (xy 103.984496 -213.602149) (xy 104.000228 -213.653152) (xy 104.008183 -213.705931)
			(xy 104.008682 -213.732618) (xy 105.17505 -213.732618) (xy 105.175549 -213.705931) (xy 105.183504 -213.653152)
			(xy 105.199236 -213.602149) (xy 105.222394 -213.55406) (xy 105.252461 -213.50996) (xy 105.288765 -213.470833)
			(xy 105.330495 -213.437555) (xy 105.376719 -213.410868) (xy 105.426404 -213.391368) (xy 105.478441 -213.379491)
			(xy 105.531666 -213.375502) (xy 105.584891 -213.379491) (xy 105.636928 -213.391368) (xy 105.686613 -213.410868)
			(xy 105.732837 -213.437555) (xy 105.774567 -213.470833) (xy 105.810871 -213.50996) (xy 105.840938 -213.55406)
			(xy 105.864096 -213.602149) (xy 105.879828 -213.653152) (xy 105.887783 -213.705931) (xy 105.888282 -213.732618)
			(xy 107.05465 -213.732618) (xy 107.055149 -213.705931) (xy 107.063104 -213.653152) (xy 107.078836 -213.602149)
			(xy 107.101994 -213.55406) (xy 107.132061 -213.50996) (xy 107.168365 -213.470833) (xy 107.210095 -213.437555)
			(xy 107.256319 -213.410868) (xy 107.306004 -213.391368) (xy 107.358041 -213.379491) (xy 107.411266 -213.375502)
			(xy 107.464491 -213.379491) (xy 107.516528 -213.391368) (xy 107.566213 -213.410868) (xy 107.612437 -213.437555)
			(xy 107.654167 -213.470833) (xy 107.690471 -213.50996) (xy 107.720538 -213.55406) (xy 107.743696 -213.602149)
			(xy 107.759428 -213.653152) (xy 107.767383 -213.705931) (xy 107.767882 -213.732618) (xy 114.57305 -213.732618)
			(xy 114.573549 -213.705931) (xy 114.581504 -213.653152) (xy 114.597236 -213.602149) (xy 114.620394 -213.55406)
			(xy 114.650461 -213.50996) (xy 114.686765 -213.470833) (xy 114.728495 -213.437555) (xy 114.774719 -213.410868)
			(xy 114.824404 -213.391368) (xy 114.876441 -213.379491) (xy 114.929666 -213.375502) (xy 114.982891 -213.379491)
			(xy 115.034928 -213.391368) (xy 115.084613 -213.410868) (xy 115.130837 -213.437555) (xy 115.172567 -213.470833)
			(xy 115.208871 -213.50996) (xy 115.238938 -213.55406) (xy 115.262096 -213.602149) (xy 115.277828 -213.653152)
			(xy 115.285783 -213.705931) (xy 115.286282 -213.732618) (xy 116.45265 -213.732618) (xy 116.453149 -213.705931)
			(xy 116.461104 -213.653152) (xy 116.476836 -213.602149) (xy 116.499994 -213.55406) (xy 116.530061 -213.50996)
			(xy 116.566365 -213.470833) (xy 116.608095 -213.437555) (xy 116.654319 -213.410868) (xy 116.704004 -213.391368)
			(xy 116.756041 -213.379491) (xy 116.809266 -213.375502) (xy 116.862491 -213.379491) (xy 116.914528 -213.391368)
			(xy 116.964213 -213.410868) (xy 117.010437 -213.437555) (xy 117.052167 -213.470833) (xy 117.088471 -213.50996)
			(xy 117.118538 -213.55406) (xy 117.141696 -213.602149) (xy 117.157428 -213.653152) (xy 117.165383 -213.705931)
			(xy 117.165882 -213.732618) (xy 118.33225 -213.732618) (xy 118.332749 -213.705931) (xy 118.340704 -213.653152)
			(xy 118.356436 -213.602149) (xy 118.379594 -213.55406) (xy 118.409661 -213.50996) (xy 118.445965 -213.470833)
			(xy 118.487695 -213.437555) (xy 118.533919 -213.410868) (xy 118.583604 -213.391368) (xy 118.635641 -213.379491)
			(xy 118.688866 -213.375502) (xy 118.742091 -213.379491) (xy 118.794128 -213.391368) (xy 118.843813 -213.410868)
			(xy 118.890037 -213.437555) (xy 118.931767 -213.470833) (xy 118.968071 -213.50996) (xy 118.998138 -213.55406)
			(xy 119.021296 -213.602149) (xy 119.037028 -213.653152) (xy 119.044983 -213.705931) (xy 119.045482 -213.732618)
			(xy 120.21185 -213.732618) (xy 120.212349 -213.705931) (xy 120.220304 -213.653152) (xy 120.236036 -213.602149)
			(xy 120.259194 -213.55406) (xy 120.289261 -213.50996) (xy 120.325565 -213.470833) (xy 120.367295 -213.437555)
			(xy 120.413519 -213.410868) (xy 120.463204 -213.391368) (xy 120.515241 -213.379491) (xy 120.568466 -213.375502)
			(xy 120.621691 -213.379491) (xy 120.673728 -213.391368) (xy 120.723413 -213.410868) (xy 120.769637 -213.437555)
			(xy 120.811367 -213.470833) (xy 120.847671 -213.50996) (xy 120.877738 -213.55406) (xy 120.900896 -213.602149)
			(xy 120.916628 -213.653152) (xy 120.924583 -213.705931) (xy 120.925082 -213.732618) (xy 122.09145 -213.732618)
			(xy 122.091949 -213.705931) (xy 122.099904 -213.653152) (xy 122.115636 -213.602149) (xy 122.138794 -213.55406)
			(xy 122.168861 -213.50996) (xy 122.205165 -213.470833) (xy 122.246895 -213.437555) (xy 122.293119 -213.410868)
			(xy 122.342804 -213.391368) (xy 122.394841 -213.379491) (xy 122.448066 -213.375502) (xy 122.501291 -213.379491)
			(xy 122.553328 -213.391368) (xy 122.603013 -213.410868) (xy 122.649237 -213.437555) (xy 122.690967 -213.470833)
			(xy 122.727271 -213.50996) (xy 122.757338 -213.55406) (xy 122.780496 -213.602149) (xy 122.796228 -213.653152)
			(xy 122.804183 -213.705931) (xy 122.804682 -213.732618) (xy 123.970796 -213.732618) (xy 123.971295 -213.705931)
			(xy 123.97925 -213.653152) (xy 123.994982 -213.602149) (xy 124.01814 -213.55406) (xy 124.048207 -213.50996)
			(xy 124.084511 -213.470833) (xy 124.126241 -213.437555) (xy 124.172465 -213.410868) (xy 124.22215 -213.391368)
			(xy 124.274187 -213.379491) (xy 124.327412 -213.375502) (xy 124.380637 -213.379491) (xy 124.432674 -213.391368)
			(xy 124.482359 -213.410868) (xy 124.528583 -213.437555) (xy 124.570313 -213.470833) (xy 124.606617 -213.50996)
			(xy 124.636684 -213.55406) (xy 124.659842 -213.602149) (xy 124.675574 -213.653152) (xy 124.683529 -213.705931)
			(xy 124.684028 -213.732618) (xy 125.850396 -213.732618) (xy 125.850895 -213.705931) (xy 125.85885 -213.653152)
			(xy 125.874582 -213.602149) (xy 125.89774 -213.55406) (xy 125.927807 -213.50996) (xy 125.964111 -213.470833)
			(xy 126.005841 -213.437555) (xy 126.052065 -213.410868) (xy 126.10175 -213.391368) (xy 126.153787 -213.379491)
			(xy 126.207012 -213.375502) (xy 126.260237 -213.379491) (xy 126.312274 -213.391368) (xy 126.361959 -213.410868)
			(xy 126.408183 -213.437555) (xy 126.449913 -213.470833) (xy 126.486217 -213.50996) (xy 126.516284 -213.55406)
			(xy 126.539442 -213.602149) (xy 126.555174 -213.653152) (xy 126.563129 -213.705931) (xy 126.563628 -213.732618)
			(xy 127.73025 -213.732618) (xy 127.730749 -213.705931) (xy 127.738704 -213.653152) (xy 127.754436 -213.602149)
			(xy 127.777594 -213.55406) (xy 127.807661 -213.50996) (xy 127.843965 -213.470833) (xy 127.885695 -213.437555)
			(xy 127.931919 -213.410868) (xy 127.981604 -213.391368) (xy 128.033641 -213.379491) (xy 128.086866 -213.375502)
			(xy 128.140091 -213.379491) (xy 128.192128 -213.391368) (xy 128.241813 -213.410868) (xy 128.288037 -213.437555)
			(xy 128.329767 -213.470833) (xy 128.366071 -213.50996) (xy 128.396138 -213.55406) (xy 128.419296 -213.602149)
			(xy 128.435028 -213.653152) (xy 128.442983 -213.705931) (xy 128.443482 -213.732618) (xy 129.60985 -213.732618)
			(xy 129.610349 -213.705931) (xy 129.618304 -213.653152) (xy 129.634036 -213.602149) (xy 129.657194 -213.55406)
			(xy 129.687261 -213.50996) (xy 129.723565 -213.470833) (xy 129.765295 -213.437555) (xy 129.811519 -213.410868)
			(xy 129.861204 -213.391368) (xy 129.913241 -213.379491) (xy 129.966466 -213.375502) (xy 130.019691 -213.379491)
			(xy 130.071728 -213.391368) (xy 130.121413 -213.410868) (xy 130.167637 -213.437555) (xy 130.209367 -213.470833)
			(xy 130.245671 -213.50996) (xy 130.275738 -213.55406) (xy 130.298896 -213.602149) (xy 130.314628 -213.653152)
			(xy 130.322583 -213.705931) (xy 130.323082 -213.732618) (xy 131.48945 -213.732618) (xy 131.489949 -213.705931)
			(xy 131.497904 -213.653152) (xy 131.513636 -213.602149) (xy 131.536794 -213.55406) (xy 131.566861 -213.50996)
			(xy 131.603165 -213.470833) (xy 131.644895 -213.437555) (xy 131.691119 -213.410868) (xy 131.740804 -213.391368)
			(xy 131.792841 -213.379491) (xy 131.846066 -213.375502) (xy 131.899291 -213.379491) (xy 131.951328 -213.391368)
			(xy 132.001013 -213.410868) (xy 132.047237 -213.437555) (xy 132.088967 -213.470833) (xy 132.125271 -213.50996)
			(xy 132.155338 -213.55406) (xy 132.178496 -213.602149) (xy 132.194228 -213.653152) (xy 132.202183 -213.705931)
			(xy 132.202682 -213.732618) (xy 338.078318 -213.732618) (xy 338.078817 -213.705931) (xy 338.086772 -213.653152)
			(xy 338.102504 -213.602149) (xy 338.125662 -213.55406) (xy 338.155729 -213.50996) (xy 338.192033 -213.470833)
			(xy 338.233763 -213.437555) (xy 338.279987 -213.410868) (xy 338.329672 -213.391368) (xy 338.381709 -213.379491)
			(xy 338.434934 -213.375502) (xy 338.488159 -213.379491) (xy 338.540196 -213.391368) (xy 338.589881 -213.410868)
			(xy 338.636105 -213.437555) (xy 338.677835 -213.470833) (xy 338.714139 -213.50996) (xy 338.744206 -213.55406)
			(xy 338.767364 -213.602149) (xy 338.783096 -213.653152) (xy 338.791051 -213.705931) (xy 338.79155 -213.732618)
			(xy 339.957918 -213.732618) (xy 339.958417 -213.705931) (xy 339.966372 -213.653152) (xy 339.982104 -213.602149)
			(xy 340.005262 -213.55406) (xy 340.035329 -213.50996) (xy 340.071633 -213.470833) (xy 340.113363 -213.437555)
			(xy 340.159587 -213.410868) (xy 340.209272 -213.391368) (xy 340.261309 -213.379491) (xy 340.314534 -213.375502)
			(xy 340.367759 -213.379491) (xy 340.419796 -213.391368) (xy 340.469481 -213.410868) (xy 340.515705 -213.437555)
			(xy 340.557435 -213.470833) (xy 340.593739 -213.50996) (xy 340.623806 -213.55406) (xy 340.646964 -213.602149)
			(xy 340.662696 -213.653152) (xy 340.670651 -213.705931) (xy 340.67115 -213.732618) (xy 341.837518 -213.732618)
			(xy 341.838017 -213.705931) (xy 341.845972 -213.653152) (xy 341.861704 -213.602149) (xy 341.884862 -213.55406)
			(xy 341.914929 -213.50996) (xy 341.951233 -213.470833) (xy 341.992963 -213.437555) (xy 342.039187 -213.410868)
			(xy 342.088872 -213.391368) (xy 342.140909 -213.379491) (xy 342.194134 -213.375502) (xy 342.247359 -213.379491)
			(xy 342.299396 -213.391368) (xy 342.349081 -213.410868) (xy 342.395305 -213.437555) (xy 342.437035 -213.470833)
			(xy 342.473339 -213.50996) (xy 342.503406 -213.55406) (xy 342.526564 -213.602149) (xy 342.542296 -213.653152)
			(xy 342.550251 -213.705931) (xy 342.55075 -213.732618) (xy 343.717118 -213.732618) (xy 343.717617 -213.705931)
			(xy 343.725572 -213.653152) (xy 343.741304 -213.602149) (xy 343.764462 -213.55406) (xy 343.794529 -213.50996)
			(xy 343.830833 -213.470833) (xy 343.872563 -213.437555) (xy 343.918787 -213.410868) (xy 343.968472 -213.391368)
			(xy 344.020509 -213.379491) (xy 344.073734 -213.375502) (xy 344.126959 -213.379491) (xy 344.178996 -213.391368)
			(xy 344.228681 -213.410868) (xy 344.274905 -213.437555) (xy 344.316635 -213.470833) (xy 344.352939 -213.50996)
			(xy 344.383006 -213.55406) (xy 344.406164 -213.602149) (xy 344.421896 -213.653152) (xy 344.429851 -213.705931)
			(xy 344.43035 -213.732618) (xy 345.596718 -213.732618) (xy 345.597217 -213.705931) (xy 345.605172 -213.653152)
			(xy 345.620904 -213.602149) (xy 345.644062 -213.55406) (xy 345.674129 -213.50996) (xy 345.710433 -213.470833)
			(xy 345.752163 -213.437555) (xy 345.798387 -213.410868) (xy 345.848072 -213.391368) (xy 345.900109 -213.379491)
			(xy 345.953334 -213.375502) (xy 346.006559 -213.379491) (xy 346.058596 -213.391368) (xy 346.108281 -213.410868)
			(xy 346.154505 -213.437555) (xy 346.196235 -213.470833) (xy 346.232539 -213.50996) (xy 346.262606 -213.55406)
			(xy 346.285764 -213.602149) (xy 346.301496 -213.653152) (xy 346.309451 -213.705931) (xy 346.30995 -213.732618)
			(xy 347.476318 -213.732618) (xy 347.476817 -213.705931) (xy 347.484772 -213.653152) (xy 347.500504 -213.602149)
			(xy 347.523662 -213.55406) (xy 347.553729 -213.50996) (xy 347.590033 -213.470833) (xy 347.631763 -213.437555)
			(xy 347.677987 -213.410868) (xy 347.727672 -213.391368) (xy 347.779709 -213.379491) (xy 347.832934 -213.375502)
			(xy 347.886159 -213.379491) (xy 347.938196 -213.391368) (xy 347.987881 -213.410868) (xy 348.034105 -213.437555)
			(xy 348.075835 -213.470833) (xy 348.112139 -213.50996) (xy 348.142206 -213.55406) (xy 348.165364 -213.602149)
			(xy 348.181096 -213.653152) (xy 348.189051 -213.705931) (xy 348.18955 -213.732618) (xy 349.355918 -213.732618)
			(xy 349.356417 -213.705931) (xy 349.364372 -213.653152) (xy 349.380104 -213.602149) (xy 349.403262 -213.55406)
			(xy 349.433329 -213.50996) (xy 349.469633 -213.470833) (xy 349.511363 -213.437555) (xy 349.557587 -213.410868)
			(xy 349.607272 -213.391368) (xy 349.659309 -213.379491) (xy 349.712534 -213.375502) (xy 349.765759 -213.379491)
			(xy 349.817796 -213.391368) (xy 349.867481 -213.410868) (xy 349.913705 -213.437555) (xy 349.955435 -213.470833)
			(xy 349.991739 -213.50996) (xy 350.021806 -213.55406) (xy 350.044964 -213.602149) (xy 350.060696 -213.653152)
			(xy 350.068651 -213.705931) (xy 350.06915 -213.732618) (xy 351.235518 -213.732618) (xy 351.236017 -213.705931)
			(xy 351.243972 -213.653152) (xy 351.259704 -213.602149) (xy 351.282862 -213.55406) (xy 351.312929 -213.50996)
			(xy 351.349233 -213.470833) (xy 351.390963 -213.437555) (xy 351.437187 -213.410868) (xy 351.486872 -213.391368)
			(xy 351.538909 -213.379491) (xy 351.592134 -213.375502) (xy 351.645359 -213.379491) (xy 351.697396 -213.391368)
			(xy 351.747081 -213.410868) (xy 351.793305 -213.437555) (xy 351.835035 -213.470833) (xy 351.871339 -213.50996)
			(xy 351.901406 -213.55406) (xy 351.924564 -213.602149) (xy 351.940296 -213.653152) (xy 351.948251 -213.705931)
			(xy 351.94875 -213.732618) (xy 353.115118 -213.732618) (xy 353.115617 -213.705931) (xy 353.123572 -213.653152)
			(xy 353.139304 -213.602149) (xy 353.162462 -213.55406) (xy 353.192529 -213.50996) (xy 353.228833 -213.470833)
			(xy 353.270563 -213.437555) (xy 353.316787 -213.410868) (xy 353.366472 -213.391368) (xy 353.418509 -213.379491)
			(xy 353.471734 -213.375502) (xy 353.524959 -213.379491) (xy 353.576996 -213.391368) (xy 353.626681 -213.410868)
			(xy 353.672905 -213.437555) (xy 353.714635 -213.470833) (xy 353.750939 -213.50996) (xy 353.781006 -213.55406)
			(xy 353.804164 -213.602149) (xy 353.819896 -213.653152) (xy 353.827851 -213.705931) (xy 353.82835 -213.732618)
			(xy 354.994718 -213.732618) (xy 354.995217 -213.705931) (xy 355.003172 -213.653152) (xy 355.018904 -213.602149)
			(xy 355.042062 -213.55406) (xy 355.072129 -213.50996) (xy 355.108433 -213.470833) (xy 355.150163 -213.437555)
			(xy 355.196387 -213.410868) (xy 355.246072 -213.391368) (xy 355.298109 -213.379491) (xy 355.351334 -213.375502)
			(xy 355.404559 -213.379491) (xy 355.456596 -213.391368) (xy 355.506281 -213.410868) (xy 355.552505 -213.437555)
			(xy 355.594235 -213.470833) (xy 355.630539 -213.50996) (xy 355.660606 -213.55406) (xy 355.683764 -213.602149)
			(xy 355.699496 -213.653152) (xy 355.707451 -213.705931) (xy 355.70795 -213.732618) (xy 355.70795 -213.732872)
			(xy 355.70742 -213.760689) (xy 355.698758 -213.815644) (xy 355.68167 -213.868588) (xy 355.669596 -213.893654)
			(xy 355.657658 -213.917022) (xy 355.8413 -214.26551) (xy 355.867208 -214.269066) (xy 355.89263 -214.2728)
			(xy 355.942086 -214.286744) (xy 355.989029 -214.307641) (xy 356.032487 -214.335058) (xy 356.07156 -214.368428)
			(xy 356.10544 -214.407061) (xy 356.133425 -214.450156) (xy 356.154936 -214.49682) (xy 356.169527 -214.546089)
			(xy 356.176896 -214.596942) (xy 356.177342 -214.622634) (xy 356.176843 -214.649321) (xy 356.168888 -214.7021)
			(xy 356.153156 -214.753103) (xy 356.129998 -214.801192) (xy 356.099931 -214.845292) (xy 356.063627 -214.884419)
			(xy 356.021897 -214.917697) (xy 355.975673 -214.944384) (xy 355.925988 -214.963884) (xy 355.873951 -214.975761)
			(xy 355.820726 -214.97975) (xy 355.767501 -214.975761) (xy 355.715464 -214.963884) (xy 355.665779 -214.944384)
			(xy 355.619555 -214.917697) (xy 355.577825 -214.884419) (xy 355.541521 -214.845292) (xy 355.511454 -214.801192)
			(xy 355.488296 -214.753103) (xy 355.472564 -214.7021) (xy 355.464609 -214.649321) (xy 355.46411 -214.622634)
			(xy 355.46411 -214.62238) (xy 355.464653 -214.594564) (xy 355.473309 -214.539609) (xy 355.490392 -214.486664)
			(xy 355.502464 -214.461598) (xy 355.514402 -214.43823) (xy 355.33076 -214.089742) (xy 355.304852 -214.086186)
			(xy 355.279446 -214.082354) (xy 355.229995 -214.068422) (xy 355.183055 -214.047536) (xy 355.139598 -214.02013)
			(xy 355.100525 -213.986771) (xy 355.066643 -213.948149) (xy 355.038655 -213.905065) (xy 355.01714 -213.858411)
			(xy 355.002544 -213.809151) (xy 354.995168 -213.758306) (xy 354.994718 -213.732618) (xy 353.82835 -213.732618)
			(xy 353.82835 -213.732872) (xy 353.82782 -213.760689) (xy 353.819158 -213.815644) (xy 353.80207 -213.868588)
			(xy 353.789996 -213.893654) (xy 353.778058 -213.917022) (xy 353.9617 -214.26551) (xy 353.987608 -214.269066)
			(xy 354.01303 -214.2728) (xy 354.062486 -214.286744) (xy 354.109429 -214.307641) (xy 354.152887 -214.335058)
			(xy 354.19196 -214.368428) (xy 354.22584 -214.407061) (xy 354.253825 -214.450156) (xy 354.275336 -214.49682)
			(xy 354.289927 -214.546089) (xy 354.297296 -214.596942) (xy 354.297742 -214.622634) (xy 354.297243 -214.649321)
			(xy 354.289288 -214.7021) (xy 354.273556 -214.753103) (xy 354.250398 -214.801192) (xy 354.220331 -214.845292)
			(xy 354.184027 -214.884419) (xy 354.142297 -214.917697) (xy 354.096073 -214.944384) (xy 354.046388 -214.963884)
			(xy 353.994351 -214.975761) (xy 353.941126 -214.97975) (xy 353.887901 -214.975761) (xy 353.835864 -214.963884)
			(xy 353.786179 -214.944384) (xy 353.739955 -214.917697) (xy 353.698225 -214.884419) (xy 353.661921 -214.845292)
			(xy 353.631854 -214.801192) (xy 353.608696 -214.753103) (xy 353.592964 -214.7021) (xy 353.585009 -214.649321)
			(xy 353.58451 -214.622634) (xy 353.58451 -214.62238) (xy 353.585053 -214.594564) (xy 353.593709 -214.539609)
			(xy 353.610792 -214.486664) (xy 353.622864 -214.461598) (xy 353.634802 -214.43823) (xy 353.45116 -214.089742)
			(xy 353.425252 -214.086186) (xy 353.399846 -214.082354) (xy 353.350395 -214.068422) (xy 353.303455 -214.047536)
			(xy 353.259998 -214.02013) (xy 353.220925 -213.986771) (xy 353.187043 -213.948149) (xy 353.159055 -213.905065)
			(xy 353.13754 -213.858411) (xy 353.122944 -213.809151) (xy 353.115568 -213.758306) (xy 353.115118 -213.732618)
			(xy 351.94875 -213.732618) (xy 351.94875 -213.732872) (xy 351.94822 -213.760689) (xy 351.939558 -213.815644)
			(xy 351.92247 -213.868588) (xy 351.910396 -213.893654) (xy 351.898458 -213.917022) (xy 352.0821 -214.26551)
			(xy 352.108008 -214.269066) (xy 352.13343 -214.2728) (xy 352.182886 -214.286744) (xy 352.229829 -214.307641)
			(xy 352.273287 -214.335058) (xy 352.31236 -214.368428) (xy 352.34624 -214.407061) (xy 352.374225 -214.450156)
			(xy 352.395736 -214.49682) (xy 352.410327 -214.546089) (xy 352.417696 -214.596942) (xy 352.418142 -214.622634)
			(xy 352.417643 -214.649321) (xy 352.409688 -214.7021) (xy 352.393956 -214.753103) (xy 352.370798 -214.801192)
			(xy 352.340731 -214.845292) (xy 352.304427 -214.884419) (xy 352.262697 -214.917697) (xy 352.216473 -214.944384)
			(xy 352.166788 -214.963884) (xy 352.114751 -214.975761) (xy 352.061526 -214.97975) (xy 352.008301 -214.975761)
			(xy 351.956264 -214.963884) (xy 351.906579 -214.944384) (xy 351.860355 -214.917697) (xy 351.818625 -214.884419)
			(xy 351.782321 -214.845292) (xy 351.752254 -214.801192) (xy 351.729096 -214.753103) (xy 351.713364 -214.7021)
			(xy 351.705409 -214.649321) (xy 351.70491 -214.622634) (xy 351.70491 -214.62238) (xy 351.705453 -214.594564)
			(xy 351.714109 -214.539609) (xy 351.731192 -214.486664) (xy 351.743264 -214.461598) (xy 351.755202 -214.43823)
			(xy 351.57156 -214.089742) (xy 351.545652 -214.086186) (xy 351.520246 -214.082354) (xy 351.470795 -214.068422)
			(xy 351.423855 -214.047536) (xy 351.380398 -214.02013) (xy 351.341325 -213.986771) (xy 351.307443 -213.948149)
			(xy 351.279455 -213.905065) (xy 351.25794 -213.858411) (xy 351.243344 -213.809151) (xy 351.235968 -213.758306)
			(xy 351.235518 -213.732618) (xy 350.06915 -213.732618) (xy 350.06915 -213.732872) (xy 350.06862 -213.760689)
			(xy 350.059958 -213.815644) (xy 350.04287 -213.868588) (xy 350.030796 -213.893654) (xy 350.018858 -213.917022)
			(xy 350.2025 -214.26551) (xy 350.228408 -214.269066) (xy 350.25383 -214.2728) (xy 350.303286 -214.286744)
			(xy 350.350229 -214.307641) (xy 350.393687 -214.335058) (xy 350.43276 -214.368428) (xy 350.46664 -214.407061)
			(xy 350.494625 -214.450156) (xy 350.516136 -214.49682) (xy 350.530727 -214.546089) (xy 350.538096 -214.596942)
			(xy 350.538542 -214.622634) (xy 350.538043 -214.649321) (xy 350.530088 -214.7021) (xy 350.514356 -214.753103)
			(xy 350.491198 -214.801192) (xy 350.461131 -214.845292) (xy 350.424827 -214.884419) (xy 350.383097 -214.917697)
			(xy 350.336873 -214.944384) (xy 350.287188 -214.963884) (xy 350.235151 -214.975761) (xy 350.181926 -214.97975)
			(xy 350.128701 -214.975761) (xy 350.076664 -214.963884) (xy 350.026979 -214.944384) (xy 349.980755 -214.917697)
			(xy 349.939025 -214.884419) (xy 349.902721 -214.845292) (xy 349.872654 -214.801192) (xy 349.849496 -214.753103)
			(xy 349.833764 -214.7021) (xy 349.825809 -214.649321) (xy 349.82531 -214.622634) (xy 349.82531 -214.62238)
			(xy 349.825853 -214.594564) (xy 349.834509 -214.539609) (xy 349.851592 -214.486664) (xy 349.863664 -214.461598)
			(xy 349.875602 -214.43823) (xy 349.69196 -214.089742) (xy 349.666052 -214.086186) (xy 349.640646 -214.082354)
			(xy 349.591195 -214.068422) (xy 349.544255 -214.047536) (xy 349.500798 -214.02013) (xy 349.461725 -213.986771)
			(xy 349.427843 -213.948149) (xy 349.399855 -213.905065) (xy 349.37834 -213.858411) (xy 349.363744 -213.809151)
			(xy 349.356368 -213.758306) (xy 349.355918 -213.732618) (xy 348.18955 -213.732618) (xy 348.18955 -213.732872)
			(xy 348.18902 -213.760689) (xy 348.180358 -213.815644) (xy 348.16327 -213.868588) (xy 348.151196 -213.893654)
			(xy 348.139258 -213.917022) (xy 348.3229 -214.26551) (xy 348.348808 -214.269066) (xy 348.37423 -214.2728)
			(xy 348.423686 -214.286744) (xy 348.470629 -214.307641) (xy 348.514087 -214.335058) (xy 348.55316 -214.368428)
			(xy 348.58704 -214.407061) (xy 348.615025 -214.450156) (xy 348.636536 -214.49682) (xy 348.651127 -214.546089)
			(xy 348.658496 -214.596942) (xy 348.658942 -214.622634) (xy 348.658443 -214.649321) (xy 348.650488 -214.7021)
			(xy 348.634756 -214.753103) (xy 348.611598 -214.801192) (xy 348.581531 -214.845292) (xy 348.545227 -214.884419)
			(xy 348.503497 -214.917697) (xy 348.457273 -214.944384) (xy 348.407588 -214.963884) (xy 348.355551 -214.975761)
			(xy 348.302326 -214.97975) (xy 348.249101 -214.975761) (xy 348.197064 -214.963884) (xy 348.147379 -214.944384)
			(xy 348.101155 -214.917697) (xy 348.059425 -214.884419) (xy 348.023121 -214.845292) (xy 347.993054 -214.801192)
			(xy 347.969896 -214.753103) (xy 347.954164 -214.7021) (xy 347.946209 -214.649321) (xy 347.94571 -214.622634)
			(xy 347.94571 -214.62238) (xy 347.946253 -214.594564) (xy 347.954909 -214.539609) (xy 347.971992 -214.486664)
			(xy 347.984064 -214.461598) (xy 347.996002 -214.43823) (xy 347.81236 -214.089742) (xy 347.786452 -214.086186)
			(xy 347.761046 -214.082354) (xy 347.711595 -214.068422) (xy 347.664655 -214.047536) (xy 347.621198 -214.02013)
			(xy 347.582125 -213.986771) (xy 347.548243 -213.948149) (xy 347.520255 -213.905065) (xy 347.49874 -213.858411)
			(xy 347.484144 -213.809151) (xy 347.476768 -213.758306) (xy 347.476318 -213.732618) (xy 346.30995 -213.732618)
			(xy 346.30995 -213.732872) (xy 346.30942 -213.760689) (xy 346.300758 -213.815644) (xy 346.28367 -213.868588)
			(xy 346.271596 -213.893654) (xy 346.259658 -213.917022) (xy 346.4433 -214.26551) (xy 346.469208 -214.269066)
			(xy 346.49463 -214.2728) (xy 346.544086 -214.286744) (xy 346.591029 -214.307641) (xy 346.634487 -214.335058)
			(xy 346.67356 -214.368428) (xy 346.70744 -214.407061) (xy 346.735425 -214.450156) (xy 346.756936 -214.49682)
			(xy 346.771527 -214.546089) (xy 346.778896 -214.596942) (xy 346.779342 -214.622634) (xy 346.778843 -214.649321)
			(xy 346.770888 -214.7021) (xy 346.755156 -214.753103) (xy 346.731998 -214.801192) (xy 346.701931 -214.845292)
			(xy 346.665627 -214.884419) (xy 346.623897 -214.917697) (xy 346.577673 -214.944384) (xy 346.527988 -214.963884)
			(xy 346.475951 -214.975761) (xy 346.422726 -214.97975) (xy 346.369501 -214.975761) (xy 346.317464 -214.963884)
			(xy 346.267779 -214.944384) (xy 346.221555 -214.917697) (xy 346.179825 -214.884419) (xy 346.143521 -214.845292)
			(xy 346.113454 -214.801192) (xy 346.090296 -214.753103) (xy 346.074564 -214.7021) (xy 346.066609 -214.649321)
			(xy 346.06611 -214.622634) (xy 346.06611 -214.62238) (xy 346.066653 -214.594564) (xy 346.075309 -214.539609)
			(xy 346.092392 -214.486664) (xy 346.104464 -214.461598) (xy 346.116402 -214.43823) (xy 345.93276 -214.089742)
			(xy 345.906852 -214.086186) (xy 345.881446 -214.082354) (xy 345.831995 -214.068422) (xy 345.785055 -214.047536)
			(xy 345.741598 -214.02013) (xy 345.702525 -213.986771) (xy 345.668643 -213.948149) (xy 345.640655 -213.905065)
			(xy 345.61914 -213.858411) (xy 345.604544 -213.809151) (xy 345.597168 -213.758306) (xy 345.596718 -213.732618)
			(xy 344.43035 -213.732618) (xy 344.43035 -213.732872) (xy 344.42982 -213.760689) (xy 344.421158 -213.815644)
			(xy 344.40407 -213.868588) (xy 344.391996 -213.893654) (xy 344.380058 -213.917022) (xy 344.5637 -214.26551)
			(xy 344.589608 -214.269066) (xy 344.61503 -214.2728) (xy 344.664486 -214.286744) (xy 344.711429 -214.307641)
			(xy 344.754887 -214.335058) (xy 344.79396 -214.368428) (xy 344.82784 -214.407061) (xy 344.855825 -214.450156)
			(xy 344.877336 -214.49682) (xy 344.891927 -214.546089) (xy 344.899296 -214.596942) (xy 344.899742 -214.622634)
			(xy 344.899243 -214.649321) (xy 344.891288 -214.7021) (xy 344.875556 -214.753103) (xy 344.852398 -214.801192)
			(xy 344.822331 -214.845292) (xy 344.786027 -214.884419) (xy 344.744297 -214.917697) (xy 344.698073 -214.944384)
			(xy 344.648388 -214.963884) (xy 344.596351 -214.975761) (xy 344.543126 -214.97975) (xy 344.489901 -214.975761)
			(xy 344.437864 -214.963884) (xy 344.388179 -214.944384) (xy 344.341955 -214.917697) (xy 344.300225 -214.884419)
			(xy 344.263921 -214.845292) (xy 344.233854 -214.801192) (xy 344.210696 -214.753103) (xy 344.194964 -214.7021)
			(xy 344.187009 -214.649321) (xy 344.18651 -214.622634) (xy 344.18651 -214.62238) (xy 344.187053 -214.594564)
			(xy 344.195709 -214.539609) (xy 344.212792 -214.486664) (xy 344.224864 -214.461598) (xy 344.236802 -214.43823)
			(xy 344.05316 -214.089742) (xy 344.027252 -214.086186) (xy 344.001846 -214.082354) (xy 343.952395 -214.068422)
			(xy 343.905455 -214.047536) (xy 343.861998 -214.02013) (xy 343.822925 -213.986771) (xy 343.789043 -213.948149)
			(xy 343.761055 -213.905065) (xy 343.73954 -213.858411) (xy 343.724944 -213.809151) (xy 343.717568 -213.758306)
			(xy 343.717118 -213.732618) (xy 342.55075 -213.732618) (xy 342.55075 -213.732872) (xy 342.55022 -213.760689)
			(xy 342.541558 -213.815644) (xy 342.52447 -213.868588) (xy 342.512396 -213.893654) (xy 342.500458 -213.917022)
			(xy 342.6841 -214.26551) (xy 342.710008 -214.269066) (xy 342.73543 -214.2728) (xy 342.784886 -214.286744)
			(xy 342.831829 -214.307641) (xy 342.875287 -214.335058) (xy 342.91436 -214.368428) (xy 342.94824 -214.407061)
			(xy 342.976225 -214.450156) (xy 342.997736 -214.49682) (xy 343.012327 -214.546089) (xy 343.019696 -214.596942)
			(xy 343.020142 -214.622634) (xy 343.019643 -214.649321) (xy 343.011688 -214.7021) (xy 342.995956 -214.753103)
			(xy 342.972798 -214.801192) (xy 342.942731 -214.845292) (xy 342.906427 -214.884419) (xy 342.864697 -214.917697)
			(xy 342.818473 -214.944384) (xy 342.768788 -214.963884) (xy 342.716751 -214.975761) (xy 342.663526 -214.97975)
			(xy 342.610301 -214.975761) (xy 342.558264 -214.963884) (xy 342.508579 -214.944384) (xy 342.462355 -214.917697)
			(xy 342.420625 -214.884419) (xy 342.384321 -214.845292) (xy 342.354254 -214.801192) (xy 342.331096 -214.753103)
			(xy 342.315364 -214.7021) (xy 342.307409 -214.649321) (xy 342.30691 -214.622634) (xy 342.30691 -214.62238)
			(xy 342.307453 -214.594564) (xy 342.316109 -214.539609) (xy 342.333192 -214.486664) (xy 342.345264 -214.461598)
			(xy 342.357202 -214.43823) (xy 342.17356 -214.089742) (xy 342.147652 -214.086186) (xy 342.122246 -214.082354)
			(xy 342.072795 -214.068422) (xy 342.025855 -214.047536) (xy 341.982398 -214.02013) (xy 341.943325 -213.986771)
			(xy 341.909443 -213.948149) (xy 341.881455 -213.905065) (xy 341.85994 -213.858411) (xy 341.845344 -213.809151)
			(xy 341.837968 -213.758306) (xy 341.837518 -213.732618) (xy 340.67115 -213.732618) (xy 340.67115 -213.732872)
			(xy 340.67062 -213.760689) (xy 340.661958 -213.815644) (xy 340.64487 -213.868588) (xy 340.632796 -213.893654)
			(xy 340.620858 -213.917022) (xy 340.8045 -214.26551) (xy 340.830408 -214.269066) (xy 340.85583 -214.2728)
			(xy 340.905286 -214.286744) (xy 340.952229 -214.307641) (xy 340.995687 -214.335058) (xy 341.03476 -214.368428)
			(xy 341.06864 -214.407061) (xy 341.096625 -214.450156) (xy 341.118136 -214.49682) (xy 341.132727 -214.546089)
			(xy 341.140096 -214.596942) (xy 341.140542 -214.622634) (xy 341.140043 -214.649321) (xy 341.132088 -214.7021)
			(xy 341.116356 -214.753103) (xy 341.093198 -214.801192) (xy 341.063131 -214.845292) (xy 341.026827 -214.884419)
			(xy 340.985097 -214.917697) (xy 340.938873 -214.944384) (xy 340.889188 -214.963884) (xy 340.837151 -214.975761)
			(xy 340.783926 -214.97975) (xy 340.730701 -214.975761) (xy 340.678664 -214.963884) (xy 340.628979 -214.944384)
			(xy 340.582755 -214.917697) (xy 340.541025 -214.884419) (xy 340.504721 -214.845292) (xy 340.474654 -214.801192)
			(xy 340.451496 -214.753103) (xy 340.435764 -214.7021) (xy 340.427809 -214.649321) (xy 340.42731 -214.622634)
			(xy 340.42731 -214.62238) (xy 340.427853 -214.594564) (xy 340.436509 -214.539609) (xy 340.453592 -214.486664)
			(xy 340.465664 -214.461598) (xy 340.477602 -214.43823) (xy 340.29396 -214.089742) (xy 340.268052 -214.086186)
			(xy 340.242646 -214.082354) (xy 340.193195 -214.068422) (xy 340.146255 -214.047536) (xy 340.102798 -214.02013)
			(xy 340.063725 -213.986771) (xy 340.029843 -213.948149) (xy 340.001855 -213.905065) (xy 339.98034 -213.858411)
			(xy 339.965744 -213.809151) (xy 339.958368 -213.758306) (xy 339.957918 -213.732618) (xy 338.79155 -213.732618)
			(xy 338.79155 -213.732872) (xy 338.79102 -213.760689) (xy 338.782358 -213.815644) (xy 338.76527 -213.868588)
			(xy 338.753196 -213.893654) (xy 338.741258 -213.917022) (xy 338.9249 -214.26551) (xy 338.950808 -214.269066)
			(xy 338.97623 -214.2728) (xy 339.025686 -214.286744) (xy 339.072629 -214.307641) (xy 339.116087 -214.335058)
			(xy 339.15516 -214.368428) (xy 339.18904 -214.407061) (xy 339.217025 -214.450156) (xy 339.238536 -214.49682)
			(xy 339.253127 -214.546089) (xy 339.260496 -214.596942) (xy 339.260942 -214.622634) (xy 339.260443 -214.649321)
			(xy 339.252488 -214.7021) (xy 339.236756 -214.753103) (xy 339.213598 -214.801192) (xy 339.183531 -214.845292)
			(xy 339.147227 -214.884419) (xy 339.105497 -214.917697) (xy 339.059273 -214.944384) (xy 339.009588 -214.963884)
			(xy 338.957551 -214.975761) (xy 338.904326 -214.97975) (xy 338.851101 -214.975761) (xy 338.799064 -214.963884)
			(xy 338.749379 -214.944384) (xy 338.703155 -214.917697) (xy 338.661425 -214.884419) (xy 338.625121 -214.845292)
			(xy 338.595054 -214.801192) (xy 338.571896 -214.753103) (xy 338.556164 -214.7021) (xy 338.548209 -214.649321)
			(xy 338.54771 -214.622634) (xy 338.54771 -214.62238) (xy 338.548253 -214.594564) (xy 338.556909 -214.539609)
			(xy 338.573992 -214.486664) (xy 338.586064 -214.461598) (xy 338.598002 -214.43823) (xy 338.41436 -214.089742)
			(xy 338.388452 -214.086186) (xy 338.363046 -214.082354) (xy 338.313595 -214.068422) (xy 338.266655 -214.047536)
			(xy 338.223198 -214.02013) (xy 338.184125 -213.986771) (xy 338.150243 -213.948149) (xy 338.122255 -213.905065)
			(xy 338.10074 -213.858411) (xy 338.086144 -213.809151) (xy 338.078768 -213.758306) (xy 338.078318 -213.732618)
			(xy 132.202682 -213.732618) (xy 132.202682 -213.732872) (xy 132.202159 -213.760689) (xy 132.193495 -213.815645)
			(xy 132.176404 -213.868589) (xy 132.164328 -213.893654) (xy 132.15239 -213.917022) (xy 132.336032 -214.26551)
			(xy 132.36194 -214.269066) (xy 132.387354 -214.272854) (xy 132.436809 -214.286788) (xy 132.483752 -214.307677)
			(xy 132.527211 -214.335087) (xy 132.566286 -214.368451) (xy 132.600167 -214.407078) (xy 132.628154 -214.450168)
			(xy 132.649666 -214.496829) (xy 132.664258 -214.546094) (xy 132.671628 -214.596944) (xy 132.672074 -214.622634)
			(xy 132.671575 -214.649321) (xy 132.66362 -214.7021) (xy 132.647888 -214.753103) (xy 132.62473 -214.801192)
			(xy 132.594663 -214.845292) (xy 132.558359 -214.884419) (xy 132.516629 -214.917697) (xy 132.470405 -214.944384)
			(xy 132.42072 -214.963884) (xy 132.368683 -214.975761) (xy 132.315458 -214.97975) (xy 132.262233 -214.975761)
			(xy 132.210196 -214.963884) (xy 132.160511 -214.944384) (xy 132.114287 -214.917697) (xy 132.072557 -214.884419)
			(xy 132.036253 -214.845292) (xy 132.006186 -214.801192) (xy 131.983028 -214.753103) (xy 131.967296 -214.7021)
			(xy 131.959341 -214.649321) (xy 131.958842 -214.622634) (xy 131.958842 -214.62238) (xy 131.959392 -214.594564)
			(xy 131.968046 -214.53961) (xy 131.985126 -214.486664) (xy 131.997196 -214.461598) (xy 132.009134 -214.43823)
			(xy 131.825492 -214.089742) (xy 131.799584 -214.086186) (xy 131.77417 -214.082408) (xy 131.724718 -214.068466)
			(xy 131.677778 -214.047572) (xy 131.634323 -214.020159) (xy 131.59525 -213.986793) (xy 131.561371 -213.948166)
			(xy 131.533384 -213.905078) (xy 131.511871 -213.858419) (xy 131.497275 -213.809156) (xy 131.489899 -213.758308)
			(xy 131.48945 -213.732618) (xy 130.323082 -213.732618) (xy 130.323082 -213.732872) (xy 130.322559 -213.760689)
			(xy 130.313895 -213.815645) (xy 130.296804 -213.868589) (xy 130.284728 -213.893654) (xy 130.27279 -213.917022)
			(xy 130.456432 -214.26551) (xy 130.48234 -214.269066) (xy 130.507754 -214.272854) (xy 130.557209 -214.286788)
			(xy 130.604152 -214.307677) (xy 130.647611 -214.335087) (xy 130.686686 -214.368451) (xy 130.720567 -214.407078)
			(xy 130.748554 -214.450168) (xy 130.770066 -214.496829) (xy 130.784658 -214.546094) (xy 130.792028 -214.596944)
			(xy 130.792474 -214.622634) (xy 130.791975 -214.649321) (xy 130.78402 -214.7021) (xy 130.768288 -214.753103)
			(xy 130.74513 -214.801192) (xy 130.715063 -214.845292) (xy 130.678759 -214.884419) (xy 130.637029 -214.917697)
			(xy 130.590805 -214.944384) (xy 130.54112 -214.963884) (xy 130.489083 -214.975761) (xy 130.435858 -214.97975)
			(xy 130.382633 -214.975761) (xy 130.330596 -214.963884) (xy 130.280911 -214.944384) (xy 130.234687 -214.917697)
			(xy 130.192957 -214.884419) (xy 130.156653 -214.845292) (xy 130.126586 -214.801192) (xy 130.103428 -214.753103)
			(xy 130.087696 -214.7021) (xy 130.079741 -214.649321) (xy 130.079242 -214.622634) (xy 130.079242 -214.62238)
			(xy 130.079792 -214.594564) (xy 130.088446 -214.53961) (xy 130.105526 -214.486664) (xy 130.117596 -214.461598)
			(xy 130.129534 -214.43823) (xy 129.945892 -214.089742) (xy 129.919984 -214.086186) (xy 129.89457 -214.082408)
			(xy 129.845118 -214.068466) (xy 129.798178 -214.047572) (xy 129.754723 -214.020159) (xy 129.71565 -213.986793)
			(xy 129.681771 -213.948166) (xy 129.653784 -213.905078) (xy 129.632271 -213.858419) (xy 129.617675 -213.809156)
			(xy 129.610299 -213.758308) (xy 129.60985 -213.732618) (xy 128.443482 -213.732618) (xy 128.443482 -213.732872)
			(xy 128.442959 -213.760689) (xy 128.434295 -213.815645) (xy 128.417204 -213.868589) (xy 128.405128 -213.893654)
			(xy 128.39319 -213.917022) (xy 128.576832 -214.26551) (xy 128.60274 -214.269066) (xy 128.628154 -214.272854)
			(xy 128.677609 -214.286788) (xy 128.724552 -214.307677) (xy 128.768011 -214.335087) (xy 128.807086 -214.368451)
			(xy 128.840967 -214.407078) (xy 128.868954 -214.450168) (xy 128.890466 -214.496829) (xy 128.905058 -214.546094)
			(xy 128.912428 -214.596944) (xy 128.912874 -214.622634) (xy 128.912375 -214.649321) (xy 128.90442 -214.7021)
			(xy 128.888688 -214.753103) (xy 128.86553 -214.801192) (xy 128.835463 -214.845292) (xy 128.799159 -214.884419)
			(xy 128.757429 -214.917697) (xy 128.711205 -214.944384) (xy 128.66152 -214.963884) (xy 128.609483 -214.975761)
			(xy 128.556258 -214.97975) (xy 128.503033 -214.975761) (xy 128.450996 -214.963884) (xy 128.401311 -214.944384)
			(xy 128.355087 -214.917697) (xy 128.313357 -214.884419) (xy 128.277053 -214.845292) (xy 128.246986 -214.801192)
			(xy 128.223828 -214.753103) (xy 128.208096 -214.7021) (xy 128.200141 -214.649321) (xy 128.199642 -214.622634)
			(xy 128.199642 -214.62238) (xy 128.200192 -214.594564) (xy 128.208846 -214.53961) (xy 128.225926 -214.486664)
			(xy 128.237996 -214.461598) (xy 128.249934 -214.43823) (xy 128.066292 -214.089742) (xy 128.040384 -214.086186)
			(xy 128.01497 -214.082408) (xy 127.965518 -214.068466) (xy 127.918578 -214.047572) (xy 127.875123 -214.020159)
			(xy 127.83605 -213.986793) (xy 127.802171 -213.948166) (xy 127.774184 -213.905078) (xy 127.752671 -213.858419)
			(xy 127.738075 -213.809156) (xy 127.730699 -213.758308) (xy 127.73025 -213.732618) (xy 126.563628 -213.732618)
			(xy 126.563628 -213.732872) (xy 126.5631 -213.760689) (xy 126.554437 -213.815644) (xy 126.537349 -213.868589)
			(xy 126.525274 -213.893654) (xy 126.513336 -213.917022) (xy 126.697232 -214.26551) (xy 126.72314 -214.269066)
			(xy 126.748554 -214.272854) (xy 126.798009 -214.286788) (xy 126.844952 -214.307677) (xy 126.888411 -214.335087)
			(xy 126.927486 -214.368451) (xy 126.961367 -214.407078) (xy 126.989354 -214.450168) (xy 127.010866 -214.496829)
			(xy 127.025458 -214.546094) (xy 127.032828 -214.596944) (xy 127.033274 -214.622634) (xy 127.032775 -214.649321)
			(xy 127.02482 -214.7021) (xy 127.009088 -214.753103) (xy 126.98593 -214.801192) (xy 126.955863 -214.845292)
			(xy 126.919559 -214.884419) (xy 126.877829 -214.917697) (xy 126.831605 -214.944384) (xy 126.78192 -214.963884)
			(xy 126.729883 -214.975761) (xy 126.676658 -214.97975) (xy 126.623433 -214.975761) (xy 126.571396 -214.963884)
			(xy 126.521711 -214.944384) (xy 126.475487 -214.917697) (xy 126.433757 -214.884419) (xy 126.397453 -214.845292)
			(xy 126.367386 -214.801192) (xy 126.344228 -214.753103) (xy 126.328496 -214.7021) (xy 126.320541 -214.649321)
			(xy 126.320042 -214.622634) (xy 126.320042 -214.62238) (xy 126.320592 -214.594564) (xy 126.329246 -214.53961)
			(xy 126.346326 -214.486664) (xy 126.358396 -214.461598) (xy 126.370334 -214.43823) (xy 126.186692 -214.089742)
			(xy 126.16053 -214.086186) (xy 126.135122 -214.082372) (xy 126.08567 -214.068436) (xy 126.03873 -214.047548)
			(xy 125.995274 -214.020139) (xy 125.956201 -213.986778) (xy 125.92232 -213.948155) (xy 125.894332 -213.905069)
			(xy 125.872818 -213.858413) (xy 125.858221 -213.809152) (xy 125.850846 -213.758307) (xy 125.850396 -213.732618)
			(xy 124.684028 -213.732618) (xy 124.683406 -213.761872) (xy 124.673809 -213.819588) (xy 124.654925 -213.874965)
			(xy 124.64161 -213.90102) (xy 124.62891 -213.924642) (xy 124.805694 -214.265002) (xy 124.832872 -214.267796)
			(xy 124.858915 -214.270933) (xy 124.909767 -214.283795) (xy 124.958187 -214.303965) (xy 125.00313 -214.331009)
			(xy 125.043628 -214.364344) (xy 125.078807 -214.403251) (xy 125.107909 -214.446891) (xy 125.130305 -214.494322)
			(xy 125.145513 -214.544522) (xy 125.153205 -214.596408) (xy 125.153674 -214.622634) (xy 125.153175 -214.649321)
			(xy 125.14522 -214.7021) (xy 125.129488 -214.753103) (xy 125.10633 -214.801192) (xy 125.076263 -214.845292)
			(xy 125.039959 -214.884419) (xy 124.998229 -214.917697) (xy 124.952005 -214.944384) (xy 124.90232 -214.963884)
			(xy 124.850283 -214.975761) (xy 124.797058 -214.97975) (xy 124.743833 -214.975761) (xy 124.691796 -214.963884)
			(xy 124.642111 -214.944384) (xy 124.595887 -214.917697) (xy 124.554157 -214.884419) (xy 124.517853 -214.845292)
			(xy 124.487786 -214.801192) (xy 124.464628 -214.753103) (xy 124.448896 -214.7021) (xy 124.440941 -214.649321)
			(xy 124.440442 -214.622634) (xy 124.441103 -214.592125) (xy 124.45152 -214.532002) (xy 124.471991 -214.474519)
			(xy 124.486416 -214.447628) (xy 124.499878 -214.423752) (xy 124.326904 -214.09025) (xy 124.298964 -214.088218)
			(xy 124.272482 -214.085641) (xy 124.220665 -214.073553) (xy 124.17122 -214.053903) (xy 124.125242 -214.027125)
			(xy 124.083751 -213.993815) (xy 124.047669 -213.954712) (xy 124.017795 -213.910682) (xy 123.994793 -213.862704)
			(xy 123.979173 -213.811841) (xy 123.971282 -213.759222) (xy 123.970796 -213.732618) (xy 122.804682 -213.732618)
			(xy 122.804682 -213.732872) (xy 122.804159 -213.760689) (xy 122.795495 -213.815645) (xy 122.778404 -213.868589)
			(xy 122.766328 -213.893654) (xy 122.75439 -213.917022) (xy 122.938032 -214.26551) (xy 122.96394 -214.269066)
			(xy 122.989354 -214.272854) (xy 123.038809 -214.286788) (xy 123.085752 -214.307677) (xy 123.129211 -214.335087)
			(xy 123.168286 -214.368451) (xy 123.202167 -214.407078) (xy 123.230154 -214.450168) (xy 123.251666 -214.496829)
			(xy 123.266258 -214.546094) (xy 123.273628 -214.596944) (xy 123.274074 -214.622634) (xy 123.273575 -214.649321)
			(xy 123.26562 -214.7021) (xy 123.249888 -214.753103) (xy 123.22673 -214.801192) (xy 123.196663 -214.845292)
			(xy 123.160359 -214.884419) (xy 123.118629 -214.917697) (xy 123.072405 -214.944384) (xy 123.02272 -214.963884)
			(xy 122.970683 -214.975761) (xy 122.917458 -214.97975) (xy 122.864233 -214.975761) (xy 122.812196 -214.963884)
			(xy 122.762511 -214.944384) (xy 122.716287 -214.917697) (xy 122.674557 -214.884419) (xy 122.638253 -214.845292)
			(xy 122.608186 -214.801192) (xy 122.585028 -214.753103) (xy 122.569296 -214.7021) (xy 122.561341 -214.649321)
			(xy 122.560842 -214.622634) (xy 122.560842 -214.62238) (xy 122.561392 -214.594564) (xy 122.570046 -214.53961)
			(xy 122.587126 -214.486664) (xy 122.599196 -214.461598) (xy 122.611134 -214.43823) (xy 122.427492 -214.089742)
			(xy 122.401584 -214.086186) (xy 122.37617 -214.082408) (xy 122.326718 -214.068466) (xy 122.279778 -214.047572)
			(xy 122.236323 -214.020159) (xy 122.19725 -213.986793) (xy 122.163371 -213.948166) (xy 122.135384 -213.905078)
			(xy 122.113871 -213.858419) (xy 122.099275 -213.809156) (xy 122.091899 -213.758308) (xy 122.09145 -213.732618)
			(xy 120.925082 -213.732618) (xy 120.925082 -213.732872) (xy 120.924559 -213.760689) (xy 120.915895 -213.815645)
			(xy 120.898804 -213.868589) (xy 120.886728 -213.893654) (xy 120.87479 -213.917022) (xy 121.058432 -214.26551)
			(xy 121.08434 -214.269066) (xy 121.109754 -214.272854) (xy 121.159209 -214.286788) (xy 121.206152 -214.307677)
			(xy 121.249611 -214.335087) (xy 121.288686 -214.368451) (xy 121.322567 -214.407078) (xy 121.350554 -214.450168)
			(xy 121.372066 -214.496829) (xy 121.386658 -214.546094) (xy 121.394028 -214.596944) (xy 121.394474 -214.622634)
			(xy 121.393975 -214.649321) (xy 121.38602 -214.7021) (xy 121.370288 -214.753103) (xy 121.34713 -214.801192)
			(xy 121.317063 -214.845292) (xy 121.280759 -214.884419) (xy 121.239029 -214.917697) (xy 121.192805 -214.944384)
			(xy 121.14312 -214.963884) (xy 121.091083 -214.975761) (xy 121.037858 -214.97975) (xy 120.984633 -214.975761)
			(xy 120.932596 -214.963884) (xy 120.882911 -214.944384) (xy 120.836687 -214.917697) (xy 120.794957 -214.884419)
			(xy 120.758653 -214.845292) (xy 120.728586 -214.801192) (xy 120.705428 -214.753103) (xy 120.689696 -214.7021)
			(xy 120.681741 -214.649321) (xy 120.681242 -214.622634) (xy 120.681242 -214.62238) (xy 120.681792 -214.594564)
			(xy 120.690446 -214.53961) (xy 120.707526 -214.486664) (xy 120.719596 -214.461598) (xy 120.731534 -214.43823)
			(xy 120.547892 -214.089742) (xy 120.521984 -214.086186) (xy 120.49657 -214.082408) (xy 120.447118 -214.068466)
			(xy 120.400178 -214.047572) (xy 120.356723 -214.020159) (xy 120.31765 -213.986793) (xy 120.283771 -213.948166)
			(xy 120.255784 -213.905078) (xy 120.234271 -213.858419) (xy 120.219675 -213.809156) (xy 120.212299 -213.758308)
			(xy 120.21185 -213.732618) (xy 119.045482 -213.732618) (xy 119.045482 -213.732872) (xy 119.044959 -213.760689)
			(xy 119.036295 -213.815645) (xy 119.019204 -213.868589) (xy 119.007128 -213.893654) (xy 118.99519 -213.917022)
			(xy 119.178832 -214.26551) (xy 119.20474 -214.269066) (xy 119.230154 -214.272854) (xy 119.279609 -214.286788)
			(xy 119.326552 -214.307677) (xy 119.370011 -214.335087) (xy 119.409086 -214.368451) (xy 119.442967 -214.407078)
			(xy 119.470954 -214.450168) (xy 119.492466 -214.496829) (xy 119.507058 -214.546094) (xy 119.514428 -214.596944)
			(xy 119.514874 -214.622634) (xy 119.514375 -214.649321) (xy 119.50642 -214.7021) (xy 119.490688 -214.753103)
			(xy 119.46753 -214.801192) (xy 119.437463 -214.845292) (xy 119.401159 -214.884419) (xy 119.359429 -214.917697)
			(xy 119.313205 -214.944384) (xy 119.26352 -214.963884) (xy 119.211483 -214.975761) (xy 119.158258 -214.97975)
			(xy 119.105033 -214.975761) (xy 119.052996 -214.963884) (xy 119.003311 -214.944384) (xy 118.957087 -214.917697)
			(xy 118.915357 -214.884419) (xy 118.879053 -214.845292) (xy 118.848986 -214.801192) (xy 118.825828 -214.753103)
			(xy 118.810096 -214.7021) (xy 118.802141 -214.649321) (xy 118.801642 -214.622634) (xy 118.801642 -214.62238)
			(xy 118.802192 -214.594564) (xy 118.810846 -214.53961) (xy 118.827926 -214.486664) (xy 118.839996 -214.461598)
			(xy 118.851934 -214.43823) (xy 118.668292 -214.089742) (xy 118.642384 -214.086186) (xy 118.61697 -214.082408)
			(xy 118.567518 -214.068466) (xy 118.520578 -214.047572) (xy 118.477123 -214.020159) (xy 118.43805 -213.986793)
			(xy 118.404171 -213.948166) (xy 118.376184 -213.905078) (xy 118.354671 -213.858419) (xy 118.340075 -213.809156)
			(xy 118.332699 -213.758308) (xy 118.33225 -213.732618) (xy 117.165882 -213.732618) (xy 117.165882 -213.732872)
			(xy 117.165359 -213.760689) (xy 117.156695 -213.815645) (xy 117.139604 -213.868589) (xy 117.127528 -213.893654)
			(xy 117.11559 -213.917022) (xy 117.299232 -214.26551) (xy 117.32514 -214.269066) (xy 117.350554 -214.272854)
			(xy 117.400009 -214.286788) (xy 117.446952 -214.307677) (xy 117.490411 -214.335087) (xy 117.529486 -214.368451)
			(xy 117.563367 -214.407078) (xy 117.591354 -214.450168) (xy 117.612866 -214.496829) (xy 117.627458 -214.546094)
			(xy 117.634828 -214.596944) (xy 117.635274 -214.622634) (xy 117.634775 -214.649321) (xy 117.62682 -214.7021)
			(xy 117.611088 -214.753103) (xy 117.58793 -214.801192) (xy 117.557863 -214.845292) (xy 117.521559 -214.884419)
			(xy 117.479829 -214.917697) (xy 117.433605 -214.944384) (xy 117.38392 -214.963884) (xy 117.331883 -214.975761)
			(xy 117.278658 -214.97975) (xy 117.225433 -214.975761) (xy 117.173396 -214.963884) (xy 117.123711 -214.944384)
			(xy 117.077487 -214.917697) (xy 117.035757 -214.884419) (xy 116.999453 -214.845292) (xy 116.969386 -214.801192)
			(xy 116.946228 -214.753103) (xy 116.930496 -214.7021) (xy 116.922541 -214.649321) (xy 116.922042 -214.622634)
			(xy 116.922042 -214.62238) (xy 116.922592 -214.594564) (xy 116.931246 -214.53961) (xy 116.948326 -214.486664)
			(xy 116.960396 -214.461598) (xy 116.972334 -214.43823) (xy 116.788692 -214.089742) (xy 116.762784 -214.086186)
			(xy 116.73737 -214.082408) (xy 116.687918 -214.068466) (xy 116.640978 -214.047572) (xy 116.597523 -214.020159)
			(xy 116.55845 -213.986793) (xy 116.524571 -213.948166) (xy 116.496584 -213.905078) (xy 116.475071 -213.858419)
			(xy 116.460475 -213.809156) (xy 116.453099 -213.758308) (xy 116.45265 -213.732618) (xy 115.286282 -213.732618)
			(xy 115.286282 -213.732872) (xy 115.285759 -213.760689) (xy 115.277095 -213.815645) (xy 115.260004 -213.868589)
			(xy 115.247928 -213.893654) (xy 115.23599 -213.917022) (xy 115.419632 -214.26551) (xy 115.44554 -214.269066)
			(xy 115.470954 -214.272854) (xy 115.520409 -214.286788) (xy 115.567352 -214.307677) (xy 115.610811 -214.335087)
			(xy 115.649886 -214.368451) (xy 115.683767 -214.407078) (xy 115.711754 -214.450168) (xy 115.733266 -214.496829)
			(xy 115.747858 -214.546094) (xy 115.755228 -214.596944) (xy 115.755674 -214.622634) (xy 115.755175 -214.649321)
			(xy 115.74722 -214.7021) (xy 115.731488 -214.753103) (xy 115.70833 -214.801192) (xy 115.678263 -214.845292)
			(xy 115.641959 -214.884419) (xy 115.600229 -214.917697) (xy 115.554005 -214.944384) (xy 115.50432 -214.963884)
			(xy 115.452283 -214.975761) (xy 115.399058 -214.97975) (xy 115.345833 -214.975761) (xy 115.293796 -214.963884)
			(xy 115.244111 -214.944384) (xy 115.197887 -214.917697) (xy 115.156157 -214.884419) (xy 115.119853 -214.845292)
			(xy 115.089786 -214.801192) (xy 115.066628 -214.753103) (xy 115.050896 -214.7021) (xy 115.042941 -214.649321)
			(xy 115.042442 -214.622634) (xy 115.042442 -214.62238) (xy 115.042992 -214.594564) (xy 115.051646 -214.53961)
			(xy 115.068726 -214.486664) (xy 115.080796 -214.461598) (xy 115.092734 -214.43823) (xy 114.909092 -214.089742)
			(xy 114.883184 -214.086186) (xy 114.85777 -214.082408) (xy 114.808318 -214.068466) (xy 114.761378 -214.047572)
			(xy 114.717923 -214.020159) (xy 114.67885 -213.986793) (xy 114.644971 -213.948166) (xy 114.616984 -213.905078)
			(xy 114.595471 -213.858419) (xy 114.580875 -213.809156) (xy 114.573499 -213.758308) (xy 114.57305 -213.732618)
			(xy 107.767882 -213.732618) (xy 107.767882 -213.732872) (xy 107.767359 -213.760689) (xy 107.758695 -213.815645)
			(xy 107.741604 -213.868589) (xy 107.729528 -213.893654) (xy 107.71759 -213.917022) (xy 107.901232 -214.26551)
			(xy 107.92714 -214.269066) (xy 107.952554 -214.272854) (xy 108.002009 -214.286788) (xy 108.048952 -214.307677)
			(xy 108.092411 -214.335087) (xy 108.131486 -214.368451) (xy 108.165367 -214.407078) (xy 108.193354 -214.450168)
			(xy 108.214866 -214.496829) (xy 108.229458 -214.546094) (xy 108.236828 -214.596944) (xy 108.237274 -214.622634)
			(xy 108.236775 -214.649321) (xy 108.22882 -214.7021) (xy 108.213088 -214.753103) (xy 108.18993 -214.801192)
			(xy 108.159863 -214.845292) (xy 108.123559 -214.884419) (xy 108.081829 -214.917697) (xy 108.035605 -214.944384)
			(xy 107.98592 -214.963884) (xy 107.933883 -214.975761) (xy 107.880658 -214.97975) (xy 107.827433 -214.975761)
			(xy 107.775396 -214.963884) (xy 107.725711 -214.944384) (xy 107.679487 -214.917697) (xy 107.637757 -214.884419)
			(xy 107.601453 -214.845292) (xy 107.571386 -214.801192) (xy 107.548228 -214.753103) (xy 107.532496 -214.7021)
			(xy 107.524541 -214.649321) (xy 107.524042 -214.622634) (xy 107.524042 -214.62238) (xy 107.524592 -214.594564)
			(xy 107.533246 -214.53961) (xy 107.550326 -214.486664) (xy 107.562396 -214.461598) (xy 107.574334 -214.43823)
			(xy 107.390692 -214.089742) (xy 107.364784 -214.086186) (xy 107.33937 -214.082408) (xy 107.289918 -214.068466)
			(xy 107.242978 -214.047572) (xy 107.199523 -214.020159) (xy 107.16045 -213.986793) (xy 107.126571 -213.948166)
			(xy 107.098584 -213.905078) (xy 107.077071 -213.858419) (xy 107.062475 -213.809156) (xy 107.055099 -213.758308)
			(xy 107.05465 -213.732618) (xy 105.888282 -213.732618) (xy 105.888282 -213.732872) (xy 105.887759 -213.760689)
			(xy 105.879095 -213.815645) (xy 105.862004 -213.868589) (xy 105.849928 -213.893654) (xy 105.83799 -213.917022)
			(xy 106.021632 -214.26551) (xy 106.04754 -214.269066) (xy 106.072954 -214.272854) (xy 106.122409 -214.286788)
			(xy 106.169352 -214.307677) (xy 106.212811 -214.335087) (xy 106.251886 -214.368451) (xy 106.285767 -214.407078)
			(xy 106.313754 -214.450168) (xy 106.335266 -214.496829) (xy 106.349858 -214.546094) (xy 106.357228 -214.596944)
			(xy 106.357674 -214.622634) (xy 106.357175 -214.649321) (xy 106.34922 -214.7021) (xy 106.333488 -214.753103)
			(xy 106.31033 -214.801192) (xy 106.280263 -214.845292) (xy 106.243959 -214.884419) (xy 106.202229 -214.917697)
			(xy 106.156005 -214.944384) (xy 106.10632 -214.963884) (xy 106.054283 -214.975761) (xy 106.001058 -214.97975)
			(xy 105.947833 -214.975761) (xy 105.895796 -214.963884) (xy 105.846111 -214.944384) (xy 105.799887 -214.917697)
			(xy 105.758157 -214.884419) (xy 105.721853 -214.845292) (xy 105.691786 -214.801192) (xy 105.668628 -214.753103)
			(xy 105.652896 -214.7021) (xy 105.644941 -214.649321) (xy 105.644442 -214.622634) (xy 105.644442 -214.62238)
			(xy 105.644992 -214.594564) (xy 105.653646 -214.53961) (xy 105.670726 -214.486664) (xy 105.682796 -214.461598)
			(xy 105.694734 -214.43823) (xy 105.511092 -214.089742) (xy 105.485184 -214.086186) (xy 105.45977 -214.082408)
			(xy 105.410318 -214.068466) (xy 105.363378 -214.047572) (xy 105.319923 -214.020159) (xy 105.28085 -213.986793)
			(xy 105.246971 -213.948166) (xy 105.218984 -213.905078) (xy 105.197471 -213.858419) (xy 105.182875 -213.809156)
			(xy 105.175499 -213.758308) (xy 105.17505 -213.732618) (xy 104.008682 -213.732618) (xy 104.008682 -213.732872)
			(xy 104.008159 -213.760689) (xy 103.999495 -213.815645) (xy 103.982404 -213.868589) (xy 103.970328 -213.893654)
			(xy 103.95839 -213.917022) (xy 104.142032 -214.26551) (xy 104.16794 -214.269066) (xy 104.193354 -214.272854)
			(xy 104.242809 -214.286788) (xy 104.289752 -214.307677) (xy 104.333211 -214.335087) (xy 104.372286 -214.368451)
			(xy 104.406167 -214.407078) (xy 104.434154 -214.450168) (xy 104.455666 -214.496829) (xy 104.470258 -214.546094)
			(xy 104.477628 -214.596944) (xy 104.478074 -214.622634) (xy 104.477575 -214.649321) (xy 104.46962 -214.7021)
			(xy 104.453888 -214.753103) (xy 104.43073 -214.801192) (xy 104.400663 -214.845292) (xy 104.364359 -214.884419)
			(xy 104.322629 -214.917697) (xy 104.276405 -214.944384) (xy 104.22672 -214.963884) (xy 104.174683 -214.975761)
			(xy 104.121458 -214.97975) (xy 104.068233 -214.975761) (xy 104.016196 -214.963884) (xy 103.966511 -214.944384)
			(xy 103.920287 -214.917697) (xy 103.878557 -214.884419) (xy 103.842253 -214.845292) (xy 103.812186 -214.801192)
			(xy 103.789028 -214.753103) (xy 103.773296 -214.7021) (xy 103.765341 -214.649321) (xy 103.764842 -214.622634)
			(xy 103.764842 -214.62238) (xy 103.765392 -214.594564) (xy 103.774046 -214.53961) (xy 103.791126 -214.486664)
			(xy 103.803196 -214.461598) (xy 103.815134 -214.43823) (xy 103.631492 -214.089742) (xy 103.605584 -214.086186)
			(xy 103.58017 -214.082408) (xy 103.530718 -214.068466) (xy 103.483778 -214.047572) (xy 103.440323 -214.020159)
			(xy 103.40125 -213.986793) (xy 103.367371 -213.948166) (xy 103.339384 -213.905078) (xy 103.317871 -213.858419)
			(xy 103.303275 -213.809156) (xy 103.295899 -213.758308) (xy 103.29545 -213.732618) (xy 102.129082 -213.732618)
			(xy 102.129082 -213.732872) (xy 102.128559 -213.760689) (xy 102.119895 -213.815645) (xy 102.102804 -213.868589)
			(xy 102.090728 -213.893654) (xy 102.07879 -213.917022) (xy 102.262432 -214.26551) (xy 102.28834 -214.269066)
			(xy 102.313754 -214.272854) (xy 102.363209 -214.286788) (xy 102.410152 -214.307677) (xy 102.453611 -214.335087)
			(xy 102.492686 -214.368451) (xy 102.526567 -214.407078) (xy 102.554554 -214.450168) (xy 102.576066 -214.496829)
			(xy 102.590658 -214.546094) (xy 102.598028 -214.596944) (xy 102.598474 -214.622634) (xy 102.597975 -214.649321)
			(xy 102.59002 -214.7021) (xy 102.574288 -214.753103) (xy 102.55113 -214.801192) (xy 102.521063 -214.845292)
			(xy 102.484759 -214.884419) (xy 102.443029 -214.917697) (xy 102.396805 -214.944384) (xy 102.34712 -214.963884)
			(xy 102.295083 -214.975761) (xy 102.241858 -214.97975) (xy 102.188633 -214.975761) (xy 102.136596 -214.963884)
			(xy 102.086911 -214.944384) (xy 102.040687 -214.917697) (xy 101.998957 -214.884419) (xy 101.962653 -214.845292)
			(xy 101.932586 -214.801192) (xy 101.909428 -214.753103) (xy 101.893696 -214.7021) (xy 101.885741 -214.649321)
			(xy 101.885242 -214.622634) (xy 101.885242 -214.62238) (xy 101.885792 -214.594564) (xy 101.894446 -214.53961)
			(xy 101.911526 -214.486664) (xy 101.923596 -214.461598) (xy 101.935534 -214.43823) (xy 101.751892 -214.089742)
			(xy 101.725984 -214.086186) (xy 101.70057 -214.082408) (xy 101.651118 -214.068466) (xy 101.604178 -214.047572)
			(xy 101.560723 -214.020159) (xy 101.52165 -213.986793) (xy 101.487771 -213.948166) (xy 101.459784 -213.905078)
			(xy 101.438271 -213.858419) (xy 101.423675 -213.809156) (xy 101.416299 -213.758308) (xy 101.41585 -213.732618)
			(xy 100.249482 -213.732618) (xy 100.249482 -213.732872) (xy 100.248959 -213.760689) (xy 100.240295 -213.815645)
			(xy 100.223204 -213.868589) (xy 100.211128 -213.893654) (xy 100.19919 -213.917022) (xy 100.382832 -214.26551)
			(xy 100.40874 -214.269066) (xy 100.434154 -214.272854) (xy 100.483609 -214.286788) (xy 100.530552 -214.307677)
			(xy 100.574011 -214.335087) (xy 100.613086 -214.368451) (xy 100.646967 -214.407078) (xy 100.674954 -214.450168)
			(xy 100.696466 -214.496829) (xy 100.711058 -214.546094) (xy 100.718428 -214.596944) (xy 100.718874 -214.622634)
			(xy 100.718375 -214.649321) (xy 100.71042 -214.7021) (xy 100.694688 -214.753103) (xy 100.67153 -214.801192)
			(xy 100.641463 -214.845292) (xy 100.605159 -214.884419) (xy 100.563429 -214.917697) (xy 100.517205 -214.944384)
			(xy 100.46752 -214.963884) (xy 100.415483 -214.975761) (xy 100.362258 -214.97975) (xy 100.309033 -214.975761)
			(xy 100.256996 -214.963884) (xy 100.207311 -214.944384) (xy 100.161087 -214.917697) (xy 100.119357 -214.884419)
			(xy 100.083053 -214.845292) (xy 100.052986 -214.801192) (xy 100.029828 -214.753103) (xy 100.014096 -214.7021)
			(xy 100.006141 -214.649321) (xy 100.005642 -214.622634) (xy 100.005642 -214.62238) (xy 100.006192 -214.594564)
			(xy 100.014846 -214.53961) (xy 100.031926 -214.486664) (xy 100.043996 -214.461598) (xy 100.055934 -214.43823)
			(xy 99.872292 -214.089742) (xy 99.846384 -214.086186) (xy 99.82097 -214.082408) (xy 99.771518 -214.068466)
			(xy 99.724578 -214.047572) (xy 99.681123 -214.020159) (xy 99.64205 -213.986793) (xy 99.608171 -213.948166)
			(xy 99.580184 -213.905078) (xy 99.558671 -213.858419) (xy 99.544075 -213.809156) (xy 99.536699 -213.758308)
			(xy 99.53625 -213.732618) (xy 98.369882 -213.732618) (xy 98.369882 -213.732872) (xy 98.369359 -213.760689)
			(xy 98.360695 -213.815645) (xy 98.343604 -213.868589) (xy 98.331528 -213.893654) (xy 98.31959 -213.917022)
			(xy 98.503232 -214.26551) (xy 98.52914 -214.269066) (xy 98.554554 -214.272854) (xy 98.604009 -214.286788)
			(xy 98.650952 -214.307677) (xy 98.694411 -214.335087) (xy 98.733486 -214.368451) (xy 98.767367 -214.407078)
			(xy 98.795354 -214.450168) (xy 98.816866 -214.496829) (xy 98.831458 -214.546094) (xy 98.838828 -214.596944)
			(xy 98.839274 -214.622634) (xy 98.838775 -214.649321) (xy 98.83082 -214.7021) (xy 98.815088 -214.753103)
			(xy 98.79193 -214.801192) (xy 98.761863 -214.845292) (xy 98.725559 -214.884419) (xy 98.683829 -214.917697)
			(xy 98.637605 -214.944384) (xy 98.58792 -214.963884) (xy 98.535883 -214.975761) (xy 98.482658 -214.97975)
			(xy 98.429433 -214.975761) (xy 98.377396 -214.963884) (xy 98.327711 -214.944384) (xy 98.281487 -214.917697)
			(xy 98.239757 -214.884419) (xy 98.203453 -214.845292) (xy 98.173386 -214.801192) (xy 98.150228 -214.753103)
			(xy 98.134496 -214.7021) (xy 98.126541 -214.649321) (xy 98.126042 -214.622634) (xy 98.126042 -214.62238)
			(xy 98.126592 -214.594564) (xy 98.135246 -214.53961) (xy 98.152326 -214.486664) (xy 98.164396 -214.461598)
			(xy 98.176334 -214.43823) (xy 97.992692 -214.089742) (xy 97.966784 -214.086186) (xy 97.94137 -214.082408)
			(xy 97.891918 -214.068466) (xy 97.844978 -214.047572) (xy 97.801523 -214.020159) (xy 97.76245 -213.986793)
			(xy 97.728571 -213.948166) (xy 97.700584 -213.905078) (xy 97.679071 -213.858419) (xy 97.664475 -213.809156)
			(xy 97.657099 -213.758308) (xy 97.65665 -213.732618) (xy 96.490282 -213.732618) (xy 96.490282 -213.732872)
			(xy 96.489759 -213.760689) (xy 96.481095 -213.815645) (xy 96.464004 -213.868589) (xy 96.451928 -213.893654)
			(xy 96.43999 -213.917022) (xy 96.623632 -214.26551) (xy 96.64954 -214.269066) (xy 96.674954 -214.272854)
			(xy 96.724409 -214.286788) (xy 96.771352 -214.307677) (xy 96.814811 -214.335087) (xy 96.853886 -214.368451)
			(xy 96.887767 -214.407078) (xy 96.915754 -214.450168) (xy 96.937266 -214.496829) (xy 96.951858 -214.546094)
			(xy 96.959228 -214.596944) (xy 96.959674 -214.622634) (xy 96.959175 -214.649321) (xy 96.95122 -214.7021)
			(xy 96.935488 -214.753103) (xy 96.91233 -214.801192) (xy 96.882263 -214.845292) (xy 96.845959 -214.884419)
			(xy 96.804229 -214.917697) (xy 96.758005 -214.944384) (xy 96.70832 -214.963884) (xy 96.656283 -214.975761)
			(xy 96.603058 -214.97975) (xy 96.549833 -214.975761) (xy 96.497796 -214.963884) (xy 96.448111 -214.944384)
			(xy 96.401887 -214.917697) (xy 96.360157 -214.884419) (xy 96.323853 -214.845292) (xy 96.293786 -214.801192)
			(xy 96.270628 -214.753103) (xy 96.254896 -214.7021) (xy 96.246941 -214.649321) (xy 96.246442 -214.622634)
			(xy 96.246442 -214.62238) (xy 96.246992 -214.594564) (xy 96.255646 -214.53961) (xy 96.272726 -214.486664)
			(xy 96.284796 -214.461598) (xy 96.296734 -214.43823) (xy 96.113092 -214.089742) (xy 96.087184 -214.086186)
			(xy 96.06177 -214.082408) (xy 96.012318 -214.068466) (xy 95.965378 -214.047572) (xy 95.921923 -214.020159)
			(xy 95.88285 -213.986793) (xy 95.848971 -213.948166) (xy 95.820984 -213.905078) (xy 95.799471 -213.858419)
			(xy 95.784875 -213.809156) (xy 95.777499 -213.758308) (xy 95.77705 -213.732618) (xy 94.610682 -213.732618)
			(xy 94.610682 -213.732872) (xy 94.610159 -213.760689) (xy 94.601495 -213.815645) (xy 94.584404 -213.868589)
			(xy 94.572328 -213.893654) (xy 94.56039 -213.917022) (xy 94.744032 -214.26551) (xy 94.76994 -214.269066)
			(xy 94.795354 -214.272854) (xy 94.844809 -214.286788) (xy 94.891752 -214.307677) (xy 94.935211 -214.335087)
			(xy 94.974286 -214.368451) (xy 95.008167 -214.407078) (xy 95.036154 -214.450168) (xy 95.057666 -214.496829)
			(xy 95.072258 -214.546094) (xy 95.079628 -214.596944) (xy 95.080074 -214.622634) (xy 95.079575 -214.649321)
			(xy 95.07162 -214.7021) (xy 95.055888 -214.753103) (xy 95.03273 -214.801192) (xy 95.002663 -214.845292)
			(xy 94.966359 -214.884419) (xy 94.924629 -214.917697) (xy 94.878405 -214.944384) (xy 94.82872 -214.963884)
			(xy 94.776683 -214.975761) (xy 94.723458 -214.97975) (xy 94.670233 -214.975761) (xy 94.618196 -214.963884)
			(xy 94.568511 -214.944384) (xy 94.522287 -214.917697) (xy 94.480557 -214.884419) (xy 94.444253 -214.845292)
			(xy 94.414186 -214.801192) (xy 94.391028 -214.753103) (xy 94.375296 -214.7021) (xy 94.367341 -214.649321)
			(xy 94.366842 -214.622634) (xy 94.366842 -214.62238) (xy 94.367392 -214.594564) (xy 94.376046 -214.53961)
			(xy 94.393126 -214.486664) (xy 94.405196 -214.461598) (xy 94.417134 -214.43823) (xy 94.233492 -214.089742)
			(xy 94.207584 -214.086186) (xy 94.18217 -214.082408) (xy 94.132718 -214.068466) (xy 94.085778 -214.047572)
			(xy 94.042323 -214.020159) (xy 94.00325 -213.986793) (xy 93.969371 -213.948166) (xy 93.941384 -213.905078)
			(xy 93.919871 -213.858419) (xy 93.905275 -213.809156) (xy 93.897899 -213.758308) (xy 93.89745 -213.732618)
			(xy 92.731082 -213.732618) (xy 92.731082 -213.732872) (xy 92.730559 -213.760689) (xy 92.721895 -213.815645)
			(xy 92.704804 -213.868589) (xy 92.692728 -213.893654) (xy 92.68079 -213.917022) (xy 92.864432 -214.26551)
			(xy 92.89034 -214.269066) (xy 92.915754 -214.272854) (xy 92.965209 -214.286788) (xy 93.012152 -214.307677)
			(xy 93.055611 -214.335087) (xy 93.094686 -214.368451) (xy 93.128567 -214.407078) (xy 93.156554 -214.450168)
			(xy 93.178066 -214.496829) (xy 93.192658 -214.546094) (xy 93.200028 -214.596944) (xy 93.200474 -214.622634)
			(xy 93.199975 -214.649321) (xy 93.19202 -214.7021) (xy 93.176288 -214.753103) (xy 93.15313 -214.801192)
			(xy 93.123063 -214.845292) (xy 93.086759 -214.884419) (xy 93.045029 -214.917697) (xy 92.998805 -214.944384)
			(xy 92.94912 -214.963884) (xy 92.897083 -214.975761) (xy 92.843858 -214.97975) (xy 92.790633 -214.975761)
			(xy 92.738596 -214.963884) (xy 92.688911 -214.944384) (xy 92.642687 -214.917697) (xy 92.600957 -214.884419)
			(xy 92.564653 -214.845292) (xy 92.534586 -214.801192) (xy 92.511428 -214.753103) (xy 92.495696 -214.7021)
			(xy 92.487741 -214.649321) (xy 92.487242 -214.622634) (xy 92.487242 -214.62238) (xy 92.487792 -214.594564)
			(xy 92.496446 -214.53961) (xy 92.513526 -214.486664) (xy 92.525596 -214.461598) (xy 92.537534 -214.43823)
			(xy 92.353892 -214.089742) (xy 92.327984 -214.086186) (xy 92.30257 -214.082408) (xy 92.253118 -214.068466)
			(xy 92.206178 -214.047572) (xy 92.162723 -214.020159) (xy 92.12365 -213.986793) (xy 92.089771 -213.948166)
			(xy 92.061784 -213.905078) (xy 92.040271 -213.858419) (xy 92.025675 -213.809156) (xy 92.018299 -213.758308)
			(xy 92.01785 -213.732618) (xy 90.851482 -213.732618) (xy 90.851482 -213.732872) (xy 90.850959 -213.760689)
			(xy 90.842295 -213.815645) (xy 90.825204 -213.868589) (xy 90.813128 -213.893654) (xy 90.80119 -213.917022)
			(xy 90.984832 -214.26551) (xy 91.01074 -214.269066) (xy 91.036154 -214.272854) (xy 91.085609 -214.286788)
			(xy 91.132552 -214.307677) (xy 91.176011 -214.335087) (xy 91.215086 -214.368451) (xy 91.248967 -214.407078)
			(xy 91.276954 -214.450168) (xy 91.298466 -214.496829) (xy 91.313058 -214.546094) (xy 91.320428 -214.596944)
			(xy 91.320874 -214.622634) (xy 91.320375 -214.649321) (xy 91.31242 -214.7021) (xy 91.296688 -214.753103)
			(xy 91.27353 -214.801192) (xy 91.243463 -214.845292) (xy 91.207159 -214.884419) (xy 91.165429 -214.917697)
			(xy 91.119205 -214.944384) (xy 91.06952 -214.963884) (xy 91.017483 -214.975761) (xy 90.964258 -214.97975)
			(xy 90.911033 -214.975761) (xy 90.858996 -214.963884) (xy 90.809311 -214.944384) (xy 90.763087 -214.917697)
			(xy 90.721357 -214.884419) (xy 90.685053 -214.845292) (xy 90.654986 -214.801192) (xy 90.631828 -214.753103)
			(xy 90.616096 -214.7021) (xy 90.608141 -214.649321) (xy 90.607642 -214.622634) (xy 90.607642 -214.62238)
			(xy 90.608192 -214.594564) (xy 90.616846 -214.53961) (xy 90.633926 -214.486664) (xy 90.645996 -214.461598)
			(xy 90.657934 -214.43823) (xy 90.474292 -214.089742) (xy 90.448384 -214.086186) (xy 90.42297 -214.082408)
			(xy 90.373518 -214.068466) (xy 90.326578 -214.047572) (xy 90.283123 -214.020159) (xy 90.24405 -213.986793)
			(xy 90.210171 -213.948166) (xy 90.182184 -213.905078) (xy 90.160671 -213.858419) (xy 90.146075 -213.809156)
			(xy 90.138699 -213.758308) (xy 90.13825 -213.732618) (xy 2.509012 -213.732618) (xy 2.509012 -215.436704)
			(xy 88.258396 -215.436704) (xy 88.258895 -215.410017) (xy 88.26685 -215.357238) (xy 88.282582 -215.306235)
			(xy 88.30574 -215.258146) (xy 88.335807 -215.214046) (xy 88.372111 -215.174919) (xy 88.413841 -215.141641)
			(xy 88.460065 -215.114954) (xy 88.50975 -215.095454) (xy 88.561787 -215.083577) (xy 88.615012 -215.079588)
			(xy 88.668237 -215.083577) (xy 88.720274 -215.095454) (xy 88.769959 -215.114954) (xy 88.816183 -215.141641)
			(xy 88.857913 -215.174919) (xy 88.894217 -215.214046) (xy 88.924284 -215.258146) (xy 88.947442 -215.306235)
			(xy 88.963174 -215.357238) (xy 88.971129 -215.410017) (xy 88.971628 -215.436704) (xy 89.198196 -215.436704)
			(xy 89.198581 -215.411033) (xy 89.205929 -215.36022) (xy 89.22049 -215.310987) (xy 89.241962 -215.264351)
			(xy 89.269901 -215.221277) (xy 89.303728 -215.182655) (xy 89.342746 -215.149285) (xy 89.386146 -215.121855)
			(xy 89.433031 -215.100934) (xy 89.482433 -215.086954) (xy 89.507822 -215.083136) (xy 89.532714 -215.079834)
			(xy 89.704672 -214.7824) (xy 89.69502 -214.759032) (xy 89.686439 -214.737327) (xy 89.674356 -214.692243)
			(xy 89.668242 -214.645971) (xy 89.667842 -214.622634) (xy 89.668341 -214.595947) (xy 89.676296 -214.543168)
			(xy 89.692028 -214.492165) (xy 89.715186 -214.444076) (xy 89.745253 -214.399976) (xy 89.781557 -214.360849)
			(xy 89.823287 -214.327571) (xy 89.869511 -214.300884) (xy 89.919196 -214.281384) (xy 89.971233 -214.269507)
			(xy 90.024458 -214.265518) (xy 90.077683 -214.269507) (xy 90.12972 -214.281384) (xy 90.179405 -214.300884)
			(xy 90.225629 -214.327571) (xy 90.267359 -214.360849) (xy 90.303663 -214.399976) (xy 90.33373 -214.444076)
			(xy 90.356888 -214.492165) (xy 90.37262 -214.543168) (xy 90.380575 -214.595947) (xy 90.381074 -214.622634)
			(xy 90.380664 -214.648303) (xy 90.373311 -214.699112) (xy 90.358749 -214.748341) (xy 90.337278 -214.794974)
			(xy 90.309342 -214.838045) (xy 90.275518 -214.876665) (xy 90.236505 -214.910036) (xy 90.193111 -214.937468)
			(xy 90.146231 -214.958393) (xy 90.096835 -214.97238) (xy 90.071448 -214.976202) (xy 90.046556 -214.979504)
			(xy 89.874598 -215.276938) (xy 89.88425 -215.300306) (xy 89.892811 -215.322019) (xy 89.904901 -215.367099)
			(xy 89.911024 -215.413368) (xy 89.911428 -215.436704) (xy 91.077796 -215.436704) (xy 91.078181 -215.411033)
			(xy 91.085529 -215.36022) (xy 91.10009 -215.310987) (xy 91.121562 -215.264351) (xy 91.149501 -215.221277)
			(xy 91.183328 -215.182655) (xy 91.222346 -215.149285) (xy 91.265746 -215.121855) (xy 91.312631 -215.100934)
			(xy 91.362033 -215.086954) (xy 91.387422 -215.083136) (xy 91.412314 -215.079834) (xy 91.584272 -214.7824)
			(xy 91.57462 -214.759032) (xy 91.566039 -214.737327) (xy 91.553956 -214.692243) (xy 91.547842 -214.645971)
			(xy 91.547442 -214.622634) (xy 91.547941 -214.595947) (xy 91.555896 -214.543168) (xy 91.571628 -214.492165)
			(xy 91.594786 -214.444076) (xy 91.624853 -214.399976) (xy 91.661157 -214.360849) (xy 91.702887 -214.327571)
			(xy 91.749111 -214.300884) (xy 91.798796 -214.281384) (xy 91.850833 -214.269507) (xy 91.904058 -214.265518)
			(xy 91.957283 -214.269507) (xy 92.00932 -214.281384) (xy 92.059005 -214.300884) (xy 92.105229 -214.327571)
			(xy 92.146959 -214.360849) (xy 92.183263 -214.399976) (xy 92.21333 -214.444076) (xy 92.236488 -214.492165)
			(xy 92.25222 -214.543168) (xy 92.260175 -214.595947) (xy 92.260674 -214.622634) (xy 92.260264 -214.648303)
			(xy 92.252911 -214.699112) (xy 92.238349 -214.748341) (xy 92.216878 -214.794974) (xy 92.188942 -214.838045)
			(xy 92.155118 -214.876665) (xy 92.116105 -214.910036) (xy 92.072711 -214.937468) (xy 92.025831 -214.958393)
			(xy 91.976435 -214.97238) (xy 91.951048 -214.976202) (xy 91.926156 -214.979504) (xy 91.754198 -215.276938)
			(xy 91.76385 -215.300306) (xy 91.772411 -215.322019) (xy 91.784501 -215.367099) (xy 91.790624 -215.413368)
			(xy 91.791028 -215.436704) (xy 92.957396 -215.436704) (xy 92.957781 -215.411033) (xy 92.965129 -215.36022)
			(xy 92.97969 -215.310987) (xy 93.001162 -215.264351) (xy 93.029101 -215.221277) (xy 93.062928 -215.182655)
			(xy 93.101946 -215.149285) (xy 93.145346 -215.121855) (xy 93.192231 -215.100934) (xy 93.241633 -215.086954)
			(xy 93.267022 -215.083136) (xy 93.291914 -215.079834) (xy 93.463872 -214.7824) (xy 93.45422 -214.759032)
			(xy 93.445639 -214.737327) (xy 93.433556 -214.692243) (xy 93.427442 -214.645971) (xy 93.427042 -214.622634)
			(xy 93.427541 -214.595947) (xy 93.435496 -214.543168) (xy 93.451228 -214.492165) (xy 93.474386 -214.444076)
			(xy 93.504453 -214.399976) (xy 93.540757 -214.360849) (xy 93.582487 -214.327571) (xy 93.628711 -214.300884)
			(xy 93.678396 -214.281384) (xy 93.730433 -214.269507) (xy 93.783658 -214.265518) (xy 93.836883 -214.269507)
			(xy 93.88892 -214.281384) (xy 93.938605 -214.300884) (xy 93.984829 -214.327571) (xy 94.026559 -214.360849)
			(xy 94.062863 -214.399976) (xy 94.09293 -214.444076) (xy 94.116088 -214.492165) (xy 94.13182 -214.543168)
			(xy 94.139775 -214.595947) (xy 94.140274 -214.622634) (xy 94.139864 -214.648303) (xy 94.132511 -214.699112)
			(xy 94.117949 -214.748341) (xy 94.096478 -214.794974) (xy 94.068542 -214.838045) (xy 94.034718 -214.876665)
			(xy 93.995705 -214.910036) (xy 93.952311 -214.937468) (xy 93.905431 -214.958393) (xy 93.856035 -214.97238)
			(xy 93.830648 -214.976202) (xy 93.805756 -214.979504) (xy 93.633798 -215.276938) (xy 93.64345 -215.300306)
			(xy 93.652011 -215.322019) (xy 93.664101 -215.367099) (xy 93.670224 -215.413368) (xy 93.670628 -215.436704)
			(xy 94.836996 -215.436704) (xy 94.837381 -215.411033) (xy 94.844729 -215.36022) (xy 94.85929 -215.310987)
			(xy 94.880762 -215.264351) (xy 94.908701 -215.221277) (xy 94.942528 -215.182655) (xy 94.981546 -215.149285)
			(xy 95.024946 -215.121855) (xy 95.071831 -215.100934) (xy 95.121233 -215.086954) (xy 95.146622 -215.083136)
			(xy 95.171514 -215.079834) (xy 95.343472 -214.7824) (xy 95.33382 -214.759032) (xy 95.325239 -214.737327)
			(xy 95.313156 -214.692243) (xy 95.307042 -214.645971) (xy 95.306642 -214.622634) (xy 95.307141 -214.595947)
			(xy 95.315096 -214.543168) (xy 95.330828 -214.492165) (xy 95.353986 -214.444076) (xy 95.384053 -214.399976)
			(xy 95.420357 -214.360849) (xy 95.462087 -214.327571) (xy 95.508311 -214.300884) (xy 95.557996 -214.281384)
			(xy 95.610033 -214.269507) (xy 95.663258 -214.265518) (xy 95.716483 -214.269507) (xy 95.76852 -214.281384)
			(xy 95.818205 -214.300884) (xy 95.864429 -214.327571) (xy 95.906159 -214.360849) (xy 95.942463 -214.399976)
			(xy 95.97253 -214.444076) (xy 95.995688 -214.492165) (xy 96.01142 -214.543168) (xy 96.019375 -214.595947)
			(xy 96.019874 -214.622634) (xy 96.019464 -214.648303) (xy 96.012111 -214.699112) (xy 95.997549 -214.748341)
			(xy 95.976078 -214.794974) (xy 95.948142 -214.838045) (xy 95.914318 -214.876665) (xy 95.875305 -214.910036)
			(xy 95.831911 -214.937468) (xy 95.785031 -214.958393) (xy 95.735635 -214.97238) (xy 95.710248 -214.976202)
			(xy 95.685356 -214.979504) (xy 95.513398 -215.276938) (xy 95.52305 -215.300306) (xy 95.531611 -215.322019)
			(xy 95.543701 -215.367099) (xy 95.549824 -215.413368) (xy 95.550228 -215.436704) (xy 96.716596 -215.436704)
			(xy 96.716981 -215.411033) (xy 96.724329 -215.36022) (xy 96.73889 -215.310987) (xy 96.760362 -215.264351)
			(xy 96.788301 -215.221277) (xy 96.822128 -215.182655) (xy 96.861146 -215.149285) (xy 96.904546 -215.121855)
			(xy 96.951431 -215.100934) (xy 97.000833 -215.086954) (xy 97.026222 -215.083136) (xy 97.051114 -215.079834)
			(xy 97.223072 -214.7824) (xy 97.21342 -214.759032) (xy 97.204839 -214.737327) (xy 97.192756 -214.692243)
			(xy 97.186642 -214.645971) (xy 97.186242 -214.622634) (xy 97.186741 -214.595947) (xy 97.194696 -214.543168)
			(xy 97.210428 -214.492165) (xy 97.233586 -214.444076) (xy 97.263653 -214.399976) (xy 97.299957 -214.360849)
			(xy 97.341687 -214.327571) (xy 97.387911 -214.300884) (xy 97.437596 -214.281384) (xy 97.489633 -214.269507)
			(xy 97.542858 -214.265518) (xy 97.596083 -214.269507) (xy 97.64812 -214.281384) (xy 97.697805 -214.300884)
			(xy 97.744029 -214.327571) (xy 97.785759 -214.360849) (xy 97.822063 -214.399976) (xy 97.85213 -214.444076)
			(xy 97.875288 -214.492165) (xy 97.89102 -214.543168) (xy 97.898975 -214.595947) (xy 97.899474 -214.622634)
			(xy 97.899064 -214.648303) (xy 97.891711 -214.699112) (xy 97.877149 -214.748341) (xy 97.855678 -214.794974)
			(xy 97.827742 -214.838045) (xy 97.793918 -214.876665) (xy 97.754905 -214.910036) (xy 97.711511 -214.937468)
			(xy 97.664631 -214.958393) (xy 97.615235 -214.97238) (xy 97.589848 -214.976202) (xy 97.564956 -214.979504)
			(xy 97.392998 -215.276938) (xy 97.40265 -215.300306) (xy 97.411211 -215.322019) (xy 97.423301 -215.367099)
			(xy 97.429424 -215.413368) (xy 97.429828 -215.436704) (xy 98.596196 -215.436704) (xy 98.596581 -215.411033)
			(xy 98.603929 -215.36022) (xy 98.61849 -215.310987) (xy 98.639962 -215.264351) (xy 98.667901 -215.221277)
			(xy 98.701728 -215.182655) (xy 98.740746 -215.149285) (xy 98.784146 -215.121855) (xy 98.831031 -215.100934)
			(xy 98.880433 -215.086954) (xy 98.905822 -215.083136) (xy 98.930714 -215.079834) (xy 99.102672 -214.7824)
			(xy 99.09302 -214.759032) (xy 99.084439 -214.737327) (xy 99.072356 -214.692243) (xy 99.066242 -214.645971)
			(xy 99.065842 -214.622634) (xy 99.066341 -214.595947) (xy 99.074296 -214.543168) (xy 99.090028 -214.492165)
			(xy 99.113186 -214.444076) (xy 99.143253 -214.399976) (xy 99.179557 -214.360849) (xy 99.221287 -214.327571)
			(xy 99.267511 -214.300884) (xy 99.317196 -214.281384) (xy 99.369233 -214.269507) (xy 99.422458 -214.265518)
			(xy 99.475683 -214.269507) (xy 99.52772 -214.281384) (xy 99.577405 -214.300884) (xy 99.623629 -214.327571)
			(xy 99.665359 -214.360849) (xy 99.701663 -214.399976) (xy 99.73173 -214.444076) (xy 99.754888 -214.492165)
			(xy 99.77062 -214.543168) (xy 99.778575 -214.595947) (xy 99.779074 -214.622634) (xy 99.778664 -214.648303)
			(xy 99.771311 -214.699112) (xy 99.756749 -214.748341) (xy 99.735278 -214.794974) (xy 99.707342 -214.838045)
			(xy 99.673518 -214.876665) (xy 99.634505 -214.910036) (xy 99.591111 -214.937468) (xy 99.544231 -214.958393)
			(xy 99.494835 -214.97238) (xy 99.469448 -214.976202) (xy 99.444556 -214.979504) (xy 99.272598 -215.276938)
			(xy 99.28225 -215.300306) (xy 99.290811 -215.322019) (xy 99.302901 -215.367099) (xy 99.309024 -215.413368)
			(xy 99.309428 -215.436704) (xy 100.475796 -215.436704) (xy 100.476181 -215.411033) (xy 100.483529 -215.36022)
			(xy 100.49809 -215.310987) (xy 100.519562 -215.264351) (xy 100.547501 -215.221277) (xy 100.581328 -215.182655)
			(xy 100.620346 -215.149285) (xy 100.663746 -215.121855) (xy 100.710631 -215.100934) (xy 100.760033 -215.086954)
			(xy 100.785422 -215.083136) (xy 100.810314 -215.079834) (xy 100.982272 -214.7824) (xy 100.97262 -214.759032)
			(xy 100.964039 -214.737327) (xy 100.951956 -214.692243) (xy 100.945842 -214.645971) (xy 100.945442 -214.622634)
			(xy 100.945941 -214.595947) (xy 100.953896 -214.543168) (xy 100.969628 -214.492165) (xy 100.992786 -214.444076)
			(xy 101.022853 -214.399976) (xy 101.059157 -214.360849) (xy 101.100887 -214.327571) (xy 101.147111 -214.300884)
			(xy 101.196796 -214.281384) (xy 101.248833 -214.269507) (xy 101.302058 -214.265518) (xy 101.355283 -214.269507)
			(xy 101.40732 -214.281384) (xy 101.457005 -214.300884) (xy 101.503229 -214.327571) (xy 101.544959 -214.360849)
			(xy 101.581263 -214.399976) (xy 101.61133 -214.444076) (xy 101.634488 -214.492165) (xy 101.65022 -214.543168)
			(xy 101.658175 -214.595947) (xy 101.658674 -214.622634) (xy 101.658264 -214.648303) (xy 101.650911 -214.699112)
			(xy 101.636349 -214.748341) (xy 101.614878 -214.794974) (xy 101.586942 -214.838045) (xy 101.553118 -214.876665)
			(xy 101.514105 -214.910036) (xy 101.470711 -214.937468) (xy 101.423831 -214.958393) (xy 101.374435 -214.97238)
			(xy 101.349048 -214.976202) (xy 101.324156 -214.979504) (xy 101.152198 -215.276938) (xy 101.16185 -215.300306)
			(xy 101.170411 -215.322019) (xy 101.182501 -215.367099) (xy 101.188624 -215.413368) (xy 101.189028 -215.436704)
			(xy 102.355396 -215.436704) (xy 102.355781 -215.411033) (xy 102.363129 -215.36022) (xy 102.37769 -215.310987)
			(xy 102.399162 -215.264351) (xy 102.427101 -215.221277) (xy 102.460928 -215.182655) (xy 102.499946 -215.149285)
			(xy 102.543346 -215.121855) (xy 102.590231 -215.100934) (xy 102.639633 -215.086954) (xy 102.665022 -215.083136)
			(xy 102.689914 -215.079834) (xy 102.861872 -214.7824) (xy 102.85222 -214.759032) (xy 102.843639 -214.737327)
			(xy 102.831556 -214.692243) (xy 102.825442 -214.645971) (xy 102.825042 -214.622634) (xy 102.825541 -214.595947)
			(xy 102.833496 -214.543168) (xy 102.849228 -214.492165) (xy 102.872386 -214.444076) (xy 102.902453 -214.399976)
			(xy 102.938757 -214.360849) (xy 102.980487 -214.327571) (xy 103.026711 -214.300884) (xy 103.076396 -214.281384)
			(xy 103.128433 -214.269507) (xy 103.181658 -214.265518) (xy 103.234883 -214.269507) (xy 103.28692 -214.281384)
			(xy 103.336605 -214.300884) (xy 103.382829 -214.327571) (xy 103.424559 -214.360849) (xy 103.460863 -214.399976)
			(xy 103.49093 -214.444076) (xy 103.514088 -214.492165) (xy 103.52982 -214.543168) (xy 103.537775 -214.595947)
			(xy 103.538274 -214.622634) (xy 103.537864 -214.648303) (xy 103.530511 -214.699112) (xy 103.515949 -214.748341)
			(xy 103.494478 -214.794974) (xy 103.466542 -214.838045) (xy 103.432718 -214.876665) (xy 103.393705 -214.910036)
			(xy 103.350311 -214.937468) (xy 103.303431 -214.958393) (xy 103.254035 -214.97238) (xy 103.228648 -214.976202)
			(xy 103.203756 -214.979504) (xy 103.031798 -215.276938) (xy 103.04145 -215.300306) (xy 103.050011 -215.322019)
			(xy 103.062101 -215.367099) (xy 103.068224 -215.413368) (xy 103.068628 -215.436704) (xy 104.234996 -215.436704)
			(xy 104.235381 -215.411033) (xy 104.242729 -215.36022) (xy 104.25729 -215.310987) (xy 104.278762 -215.264351)
			(xy 104.306701 -215.221277) (xy 104.340528 -215.182655) (xy 104.379546 -215.149285) (xy 104.422946 -215.121855)
			(xy 104.469831 -215.100934) (xy 104.519233 -215.086954) (xy 104.544622 -215.083136) (xy 104.569514 -215.079834)
			(xy 104.741472 -214.7824) (xy 104.73182 -214.759032) (xy 104.723239 -214.737327) (xy 104.711156 -214.692243)
			(xy 104.705042 -214.645971) (xy 104.704642 -214.622634) (xy 104.705141 -214.595947) (xy 104.713096 -214.543168)
			(xy 104.728828 -214.492165) (xy 104.751986 -214.444076) (xy 104.782053 -214.399976) (xy 104.818357 -214.360849)
			(xy 104.860087 -214.327571) (xy 104.906311 -214.300884) (xy 104.955996 -214.281384) (xy 105.008033 -214.269507)
			(xy 105.061258 -214.265518) (xy 105.114483 -214.269507) (xy 105.16652 -214.281384) (xy 105.216205 -214.300884)
			(xy 105.262429 -214.327571) (xy 105.304159 -214.360849) (xy 105.340463 -214.399976) (xy 105.37053 -214.444076)
			(xy 105.393688 -214.492165) (xy 105.40942 -214.543168) (xy 105.417375 -214.595947) (xy 105.417874 -214.622634)
			(xy 105.417464 -214.648303) (xy 105.410111 -214.699112) (xy 105.395549 -214.748341) (xy 105.374078 -214.794974)
			(xy 105.346142 -214.838045) (xy 105.312318 -214.876665) (xy 105.273305 -214.910036) (xy 105.229911 -214.937468)
			(xy 105.183031 -214.958393) (xy 105.133635 -214.97238) (xy 105.108248 -214.976202) (xy 105.083356 -214.979504)
			(xy 104.911398 -215.276938) (xy 104.92105 -215.300306) (xy 104.929611 -215.322019) (xy 104.941701 -215.367099)
			(xy 104.947824 -215.413368) (xy 104.948228 -215.436704) (xy 106.114596 -215.436704) (xy 106.114981 -215.411033)
			(xy 106.122329 -215.36022) (xy 106.13689 -215.310987) (xy 106.158362 -215.264351) (xy 106.186301 -215.221277)
			(xy 106.220128 -215.182655) (xy 106.259146 -215.149285) (xy 106.302546 -215.121855) (xy 106.349431 -215.100934)
			(xy 106.398833 -215.086954) (xy 106.424222 -215.083136) (xy 106.449114 -215.079834) (xy 106.621072 -214.7824)
			(xy 106.61142 -214.759032) (xy 106.602839 -214.737327) (xy 106.590756 -214.692243) (xy 106.584642 -214.645971)
			(xy 106.584242 -214.622634) (xy 106.584741 -214.595947) (xy 106.592696 -214.543168) (xy 106.608428 -214.492165)
			(xy 106.631586 -214.444076) (xy 106.661653 -214.399976) (xy 106.697957 -214.360849) (xy 106.739687 -214.327571)
			(xy 106.785911 -214.300884) (xy 106.835596 -214.281384) (xy 106.887633 -214.269507) (xy 106.940858 -214.265518)
			(xy 106.994083 -214.269507) (xy 107.04612 -214.281384) (xy 107.095805 -214.300884) (xy 107.142029 -214.327571)
			(xy 107.183759 -214.360849) (xy 107.220063 -214.399976) (xy 107.25013 -214.444076) (xy 107.273288 -214.492165)
			(xy 107.28902 -214.543168) (xy 107.296975 -214.595947) (xy 107.297474 -214.622634) (xy 107.297064 -214.648303)
			(xy 107.289711 -214.699112) (xy 107.275149 -214.748341) (xy 107.253678 -214.794974) (xy 107.225742 -214.838045)
			(xy 107.191918 -214.876665) (xy 107.152905 -214.910036) (xy 107.109511 -214.937468) (xy 107.062631 -214.958393)
			(xy 107.013235 -214.97238) (xy 106.987848 -214.976202) (xy 106.962956 -214.979504) (xy 106.790998 -215.276938)
			(xy 106.80065 -215.300306) (xy 106.809211 -215.322019) (xy 106.821301 -215.367099) (xy 106.827424 -215.413368)
			(xy 106.827828 -215.436704) (xy 107.994196 -215.436704) (xy 107.994581 -215.411033) (xy 108.001929 -215.36022)
			(xy 108.01649 -215.310987) (xy 108.037962 -215.264351) (xy 108.065901 -215.221277) (xy 108.099728 -215.182655)
			(xy 108.138746 -215.149285) (xy 108.182146 -215.121855) (xy 108.229031 -215.100934) (xy 108.278433 -215.086954)
			(xy 108.303822 -215.083136) (xy 108.328714 -215.079834) (xy 108.500672 -214.7824) (xy 108.49102 -214.759032)
			(xy 108.482439 -214.737327) (xy 108.470356 -214.692243) (xy 108.464242 -214.645971) (xy 108.463842 -214.622634)
			(xy 108.464341 -214.595947) (xy 108.472296 -214.543168) (xy 108.488028 -214.492165) (xy 108.511186 -214.444076)
			(xy 108.541253 -214.399976) (xy 108.577557 -214.360849) (xy 108.619287 -214.327571) (xy 108.665511 -214.300884)
			(xy 108.715196 -214.281384) (xy 108.767233 -214.269507) (xy 108.820458 -214.265518) (xy 108.873683 -214.269507)
			(xy 108.92572 -214.281384) (xy 108.975405 -214.300884) (xy 109.021629 -214.327571) (xy 109.063359 -214.360849)
			(xy 109.099663 -214.399976) (xy 109.12973 -214.444076) (xy 109.152888 -214.492165) (xy 109.16862 -214.543168)
			(xy 109.169112 -214.546434) (xy 110.34395 -214.546434) (xy 110.344449 -214.519747) (xy 110.352404 -214.466968)
			(xy 110.368136 -214.415965) (xy 110.391294 -214.367876) (xy 110.421361 -214.323776) (xy 110.457665 -214.284649)
			(xy 110.499395 -214.251371) (xy 110.545619 -214.224684) (xy 110.595304 -214.205184) (xy 110.647341 -214.193307)
			(xy 110.700566 -214.189318) (xy 110.753791 -214.193307) (xy 110.805828 -214.205184) (xy 110.855513 -214.224684)
			(xy 110.901737 -214.251371) (xy 110.943467 -214.284649) (xy 110.979771 -214.323776) (xy 111.009838 -214.367876)
			(xy 111.032996 -214.415965) (xy 111.048728 -214.466968) (xy 111.056683 -214.519747) (xy 111.057181 -214.5464)
			(xy 112.223635 -214.5464) (xy 112.227612 -214.493335) (xy 112.239452 -214.441456) (xy 112.258892 -214.39192)
			(xy 112.285497 -214.345835) (xy 112.318673 -214.304229) (xy 112.357679 -214.268033) (xy 112.401643 -214.238053)
			(xy 112.449585 -214.214961) (xy 112.500433 -214.199271) (xy 112.553051 -214.191334) (xy 112.579658 -214.190834)
			(xy 112.604627 -214.191287) (xy 112.654075 -214.198276) (xy 112.70206 -214.212107) (xy 112.747641 -214.232511)
			(xy 112.789922 -214.259085) (xy 112.828074 -214.291308) (xy 112.861347 -214.328548) (xy 112.875568 -214.349076)
			(xy 113.223548 -214.349076) (xy 113.237736 -214.328521) (xy 113.271006 -214.29127) (xy 113.30916 -214.259038)
			(xy 113.351446 -214.232459) (xy 113.397035 -214.212056) (xy 113.445029 -214.19823) (xy 113.494485 -214.191252)
			(xy 113.519458 -214.190834) (xy 113.546076 -214.191235) (xy 113.598717 -214.199164) (xy 113.649589 -214.214851)
			(xy 113.697554 -214.237945) (xy 113.741542 -214.26793) (xy 113.780568 -214.304137) (xy 113.813762 -214.345756)
			(xy 113.840382 -214.391858) (xy 113.859832 -214.441413) (xy 113.871679 -214.493314) (xy 113.875658 -214.5464)
			(xy 113.871679 -214.599486) (xy 113.859832 -214.651387) (xy 113.840382 -214.700942) (xy 113.813762 -214.747044)
			(xy 113.780568 -214.788663) (xy 113.741542 -214.82487) (xy 113.697554 -214.854855) (xy 113.649589 -214.877949)
			(xy 113.598717 -214.893636) (xy 113.546076 -214.901565) (xy 113.519458 -214.902034) (xy 113.494488 -214.901583)
			(xy 113.44504 -214.894596) (xy 113.397054 -214.880765) (xy 113.351473 -214.860362) (xy 113.309192 -214.833787)
			(xy 113.27104 -214.801563) (xy 113.237768 -214.764321) (xy 113.223548 -214.743792) (xy 112.875568 -214.743792)
			(xy 112.86136 -214.764332) (xy 112.828094 -214.801586) (xy 112.789944 -214.83382) (xy 112.747661 -214.860401)
			(xy 112.702076 -214.880806) (xy 112.654084 -214.894635) (xy 112.60463 -214.901615) (xy 112.579658 -214.902034)
			(xy 112.553051 -214.901466) (xy 112.500433 -214.893529) (xy 112.449585 -214.877839) (xy 112.401643 -214.854747)
			(xy 112.357679 -214.824767) (xy 112.318673 -214.788571) (xy 112.285497 -214.746965) (xy 112.258892 -214.70088)
			(xy 112.239452 -214.651344) (xy 112.227612 -214.599465) (xy 112.223635 -214.5464) (xy 111.057181 -214.5464)
			(xy 111.057182 -214.546434) (xy 111.057182 -214.546688) (xy 111.056628 -214.574504) (xy 111.047977 -214.629459)
			(xy 111.030898 -214.682404) (xy 111.018828 -214.70747) (xy 111.00689 -214.730838) (xy 111.190786 -215.07958)
			(xy 111.216694 -215.083136) (xy 111.242109 -215.08691) (xy 111.291563 -215.10085) (xy 111.338504 -215.121743)
			(xy 111.381961 -215.149156) (xy 111.421034 -215.182522) (xy 111.454914 -215.22115) (xy 111.4829 -215.26424)
			(xy 111.504413 -215.3109) (xy 111.519007 -215.360165) (xy 111.52638 -215.411014) (xy 111.526828 -215.436704)
			(xy 113.632996 -215.436704) (xy 113.633409 -215.411024) (xy 113.640776 -215.360196) (xy 113.655358 -215.31095)
			(xy 113.676852 -215.264305) (xy 113.704816 -215.221226) (xy 113.73867 -215.182603) (xy 113.777714 -215.149236)
			(xy 113.82114 -215.121815) (xy 113.868051 -215.100907) (xy 113.917476 -215.086944) (xy 113.942876 -215.083136)
			(xy 113.967514 -215.079834) (xy 114.139726 -214.7824) (xy 114.130074 -214.759032) (xy 114.12149 -214.737328)
			(xy 114.109409 -214.692244) (xy 114.103295 -214.645971) (xy 114.102896 -214.622634) (xy 114.103395 -214.595947)
			(xy 114.11135 -214.543168) (xy 114.127082 -214.492165) (xy 114.15024 -214.444076) (xy 114.180307 -214.399976)
			(xy 114.216611 -214.360849) (xy 114.258341 -214.327571) (xy 114.304565 -214.300884) (xy 114.35425 -214.281384)
			(xy 114.406287 -214.269507) (xy 114.459512 -214.265518) (xy 114.512737 -214.269507) (xy 114.564774 -214.281384)
			(xy 114.614459 -214.300884) (xy 114.660683 -214.327571) (xy 114.702413 -214.360849) (xy 114.738717 -214.399976)
			(xy 114.768784 -214.444076) (xy 114.791942 -214.492165) (xy 114.807674 -214.543168) (xy 114.815629 -214.595947)
			(xy 114.816128 -214.622634) (xy 114.815637 -214.648311) (xy 114.808279 -214.699135) (xy 114.793707 -214.748378)
			(xy 114.772221 -214.795022) (xy 114.744267 -214.8381) (xy 114.710422 -214.876723) (xy 114.671386 -214.910092)
			(xy 114.627967 -214.937515) (xy 114.581063 -214.958426) (xy 114.531645 -214.972392) (xy 114.506248 -214.976202)
			(xy 114.48161 -214.979504) (xy 114.309398 -215.276938) (xy 114.31905 -215.300306) (xy 114.327611 -215.322019)
			(xy 114.339701 -215.367099) (xy 114.345824 -215.413368) (xy 114.346228 -215.436704) (xy 115.512596 -215.436704)
			(xy 115.512981 -215.411033) (xy 115.520329 -215.36022) (xy 115.53489 -215.310987) (xy 115.556362 -215.264351)
			(xy 115.584301 -215.221277) (xy 115.618128 -215.182655) (xy 115.657146 -215.149285) (xy 115.700546 -215.121855)
			(xy 115.747431 -215.100934) (xy 115.796833 -215.086954) (xy 115.822222 -215.083136) (xy 115.847114 -215.079834)
			(xy 116.019072 -214.7824) (xy 116.00942 -214.759032) (xy 116.000839 -214.737327) (xy 115.988756 -214.692243)
			(xy 115.982642 -214.645971) (xy 115.982242 -214.622634) (xy 115.982741 -214.595947) (xy 115.990696 -214.543168)
			(xy 116.006428 -214.492165) (xy 116.029586 -214.444076) (xy 116.059653 -214.399976) (xy 116.095957 -214.360849)
			(xy 116.137687 -214.327571) (xy 116.183911 -214.300884) (xy 116.233596 -214.281384) (xy 116.285633 -214.269507)
			(xy 116.338858 -214.265518) (xy 116.392083 -214.269507) (xy 116.44412 -214.281384) (xy 116.493805 -214.300884)
			(xy 116.540029 -214.327571) (xy 116.581759 -214.360849) (xy 116.618063 -214.399976) (xy 116.64813 -214.444076)
			(xy 116.671288 -214.492165) (xy 116.68702 -214.543168) (xy 116.694975 -214.595947) (xy 116.695474 -214.622634)
			(xy 116.695064 -214.648303) (xy 116.687711 -214.699112) (xy 116.673149 -214.748341) (xy 116.651678 -214.794974)
			(xy 116.623742 -214.838045) (xy 116.589918 -214.876665) (xy 116.550905 -214.910036) (xy 116.507511 -214.937468)
			(xy 116.460631 -214.958393) (xy 116.411235 -214.97238) (xy 116.385848 -214.976202) (xy 116.360956 -214.979504)
			(xy 116.188998 -215.276938) (xy 116.19865 -215.300306) (xy 116.207211 -215.322019) (xy 116.219301 -215.367099)
			(xy 116.225424 -215.413368) (xy 116.225828 -215.436704) (xy 117.392196 -215.436704) (xy 117.392581 -215.411033)
			(xy 117.399929 -215.36022) (xy 117.41449 -215.310987) (xy 117.435962 -215.264351) (xy 117.463901 -215.221277)
			(xy 117.497728 -215.182655) (xy 117.536746 -215.149285) (xy 117.580146 -215.121855) (xy 117.627031 -215.100934)
			(xy 117.676433 -215.086954) (xy 117.701822 -215.083136) (xy 117.726714 -215.079834) (xy 117.898672 -214.7824)
			(xy 117.88902 -214.759032) (xy 117.880439 -214.737327) (xy 117.868356 -214.692243) (xy 117.862242 -214.645971)
			(xy 117.861842 -214.622634) (xy 117.862341 -214.595947) (xy 117.870296 -214.543168) (xy 117.886028 -214.492165)
			(xy 117.909186 -214.444076) (xy 117.939253 -214.399976) (xy 117.975557 -214.360849) (xy 118.017287 -214.327571)
			(xy 118.063511 -214.300884) (xy 118.113196 -214.281384) (xy 118.165233 -214.269507) (xy 118.218458 -214.265518)
			(xy 118.271683 -214.269507) (xy 118.32372 -214.281384) (xy 118.373405 -214.300884) (xy 118.419629 -214.327571)
			(xy 118.461359 -214.360849) (xy 118.497663 -214.399976) (xy 118.52773 -214.444076) (xy 118.550888 -214.492165)
			(xy 118.56662 -214.543168) (xy 118.574575 -214.595947) (xy 118.575074 -214.622634) (xy 118.574664 -214.648303)
			(xy 118.567311 -214.699112) (xy 118.552749 -214.748341) (xy 118.531278 -214.794974) (xy 118.503342 -214.838045)
			(xy 118.469518 -214.876665) (xy 118.430505 -214.910036) (xy 118.387111 -214.937468) (xy 118.340231 -214.958393)
			(xy 118.290835 -214.97238) (xy 118.265448 -214.976202) (xy 118.240556 -214.979504) (xy 118.068598 -215.276938)
			(xy 118.07825 -215.300306) (xy 118.086811 -215.322019) (xy 118.098901 -215.367099) (xy 118.105024 -215.413368)
			(xy 118.105428 -215.436704) (xy 119.271796 -215.436704) (xy 119.272181 -215.411033) (xy 119.279529 -215.36022)
			(xy 119.29409 -215.310987) (xy 119.315562 -215.264351) (xy 119.343501 -215.221277) (xy 119.377328 -215.182655)
			(xy 119.416346 -215.149285) (xy 119.459746 -215.121855) (xy 119.506631 -215.100934) (xy 119.556033 -215.086954)
			(xy 119.581422 -215.083136) (xy 119.606314 -215.079834) (xy 119.778272 -214.7824) (xy 119.76862 -214.759032)
			(xy 119.760039 -214.737327) (xy 119.747956 -214.692243) (xy 119.741842 -214.645971) (xy 119.741442 -214.622634)
			(xy 119.741941 -214.595947) (xy 119.749896 -214.543168) (xy 119.765628 -214.492165) (xy 119.788786 -214.444076)
			(xy 119.818853 -214.399976) (xy 119.855157 -214.360849) (xy 119.896887 -214.327571) (xy 119.943111 -214.300884)
			(xy 119.992796 -214.281384) (xy 120.044833 -214.269507) (xy 120.098058 -214.265518) (xy 120.151283 -214.269507)
			(xy 120.20332 -214.281384) (xy 120.253005 -214.300884) (xy 120.299229 -214.327571) (xy 120.340959 -214.360849)
			(xy 120.377263 -214.399976) (xy 120.40733 -214.444076) (xy 120.430488 -214.492165) (xy 120.44622 -214.543168)
			(xy 120.454175 -214.595947) (xy 120.454674 -214.622634) (xy 120.454264 -214.648303) (xy 120.446911 -214.699112)
			(xy 120.432349 -214.748341) (xy 120.410878 -214.794974) (xy 120.382942 -214.838045) (xy 120.349118 -214.876665)
			(xy 120.310105 -214.910036) (xy 120.266711 -214.937468) (xy 120.219831 -214.958393) (xy 120.170435 -214.97238)
			(xy 120.145048 -214.976202) (xy 120.120156 -214.979504) (xy 119.948198 -215.276938) (xy 119.95785 -215.300306)
			(xy 119.966411 -215.322019) (xy 119.978501 -215.367099) (xy 119.984624 -215.413368) (xy 119.985028 -215.436704)
			(xy 121.151396 -215.436704) (xy 121.151781 -215.411033) (xy 121.159129 -215.36022) (xy 121.17369 -215.310987)
			(xy 121.195162 -215.264351) (xy 121.223101 -215.221277) (xy 121.256928 -215.182655) (xy 121.295946 -215.149285)
			(xy 121.339346 -215.121855) (xy 121.386231 -215.100934) (xy 121.435633 -215.086954) (xy 121.461022 -215.083136)
			(xy 121.485914 -215.079834) (xy 121.657872 -214.7824) (xy 121.64822 -214.759032) (xy 121.639639 -214.737327)
			(xy 121.627556 -214.692243) (xy 121.621442 -214.645971) (xy 121.621042 -214.622634) (xy 121.621541 -214.595947)
			(xy 121.629496 -214.543168) (xy 121.645228 -214.492165) (xy 121.668386 -214.444076) (xy 121.698453 -214.399976)
			(xy 121.734757 -214.360849) (xy 121.776487 -214.327571) (xy 121.822711 -214.300884) (xy 121.872396 -214.281384)
			(xy 121.924433 -214.269507) (xy 121.977658 -214.265518) (xy 122.030883 -214.269507) (xy 122.08292 -214.281384)
			(xy 122.132605 -214.300884) (xy 122.178829 -214.327571) (xy 122.220559 -214.360849) (xy 122.256863 -214.399976)
			(xy 122.28693 -214.444076) (xy 122.310088 -214.492165) (xy 122.32582 -214.543168) (xy 122.333775 -214.595947)
			(xy 122.334274 -214.622634) (xy 122.333864 -214.648303) (xy 122.326511 -214.699112) (xy 122.311949 -214.748341)
			(xy 122.290478 -214.794974) (xy 122.262542 -214.838045) (xy 122.228718 -214.876665) (xy 122.189705 -214.910036)
			(xy 122.146311 -214.937468) (xy 122.099431 -214.958393) (xy 122.050035 -214.97238) (xy 122.024648 -214.976202)
			(xy 121.999756 -214.979504) (xy 121.827798 -215.276938) (xy 121.83745 -215.300306) (xy 121.846011 -215.322019)
			(xy 121.858101 -215.367099) (xy 121.864224 -215.413368) (xy 121.864628 -215.436704) (xy 123.030996 -215.436704)
			(xy 123.031381 -215.411033) (xy 123.038729 -215.36022) (xy 123.05329 -215.310987) (xy 123.074762 -215.264351)
			(xy 123.102701 -215.221277) (xy 123.136528 -215.182655) (xy 123.175546 -215.149285) (xy 123.218946 -215.121855)
			(xy 123.265831 -215.100934) (xy 123.315233 -215.086954) (xy 123.340622 -215.083136) (xy 123.365514 -215.079834)
			(xy 123.537472 -214.7824) (xy 123.52782 -214.759032) (xy 123.519239 -214.737327) (xy 123.507156 -214.692243)
			(xy 123.501042 -214.645971) (xy 123.500642 -214.622634) (xy 123.501141 -214.595947) (xy 123.509096 -214.543168)
			(xy 123.524828 -214.492165) (xy 123.547986 -214.444076) (xy 123.578053 -214.399976) (xy 123.614357 -214.360849)
			(xy 123.656087 -214.327571) (xy 123.702311 -214.300884) (xy 123.751996 -214.281384) (xy 123.804033 -214.269507)
			(xy 123.857258 -214.265518) (xy 123.910483 -214.269507) (xy 123.96252 -214.281384) (xy 124.012205 -214.300884)
			(xy 124.058429 -214.327571) (xy 124.100159 -214.360849) (xy 124.136463 -214.399976) (xy 124.16653 -214.444076)
			(xy 124.189688 -214.492165) (xy 124.20542 -214.543168) (xy 124.213375 -214.595947) (xy 124.213874 -214.622634)
			(xy 124.213464 -214.648303) (xy 124.206111 -214.699112) (xy 124.191549 -214.748341) (xy 124.170078 -214.794974)
			(xy 124.142142 -214.838045) (xy 124.108318 -214.876665) (xy 124.069305 -214.910036) (xy 124.025911 -214.937468)
			(xy 123.979031 -214.958393) (xy 123.929635 -214.97238) (xy 123.904248 -214.976202) (xy 123.879356 -214.979504)
			(xy 123.707398 -215.276938) (xy 123.71705 -215.300306) (xy 123.725611 -215.322019) (xy 123.737701 -215.367099)
			(xy 123.743824 -215.413368) (xy 123.744228 -215.436704) (xy 124.910596 -215.436704) (xy 124.910981 -215.411033)
			(xy 124.918329 -215.36022) (xy 124.93289 -215.310987) (xy 124.954362 -215.264351) (xy 124.982301 -215.221277)
			(xy 125.016128 -215.182655) (xy 125.055146 -215.149285) (xy 125.098546 -215.121855) (xy 125.145431 -215.100934)
			(xy 125.194833 -215.086954) (xy 125.220222 -215.083136) (xy 125.245114 -215.079834) (xy 125.417072 -214.7824)
			(xy 125.40742 -214.759032) (xy 125.398839 -214.737327) (xy 125.386756 -214.692243) (xy 125.380642 -214.645971)
			(xy 125.380242 -214.622634) (xy 125.380741 -214.595947) (xy 125.388696 -214.543168) (xy 125.404428 -214.492165)
			(xy 125.427586 -214.444076) (xy 125.457653 -214.399976) (xy 125.493957 -214.360849) (xy 125.535687 -214.327571)
			(xy 125.581911 -214.300884) (xy 125.631596 -214.281384) (xy 125.683633 -214.269507) (xy 125.736858 -214.265518)
			(xy 125.790083 -214.269507) (xy 125.84212 -214.281384) (xy 125.891805 -214.300884) (xy 125.938029 -214.327571)
			(xy 125.979759 -214.360849) (xy 126.016063 -214.399976) (xy 126.04613 -214.444076) (xy 126.069288 -214.492165)
			(xy 126.08502 -214.543168) (xy 126.092975 -214.595947) (xy 126.093474 -214.622634) (xy 126.093064 -214.648303)
			(xy 126.085711 -214.699112) (xy 126.071149 -214.748341) (xy 126.049678 -214.794974) (xy 126.021742 -214.838045)
			(xy 125.987918 -214.876665) (xy 125.948905 -214.910036) (xy 125.905511 -214.937468) (xy 125.858631 -214.958393)
			(xy 125.809235 -214.97238) (xy 125.783848 -214.976202) (xy 125.758956 -214.979504) (xy 125.586998 -215.276938)
			(xy 125.59665 -215.300306) (xy 125.605211 -215.322019) (xy 125.617301 -215.367099) (xy 125.623424 -215.413368)
			(xy 125.623828 -215.436704) (xy 126.790196 -215.436704) (xy 126.790581 -215.411033) (xy 126.797929 -215.36022)
			(xy 126.81249 -215.310987) (xy 126.833962 -215.264351) (xy 126.861901 -215.221277) (xy 126.895728 -215.182655)
			(xy 126.934746 -215.149285) (xy 126.978146 -215.121855) (xy 127.025031 -215.100934) (xy 127.074433 -215.086954)
			(xy 127.099822 -215.083136) (xy 127.124714 -215.079834) (xy 127.296672 -214.7824) (xy 127.28702 -214.759032)
			(xy 127.278439 -214.737327) (xy 127.266356 -214.692243) (xy 127.260242 -214.645971) (xy 127.259842 -214.622634)
			(xy 127.260341 -214.595947) (xy 127.268296 -214.543168) (xy 127.284028 -214.492165) (xy 127.307186 -214.444076)
			(xy 127.337253 -214.399976) (xy 127.373557 -214.360849) (xy 127.415287 -214.327571) (xy 127.461511 -214.300884)
			(xy 127.511196 -214.281384) (xy 127.563233 -214.269507) (xy 127.616458 -214.265518) (xy 127.669683 -214.269507)
			(xy 127.72172 -214.281384) (xy 127.771405 -214.300884) (xy 127.817629 -214.327571) (xy 127.859359 -214.360849)
			(xy 127.895663 -214.399976) (xy 127.92573 -214.444076) (xy 127.948888 -214.492165) (xy 127.96462 -214.543168)
			(xy 127.972575 -214.595947) (xy 127.973074 -214.622634) (xy 127.972664 -214.648303) (xy 127.965311 -214.699112)
			(xy 127.950749 -214.748341) (xy 127.929278 -214.794974) (xy 127.901342 -214.838045) (xy 127.867518 -214.876665)
			(xy 127.828505 -214.910036) (xy 127.785111 -214.937468) (xy 127.738231 -214.958393) (xy 127.688835 -214.97238)
			(xy 127.663448 -214.976202) (xy 127.638556 -214.979504) (xy 127.466598 -215.276938) (xy 127.47625 -215.300306)
			(xy 127.484811 -215.322019) (xy 127.496901 -215.367099) (xy 127.503024 -215.413368) (xy 127.503428 -215.436704)
			(xy 128.669796 -215.436704) (xy 128.670181 -215.411033) (xy 128.677529 -215.36022) (xy 128.69209 -215.310987)
			(xy 128.713562 -215.264351) (xy 128.741501 -215.221277) (xy 128.775328 -215.182655) (xy 128.814346 -215.149285)
			(xy 128.857746 -215.121855) (xy 128.904631 -215.100934) (xy 128.954033 -215.086954) (xy 128.979422 -215.083136)
			(xy 129.004314 -215.079834) (xy 129.176272 -214.7824) (xy 129.16662 -214.759032) (xy 129.158039 -214.737327)
			(xy 129.145956 -214.692243) (xy 129.139842 -214.645971) (xy 129.139442 -214.622634) (xy 129.139941 -214.595947)
			(xy 129.147896 -214.543168) (xy 129.163628 -214.492165) (xy 129.186786 -214.444076) (xy 129.216853 -214.399976)
			(xy 129.253157 -214.360849) (xy 129.294887 -214.327571) (xy 129.341111 -214.300884) (xy 129.390796 -214.281384)
			(xy 129.442833 -214.269507) (xy 129.496058 -214.265518) (xy 129.549283 -214.269507) (xy 129.60132 -214.281384)
			(xy 129.651005 -214.300884) (xy 129.697229 -214.327571) (xy 129.738959 -214.360849) (xy 129.775263 -214.399976)
			(xy 129.80533 -214.444076) (xy 129.828488 -214.492165) (xy 129.84422 -214.543168) (xy 129.852175 -214.595947)
			(xy 129.852674 -214.622634) (xy 129.852264 -214.648303) (xy 129.844911 -214.699112) (xy 129.830349 -214.748341)
			(xy 129.808878 -214.794974) (xy 129.780942 -214.838045) (xy 129.747118 -214.876665) (xy 129.708105 -214.910036)
			(xy 129.664711 -214.937468) (xy 129.617831 -214.958393) (xy 129.568435 -214.97238) (xy 129.543048 -214.976202)
			(xy 129.518156 -214.979504) (xy 129.346198 -215.276938) (xy 129.35585 -215.300306) (xy 129.364411 -215.322019)
			(xy 129.376501 -215.367099) (xy 129.382624 -215.413368) (xy 129.383028 -215.436704) (xy 130.549396 -215.436704)
			(xy 130.549781 -215.411033) (xy 130.557129 -215.36022) (xy 130.57169 -215.310987) (xy 130.593162 -215.264351)
			(xy 130.621101 -215.221277) (xy 130.654928 -215.182655) (xy 130.693946 -215.149285) (xy 130.737346 -215.121855)
			(xy 130.784231 -215.100934) (xy 130.833633 -215.086954) (xy 130.859022 -215.083136) (xy 130.883914 -215.079834)
			(xy 131.055872 -214.7824) (xy 131.04622 -214.759032) (xy 131.037639 -214.737327) (xy 131.025556 -214.692243)
			(xy 131.019442 -214.645971) (xy 131.019042 -214.622634) (xy 131.019541 -214.595947) (xy 131.027496 -214.543168)
			(xy 131.043228 -214.492165) (xy 131.066386 -214.444076) (xy 131.096453 -214.399976) (xy 131.132757 -214.360849)
			(xy 131.174487 -214.327571) (xy 131.220711 -214.300884) (xy 131.270396 -214.281384) (xy 131.322433 -214.269507)
			(xy 131.375658 -214.265518) (xy 131.428883 -214.269507) (xy 131.48092 -214.281384) (xy 131.530605 -214.300884)
			(xy 131.576829 -214.327571) (xy 131.618559 -214.360849) (xy 131.654863 -214.399976) (xy 131.68493 -214.444076)
			(xy 131.708088 -214.492165) (xy 131.72382 -214.543168) (xy 131.731775 -214.595947) (xy 131.732274 -214.622634)
			(xy 131.731864 -214.648303) (xy 131.724511 -214.699112) (xy 131.709949 -214.748341) (xy 131.688478 -214.794974)
			(xy 131.660542 -214.838045) (xy 131.626718 -214.876665) (xy 131.587705 -214.910036) (xy 131.544311 -214.937468)
			(xy 131.497431 -214.958393) (xy 131.448035 -214.97238) (xy 131.422648 -214.976202) (xy 131.397756 -214.979504)
			(xy 131.225798 -215.276938) (xy 131.23545 -215.300306) (xy 131.244011 -215.322019) (xy 131.256101 -215.367099)
			(xy 131.262224 -215.413368) (xy 131.262628 -215.436704) (xy 132.428996 -215.436704) (xy 132.429381 -215.411033)
			(xy 132.436729 -215.36022) (xy 132.45129 -215.310987) (xy 132.472762 -215.264351) (xy 132.500701 -215.221277)
			(xy 132.534528 -215.182655) (xy 132.573546 -215.149285) (xy 132.616946 -215.121855) (xy 132.663831 -215.100934)
			(xy 132.713233 -215.086954) (xy 132.738622 -215.083136) (xy 132.763514 -215.079834) (xy 132.935472 -214.7824)
			(xy 132.92582 -214.759032) (xy 132.917239 -214.737327) (xy 132.905156 -214.692243) (xy 132.899042 -214.645971)
			(xy 132.898642 -214.622634) (xy 132.899141 -214.595947) (xy 132.907096 -214.543168) (xy 132.922828 -214.492165)
			(xy 132.945986 -214.444076) (xy 132.976053 -214.399976) (xy 133.012357 -214.360849) (xy 133.054087 -214.327571)
			(xy 133.100311 -214.300884) (xy 133.149996 -214.281384) (xy 133.202033 -214.269507) (xy 133.255258 -214.265518)
			(xy 133.308483 -214.269507) (xy 133.36052 -214.281384) (xy 133.410205 -214.300884) (xy 133.456429 -214.327571)
			(xy 133.498159 -214.360849) (xy 133.534463 -214.399976) (xy 133.56453 -214.444076) (xy 133.587688 -214.492165)
			(xy 133.60342 -214.543168) (xy 133.603912 -214.546434) (xy 134.779512 -214.546434) (xy 134.780009 -214.519823)
			(xy 134.787942 -214.467195) (xy 134.803629 -214.416337) (xy 134.826722 -214.368385) (xy 134.856703 -214.32441)
			(xy 134.892904 -214.285395) (xy 134.934515 -214.252212) (xy 134.980607 -214.2256) (xy 135.03015 -214.206156)
			(xy 135.082038 -214.194313) (xy 135.135112 -214.190336) (xy 135.188186 -214.194313) (xy 135.240074 -214.206156)
			(xy 135.289617 -214.2256) (xy 135.335709 -214.252212) (xy 135.37732 -214.285395) (xy 135.413521 -214.32441)
			(xy 135.443502 -214.368385) (xy 135.466595 -214.416337) (xy 135.482282 -214.467195) (xy 135.490215 -214.519823)
			(xy 135.490712 -214.546434) (xy 135.490091 -214.57588) (xy 135.480393 -214.633967) (xy 135.461267 -214.689667)
			(xy 135.447786 -214.715852) (xy 135.641588 -215.082882) (xy 135.66751 -215.086051) (xy 135.718106 -215.098984)
			(xy 135.766267 -215.119175) (xy 135.81096 -215.146188) (xy 135.851225 -215.179443) (xy 135.886196 -215.218227)
			(xy 135.915122 -215.261707) (xy 135.937383 -215.308947) (xy 135.952499 -215.358934) (xy 135.960146 -215.410593)
			(xy 135.960612 -215.436704) (xy 336.198464 -215.436704) (xy 336.198963 -215.410017) (xy 336.206918 -215.357238)
			(xy 336.22265 -215.306235) (xy 336.245808 -215.258146) (xy 336.275875 -215.214046) (xy 336.312179 -215.174919)
			(xy 336.353909 -215.141641) (xy 336.400133 -215.114954) (xy 336.449818 -215.095454) (xy 336.501855 -215.083577)
			(xy 336.55508 -215.079588) (xy 336.608305 -215.083577) (xy 336.660342 -215.095454) (xy 336.710027 -215.114954)
			(xy 336.756251 -215.141641) (xy 336.797981 -215.174919) (xy 336.834285 -215.214046) (xy 336.864352 -215.258146)
			(xy 336.88751 -215.306235) (xy 336.903242 -215.357238) (xy 336.911197 -215.410017) (xy 336.911696 -215.436704)
			(xy 337.138264 -215.436704) (xy 337.138676 -215.411034) (xy 337.146024 -215.360224) (xy 337.160584 -215.310993)
			(xy 337.182053 -215.264359) (xy 337.209989 -215.221286) (xy 337.243813 -215.182665) (xy 337.282827 -215.149294)
			(xy 337.326223 -215.121863) (xy 337.373105 -215.10094) (xy 337.422502 -215.086956) (xy 337.44789 -215.083136)
			(xy 337.472782 -215.079834) (xy 337.64474 -214.7824) (xy 337.635088 -214.759032) (xy 337.626505 -214.737327)
			(xy 337.614424 -214.692243) (xy 337.60831 -214.645971) (xy 337.60791 -214.622634) (xy 337.608409 -214.595947)
			(xy 337.616364 -214.543168) (xy 337.632096 -214.492165) (xy 337.655254 -214.444076) (xy 337.685321 -214.399976)
			(xy 337.721625 -214.360849) (xy 337.763355 -214.327571) (xy 337.809579 -214.300884) (xy 337.859264 -214.281384)
			(xy 337.911301 -214.269507) (xy 337.964526 -214.265518) (xy 338.017751 -214.269507) (xy 338.069788 -214.281384)
			(xy 338.119473 -214.300884) (xy 338.165697 -214.327571) (xy 338.207427 -214.360849) (xy 338.243731 -214.399976)
			(xy 338.273798 -214.444076) (xy 338.296956 -214.492165) (xy 338.312688 -214.543168) (xy 338.320643 -214.595947)
			(xy 338.321142 -214.622634) (xy 338.32076 -214.648304) (xy 338.313406 -214.699116) (xy 338.298842 -214.748347)
			(xy 338.277369 -214.794981) (xy 338.24943 -214.838054) (xy 338.215602 -214.876675) (xy 338.176586 -214.910045)
			(xy 338.133188 -214.937475) (xy 338.086304 -214.958398) (xy 338.036904 -214.972382) (xy 338.011516 -214.976202)
			(xy 337.986624 -214.979504) (xy 337.814666 -215.276938) (xy 337.824318 -215.300306) (xy 337.832883 -215.322018)
			(xy 337.844971 -215.367098) (xy 337.851092 -215.413368) (xy 337.851496 -215.436704) (xy 339.017864 -215.436704)
			(xy 339.018276 -215.411034) (xy 339.025624 -215.360224) (xy 339.040184 -215.310993) (xy 339.061653 -215.264359)
			(xy 339.089589 -215.221286) (xy 339.123413 -215.182665) (xy 339.162427 -215.149294) (xy 339.205823 -215.121863)
			(xy 339.252705 -215.10094) (xy 339.302102 -215.086956) (xy 339.32749 -215.083136) (xy 339.352382 -215.079834)
			(xy 339.52434 -214.7824) (xy 339.514688 -214.759032) (xy 339.506105 -214.737327) (xy 339.494024 -214.692243)
			(xy 339.48791 -214.645971) (xy 339.48751 -214.622634) (xy 339.488009 -214.595947) (xy 339.495964 -214.543168)
			(xy 339.511696 -214.492165) (xy 339.534854 -214.444076) (xy 339.564921 -214.399976) (xy 339.601225 -214.360849)
			(xy 339.642955 -214.327571) (xy 339.689179 -214.300884) (xy 339.738864 -214.281384) (xy 339.790901 -214.269507)
			(xy 339.844126 -214.265518) (xy 339.897351 -214.269507) (xy 339.949388 -214.281384) (xy 339.999073 -214.300884)
			(xy 340.045297 -214.327571) (xy 340.087027 -214.360849) (xy 340.123331 -214.399976) (xy 340.153398 -214.444076)
			(xy 340.176556 -214.492165) (xy 340.192288 -214.543168) (xy 340.200243 -214.595947) (xy 340.200742 -214.622634)
			(xy 340.20036 -214.648304) (xy 340.193006 -214.699116) (xy 340.178442 -214.748347) (xy 340.156969 -214.794981)
			(xy 340.12903 -214.838054) (xy 340.095202 -214.876675) (xy 340.056186 -214.910045) (xy 340.012788 -214.937475)
			(xy 339.965904 -214.958398) (xy 339.916504 -214.972382) (xy 339.891116 -214.976202) (xy 339.866224 -214.979504)
			(xy 339.694266 -215.276938) (xy 339.703918 -215.300306) (xy 339.712483 -215.322018) (xy 339.724571 -215.367098)
			(xy 339.730692 -215.413368) (xy 339.731096 -215.436704) (xy 340.897464 -215.436704) (xy 340.897876 -215.411034)
			(xy 340.905224 -215.360224) (xy 340.919784 -215.310993) (xy 340.941253 -215.264359) (xy 340.969189 -215.221286)
			(xy 341.003013 -215.182665) (xy 341.042027 -215.149294) (xy 341.085423 -215.121863) (xy 341.132305 -215.10094)
			(xy 341.181702 -215.086956) (xy 341.20709 -215.083136) (xy 341.231982 -215.079834) (xy 341.40394 -214.7824)
			(xy 341.394288 -214.759032) (xy 341.385705 -214.737327) (xy 341.373624 -214.692243) (xy 341.36751 -214.645971)
			(xy 341.36711 -214.622634) (xy 341.367609 -214.595947) (xy 341.375564 -214.543168) (xy 341.391296 -214.492165)
			(xy 341.414454 -214.444076) (xy 341.444521 -214.399976) (xy 341.480825 -214.360849) (xy 341.522555 -214.327571)
			(xy 341.568779 -214.300884) (xy 341.618464 -214.281384) (xy 341.670501 -214.269507) (xy 341.723726 -214.265518)
			(xy 341.776951 -214.269507) (xy 341.828988 -214.281384) (xy 341.878673 -214.300884) (xy 341.924897 -214.327571)
			(xy 341.966627 -214.360849) (xy 342.002931 -214.399976) (xy 342.032998 -214.444076) (xy 342.056156 -214.492165)
			(xy 342.071888 -214.543168) (xy 342.079843 -214.595947) (xy 342.080342 -214.622634) (xy 342.07996 -214.648304)
			(xy 342.072606 -214.699116) (xy 342.058042 -214.748347) (xy 342.036569 -214.794981) (xy 342.00863 -214.838054)
			(xy 341.974802 -214.876675) (xy 341.935786 -214.910045) (xy 341.892388 -214.937475) (xy 341.845504 -214.958398)
			(xy 341.796104 -214.972382) (xy 341.770716 -214.976202) (xy 341.745824 -214.979504) (xy 341.573866 -215.276938)
			(xy 341.583518 -215.300306) (xy 341.592083 -215.322018) (xy 341.604171 -215.367098) (xy 341.610292 -215.413368)
			(xy 341.610696 -215.436704) (xy 342.777064 -215.436704) (xy 342.777476 -215.411034) (xy 342.784824 -215.360224)
			(xy 342.799384 -215.310993) (xy 342.820853 -215.264359) (xy 342.848789 -215.221286) (xy 342.882613 -215.182665)
			(xy 342.921627 -215.149294) (xy 342.965023 -215.121863) (xy 343.011905 -215.10094) (xy 343.061302 -215.086956)
			(xy 343.08669 -215.083136) (xy 343.111582 -215.079834) (xy 343.28354 -214.7824) (xy 343.273888 -214.759032)
			(xy 343.265305 -214.737327) (xy 343.253224 -214.692243) (xy 343.24711 -214.645971) (xy 343.24671 -214.622634)
			(xy 343.247209 -214.595947) (xy 343.255164 -214.543168) (xy 343.270896 -214.492165) (xy 343.294054 -214.444076)
			(xy 343.324121 -214.399976) (xy 343.360425 -214.360849) (xy 343.402155 -214.327571) (xy 343.448379 -214.300884)
			(xy 343.498064 -214.281384) (xy 343.550101 -214.269507) (xy 343.603326 -214.265518) (xy 343.656551 -214.269507)
			(xy 343.708588 -214.281384) (xy 343.758273 -214.300884) (xy 343.804497 -214.327571) (xy 343.846227 -214.360849)
			(xy 343.882531 -214.399976) (xy 343.912598 -214.444076) (xy 343.935756 -214.492165) (xy 343.951488 -214.543168)
			(xy 343.959443 -214.595947) (xy 343.959942 -214.622634) (xy 343.95956 -214.648304) (xy 343.952206 -214.699116)
			(xy 343.937642 -214.748347) (xy 343.916169 -214.794981) (xy 343.88823 -214.838054) (xy 343.854402 -214.876675)
			(xy 343.815386 -214.910045) (xy 343.771988 -214.937475) (xy 343.725104 -214.958398) (xy 343.675704 -214.972382)
			(xy 343.650316 -214.976202) (xy 343.625424 -214.979504) (xy 343.453466 -215.276938) (xy 343.463118 -215.300306)
			(xy 343.471683 -215.322018) (xy 343.483771 -215.367098) (xy 343.489892 -215.413368) (xy 343.490296 -215.436704)
			(xy 344.656664 -215.436704) (xy 344.657076 -215.411034) (xy 344.664424 -215.360224) (xy 344.678984 -215.310993)
			(xy 344.700453 -215.264359) (xy 344.728389 -215.221286) (xy 344.762213 -215.182665) (xy 344.801227 -215.149294)
			(xy 344.844623 -215.121863) (xy 344.891505 -215.10094) (xy 344.940902 -215.086956) (xy 344.96629 -215.083136)
			(xy 344.991182 -215.079834) (xy 345.16314 -214.7824) (xy 345.153488 -214.759032) (xy 345.144905 -214.737327)
			(xy 345.132824 -214.692243) (xy 345.12671 -214.645971) (xy 345.12631 -214.622634) (xy 345.126809 -214.595947)
			(xy 345.134764 -214.543168) (xy 345.150496 -214.492165) (xy 345.173654 -214.444076) (xy 345.203721 -214.399976)
			(xy 345.240025 -214.360849) (xy 345.281755 -214.327571) (xy 345.327979 -214.300884) (xy 345.377664 -214.281384)
			(xy 345.429701 -214.269507) (xy 345.482926 -214.265518) (xy 345.536151 -214.269507) (xy 345.588188 -214.281384)
			(xy 345.637873 -214.300884) (xy 345.684097 -214.327571) (xy 345.725827 -214.360849) (xy 345.762131 -214.399976)
			(xy 345.792198 -214.444076) (xy 345.815356 -214.492165) (xy 345.831088 -214.543168) (xy 345.839043 -214.595947)
			(xy 345.839542 -214.622634) (xy 345.83916 -214.648304) (xy 345.831806 -214.699116) (xy 345.817242 -214.748347)
			(xy 345.795769 -214.794981) (xy 345.76783 -214.838054) (xy 345.734002 -214.876675) (xy 345.694986 -214.910045)
			(xy 345.651588 -214.937475) (xy 345.604704 -214.958398) (xy 345.555304 -214.972382) (xy 345.529916 -214.976202)
			(xy 345.505024 -214.979504) (xy 345.333066 -215.276938) (xy 345.342718 -215.300306) (xy 345.351283 -215.322018)
			(xy 345.363371 -215.367098) (xy 345.369492 -215.413368) (xy 345.369896 -215.436704) (xy 346.536264 -215.436704)
			(xy 346.536676 -215.411034) (xy 346.544024 -215.360224) (xy 346.558584 -215.310993) (xy 346.580053 -215.264359)
			(xy 346.607989 -215.221286) (xy 346.641813 -215.182665) (xy 346.680827 -215.149294) (xy 346.724223 -215.121863)
			(xy 346.771105 -215.10094) (xy 346.820502 -215.086956) (xy 346.84589 -215.083136) (xy 346.870782 -215.079834)
			(xy 347.04274 -214.7824) (xy 347.033088 -214.759032) (xy 347.024505 -214.737327) (xy 347.012424 -214.692243)
			(xy 347.00631 -214.645971) (xy 347.00591 -214.622634) (xy 347.006409 -214.595947) (xy 347.014364 -214.543168)
			(xy 347.030096 -214.492165) (xy 347.053254 -214.444076) (xy 347.083321 -214.399976) (xy 347.119625 -214.360849)
			(xy 347.161355 -214.327571) (xy 347.207579 -214.300884) (xy 347.257264 -214.281384) (xy 347.309301 -214.269507)
			(xy 347.362526 -214.265518) (xy 347.415751 -214.269507) (xy 347.467788 -214.281384) (xy 347.517473 -214.300884)
			(xy 347.563697 -214.327571) (xy 347.605427 -214.360849) (xy 347.641731 -214.399976) (xy 347.671798 -214.444076)
			(xy 347.694956 -214.492165) (xy 347.710688 -214.543168) (xy 347.718643 -214.595947) (xy 347.719142 -214.622634)
			(xy 347.71876 -214.648304) (xy 347.711406 -214.699116) (xy 347.696842 -214.748347) (xy 347.675369 -214.794981)
			(xy 347.64743 -214.838054) (xy 347.613602 -214.876675) (xy 347.574586 -214.910045) (xy 347.531188 -214.937475)
			(xy 347.484304 -214.958398) (xy 347.434904 -214.972382) (xy 347.409516 -214.976202) (xy 347.384624 -214.979504)
			(xy 347.212666 -215.276938) (xy 347.222318 -215.300306) (xy 347.230883 -215.322018) (xy 347.242971 -215.367098)
			(xy 347.249092 -215.413368) (xy 347.249496 -215.436704) (xy 348.415864 -215.436704) (xy 348.416276 -215.411034)
			(xy 348.423624 -215.360224) (xy 348.438184 -215.310993) (xy 348.459653 -215.264359) (xy 348.487589 -215.221286)
			(xy 348.521413 -215.182665) (xy 348.560427 -215.149294) (xy 348.603823 -215.121863) (xy 348.650705 -215.10094)
			(xy 348.700102 -215.086956) (xy 348.72549 -215.083136) (xy 348.750382 -215.079834) (xy 348.92234 -214.7824)
			(xy 348.912688 -214.759032) (xy 348.904105 -214.737327) (xy 348.892024 -214.692243) (xy 348.88591 -214.645971)
			(xy 348.88551 -214.622634) (xy 348.886009 -214.595947) (xy 348.893964 -214.543168) (xy 348.909696 -214.492165)
			(xy 348.932854 -214.444076) (xy 348.962921 -214.399976) (xy 348.999225 -214.360849) (xy 349.040955 -214.327571)
			(xy 349.087179 -214.300884) (xy 349.136864 -214.281384) (xy 349.188901 -214.269507) (xy 349.242126 -214.265518)
			(xy 349.295351 -214.269507) (xy 349.347388 -214.281384) (xy 349.397073 -214.300884) (xy 349.443297 -214.327571)
			(xy 349.485027 -214.360849) (xy 349.521331 -214.399976) (xy 349.551398 -214.444076) (xy 349.574556 -214.492165)
			(xy 349.590288 -214.543168) (xy 349.598243 -214.595947) (xy 349.598742 -214.622634) (xy 349.59836 -214.648304)
			(xy 349.591006 -214.699116) (xy 349.576442 -214.748347) (xy 349.554969 -214.794981) (xy 349.52703 -214.838054)
			(xy 349.493202 -214.876675) (xy 349.454186 -214.910045) (xy 349.410788 -214.937475) (xy 349.363904 -214.958398)
			(xy 349.314504 -214.972382) (xy 349.289116 -214.976202) (xy 349.264224 -214.979504) (xy 349.092266 -215.276938)
			(xy 349.101918 -215.300306) (xy 349.110483 -215.322018) (xy 349.122571 -215.367098) (xy 349.128692 -215.413368)
			(xy 349.129096 -215.436704) (xy 350.295464 -215.436704) (xy 350.295876 -215.411034) (xy 350.303224 -215.360224)
			(xy 350.317784 -215.310993) (xy 350.339253 -215.264359) (xy 350.367189 -215.221286) (xy 350.401013 -215.182665)
			(xy 350.440027 -215.149294) (xy 350.483423 -215.121863) (xy 350.530305 -215.10094) (xy 350.579702 -215.086956)
			(xy 350.60509 -215.083136) (xy 350.629982 -215.079834) (xy 350.80194 -214.7824) (xy 350.792288 -214.759032)
			(xy 350.783705 -214.737327) (xy 350.771624 -214.692243) (xy 350.76551 -214.645971) (xy 350.76511 -214.622634)
			(xy 350.765609 -214.595947) (xy 350.773564 -214.543168) (xy 350.789296 -214.492165) (xy 350.812454 -214.444076)
			(xy 350.842521 -214.399976) (xy 350.878825 -214.360849) (xy 350.920555 -214.327571) (xy 350.966779 -214.300884)
			(xy 351.016464 -214.281384) (xy 351.068501 -214.269507) (xy 351.121726 -214.265518) (xy 351.174951 -214.269507)
			(xy 351.226988 -214.281384) (xy 351.276673 -214.300884) (xy 351.322897 -214.327571) (xy 351.364627 -214.360849)
			(xy 351.400931 -214.399976) (xy 351.430998 -214.444076) (xy 351.454156 -214.492165) (xy 351.469888 -214.543168)
			(xy 351.477843 -214.595947) (xy 351.478342 -214.622634) (xy 351.47796 -214.648304) (xy 351.470606 -214.699116)
			(xy 351.456042 -214.748347) (xy 351.434569 -214.794981) (xy 351.40663 -214.838054) (xy 351.372802 -214.876675)
			(xy 351.333786 -214.910045) (xy 351.290388 -214.937475) (xy 351.243504 -214.958398) (xy 351.194104 -214.972382)
			(xy 351.168716 -214.976202) (xy 351.143824 -214.979504) (xy 350.971866 -215.276938) (xy 350.981518 -215.300306)
			(xy 350.990083 -215.322018) (xy 351.002171 -215.367098) (xy 351.008292 -215.413368) (xy 351.008696 -215.436704)
			(xy 352.175064 -215.436704) (xy 352.175476 -215.411034) (xy 352.182824 -215.360224) (xy 352.197384 -215.310993)
			(xy 352.218853 -215.264359) (xy 352.246789 -215.221286) (xy 352.280613 -215.182665) (xy 352.319627 -215.149294)
			(xy 352.363023 -215.121863) (xy 352.409905 -215.10094) (xy 352.459302 -215.086956) (xy 352.48469 -215.083136)
			(xy 352.509582 -215.079834) (xy 352.68154 -214.7824) (xy 352.671888 -214.759032) (xy 352.663305 -214.737327)
			(xy 352.651224 -214.692243) (xy 352.64511 -214.645971) (xy 352.64471 -214.622634) (xy 352.645209 -214.595947)
			(xy 352.653164 -214.543168) (xy 352.668896 -214.492165) (xy 352.692054 -214.444076) (xy 352.722121 -214.399976)
			(xy 352.758425 -214.360849) (xy 352.800155 -214.327571) (xy 352.846379 -214.300884) (xy 352.896064 -214.281384)
			(xy 352.948101 -214.269507) (xy 353.001326 -214.265518) (xy 353.054551 -214.269507) (xy 353.106588 -214.281384)
			(xy 353.156273 -214.300884) (xy 353.202497 -214.327571) (xy 353.244227 -214.360849) (xy 353.280531 -214.399976)
			(xy 353.310598 -214.444076) (xy 353.333756 -214.492165) (xy 353.349488 -214.543168) (xy 353.357443 -214.595947)
			(xy 353.357942 -214.622634) (xy 353.35756 -214.648304) (xy 353.350206 -214.699116) (xy 353.335642 -214.748347)
			(xy 353.314169 -214.794981) (xy 353.28623 -214.838054) (xy 353.252402 -214.876675) (xy 353.213386 -214.910045)
			(xy 353.169988 -214.937475) (xy 353.123104 -214.958398) (xy 353.073704 -214.972382) (xy 353.048316 -214.976202)
			(xy 353.023424 -214.979504) (xy 352.851466 -215.276938) (xy 352.861118 -215.300306) (xy 352.869683 -215.322018)
			(xy 352.881771 -215.367098) (xy 352.887892 -215.413368) (xy 352.888296 -215.436704) (xy 354.054664 -215.436704)
			(xy 354.055076 -215.411034) (xy 354.062424 -215.360224) (xy 354.076984 -215.310993) (xy 354.098453 -215.264359)
			(xy 354.126389 -215.221286) (xy 354.160213 -215.182665) (xy 354.199227 -215.149294) (xy 354.242623 -215.121863)
			(xy 354.289505 -215.10094) (xy 354.338902 -215.086956) (xy 354.36429 -215.083136) (xy 354.389182 -215.079834)
			(xy 354.56114 -214.7824) (xy 354.551488 -214.759032) (xy 354.542905 -214.737327) (xy 354.530824 -214.692243)
			(xy 354.52471 -214.645971) (xy 354.52431 -214.622634) (xy 354.524809 -214.595947) (xy 354.532764 -214.543168)
			(xy 354.548496 -214.492165) (xy 354.571654 -214.444076) (xy 354.601721 -214.399976) (xy 354.638025 -214.360849)
			(xy 354.679755 -214.327571) (xy 354.725979 -214.300884) (xy 354.775664 -214.281384) (xy 354.827701 -214.269507)
			(xy 354.880926 -214.265518) (xy 354.934151 -214.269507) (xy 354.986188 -214.281384) (xy 355.035873 -214.300884)
			(xy 355.082097 -214.327571) (xy 355.123827 -214.360849) (xy 355.160131 -214.399976) (xy 355.190198 -214.444076)
			(xy 355.213356 -214.492165) (xy 355.229088 -214.543168) (xy 355.237043 -214.595947) (xy 355.237542 -214.622634)
			(xy 355.23716 -214.648304) (xy 355.229806 -214.699116) (xy 355.215242 -214.748347) (xy 355.193769 -214.794981)
			(xy 355.16583 -214.838054) (xy 355.132002 -214.876675) (xy 355.092986 -214.910045) (xy 355.049588 -214.937475)
			(xy 355.002704 -214.958398) (xy 354.953304 -214.972382) (xy 354.927916 -214.976202) (xy 354.903024 -214.979504)
			(xy 354.731066 -215.276938) (xy 354.740718 -215.300306) (xy 354.749283 -215.322018) (xy 354.761371 -215.367098)
			(xy 354.767492 -215.413368) (xy 354.767896 -215.436704) (xy 355.934264 -215.436704) (xy 355.934676 -215.411034)
			(xy 355.942024 -215.360224) (xy 355.956584 -215.310993) (xy 355.978053 -215.264359) (xy 356.005989 -215.221286)
			(xy 356.039813 -215.182665) (xy 356.078827 -215.149294) (xy 356.122223 -215.121863) (xy 356.169105 -215.10094)
			(xy 356.218502 -215.086956) (xy 356.24389 -215.083136) (xy 356.268782 -215.079834) (xy 356.44074 -214.7824)
			(xy 356.431088 -214.759032) (xy 356.422505 -214.737327) (xy 356.410424 -214.692243) (xy 356.40431 -214.645971)
			(xy 356.40391 -214.622634) (xy 356.404409 -214.595947) (xy 356.412364 -214.543168) (xy 356.428096 -214.492165)
			(xy 356.451254 -214.444076) (xy 356.481321 -214.399976) (xy 356.517625 -214.360849) (xy 356.559355 -214.327571)
			(xy 356.605579 -214.300884) (xy 356.655264 -214.281384) (xy 356.707301 -214.269507) (xy 356.760526 -214.265518)
			(xy 356.813751 -214.269507) (xy 356.865788 -214.281384) (xy 356.915473 -214.300884) (xy 356.961697 -214.327571)
			(xy 357.003427 -214.360849) (xy 357.039731 -214.399976) (xy 357.069798 -214.444076) (xy 357.092956 -214.492165)
			(xy 357.108688 -214.543168) (xy 357.116643 -214.595947) (xy 357.117142 -214.622634) (xy 358.28351 -214.622634)
			(xy 358.284009 -214.595947) (xy 358.291964 -214.543168) (xy 358.307696 -214.492165) (xy 358.330854 -214.444076)
			(xy 358.360921 -214.399976) (xy 358.397225 -214.360849) (xy 358.438955 -214.327571) (xy 358.485179 -214.300884)
			(xy 358.534864 -214.281384) (xy 358.586901 -214.269507) (xy 358.640126 -214.265518) (xy 358.693351 -214.269507)
			(xy 358.745388 -214.281384) (xy 358.795073 -214.300884) (xy 358.841297 -214.327571) (xy 358.883027 -214.360849)
			(xy 358.919331 -214.399976) (xy 358.949398 -214.444076) (xy 358.972556 -214.492165) (xy 358.988288 -214.543168)
			(xy 358.996243 -214.595947) (xy 358.996742 -214.622634) (xy 358.996742 -214.623142) (xy 358.996333 -214.646343)
			(xy 358.990277 -214.69235) (xy 358.978312 -214.737184) (xy 358.969818 -214.758778) (xy 358.960166 -214.781892)
			(xy 359.132378 -215.079834) (xy 359.15727 -215.083136) (xy 359.182638 -215.08705) (xy 359.232018 -215.101043)
			(xy 359.278883 -215.121969) (xy 359.322265 -215.149396) (xy 359.361268 -215.182758) (xy 359.395087 -215.221365)
			(xy 359.423023 -215.264421) (xy 359.444499 -215.311037) (xy 359.459073 -215.360249) (xy 359.466443 -215.411042)
			(xy 359.466896 -215.436704) (xy 359.466397 -215.463391) (xy 359.458442 -215.51617) (xy 359.44271 -215.567173)
			(xy 359.419552 -215.615262) (xy 359.389485 -215.659362) (xy 359.353181 -215.698489) (xy 359.311451 -215.731767)
			(xy 359.265227 -215.758454) (xy 359.215542 -215.777954) (xy 359.163505 -215.789831) (xy 359.11028 -215.79382)
			(xy 359.057055 -215.789831) (xy 359.005018 -215.777954) (xy 358.955333 -215.758454) (xy 358.909109 -215.731767)
			(xy 358.867379 -215.698489) (xy 358.831075 -215.659362) (xy 358.801008 -215.615262) (xy 358.77785 -215.567173)
			(xy 358.762118 -215.51617) (xy 358.754163 -215.463391) (xy 358.753664 -215.436704) (xy 358.753664 -215.436196)
			(xy 358.754053 -215.412994) (xy 358.760117 -215.366987) (xy 358.77209 -215.322154) (xy 358.780588 -215.30056)
			(xy 358.79024 -215.277446) (xy 358.618282 -214.979504) (xy 358.59339 -214.976202) (xy 358.567993 -214.972392)
			(xy 358.518575 -214.958421) (xy 358.471671 -214.937507) (xy 358.428252 -214.910082) (xy 358.389214 -214.876715)
			(xy 358.355365 -214.838093) (xy 358.327405 -214.795017) (xy 358.305912 -214.748376) (xy 358.291329 -214.699135)
			(xy 358.28396 -214.648311) (xy 358.28351 -214.622634) (xy 357.117142 -214.622634) (xy 357.11676 -214.648304)
			(xy 357.109406 -214.699116) (xy 357.094842 -214.748347) (xy 357.073369 -214.794981) (xy 357.04543 -214.838054)
			(xy 357.011602 -214.876675) (xy 356.972586 -214.910045) (xy 356.929188 -214.937475) (xy 356.882304 -214.958398)
			(xy 356.832904 -214.972382) (xy 356.807516 -214.976202) (xy 356.782624 -214.979504) (xy 356.610666 -215.276938)
			(xy 356.620318 -215.300306) (xy 356.628883 -215.322018) (xy 356.640971 -215.367098) (xy 356.647092 -215.413368)
			(xy 356.647496 -215.4367) (xy 356.874605 -215.4367) (xy 356.878582 -215.383629) (xy 356.890425 -215.331743)
			(xy 356.909867 -215.282202) (xy 356.936477 -215.236111) (xy 356.969658 -215.194501) (xy 357.00867 -215.158301)
			(xy 357.052641 -215.12832) (xy 357.10059 -215.105227) (xy 357.151445 -215.089537) (xy 357.20407 -215.081603)
			(xy 357.23068 -215.081104) (xy 357.255627 -215.081478) (xy 357.305031 -215.088451) (xy 357.352975 -215.102262)
			(xy 357.398517 -215.122641) (xy 357.440763 -215.149186) (xy 357.478883 -215.181378) (xy 357.512127 -215.218582)
			(xy 357.526336 -215.239092) (xy 357.874824 -215.239092) (xy 357.889031 -215.218584) (xy 357.922285 -215.181394)
			(xy 357.960409 -215.149215) (xy 358.002656 -215.12268) (xy 358.048196 -215.102308) (xy 358.096136 -215.0885)
			(xy 358.145535 -215.081526) (xy 358.17048 -215.081104) (xy 358.197094 -215.081567) (xy 358.249729 -215.089498)
			(xy 358.300594 -215.105185) (xy 358.348552 -215.128278) (xy 358.392533 -215.158262) (xy 358.431553 -215.194465)
			(xy 358.464742 -215.23608) (xy 358.491357 -215.282177) (xy 358.510804 -215.331726) (xy 358.522649 -215.38362)
			(xy 358.526627 -215.4367) (xy 358.522649 -215.48978) (xy 358.510804 -215.541674) (xy 358.491357 -215.591223)
			(xy 358.464742 -215.63732) (xy 358.431553 -215.678935) (xy 358.392533 -215.715138) (xy 358.348552 -215.745122)
			(xy 358.300594 -215.768215) (xy 358.249729 -215.783902) (xy 358.197094 -215.791833) (xy 358.17048 -215.792304)
			(xy 358.145535 -215.791881) (xy 358.096133 -215.784917) (xy 358.04819 -215.771113) (xy 358.002648 -215.750743)
			(xy 357.960402 -215.724205) (xy 357.922281 -215.692021) (xy 357.889034 -215.654823) (xy 357.874824 -215.634316)
			(xy 357.526336 -215.634316) (xy 357.512157 -215.654844) (xy 357.478899 -215.692034) (xy 357.440769 -215.72421)
			(xy 357.398518 -215.750743) (xy 357.352973 -215.771112) (xy 357.305029 -215.784916) (xy 357.255626 -215.791885)
			(xy 357.23068 -215.792304) (xy 357.20407 -215.791797) (xy 357.151445 -215.783863) (xy 357.10059 -215.768173)
			(xy 357.052641 -215.74508) (xy 357.00867 -215.715099) (xy 356.969658 -215.678899) (xy 356.936477 -215.637289)
			(xy 356.909867 -215.591198) (xy 356.890425 -215.541657) (xy 356.878582 -215.489771) (xy 356.874605 -215.4367)
			(xy 356.647496 -215.4367) (xy 356.647496 -215.436704) (xy 356.646997 -215.463391) (xy 356.639042 -215.51617)
			(xy 356.62331 -215.567173) (xy 356.600152 -215.615262) (xy 356.570085 -215.659362) (xy 356.533781 -215.698489)
			(xy 356.492051 -215.731767) (xy 356.445827 -215.758454) (xy 356.396142 -215.777954) (xy 356.344105 -215.789831)
			(xy 356.29088 -215.79382) (xy 356.237655 -215.789831) (xy 356.185618 -215.777954) (xy 356.135933 -215.758454)
			(xy 356.089709 -215.731767) (xy 356.047979 -215.698489) (xy 356.011675 -215.659362) (xy 355.981608 -215.615262)
			(xy 355.95845 -215.567173) (xy 355.942718 -215.51617) (xy 355.934763 -215.463391) (xy 355.934264 -215.436704)
			(xy 354.767896 -215.436704) (xy 354.767397 -215.463391) (xy 354.759442 -215.51617) (xy 354.74371 -215.567173)
			(xy 354.720552 -215.615262) (xy 354.690485 -215.659362) (xy 354.654181 -215.698489) (xy 354.612451 -215.731767)
			(xy 354.566227 -215.758454) (xy 354.516542 -215.777954) (xy 354.464505 -215.789831) (xy 354.41128 -215.79382)
			(xy 354.358055 -215.789831) (xy 354.306018 -215.777954) (xy 354.256333 -215.758454) (xy 354.210109 -215.731767)
			(xy 354.168379 -215.698489) (xy 354.132075 -215.659362) (xy 354.102008 -215.615262) (xy 354.07885 -215.567173)
			(xy 354.063118 -215.51617) (xy 354.055163 -215.463391) (xy 354.054664 -215.436704) (xy 352.888296 -215.436704)
			(xy 352.887797 -215.463391) (xy 352.879842 -215.51617) (xy 352.86411 -215.567173) (xy 352.840952 -215.615262)
			(xy 352.810885 -215.659362) (xy 352.774581 -215.698489) (xy 352.732851 -215.731767) (xy 352.686627 -215.758454)
			(xy 352.636942 -215.777954) (xy 352.584905 -215.789831) (xy 352.53168 -215.79382) (xy 352.478455 -215.789831)
			(xy 352.426418 -215.777954) (xy 352.376733 -215.758454) (xy 352.330509 -215.731767) (xy 352.288779 -215.698489)
			(xy 352.252475 -215.659362) (xy 352.222408 -215.615262) (xy 352.19925 -215.567173) (xy 352.183518 -215.51617)
			(xy 352.175563 -215.463391) (xy 352.175064 -215.436704) (xy 351.008696 -215.436704) (xy 351.008197 -215.463391)
			(xy 351.000242 -215.51617) (xy 350.98451 -215.567173) (xy 350.961352 -215.615262) (xy 350.931285 -215.659362)
			(xy 350.894981 -215.698489) (xy 350.853251 -215.731767) (xy 350.807027 -215.758454) (xy 350.757342 -215.777954)
			(xy 350.705305 -215.789831) (xy 350.65208 -215.79382) (xy 350.598855 -215.789831) (xy 350.546818 -215.777954)
			(xy 350.497133 -215.758454) (xy 350.450909 -215.731767) (xy 350.409179 -215.698489) (xy 350.372875 -215.659362)
			(xy 350.342808 -215.615262) (xy 350.31965 -215.567173) (xy 350.303918 -215.51617) (xy 350.295963 -215.463391)
			(xy 350.295464 -215.436704) (xy 349.129096 -215.436704) (xy 349.128597 -215.463391) (xy 349.120642 -215.51617)
			(xy 349.10491 -215.567173) (xy 349.081752 -215.615262) (xy 349.051685 -215.659362) (xy 349.015381 -215.698489)
			(xy 348.973651 -215.731767) (xy 348.927427 -215.758454) (xy 348.877742 -215.777954) (xy 348.825705 -215.789831)
			(xy 348.77248 -215.79382) (xy 348.719255 -215.789831) (xy 348.667218 -215.777954) (xy 348.617533 -215.758454)
			(xy 348.571309 -215.731767) (xy 348.529579 -215.698489) (xy 348.493275 -215.659362) (xy 348.463208 -215.615262)
			(xy 348.44005 -215.567173) (xy 348.424318 -215.51617) (xy 348.416363 -215.463391) (xy 348.415864 -215.436704)
			(xy 347.249496 -215.436704) (xy 347.248997 -215.463391) (xy 347.241042 -215.51617) (xy 347.22531 -215.567173)
			(xy 347.202152 -215.615262) (xy 347.172085 -215.659362) (xy 347.135781 -215.698489) (xy 347.094051 -215.731767)
			(xy 347.047827 -215.758454) (xy 346.998142 -215.777954) (xy 346.946105 -215.789831) (xy 346.89288 -215.79382)
			(xy 346.839655 -215.789831) (xy 346.787618 -215.777954) (xy 346.737933 -215.758454) (xy 346.691709 -215.731767)
			(xy 346.649979 -215.698489) (xy 346.613675 -215.659362) (xy 346.583608 -215.615262) (xy 346.56045 -215.567173)
			(xy 346.544718 -215.51617) (xy 346.536763 -215.463391) (xy 346.536264 -215.436704) (xy 345.369896 -215.436704)
			(xy 345.369397 -215.463391) (xy 345.361442 -215.51617) (xy 345.34571 -215.567173) (xy 345.322552 -215.615262)
			(xy 345.292485 -215.659362) (xy 345.256181 -215.698489) (xy 345.214451 -215.731767) (xy 345.168227 -215.758454)
			(xy 345.118542 -215.777954) (xy 345.066505 -215.789831) (xy 345.01328 -215.79382) (xy 344.960055 -215.789831)
			(xy 344.908018 -215.777954) (xy 344.858333 -215.758454) (xy 344.812109 -215.731767) (xy 344.770379 -215.698489)
			(xy 344.734075 -215.659362) (xy 344.704008 -215.615262) (xy 344.68085 -215.567173) (xy 344.665118 -215.51617)
			(xy 344.657163 -215.463391) (xy 344.656664 -215.436704) (xy 343.490296 -215.436704) (xy 343.489797 -215.463391)
			(xy 343.481842 -215.51617) (xy 343.46611 -215.567173) (xy 343.442952 -215.615262) (xy 343.412885 -215.659362)
			(xy 343.376581 -215.698489) (xy 343.334851 -215.731767) (xy 343.288627 -215.758454) (xy 343.238942 -215.777954)
			(xy 343.186905 -215.789831) (xy 343.13368 -215.79382) (xy 343.080455 -215.789831) (xy 343.028418 -215.777954)
			(xy 342.978733 -215.758454) (xy 342.932509 -215.731767) (xy 342.890779 -215.698489) (xy 342.854475 -215.659362)
			(xy 342.824408 -215.615262) (xy 342.80125 -215.567173) (xy 342.785518 -215.51617) (xy 342.777563 -215.463391)
			(xy 342.777064 -215.436704) (xy 341.610696 -215.436704) (xy 341.610197 -215.463391) (xy 341.602242 -215.51617)
			(xy 341.58651 -215.567173) (xy 341.563352 -215.615262) (xy 341.533285 -215.659362) (xy 341.496981 -215.698489)
			(xy 341.455251 -215.731767) (xy 341.409027 -215.758454) (xy 341.359342 -215.777954) (xy 341.307305 -215.789831)
			(xy 341.25408 -215.79382) (xy 341.200855 -215.789831) (xy 341.148818 -215.777954) (xy 341.099133 -215.758454)
			(xy 341.052909 -215.731767) (xy 341.011179 -215.698489) (xy 340.974875 -215.659362) (xy 340.944808 -215.615262)
			(xy 340.92165 -215.567173) (xy 340.905918 -215.51617) (xy 340.897963 -215.463391) (xy 340.897464 -215.436704)
			(xy 339.731096 -215.436704) (xy 339.730597 -215.463391) (xy 339.722642 -215.51617) (xy 339.70691 -215.567173)
			(xy 339.683752 -215.615262) (xy 339.653685 -215.659362) (xy 339.617381 -215.698489) (xy 339.575651 -215.731767)
			(xy 339.529427 -215.758454) (xy 339.479742 -215.777954) (xy 339.427705 -215.789831) (xy 339.37448 -215.79382)
			(xy 339.321255 -215.789831) (xy 339.269218 -215.777954) (xy 339.219533 -215.758454) (xy 339.173309 -215.731767)
			(xy 339.131579 -215.698489) (xy 339.095275 -215.659362) (xy 339.065208 -215.615262) (xy 339.04205 -215.567173)
			(xy 339.026318 -215.51617) (xy 339.018363 -215.463391) (xy 339.017864 -215.436704) (xy 337.851496 -215.436704)
			(xy 337.850997 -215.463391) (xy 337.843042 -215.51617) (xy 337.82731 -215.567173) (xy 337.804152 -215.615262)
			(xy 337.774085 -215.659362) (xy 337.737781 -215.698489) (xy 337.696051 -215.731767) (xy 337.649827 -215.758454)
			(xy 337.600142 -215.777954) (xy 337.548105 -215.789831) (xy 337.49488 -215.79382) (xy 337.441655 -215.789831)
			(xy 337.389618 -215.777954) (xy 337.339933 -215.758454) (xy 337.293709 -215.731767) (xy 337.251979 -215.698489)
			(xy 337.215675 -215.659362) (xy 337.185608 -215.615262) (xy 337.16245 -215.567173) (xy 337.146718 -215.51617)
			(xy 337.138763 -215.463391) (xy 337.138264 -215.436704) (xy 336.911696 -215.436704) (xy 336.911349 -215.460044)
			(xy 336.905241 -215.506324) (xy 336.893131 -215.551406) (xy 336.884518 -215.573102) (xy 336.874866 -215.59647)
			(xy 337.046824 -215.89365) (xy 337.071716 -215.896952) (xy 337.097092 -215.900814) (xy 337.146474 -215.914814)
			(xy 337.19334 -215.935747) (xy 337.236722 -215.963181) (xy 337.275724 -215.996549) (xy 337.309542 -216.035162)
			(xy 337.337476 -216.078223) (xy 337.358951 -216.124843) (xy 337.373523 -216.174059) (xy 337.38089 -216.224856)
			(xy 337.381342 -216.25052) (xy 337.380843 -216.277207) (xy 337.372888 -216.329986) (xy 337.357156 -216.380989)
			(xy 337.333998 -216.429078) (xy 337.303931 -216.473178) (xy 337.267627 -216.512305) (xy 337.225897 -216.545583)
			(xy 337.179673 -216.57227) (xy 337.129988 -216.59177) (xy 337.077951 -216.603647) (xy 337.024726 -216.607636)
			(xy 336.971501 -216.603647) (xy 336.919464 -216.59177) (xy 336.869779 -216.57227) (xy 336.823555 -216.545583)
			(xy 336.781825 -216.512305) (xy 336.745521 -216.473178) (xy 336.715454 -216.429078) (xy 336.692296 -216.380989)
			(xy 336.676564 -216.329986) (xy 336.668609 -216.277207) (xy 336.66811 -216.25052) (xy 336.668464 -216.22718)
			(xy 336.674569 -216.180901) (xy 336.686677 -216.135818) (xy 336.695288 -216.114122) (xy 336.70494 -216.090754)
			(xy 336.532982 -215.793574) (xy 336.50809 -215.790272) (xy 336.482701 -215.786479) (xy 336.433314 -215.772475)
			(xy 336.386443 -215.751537) (xy 336.343058 -215.724097) (xy 336.304054 -215.690721) (xy 336.270237 -215.6521)
			(xy 336.242304 -215.60903) (xy 336.220834 -215.562401) (xy 336.206269 -215.513176) (xy 336.198911 -215.462371)
			(xy 336.198464 -215.436704) (xy 135.960612 -215.436704) (xy 135.960115 -215.463315) (xy 135.952182 -215.515943)
			(xy 135.936495 -215.566801) (xy 135.913402 -215.614753) (xy 135.883421 -215.658728) (xy 135.84722 -215.697743)
			(xy 135.805609 -215.730926) (xy 135.759517 -215.757538) (xy 135.709974 -215.776982) (xy 135.658086 -215.788825)
			(xy 135.605012 -215.792803) (xy 135.551938 -215.788825) (xy 135.50005 -215.776982) (xy 135.450507 -215.757538)
			(xy 135.404415 -215.730926) (xy 135.362804 -215.697743) (xy 135.326603 -215.658728) (xy 135.296622 -215.614753)
			(xy 135.273529 -215.566801) (xy 135.257842 -215.515943) (xy 135.249909 -215.463315) (xy 135.249412 -215.436704)
			(xy 135.250046 -215.407259) (xy 135.259738 -215.349172) (xy 135.278859 -215.293472) (xy 135.292338 -215.267286)
			(xy 135.098536 -214.900256) (xy 135.072607 -214.897128) (xy 135.022007 -214.884195) (xy 134.973841 -214.864003)
			(xy 134.929145 -214.836987) (xy 134.888879 -214.803727) (xy 134.853907 -214.764937) (xy 134.824982 -214.721452)
			(xy 134.802725 -214.674205) (xy 134.787614 -214.624212) (xy 134.779974 -214.572547) (xy 134.779512 -214.546434)
			(xy 133.603912 -214.546434) (xy 133.611375 -214.595947) (xy 133.611874 -214.622634) (xy 133.611464 -214.648303)
			(xy 133.604111 -214.699112) (xy 133.589549 -214.748341) (xy 133.568078 -214.794974) (xy 133.540142 -214.838045)
			(xy 133.506318 -214.876665) (xy 133.467305 -214.910036) (xy 133.423911 -214.937468) (xy 133.377031 -214.958393)
			(xy 133.327635 -214.97238) (xy 133.302248 -214.976202) (xy 133.277356 -214.979504) (xy 133.105398 -215.276938)
			(xy 133.11505 -215.300306) (xy 133.123611 -215.322019) (xy 133.135701 -215.367099) (xy 133.141824 -215.413368)
			(xy 133.142228 -215.4367) (xy 133.369281 -215.4367) (xy 133.373259 -215.383622) (xy 133.385103 -215.33173)
			(xy 133.404549 -215.282183) (xy 133.431163 -215.236087) (xy 133.46435 -215.194473) (xy 133.503369 -215.158271)
			(xy 133.547347 -215.128288) (xy 133.595304 -215.105195) (xy 133.646166 -215.089507) (xy 133.698799 -215.081576)
			(xy 133.725412 -215.081104) (xy 133.750357 -215.08153) (xy 133.799759 -215.088493) (xy 133.847702 -215.102295)
			(xy 133.893244 -215.122666) (xy 133.935491 -215.149203) (xy 133.973612 -215.181387) (xy 134.006858 -215.218585)
			(xy 134.021068 -215.239092) (xy 134.369556 -215.239092) (xy 134.383742 -215.218569) (xy 134.416999 -215.181379)
			(xy 134.455127 -215.149202) (xy 134.497378 -215.122668) (xy 134.542921 -215.102299) (xy 134.590864 -215.088494)
			(xy 134.640266 -215.081523) (xy 134.665212 -215.081104) (xy 134.691823 -215.081594) (xy 134.74445 -215.089528)
			(xy 134.795307 -215.105217) (xy 134.843258 -215.12831) (xy 134.887232 -215.158292) (xy 134.926245 -215.194493)
			(xy 134.959428 -215.236104) (xy 134.986039 -215.282196) (xy 135.005483 -215.331739) (xy 135.017325 -215.383627)
			(xy 135.021303 -215.4367) (xy 135.017325 -215.489773) (xy 135.005483 -215.541661) (xy 134.986039 -215.591204)
			(xy 134.959428 -215.637296) (xy 134.926245 -215.678907) (xy 134.887232 -215.715108) (xy 134.843258 -215.74509)
			(xy 134.795307 -215.768183) (xy 134.74445 -215.783872) (xy 134.691823 -215.791806) (xy 134.665212 -215.792304)
			(xy 134.640265 -215.791933) (xy 134.590861 -215.784959) (xy 134.542917 -215.771147) (xy 134.497375 -215.750768)
			(xy 134.455129 -215.724222) (xy 134.417009 -215.69203) (xy 134.383765 -215.654826) (xy 134.369556 -215.634316)
			(xy 134.021068 -215.634316) (xy 134.006869 -215.654829) (xy 133.973614 -215.692019) (xy 133.935488 -215.724197)
			(xy 133.89324 -215.750732) (xy 133.847698 -215.771103) (xy 133.799757 -215.78491) (xy 133.750357 -215.791883)
			(xy 133.725412 -215.792304) (xy 133.698799 -215.791824) (xy 133.646166 -215.783893) (xy 133.595304 -215.768205)
			(xy 133.547347 -215.745112) (xy 133.503369 -215.715129) (xy 133.46435 -215.678927) (xy 133.431163 -215.637313)
			(xy 133.404549 -215.591217) (xy 133.385103 -215.54167) (xy 133.373259 -215.489778) (xy 133.369281 -215.4367)
			(xy 133.142228 -215.4367) (xy 133.142228 -215.436704) (xy 133.141729 -215.463391) (xy 133.133774 -215.51617)
			(xy 133.118042 -215.567173) (xy 133.094884 -215.615262) (xy 133.064817 -215.659362) (xy 133.028513 -215.698489)
			(xy 132.986783 -215.731767) (xy 132.940559 -215.758454) (xy 132.890874 -215.777954) (xy 132.838837 -215.789831)
			(xy 132.785612 -215.79382) (xy 132.732387 -215.789831) (xy 132.68035 -215.777954) (xy 132.630665 -215.758454)
			(xy 132.584441 -215.731767) (xy 132.542711 -215.698489) (xy 132.506407 -215.659362) (xy 132.47634 -215.615262)
			(xy 132.453182 -215.567173) (xy 132.43745 -215.51617) (xy 132.429495 -215.463391) (xy 132.428996 -215.436704)
			(xy 131.262628 -215.436704) (xy 131.262129 -215.463391) (xy 131.254174 -215.51617) (xy 131.238442 -215.567173)
			(xy 131.215284 -215.615262) (xy 131.185217 -215.659362) (xy 131.148913 -215.698489) (xy 131.107183 -215.731767)
			(xy 131.060959 -215.758454) (xy 131.011274 -215.777954) (xy 130.959237 -215.789831) (xy 130.906012 -215.79382)
			(xy 130.852787 -215.789831) (xy 130.80075 -215.777954) (xy 130.751065 -215.758454) (xy 130.704841 -215.731767)
			(xy 130.663111 -215.698489) (xy 130.626807 -215.659362) (xy 130.59674 -215.615262) (xy 130.573582 -215.567173)
			(xy 130.55785 -215.51617) (xy 130.549895 -215.463391) (xy 130.549396 -215.436704) (xy 129.383028 -215.436704)
			(xy 129.382529 -215.463391) (xy 129.374574 -215.51617) (xy 129.358842 -215.567173) (xy 129.335684 -215.615262)
			(xy 129.305617 -215.659362) (xy 129.269313 -215.698489) (xy 129.227583 -215.731767) (xy 129.181359 -215.758454)
			(xy 129.131674 -215.777954) (xy 129.079637 -215.789831) (xy 129.026412 -215.79382) (xy 128.973187 -215.789831)
			(xy 128.92115 -215.777954) (xy 128.871465 -215.758454) (xy 128.825241 -215.731767) (xy 128.783511 -215.698489)
			(xy 128.747207 -215.659362) (xy 128.71714 -215.615262) (xy 128.693982 -215.567173) (xy 128.67825 -215.51617)
			(xy 128.670295 -215.463391) (xy 128.669796 -215.436704) (xy 127.503428 -215.436704) (xy 127.502929 -215.463391)
			(xy 127.494974 -215.51617) (xy 127.479242 -215.567173) (xy 127.456084 -215.615262) (xy 127.426017 -215.659362)
			(xy 127.389713 -215.698489) (xy 127.347983 -215.731767) (xy 127.301759 -215.758454) (xy 127.252074 -215.777954)
			(xy 127.200037 -215.789831) (xy 127.146812 -215.79382) (xy 127.093587 -215.789831) (xy 127.04155 -215.777954)
			(xy 126.991865 -215.758454) (xy 126.945641 -215.731767) (xy 126.903911 -215.698489) (xy 126.867607 -215.659362)
			(xy 126.83754 -215.615262) (xy 126.814382 -215.567173) (xy 126.79865 -215.51617) (xy 126.790695 -215.463391)
			(xy 126.790196 -215.436704) (xy 125.623828 -215.436704) (xy 125.623329 -215.463391) (xy 125.615374 -215.51617)
			(xy 125.599642 -215.567173) (xy 125.576484 -215.615262) (xy 125.546417 -215.659362) (xy 125.510113 -215.698489)
			(xy 125.468383 -215.731767) (xy 125.422159 -215.758454) (xy 125.372474 -215.777954) (xy 125.320437 -215.789831)
			(xy 125.267212 -215.79382) (xy 125.213987 -215.789831) (xy 125.16195 -215.777954) (xy 125.112265 -215.758454)
			(xy 125.066041 -215.731767) (xy 125.024311 -215.698489) (xy 124.988007 -215.659362) (xy 124.95794 -215.615262)
			(xy 124.934782 -215.567173) (xy 124.91905 -215.51617) (xy 124.911095 -215.463391) (xy 124.910596 -215.436704)
			(xy 123.744228 -215.436704) (xy 123.743729 -215.463391) (xy 123.735774 -215.51617) (xy 123.720042 -215.567173)
			(xy 123.696884 -215.615262) (xy 123.666817 -215.659362) (xy 123.630513 -215.698489) (xy 123.588783 -215.731767)
			(xy 123.542559 -215.758454) (xy 123.492874 -215.777954) (xy 123.440837 -215.789831) (xy 123.387612 -215.79382)
			(xy 123.334387 -215.789831) (xy 123.28235 -215.777954) (xy 123.232665 -215.758454) (xy 123.186441 -215.731767)
			(xy 123.144711 -215.698489) (xy 123.108407 -215.659362) (xy 123.07834 -215.615262) (xy 123.055182 -215.567173)
			(xy 123.03945 -215.51617) (xy 123.031495 -215.463391) (xy 123.030996 -215.436704) (xy 121.864628 -215.436704)
			(xy 121.864129 -215.463391) (xy 121.856174 -215.51617) (xy 121.840442 -215.567173) (xy 121.817284 -215.615262)
			(xy 121.787217 -215.659362) (xy 121.750913 -215.698489) (xy 121.709183 -215.731767) (xy 121.662959 -215.758454)
			(xy 121.613274 -215.777954) (xy 121.561237 -215.789831) (xy 121.508012 -215.79382) (xy 121.454787 -215.789831)
			(xy 121.40275 -215.777954) (xy 121.353065 -215.758454) (xy 121.306841 -215.731767) (xy 121.265111 -215.698489)
			(xy 121.228807 -215.659362) (xy 121.19874 -215.615262) (xy 121.175582 -215.567173) (xy 121.15985 -215.51617)
			(xy 121.151895 -215.463391) (xy 121.151396 -215.436704) (xy 119.985028 -215.436704) (xy 119.984529 -215.463391)
			(xy 119.976574 -215.51617) (xy 119.960842 -215.567173) (xy 119.937684 -215.615262) (xy 119.907617 -215.659362)
			(xy 119.871313 -215.698489) (xy 119.829583 -215.731767) (xy 119.783359 -215.758454) (xy 119.733674 -215.777954)
			(xy 119.681637 -215.789831) (xy 119.628412 -215.79382) (xy 119.575187 -215.789831) (xy 119.52315 -215.777954)
			(xy 119.473465 -215.758454) (xy 119.427241 -215.731767) (xy 119.385511 -215.698489) (xy 119.349207 -215.659362)
			(xy 119.31914 -215.615262) (xy 119.295982 -215.567173) (xy 119.28025 -215.51617) (xy 119.272295 -215.463391)
			(xy 119.271796 -215.436704) (xy 118.105428 -215.436704) (xy 118.104929 -215.463391) (xy 118.096974 -215.51617)
			(xy 118.081242 -215.567173) (xy 118.058084 -215.615262) (xy 118.028017 -215.659362) (xy 117.991713 -215.698489)
			(xy 117.949983 -215.731767) (xy 117.903759 -215.758454) (xy 117.854074 -215.777954) (xy 117.802037 -215.789831)
			(xy 117.748812 -215.79382) (xy 117.695587 -215.789831) (xy 117.64355 -215.777954) (xy 117.593865 -215.758454)
			(xy 117.547641 -215.731767) (xy 117.505911 -215.698489) (xy 117.469607 -215.659362) (xy 117.43954 -215.615262)
			(xy 117.416382 -215.567173) (xy 117.40065 -215.51617) (xy 117.392695 -215.463391) (xy 117.392196 -215.436704)
			(xy 116.225828 -215.436704) (xy 116.225329 -215.463391) (xy 116.217374 -215.51617) (xy 116.201642 -215.567173)
			(xy 116.178484 -215.615262) (xy 116.148417 -215.659362) (xy 116.112113 -215.698489) (xy 116.070383 -215.731767)
			(xy 116.024159 -215.758454) (xy 115.974474 -215.777954) (xy 115.922437 -215.789831) (xy 115.869212 -215.79382)
			(xy 115.815987 -215.789831) (xy 115.76395 -215.777954) (xy 115.714265 -215.758454) (xy 115.668041 -215.731767)
			(xy 115.626311 -215.698489) (xy 115.590007 -215.659362) (xy 115.55994 -215.615262) (xy 115.536782 -215.567173)
			(xy 115.52105 -215.51617) (xy 115.513095 -215.463391) (xy 115.512596 -215.436704) (xy 114.346228 -215.436704)
			(xy 114.345729 -215.463391) (xy 114.337774 -215.51617) (xy 114.322042 -215.567173) (xy 114.298884 -215.615262)
			(xy 114.268817 -215.659362) (xy 114.232513 -215.698489) (xy 114.190783 -215.731767) (xy 114.144559 -215.758454)
			(xy 114.094874 -215.777954) (xy 114.042837 -215.789831) (xy 113.989612 -215.79382) (xy 113.936387 -215.789831)
			(xy 113.88435 -215.777954) (xy 113.834665 -215.758454) (xy 113.788441 -215.731767) (xy 113.746711 -215.698489)
			(xy 113.710407 -215.659362) (xy 113.68034 -215.615262) (xy 113.657182 -215.567173) (xy 113.64145 -215.51617)
			(xy 113.633495 -215.463391) (xy 113.632996 -215.436704) (xy 111.526828 -215.436704) (xy 111.526329 -215.463391)
			(xy 111.518374 -215.51617) (xy 111.502642 -215.567173) (xy 111.479484 -215.615262) (xy 111.449417 -215.659362)
			(xy 111.413113 -215.698489) (xy 111.371383 -215.731767) (xy 111.325159 -215.758454) (xy 111.275474 -215.777954)
			(xy 111.223437 -215.789831) (xy 111.170212 -215.79382) (xy 111.116987 -215.789831) (xy 111.06495 -215.777954)
			(xy 111.015265 -215.758454) (xy 110.969041 -215.731767) (xy 110.927311 -215.698489) (xy 110.891007 -215.659362)
			(xy 110.86094 -215.615262) (xy 110.837782 -215.567173) (xy 110.82205 -215.51617) (xy 110.814095 -215.463391)
			(xy 110.813596 -215.436704) (xy 110.813596 -215.43645) (xy 110.814129 -215.408633) (xy 110.822789 -215.353678)
			(xy 110.839876 -215.300734) (xy 110.85195 -215.275668) (xy 110.863888 -215.2523) (xy 110.679992 -214.903558)
			(xy 110.654084 -214.900002) (xy 110.628672 -214.896209) (xy 110.579222 -214.882268) (xy 110.532283 -214.861375)
			(xy 110.488828 -214.833963) (xy 110.449756 -214.800599) (xy 110.415876 -214.761974) (xy 110.38789 -214.718887)
			(xy 110.366375 -214.67223) (xy 110.351778 -214.622969) (xy 110.344401 -214.572123) (xy 110.34395 -214.546434)
			(xy 109.169112 -214.546434) (xy 109.176575 -214.595947) (xy 109.177074 -214.622634) (xy 109.176664 -214.648303)
			(xy 109.169311 -214.699112) (xy 109.154749 -214.748341) (xy 109.133278 -214.794974) (xy 109.105342 -214.838045)
			(xy 109.071518 -214.876665) (xy 109.032505 -214.910036) (xy 108.989111 -214.937468) (xy 108.942231 -214.958393)
			(xy 108.892835 -214.97238) (xy 108.867448 -214.976202) (xy 108.842556 -214.979504) (xy 108.670598 -215.276938)
			(xy 108.68025 -215.300306) (xy 108.688811 -215.322019) (xy 108.700901 -215.367099) (xy 108.707024 -215.413368)
			(xy 108.707428 -215.4367) (xy 108.934481 -215.4367) (xy 108.938459 -215.383622) (xy 108.950303 -215.33173)
			(xy 108.969749 -215.282183) (xy 108.996363 -215.236087) (xy 109.02955 -215.194473) (xy 109.068569 -215.158271)
			(xy 109.112547 -215.128288) (xy 109.160504 -215.105195) (xy 109.211366 -215.089507) (xy 109.263999 -215.081576)
			(xy 109.290612 -215.081104) (xy 109.315557 -215.08153) (xy 109.364959 -215.088493) (xy 109.412902 -215.102295)
			(xy 109.458444 -215.122666) (xy 109.500691 -215.149203) (xy 109.538812 -215.181387) (xy 109.572058 -215.218585)
			(xy 109.586268 -215.239092) (xy 109.934756 -215.239092) (xy 109.948942 -215.218569) (xy 109.982199 -215.181379)
			(xy 110.020327 -215.149202) (xy 110.062578 -215.122668) (xy 110.108121 -215.102299) (xy 110.156064 -215.088494)
			(xy 110.205466 -215.081523) (xy 110.230412 -215.081104) (xy 110.257023 -215.081594) (xy 110.30965 -215.089528)
			(xy 110.360507 -215.105217) (xy 110.408458 -215.12831) (xy 110.452432 -215.158292) (xy 110.491445 -215.194493)
			(xy 110.524628 -215.236104) (xy 110.551239 -215.282196) (xy 110.570683 -215.331739) (xy 110.582525 -215.383627)
			(xy 110.586503 -215.4367) (xy 110.582525 -215.489773) (xy 110.570683 -215.541661) (xy 110.551239 -215.591204)
			(xy 110.524628 -215.637296) (xy 110.491445 -215.678907) (xy 110.452432 -215.715108) (xy 110.408458 -215.74509)
			(xy 110.360507 -215.768183) (xy 110.30965 -215.783872) (xy 110.257023 -215.791806) (xy 110.230412 -215.792304)
			(xy 110.205465 -215.791933) (xy 110.156061 -215.784959) (xy 110.108117 -215.771147) (xy 110.062575 -215.750768)
			(xy 110.020329 -215.724222) (xy 109.982209 -215.69203) (xy 109.948965 -215.654826) (xy 109.934756 -215.634316)
			(xy 109.586268 -215.634316) (xy 109.572069 -215.654829) (xy 109.538814 -215.692019) (xy 109.500688 -215.724197)
			(xy 109.45844 -215.750732) (xy 109.412898 -215.771103) (xy 109.364957 -215.78491) (xy 109.315557 -215.791883)
			(xy 109.290612 -215.792304) (xy 109.263999 -215.791824) (xy 109.211366 -215.783893) (xy 109.160504 -215.768205)
			(xy 109.112547 -215.745112) (xy 109.068569 -215.715129) (xy 109.02955 -215.678927) (xy 108.996363 -215.637313)
			(xy 108.969749 -215.591217) (xy 108.950303 -215.54167) (xy 108.938459 -215.489778) (xy 108.934481 -215.4367)
			(xy 108.707428 -215.4367) (xy 108.707428 -215.436704) (xy 108.706929 -215.463391) (xy 108.698974 -215.51617)
			(xy 108.683242 -215.567173) (xy 108.660084 -215.615262) (xy 108.630017 -215.659362) (xy 108.593713 -215.698489)
			(xy 108.551983 -215.731767) (xy 108.505759 -215.758454) (xy 108.456074 -215.777954) (xy 108.404037 -215.789831)
			(xy 108.350812 -215.79382) (xy 108.297587 -215.789831) (xy 108.24555 -215.777954) (xy 108.195865 -215.758454)
			(xy 108.149641 -215.731767) (xy 108.107911 -215.698489) (xy 108.071607 -215.659362) (xy 108.04154 -215.615262)
			(xy 108.018382 -215.567173) (xy 108.00265 -215.51617) (xy 107.994695 -215.463391) (xy 107.994196 -215.436704)
			(xy 106.827828 -215.436704) (xy 106.827329 -215.463391) (xy 106.819374 -215.51617) (xy 106.803642 -215.567173)
			(xy 106.780484 -215.615262) (xy 106.750417 -215.659362) (xy 106.714113 -215.698489) (xy 106.672383 -215.731767)
			(xy 106.626159 -215.758454) (xy 106.576474 -215.777954) (xy 106.524437 -215.789831) (xy 106.471212 -215.79382)
			(xy 106.417987 -215.789831) (xy 106.36595 -215.777954) (xy 106.316265 -215.758454) (xy 106.270041 -215.731767)
			(xy 106.228311 -215.698489) (xy 106.192007 -215.659362) (xy 106.16194 -215.615262) (xy 106.138782 -215.567173)
			(xy 106.12305 -215.51617) (xy 106.115095 -215.463391) (xy 106.114596 -215.436704) (xy 104.948228 -215.436704)
			(xy 104.947729 -215.463391) (xy 104.939774 -215.51617) (xy 104.924042 -215.567173) (xy 104.900884 -215.615262)
			(xy 104.870817 -215.659362) (xy 104.834513 -215.698489) (xy 104.792783 -215.731767) (xy 104.746559 -215.758454)
			(xy 104.696874 -215.777954) (xy 104.644837 -215.789831) (xy 104.591612 -215.79382) (xy 104.538387 -215.789831)
			(xy 104.48635 -215.777954) (xy 104.436665 -215.758454) (xy 104.390441 -215.731767) (xy 104.348711 -215.698489)
			(xy 104.312407 -215.659362) (xy 104.28234 -215.615262) (xy 104.259182 -215.567173) (xy 104.24345 -215.51617)
			(xy 104.235495 -215.463391) (xy 104.234996 -215.436704) (xy 103.068628 -215.436704) (xy 103.068129 -215.463391)
			(xy 103.060174 -215.51617) (xy 103.044442 -215.567173) (xy 103.021284 -215.615262) (xy 102.991217 -215.659362)
			(xy 102.954913 -215.698489) (xy 102.913183 -215.731767) (xy 102.866959 -215.758454) (xy 102.817274 -215.777954)
			(xy 102.765237 -215.789831) (xy 102.712012 -215.79382) (xy 102.658787 -215.789831) (xy 102.60675 -215.777954)
			(xy 102.557065 -215.758454) (xy 102.510841 -215.731767) (xy 102.469111 -215.698489) (xy 102.432807 -215.659362)
			(xy 102.40274 -215.615262) (xy 102.379582 -215.567173) (xy 102.36385 -215.51617) (xy 102.355895 -215.463391)
			(xy 102.355396 -215.436704) (xy 101.189028 -215.436704) (xy 101.188529 -215.463391) (xy 101.180574 -215.51617)
			(xy 101.164842 -215.567173) (xy 101.141684 -215.615262) (xy 101.111617 -215.659362) (xy 101.075313 -215.698489)
			(xy 101.033583 -215.731767) (xy 100.987359 -215.758454) (xy 100.937674 -215.777954) (xy 100.885637 -215.789831)
			(xy 100.832412 -215.79382) (xy 100.779187 -215.789831) (xy 100.72715 -215.777954) (xy 100.677465 -215.758454)
			(xy 100.631241 -215.731767) (xy 100.589511 -215.698489) (xy 100.553207 -215.659362) (xy 100.52314 -215.615262)
			(xy 100.499982 -215.567173) (xy 100.48425 -215.51617) (xy 100.476295 -215.463391) (xy 100.475796 -215.436704)
			(xy 99.309428 -215.436704) (xy 99.308929 -215.463391) (xy 99.300974 -215.51617) (xy 99.285242 -215.567173)
			(xy 99.262084 -215.615262) (xy 99.232017 -215.659362) (xy 99.195713 -215.698489) (xy 99.153983 -215.731767)
			(xy 99.107759 -215.758454) (xy 99.058074 -215.777954) (xy 99.006037 -215.789831) (xy 98.952812 -215.79382)
			(xy 98.899587 -215.789831) (xy 98.84755 -215.777954) (xy 98.797865 -215.758454) (xy 98.751641 -215.731767)
			(xy 98.709911 -215.698489) (xy 98.673607 -215.659362) (xy 98.64354 -215.615262) (xy 98.620382 -215.567173)
			(xy 98.60465 -215.51617) (xy 98.596695 -215.463391) (xy 98.596196 -215.436704) (xy 97.429828 -215.436704)
			(xy 97.429329 -215.463391) (xy 97.421374 -215.51617) (xy 97.405642 -215.567173) (xy 97.382484 -215.615262)
			(xy 97.352417 -215.659362) (xy 97.316113 -215.698489) (xy 97.274383 -215.731767) (xy 97.228159 -215.758454)
			(xy 97.178474 -215.777954) (xy 97.126437 -215.789831) (xy 97.073212 -215.79382) (xy 97.019987 -215.789831)
			(xy 96.96795 -215.777954) (xy 96.918265 -215.758454) (xy 96.872041 -215.731767) (xy 96.830311 -215.698489)
			(xy 96.794007 -215.659362) (xy 96.76394 -215.615262) (xy 96.740782 -215.567173) (xy 96.72505 -215.51617)
			(xy 96.717095 -215.463391) (xy 96.716596 -215.436704) (xy 95.550228 -215.436704) (xy 95.549729 -215.463391)
			(xy 95.541774 -215.51617) (xy 95.526042 -215.567173) (xy 95.502884 -215.615262) (xy 95.472817 -215.659362)
			(xy 95.436513 -215.698489) (xy 95.394783 -215.731767) (xy 95.348559 -215.758454) (xy 95.298874 -215.777954)
			(xy 95.246837 -215.789831) (xy 95.193612 -215.79382) (xy 95.140387 -215.789831) (xy 95.08835 -215.777954)
			(xy 95.038665 -215.758454) (xy 94.992441 -215.731767) (xy 94.950711 -215.698489) (xy 94.914407 -215.659362)
			(xy 94.88434 -215.615262) (xy 94.861182 -215.567173) (xy 94.84545 -215.51617) (xy 94.837495 -215.463391)
			(xy 94.836996 -215.436704) (xy 93.670628 -215.436704) (xy 93.670129 -215.463391) (xy 93.662174 -215.51617)
			(xy 93.646442 -215.567173) (xy 93.623284 -215.615262) (xy 93.593217 -215.659362) (xy 93.556913 -215.698489)
			(xy 93.515183 -215.731767) (xy 93.468959 -215.758454) (xy 93.419274 -215.777954) (xy 93.367237 -215.789831)
			(xy 93.314012 -215.79382) (xy 93.260787 -215.789831) (xy 93.20875 -215.777954) (xy 93.159065 -215.758454)
			(xy 93.112841 -215.731767) (xy 93.071111 -215.698489) (xy 93.034807 -215.659362) (xy 93.00474 -215.615262)
			(xy 92.981582 -215.567173) (xy 92.96585 -215.51617) (xy 92.957895 -215.463391) (xy 92.957396 -215.436704)
			(xy 91.791028 -215.436704) (xy 91.790529 -215.463391) (xy 91.782574 -215.51617) (xy 91.766842 -215.567173)
			(xy 91.743684 -215.615262) (xy 91.713617 -215.659362) (xy 91.677313 -215.698489) (xy 91.635583 -215.731767)
			(xy 91.589359 -215.758454) (xy 91.539674 -215.777954) (xy 91.487637 -215.789831) (xy 91.434412 -215.79382)
			(xy 91.381187 -215.789831) (xy 91.32915 -215.777954) (xy 91.279465 -215.758454) (xy 91.233241 -215.731767)
			(xy 91.191511 -215.698489) (xy 91.155207 -215.659362) (xy 91.12514 -215.615262) (xy 91.101982 -215.567173)
			(xy 91.08625 -215.51617) (xy 91.078295 -215.463391) (xy 91.077796 -215.436704) (xy 89.911428 -215.436704)
			(xy 89.910929 -215.463391) (xy 89.902974 -215.51617) (xy 89.887242 -215.567173) (xy 89.864084 -215.615262)
			(xy 89.834017 -215.659362) (xy 89.797713 -215.698489) (xy 89.755983 -215.731767) (xy 89.709759 -215.758454)
			(xy 89.660074 -215.777954) (xy 89.608037 -215.789831) (xy 89.554812 -215.79382) (xy 89.501587 -215.789831)
			(xy 89.44955 -215.777954) (xy 89.399865 -215.758454) (xy 89.353641 -215.731767) (xy 89.311911 -215.698489)
			(xy 89.275607 -215.659362) (xy 89.24554 -215.615262) (xy 89.222382 -215.567173) (xy 89.20665 -215.51617)
			(xy 89.198695 -215.463391) (xy 89.198196 -215.436704) (xy 88.971628 -215.436704) (xy 88.971279 -215.460044)
			(xy 88.965172 -215.506323) (xy 88.953062 -215.551406) (xy 88.94445 -215.573102) (xy 88.934798 -215.59647)
			(xy 89.106756 -215.89365) (xy 89.131648 -215.896952) (xy 89.157028 -215.900789) (xy 89.206411 -215.914793)
			(xy 89.253276 -215.93573) (xy 89.296658 -215.963167) (xy 89.335659 -215.996538) (xy 89.369476 -216.035154)
			(xy 89.39741 -216.078217) (xy 89.418884 -216.124839) (xy 89.433455 -216.174057) (xy 89.440822 -216.224855)
			(xy 89.441274 -216.25052) (xy 89.440775 -216.277207) (xy 89.43282 -216.329986) (xy 89.417088 -216.380989)
			(xy 89.39393 -216.429078) (xy 89.363863 -216.473178) (xy 89.327559 -216.512305) (xy 89.285829 -216.545583)
			(xy 89.239605 -216.57227) (xy 89.18992 -216.59177) (xy 89.137883 -216.603647) (xy 89.084658 -216.607636)
			(xy 89.031433 -216.603647) (xy 88.979396 -216.59177) (xy 88.929711 -216.57227) (xy 88.883487 -216.545583)
			(xy 88.841757 -216.512305) (xy 88.805453 -216.473178) (xy 88.775386 -216.429078) (xy 88.752228 -216.380989)
			(xy 88.736496 -216.329986) (xy 88.728541 -216.277207) (xy 88.728042 -216.25052) (xy 88.728401 -216.22718)
			(xy 88.734505 -216.180901) (xy 88.74661 -216.135819) (xy 88.75522 -216.114122) (xy 88.764872 -216.090754)
			(xy 88.592914 -215.793574) (xy 88.568022 -215.790272) (xy 88.542637 -215.786453) (xy 88.49325 -215.772454)
			(xy 88.446379 -215.75152) (xy 88.402994 -215.724083) (xy 88.363989 -215.690711) (xy 88.330171 -215.652092)
			(xy 88.302238 -215.609024) (xy 88.280767 -215.562397) (xy 88.266202 -215.513173) (xy 88.258843 -215.462371)
			(xy 88.258396 -215.436704) (xy 2.509012 -215.436704) (xy 2.509012 -217.878406) (xy 88.72855 -217.878406)
			(xy 88.729049 -217.851719) (xy 88.737004 -217.79894) (xy 88.752736 -217.747937) (xy 88.775894 -217.699848)
			(xy 88.805961 -217.655748) (xy 88.842265 -217.616621) (xy 88.883995 -217.583343) (xy 88.930219 -217.556656)
			(xy 88.979904 -217.537156) (xy 89.031941 -217.525279) (xy 89.085166 -217.52129) (xy 89.138391 -217.525279)
			(xy 89.190428 -217.537156) (xy 89.240113 -217.556656) (xy 89.286337 -217.583343) (xy 89.328067 -217.616621)
			(xy 89.364371 -217.655748) (xy 89.394438 -217.699848) (xy 89.417596 -217.747937) (xy 89.433328 -217.79894)
			(xy 89.441283 -217.851719) (xy 89.441782 -217.878406) (xy 89.66835 -217.878406) (xy 89.668776 -217.852737)
			(xy 89.676124 -217.801928) (xy 89.690682 -217.752698) (xy 89.71215 -217.706064) (xy 89.740084 -217.662992)
			(xy 89.773907 -217.624371) (xy 89.812919 -217.591) (xy 89.856313 -217.563568) (xy 89.903193 -217.542644)
			(xy 89.952589 -217.528659) (xy 89.977976 -217.524838) (xy 90.002868 -217.521536) (xy 90.174826 -217.224102)
			(xy 90.165174 -217.200734) (xy 90.15659 -217.179029) (xy 90.144509 -217.133945) (xy 90.138395 -217.087673)
			(xy 90.137996 -217.064336) (xy 90.138495 -217.037649) (xy 90.14645 -216.98487) (xy 90.162182 -216.933867)
			(xy 90.18534 -216.885778) (xy 90.215407 -216.841678) (xy 90.251711 -216.802551) (xy 90.293441 -216.769273)
			(xy 90.339665 -216.742586) (xy 90.38935 -216.723086) (xy 90.441387 -216.711209) (xy 90.494612 -216.70722)
			(xy 90.547837 -216.711209) (xy 90.599874 -216.723086) (xy 90.649559 -216.742586) (xy 90.695783 -216.769273)
			(xy 90.737513 -216.802551) (xy 90.773817 -216.841678) (xy 90.803884 -216.885778) (xy 90.827042 -216.933867)
			(xy 90.842774 -216.98487) (xy 90.850729 -217.037649) (xy 90.851228 -217.064336) (xy 90.850767 -217.090004)
			(xy 90.843427 -217.140813) (xy 90.828876 -217.190044) (xy 90.807413 -217.236678) (xy 90.779483 -217.279751)
			(xy 90.745664 -217.318373) (xy 90.706654 -217.351745) (xy 90.663262 -217.379177) (xy 90.616383 -217.400101)
			(xy 90.566988 -217.414084) (xy 90.541602 -217.417904) (xy 90.51671 -217.421206) (xy 90.344752 -217.71864)
			(xy 90.354404 -217.742008) (xy 90.362969 -217.76372) (xy 90.375057 -217.8088) (xy 90.381179 -217.85507)
			(xy 90.381582 -217.878406) (xy 90.60815 -217.878406) (xy 90.608649 -217.851719) (xy 90.616604 -217.79894)
			(xy 90.632336 -217.747937) (xy 90.655494 -217.699848) (xy 90.685561 -217.655748) (xy 90.721865 -217.616621)
			(xy 90.763595 -217.583343) (xy 90.809819 -217.556656) (xy 90.859504 -217.537156) (xy 90.911541 -217.525279)
			(xy 90.964766 -217.52129) (xy 91.017991 -217.525279) (xy 91.070028 -217.537156) (xy 91.119713 -217.556656)
			(xy 91.165937 -217.583343) (xy 91.207667 -217.616621) (xy 91.243971 -217.655748) (xy 91.274038 -217.699848)
			(xy 91.297196 -217.747937) (xy 91.312928 -217.79894) (xy 91.320883 -217.851719) (xy 91.321382 -217.878406)
			(xy 91.54795 -217.878406) (xy 91.548376 -217.852737) (xy 91.555724 -217.801928) (xy 91.570282 -217.752698)
			(xy 91.59175 -217.706064) (xy 91.619684 -217.662992) (xy 91.653507 -217.624371) (xy 91.692519 -217.591)
			(xy 91.735913 -217.563568) (xy 91.782793 -217.542644) (xy 91.832189 -217.528659) (xy 91.857576 -217.524838)
			(xy 91.882468 -217.521536) (xy 92.054426 -217.224102) (xy 92.044774 -217.200734) (xy 92.03619 -217.179029)
			(xy 92.024109 -217.133945) (xy 92.017995 -217.087673) (xy 92.017596 -217.064336) (xy 92.018095 -217.037649)
			(xy 92.02605 -216.98487) (xy 92.041782 -216.933867) (xy 92.06494 -216.885778) (xy 92.095007 -216.841678)
			(xy 92.131311 -216.802551) (xy 92.173041 -216.769273) (xy 92.219265 -216.742586) (xy 92.26895 -216.723086)
			(xy 92.320987 -216.711209) (xy 92.374212 -216.70722) (xy 92.427437 -216.711209) (xy 92.479474 -216.723086)
			(xy 92.529159 -216.742586) (xy 92.575383 -216.769273) (xy 92.617113 -216.802551) (xy 92.653417 -216.841678)
			(xy 92.683484 -216.885778) (xy 92.706642 -216.933867) (xy 92.722374 -216.98487) (xy 92.730329 -217.037649)
			(xy 92.730828 -217.064336) (xy 92.730367 -217.090004) (xy 92.723027 -217.140813) (xy 92.708476 -217.190044)
			(xy 92.687013 -217.236678) (xy 92.659083 -217.279751) (xy 92.625264 -217.318373) (xy 92.586254 -217.351745)
			(xy 92.542862 -217.379177) (xy 92.495983 -217.400101) (xy 92.446588 -217.414084) (xy 92.421202 -217.417904)
			(xy 92.39631 -217.421206) (xy 92.224352 -217.71864) (xy 92.234004 -217.742008) (xy 92.242569 -217.76372)
			(xy 92.254657 -217.8088) (xy 92.260779 -217.85507) (xy 92.261182 -217.878406) (xy 92.48775 -217.878406)
			(xy 92.488249 -217.851719) (xy 92.496204 -217.79894) (xy 92.511936 -217.747937) (xy 92.535094 -217.699848)
			(xy 92.565161 -217.655748) (xy 92.601465 -217.616621) (xy 92.643195 -217.583343) (xy 92.689419 -217.556656)
			(xy 92.739104 -217.537156) (xy 92.791141 -217.525279) (xy 92.844366 -217.52129) (xy 92.897591 -217.525279)
			(xy 92.949628 -217.537156) (xy 92.999313 -217.556656) (xy 93.045537 -217.583343) (xy 93.087267 -217.616621)
			(xy 93.123571 -217.655748) (xy 93.153638 -217.699848) (xy 93.176796 -217.747937) (xy 93.192528 -217.79894)
			(xy 93.200483 -217.851719) (xy 93.200982 -217.878406) (xy 93.42755 -217.878406) (xy 93.427976 -217.852737)
			(xy 93.435324 -217.801928) (xy 93.449882 -217.752698) (xy 93.47135 -217.706064) (xy 93.499284 -217.662992)
			(xy 93.533107 -217.624371) (xy 93.572119 -217.591) (xy 93.615513 -217.563568) (xy 93.662393 -217.542644)
			(xy 93.711789 -217.528659) (xy 93.737176 -217.524838) (xy 93.762068 -217.521536) (xy 93.934026 -217.224102)
			(xy 93.924374 -217.200734) (xy 93.91579 -217.179029) (xy 93.903709 -217.133945) (xy 93.897595 -217.087673)
			(xy 93.897196 -217.064336) (xy 93.897695 -217.037649) (xy 93.90565 -216.98487) (xy 93.921382 -216.933867)
			(xy 93.94454 -216.885778) (xy 93.974607 -216.841678) (xy 94.010911 -216.802551) (xy 94.052641 -216.769273)
			(xy 94.098865 -216.742586) (xy 94.14855 -216.723086) (xy 94.200587 -216.711209) (xy 94.253812 -216.70722)
			(xy 94.307037 -216.711209) (xy 94.359074 -216.723086) (xy 94.408759 -216.742586) (xy 94.454983 -216.769273)
			(xy 94.496713 -216.802551) (xy 94.533017 -216.841678) (xy 94.563084 -216.885778) (xy 94.586242 -216.933867)
			(xy 94.601974 -216.98487) (xy 94.609929 -217.037649) (xy 94.610428 -217.064336) (xy 94.609967 -217.090004)
			(xy 94.602627 -217.140813) (xy 94.588076 -217.190044) (xy 94.566613 -217.236678) (xy 94.538683 -217.279751)
			(xy 94.504864 -217.318373) (xy 94.465854 -217.351745) (xy 94.422462 -217.379177) (xy 94.375583 -217.400101)
			(xy 94.326188 -217.414084) (xy 94.300802 -217.417904) (xy 94.27591 -217.421206) (xy 94.103952 -217.71864)
			(xy 94.113604 -217.742008) (xy 94.122169 -217.76372) (xy 94.134257 -217.8088) (xy 94.140379 -217.85507)
			(xy 94.140782 -217.878406) (xy 94.36735 -217.878406) (xy 94.367849 -217.851719) (xy 94.375804 -217.79894)
			(xy 94.391536 -217.747937) (xy 94.414694 -217.699848) (xy 94.444761 -217.655748) (xy 94.481065 -217.616621)
			(xy 94.522795 -217.583343) (xy 94.569019 -217.556656) (xy 94.618704 -217.537156) (xy 94.670741 -217.525279)
			(xy 94.723966 -217.52129) (xy 94.777191 -217.525279) (xy 94.829228 -217.537156) (xy 94.878913 -217.556656)
			(xy 94.925137 -217.583343) (xy 94.966867 -217.616621) (xy 95.003171 -217.655748) (xy 95.033238 -217.699848)
			(xy 95.056396 -217.747937) (xy 95.072128 -217.79894) (xy 95.080083 -217.851719) (xy 95.080582 -217.878406)
			(xy 95.30715 -217.878406) (xy 95.307576 -217.852737) (xy 95.314924 -217.801928) (xy 95.329482 -217.752698)
			(xy 95.35095 -217.706064) (xy 95.378884 -217.662992) (xy 95.412707 -217.624371) (xy 95.451719 -217.591)
			(xy 95.495113 -217.563568) (xy 95.541993 -217.542644) (xy 95.591389 -217.528659) (xy 95.616776 -217.524838)
			(xy 95.641668 -217.521536) (xy 95.813626 -217.224102) (xy 95.803974 -217.200734) (xy 95.79539 -217.179029)
			(xy 95.783309 -217.133945) (xy 95.777195 -217.087673) (xy 95.776796 -217.064336) (xy 95.777295 -217.037649)
			(xy 95.78525 -216.98487) (xy 95.800982 -216.933867) (xy 95.82414 -216.885778) (xy 95.854207 -216.841678)
			(xy 95.890511 -216.802551) (xy 95.932241 -216.769273) (xy 95.978465 -216.742586) (xy 96.02815 -216.723086)
			(xy 96.080187 -216.711209) (xy 96.133412 -216.70722) (xy 96.186637 -216.711209) (xy 96.238674 -216.723086)
			(xy 96.288359 -216.742586) (xy 96.334583 -216.769273) (xy 96.376313 -216.802551) (xy 96.412617 -216.841678)
			(xy 96.442684 -216.885778) (xy 96.465842 -216.933867) (xy 96.481574 -216.98487) (xy 96.489529 -217.037649)
			(xy 96.490028 -217.064336) (xy 96.489567 -217.090004) (xy 96.482227 -217.140813) (xy 96.467676 -217.190044)
			(xy 96.446213 -217.236678) (xy 96.418283 -217.279751) (xy 96.384464 -217.318373) (xy 96.345454 -217.351745)
			(xy 96.302062 -217.379177) (xy 96.255183 -217.400101) (xy 96.205788 -217.414084) (xy 96.180402 -217.417904)
			(xy 96.15551 -217.421206) (xy 95.983552 -217.71864) (xy 95.993204 -217.742008) (xy 96.001769 -217.76372)
			(xy 96.013857 -217.8088) (xy 96.019979 -217.85507) (xy 96.020382 -217.878406) (xy 96.24695 -217.878406)
			(xy 96.247449 -217.851719) (xy 96.255404 -217.79894) (xy 96.271136 -217.747937) (xy 96.294294 -217.699848)
			(xy 96.324361 -217.655748) (xy 96.360665 -217.616621) (xy 96.402395 -217.583343) (xy 96.448619 -217.556656)
			(xy 96.498304 -217.537156) (xy 96.550341 -217.525279) (xy 96.603566 -217.52129) (xy 96.656791 -217.525279)
			(xy 96.708828 -217.537156) (xy 96.758513 -217.556656) (xy 96.804737 -217.583343) (xy 96.846467 -217.616621)
			(xy 96.882771 -217.655748) (xy 96.912838 -217.699848) (xy 96.935996 -217.747937) (xy 96.951728 -217.79894)
			(xy 96.959683 -217.851719) (xy 96.960182 -217.878406) (xy 97.18675 -217.878406) (xy 97.187176 -217.852737)
			(xy 97.194524 -217.801928) (xy 97.209082 -217.752698) (xy 97.23055 -217.706064) (xy 97.258484 -217.662992)
			(xy 97.292307 -217.624371) (xy 97.331319 -217.591) (xy 97.374713 -217.563568) (xy 97.421593 -217.542644)
			(xy 97.470989 -217.528659) (xy 97.496376 -217.524838) (xy 97.521268 -217.521536) (xy 97.693226 -217.224102)
			(xy 97.683574 -217.200734) (xy 97.67499 -217.179029) (xy 97.662909 -217.133945) (xy 97.656795 -217.087673)
			(xy 97.656396 -217.064336) (xy 97.656895 -217.037649) (xy 97.66485 -216.98487) (xy 97.680582 -216.933867)
			(xy 97.70374 -216.885778) (xy 97.733807 -216.841678) (xy 97.770111 -216.802551) (xy 97.811841 -216.769273)
			(xy 97.858065 -216.742586) (xy 97.90775 -216.723086) (xy 97.959787 -216.711209) (xy 98.013012 -216.70722)
			(xy 98.066237 -216.711209) (xy 98.118274 -216.723086) (xy 98.167959 -216.742586) (xy 98.214183 -216.769273)
			(xy 98.255913 -216.802551) (xy 98.292217 -216.841678) (xy 98.322284 -216.885778) (xy 98.345442 -216.933867)
			(xy 98.361174 -216.98487) (xy 98.369129 -217.037649) (xy 98.369628 -217.064336) (xy 98.369167 -217.090004)
			(xy 98.361827 -217.140813) (xy 98.347276 -217.190044) (xy 98.325813 -217.236678) (xy 98.297883 -217.279751)
			(xy 98.264064 -217.318373) (xy 98.225054 -217.351745) (xy 98.181662 -217.379177) (xy 98.134783 -217.400101)
			(xy 98.085388 -217.414084) (xy 98.060002 -217.417904) (xy 98.03511 -217.421206) (xy 97.863152 -217.71864)
			(xy 97.872804 -217.742008) (xy 97.881369 -217.76372) (xy 97.893457 -217.8088) (xy 97.899579 -217.85507)
			(xy 97.899982 -217.878406) (xy 98.12655 -217.878406) (xy 98.127049 -217.851719) (xy 98.135004 -217.79894)
			(xy 98.150736 -217.747937) (xy 98.173894 -217.699848) (xy 98.203961 -217.655748) (xy 98.240265 -217.616621)
			(xy 98.281995 -217.583343) (xy 98.328219 -217.556656) (xy 98.377904 -217.537156) (xy 98.429941 -217.525279)
			(xy 98.483166 -217.52129) (xy 98.536391 -217.525279) (xy 98.588428 -217.537156) (xy 98.638113 -217.556656)
			(xy 98.684337 -217.583343) (xy 98.726067 -217.616621) (xy 98.762371 -217.655748) (xy 98.792438 -217.699848)
			(xy 98.815596 -217.747937) (xy 98.831328 -217.79894) (xy 98.839283 -217.851719) (xy 98.839782 -217.878406)
			(xy 99.06635 -217.878406) (xy 99.066776 -217.852737) (xy 99.074124 -217.801928) (xy 99.088682 -217.752698)
			(xy 99.11015 -217.706064) (xy 99.138084 -217.662992) (xy 99.171907 -217.624371) (xy 99.210919 -217.591)
			(xy 99.254313 -217.563568) (xy 99.301193 -217.542644) (xy 99.350589 -217.528659) (xy 99.375976 -217.524838)
			(xy 99.400868 -217.521536) (xy 99.572826 -217.224102) (xy 99.563174 -217.200734) (xy 99.55459 -217.179029)
			(xy 99.542509 -217.133945) (xy 99.536395 -217.087673) (xy 99.535996 -217.064336) (xy 99.536495 -217.037649)
			(xy 99.54445 -216.98487) (xy 99.560182 -216.933867) (xy 99.58334 -216.885778) (xy 99.613407 -216.841678)
			(xy 99.649711 -216.802551) (xy 99.691441 -216.769273) (xy 99.737665 -216.742586) (xy 99.78735 -216.723086)
			(xy 99.839387 -216.711209) (xy 99.892612 -216.70722) (xy 99.945837 -216.711209) (xy 99.997874 -216.723086)
			(xy 100.047559 -216.742586) (xy 100.093783 -216.769273) (xy 100.135513 -216.802551) (xy 100.171817 -216.841678)
			(xy 100.201884 -216.885778) (xy 100.225042 -216.933867) (xy 100.240774 -216.98487) (xy 100.248729 -217.037649)
			(xy 100.249228 -217.064336) (xy 100.248767 -217.090004) (xy 100.241427 -217.140813) (xy 100.226876 -217.190044)
			(xy 100.205413 -217.236678) (xy 100.177483 -217.279751) (xy 100.143664 -217.318373) (xy 100.104654 -217.351745)
			(xy 100.061262 -217.379177) (xy 100.014383 -217.400101) (xy 99.964988 -217.414084) (xy 99.939602 -217.417904)
			(xy 99.91471 -217.421206) (xy 99.742752 -217.71864) (xy 99.752404 -217.742008) (xy 99.760969 -217.76372)
			(xy 99.773057 -217.8088) (xy 99.779179 -217.85507) (xy 99.779582 -217.878406) (xy 100.00615 -217.878406)
			(xy 100.006649 -217.851719) (xy 100.014604 -217.79894) (xy 100.030336 -217.747937) (xy 100.053494 -217.699848)
			(xy 100.083561 -217.655748) (xy 100.119865 -217.616621) (xy 100.161595 -217.583343) (xy 100.207819 -217.556656)
			(xy 100.257504 -217.537156) (xy 100.309541 -217.525279) (xy 100.362766 -217.52129) (xy 100.415991 -217.525279)
			(xy 100.468028 -217.537156) (xy 100.517713 -217.556656) (xy 100.563937 -217.583343) (xy 100.605667 -217.616621)
			(xy 100.641971 -217.655748) (xy 100.672038 -217.699848) (xy 100.695196 -217.747937) (xy 100.710928 -217.79894)
			(xy 100.718883 -217.851719) (xy 100.719382 -217.878406) (xy 100.94595 -217.878406) (xy 100.946376 -217.852737)
			(xy 100.953724 -217.801928) (xy 100.968282 -217.752698) (xy 100.98975 -217.706064) (xy 101.017684 -217.662992)
			(xy 101.051507 -217.624371) (xy 101.090519 -217.591) (xy 101.133913 -217.563568) (xy 101.180793 -217.542644)
			(xy 101.230189 -217.528659) (xy 101.255576 -217.524838) (xy 101.280468 -217.521536) (xy 101.452426 -217.224102)
			(xy 101.442774 -217.200734) (xy 101.43419 -217.179029) (xy 101.422109 -217.133945) (xy 101.415995 -217.087673)
			(xy 101.415596 -217.064336) (xy 101.416095 -217.037649) (xy 101.42405 -216.98487) (xy 101.439782 -216.933867)
			(xy 101.46294 -216.885778) (xy 101.493007 -216.841678) (xy 101.529311 -216.802551) (xy 101.571041 -216.769273)
			(xy 101.617265 -216.742586) (xy 101.66695 -216.723086) (xy 101.718987 -216.711209) (xy 101.772212 -216.70722)
			(xy 101.825437 -216.711209) (xy 101.877474 -216.723086) (xy 101.927159 -216.742586) (xy 101.973383 -216.769273)
			(xy 102.015113 -216.802551) (xy 102.051417 -216.841678) (xy 102.081484 -216.885778) (xy 102.104642 -216.933867)
			(xy 102.120374 -216.98487) (xy 102.128329 -217.037649) (xy 102.128828 -217.064336) (xy 102.128367 -217.090004)
			(xy 102.121027 -217.140813) (xy 102.106476 -217.190044) (xy 102.085013 -217.236678) (xy 102.057083 -217.279751)
			(xy 102.023264 -217.318373) (xy 101.984254 -217.351745) (xy 101.940862 -217.379177) (xy 101.893983 -217.400101)
			(xy 101.844588 -217.414084) (xy 101.819202 -217.417904) (xy 101.79431 -217.421206) (xy 101.622352 -217.71864)
			(xy 101.632004 -217.742008) (xy 101.640569 -217.76372) (xy 101.652657 -217.8088) (xy 101.658779 -217.85507)
			(xy 101.659182 -217.878406) (xy 101.88575 -217.878406) (xy 101.886249 -217.851719) (xy 101.894204 -217.79894)
			(xy 101.909936 -217.747937) (xy 101.933094 -217.699848) (xy 101.963161 -217.655748) (xy 101.999465 -217.616621)
			(xy 102.041195 -217.583343) (xy 102.087419 -217.556656) (xy 102.137104 -217.537156) (xy 102.189141 -217.525279)
			(xy 102.242366 -217.52129) (xy 102.295591 -217.525279) (xy 102.347628 -217.537156) (xy 102.397313 -217.556656)
			(xy 102.443537 -217.583343) (xy 102.485267 -217.616621) (xy 102.521571 -217.655748) (xy 102.551638 -217.699848)
			(xy 102.574796 -217.747937) (xy 102.590528 -217.79894) (xy 102.598483 -217.851719) (xy 102.598982 -217.878406)
			(xy 102.82555 -217.878406) (xy 102.825976 -217.852737) (xy 102.833324 -217.801928) (xy 102.847882 -217.752698)
			(xy 102.86935 -217.706064) (xy 102.897284 -217.662992) (xy 102.931107 -217.624371) (xy 102.970119 -217.591)
			(xy 103.013513 -217.563568) (xy 103.060393 -217.542644) (xy 103.109789 -217.528659) (xy 103.135176 -217.524838)
			(xy 103.160068 -217.521536) (xy 103.332026 -217.224102) (xy 103.322374 -217.200734) (xy 103.31379 -217.179029)
			(xy 103.301709 -217.133945) (xy 103.295595 -217.087673) (xy 103.295196 -217.064336) (xy 103.295695 -217.037649)
			(xy 103.30365 -216.98487) (xy 103.319382 -216.933867) (xy 103.34254 -216.885778) (xy 103.372607 -216.841678)
			(xy 103.408911 -216.802551) (xy 103.450641 -216.769273) (xy 103.496865 -216.742586) (xy 103.54655 -216.723086)
			(xy 103.598587 -216.711209) (xy 103.651812 -216.70722) (xy 103.705037 -216.711209) (xy 103.757074 -216.723086)
			(xy 103.806759 -216.742586) (xy 103.852983 -216.769273) (xy 103.894713 -216.802551) (xy 103.931017 -216.841678)
			(xy 103.961084 -216.885778) (xy 103.984242 -216.933867) (xy 103.999974 -216.98487) (xy 104.007929 -217.037649)
			(xy 104.008428 -217.064336) (xy 104.007967 -217.090004) (xy 104.000627 -217.140813) (xy 103.986076 -217.190044)
			(xy 103.964613 -217.236678) (xy 103.936683 -217.279751) (xy 103.902864 -217.318373) (xy 103.863854 -217.351745)
			(xy 103.820462 -217.379177) (xy 103.773583 -217.400101) (xy 103.724188 -217.414084) (xy 103.698802 -217.417904)
			(xy 103.67391 -217.421206) (xy 103.501952 -217.71864) (xy 103.511604 -217.742008) (xy 103.520169 -217.76372)
			(xy 103.532257 -217.8088) (xy 103.538379 -217.85507) (xy 103.538782 -217.878406) (xy 103.76535 -217.878406)
			(xy 103.765849 -217.851719) (xy 103.773804 -217.79894) (xy 103.789536 -217.747937) (xy 103.812694 -217.699848)
			(xy 103.842761 -217.655748) (xy 103.879065 -217.616621) (xy 103.920795 -217.583343) (xy 103.967019 -217.556656)
			(xy 104.016704 -217.537156) (xy 104.068741 -217.525279) (xy 104.121966 -217.52129) (xy 104.175191 -217.525279)
			(xy 104.227228 -217.537156) (xy 104.276913 -217.556656) (xy 104.323137 -217.583343) (xy 104.364867 -217.616621)
			(xy 104.401171 -217.655748) (xy 104.431238 -217.699848) (xy 104.454396 -217.747937) (xy 104.470128 -217.79894)
			(xy 104.478083 -217.851719) (xy 104.478582 -217.878406) (xy 104.70515 -217.878406) (xy 104.705576 -217.852737)
			(xy 104.712924 -217.801928) (xy 104.727482 -217.752698) (xy 104.74895 -217.706064) (xy 104.776884 -217.662992)
			(xy 104.810707 -217.624371) (xy 104.849719 -217.591) (xy 104.893113 -217.563568) (xy 104.939993 -217.542644)
			(xy 104.989389 -217.528659) (xy 105.014776 -217.524838) (xy 105.039668 -217.521536) (xy 105.211626 -217.224102)
			(xy 105.201974 -217.200734) (xy 105.19339 -217.179029) (xy 105.181309 -217.133945) (xy 105.175195 -217.087673)
			(xy 105.174796 -217.064336) (xy 105.175295 -217.037649) (xy 105.18325 -216.98487) (xy 105.198982 -216.933867)
			(xy 105.22214 -216.885778) (xy 105.252207 -216.841678) (xy 105.288511 -216.802551) (xy 105.330241 -216.769273)
			(xy 105.376465 -216.742586) (xy 105.42615 -216.723086) (xy 105.478187 -216.711209) (xy 105.531412 -216.70722)
			(xy 105.584637 -216.711209) (xy 105.636674 -216.723086) (xy 105.686359 -216.742586) (xy 105.732583 -216.769273)
			(xy 105.774313 -216.802551) (xy 105.810617 -216.841678) (xy 105.840684 -216.885778) (xy 105.863842 -216.933867)
			(xy 105.879574 -216.98487) (xy 105.887529 -217.037649) (xy 105.888028 -217.064336) (xy 105.887567 -217.090004)
			(xy 105.880227 -217.140813) (xy 105.865676 -217.190044) (xy 105.844213 -217.236678) (xy 105.816283 -217.279751)
			(xy 105.782464 -217.318373) (xy 105.743454 -217.351745) (xy 105.700062 -217.379177) (xy 105.653183 -217.400101)
			(xy 105.603788 -217.414084) (xy 105.578402 -217.417904) (xy 105.55351 -217.421206) (xy 105.381552 -217.71864)
			(xy 105.391204 -217.742008) (xy 105.399769 -217.76372) (xy 105.411857 -217.8088) (xy 105.417979 -217.85507)
			(xy 105.418382 -217.878406) (xy 105.64495 -217.878406) (xy 105.645449 -217.851719) (xy 105.653404 -217.79894)
			(xy 105.669136 -217.747937) (xy 105.692294 -217.699848) (xy 105.722361 -217.655748) (xy 105.758665 -217.616621)
			(xy 105.800395 -217.583343) (xy 105.846619 -217.556656) (xy 105.896304 -217.537156) (xy 105.948341 -217.525279)
			(xy 106.001566 -217.52129) (xy 106.054791 -217.525279) (xy 106.106828 -217.537156) (xy 106.156513 -217.556656)
			(xy 106.202737 -217.583343) (xy 106.244467 -217.616621) (xy 106.280771 -217.655748) (xy 106.310838 -217.699848)
			(xy 106.333996 -217.747937) (xy 106.349728 -217.79894) (xy 106.357683 -217.851719) (xy 106.358182 -217.878406)
			(xy 106.58475 -217.878406) (xy 106.585176 -217.852737) (xy 106.592524 -217.801928) (xy 106.607082 -217.752698)
			(xy 106.62855 -217.706064) (xy 106.656484 -217.662992) (xy 106.690307 -217.624371) (xy 106.729319 -217.591)
			(xy 106.772713 -217.563568) (xy 106.819593 -217.542644) (xy 106.868989 -217.528659) (xy 106.894376 -217.524838)
			(xy 106.919268 -217.521536) (xy 107.091226 -217.224102) (xy 107.081574 -217.200734) (xy 107.07299 -217.179029)
			(xy 107.060909 -217.133945) (xy 107.054795 -217.087673) (xy 107.054396 -217.064336) (xy 107.054895 -217.037649)
			(xy 107.06285 -216.98487) (xy 107.078582 -216.933867) (xy 107.10174 -216.885778) (xy 107.131807 -216.841678)
			(xy 107.168111 -216.802551) (xy 107.209841 -216.769273) (xy 107.256065 -216.742586) (xy 107.30575 -216.723086)
			(xy 107.357787 -216.711209) (xy 107.411012 -216.70722) (xy 107.464237 -216.711209) (xy 107.516274 -216.723086)
			(xy 107.565959 -216.742586) (xy 107.612183 -216.769273) (xy 107.653913 -216.802551) (xy 107.690217 -216.841678)
			(xy 107.720284 -216.885778) (xy 107.743442 -216.933867) (xy 107.759174 -216.98487) (xy 107.767129 -217.037649)
			(xy 107.767628 -217.064336) (xy 107.767167 -217.090004) (xy 107.759827 -217.140813) (xy 107.745276 -217.190044)
			(xy 107.723813 -217.236678) (xy 107.695883 -217.279751) (xy 107.662064 -217.318373) (xy 107.623054 -217.351745)
			(xy 107.579662 -217.379177) (xy 107.532783 -217.400101) (xy 107.483388 -217.414084) (xy 107.458002 -217.417904)
			(xy 107.43311 -217.421206) (xy 107.261152 -217.71864) (xy 107.270804 -217.742008) (xy 107.279369 -217.76372)
			(xy 107.291457 -217.8088) (xy 107.297579 -217.85507) (xy 107.297982 -217.878406) (xy 107.52455 -217.878406)
			(xy 107.525049 -217.851719) (xy 107.533004 -217.79894) (xy 107.548736 -217.747937) (xy 107.571894 -217.699848)
			(xy 107.601961 -217.655748) (xy 107.638265 -217.616621) (xy 107.679995 -217.583343) (xy 107.726219 -217.556656)
			(xy 107.775904 -217.537156) (xy 107.827941 -217.525279) (xy 107.881166 -217.52129) (xy 107.934391 -217.525279)
			(xy 107.986428 -217.537156) (xy 108.036113 -217.556656) (xy 108.082337 -217.583343) (xy 108.124067 -217.616621)
			(xy 108.160371 -217.655748) (xy 108.190438 -217.699848) (xy 108.213596 -217.747937) (xy 108.229328 -217.79894)
			(xy 108.237283 -217.851719) (xy 108.237782 -217.878406) (xy 108.46435 -217.878406) (xy 108.464776 -217.852737)
			(xy 108.472124 -217.801928) (xy 108.486682 -217.752698) (xy 108.50815 -217.706064) (xy 108.536084 -217.662992)
			(xy 108.569907 -217.624371) (xy 108.608919 -217.591) (xy 108.652313 -217.563568) (xy 108.699193 -217.542644)
			(xy 108.748589 -217.528659) (xy 108.773976 -217.524838) (xy 108.798868 -217.521536) (xy 108.970826 -217.224102)
			(xy 108.961174 -217.200734) (xy 108.95259 -217.179029) (xy 108.940509 -217.133945) (xy 108.934395 -217.087673)
			(xy 108.933996 -217.064336) (xy 108.934495 -217.037649) (xy 108.94245 -216.98487) (xy 108.958182 -216.933867)
			(xy 108.98134 -216.885778) (xy 109.011407 -216.841678) (xy 109.047711 -216.802551) (xy 109.089441 -216.769273)
			(xy 109.135665 -216.742586) (xy 109.18535 -216.723086) (xy 109.237387 -216.711209) (xy 109.290612 -216.70722)
			(xy 109.343837 -216.711209) (xy 109.395874 -216.723086) (xy 109.445559 -216.742586) (xy 109.491783 -216.769273)
			(xy 109.533513 -216.802551) (xy 109.569817 -216.841678) (xy 109.599884 -216.885778) (xy 109.623042 -216.933867)
			(xy 109.638774 -216.98487) (xy 109.646729 -217.037649) (xy 109.647228 -217.064336) (xy 109.646767 -217.090004)
			(xy 109.639427 -217.140813) (xy 109.624876 -217.190044) (xy 109.603413 -217.236678) (xy 109.575483 -217.279751)
			(xy 109.541664 -217.318373) (xy 109.502654 -217.351745) (xy 109.459262 -217.379177) (xy 109.412383 -217.400101)
			(xy 109.362988 -217.414084) (xy 109.337602 -217.417904) (xy 109.31271 -217.421206) (xy 109.140752 -217.71864)
			(xy 109.150404 -217.742008) (xy 109.158969 -217.76372) (xy 109.171057 -217.8088) (xy 109.177179 -217.85507)
			(xy 109.177582 -217.878406) (xy 109.40415 -217.878406) (xy 109.404649 -217.851719) (xy 109.412604 -217.79894)
			(xy 109.428336 -217.747937) (xy 109.451494 -217.699848) (xy 109.481561 -217.655748) (xy 109.517865 -217.616621)
			(xy 109.559595 -217.583343) (xy 109.605819 -217.556656) (xy 109.655504 -217.537156) (xy 109.707541 -217.525279)
			(xy 109.760766 -217.52129) (xy 109.813991 -217.525279) (xy 109.866028 -217.537156) (xy 109.915713 -217.556656)
			(xy 109.961937 -217.583343) (xy 110.003667 -217.616621) (xy 110.039971 -217.655748) (xy 110.070038 -217.699848)
			(xy 110.093196 -217.747937) (xy 110.108928 -217.79894) (xy 110.116883 -217.851719) (xy 110.117382 -217.878406)
			(xy 110.34395 -217.878406) (xy 110.344376 -217.852737) (xy 110.351724 -217.801928) (xy 110.366282 -217.752698)
			(xy 110.38775 -217.706064) (xy 110.415684 -217.662992) (xy 110.449507 -217.624371) (xy 110.488519 -217.591)
			(xy 110.531913 -217.563568) (xy 110.578793 -217.542644) (xy 110.628189 -217.528659) (xy 110.653576 -217.524838)
			(xy 110.678468 -217.521536) (xy 110.850426 -217.223594) (xy 110.840774 -217.20048) (xy 110.832281 -217.178884)
			(xy 110.820298 -217.134054) (xy 110.81424 -217.088046) (xy 110.81385 -217.064844) (xy 110.81385 -217.064336)
			(xy 110.814349 -217.037649) (xy 110.822304 -216.98487) (xy 110.838036 -216.933867) (xy 110.861194 -216.885778)
			(xy 110.891261 -216.841678) (xy 110.927565 -216.802551) (xy 110.969295 -216.769273) (xy 111.015519 -216.742586)
			(xy 111.065204 -216.723086) (xy 111.117241 -216.711209) (xy 111.170466 -216.70722) (xy 111.223691 -216.711209)
			(xy 111.275728 -216.723086) (xy 111.325413 -216.742586) (xy 111.371637 -216.769273) (xy 111.413367 -216.802551)
			(xy 111.449671 -216.841678) (xy 111.479738 -216.885778) (xy 111.502896 -216.933867) (xy 111.518628 -216.98487)
			(xy 111.526583 -217.037649) (xy 111.527082 -217.064336) (xy 112.693196 -217.064336) (xy 112.693695 -217.037649)
			(xy 112.70165 -216.98487) (xy 112.717382 -216.933867) (xy 112.74054 -216.885778) (xy 112.770607 -216.841678)
			(xy 112.806911 -216.802551) (xy 112.848641 -216.769273) (xy 112.894865 -216.742586) (xy 112.94455 -216.723086)
			(xy 112.996587 -216.711209) (xy 113.049812 -216.70722) (xy 113.103037 -216.711209) (xy 113.155074 -216.723086)
			(xy 113.204759 -216.742586) (xy 113.250983 -216.769273) (xy 113.292713 -216.802551) (xy 113.329017 -216.841678)
			(xy 113.359084 -216.885778) (xy 113.382242 -216.933867) (xy 113.397974 -216.98487) (xy 113.405929 -217.037649)
			(xy 113.406428 -217.064336) (xy 114.572796 -217.064336) (xy 114.573295 -217.037649) (xy 114.58125 -216.98487)
			(xy 114.596982 -216.933867) (xy 114.62014 -216.885778) (xy 114.650207 -216.841678) (xy 114.686511 -216.802551)
			(xy 114.728241 -216.769273) (xy 114.774465 -216.742586) (xy 114.82415 -216.723086) (xy 114.876187 -216.711209)
			(xy 114.929412 -216.70722) (xy 114.982637 -216.711209) (xy 115.034674 -216.723086) (xy 115.084359 -216.742586)
			(xy 115.130583 -216.769273) (xy 115.172313 -216.802551) (xy 115.208617 -216.841678) (xy 115.238684 -216.885778)
			(xy 115.261842 -216.933867) (xy 115.277574 -216.98487) (xy 115.285529 -217.037649) (xy 115.286028 -217.064336)
			(xy 116.452396 -217.064336) (xy 116.452895 -217.037649) (xy 116.46085 -216.98487) (xy 116.476582 -216.933867)
			(xy 116.49974 -216.885778) (xy 116.529807 -216.841678) (xy 116.566111 -216.802551) (xy 116.607841 -216.769273)
			(xy 116.654065 -216.742586) (xy 116.70375 -216.723086) (xy 116.755787 -216.711209) (xy 116.809012 -216.70722)
			(xy 116.862237 -216.711209) (xy 116.914274 -216.723086) (xy 116.963959 -216.742586) (xy 117.010183 -216.769273)
			(xy 117.051913 -216.802551) (xy 117.088217 -216.841678) (xy 117.118284 -216.885778) (xy 117.141442 -216.933867)
			(xy 117.157174 -216.98487) (xy 117.165129 -217.037649) (xy 117.165628 -217.064336) (xy 118.331996 -217.064336)
			(xy 118.332495 -217.037649) (xy 118.34045 -216.98487) (xy 118.356182 -216.933867) (xy 118.37934 -216.885778)
			(xy 118.409407 -216.841678) (xy 118.445711 -216.802551) (xy 118.487441 -216.769273) (xy 118.533665 -216.742586)
			(xy 118.58335 -216.723086) (xy 118.635387 -216.711209) (xy 118.688612 -216.70722) (xy 118.741837 -216.711209)
			(xy 118.793874 -216.723086) (xy 118.843559 -216.742586) (xy 118.889783 -216.769273) (xy 118.931513 -216.802551)
			(xy 118.967817 -216.841678) (xy 118.997884 -216.885778) (xy 119.021042 -216.933867) (xy 119.036774 -216.98487)
			(xy 119.044729 -217.037649) (xy 119.045228 -217.064336) (xy 120.211596 -217.064336) (xy 120.212095 -217.037649)
			(xy 120.22005 -216.98487) (xy 120.235782 -216.933867) (xy 120.25894 -216.885778) (xy 120.289007 -216.841678)
			(xy 120.325311 -216.802551) (xy 120.367041 -216.769273) (xy 120.413265 -216.742586) (xy 120.46295 -216.723086)
			(xy 120.514987 -216.711209) (xy 120.568212 -216.70722) (xy 120.621437 -216.711209) (xy 120.673474 -216.723086)
			(xy 120.723159 -216.742586) (xy 120.769383 -216.769273) (xy 120.811113 -216.802551) (xy 120.847417 -216.841678)
			(xy 120.877484 -216.885778) (xy 120.900642 -216.933867) (xy 120.916374 -216.98487) (xy 120.924329 -217.037649)
			(xy 120.924828 -217.064336) (xy 122.091196 -217.064336) (xy 122.091695 -217.037649) (xy 122.09965 -216.98487)
			(xy 122.115382 -216.933867) (xy 122.13854 -216.885778) (xy 122.168607 -216.841678) (xy 122.204911 -216.802551)
			(xy 122.246641 -216.769273) (xy 122.292865 -216.742586) (xy 122.34255 -216.723086) (xy 122.394587 -216.711209)
			(xy 122.447812 -216.70722) (xy 122.501037 -216.711209) (xy 122.553074 -216.723086) (xy 122.602759 -216.742586)
			(xy 122.648983 -216.769273) (xy 122.690713 -216.802551) (xy 122.727017 -216.841678) (xy 122.757084 -216.885778)
			(xy 122.780242 -216.933867) (xy 122.795974 -216.98487) (xy 122.803929 -217.037649) (xy 122.804428 -217.064336)
			(xy 123.970796 -217.064336) (xy 123.971295 -217.037649) (xy 123.97925 -216.98487) (xy 123.994982 -216.933867)
			(xy 124.01814 -216.885778) (xy 124.048207 -216.841678) (xy 124.084511 -216.802551) (xy 124.126241 -216.769273)
			(xy 124.172465 -216.742586) (xy 124.22215 -216.723086) (xy 124.274187 -216.711209) (xy 124.327412 -216.70722)
			(xy 124.380637 -216.711209) (xy 124.432674 -216.723086) (xy 124.482359 -216.742586) (xy 124.528583 -216.769273)
			(xy 124.570313 -216.802551) (xy 124.606617 -216.841678) (xy 124.636684 -216.885778) (xy 124.659842 -216.933867)
			(xy 124.675574 -216.98487) (xy 124.683529 -217.037649) (xy 124.684028 -217.064336) (xy 125.850396 -217.064336)
			(xy 125.850895 -217.037649) (xy 125.85885 -216.98487) (xy 125.874582 -216.933867) (xy 125.89774 -216.885778)
			(xy 125.927807 -216.841678) (xy 125.964111 -216.802551) (xy 126.005841 -216.769273) (xy 126.052065 -216.742586)
			(xy 126.10175 -216.723086) (xy 126.153787 -216.711209) (xy 126.207012 -216.70722) (xy 126.260237 -216.711209)
			(xy 126.312274 -216.723086) (xy 126.361959 -216.742586) (xy 126.408183 -216.769273) (xy 126.449913 -216.802551)
			(xy 126.486217 -216.841678) (xy 126.516284 -216.885778) (xy 126.539442 -216.933867) (xy 126.555174 -216.98487)
			(xy 126.563129 -217.037649) (xy 126.563628 -217.064336) (xy 127.729996 -217.064336) (xy 127.730495 -217.037649)
			(xy 127.73845 -216.98487) (xy 127.754182 -216.933867) (xy 127.77734 -216.885778) (xy 127.807407 -216.841678)
			(xy 127.843711 -216.802551) (xy 127.885441 -216.769273) (xy 127.931665 -216.742586) (xy 127.98135 -216.723086)
			(xy 128.033387 -216.711209) (xy 128.086612 -216.70722) (xy 128.139837 -216.711209) (xy 128.191874 -216.723086)
			(xy 128.241559 -216.742586) (xy 128.287783 -216.769273) (xy 128.329513 -216.802551) (xy 128.365817 -216.841678)
			(xy 128.395884 -216.885778) (xy 128.419042 -216.933867) (xy 128.434774 -216.98487) (xy 128.442729 -217.037649)
			(xy 128.443228 -217.064336) (xy 129.609596 -217.064336) (xy 129.610095 -217.037649) (xy 129.61805 -216.98487)
			(xy 129.633782 -216.933867) (xy 129.65694 -216.885778) (xy 129.687007 -216.841678) (xy 129.723311 -216.802551)
			(xy 129.765041 -216.769273) (xy 129.811265 -216.742586) (xy 129.86095 -216.723086) (xy 129.912987 -216.711209)
			(xy 129.966212 -216.70722) (xy 130.019437 -216.711209) (xy 130.071474 -216.723086) (xy 130.121159 -216.742586)
			(xy 130.167383 -216.769273) (xy 130.209113 -216.802551) (xy 130.245417 -216.841678) (xy 130.275484 -216.885778)
			(xy 130.298642 -216.933867) (xy 130.314374 -216.98487) (xy 130.322329 -217.037649) (xy 130.322828 -217.064336)
			(xy 131.489196 -217.064336) (xy 131.489695 -217.037649) (xy 131.49765 -216.98487) (xy 131.513382 -216.933867)
			(xy 131.53654 -216.885778) (xy 131.566607 -216.841678) (xy 131.602911 -216.802551) (xy 131.644641 -216.769273)
			(xy 131.690865 -216.742586) (xy 131.74055 -216.723086) (xy 131.792587 -216.711209) (xy 131.845812 -216.70722)
			(xy 131.899037 -216.711209) (xy 131.951074 -216.723086) (xy 132.000759 -216.742586) (xy 132.046983 -216.769273)
			(xy 132.088713 -216.802551) (xy 132.125017 -216.841678) (xy 132.155084 -216.885778) (xy 132.178242 -216.933867)
			(xy 132.193974 -216.98487) (xy 132.201929 -217.037649) (xy 132.202428 -217.064336) (xy 133.368796 -217.064336)
			(xy 133.369295 -217.037649) (xy 133.37725 -216.98487) (xy 133.392982 -216.933867) (xy 133.41614 -216.885778)
			(xy 133.446207 -216.841678) (xy 133.482511 -216.802551) (xy 133.524241 -216.769273) (xy 133.570465 -216.742586)
			(xy 133.62015 -216.723086) (xy 133.672187 -216.711209) (xy 133.725412 -216.70722) (xy 133.778637 -216.711209)
			(xy 133.830674 -216.723086) (xy 133.880359 -216.742586) (xy 133.926583 -216.769273) (xy 133.968313 -216.802551)
			(xy 134.004617 -216.841678) (xy 134.034684 -216.885778) (xy 134.057842 -216.933867) (xy 134.073574 -216.98487)
			(xy 134.081529 -217.037649) (xy 134.082028 -217.064336) (xy 134.082028 -217.064844) (xy 134.081621 -217.088045)
			(xy 134.075564 -217.134052) (xy 134.063598 -217.178886) (xy 134.055104 -217.20048) (xy 134.045452 -217.223594)
			(xy 134.217664 -217.521536) (xy 134.242556 -217.524838) (xy 134.267935 -217.528682) (xy 134.317316 -217.542687)
			(xy 134.364181 -217.563624) (xy 134.407562 -217.59106) (xy 134.446563 -217.62443) (xy 134.480379 -217.663045)
			(xy 134.508313 -217.706107) (xy 134.529788 -217.752728) (xy 134.54436 -217.801945) (xy 134.551729 -217.852742)
			(xy 134.552182 -217.878406) (xy 336.668618 -217.878406) (xy 336.669117 -217.851719) (xy 336.677072 -217.79894)
			(xy 336.692804 -217.747937) (xy 336.715962 -217.699848) (xy 336.746029 -217.655748) (xy 336.782333 -217.616621)
			(xy 336.824063 -217.583343) (xy 336.870287 -217.556656) (xy 336.919972 -217.537156) (xy 336.972009 -217.525279)
			(xy 337.025234 -217.52129) (xy 337.078459 -217.525279) (xy 337.130496 -217.537156) (xy 337.180181 -217.556656)
			(xy 337.226405 -217.583343) (xy 337.268135 -217.616621) (xy 337.304439 -217.655748) (xy 337.334506 -217.699848)
			(xy 337.357664 -217.747937) (xy 337.373396 -217.79894) (xy 337.381351 -217.851719) (xy 337.38185 -217.878406)
			(xy 337.608418 -217.878406) (xy 337.608872 -217.852738) (xy 337.616219 -217.801932) (xy 337.630775 -217.752704)
			(xy 337.652241 -217.706072) (xy 337.680172 -217.663001) (xy 337.713991 -217.62438) (xy 337.753 -217.591008)
			(xy 337.79639 -217.563576) (xy 337.843266 -217.542649) (xy 337.892659 -217.528661) (xy 337.918044 -217.524838)
			(xy 337.942936 -217.521536) (xy 338.114894 -217.224102) (xy 338.105242 -217.200734) (xy 338.096662 -217.179028)
			(xy 338.084579 -217.133945) (xy 338.078464 -217.087673) (xy 338.078064 -217.064336) (xy 338.078563 -217.037649)
			(xy 338.086518 -216.98487) (xy 338.10225 -216.933867) (xy 338.125408 -216.885778) (xy 338.155475 -216.841678)
			(xy 338.191779 -216.802551) (xy 338.233509 -216.769273) (xy 338.279733 -216.742586) (xy 338.329418 -216.723086)
			(xy 338.381455 -216.711209) (xy 338.43468 -216.70722) (xy 338.487905 -216.711209) (xy 338.539942 -216.723086)
			(xy 338.589627 -216.742586) (xy 338.635851 -216.769273) (xy 338.677581 -216.802551) (xy 338.713885 -216.841678)
			(xy 338.743952 -216.885778) (xy 338.76711 -216.933867) (xy 338.782842 -216.98487) (xy 338.790797 -217.037649)
			(xy 338.791296 -217.064336) (xy 338.790777 -217.090002) (xy 338.783438 -217.140805) (xy 338.76889 -217.190031)
			(xy 338.747432 -217.236662) (xy 338.719508 -217.279733) (xy 338.685696 -217.318354) (xy 338.646695 -217.351726)
			(xy 338.603311 -217.379161) (xy 338.55644 -217.400089) (xy 338.507053 -217.41408) (xy 338.48167 -217.417904)
			(xy 338.456778 -217.421206) (xy 338.28482 -217.71864) (xy 338.294472 -217.742008) (xy 338.303035 -217.76372)
			(xy 338.315124 -217.8088) (xy 338.321246 -217.85507) (xy 338.32165 -217.878406) (xy 338.548218 -217.878406)
			(xy 338.548717 -217.851719) (xy 338.556672 -217.79894) (xy 338.572404 -217.747937) (xy 338.595562 -217.699848)
			(xy 338.625629 -217.655748) (xy 338.661933 -217.616621) (xy 338.703663 -217.583343) (xy 338.749887 -217.556656)
			(xy 338.799572 -217.537156) (xy 338.851609 -217.525279) (xy 338.904834 -217.52129) (xy 338.958059 -217.525279)
			(xy 339.010096 -217.537156) (xy 339.059781 -217.556656) (xy 339.106005 -217.583343) (xy 339.147735 -217.616621)
			(xy 339.184039 -217.655748) (xy 339.214106 -217.699848) (xy 339.237264 -217.747937) (xy 339.252996 -217.79894)
			(xy 339.260951 -217.851719) (xy 339.26145 -217.878406) (xy 339.488018 -217.878406) (xy 339.488472 -217.852738)
			(xy 339.495819 -217.801932) (xy 339.510375 -217.752704) (xy 339.531841 -217.706072) (xy 339.559772 -217.663001)
			(xy 339.593591 -217.62438) (xy 339.6326 -217.591008) (xy 339.67599 -217.563576) (xy 339.722866 -217.542649)
			(xy 339.772259 -217.528661) (xy 339.797644 -217.524838) (xy 339.822536 -217.521536) (xy 339.994494 -217.224102)
			(xy 339.984842 -217.200734) (xy 339.976262 -217.179028) (xy 339.964179 -217.133945) (xy 339.958064 -217.087673)
			(xy 339.957664 -217.064336) (xy 339.958163 -217.037649) (xy 339.966118 -216.98487) (xy 339.98185 -216.933867)
			(xy 340.005008 -216.885778) (xy 340.035075 -216.841678) (xy 340.071379 -216.802551) (xy 340.113109 -216.769273)
			(xy 340.159333 -216.742586) (xy 340.209018 -216.723086) (xy 340.261055 -216.711209) (xy 340.31428 -216.70722)
			(xy 340.367505 -216.711209) (xy 340.419542 -216.723086) (xy 340.469227 -216.742586) (xy 340.515451 -216.769273)
			(xy 340.557181 -216.802551) (xy 340.593485 -216.841678) (xy 340.623552 -216.885778) (xy 340.64671 -216.933867)
			(xy 340.662442 -216.98487) (xy 340.670397 -217.037649) (xy 340.670896 -217.064336) (xy 340.670377 -217.090002)
			(xy 340.663038 -217.140805) (xy 340.64849 -217.190031) (xy 340.627032 -217.236662) (xy 340.599108 -217.279733)
			(xy 340.565296 -217.318354) (xy 340.526295 -217.351726) (xy 340.482911 -217.379161) (xy 340.43604 -217.400089)
			(xy 340.386653 -217.41408) (xy 340.36127 -217.417904) (xy 340.336378 -217.421206) (xy 340.16442 -217.71864)
			(xy 340.174072 -217.742008) (xy 340.182635 -217.76372) (xy 340.194724 -217.8088) (xy 340.200846 -217.85507)
			(xy 340.20125 -217.878406) (xy 340.427818 -217.878406) (xy 340.428317 -217.851719) (xy 340.436272 -217.79894)
			(xy 340.452004 -217.747937) (xy 340.475162 -217.699848) (xy 340.505229 -217.655748) (xy 340.541533 -217.616621)
			(xy 340.583263 -217.583343) (xy 340.629487 -217.556656) (xy 340.679172 -217.537156) (xy 340.731209 -217.525279)
			(xy 340.784434 -217.52129) (xy 340.837659 -217.525279) (xy 340.889696 -217.537156) (xy 340.939381 -217.556656)
			(xy 340.985605 -217.583343) (xy 341.027335 -217.616621) (xy 341.063639 -217.655748) (xy 341.093706 -217.699848)
			(xy 341.116864 -217.747937) (xy 341.132596 -217.79894) (xy 341.140551 -217.851719) (xy 341.14105 -217.878406)
			(xy 341.367618 -217.878406) (xy 341.368072 -217.852738) (xy 341.375419 -217.801932) (xy 341.389975 -217.752704)
			(xy 341.411441 -217.706072) (xy 341.439372 -217.663001) (xy 341.473191 -217.62438) (xy 341.5122 -217.591008)
			(xy 341.55559 -217.563576) (xy 341.602466 -217.542649) (xy 341.651859 -217.528661) (xy 341.677244 -217.524838)
			(xy 341.702136 -217.521536) (xy 341.874094 -217.224102) (xy 341.864442 -217.200734) (xy 341.855862 -217.179028)
			(xy 341.843779 -217.133945) (xy 341.837664 -217.087673) (xy 341.837264 -217.064336) (xy 341.837763 -217.037649)
			(xy 341.845718 -216.98487) (xy 341.86145 -216.933867) (xy 341.884608 -216.885778) (xy 341.914675 -216.841678)
			(xy 341.950979 -216.802551) (xy 341.992709 -216.769273) (xy 342.038933 -216.742586) (xy 342.088618 -216.723086)
			(xy 342.140655 -216.711209) (xy 342.19388 -216.70722) (xy 342.247105 -216.711209) (xy 342.299142 -216.723086)
			(xy 342.348827 -216.742586) (xy 342.395051 -216.769273) (xy 342.436781 -216.802551) (xy 342.473085 -216.841678)
			(xy 342.503152 -216.885778) (xy 342.52631 -216.933867) (xy 342.542042 -216.98487) (xy 342.549997 -217.037649)
			(xy 342.550496 -217.064336) (xy 342.549977 -217.090002) (xy 342.542638 -217.140805) (xy 342.52809 -217.190031)
			(xy 342.506632 -217.236662) (xy 342.478708 -217.279733) (xy 342.444896 -217.318354) (xy 342.405895 -217.351726)
			(xy 342.362511 -217.379161) (xy 342.31564 -217.400089) (xy 342.266253 -217.41408) (xy 342.24087 -217.417904)
			(xy 342.215978 -217.421206) (xy 342.04402 -217.71864) (xy 342.053672 -217.742008) (xy 342.062235 -217.76372)
			(xy 342.074324 -217.8088) (xy 342.080446 -217.85507) (xy 342.08085 -217.878406) (xy 342.307418 -217.878406)
			(xy 342.307917 -217.851719) (xy 342.315872 -217.79894) (xy 342.331604 -217.747937) (xy 342.354762 -217.699848)
			(xy 342.384829 -217.655748) (xy 342.421133 -217.616621) (xy 342.462863 -217.583343) (xy 342.509087 -217.556656)
			(xy 342.558772 -217.537156) (xy 342.610809 -217.525279) (xy 342.664034 -217.52129) (xy 342.717259 -217.525279)
			(xy 342.769296 -217.537156) (xy 342.818981 -217.556656) (xy 342.865205 -217.583343) (xy 342.906935 -217.616621)
			(xy 342.943239 -217.655748) (xy 342.973306 -217.699848) (xy 342.996464 -217.747937) (xy 343.012196 -217.79894)
			(xy 343.020151 -217.851719) (xy 343.02065 -217.878406) (xy 343.247218 -217.878406) (xy 343.247672 -217.852738)
			(xy 343.255019 -217.801932) (xy 343.269575 -217.752704) (xy 343.291041 -217.706072) (xy 343.318972 -217.663001)
			(xy 343.352791 -217.62438) (xy 343.3918 -217.591008) (xy 343.43519 -217.563576) (xy 343.482066 -217.542649)
			(xy 343.531459 -217.528661) (xy 343.556844 -217.524838) (xy 343.581736 -217.521536) (xy 343.753694 -217.224102)
			(xy 343.744042 -217.200734) (xy 343.735462 -217.179028) (xy 343.723379 -217.133945) (xy 343.717264 -217.087673)
			(xy 343.716864 -217.064336) (xy 343.717363 -217.037649) (xy 343.725318 -216.98487) (xy 343.74105 -216.933867)
			(xy 343.764208 -216.885778) (xy 343.794275 -216.841678) (xy 343.830579 -216.802551) (xy 343.872309 -216.769273)
			(xy 343.918533 -216.742586) (xy 343.968218 -216.723086) (xy 344.020255 -216.711209) (xy 344.07348 -216.70722)
			(xy 344.126705 -216.711209) (xy 344.178742 -216.723086) (xy 344.228427 -216.742586) (xy 344.274651 -216.769273)
			(xy 344.316381 -216.802551) (xy 344.352685 -216.841678) (xy 344.382752 -216.885778) (xy 344.40591 -216.933867)
			(xy 344.421642 -216.98487) (xy 344.429597 -217.037649) (xy 344.430096 -217.064336) (xy 344.429577 -217.090002)
			(xy 344.422238 -217.140805) (xy 344.40769 -217.190031) (xy 344.386232 -217.236662) (xy 344.358308 -217.279733)
			(xy 344.324496 -217.318354) (xy 344.285495 -217.351726) (xy 344.242111 -217.379161) (xy 344.19524 -217.400089)
			(xy 344.145853 -217.41408) (xy 344.12047 -217.417904) (xy 344.095578 -217.421206) (xy 343.92362 -217.71864)
			(xy 343.933272 -217.742008) (xy 343.941835 -217.76372) (xy 343.953924 -217.8088) (xy 343.960046 -217.85507)
			(xy 343.96045 -217.878406) (xy 344.187018 -217.878406) (xy 344.187517 -217.851719) (xy 344.195472 -217.79894)
			(xy 344.211204 -217.747937) (xy 344.234362 -217.699848) (xy 344.264429 -217.655748) (xy 344.300733 -217.616621)
			(xy 344.342463 -217.583343) (xy 344.388687 -217.556656) (xy 344.438372 -217.537156) (xy 344.490409 -217.525279)
			(xy 344.543634 -217.52129) (xy 344.596859 -217.525279) (xy 344.648896 -217.537156) (xy 344.698581 -217.556656)
			(xy 344.744805 -217.583343) (xy 344.786535 -217.616621) (xy 344.822839 -217.655748) (xy 344.852906 -217.699848)
			(xy 344.876064 -217.747937) (xy 344.891796 -217.79894) (xy 344.899751 -217.851719) (xy 344.90025 -217.878406)
			(xy 345.126818 -217.878406) (xy 345.127272 -217.852738) (xy 345.134619 -217.801932) (xy 345.149175 -217.752704)
			(xy 345.170641 -217.706072) (xy 345.198572 -217.663001) (xy 345.232391 -217.62438) (xy 345.2714 -217.591008)
			(xy 345.31479 -217.563576) (xy 345.361666 -217.542649) (xy 345.411059 -217.528661) (xy 345.436444 -217.524838)
			(xy 345.461336 -217.521536) (xy 345.633294 -217.224102) (xy 345.623642 -217.200734) (xy 345.615062 -217.179028)
			(xy 345.602979 -217.133945) (xy 345.596864 -217.087673) (xy 345.596464 -217.064336) (xy 345.596963 -217.037649)
			(xy 345.604918 -216.98487) (xy 345.62065 -216.933867) (xy 345.643808 -216.885778) (xy 345.673875 -216.841678)
			(xy 345.710179 -216.802551) (xy 345.751909 -216.769273) (xy 345.798133 -216.742586) (xy 345.847818 -216.723086)
			(xy 345.899855 -216.711209) (xy 345.95308 -216.70722) (xy 346.006305 -216.711209) (xy 346.058342 -216.723086)
			(xy 346.108027 -216.742586) (xy 346.154251 -216.769273) (xy 346.195981 -216.802551) (xy 346.232285 -216.841678)
			(xy 346.262352 -216.885778) (xy 346.28551 -216.933867) (xy 346.301242 -216.98487) (xy 346.309197 -217.037649)
			(xy 346.309696 -217.064336) (xy 346.309177 -217.090002) (xy 346.301838 -217.140805) (xy 346.28729 -217.190031)
			(xy 346.265832 -217.236662) (xy 346.237908 -217.279733) (xy 346.204096 -217.318354) (xy 346.165095 -217.351726)
			(xy 346.121711 -217.379161) (xy 346.07484 -217.400089) (xy 346.025453 -217.41408) (xy 346.00007 -217.417904)
			(xy 345.975178 -217.421206) (xy 345.80322 -217.71864) (xy 345.812872 -217.742008) (xy 345.821435 -217.76372)
			(xy 345.833524 -217.8088) (xy 345.839646 -217.85507) (xy 345.84005 -217.878406) (xy 346.066618 -217.878406)
			(xy 346.067117 -217.851719) (xy 346.075072 -217.79894) (xy 346.090804 -217.747937) (xy 346.113962 -217.699848)
			(xy 346.144029 -217.655748) (xy 346.180333 -217.616621) (xy 346.222063 -217.583343) (xy 346.268287 -217.556656)
			(xy 346.317972 -217.537156) (xy 346.370009 -217.525279) (xy 346.423234 -217.52129) (xy 346.476459 -217.525279)
			(xy 346.528496 -217.537156) (xy 346.578181 -217.556656) (xy 346.624405 -217.583343) (xy 346.666135 -217.616621)
			(xy 346.702439 -217.655748) (xy 346.732506 -217.699848) (xy 346.755664 -217.747937) (xy 346.771396 -217.79894)
			(xy 346.779351 -217.851719) (xy 346.77985 -217.878406) (xy 347.006418 -217.878406) (xy 347.006872 -217.852738)
			(xy 347.014219 -217.801932) (xy 347.028775 -217.752704) (xy 347.050241 -217.706072) (xy 347.078172 -217.663001)
			(xy 347.111991 -217.62438) (xy 347.151 -217.591008) (xy 347.19439 -217.563576) (xy 347.241266 -217.542649)
			(xy 347.290659 -217.528661) (xy 347.316044 -217.524838) (xy 347.340936 -217.521536) (xy 347.512894 -217.224102)
			(xy 347.503242 -217.200734) (xy 347.494662 -217.179028) (xy 347.482579 -217.133945) (xy 347.476464 -217.087673)
			(xy 347.476064 -217.064336) (xy 347.476563 -217.037649) (xy 347.484518 -216.98487) (xy 347.50025 -216.933867)
			(xy 347.523408 -216.885778) (xy 347.553475 -216.841678) (xy 347.589779 -216.802551) (xy 347.631509 -216.769273)
			(xy 347.677733 -216.742586) (xy 347.727418 -216.723086) (xy 347.779455 -216.711209) (xy 347.83268 -216.70722)
			(xy 347.885905 -216.711209) (xy 347.937942 -216.723086) (xy 347.987627 -216.742586) (xy 348.033851 -216.769273)
			(xy 348.075581 -216.802551) (xy 348.111885 -216.841678) (xy 348.141952 -216.885778) (xy 348.16511 -216.933867)
			(xy 348.180842 -216.98487) (xy 348.188797 -217.037649) (xy 348.189296 -217.064336) (xy 348.188777 -217.090002)
			(xy 348.181438 -217.140805) (xy 348.16689 -217.190031) (xy 348.145432 -217.236662) (xy 348.117508 -217.279733)
			(xy 348.083696 -217.318354) (xy 348.044695 -217.351726) (xy 348.001311 -217.379161) (xy 347.95444 -217.400089)
			(xy 347.905053 -217.41408) (xy 347.87967 -217.417904) (xy 347.854778 -217.421206) (xy 347.68282 -217.71864)
			(xy 347.692472 -217.742008) (xy 347.701035 -217.76372) (xy 347.713124 -217.8088) (xy 347.719246 -217.85507)
			(xy 347.71965 -217.878406) (xy 347.946218 -217.878406) (xy 347.946717 -217.851719) (xy 347.954672 -217.79894)
			(xy 347.970404 -217.747937) (xy 347.993562 -217.699848) (xy 348.023629 -217.655748) (xy 348.059933 -217.616621)
			(xy 348.101663 -217.583343) (xy 348.147887 -217.556656) (xy 348.197572 -217.537156) (xy 348.249609 -217.525279)
			(xy 348.302834 -217.52129) (xy 348.356059 -217.525279) (xy 348.408096 -217.537156) (xy 348.457781 -217.556656)
			(xy 348.504005 -217.583343) (xy 348.545735 -217.616621) (xy 348.582039 -217.655748) (xy 348.612106 -217.699848)
			(xy 348.635264 -217.747937) (xy 348.650996 -217.79894) (xy 348.658951 -217.851719) (xy 348.65945 -217.878406)
			(xy 348.886018 -217.878406) (xy 348.886472 -217.852738) (xy 348.893819 -217.801932) (xy 348.908375 -217.752704)
			(xy 348.929841 -217.706072) (xy 348.957772 -217.663001) (xy 348.991591 -217.62438) (xy 349.0306 -217.591008)
			(xy 349.07399 -217.563576) (xy 349.120866 -217.542649) (xy 349.170259 -217.528661) (xy 349.195644 -217.524838)
			(xy 349.220536 -217.521536) (xy 349.392494 -217.224102) (xy 349.382842 -217.200734) (xy 349.374262 -217.179028)
			(xy 349.362179 -217.133945) (xy 349.356064 -217.087673) (xy 349.355664 -217.064336) (xy 349.356163 -217.037649)
			(xy 349.364118 -216.98487) (xy 349.37985 -216.933867) (xy 349.403008 -216.885778) (xy 349.433075 -216.841678)
			(xy 349.469379 -216.802551) (xy 349.511109 -216.769273) (xy 349.557333 -216.742586) (xy 349.607018 -216.723086)
			(xy 349.659055 -216.711209) (xy 349.71228 -216.70722) (xy 349.765505 -216.711209) (xy 349.817542 -216.723086)
			(xy 349.867227 -216.742586) (xy 349.913451 -216.769273) (xy 349.955181 -216.802551) (xy 349.991485 -216.841678)
			(xy 350.021552 -216.885778) (xy 350.04471 -216.933867) (xy 350.060442 -216.98487) (xy 350.068397 -217.037649)
			(xy 350.068896 -217.064336) (xy 350.068377 -217.090002) (xy 350.061038 -217.140805) (xy 350.04649 -217.190031)
			(xy 350.025032 -217.236662) (xy 349.997108 -217.279733) (xy 349.963296 -217.318354) (xy 349.924295 -217.351726)
			(xy 349.880911 -217.379161) (xy 349.83404 -217.400089) (xy 349.784653 -217.41408) (xy 349.75927 -217.417904)
			(xy 349.734378 -217.421206) (xy 349.56242 -217.71864) (xy 349.572072 -217.742008) (xy 349.580635 -217.76372)
			(xy 349.592724 -217.8088) (xy 349.598846 -217.85507) (xy 349.59925 -217.878406) (xy 349.825818 -217.878406)
			(xy 349.826317 -217.851719) (xy 349.834272 -217.79894) (xy 349.850004 -217.747937) (xy 349.873162 -217.699848)
			(xy 349.903229 -217.655748) (xy 349.939533 -217.616621) (xy 349.981263 -217.583343) (xy 350.027487 -217.556656)
			(xy 350.077172 -217.537156) (xy 350.129209 -217.525279) (xy 350.182434 -217.52129) (xy 350.235659 -217.525279)
			(xy 350.287696 -217.537156) (xy 350.337381 -217.556656) (xy 350.383605 -217.583343) (xy 350.425335 -217.616621)
			(xy 350.461639 -217.655748) (xy 350.491706 -217.699848) (xy 350.514864 -217.747937) (xy 350.530596 -217.79894)
			(xy 350.538551 -217.851719) (xy 350.53905 -217.878406) (xy 350.765618 -217.878406) (xy 350.766072 -217.852738)
			(xy 350.773419 -217.801932) (xy 350.787975 -217.752704) (xy 350.809441 -217.706072) (xy 350.837372 -217.663001)
			(xy 350.871191 -217.62438) (xy 350.9102 -217.591008) (xy 350.95359 -217.563576) (xy 351.000466 -217.542649)
			(xy 351.049859 -217.528661) (xy 351.075244 -217.524838) (xy 351.100136 -217.521536) (xy 351.272094 -217.224102)
			(xy 351.262442 -217.200734) (xy 351.253862 -217.179028) (xy 351.241779 -217.133945) (xy 351.235664 -217.087673)
			(xy 351.235264 -217.064336) (xy 351.235763 -217.037649) (xy 351.243718 -216.98487) (xy 351.25945 -216.933867)
			(xy 351.282608 -216.885778) (xy 351.312675 -216.841678) (xy 351.348979 -216.802551) (xy 351.390709 -216.769273)
			(xy 351.436933 -216.742586) (xy 351.486618 -216.723086) (xy 351.538655 -216.711209) (xy 351.59188 -216.70722)
			(xy 351.645105 -216.711209) (xy 351.697142 -216.723086) (xy 351.746827 -216.742586) (xy 351.793051 -216.769273)
			(xy 351.834781 -216.802551) (xy 351.871085 -216.841678) (xy 351.901152 -216.885778) (xy 351.92431 -216.933867)
			(xy 351.940042 -216.98487) (xy 351.947997 -217.037649) (xy 351.948496 -217.064336) (xy 351.947977 -217.090002)
			(xy 351.940638 -217.140805) (xy 351.92609 -217.190031) (xy 351.904632 -217.236662) (xy 351.876708 -217.279733)
			(xy 351.842896 -217.318354) (xy 351.803895 -217.351726) (xy 351.760511 -217.379161) (xy 351.71364 -217.400089)
			(xy 351.664253 -217.41408) (xy 351.63887 -217.417904) (xy 351.613978 -217.421206) (xy 351.44202 -217.71864)
			(xy 351.451672 -217.742008) (xy 351.460235 -217.76372) (xy 351.472324 -217.8088) (xy 351.478446 -217.85507)
			(xy 351.47885 -217.878406) (xy 351.705418 -217.878406) (xy 351.705917 -217.851719) (xy 351.713872 -217.79894)
			(xy 351.729604 -217.747937) (xy 351.752762 -217.699848) (xy 351.782829 -217.655748) (xy 351.819133 -217.616621)
			(xy 351.860863 -217.583343) (xy 351.907087 -217.556656) (xy 351.956772 -217.537156) (xy 352.008809 -217.525279)
			(xy 352.062034 -217.52129) (xy 352.115259 -217.525279) (xy 352.167296 -217.537156) (xy 352.216981 -217.556656)
			(xy 352.263205 -217.583343) (xy 352.304935 -217.616621) (xy 352.341239 -217.655748) (xy 352.371306 -217.699848)
			(xy 352.394464 -217.747937) (xy 352.410196 -217.79894) (xy 352.418151 -217.851719) (xy 352.41865 -217.878406)
			(xy 352.645218 -217.878406) (xy 352.645672 -217.852738) (xy 352.653019 -217.801932) (xy 352.667575 -217.752704)
			(xy 352.689041 -217.706072) (xy 352.716972 -217.663001) (xy 352.750791 -217.62438) (xy 352.7898 -217.591008)
			(xy 352.83319 -217.563576) (xy 352.880066 -217.542649) (xy 352.929459 -217.528661) (xy 352.954844 -217.524838)
			(xy 352.979736 -217.521536) (xy 353.151694 -217.224102) (xy 353.142042 -217.200734) (xy 353.133462 -217.179028)
			(xy 353.121379 -217.133945) (xy 353.115264 -217.087673) (xy 353.114864 -217.064336) (xy 353.115363 -217.037649)
			(xy 353.123318 -216.98487) (xy 353.13905 -216.933867) (xy 353.162208 -216.885778) (xy 353.192275 -216.841678)
			(xy 353.228579 -216.802551) (xy 353.270309 -216.769273) (xy 353.316533 -216.742586) (xy 353.366218 -216.723086)
			(xy 353.418255 -216.711209) (xy 353.47148 -216.70722) (xy 353.524705 -216.711209) (xy 353.576742 -216.723086)
			(xy 353.626427 -216.742586) (xy 353.672651 -216.769273) (xy 353.714381 -216.802551) (xy 353.750685 -216.841678)
			(xy 353.780752 -216.885778) (xy 353.80391 -216.933867) (xy 353.819642 -216.98487) (xy 353.827597 -217.037649)
			(xy 353.828096 -217.064336) (xy 353.827577 -217.090002) (xy 353.820238 -217.140805) (xy 353.80569 -217.190031)
			(xy 353.784232 -217.236662) (xy 353.756308 -217.279733) (xy 353.722496 -217.318354) (xy 353.683495 -217.351726)
			(xy 353.640111 -217.379161) (xy 353.59324 -217.400089) (xy 353.543853 -217.41408) (xy 353.51847 -217.417904)
			(xy 353.493578 -217.421206) (xy 353.32162 -217.71864) (xy 353.331272 -217.742008) (xy 353.339835 -217.76372)
			(xy 353.351924 -217.8088) (xy 353.358046 -217.85507) (xy 353.35845 -217.878406) (xy 353.585018 -217.878406)
			(xy 353.585517 -217.851719) (xy 353.593472 -217.79894) (xy 353.609204 -217.747937) (xy 353.632362 -217.699848)
			(xy 353.662429 -217.655748) (xy 353.698733 -217.616621) (xy 353.740463 -217.583343) (xy 353.786687 -217.556656)
			(xy 353.836372 -217.537156) (xy 353.888409 -217.525279) (xy 353.941634 -217.52129) (xy 353.994859 -217.525279)
			(xy 354.046896 -217.537156) (xy 354.096581 -217.556656) (xy 354.142805 -217.583343) (xy 354.184535 -217.616621)
			(xy 354.220839 -217.655748) (xy 354.250906 -217.699848) (xy 354.274064 -217.747937) (xy 354.289796 -217.79894)
			(xy 354.297751 -217.851719) (xy 354.29825 -217.878406) (xy 354.524818 -217.878406) (xy 354.525272 -217.852738)
			(xy 354.532619 -217.801932) (xy 354.547175 -217.752704) (xy 354.568641 -217.706072) (xy 354.596572 -217.663001)
			(xy 354.630391 -217.62438) (xy 354.6694 -217.591008) (xy 354.71279 -217.563576) (xy 354.759666 -217.542649)
			(xy 354.809059 -217.528661) (xy 354.834444 -217.524838) (xy 354.859336 -217.521536) (xy 355.031294 -217.224102)
			(xy 355.021642 -217.200734) (xy 355.013062 -217.179028) (xy 355.000979 -217.133945) (xy 354.994864 -217.087673)
			(xy 354.994464 -217.064336) (xy 354.994963 -217.037649) (xy 355.002918 -216.98487) (xy 355.01865 -216.933867)
			(xy 355.041808 -216.885778) (xy 355.071875 -216.841678) (xy 355.108179 -216.802551) (xy 355.149909 -216.769273)
			(xy 355.196133 -216.742586) (xy 355.245818 -216.723086) (xy 355.297855 -216.711209) (xy 355.35108 -216.70722)
			(xy 355.404305 -216.711209) (xy 355.456342 -216.723086) (xy 355.506027 -216.742586) (xy 355.552251 -216.769273)
			(xy 355.593981 -216.802551) (xy 355.630285 -216.841678) (xy 355.660352 -216.885778) (xy 355.68351 -216.933867)
			(xy 355.699242 -216.98487) (xy 355.707197 -217.037649) (xy 355.707696 -217.064336) (xy 355.707177 -217.090002)
			(xy 355.699838 -217.140805) (xy 355.68529 -217.190031) (xy 355.663832 -217.236662) (xy 355.635908 -217.279733)
			(xy 355.602096 -217.318354) (xy 355.563095 -217.351726) (xy 355.519711 -217.379161) (xy 355.47284 -217.400089)
			(xy 355.423453 -217.41408) (xy 355.39807 -217.417904) (xy 355.373178 -217.421206) (xy 355.20122 -217.71864)
			(xy 355.210872 -217.742008) (xy 355.219435 -217.76372) (xy 355.231524 -217.8088) (xy 355.237646 -217.85507)
			(xy 355.23805 -217.878406) (xy 355.464618 -217.878406) (xy 355.465117 -217.851719) (xy 355.473072 -217.79894)
			(xy 355.488804 -217.747937) (xy 355.511962 -217.699848) (xy 355.542029 -217.655748) (xy 355.578333 -217.616621)
			(xy 355.620063 -217.583343) (xy 355.666287 -217.556656) (xy 355.715972 -217.537156) (xy 355.768009 -217.525279)
			(xy 355.821234 -217.52129) (xy 355.874459 -217.525279) (xy 355.926496 -217.537156) (xy 355.976181 -217.556656)
			(xy 356.022405 -217.583343) (xy 356.064135 -217.616621) (xy 356.100439 -217.655748) (xy 356.130506 -217.699848)
			(xy 356.153664 -217.747937) (xy 356.169396 -217.79894) (xy 356.177351 -217.851719) (xy 356.17785 -217.878406)
			(xy 356.404418 -217.878406) (xy 356.404872 -217.852738) (xy 356.412219 -217.801932) (xy 356.426775 -217.752704)
			(xy 356.448241 -217.706072) (xy 356.476172 -217.663001) (xy 356.509991 -217.62438) (xy 356.549 -217.591008)
			(xy 356.59239 -217.563576) (xy 356.639266 -217.542649) (xy 356.688659 -217.528661) (xy 356.714044 -217.524838)
			(xy 356.738936 -217.521536) (xy 356.910894 -217.224102) (xy 356.901242 -217.200734) (xy 356.892662 -217.179028)
			(xy 356.880579 -217.133945) (xy 356.874464 -217.087673) (xy 356.874064 -217.064336) (xy 356.874563 -217.037649)
			(xy 356.882518 -216.98487) (xy 356.89825 -216.933867) (xy 356.921408 -216.885778) (xy 356.951475 -216.841678)
			(xy 356.987779 -216.802551) (xy 357.029509 -216.769273) (xy 357.075733 -216.742586) (xy 357.125418 -216.723086)
			(xy 357.177455 -216.711209) (xy 357.23068 -216.70722) (xy 357.283905 -216.711209) (xy 357.335942 -216.723086)
			(xy 357.385627 -216.742586) (xy 357.431851 -216.769273) (xy 357.473581 -216.802551) (xy 357.509885 -216.841678)
			(xy 357.539952 -216.885778) (xy 357.56311 -216.933867) (xy 357.578842 -216.98487) (xy 357.586797 -217.037649)
			(xy 357.587296 -217.064336) (xy 357.586777 -217.090002) (xy 357.579438 -217.140805) (xy 357.56489 -217.190031)
			(xy 357.543432 -217.236662) (xy 357.515508 -217.279733) (xy 357.481696 -217.318354) (xy 357.442695 -217.351726)
			(xy 357.399311 -217.379161) (xy 357.35244 -217.400089) (xy 357.303053 -217.41408) (xy 357.27767 -217.417904)
			(xy 357.252778 -217.421206) (xy 357.08082 -217.71864) (xy 357.090472 -217.742008) (xy 357.099035 -217.76372)
			(xy 357.111124 -217.8088) (xy 357.117246 -217.85507) (xy 357.11765 -217.878406) (xy 357.344218 -217.878406)
			(xy 357.344717 -217.851719) (xy 357.352672 -217.79894) (xy 357.368404 -217.747937) (xy 357.391562 -217.699848)
			(xy 357.421629 -217.655748) (xy 357.457933 -217.616621) (xy 357.499663 -217.583343) (xy 357.545887 -217.556656)
			(xy 357.595572 -217.537156) (xy 357.647609 -217.525279) (xy 357.700834 -217.52129) (xy 357.754059 -217.525279)
			(xy 357.806096 -217.537156) (xy 357.855781 -217.556656) (xy 357.902005 -217.583343) (xy 357.943735 -217.616621)
			(xy 357.980039 -217.655748) (xy 358.010106 -217.699848) (xy 358.033264 -217.747937) (xy 358.048996 -217.79894)
			(xy 358.056951 -217.851719) (xy 358.05745 -217.878406) (xy 358.284018 -217.878406) (xy 358.284472 -217.852738)
			(xy 358.291819 -217.801932) (xy 358.306375 -217.752704) (xy 358.327841 -217.706072) (xy 358.355772 -217.663001)
			(xy 358.389591 -217.62438) (xy 358.4286 -217.591008) (xy 358.47199 -217.563576) (xy 358.518866 -217.542649)
			(xy 358.568259 -217.528661) (xy 358.593644 -217.524838) (xy 358.618536 -217.521536) (xy 358.790494 -217.223594)
			(xy 358.780842 -217.20048) (xy 358.772347 -217.178885) (xy 358.760366 -217.134054) (xy 358.754308 -217.088046)
			(xy 358.753918 -217.064844) (xy 358.753918 -217.064336) (xy 358.754417 -217.037649) (xy 358.762372 -216.98487)
			(xy 358.778104 -216.933867) (xy 358.801262 -216.885778) (xy 358.831329 -216.841678) (xy 358.867633 -216.802551)
			(xy 358.909363 -216.769273) (xy 358.955587 -216.742586) (xy 359.005272 -216.723086) (xy 359.057309 -216.711209)
			(xy 359.110534 -216.70722) (xy 359.163759 -216.711209) (xy 359.215796 -216.723086) (xy 359.265481 -216.742586)
			(xy 359.311705 -216.769273) (xy 359.353435 -216.802551) (xy 359.389739 -216.841678) (xy 359.419806 -216.885778)
			(xy 359.442964 -216.933867) (xy 359.458696 -216.98487) (xy 359.466651 -217.037649) (xy 359.46715 -217.064336)
			(xy 360.633264 -217.064336) (xy 360.633763 -217.037649) (xy 360.641718 -216.98487) (xy 360.65745 -216.933867)
			(xy 360.680608 -216.885778) (xy 360.710675 -216.841678) (xy 360.746979 -216.802551) (xy 360.788709 -216.769273)
			(xy 360.834933 -216.742586) (xy 360.884618 -216.723086) (xy 360.936655 -216.711209) (xy 360.98988 -216.70722)
			(xy 361.043105 -216.711209) (xy 361.095142 -216.723086) (xy 361.144827 -216.742586) (xy 361.191051 -216.769273)
			(xy 361.232781 -216.802551) (xy 361.269085 -216.841678) (xy 361.299152 -216.885778) (xy 361.32231 -216.933867)
			(xy 361.338042 -216.98487) (xy 361.345997 -217.037649) (xy 361.346496 -217.064336) (xy 362.512864 -217.064336)
			(xy 362.513363 -217.037649) (xy 362.521318 -216.98487) (xy 362.53705 -216.933867) (xy 362.560208 -216.885778)
			(xy 362.590275 -216.841678) (xy 362.626579 -216.802551) (xy 362.668309 -216.769273) (xy 362.714533 -216.742586)
			(xy 362.764218 -216.723086) (xy 362.816255 -216.711209) (xy 362.86948 -216.70722) (xy 362.922705 -216.711209)
			(xy 362.974742 -216.723086) (xy 363.024427 -216.742586) (xy 363.070651 -216.769273) (xy 363.112381 -216.802551)
			(xy 363.148685 -216.841678) (xy 363.178752 -216.885778) (xy 363.20191 -216.933867) (xy 363.217642 -216.98487)
			(xy 363.225597 -217.037649) (xy 363.226096 -217.064336) (xy 364.392464 -217.064336) (xy 364.392963 -217.037649)
			(xy 364.400918 -216.98487) (xy 364.41665 -216.933867) (xy 364.439808 -216.885778) (xy 364.469875 -216.841678)
			(xy 364.506179 -216.802551) (xy 364.547909 -216.769273) (xy 364.594133 -216.742586) (xy 364.643818 -216.723086)
			(xy 364.695855 -216.711209) (xy 364.74908 -216.70722) (xy 364.802305 -216.711209) (xy 364.854342 -216.723086)
			(xy 364.904027 -216.742586) (xy 364.950251 -216.769273) (xy 364.991981 -216.802551) (xy 365.028285 -216.841678)
			(xy 365.058352 -216.885778) (xy 365.08151 -216.933867) (xy 365.097242 -216.98487) (xy 365.105197 -217.037649)
			(xy 365.105696 -217.064336) (xy 366.272064 -217.064336) (xy 366.272563 -217.037649) (xy 366.280518 -216.98487)
			(xy 366.29625 -216.933867) (xy 366.319408 -216.885778) (xy 366.349475 -216.841678) (xy 366.385779 -216.802551)
			(xy 366.427509 -216.769273) (xy 366.473733 -216.742586) (xy 366.523418 -216.723086) (xy 366.575455 -216.711209)
			(xy 366.62868 -216.70722) (xy 366.681905 -216.711209) (xy 366.733942 -216.723086) (xy 366.783627 -216.742586)
			(xy 366.829851 -216.769273) (xy 366.871581 -216.802551) (xy 366.907885 -216.841678) (xy 366.937952 -216.885778)
			(xy 366.96111 -216.933867) (xy 366.976842 -216.98487) (xy 366.984797 -217.037649) (xy 366.985296 -217.064336)
			(xy 368.151664 -217.064336) (xy 368.152163 -217.037649) (xy 368.160118 -216.98487) (xy 368.17585 -216.933867)
			(xy 368.199008 -216.885778) (xy 368.229075 -216.841678) (xy 368.265379 -216.802551) (xy 368.307109 -216.769273)
			(xy 368.353333 -216.742586) (xy 368.403018 -216.723086) (xy 368.455055 -216.711209) (xy 368.50828 -216.70722)
			(xy 368.561505 -216.711209) (xy 368.613542 -216.723086) (xy 368.663227 -216.742586) (xy 368.709451 -216.769273)
			(xy 368.751181 -216.802551) (xy 368.787485 -216.841678) (xy 368.817552 -216.885778) (xy 368.84071 -216.933867)
			(xy 368.856442 -216.98487) (xy 368.864397 -217.037649) (xy 368.864896 -217.064336) (xy 370.031264 -217.064336)
			(xy 370.031763 -217.037649) (xy 370.039718 -216.98487) (xy 370.05545 -216.933867) (xy 370.078608 -216.885778)
			(xy 370.108675 -216.841678) (xy 370.144979 -216.802551) (xy 370.186709 -216.769273) (xy 370.232933 -216.742586)
			(xy 370.282618 -216.723086) (xy 370.334655 -216.711209) (xy 370.38788 -216.70722) (xy 370.441105 -216.711209)
			(xy 370.493142 -216.723086) (xy 370.542827 -216.742586) (xy 370.589051 -216.769273) (xy 370.630781 -216.802551)
			(xy 370.667085 -216.841678) (xy 370.697152 -216.885778) (xy 370.72031 -216.933867) (xy 370.736042 -216.98487)
			(xy 370.743997 -217.037649) (xy 370.744496 -217.064336) (xy 371.910864 -217.064336) (xy 371.911363 -217.037649)
			(xy 371.919318 -216.98487) (xy 371.93505 -216.933867) (xy 371.958208 -216.885778) (xy 371.988275 -216.841678)
			(xy 372.024579 -216.802551) (xy 372.066309 -216.769273) (xy 372.112533 -216.742586) (xy 372.162218 -216.723086)
			(xy 372.214255 -216.711209) (xy 372.26748 -216.70722) (xy 372.320705 -216.711209) (xy 372.372742 -216.723086)
			(xy 372.422427 -216.742586) (xy 372.468651 -216.769273) (xy 372.510381 -216.802551) (xy 372.546685 -216.841678)
			(xy 372.576752 -216.885778) (xy 372.59991 -216.933867) (xy 372.615642 -216.98487) (xy 372.623597 -217.037649)
			(xy 372.624096 -217.064336) (xy 373.790464 -217.064336) (xy 373.790963 -217.037649) (xy 373.798918 -216.98487)
			(xy 373.81465 -216.933867) (xy 373.837808 -216.885778) (xy 373.867875 -216.841678) (xy 373.904179 -216.802551)
			(xy 373.945909 -216.769273) (xy 373.992133 -216.742586) (xy 374.041818 -216.723086) (xy 374.093855 -216.711209)
			(xy 374.14708 -216.70722) (xy 374.200305 -216.711209) (xy 374.252342 -216.723086) (xy 374.302027 -216.742586)
			(xy 374.348251 -216.769273) (xy 374.389981 -216.802551) (xy 374.426285 -216.841678) (xy 374.456352 -216.885778)
			(xy 374.47951 -216.933867) (xy 374.495242 -216.98487) (xy 374.503197 -217.037649) (xy 374.503696 -217.064336)
			(xy 375.670064 -217.064336) (xy 375.670563 -217.037649) (xy 375.678518 -216.98487) (xy 375.69425 -216.933867)
			(xy 375.717408 -216.885778) (xy 375.747475 -216.841678) (xy 375.783779 -216.802551) (xy 375.825509 -216.769273)
			(xy 375.871733 -216.742586) (xy 375.921418 -216.723086) (xy 375.973455 -216.711209) (xy 376.02668 -216.70722)
			(xy 376.079905 -216.711209) (xy 376.131942 -216.723086) (xy 376.181627 -216.742586) (xy 376.227851 -216.769273)
			(xy 376.269581 -216.802551) (xy 376.305885 -216.841678) (xy 376.335952 -216.885778) (xy 376.35911 -216.933867)
			(xy 376.374842 -216.98487) (xy 376.382797 -217.037649) (xy 376.383296 -217.064336) (xy 377.549664 -217.064336)
			(xy 377.550163 -217.037649) (xy 377.558118 -216.98487) (xy 377.57385 -216.933867) (xy 377.597008 -216.885778)
			(xy 377.627075 -216.841678) (xy 377.663379 -216.802551) (xy 377.705109 -216.769273) (xy 377.751333 -216.742586)
			(xy 377.801018 -216.723086) (xy 377.853055 -216.711209) (xy 377.90628 -216.70722) (xy 377.959505 -216.711209)
			(xy 378.011542 -216.723086) (xy 378.061227 -216.742586) (xy 378.107451 -216.769273) (xy 378.149181 -216.802551)
			(xy 378.185485 -216.841678) (xy 378.215552 -216.885778) (xy 378.23871 -216.933867) (xy 378.254442 -216.98487)
			(xy 378.262397 -217.037649) (xy 378.262896 -217.064336) (xy 379.429264 -217.064336) (xy 379.429763 -217.037649)
			(xy 379.437718 -216.98487) (xy 379.45345 -216.933867) (xy 379.476608 -216.885778) (xy 379.506675 -216.841678)
			(xy 379.542979 -216.802551) (xy 379.584709 -216.769273) (xy 379.630933 -216.742586) (xy 379.680618 -216.723086)
			(xy 379.732655 -216.711209) (xy 379.78588 -216.70722) (xy 379.839105 -216.711209) (xy 379.891142 -216.723086)
			(xy 379.940827 -216.742586) (xy 379.987051 -216.769273) (xy 380.028781 -216.802551) (xy 380.065085 -216.841678)
			(xy 380.095152 -216.885778) (xy 380.11831 -216.933867) (xy 380.134042 -216.98487) (xy 380.141997 -217.037649)
			(xy 380.142496 -217.064336) (xy 381.308864 -217.064336) (xy 381.309363 -217.037649) (xy 381.317318 -216.98487)
			(xy 381.33305 -216.933867) (xy 381.356208 -216.885778) (xy 381.386275 -216.841678) (xy 381.422579 -216.802551)
			(xy 381.464309 -216.769273) (xy 381.510533 -216.742586) (xy 381.560218 -216.723086) (xy 381.612255 -216.711209)
			(xy 381.66548 -216.70722) (xy 381.718705 -216.711209) (xy 381.770742 -216.723086) (xy 381.820427 -216.742586)
			(xy 381.866651 -216.769273) (xy 381.908381 -216.802551) (xy 381.944685 -216.841678) (xy 381.974752 -216.885778)
			(xy 381.99791 -216.933867) (xy 382.013642 -216.98487) (xy 382.021597 -217.037649) (xy 382.022096 -217.064336)
			(xy 382.022096 -217.064844) (xy 382.021691 -217.088045) (xy 382.015634 -217.134052) (xy 382.003667 -217.178886)
			(xy 381.995172 -217.20048) (xy 381.98552 -217.223594) (xy 382.157732 -217.521536) (xy 382.182624 -217.524838)
			(xy 382.207999 -217.528707) (xy 382.25738 -217.542708) (xy 382.304245 -217.563641) (xy 382.347626 -217.591074)
			(xy 382.386628 -217.624441) (xy 382.420445 -217.663053) (xy 382.44838 -217.706113) (xy 382.469855 -217.752732)
			(xy 382.484428 -217.801947) (xy 382.491797 -217.852742) (xy 382.49225 -217.878406) (xy 382.491751 -217.905093)
			(xy 382.483796 -217.957872) (xy 382.468064 -218.008875) (xy 382.444906 -218.056964) (xy 382.414839 -218.101064)
			(xy 382.378535 -218.140191) (xy 382.336805 -218.173469) (xy 382.290581 -218.200156) (xy 382.240896 -218.219656)
			(xy 382.188859 -218.231533) (xy 382.135634 -218.235522) (xy 382.082409 -218.231533) (xy 382.030372 -218.219656)
			(xy 381.980687 -218.200156) (xy 381.934463 -218.173469) (xy 381.892733 -218.140191) (xy 381.856429 -218.101064)
			(xy 381.826362 -218.056964) (xy 381.803204 -218.008875) (xy 381.787472 -217.957872) (xy 381.779517 -217.905093)
			(xy 381.779018 -217.878406) (xy 381.779374 -217.855066) (xy 381.785479 -217.808787) (xy 381.797586 -217.763705)
			(xy 381.806196 -217.742008) (xy 381.815848 -217.71864) (xy 381.644144 -217.421206) (xy 381.619252 -217.417904)
			(xy 381.593819 -217.414163) (xy 381.544328 -217.400257) (xy 381.497348 -217.379387) (xy 381.453853 -217.351987)
			(xy 381.414743 -217.318623) (xy 381.380831 -217.279989) (xy 381.352818 -217.236884) (xy 381.331287 -217.190204)
			(xy 381.316683 -217.140915) (xy 381.309309 -217.09004) (xy 381.308864 -217.064336) (xy 380.142496 -217.064336)
			(xy 380.142496 -217.064844) (xy 380.142091 -217.088045) (xy 380.136034 -217.134052) (xy 380.124067 -217.178886)
			(xy 380.115572 -217.20048) (xy 380.10592 -217.223594) (xy 380.278132 -217.521536) (xy 380.303024 -217.524838)
			(xy 380.328399 -217.528707) (xy 380.37778 -217.542708) (xy 380.424645 -217.563641) (xy 380.468026 -217.591074)
			(xy 380.507028 -217.624441) (xy 380.540845 -217.663053) (xy 380.56878 -217.706113) (xy 380.590255 -217.752732)
			(xy 380.604828 -217.801947) (xy 380.612197 -217.852742) (xy 380.61265 -217.878406) (xy 380.612151 -217.905093)
			(xy 380.604196 -217.957872) (xy 380.588464 -218.008875) (xy 380.565306 -218.056964) (xy 380.535239 -218.101064)
			(xy 380.498935 -218.140191) (xy 380.457205 -218.173469) (xy 380.410981 -218.200156) (xy 380.361296 -218.219656)
			(xy 380.309259 -218.231533) (xy 380.256034 -218.235522) (xy 380.202809 -218.231533) (xy 380.150772 -218.219656)
			(xy 380.101087 -218.200156) (xy 380.054863 -218.173469) (xy 380.013133 -218.140191) (xy 379.976829 -218.101064)
			(xy 379.946762 -218.056964) (xy 379.923604 -218.008875) (xy 379.907872 -217.957872) (xy 379.899917 -217.905093)
			(xy 379.899418 -217.878406) (xy 379.899774 -217.855066) (xy 379.905879 -217.808787) (xy 379.917986 -217.763705)
			(xy 379.926596 -217.742008) (xy 379.936248 -217.71864) (xy 379.764544 -217.421206) (xy 379.739652 -217.417904)
			(xy 379.714219 -217.414163) (xy 379.664728 -217.400257) (xy 379.617748 -217.379387) (xy 379.574253 -217.351987)
			(xy 379.535143 -217.318623) (xy 379.501231 -217.279989) (xy 379.473218 -217.236884) (xy 379.451687 -217.190204)
			(xy 379.437083 -217.140915) (xy 379.429709 -217.09004) (xy 379.429264 -217.064336) (xy 378.262896 -217.064336)
			(xy 378.262896 -217.064844) (xy 378.262491 -217.088045) (xy 378.256434 -217.134052) (xy 378.244467 -217.178886)
			(xy 378.235972 -217.20048) (xy 378.22632 -217.223594) (xy 378.398532 -217.521536) (xy 378.423424 -217.524838)
			(xy 378.448799 -217.528707) (xy 378.49818 -217.542708) (xy 378.545045 -217.563641) (xy 378.588426 -217.591074)
			(xy 378.627428 -217.624441) (xy 378.661245 -217.663053) (xy 378.68918 -217.706113) (xy 378.710655 -217.752732)
			(xy 378.725228 -217.801947) (xy 378.732597 -217.852742) (xy 378.73305 -217.878406) (xy 378.732551 -217.905093)
			(xy 378.724596 -217.957872) (xy 378.708864 -218.008875) (xy 378.685706 -218.056964) (xy 378.655639 -218.101064)
			(xy 378.619335 -218.140191) (xy 378.577605 -218.173469) (xy 378.531381 -218.200156) (xy 378.481696 -218.219656)
			(xy 378.429659 -218.231533) (xy 378.376434 -218.235522) (xy 378.323209 -218.231533) (xy 378.271172 -218.219656)
			(xy 378.221487 -218.200156) (xy 378.175263 -218.173469) (xy 378.133533 -218.140191) (xy 378.097229 -218.101064)
			(xy 378.067162 -218.056964) (xy 378.044004 -218.008875) (xy 378.028272 -217.957872) (xy 378.020317 -217.905093)
			(xy 378.019818 -217.878406) (xy 378.020174 -217.855066) (xy 378.026279 -217.808787) (xy 378.038386 -217.763705)
			(xy 378.046996 -217.742008) (xy 378.056648 -217.71864) (xy 377.884944 -217.421206) (xy 377.860052 -217.417904)
			(xy 377.834619 -217.414163) (xy 377.785128 -217.400257) (xy 377.738148 -217.379387) (xy 377.694653 -217.351987)
			(xy 377.655543 -217.318623) (xy 377.621631 -217.279989) (xy 377.593618 -217.236884) (xy 377.572087 -217.190204)
			(xy 377.557483 -217.140915) (xy 377.550109 -217.09004) (xy 377.549664 -217.064336) (xy 376.383296 -217.064336)
			(xy 376.383296 -217.064844) (xy 376.382891 -217.088045) (xy 376.376834 -217.134052) (xy 376.364867 -217.178886)
			(xy 376.356372 -217.20048) (xy 376.34672 -217.223594) (xy 376.518932 -217.521536) (xy 376.543824 -217.524838)
			(xy 376.569199 -217.528707) (xy 376.61858 -217.542708) (xy 376.665445 -217.563641) (xy 376.708826 -217.591074)
			(xy 376.747828 -217.624441) (xy 376.781645 -217.663053) (xy 376.80958 -217.706113) (xy 376.831055 -217.752732)
			(xy 376.845628 -217.801947) (xy 376.852997 -217.852742) (xy 376.85345 -217.878406) (xy 376.852951 -217.905093)
			(xy 376.844996 -217.957872) (xy 376.829264 -218.008875) (xy 376.806106 -218.056964) (xy 376.776039 -218.101064)
			(xy 376.739735 -218.140191) (xy 376.698005 -218.173469) (xy 376.651781 -218.200156) (xy 376.602096 -218.219656)
			(xy 376.550059 -218.231533) (xy 376.496834 -218.235522) (xy 376.443609 -218.231533) (xy 376.391572 -218.219656)
			(xy 376.341887 -218.200156) (xy 376.295663 -218.173469) (xy 376.253933 -218.140191) (xy 376.217629 -218.101064)
			(xy 376.187562 -218.056964) (xy 376.164404 -218.008875) (xy 376.148672 -217.957872) (xy 376.140717 -217.905093)
			(xy 376.140218 -217.878406) (xy 376.140574 -217.855066) (xy 376.146679 -217.808787) (xy 376.158786 -217.763705)
			(xy 376.167396 -217.742008) (xy 376.177048 -217.71864) (xy 376.005344 -217.421206) (xy 375.980452 -217.417904)
			(xy 375.955019 -217.414163) (xy 375.905528 -217.400257) (xy 375.858548 -217.379387) (xy 375.815053 -217.351987)
			(xy 375.775943 -217.318623) (xy 375.742031 -217.279989) (xy 375.714018 -217.236884) (xy 375.692487 -217.190204)
			(xy 375.677883 -217.140915) (xy 375.670509 -217.09004) (xy 375.670064 -217.064336) (xy 374.503696 -217.064336)
			(xy 374.503696 -217.064844) (xy 374.503291 -217.088045) (xy 374.497234 -217.134052) (xy 374.485267 -217.178886)
			(xy 374.476772 -217.20048) (xy 374.46712 -217.223594) (xy 374.639332 -217.521536) (xy 374.664224 -217.524838)
			(xy 374.689599 -217.528707) (xy 374.73898 -217.542708) (xy 374.785845 -217.563641) (xy 374.829226 -217.591074)
			(xy 374.868228 -217.624441) (xy 374.902045 -217.663053) (xy 374.92998 -217.706113) (xy 374.951455 -217.752732)
			(xy 374.966028 -217.801947) (xy 374.973397 -217.852742) (xy 374.97385 -217.878406) (xy 374.973351 -217.905093)
			(xy 374.965396 -217.957872) (xy 374.949664 -218.008875) (xy 374.926506 -218.056964) (xy 374.896439 -218.101064)
			(xy 374.860135 -218.140191) (xy 374.818405 -218.173469) (xy 374.772181 -218.200156) (xy 374.722496 -218.219656)
			(xy 374.670459 -218.231533) (xy 374.617234 -218.235522) (xy 374.564009 -218.231533) (xy 374.511972 -218.219656)
			(xy 374.462287 -218.200156) (xy 374.416063 -218.173469) (xy 374.374333 -218.140191) (xy 374.338029 -218.101064)
			(xy 374.307962 -218.056964) (xy 374.284804 -218.008875) (xy 374.269072 -217.957872) (xy 374.261117 -217.905093)
			(xy 374.260618 -217.878406) (xy 374.260974 -217.855066) (xy 374.267079 -217.808787) (xy 374.279186 -217.763705)
			(xy 374.287796 -217.742008) (xy 374.297448 -217.71864) (xy 374.125744 -217.421206) (xy 374.100852 -217.417904)
			(xy 374.075419 -217.414163) (xy 374.025928 -217.400257) (xy 373.978948 -217.379387) (xy 373.935453 -217.351987)
			(xy 373.896343 -217.318623) (xy 373.862431 -217.279989) (xy 373.834418 -217.236884) (xy 373.812887 -217.190204)
			(xy 373.798283 -217.140915) (xy 373.790909 -217.09004) (xy 373.790464 -217.064336) (xy 372.624096 -217.064336)
			(xy 372.624096 -217.064844) (xy 372.623691 -217.088045) (xy 372.617634 -217.134052) (xy 372.605667 -217.178886)
			(xy 372.597172 -217.20048) (xy 372.58752 -217.223594) (xy 372.759732 -217.521536) (xy 372.784624 -217.524838)
			(xy 372.809999 -217.528707) (xy 372.85938 -217.542708) (xy 372.906245 -217.563641) (xy 372.949626 -217.591074)
			(xy 372.988628 -217.624441) (xy 373.022445 -217.663053) (xy 373.05038 -217.706113) (xy 373.071855 -217.752732)
			(xy 373.086428 -217.801947) (xy 373.093797 -217.852742) (xy 373.09425 -217.878406) (xy 373.093751 -217.905093)
			(xy 373.085796 -217.957872) (xy 373.070064 -218.008875) (xy 373.046906 -218.056964) (xy 373.016839 -218.101064)
			(xy 372.980535 -218.140191) (xy 372.938805 -218.173469) (xy 372.892581 -218.200156) (xy 372.842896 -218.219656)
			(xy 372.790859 -218.231533) (xy 372.737634 -218.235522) (xy 372.684409 -218.231533) (xy 372.632372 -218.219656)
			(xy 372.582687 -218.200156) (xy 372.536463 -218.173469) (xy 372.494733 -218.140191) (xy 372.458429 -218.101064)
			(xy 372.428362 -218.056964) (xy 372.405204 -218.008875) (xy 372.389472 -217.957872) (xy 372.381517 -217.905093)
			(xy 372.381018 -217.878406) (xy 372.381374 -217.855066) (xy 372.387479 -217.808787) (xy 372.399586 -217.763705)
			(xy 372.408196 -217.742008) (xy 372.417848 -217.71864) (xy 372.246144 -217.421206) (xy 372.221252 -217.417904)
			(xy 372.195819 -217.414163) (xy 372.146328 -217.400257) (xy 372.099348 -217.379387) (xy 372.055853 -217.351987)
			(xy 372.016743 -217.318623) (xy 371.982831 -217.279989) (xy 371.954818 -217.236884) (xy 371.933287 -217.190204)
			(xy 371.918683 -217.140915) (xy 371.911309 -217.09004) (xy 371.910864 -217.064336) (xy 370.744496 -217.064336)
			(xy 370.744496 -217.064844) (xy 370.744091 -217.088045) (xy 370.738034 -217.134052) (xy 370.726067 -217.178886)
			(xy 370.717572 -217.20048) (xy 370.70792 -217.223594) (xy 370.880132 -217.521536) (xy 370.905024 -217.524838)
			(xy 370.930399 -217.528707) (xy 370.97978 -217.542708) (xy 371.026645 -217.563641) (xy 371.070026 -217.591074)
			(xy 371.109028 -217.624441) (xy 371.142845 -217.663053) (xy 371.17078 -217.706113) (xy 371.192255 -217.752732)
			(xy 371.206828 -217.801947) (xy 371.214197 -217.852742) (xy 371.21465 -217.878406) (xy 371.214151 -217.905093)
			(xy 371.206196 -217.957872) (xy 371.190464 -218.008875) (xy 371.167306 -218.056964) (xy 371.137239 -218.101064)
			(xy 371.100935 -218.140191) (xy 371.059205 -218.173469) (xy 371.012981 -218.200156) (xy 370.963296 -218.219656)
			(xy 370.911259 -218.231533) (xy 370.858034 -218.235522) (xy 370.804809 -218.231533) (xy 370.752772 -218.219656)
			(xy 370.703087 -218.200156) (xy 370.656863 -218.173469) (xy 370.615133 -218.140191) (xy 370.578829 -218.101064)
			(xy 370.548762 -218.056964) (xy 370.525604 -218.008875) (xy 370.509872 -217.957872) (xy 370.501917 -217.905093)
			(xy 370.501418 -217.878406) (xy 370.501774 -217.855066) (xy 370.507879 -217.808787) (xy 370.519986 -217.763705)
			(xy 370.528596 -217.742008) (xy 370.538248 -217.71864) (xy 370.366544 -217.421206) (xy 370.341652 -217.417904)
			(xy 370.316219 -217.414163) (xy 370.266728 -217.400257) (xy 370.219748 -217.379387) (xy 370.176253 -217.351987)
			(xy 370.137143 -217.318623) (xy 370.103231 -217.279989) (xy 370.075218 -217.236884) (xy 370.053687 -217.190204)
			(xy 370.039083 -217.140915) (xy 370.031709 -217.09004) (xy 370.031264 -217.064336) (xy 368.864896 -217.064336)
			(xy 368.864896 -217.064844) (xy 368.864491 -217.088045) (xy 368.858434 -217.134052) (xy 368.846467 -217.178886)
			(xy 368.837972 -217.20048) (xy 368.82832 -217.223594) (xy 369.000532 -217.521536) (xy 369.025424 -217.524838)
			(xy 369.050799 -217.528707) (xy 369.10018 -217.542708) (xy 369.147045 -217.563641) (xy 369.190426 -217.591074)
			(xy 369.229428 -217.624441) (xy 369.263245 -217.663053) (xy 369.29118 -217.706113) (xy 369.312655 -217.752732)
			(xy 369.327228 -217.801947) (xy 369.334597 -217.852742) (xy 369.33505 -217.878406) (xy 369.334551 -217.905093)
			(xy 369.326596 -217.957872) (xy 369.310864 -218.008875) (xy 369.287706 -218.056964) (xy 369.257639 -218.101064)
			(xy 369.221335 -218.140191) (xy 369.179605 -218.173469) (xy 369.133381 -218.200156) (xy 369.083696 -218.219656)
			(xy 369.031659 -218.231533) (xy 368.978434 -218.235522) (xy 368.925209 -218.231533) (xy 368.873172 -218.219656)
			(xy 368.823487 -218.200156) (xy 368.777263 -218.173469) (xy 368.735533 -218.140191) (xy 368.699229 -218.101064)
			(xy 368.669162 -218.056964) (xy 368.646004 -218.008875) (xy 368.630272 -217.957872) (xy 368.622317 -217.905093)
			(xy 368.621818 -217.878406) (xy 368.622174 -217.855066) (xy 368.628279 -217.808787) (xy 368.640386 -217.763705)
			(xy 368.648996 -217.742008) (xy 368.658648 -217.71864) (xy 368.486944 -217.421206) (xy 368.462052 -217.417904)
			(xy 368.436619 -217.414163) (xy 368.387128 -217.400257) (xy 368.340148 -217.379387) (xy 368.296653 -217.351987)
			(xy 368.257543 -217.318623) (xy 368.223631 -217.279989) (xy 368.195618 -217.236884) (xy 368.174087 -217.190204)
			(xy 368.159483 -217.140915) (xy 368.152109 -217.09004) (xy 368.151664 -217.064336) (xy 366.985296 -217.064336)
			(xy 366.985296 -217.064844) (xy 366.984891 -217.088045) (xy 366.978834 -217.134052) (xy 366.966867 -217.178886)
			(xy 366.958372 -217.20048) (xy 366.94872 -217.223594) (xy 367.120932 -217.521536) (xy 367.145824 -217.524838)
			(xy 367.171199 -217.528707) (xy 367.22058 -217.542708) (xy 367.267445 -217.563641) (xy 367.310826 -217.591074)
			(xy 367.349828 -217.624441) (xy 367.383645 -217.663053) (xy 367.41158 -217.706113) (xy 367.433055 -217.752732)
			(xy 367.447628 -217.801947) (xy 367.454997 -217.852742) (xy 367.45545 -217.878406) (xy 367.454951 -217.905093)
			(xy 367.446996 -217.957872) (xy 367.431264 -218.008875) (xy 367.408106 -218.056964) (xy 367.378039 -218.101064)
			(xy 367.341735 -218.140191) (xy 367.300005 -218.173469) (xy 367.253781 -218.200156) (xy 367.204096 -218.219656)
			(xy 367.152059 -218.231533) (xy 367.098834 -218.235522) (xy 367.045609 -218.231533) (xy 366.993572 -218.219656)
			(xy 366.943887 -218.200156) (xy 366.897663 -218.173469) (xy 366.855933 -218.140191) (xy 366.819629 -218.101064)
			(xy 366.789562 -218.056964) (xy 366.766404 -218.008875) (xy 366.750672 -217.957872) (xy 366.742717 -217.905093)
			(xy 366.742218 -217.878406) (xy 366.742574 -217.855066) (xy 366.748679 -217.808787) (xy 366.760786 -217.763705)
			(xy 366.769396 -217.742008) (xy 366.779048 -217.71864) (xy 366.607344 -217.421206) (xy 366.582452 -217.417904)
			(xy 366.557019 -217.414163) (xy 366.507528 -217.400257) (xy 366.460548 -217.379387) (xy 366.417053 -217.351987)
			(xy 366.377943 -217.318623) (xy 366.344031 -217.279989) (xy 366.316018 -217.236884) (xy 366.294487 -217.190204)
			(xy 366.279883 -217.140915) (xy 366.272509 -217.09004) (xy 366.272064 -217.064336) (xy 365.105696 -217.064336)
			(xy 365.105696 -217.064844) (xy 365.105291 -217.088045) (xy 365.099234 -217.134052) (xy 365.087267 -217.178886)
			(xy 365.078772 -217.20048) (xy 365.06912 -217.223594) (xy 365.241332 -217.521536) (xy 365.266224 -217.524838)
			(xy 365.291599 -217.528707) (xy 365.34098 -217.542708) (xy 365.387845 -217.563641) (xy 365.431226 -217.591074)
			(xy 365.470228 -217.624441) (xy 365.504045 -217.663053) (xy 365.53198 -217.706113) (xy 365.553455 -217.752732)
			(xy 365.568028 -217.801947) (xy 365.575397 -217.852742) (xy 365.57585 -217.878406) (xy 365.575351 -217.905093)
			(xy 365.567396 -217.957872) (xy 365.551664 -218.008875) (xy 365.528506 -218.056964) (xy 365.498439 -218.101064)
			(xy 365.462135 -218.140191) (xy 365.420405 -218.173469) (xy 365.374181 -218.200156) (xy 365.324496 -218.219656)
			(xy 365.272459 -218.231533) (xy 365.219234 -218.235522) (xy 365.166009 -218.231533) (xy 365.113972 -218.219656)
			(xy 365.064287 -218.200156) (xy 365.018063 -218.173469) (xy 364.976333 -218.140191) (xy 364.940029 -218.101064)
			(xy 364.909962 -218.056964) (xy 364.886804 -218.008875) (xy 364.871072 -217.957872) (xy 364.863117 -217.905093)
			(xy 364.862618 -217.878406) (xy 364.862974 -217.855066) (xy 364.869079 -217.808787) (xy 364.881186 -217.763705)
			(xy 364.889796 -217.742008) (xy 364.899448 -217.71864) (xy 364.727744 -217.421206) (xy 364.702852 -217.417904)
			(xy 364.677419 -217.414163) (xy 364.627928 -217.400257) (xy 364.580948 -217.379387) (xy 364.537453 -217.351987)
			(xy 364.498343 -217.318623) (xy 364.464431 -217.279989) (xy 364.436418 -217.236884) (xy 364.414887 -217.190204)
			(xy 364.400283 -217.140915) (xy 364.392909 -217.09004) (xy 364.392464 -217.064336) (xy 363.226096 -217.064336)
			(xy 363.226096 -217.064844) (xy 363.225691 -217.088045) (xy 363.219634 -217.134052) (xy 363.207667 -217.178886)
			(xy 363.199172 -217.20048) (xy 363.18952 -217.223594) (xy 363.361732 -217.521536) (xy 363.386624 -217.524838)
			(xy 363.411999 -217.528707) (xy 363.46138 -217.542708) (xy 363.508245 -217.563641) (xy 363.551626 -217.591074)
			(xy 363.590628 -217.624441) (xy 363.624445 -217.663053) (xy 363.65238 -217.706113) (xy 363.673855 -217.752732)
			(xy 363.688428 -217.801947) (xy 363.695797 -217.852742) (xy 363.69625 -217.878406) (xy 363.695751 -217.905093)
			(xy 363.687796 -217.957872) (xy 363.672064 -218.008875) (xy 363.648906 -218.056964) (xy 363.618839 -218.101064)
			(xy 363.582535 -218.140191) (xy 363.540805 -218.173469) (xy 363.494581 -218.200156) (xy 363.444896 -218.219656)
			(xy 363.392859 -218.231533) (xy 363.339634 -218.235522) (xy 363.286409 -218.231533) (xy 363.234372 -218.219656)
			(xy 363.184687 -218.200156) (xy 363.138463 -218.173469) (xy 363.096733 -218.140191) (xy 363.060429 -218.101064)
			(xy 363.030362 -218.056964) (xy 363.007204 -218.008875) (xy 362.991472 -217.957872) (xy 362.983517 -217.905093)
			(xy 362.983018 -217.878406) (xy 362.983374 -217.855066) (xy 362.989479 -217.808787) (xy 363.001586 -217.763705)
			(xy 363.010196 -217.742008) (xy 363.019848 -217.71864) (xy 362.848144 -217.421206) (xy 362.823252 -217.417904)
			(xy 362.797819 -217.414163) (xy 362.748328 -217.400257) (xy 362.701348 -217.379387) (xy 362.657853 -217.351987)
			(xy 362.618743 -217.318623) (xy 362.584831 -217.279989) (xy 362.556818 -217.236884) (xy 362.535287 -217.190204)
			(xy 362.520683 -217.140915) (xy 362.513309 -217.09004) (xy 362.512864 -217.064336) (xy 361.346496 -217.064336)
			(xy 361.346496 -217.064844) (xy 361.346091 -217.088045) (xy 361.340034 -217.134052) (xy 361.328067 -217.178886)
			(xy 361.319572 -217.20048) (xy 361.30992 -217.223594) (xy 361.482132 -217.521536) (xy 361.507024 -217.524838)
			(xy 361.532399 -217.528707) (xy 361.58178 -217.542708) (xy 361.628645 -217.563641) (xy 361.672026 -217.591074)
			(xy 361.711028 -217.624441) (xy 361.744845 -217.663053) (xy 361.77278 -217.706113) (xy 361.794255 -217.752732)
			(xy 361.808828 -217.801947) (xy 361.816197 -217.852742) (xy 361.81665 -217.878406) (xy 361.816151 -217.905093)
			(xy 361.808196 -217.957872) (xy 361.792464 -218.008875) (xy 361.769306 -218.056964) (xy 361.739239 -218.101064)
			(xy 361.702935 -218.140191) (xy 361.661205 -218.173469) (xy 361.614981 -218.200156) (xy 361.565296 -218.219656)
			(xy 361.513259 -218.231533) (xy 361.460034 -218.235522) (xy 361.406809 -218.231533) (xy 361.354772 -218.219656)
			(xy 361.305087 -218.200156) (xy 361.258863 -218.173469) (xy 361.217133 -218.140191) (xy 361.180829 -218.101064)
			(xy 361.150762 -218.056964) (xy 361.127604 -218.008875) (xy 361.111872 -217.957872) (xy 361.103917 -217.905093)
			(xy 361.103418 -217.878406) (xy 361.103774 -217.855066) (xy 361.109879 -217.808787) (xy 361.121986 -217.763705)
			(xy 361.130596 -217.742008) (xy 361.140248 -217.71864) (xy 360.968544 -217.421206) (xy 360.943652 -217.417904)
			(xy 360.918219 -217.414163) (xy 360.868728 -217.400257) (xy 360.821748 -217.379387) (xy 360.778253 -217.351987)
			(xy 360.739143 -217.318623) (xy 360.705231 -217.279989) (xy 360.677218 -217.236884) (xy 360.655687 -217.190204)
			(xy 360.641083 -217.140915) (xy 360.633709 -217.09004) (xy 360.633264 -217.064336) (xy 359.46715 -217.064336)
			(xy 359.466728 -217.090016) (xy 359.459369 -217.140847) (xy 359.444792 -217.190095) (xy 359.4233 -217.236743)
			(xy 359.395338 -217.279824) (xy 359.361485 -217.318448) (xy 359.32244 -217.351815) (xy 359.279011 -217.379235)
			(xy 359.232098 -217.400141) (xy 359.182671 -217.414099) (xy 359.15727 -217.417904) (xy 359.132378 -217.421206)
			(xy 358.96042 -217.71864) (xy 358.970072 -217.742008) (xy 358.978635 -217.76372) (xy 358.990724 -217.8088)
			(xy 358.996846 -217.85507) (xy 358.99725 -217.878406) (xy 358.996751 -217.905093) (xy 358.988796 -217.957872)
			(xy 358.973064 -218.008875) (xy 358.949906 -218.056964) (xy 358.919839 -218.101064) (xy 358.883535 -218.140191)
			(xy 358.841805 -218.173469) (xy 358.795581 -218.200156) (xy 358.745896 -218.219656) (xy 358.693859 -218.231533)
			(xy 358.640634 -218.235522) (xy 358.587409 -218.231533) (xy 358.535372 -218.219656) (xy 358.485687 -218.200156)
			(xy 358.439463 -218.173469) (xy 358.397733 -218.140191) (xy 358.361429 -218.101064) (xy 358.331362 -218.056964)
			(xy 358.308204 -218.008875) (xy 358.292472 -217.957872) (xy 358.284517 -217.905093) (xy 358.284018 -217.878406)
			(xy 358.05745 -217.878406) (xy 358.05745 -217.878914) (xy 358.057063 -217.902116) (xy 358.050998 -217.948123)
			(xy 358.039024 -217.992956) (xy 358.030526 -218.01455) (xy 358.020874 -218.037664) (xy 358.192832 -218.335352)
			(xy 358.217724 -218.338654) (xy 358.243102 -218.342508) (xy 358.292484 -218.356509) (xy 358.33935 -218.377443)
			(xy 358.382732 -218.404878) (xy 358.421734 -218.438247) (xy 358.455551 -218.476861) (xy 358.483485 -218.519923)
			(xy 358.50496 -218.566543) (xy 358.519531 -218.61576) (xy 358.526898 -218.666558) (xy 358.52735 -218.692222)
			(xy 359.693464 -218.692222) (xy 359.693893 -218.666553) (xy 359.701238 -218.615743) (xy 359.715795 -218.566512)
			(xy 359.737263 -218.519878) (xy 359.765196 -218.476805) (xy 359.799019 -218.438184) (xy 359.838031 -218.404813)
			(xy 359.881426 -218.377382) (xy 359.928306 -218.356458) (xy 359.977703 -218.342474) (xy 360.00309 -218.338654)
			(xy 360.027982 -218.335352) (xy 360.200194 -218.037664) (xy 360.190542 -218.01455) (xy 360.182038 -217.992958)
			(xy 360.17006 -217.948125) (xy 360.164006 -217.902117) (xy 360.163618 -217.878914) (xy 360.163618 -217.878406)
			(xy 360.164117 -217.851719) (xy 360.172072 -217.79894) (xy 360.187804 -217.747937) (xy 360.210962 -217.699848)
			(xy 360.241029 -217.655748) (xy 360.277333 -217.616621) (xy 360.319063 -217.583343) (xy 360.365287 -217.556656)
			(xy 360.414972 -217.537156) (xy 360.467009 -217.525279) (xy 360.520234 -217.52129) (xy 360.573459 -217.525279)
			(xy 360.625496 -217.537156) (xy 360.675181 -217.556656) (xy 360.721405 -217.583343) (xy 360.763135 -217.616621)
			(xy 360.799439 -217.655748) (xy 360.829506 -217.699848) (xy 360.852664 -217.747937) (xy 360.868396 -217.79894)
			(xy 360.876351 -217.851719) (xy 360.87685 -217.878406) (xy 360.876397 -217.904117) (xy 360.868996 -217.955005)
			(xy 360.854364 -218.004303) (xy 360.832804 -218.050988) (xy 360.804763 -218.094092) (xy 360.770822 -218.132723)
			(xy 360.731685 -218.166079) (xy 360.688163 -218.193468) (xy 360.641159 -218.214323) (xy 360.591647 -218.228211)
			(xy 360.566208 -218.231974) (xy 360.541316 -218.235276) (xy 360.369866 -218.532456) (xy 360.379518 -218.55557)
			(xy 360.388102 -218.577274) (xy 360.400183 -218.622359) (xy 360.406297 -218.668631) (xy 360.406696 -218.691968)
			(xy 360.406696 -218.692222) (xy 361.573318 -218.692222) (xy 361.573787 -218.666555) (xy 361.581131 -218.615749)
			(xy 361.595686 -218.566521) (xy 361.61715 -218.519889) (xy 361.645079 -218.476818) (xy 361.678897 -218.438197)
			(xy 361.717903 -218.404825) (xy 361.761293 -218.377392) (xy 361.808168 -218.356465) (xy 361.857559 -218.342477)
			(xy 361.882944 -218.338654) (xy 361.907836 -218.335352) (xy 362.079794 -218.037664) (xy 362.070142 -218.01455)
			(xy 362.061638 -217.992958) (xy 362.04966 -217.948125) (xy 362.043606 -217.902117) (xy 362.043218 -217.878914)
			(xy 362.043218 -217.878406) (xy 362.043717 -217.851719) (xy 362.051672 -217.79894) (xy 362.067404 -217.747937)
			(xy 362.090562 -217.699848) (xy 362.120629 -217.655748) (xy 362.156933 -217.616621) (xy 362.198663 -217.583343)
			(xy 362.244887 -217.556656) (xy 362.294572 -217.537156) (xy 362.346609 -217.525279) (xy 362.399834 -217.52129)
			(xy 362.453059 -217.525279) (xy 362.505096 -217.537156) (xy 362.554781 -217.556656) (xy 362.601005 -217.583343)
			(xy 362.642735 -217.616621) (xy 362.679039 -217.655748) (xy 362.709106 -217.699848) (xy 362.732264 -217.747937)
			(xy 362.747996 -217.79894) (xy 362.755951 -217.851719) (xy 362.75645 -217.878406) (xy 362.755972 -217.904094)
			(xy 362.748599 -217.954939) (xy 362.734005 -218.0042) (xy 362.712494 -218.050856) (xy 362.68451 -218.093943)
			(xy 362.650633 -218.132568) (xy 362.611564 -218.165932) (xy 362.568112 -218.193344) (xy 362.521175 -218.214237)
			(xy 362.471726 -218.228179) (xy 362.446316 -218.231974) (xy 362.421424 -218.235276) (xy 362.24972 -218.532456)
			(xy 362.259372 -218.555824) (xy 362.26794 -218.577534) (xy 362.280027 -218.622615) (xy 362.286147 -218.668886)
			(xy 362.28655 -218.692222) (xy 363.452664 -218.692222) (xy 363.453093 -218.666553) (xy 363.460438 -218.615743)
			(xy 363.474995 -218.566512) (xy 363.496463 -218.519878) (xy 363.524396 -218.476805) (xy 363.558219 -218.438184)
			(xy 363.597231 -218.404813) (xy 363.640626 -218.377382) (xy 363.687506 -218.356458) (xy 363.736903 -218.342474)
			(xy 363.76229 -218.338654) (xy 363.787182 -218.335352) (xy 363.959394 -218.037664) (xy 363.949742 -218.01455)
			(xy 363.941238 -217.992958) (xy 363.92926 -217.948125) (xy 363.923206 -217.902117) (xy 363.922818 -217.878914)
			(xy 363.922818 -217.878406) (xy 363.923317 -217.851719) (xy 363.931272 -217.79894) (xy 363.947004 -217.747937)
			(xy 363.970162 -217.699848) (xy 364.000229 -217.655748) (xy 364.036533 -217.616621) (xy 364.078263 -217.583343)
			(xy 364.124487 -217.556656) (xy 364.174172 -217.537156) (xy 364.226209 -217.525279) (xy 364.279434 -217.52129)
			(xy 364.332659 -217.525279) (xy 364.384696 -217.537156) (xy 364.434381 -217.556656) (xy 364.480605 -217.583343)
			(xy 364.522335 -217.616621) (xy 364.558639 -217.655748) (xy 364.588706 -217.699848) (xy 364.611864 -217.747937)
			(xy 364.627596 -217.79894) (xy 364.635551 -217.851719) (xy 364.63605 -217.878406) (xy 364.635597 -217.904117)
			(xy 364.628196 -217.955005) (xy 364.613564 -218.004303) (xy 364.592004 -218.050988) (xy 364.563963 -218.094092)
			(xy 364.530022 -218.132723) (xy 364.490885 -218.166079) (xy 364.447363 -218.193468) (xy 364.400359 -218.214323)
			(xy 364.350847 -218.228211) (xy 364.325408 -218.231974) (xy 364.300516 -218.235276) (xy 364.129066 -218.532456)
			(xy 364.138718 -218.55557) (xy 364.147302 -218.577274) (xy 364.159383 -218.622359) (xy 364.165497 -218.668631)
			(xy 364.165896 -218.691968) (xy 364.165896 -218.692222) (xy 365.332264 -218.692222) (xy 365.332693 -218.666553)
			(xy 365.340038 -218.615743) (xy 365.354595 -218.566512) (xy 365.376063 -218.519878) (xy 365.403996 -218.476805)
			(xy 365.437819 -218.438184) (xy 365.476831 -218.404813) (xy 365.520226 -218.377382) (xy 365.567106 -218.356458)
			(xy 365.616503 -218.342474) (xy 365.64189 -218.338654) (xy 365.666782 -218.335352) (xy 365.838994 -218.037664)
			(xy 365.829342 -218.01455) (xy 365.820838 -217.992958) (xy 365.80886 -217.948125) (xy 365.802806 -217.902117)
			(xy 365.802418 -217.878914) (xy 365.802418 -217.878406) (xy 365.802917 -217.851719) (xy 365.810872 -217.79894)
			(xy 365.826604 -217.747937) (xy 365.849762 -217.699848) (xy 365.879829 -217.655748) (xy 365.916133 -217.616621)
			(xy 365.957863 -217.583343) (xy 366.004087 -217.556656) (xy 366.053772 -217.537156) (xy 366.105809 -217.525279)
			(xy 366.159034 -217.52129) (xy 366.212259 -217.525279) (xy 366.264296 -217.537156) (xy 366.313981 -217.556656)
			(xy 366.360205 -217.583343) (xy 366.401935 -217.616621) (xy 366.438239 -217.655748) (xy 366.468306 -217.699848)
			(xy 366.491464 -217.747937) (xy 366.507196 -217.79894) (xy 366.515151 -217.851719) (xy 366.51565 -217.878406)
			(xy 366.515197 -217.904117) (xy 366.507796 -217.955005) (xy 366.493164 -218.004303) (xy 366.471604 -218.050988)
			(xy 366.443563 -218.094092) (xy 366.409622 -218.132723) (xy 366.370485 -218.166079) (xy 366.326963 -218.193468)
			(xy 366.279959 -218.214323) (xy 366.230447 -218.228211) (xy 366.205008 -218.231974) (xy 366.180116 -218.235276)
			(xy 366.008666 -218.532456) (xy 366.018318 -218.55557) (xy 366.026902 -218.577274) (xy 366.038983 -218.622359)
			(xy 366.045097 -218.668631) (xy 366.045496 -218.691968) (xy 366.045496 -218.692222) (xy 367.211864 -218.692222)
			(xy 367.212293 -218.666553) (xy 367.219638 -218.615743) (xy 367.234195 -218.566512) (xy 367.255663 -218.519878)
			(xy 367.283596 -218.476805) (xy 367.317419 -218.438184) (xy 367.356431 -218.404813) (xy 367.399826 -218.377382)
			(xy 367.446706 -218.356458) (xy 367.496103 -218.342474) (xy 367.52149 -218.338654) (xy 367.546382 -218.335352)
			(xy 367.718594 -218.037664) (xy 367.708942 -218.01455) (xy 367.700438 -217.992958) (xy 367.68846 -217.948125)
			(xy 367.682406 -217.902117) (xy 367.682018 -217.878914) (xy 367.682018 -217.878406) (xy 367.682517 -217.851719)
			(xy 367.690472 -217.79894) (xy 367.706204 -217.747937) (xy 367.729362 -217.699848) (xy 367.759429 -217.655748)
			(xy 367.795733 -217.616621) (xy 367.837463 -217.583343) (xy 367.883687 -217.556656) (xy 367.933372 -217.537156)
			(xy 367.985409 -217.525279) (xy 368.038634 -217.52129) (xy 368.091859 -217.525279) (xy 368.143896 -217.537156)
			(xy 368.193581 -217.556656) (xy 368.239805 -217.583343) (xy 368.281535 -217.616621) (xy 368.317839 -217.655748)
			(xy 368.347906 -217.699848) (xy 368.371064 -217.747937) (xy 368.386796 -217.79894) (xy 368.394751 -217.851719)
			(xy 368.39525 -217.878406) (xy 368.394797 -217.904117) (xy 368.387396 -217.955005) (xy 368.372764 -218.004303)
			(xy 368.351204 -218.050988) (xy 368.323163 -218.094092) (xy 368.289222 -218.132723) (xy 368.250085 -218.166079)
			(xy 368.206563 -218.193468) (xy 368.159559 -218.214323) (xy 368.110047 -218.228211) (xy 368.084608 -218.231974)
			(xy 368.059716 -218.235276) (xy 367.888266 -218.532456) (xy 367.897918 -218.55557) (xy 367.906502 -218.577274)
			(xy 367.918583 -218.622359) (xy 367.924697 -218.668631) (xy 367.925096 -218.691968) (xy 367.925096 -218.692222)
			(xy 369.091464 -218.692222) (xy 369.091893 -218.666553) (xy 369.099238 -218.615743) (xy 369.113795 -218.566512)
			(xy 369.135263 -218.519878) (xy 369.163196 -218.476805) (xy 369.197019 -218.438184) (xy 369.236031 -218.404813)
			(xy 369.279426 -218.377382) (xy 369.326306 -218.356458) (xy 369.375703 -218.342474) (xy 369.40109 -218.338654)
			(xy 369.425982 -218.335352) (xy 369.598194 -218.037664) (xy 369.588542 -218.01455) (xy 369.580038 -217.992958)
			(xy 369.56806 -217.948125) (xy 369.562006 -217.902117) (xy 369.561618 -217.878914) (xy 369.561618 -217.878406)
			(xy 369.562117 -217.851719) (xy 369.570072 -217.79894) (xy 369.585804 -217.747937) (xy 369.608962 -217.699848)
			(xy 369.639029 -217.655748) (xy 369.675333 -217.616621) (xy 369.717063 -217.583343) (xy 369.763287 -217.556656)
			(xy 369.812972 -217.537156) (xy 369.865009 -217.525279) (xy 369.918234 -217.52129) (xy 369.971459 -217.525279)
			(xy 370.023496 -217.537156) (xy 370.073181 -217.556656) (xy 370.119405 -217.583343) (xy 370.161135 -217.616621)
			(xy 370.197439 -217.655748) (xy 370.227506 -217.699848) (xy 370.250664 -217.747937) (xy 370.266396 -217.79894)
			(xy 370.274351 -217.851719) (xy 370.27485 -217.878406) (xy 370.274397 -217.904117) (xy 370.266996 -217.955005)
			(xy 370.252364 -218.004303) (xy 370.230804 -218.050988) (xy 370.202763 -218.094092) (xy 370.168822 -218.132723)
			(xy 370.129685 -218.166079) (xy 370.086163 -218.193468) (xy 370.039159 -218.214323) (xy 369.989647 -218.228211)
			(xy 369.964208 -218.231974) (xy 369.939316 -218.235276) (xy 369.767866 -218.532456) (xy 369.777518 -218.55557)
			(xy 369.786102 -218.577274) (xy 369.798183 -218.622359) (xy 369.804297 -218.668631) (xy 369.804696 -218.691968)
			(xy 369.804696 -218.692222) (xy 370.971064 -218.692222) (xy 370.971493 -218.666553) (xy 370.978838 -218.615743)
			(xy 370.993395 -218.566512) (xy 371.014863 -218.519878) (xy 371.042796 -218.476805) (xy 371.076619 -218.438184)
			(xy 371.115631 -218.404813) (xy 371.159026 -218.377382) (xy 371.205906 -218.356458) (xy 371.255303 -218.342474)
			(xy 371.28069 -218.338654) (xy 371.305582 -218.335352) (xy 371.477794 -218.037664) (xy 371.468142 -218.01455)
			(xy 371.459638 -217.992958) (xy 371.44766 -217.948125) (xy 371.441606 -217.902117) (xy 371.441218 -217.878914)
			(xy 371.441218 -217.878406) (xy 371.441717 -217.851719) (xy 371.449672 -217.79894) (xy 371.465404 -217.747937)
			(xy 371.488562 -217.699848) (xy 371.518629 -217.655748) (xy 371.554933 -217.616621) (xy 371.596663 -217.583343)
			(xy 371.642887 -217.556656) (xy 371.692572 -217.537156) (xy 371.744609 -217.525279) (xy 371.797834 -217.52129)
			(xy 371.851059 -217.525279) (xy 371.903096 -217.537156) (xy 371.952781 -217.556656) (xy 371.999005 -217.583343)
			(xy 372.040735 -217.616621) (xy 372.077039 -217.655748) (xy 372.107106 -217.699848) (xy 372.130264 -217.747937)
			(xy 372.145996 -217.79894) (xy 372.153951 -217.851719) (xy 372.15445 -217.878406) (xy 372.153997 -217.904117)
			(xy 372.146596 -217.955005) (xy 372.131964 -218.004303) (xy 372.110404 -218.050988) (xy 372.082363 -218.094092)
			(xy 372.048422 -218.132723) (xy 372.009285 -218.166079) (xy 371.965763 -218.193468) (xy 371.918759 -218.214323)
			(xy 371.869247 -218.228211) (xy 371.843808 -218.231974) (xy 371.818916 -218.235276) (xy 371.647466 -218.532456)
			(xy 371.657118 -218.55557) (xy 371.665702 -218.577274) (xy 371.677783 -218.622359) (xy 371.683897 -218.668631)
			(xy 371.684296 -218.691968) (xy 371.684296 -218.692222) (xy 372.850664 -218.692222) (xy 372.851093 -218.666553)
			(xy 372.858438 -218.615743) (xy 372.872995 -218.566512) (xy 372.894463 -218.519878) (xy 372.922396 -218.476805)
			(xy 372.956219 -218.438184) (xy 372.995231 -218.404813) (xy 373.038626 -218.377382) (xy 373.085506 -218.356458)
			(xy 373.134903 -218.342474) (xy 373.16029 -218.338654) (xy 373.185182 -218.335352) (xy 373.357394 -218.037664)
			(xy 373.347742 -218.01455) (xy 373.339238 -217.992958) (xy 373.32726 -217.948125) (xy 373.321206 -217.902117)
			(xy 373.320818 -217.878914) (xy 373.320818 -217.878406) (xy 373.321317 -217.851719) (xy 373.329272 -217.79894)
			(xy 373.345004 -217.747937) (xy 373.368162 -217.699848) (xy 373.398229 -217.655748) (xy 373.434533 -217.616621)
			(xy 373.476263 -217.583343) (xy 373.522487 -217.556656) (xy 373.572172 -217.537156) (xy 373.624209 -217.525279)
			(xy 373.677434 -217.52129) (xy 373.730659 -217.525279) (xy 373.782696 -217.537156) (xy 373.832381 -217.556656)
			(xy 373.878605 -217.583343) (xy 373.920335 -217.616621) (xy 373.956639 -217.655748) (xy 373.986706 -217.699848)
			(xy 374.009864 -217.747937) (xy 374.025596 -217.79894) (xy 374.033551 -217.851719) (xy 374.03405 -217.878406)
			(xy 374.033597 -217.904117) (xy 374.026196 -217.955005) (xy 374.011564 -218.004303) (xy 373.990004 -218.050988)
			(xy 373.961963 -218.094092) (xy 373.928022 -218.132723) (xy 373.888885 -218.166079) (xy 373.845363 -218.193468)
			(xy 373.798359 -218.214323) (xy 373.748847 -218.228211) (xy 373.723408 -218.231974) (xy 373.698516 -218.235276)
			(xy 373.527066 -218.532456) (xy 373.536718 -218.55557) (xy 373.545302 -218.577274) (xy 373.557383 -218.622359)
			(xy 373.563497 -218.668631) (xy 373.563896 -218.691968) (xy 373.563896 -218.692222) (xy 374.730264 -218.692222)
			(xy 374.730693 -218.666553) (xy 374.738038 -218.615743) (xy 374.752595 -218.566512) (xy 374.774063 -218.519878)
			(xy 374.801996 -218.476805) (xy 374.835819 -218.438184) (xy 374.874831 -218.404813) (xy 374.918226 -218.377382)
			(xy 374.965106 -218.356458) (xy 375.014503 -218.342474) (xy 375.03989 -218.338654) (xy 375.064782 -218.335352)
			(xy 375.236994 -218.037664) (xy 375.227342 -218.01455) (xy 375.218838 -217.992958) (xy 375.20686 -217.948125)
			(xy 375.200806 -217.902117) (xy 375.200418 -217.878914) (xy 375.200418 -217.878406) (xy 375.200917 -217.851719)
			(xy 375.208872 -217.79894) (xy 375.224604 -217.747937) (xy 375.247762 -217.699848) (xy 375.277829 -217.655748)
			(xy 375.314133 -217.616621) (xy 375.355863 -217.583343) (xy 375.402087 -217.556656) (xy 375.451772 -217.537156)
			(xy 375.503809 -217.525279) (xy 375.557034 -217.52129) (xy 375.610259 -217.525279) (xy 375.662296 -217.537156)
			(xy 375.711981 -217.556656) (xy 375.758205 -217.583343) (xy 375.799935 -217.616621) (xy 375.836239 -217.655748)
			(xy 375.866306 -217.699848) (xy 375.889464 -217.747937) (xy 375.905196 -217.79894) (xy 375.913151 -217.851719)
			(xy 375.91365 -217.878406) (xy 375.913197 -217.904117) (xy 375.905796 -217.955005) (xy 375.891164 -218.004303)
			(xy 375.869604 -218.050988) (xy 375.841563 -218.094092) (xy 375.807622 -218.132723) (xy 375.768485 -218.166079)
			(xy 375.724963 -218.193468) (xy 375.677959 -218.214323) (xy 375.628447 -218.228211) (xy 375.603008 -218.231974)
			(xy 375.578116 -218.235276) (xy 375.406666 -218.532456) (xy 375.416318 -218.55557) (xy 375.424902 -218.577274)
			(xy 375.436983 -218.622359) (xy 375.443097 -218.668631) (xy 375.443496 -218.691968) (xy 375.443496 -218.692222)
			(xy 376.609864 -218.692222) (xy 376.610293 -218.666553) (xy 376.617638 -218.615743) (xy 376.632195 -218.566512)
			(xy 376.653663 -218.519878) (xy 376.681596 -218.476805) (xy 376.715419 -218.438184) (xy 376.754431 -218.404813)
			(xy 376.797826 -218.377382) (xy 376.844706 -218.356458) (xy 376.894103 -218.342474) (xy 376.91949 -218.338654)
			(xy 376.944382 -218.335352) (xy 377.116594 -218.037664) (xy 377.106942 -218.01455) (xy 377.098438 -217.992958)
			(xy 377.08646 -217.948125) (xy 377.080406 -217.902117) (xy 377.080018 -217.878914) (xy 377.080018 -217.878406)
			(xy 377.080517 -217.851719) (xy 377.088472 -217.79894) (xy 377.104204 -217.747937) (xy 377.127362 -217.699848)
			(xy 377.157429 -217.655748) (xy 377.193733 -217.616621) (xy 377.235463 -217.583343) (xy 377.281687 -217.556656)
			(xy 377.331372 -217.537156) (xy 377.383409 -217.525279) (xy 377.436634 -217.52129) (xy 377.489859 -217.525279)
			(xy 377.541896 -217.537156) (xy 377.591581 -217.556656) (xy 377.637805 -217.583343) (xy 377.679535 -217.616621)
			(xy 377.715839 -217.655748) (xy 377.745906 -217.699848) (xy 377.769064 -217.747937) (xy 377.784796 -217.79894)
			(xy 377.792751 -217.851719) (xy 377.79325 -217.878406) (xy 377.792797 -217.904117) (xy 377.785396 -217.955005)
			(xy 377.770764 -218.004303) (xy 377.749204 -218.050988) (xy 377.721163 -218.094092) (xy 377.687222 -218.132723)
			(xy 377.648085 -218.166079) (xy 377.604563 -218.193468) (xy 377.557559 -218.214323) (xy 377.508047 -218.228211)
			(xy 377.482608 -218.231974) (xy 377.457716 -218.235276) (xy 377.286266 -218.532456) (xy 377.295918 -218.55557)
			(xy 377.304502 -218.577274) (xy 377.316583 -218.622359) (xy 377.322697 -218.668631) (xy 377.323096 -218.691968)
			(xy 377.323096 -218.692222) (xy 378.489464 -218.692222) (xy 378.489893 -218.666553) (xy 378.497238 -218.615743)
			(xy 378.511795 -218.566512) (xy 378.533263 -218.519878) (xy 378.561196 -218.476805) (xy 378.595019 -218.438184)
			(xy 378.634031 -218.404813) (xy 378.677426 -218.377382) (xy 378.724306 -218.356458) (xy 378.773703 -218.342474)
			(xy 378.79909 -218.338654) (xy 378.823982 -218.335352) (xy 378.996194 -218.037664) (xy 378.986542 -218.01455)
			(xy 378.978038 -217.992958) (xy 378.96606 -217.948125) (xy 378.960006 -217.902117) (xy 378.959618 -217.878914)
			(xy 378.959618 -217.878406) (xy 378.960117 -217.851719) (xy 378.968072 -217.79894) (xy 378.983804 -217.747937)
			(xy 379.006962 -217.699848) (xy 379.037029 -217.655748) (xy 379.073333 -217.616621) (xy 379.115063 -217.583343)
			(xy 379.161287 -217.556656) (xy 379.210972 -217.537156) (xy 379.263009 -217.525279) (xy 379.316234 -217.52129)
			(xy 379.369459 -217.525279) (xy 379.421496 -217.537156) (xy 379.471181 -217.556656) (xy 379.517405 -217.583343)
			(xy 379.559135 -217.616621) (xy 379.595439 -217.655748) (xy 379.625506 -217.699848) (xy 379.648664 -217.747937)
			(xy 379.664396 -217.79894) (xy 379.672351 -217.851719) (xy 379.67285 -217.878406) (xy 379.672397 -217.904117)
			(xy 379.664996 -217.955005) (xy 379.650364 -218.004303) (xy 379.628804 -218.050988) (xy 379.600763 -218.094092)
			(xy 379.566822 -218.132723) (xy 379.527685 -218.166079) (xy 379.484163 -218.193468) (xy 379.437159 -218.214323)
			(xy 379.387647 -218.228211) (xy 379.362208 -218.231974) (xy 379.337316 -218.235276) (xy 379.165866 -218.532456)
			(xy 379.175518 -218.55557) (xy 379.184102 -218.577274) (xy 379.196183 -218.622359) (xy 379.202297 -218.668631)
			(xy 379.202696 -218.691968) (xy 379.202696 -218.692222) (xy 380.369064 -218.692222) (xy 380.369493 -218.666553)
			(xy 380.376838 -218.615743) (xy 380.391395 -218.566512) (xy 380.412863 -218.519878) (xy 380.440796 -218.476805)
			(xy 380.474619 -218.438184) (xy 380.513631 -218.404813) (xy 380.557026 -218.377382) (xy 380.603906 -218.356458)
			(xy 380.653303 -218.342474) (xy 380.67869 -218.338654) (xy 380.703582 -218.335352) (xy 380.875794 -218.037664)
			(xy 380.866142 -218.01455) (xy 380.857638 -217.992958) (xy 380.84566 -217.948125) (xy 380.839606 -217.902117)
			(xy 380.839218 -217.878914) (xy 380.839218 -217.878406) (xy 380.839717 -217.851719) (xy 380.847672 -217.79894)
			(xy 380.863404 -217.747937) (xy 380.886562 -217.699848) (xy 380.916629 -217.655748) (xy 380.952933 -217.616621)
			(xy 380.994663 -217.583343) (xy 381.040887 -217.556656) (xy 381.090572 -217.537156) (xy 381.142609 -217.525279)
			(xy 381.195834 -217.52129) (xy 381.249059 -217.525279) (xy 381.301096 -217.537156) (xy 381.350781 -217.556656)
			(xy 381.397005 -217.583343) (xy 381.438735 -217.616621) (xy 381.475039 -217.655748) (xy 381.505106 -217.699848)
			(xy 381.528264 -217.747937) (xy 381.543996 -217.79894) (xy 381.551951 -217.851719) (xy 381.55245 -217.878406)
			(xy 381.551997 -217.904117) (xy 381.544596 -217.955005) (xy 381.529964 -218.004303) (xy 381.508404 -218.050988)
			(xy 381.480363 -218.094092) (xy 381.446422 -218.132723) (xy 381.407285 -218.166079) (xy 381.363763 -218.193468)
			(xy 381.316759 -218.214323) (xy 381.267247 -218.228211) (xy 381.241808 -218.231974) (xy 381.216916 -218.235276)
			(xy 381.045466 -218.532456) (xy 381.055118 -218.55557) (xy 381.063702 -218.577274) (xy 381.075783 -218.622359)
			(xy 381.081897 -218.668631) (xy 381.082296 -218.691968) (xy 381.082296 -218.692222) (xy 381.081797 -218.718909)
			(xy 381.073842 -218.771688) (xy 381.05811 -218.822691) (xy 381.034952 -218.87078) (xy 381.004885 -218.91488)
			(xy 380.968581 -218.954007) (xy 380.926851 -218.987285) (xy 380.880627 -219.013972) (xy 380.830942 -219.033472)
			(xy 380.778905 -219.045349) (xy 380.72568 -219.049338) (xy 380.672455 -219.045349) (xy 380.620418 -219.033472)
			(xy 380.570733 -219.013972) (xy 380.524509 -218.987285) (xy 380.482779 -218.954007) (xy 380.446475 -218.91488)
			(xy 380.416408 -218.87078) (xy 380.39325 -218.822691) (xy 380.377518 -218.771688) (xy 380.369563 -218.718909)
			(xy 380.369064 -218.692222) (xy 379.202696 -218.692222) (xy 379.202197 -218.718909) (xy 379.194242 -218.771688)
			(xy 379.17851 -218.822691) (xy 379.155352 -218.87078) (xy 379.125285 -218.91488) (xy 379.088981 -218.954007)
			(xy 379.047251 -218.987285) (xy 379.001027 -219.013972) (xy 378.951342 -219.033472) (xy 378.899305 -219.045349)
			(xy 378.84608 -219.049338) (xy 378.792855 -219.045349) (xy 378.740818 -219.033472) (xy 378.691133 -219.013972)
			(xy 378.644909 -218.987285) (xy 378.603179 -218.954007) (xy 378.566875 -218.91488) (xy 378.536808 -218.87078)
			(xy 378.51365 -218.822691) (xy 378.497918 -218.771688) (xy 378.489963 -218.718909) (xy 378.489464 -218.692222)
			(xy 377.323096 -218.692222) (xy 377.322597 -218.718909) (xy 377.314642 -218.771688) (xy 377.29891 -218.822691)
			(xy 377.275752 -218.87078) (xy 377.245685 -218.91488) (xy 377.209381 -218.954007) (xy 377.167651 -218.987285)
			(xy 377.121427 -219.013972) (xy 377.071742 -219.033472) (xy 377.019705 -219.045349) (xy 376.96648 -219.049338)
			(xy 376.913255 -219.045349) (xy 376.861218 -219.033472) (xy 376.811533 -219.013972) (xy 376.765309 -218.987285)
			(xy 376.723579 -218.954007) (xy 376.687275 -218.91488) (xy 376.657208 -218.87078) (xy 376.63405 -218.822691)
			(xy 376.618318 -218.771688) (xy 376.610363 -218.718909) (xy 376.609864 -218.692222) (xy 375.443496 -218.692222)
			(xy 375.442997 -218.718909) (xy 375.435042 -218.771688) (xy 375.41931 -218.822691) (xy 375.396152 -218.87078)
			(xy 375.366085 -218.91488) (xy 375.329781 -218.954007) (xy 375.288051 -218.987285) (xy 375.241827 -219.013972)
			(xy 375.192142 -219.033472) (xy 375.140105 -219.045349) (xy 375.08688 -219.049338) (xy 375.033655 -219.045349)
			(xy 374.981618 -219.033472) (xy 374.931933 -219.013972) (xy 374.885709 -218.987285) (xy 374.843979 -218.954007)
			(xy 374.807675 -218.91488) (xy 374.777608 -218.87078) (xy 374.75445 -218.822691) (xy 374.738718 -218.771688)
			(xy 374.730763 -218.718909) (xy 374.730264 -218.692222) (xy 373.563896 -218.692222) (xy 373.563397 -218.718909)
			(xy 373.555442 -218.771688) (xy 373.53971 -218.822691) (xy 373.516552 -218.87078) (xy 373.486485 -218.91488)
			(xy 373.450181 -218.954007) (xy 373.408451 -218.987285) (xy 373.362227 -219.013972) (xy 373.312542 -219.033472)
			(xy 373.260505 -219.045349) (xy 373.20728 -219.049338) (xy 373.154055 -219.045349) (xy 373.102018 -219.033472)
			(xy 373.052333 -219.013972) (xy 373.006109 -218.987285) (xy 372.964379 -218.954007) (xy 372.928075 -218.91488)
			(xy 372.898008 -218.87078) (xy 372.87485 -218.822691) (xy 372.859118 -218.771688) (xy 372.851163 -218.718909)
			(xy 372.850664 -218.692222) (xy 371.684296 -218.692222) (xy 371.683797 -218.718909) (xy 371.675842 -218.771688)
			(xy 371.66011 -218.822691) (xy 371.636952 -218.87078) (xy 371.606885 -218.91488) (xy 371.570581 -218.954007)
			(xy 371.528851 -218.987285) (xy 371.482627 -219.013972) (xy 371.432942 -219.033472) (xy 371.380905 -219.045349)
			(xy 371.32768 -219.049338) (xy 371.274455 -219.045349) (xy 371.222418 -219.033472) (xy 371.172733 -219.013972)
			(xy 371.126509 -218.987285) (xy 371.084779 -218.954007) (xy 371.048475 -218.91488) (xy 371.018408 -218.87078)
			(xy 370.99525 -218.822691) (xy 370.979518 -218.771688) (xy 370.971563 -218.718909) (xy 370.971064 -218.692222)
			(xy 369.804696 -218.692222) (xy 369.804197 -218.718909) (xy 369.796242 -218.771688) (xy 369.78051 -218.822691)
			(xy 369.757352 -218.87078) (xy 369.727285 -218.91488) (xy 369.690981 -218.954007) (xy 369.649251 -218.987285)
			(xy 369.603027 -219.013972) (xy 369.553342 -219.033472) (xy 369.501305 -219.045349) (xy 369.44808 -219.049338)
			(xy 369.394855 -219.045349) (xy 369.342818 -219.033472) (xy 369.293133 -219.013972) (xy 369.246909 -218.987285)
			(xy 369.205179 -218.954007) (xy 369.168875 -218.91488) (xy 369.138808 -218.87078) (xy 369.11565 -218.822691)
			(xy 369.099918 -218.771688) (xy 369.091963 -218.718909) (xy 369.091464 -218.692222) (xy 367.925096 -218.692222)
			(xy 367.924597 -218.718909) (xy 367.916642 -218.771688) (xy 367.90091 -218.822691) (xy 367.877752 -218.87078)
			(xy 367.847685 -218.91488) (xy 367.811381 -218.954007) (xy 367.769651 -218.987285) (xy 367.723427 -219.013972)
			(xy 367.673742 -219.033472) (xy 367.621705 -219.045349) (xy 367.56848 -219.049338) (xy 367.515255 -219.045349)
			(xy 367.463218 -219.033472) (xy 367.413533 -219.013972) (xy 367.367309 -218.987285) (xy 367.325579 -218.954007)
			(xy 367.289275 -218.91488) (xy 367.259208 -218.87078) (xy 367.23605 -218.822691) (xy 367.220318 -218.771688)
			(xy 367.212363 -218.718909) (xy 367.211864 -218.692222) (xy 366.045496 -218.692222) (xy 366.044997 -218.718909)
			(xy 366.037042 -218.771688) (xy 366.02131 -218.822691) (xy 365.998152 -218.87078) (xy 365.968085 -218.91488)
			(xy 365.931781 -218.954007) (xy 365.890051 -218.987285) (xy 365.843827 -219.013972) (xy 365.794142 -219.033472)
			(xy 365.742105 -219.045349) (xy 365.68888 -219.049338) (xy 365.635655 -219.045349) (xy 365.583618 -219.033472)
			(xy 365.533933 -219.013972) (xy 365.487709 -218.987285) (xy 365.445979 -218.954007) (xy 365.409675 -218.91488)
			(xy 365.379608 -218.87078) (xy 365.35645 -218.822691) (xy 365.340718 -218.771688) (xy 365.332763 -218.718909)
			(xy 365.332264 -218.692222) (xy 364.165896 -218.692222) (xy 364.165397 -218.718909) (xy 364.157442 -218.771688)
			(xy 364.14171 -218.822691) (xy 364.118552 -218.87078) (xy 364.088485 -218.91488) (xy 364.052181 -218.954007)
			(xy 364.010451 -218.987285) (xy 363.964227 -219.013972) (xy 363.914542 -219.033472) (xy 363.862505 -219.045349)
			(xy 363.80928 -219.049338) (xy 363.756055 -219.045349) (xy 363.704018 -219.033472) (xy 363.654333 -219.013972)
			(xy 363.608109 -218.987285) (xy 363.566379 -218.954007) (xy 363.530075 -218.91488) (xy 363.500008 -218.87078)
			(xy 363.47685 -218.822691) (xy 363.461118 -218.771688) (xy 363.453163 -218.718909) (xy 363.452664 -218.692222)
			(xy 362.28655 -218.692222) (xy 362.286051 -218.718909) (xy 362.278096 -218.771688) (xy 362.262364 -218.822691)
			(xy 362.239206 -218.87078) (xy 362.209139 -218.91488) (xy 362.172835 -218.954007) (xy 362.131105 -218.987285)
			(xy 362.084881 -219.013972) (xy 362.035196 -219.033472) (xy 361.983159 -219.045349) (xy 361.929934 -219.049338)
			(xy 361.876709 -219.045349) (xy 361.824672 -219.033472) (xy 361.774987 -219.013972) (xy 361.728763 -218.987285)
			(xy 361.687033 -218.954007) (xy 361.650729 -218.91488) (xy 361.620662 -218.87078) (xy 361.597504 -218.822691)
			(xy 361.581772 -218.771688) (xy 361.573817 -218.718909) (xy 361.573318 -218.692222) (xy 360.406696 -218.692222)
			(xy 360.406197 -218.718909) (xy 360.398242 -218.771688) (xy 360.38251 -218.822691) (xy 360.359352 -218.87078)
			(xy 360.329285 -218.91488) (xy 360.292981 -218.954007) (xy 360.251251 -218.987285) (xy 360.205027 -219.013972)
			(xy 360.155342 -219.033472) (xy 360.103305 -219.045349) (xy 360.05008 -219.049338) (xy 359.996855 -219.045349)
			(xy 359.944818 -219.033472) (xy 359.895133 -219.013972) (xy 359.848909 -218.987285) (xy 359.807179 -218.954007)
			(xy 359.770875 -218.91488) (xy 359.740808 -218.87078) (xy 359.71765 -218.822691) (xy 359.701918 -218.771688)
			(xy 359.693963 -218.718909) (xy 359.693464 -218.692222) (xy 358.52735 -218.692222) (xy 358.526851 -218.718909)
			(xy 358.518896 -218.771688) (xy 358.503164 -218.822691) (xy 358.480006 -218.87078) (xy 358.449939 -218.91488)
			(xy 358.413635 -218.954007) (xy 358.371905 -218.987285) (xy 358.325681 -219.013972) (xy 358.275996 -219.033472)
			(xy 358.223959 -219.045349) (xy 358.170734 -219.049338) (xy 358.117509 -219.045349) (xy 358.065472 -219.033472)
			(xy 358.015787 -219.013972) (xy 357.969563 -218.987285) (xy 357.927833 -218.954007) (xy 357.891529 -218.91488)
			(xy 357.861462 -218.87078) (xy 357.838304 -218.822691) (xy 357.822572 -218.771688) (xy 357.814617 -218.718909)
			(xy 357.814118 -218.692222) (xy 357.814479 -218.668882) (xy 357.820582 -218.622604) (xy 357.832687 -218.577521)
			(xy 357.841296 -218.555824) (xy 357.850948 -218.532456) (xy 357.67899 -218.235276) (xy 357.654098 -218.231974)
			(xy 357.628697 -218.228185) (xy 357.579277 -218.214213) (xy 357.532372 -218.193298) (xy 357.488951 -218.165872)
			(xy 357.449912 -218.132502) (xy 357.416064 -218.093878) (xy 357.388104 -218.050799) (xy 357.366612 -218.004155)
			(xy 357.352032 -217.954911) (xy 357.344666 -217.904085) (xy 357.344218 -217.878406) (xy 357.11765 -217.878406)
			(xy 357.117151 -217.905093) (xy 357.109196 -217.957872) (xy 357.093464 -218.008875) (xy 357.070306 -218.056964)
			(xy 357.040239 -218.101064) (xy 357.003935 -218.140191) (xy 356.962205 -218.173469) (xy 356.915981 -218.200156)
			(xy 356.866296 -218.219656) (xy 356.814259 -218.231533) (xy 356.761034 -218.235522) (xy 356.707809 -218.231533)
			(xy 356.655772 -218.219656) (xy 356.606087 -218.200156) (xy 356.559863 -218.173469) (xy 356.518133 -218.140191)
			(xy 356.481829 -218.101064) (xy 356.451762 -218.056964) (xy 356.428604 -218.008875) (xy 356.412872 -217.957872)
			(xy 356.404917 -217.905093) (xy 356.404418 -217.878406) (xy 356.17785 -217.878406) (xy 356.177468 -217.901745)
			(xy 356.171374 -217.948023) (xy 356.159278 -217.993106) (xy 356.150672 -218.014804) (xy 356.14102 -218.038172)
			(xy 356.312978 -218.335352) (xy 356.33787 -218.338654) (xy 356.363241 -218.34255) (xy 356.412623 -218.356544)
			(xy 356.459489 -218.377472) (xy 356.502871 -218.404901) (xy 356.541875 -218.438265) (xy 356.575693 -218.476874)
			(xy 356.603629 -218.519932) (xy 356.625104 -218.56655) (xy 356.639677 -218.615764) (xy 356.647044 -218.666559)
			(xy 356.647496 -218.692222) (xy 356.646997 -218.718909) (xy 356.639042 -218.771688) (xy 356.62331 -218.822691)
			(xy 356.600152 -218.87078) (xy 356.570085 -218.91488) (xy 356.533781 -218.954007) (xy 356.492051 -218.987285)
			(xy 356.445827 -219.013972) (xy 356.396142 -219.033472) (xy 356.344105 -219.045349) (xy 356.29088 -219.049338)
			(xy 356.237655 -219.045349) (xy 356.185618 -219.033472) (xy 356.135933 -219.013972) (xy 356.089709 -218.987285)
			(xy 356.047979 -218.954007) (xy 356.011675 -218.91488) (xy 355.981608 -218.87078) (xy 355.95845 -218.822691)
			(xy 355.942718 -218.771688) (xy 355.934763 -218.718909) (xy 355.934264 -218.692222) (xy 355.934622 -218.668882)
			(xy 355.940726 -218.622603) (xy 355.952832 -218.577521) (xy 355.961442 -218.555824) (xy 355.971094 -218.532456)
			(xy 355.799136 -218.235276) (xy 355.774244 -218.231974) (xy 355.74885 -218.228215) (xy 355.699462 -218.214205)
			(xy 355.652592 -218.193262) (xy 355.609208 -218.165817) (xy 355.570205 -218.132437) (xy 355.536388 -218.093812)
			(xy 355.508457 -218.050739) (xy 355.486988 -218.004108) (xy 355.472423 -217.954881) (xy 355.465065 -217.904074)
			(xy 355.464618 -217.878406) (xy 355.23805 -217.878406) (xy 355.237551 -217.905093) (xy 355.229596 -217.957872)
			(xy 355.213864 -218.008875) (xy 355.190706 -218.056964) (xy 355.160639 -218.101064) (xy 355.124335 -218.140191)
			(xy 355.082605 -218.173469) (xy 355.036381 -218.200156) (xy 354.986696 -218.219656) (xy 354.934659 -218.231533)
			(xy 354.881434 -218.235522) (xy 354.828209 -218.231533) (xy 354.776172 -218.219656) (xy 354.726487 -218.200156)
			(xy 354.680263 -218.173469) (xy 354.638533 -218.140191) (xy 354.602229 -218.101064) (xy 354.572162 -218.056964)
			(xy 354.549004 -218.008875) (xy 354.533272 -217.957872) (xy 354.525317 -217.905093) (xy 354.524818 -217.878406)
			(xy 354.29825 -217.878406) (xy 354.297868 -217.901745) (xy 354.291774 -217.948023) (xy 354.279678 -217.993106)
			(xy 354.271072 -218.014804) (xy 354.26142 -218.038172) (xy 354.433378 -218.335352) (xy 354.45827 -218.338654)
			(xy 354.483641 -218.34255) (xy 354.533023 -218.356544) (xy 354.579889 -218.377472) (xy 354.623271 -218.404901)
			(xy 354.662275 -218.438265) (xy 354.696093 -218.476874) (xy 354.724029 -218.519932) (xy 354.745504 -218.56655)
			(xy 354.760077 -218.615764) (xy 354.767444 -218.666559) (xy 354.767896 -218.692222) (xy 354.767397 -218.718909)
			(xy 354.759442 -218.771688) (xy 354.74371 -218.822691) (xy 354.720552 -218.87078) (xy 354.690485 -218.91488)
			(xy 354.654181 -218.954007) (xy 354.612451 -218.987285) (xy 354.566227 -219.013972) (xy 354.516542 -219.033472)
			(xy 354.464505 -219.045349) (xy 354.41128 -219.049338) (xy 354.358055 -219.045349) (xy 354.306018 -219.033472)
			(xy 354.256333 -219.013972) (xy 354.210109 -218.987285) (xy 354.168379 -218.954007) (xy 354.132075 -218.91488)
			(xy 354.102008 -218.87078) (xy 354.07885 -218.822691) (xy 354.063118 -218.771688) (xy 354.055163 -218.718909)
			(xy 354.054664 -218.692222) (xy 354.055022 -218.668882) (xy 354.061126 -218.622603) (xy 354.073232 -218.577521)
			(xy 354.081842 -218.555824) (xy 354.091494 -218.532456) (xy 353.919536 -218.235276) (xy 353.894644 -218.231974)
			(xy 353.86925 -218.228215) (xy 353.819862 -218.214205) (xy 353.772992 -218.193262) (xy 353.729608 -218.165817)
			(xy 353.690605 -218.132437) (xy 353.656788 -218.093812) (xy 353.628857 -218.050739) (xy 353.607388 -218.004108)
			(xy 353.592823 -217.954881) (xy 353.585465 -217.904074) (xy 353.585018 -217.878406) (xy 353.35845 -217.878406)
			(xy 353.357951 -217.905093) (xy 353.349996 -217.957872) (xy 353.334264 -218.008875) (xy 353.311106 -218.056964)
			(xy 353.281039 -218.101064) (xy 353.244735 -218.140191) (xy 353.203005 -218.173469) (xy 353.156781 -218.200156)
			(xy 353.107096 -218.219656) (xy 353.055059 -218.231533) (xy 353.001834 -218.235522) (xy 352.948609 -218.231533)
			(xy 352.896572 -218.219656) (xy 352.846887 -218.200156) (xy 352.800663 -218.173469) (xy 352.758933 -218.140191)
			(xy 352.722629 -218.101064) (xy 352.692562 -218.056964) (xy 352.669404 -218.008875) (xy 352.653672 -217.957872)
			(xy 352.645717 -217.905093) (xy 352.645218 -217.878406) (xy 352.41865 -217.878406) (xy 352.418268 -217.901745)
			(xy 352.412174 -217.948023) (xy 352.400078 -217.993106) (xy 352.391472 -218.014804) (xy 352.38182 -218.038172)
			(xy 352.553778 -218.335352) (xy 352.57867 -218.338654) (xy 352.604041 -218.34255) (xy 352.653423 -218.356544)
			(xy 352.700289 -218.377472) (xy 352.743671 -218.404901) (xy 352.782675 -218.438265) (xy 352.816493 -218.476874)
			(xy 352.844429 -218.519932) (xy 352.865904 -218.56655) (xy 352.880477 -218.615764) (xy 352.887844 -218.666559)
			(xy 352.888296 -218.692222) (xy 352.887797 -218.718909) (xy 352.879842 -218.771688) (xy 352.86411 -218.822691)
			(xy 352.840952 -218.87078) (xy 352.810885 -218.91488) (xy 352.774581 -218.954007) (xy 352.732851 -218.987285)
			(xy 352.686627 -219.013972) (xy 352.636942 -219.033472) (xy 352.584905 -219.045349) (xy 352.53168 -219.049338)
			(xy 352.478455 -219.045349) (xy 352.426418 -219.033472) (xy 352.376733 -219.013972) (xy 352.330509 -218.987285)
			(xy 352.288779 -218.954007) (xy 352.252475 -218.91488) (xy 352.222408 -218.87078) (xy 352.19925 -218.822691)
			(xy 352.183518 -218.771688) (xy 352.175563 -218.718909) (xy 352.175064 -218.692222) (xy 352.175422 -218.668882)
			(xy 352.181526 -218.622603) (xy 352.193632 -218.577521) (xy 352.202242 -218.555824) (xy 352.211894 -218.532456)
			(xy 352.039936 -218.235276) (xy 352.015044 -218.231974) (xy 351.98965 -218.228215) (xy 351.940262 -218.214205)
			(xy 351.893392 -218.193262) (xy 351.850008 -218.165817) (xy 351.811005 -218.132437) (xy 351.777188 -218.093812)
			(xy 351.749257 -218.050739) (xy 351.727788 -218.004108) (xy 351.713223 -217.954881) (xy 351.705865 -217.904074)
			(xy 351.705418 -217.878406) (xy 351.47885 -217.878406) (xy 351.478351 -217.905093) (xy 351.470396 -217.957872)
			(xy 351.454664 -218.008875) (xy 351.431506 -218.056964) (xy 351.401439 -218.101064) (xy 351.365135 -218.140191)
			(xy 351.323405 -218.173469) (xy 351.277181 -218.200156) (xy 351.227496 -218.219656) (xy 351.175459 -218.231533)
			(xy 351.122234 -218.235522) (xy 351.069009 -218.231533) (xy 351.016972 -218.219656) (xy 350.967287 -218.200156)
			(xy 350.921063 -218.173469) (xy 350.879333 -218.140191) (xy 350.843029 -218.101064) (xy 350.812962 -218.056964)
			(xy 350.789804 -218.008875) (xy 350.774072 -217.957872) (xy 350.766117 -217.905093) (xy 350.765618 -217.878406)
			(xy 350.53905 -217.878406) (xy 350.538668 -217.901745) (xy 350.532574 -217.948023) (xy 350.520478 -217.993106)
			(xy 350.511872 -218.014804) (xy 350.50222 -218.038172) (xy 350.674178 -218.335352) (xy 350.69907 -218.338654)
			(xy 350.724441 -218.34255) (xy 350.773823 -218.356544) (xy 350.820689 -218.377472) (xy 350.864071 -218.404901)
			(xy 350.903075 -218.438265) (xy 350.936893 -218.476874) (xy 350.964829 -218.519932) (xy 350.986304 -218.56655)
			(xy 351.000877 -218.615764) (xy 351.008244 -218.666559) (xy 351.008696 -218.692222) (xy 351.008197 -218.718909)
			(xy 351.000242 -218.771688) (xy 350.98451 -218.822691) (xy 350.961352 -218.87078) (xy 350.931285 -218.91488)
			(xy 350.894981 -218.954007) (xy 350.853251 -218.987285) (xy 350.807027 -219.013972) (xy 350.757342 -219.033472)
			(xy 350.705305 -219.045349) (xy 350.65208 -219.049338) (xy 350.598855 -219.045349) (xy 350.546818 -219.033472)
			(xy 350.497133 -219.013972) (xy 350.450909 -218.987285) (xy 350.409179 -218.954007) (xy 350.372875 -218.91488)
			(xy 350.342808 -218.87078) (xy 350.31965 -218.822691) (xy 350.303918 -218.771688) (xy 350.295963 -218.718909)
			(xy 350.295464 -218.692222) (xy 350.295822 -218.668882) (xy 350.301926 -218.622603) (xy 350.314032 -218.577521)
			(xy 350.322642 -218.555824) (xy 350.332294 -218.532456) (xy 350.160336 -218.235276) (xy 350.135444 -218.231974)
			(xy 350.11005 -218.228215) (xy 350.060662 -218.214205) (xy 350.013792 -218.193262) (xy 349.970408 -218.165817)
			(xy 349.931405 -218.132437) (xy 349.897588 -218.093812) (xy 349.869657 -218.050739) (xy 349.848188 -218.004108)
			(xy 349.833623 -217.954881) (xy 349.826265 -217.904074) (xy 349.825818 -217.878406) (xy 349.59925 -217.878406)
			(xy 349.598751 -217.905093) (xy 349.590796 -217.957872) (xy 349.575064 -218.008875) (xy 349.551906 -218.056964)
			(xy 349.521839 -218.101064) (xy 349.485535 -218.140191) (xy 349.443805 -218.173469) (xy 349.397581 -218.200156)
			(xy 349.347896 -218.219656) (xy 349.295859 -218.231533) (xy 349.242634 -218.235522) (xy 349.189409 -218.231533)
			(xy 349.137372 -218.219656) (xy 349.087687 -218.200156) (xy 349.041463 -218.173469) (xy 348.999733 -218.140191)
			(xy 348.963429 -218.101064) (xy 348.933362 -218.056964) (xy 348.910204 -218.008875) (xy 348.894472 -217.957872)
			(xy 348.886517 -217.905093) (xy 348.886018 -217.878406) (xy 348.65945 -217.878406) (xy 348.659068 -217.901745)
			(xy 348.652974 -217.948023) (xy 348.640878 -217.993106) (xy 348.632272 -218.014804) (xy 348.62262 -218.038172)
			(xy 348.794578 -218.335352) (xy 348.81947 -218.338654) (xy 348.844841 -218.34255) (xy 348.894223 -218.356544)
			(xy 348.941089 -218.377472) (xy 348.984471 -218.404901) (xy 349.023475 -218.438265) (xy 349.057293 -218.476874)
			(xy 349.085229 -218.519932) (xy 349.106704 -218.56655) (xy 349.121277 -218.615764) (xy 349.128644 -218.666559)
			(xy 349.129096 -218.692222) (xy 349.128597 -218.718909) (xy 349.120642 -218.771688) (xy 349.10491 -218.822691)
			(xy 349.081752 -218.87078) (xy 349.051685 -218.91488) (xy 349.015381 -218.954007) (xy 348.973651 -218.987285)
			(xy 348.927427 -219.013972) (xy 348.877742 -219.033472) (xy 348.825705 -219.045349) (xy 348.77248 -219.049338)
			(xy 348.719255 -219.045349) (xy 348.667218 -219.033472) (xy 348.617533 -219.013972) (xy 348.571309 -218.987285)
			(xy 348.529579 -218.954007) (xy 348.493275 -218.91488) (xy 348.463208 -218.87078) (xy 348.44005 -218.822691)
			(xy 348.424318 -218.771688) (xy 348.416363 -218.718909) (xy 348.415864 -218.692222) (xy 348.416222 -218.668882)
			(xy 348.422326 -218.622603) (xy 348.434432 -218.577521) (xy 348.443042 -218.555824) (xy 348.452694 -218.532456)
			(xy 348.280736 -218.235276) (xy 348.255844 -218.231974) (xy 348.23045 -218.228215) (xy 348.181062 -218.214205)
			(xy 348.134192 -218.193262) (xy 348.090808 -218.165817) (xy 348.051805 -218.132437) (xy 348.017988 -218.093812)
			(xy 347.990057 -218.050739) (xy 347.968588 -218.004108) (xy 347.954023 -217.954881) (xy 347.946665 -217.904074)
			(xy 347.946218 -217.878406) (xy 347.71965 -217.878406) (xy 347.719151 -217.905093) (xy 347.711196 -217.957872)
			(xy 347.695464 -218.008875) (xy 347.672306 -218.056964) (xy 347.642239 -218.101064) (xy 347.605935 -218.140191)
			(xy 347.564205 -218.173469) (xy 347.517981 -218.200156) (xy 347.468296 -218.219656) (xy 347.416259 -218.231533)
			(xy 347.363034 -218.235522) (xy 347.309809 -218.231533) (xy 347.257772 -218.219656) (xy 347.208087 -218.200156)
			(xy 347.161863 -218.173469) (xy 347.120133 -218.140191) (xy 347.083829 -218.101064) (xy 347.053762 -218.056964)
			(xy 347.030604 -218.008875) (xy 347.014872 -217.957872) (xy 347.006917 -217.905093) (xy 347.006418 -217.878406)
			(xy 346.77985 -217.878406) (xy 346.779468 -217.901745) (xy 346.773374 -217.948023) (xy 346.761278 -217.993106)
			(xy 346.752672 -218.014804) (xy 346.74302 -218.038172) (xy 346.914978 -218.335352) (xy 346.93987 -218.338654)
			(xy 346.965241 -218.34255) (xy 347.014623 -218.356544) (xy 347.061489 -218.377472) (xy 347.104871 -218.404901)
			(xy 347.143875 -218.438265) (xy 347.177693 -218.476874) (xy 347.205629 -218.519932) (xy 347.227104 -218.56655)
			(xy 347.241677 -218.615764) (xy 347.249044 -218.666559) (xy 347.249496 -218.692222) (xy 347.248997 -218.718909)
			(xy 347.241042 -218.771688) (xy 347.22531 -218.822691) (xy 347.202152 -218.87078) (xy 347.172085 -218.91488)
			(xy 347.135781 -218.954007) (xy 347.094051 -218.987285) (xy 347.047827 -219.013972) (xy 346.998142 -219.033472)
			(xy 346.946105 -219.045349) (xy 346.89288 -219.049338) (xy 346.839655 -219.045349) (xy 346.787618 -219.033472)
			(xy 346.737933 -219.013972) (xy 346.691709 -218.987285) (xy 346.649979 -218.954007) (xy 346.613675 -218.91488)
			(xy 346.583608 -218.87078) (xy 346.56045 -218.822691) (xy 346.544718 -218.771688) (xy 346.536763 -218.718909)
			(xy 346.536264 -218.692222) (xy 346.536622 -218.668882) (xy 346.542726 -218.622603) (xy 346.554832 -218.577521)
			(xy 346.563442 -218.555824) (xy 346.573094 -218.532456) (xy 346.401136 -218.235276) (xy 346.376244 -218.231974)
			(xy 346.35085 -218.228215) (xy 346.301462 -218.214205) (xy 346.254592 -218.193262) (xy 346.211208 -218.165817)
			(xy 346.172205 -218.132437) (xy 346.138388 -218.093812) (xy 346.110457 -218.050739) (xy 346.088988 -218.004108)
			(xy 346.074423 -217.954881) (xy 346.067065 -217.904074) (xy 346.066618 -217.878406) (xy 345.84005 -217.878406)
			(xy 345.839551 -217.905093) (xy 345.831596 -217.957872) (xy 345.815864 -218.008875) (xy 345.792706 -218.056964)
			(xy 345.762639 -218.101064) (xy 345.726335 -218.140191) (xy 345.684605 -218.173469) (xy 345.638381 -218.200156)
			(xy 345.588696 -218.219656) (xy 345.536659 -218.231533) (xy 345.483434 -218.235522) (xy 345.430209 -218.231533)
			(xy 345.378172 -218.219656) (xy 345.328487 -218.200156) (xy 345.282263 -218.173469) (xy 345.240533 -218.140191)
			(xy 345.204229 -218.101064) (xy 345.174162 -218.056964) (xy 345.151004 -218.008875) (xy 345.135272 -217.957872)
			(xy 345.127317 -217.905093) (xy 345.126818 -217.878406) (xy 344.90025 -217.878406) (xy 344.899868 -217.901745)
			(xy 344.893774 -217.948023) (xy 344.881678 -217.993106) (xy 344.873072 -218.014804) (xy 344.86342 -218.038172)
			(xy 345.035378 -218.335352) (xy 345.06027 -218.338654) (xy 345.085641 -218.34255) (xy 345.135023 -218.356544)
			(xy 345.181889 -218.377472) (xy 345.225271 -218.404901) (xy 345.264275 -218.438265) (xy 345.298093 -218.476874)
			(xy 345.326029 -218.519932) (xy 345.347504 -218.56655) (xy 345.362077 -218.615764) (xy 345.369444 -218.666559)
			(xy 345.369896 -218.692222) (xy 345.369397 -218.718909) (xy 345.361442 -218.771688) (xy 345.34571 -218.822691)
			(xy 345.322552 -218.87078) (xy 345.292485 -218.91488) (xy 345.256181 -218.954007) (xy 345.214451 -218.987285)
			(xy 345.168227 -219.013972) (xy 345.118542 -219.033472) (xy 345.066505 -219.045349) (xy 345.01328 -219.049338)
			(xy 344.960055 -219.045349) (xy 344.908018 -219.033472) (xy 344.858333 -219.013972) (xy 344.812109 -218.987285)
			(xy 344.770379 -218.954007) (xy 344.734075 -218.91488) (xy 344.704008 -218.87078) (xy 344.68085 -218.822691)
			(xy 344.665118 -218.771688) (xy 344.657163 -218.718909) (xy 344.656664 -218.692222) (xy 344.657022 -218.668882)
			(xy 344.663126 -218.622603) (xy 344.675232 -218.577521) (xy 344.683842 -218.555824) (xy 344.693494 -218.532456)
			(xy 344.521536 -218.235276) (xy 344.496644 -218.231974) (xy 344.47125 -218.228215) (xy 344.421862 -218.214205)
			(xy 344.374992 -218.193262) (xy 344.331608 -218.165817) (xy 344.292605 -218.132437) (xy 344.258788 -218.093812)
			(xy 344.230857 -218.050739) (xy 344.209388 -218.004108) (xy 344.194823 -217.954881) (xy 344.187465 -217.904074)
			(xy 344.187018 -217.878406) (xy 343.96045 -217.878406) (xy 343.959951 -217.905093) (xy 343.951996 -217.957872)
			(xy 343.936264 -218.008875) (xy 343.913106 -218.056964) (xy 343.883039 -218.101064) (xy 343.846735 -218.140191)
			(xy 343.805005 -218.173469) (xy 343.758781 -218.200156) (xy 343.709096 -218.219656) (xy 343.657059 -218.231533)
			(xy 343.603834 -218.235522) (xy 343.550609 -218.231533) (xy 343.498572 -218.219656) (xy 343.448887 -218.200156)
			(xy 343.402663 -218.173469) (xy 343.360933 -218.140191) (xy 343.324629 -218.101064) (xy 343.294562 -218.056964)
			(xy 343.271404 -218.008875) (xy 343.255672 -217.957872) (xy 343.247717 -217.905093) (xy 343.247218 -217.878406)
			(xy 343.02065 -217.878406) (xy 343.020268 -217.901745) (xy 343.014174 -217.948023) (xy 343.002078 -217.993106)
			(xy 342.993472 -218.014804) (xy 342.98382 -218.038172) (xy 343.155778 -218.335352) (xy 343.18067 -218.338654)
			(xy 343.206041 -218.34255) (xy 343.255423 -218.356544) (xy 343.302289 -218.377472) (xy 343.345671 -218.404901)
			(xy 343.384675 -218.438265) (xy 343.418493 -218.476874) (xy 343.446429 -218.519932) (xy 343.467904 -218.56655)
			(xy 343.482477 -218.615764) (xy 343.489844 -218.666559) (xy 343.490296 -218.692222) (xy 343.489797 -218.718909)
			(xy 343.481842 -218.771688) (xy 343.46611 -218.822691) (xy 343.442952 -218.87078) (xy 343.412885 -218.91488)
			(xy 343.376581 -218.954007) (xy 343.334851 -218.987285) (xy 343.288627 -219.013972) (xy 343.238942 -219.033472)
			(xy 343.186905 -219.045349) (xy 343.13368 -219.049338) (xy 343.080455 -219.045349) (xy 343.028418 -219.033472)
			(xy 342.978733 -219.013972) (xy 342.932509 -218.987285) (xy 342.890779 -218.954007) (xy 342.854475 -218.91488)
			(xy 342.824408 -218.87078) (xy 342.80125 -218.822691) (xy 342.785518 -218.771688) (xy 342.777563 -218.718909)
			(xy 342.777064 -218.692222) (xy 342.777422 -218.668882) (xy 342.783526 -218.622603) (xy 342.795632 -218.577521)
			(xy 342.804242 -218.555824) (xy 342.813894 -218.532456) (xy 342.641936 -218.235276) (xy 342.617044 -218.231974)
			(xy 342.59165 -218.228215) (xy 342.542262 -218.214205) (xy 342.495392 -218.193262) (xy 342.452008 -218.165817)
			(xy 342.413005 -218.132437) (xy 342.379188 -218.093812) (xy 342.351257 -218.050739) (xy 342.329788 -218.004108)
			(xy 342.315223 -217.954881) (xy 342.307865 -217.904074) (xy 342.307418 -217.878406) (xy 342.08085 -217.878406)
			(xy 342.080351 -217.905093) (xy 342.072396 -217.957872) (xy 342.056664 -218.008875) (xy 342.033506 -218.056964)
			(xy 342.003439 -218.101064) (xy 341.967135 -218.140191) (xy 341.925405 -218.173469) (xy 341.879181 -218.200156)
			(xy 341.829496 -218.219656) (xy 341.777459 -218.231533) (xy 341.724234 -218.235522) (xy 341.671009 -218.231533)
			(xy 341.618972 -218.219656) (xy 341.569287 -218.200156) (xy 341.523063 -218.173469) (xy 341.481333 -218.140191)
			(xy 341.445029 -218.101064) (xy 341.414962 -218.056964) (xy 341.391804 -218.008875) (xy 341.376072 -217.957872)
			(xy 341.368117 -217.905093) (xy 341.367618 -217.878406) (xy 341.14105 -217.878406) (xy 341.140668 -217.901745)
			(xy 341.134574 -217.948023) (xy 341.122478 -217.993106) (xy 341.113872 -218.014804) (xy 341.10422 -218.038172)
			(xy 341.276178 -218.335352) (xy 341.30107 -218.338654) (xy 341.326441 -218.34255) (xy 341.375823 -218.356544)
			(xy 341.422689 -218.377472) (xy 341.466071 -218.404901) (xy 341.505075 -218.438265) (xy 341.538893 -218.476874)
			(xy 341.566829 -218.519932) (xy 341.588304 -218.56655) (xy 341.602877 -218.615764) (xy 341.610244 -218.666559)
			(xy 341.610696 -218.692222) (xy 341.610197 -218.718909) (xy 341.602242 -218.771688) (xy 341.58651 -218.822691)
			(xy 341.563352 -218.87078) (xy 341.533285 -218.91488) (xy 341.496981 -218.954007) (xy 341.455251 -218.987285)
			(xy 341.409027 -219.013972) (xy 341.359342 -219.033472) (xy 341.307305 -219.045349) (xy 341.25408 -219.049338)
			(xy 341.200855 -219.045349) (xy 341.148818 -219.033472) (xy 341.099133 -219.013972) (xy 341.052909 -218.987285)
			(xy 341.011179 -218.954007) (xy 340.974875 -218.91488) (xy 340.944808 -218.87078) (xy 340.92165 -218.822691)
			(xy 340.905918 -218.771688) (xy 340.897963 -218.718909) (xy 340.897464 -218.692222) (xy 340.897822 -218.668882)
			(xy 340.903926 -218.622603) (xy 340.916032 -218.577521) (xy 340.924642 -218.555824) (xy 340.934294 -218.532456)
			(xy 340.762336 -218.235276) (xy 340.737444 -218.231974) (xy 340.71205 -218.228215) (xy 340.662662 -218.214205)
			(xy 340.615792 -218.193262) (xy 340.572408 -218.165817) (xy 340.533405 -218.132437) (xy 340.499588 -218.093812)
			(xy 340.471657 -218.050739) (xy 340.450188 -218.004108) (xy 340.435623 -217.954881) (xy 340.428265 -217.904074)
			(xy 340.427818 -217.878406) (xy 340.20125 -217.878406) (xy 340.200751 -217.905093) (xy 340.192796 -217.957872)
			(xy 340.177064 -218.008875) (xy 340.153906 -218.056964) (xy 340.123839 -218.101064) (xy 340.087535 -218.140191)
			(xy 340.045805 -218.173469) (xy 339.999581 -218.200156) (xy 339.949896 -218.219656) (xy 339.897859 -218.231533)
			(xy 339.844634 -218.235522) (xy 339.791409 -218.231533) (xy 339.739372 -218.219656) (xy 339.689687 -218.200156)
			(xy 339.643463 -218.173469) (xy 339.601733 -218.140191) (xy 339.565429 -218.101064) (xy 339.535362 -218.056964)
			(xy 339.512204 -218.008875) (xy 339.496472 -217.957872) (xy 339.488517 -217.905093) (xy 339.488018 -217.878406)
			(xy 339.26145 -217.878406) (xy 339.261068 -217.901745) (xy 339.254974 -217.948023) (xy 339.242878 -217.993106)
			(xy 339.234272 -218.014804) (xy 339.22462 -218.038172) (xy 339.396578 -218.335352) (xy 339.42147 -218.338654)
			(xy 339.446841 -218.34255) (xy 339.496223 -218.356544) (xy 339.543089 -218.377472) (xy 339.586471 -218.404901)
			(xy 339.625475 -218.438265) (xy 339.659293 -218.476874) (xy 339.687229 -218.519932) (xy 339.708704 -218.56655)
			(xy 339.723277 -218.615764) (xy 339.730644 -218.666559) (xy 339.731096 -218.692222) (xy 339.730597 -218.718909)
			(xy 339.722642 -218.771688) (xy 339.70691 -218.822691) (xy 339.683752 -218.87078) (xy 339.653685 -218.91488)
			(xy 339.617381 -218.954007) (xy 339.575651 -218.987285) (xy 339.529427 -219.013972) (xy 339.479742 -219.033472)
			(xy 339.427705 -219.045349) (xy 339.37448 -219.049338) (xy 339.321255 -219.045349) (xy 339.269218 -219.033472)
			(xy 339.219533 -219.013972) (xy 339.173309 -218.987285) (xy 339.131579 -218.954007) (xy 339.095275 -218.91488)
			(xy 339.065208 -218.87078) (xy 339.04205 -218.822691) (xy 339.026318 -218.771688) (xy 339.018363 -218.718909)
			(xy 339.017864 -218.692222) (xy 339.018222 -218.668882) (xy 339.024326 -218.622603) (xy 339.036432 -218.577521)
			(xy 339.045042 -218.555824) (xy 339.054694 -218.532456) (xy 338.882736 -218.235276) (xy 338.857844 -218.231974)
			(xy 338.83245 -218.228215) (xy 338.783062 -218.214205) (xy 338.736192 -218.193262) (xy 338.692808 -218.165817)
			(xy 338.653805 -218.132437) (xy 338.619988 -218.093812) (xy 338.592057 -218.050739) (xy 338.570588 -218.004108)
			(xy 338.556023 -217.954881) (xy 338.548665 -217.904074) (xy 338.548218 -217.878406) (xy 338.32165 -217.878406)
			(xy 338.321151 -217.905093) (xy 338.313196 -217.957872) (xy 338.297464 -218.008875) (xy 338.274306 -218.056964)
			(xy 338.244239 -218.101064) (xy 338.207935 -218.140191) (xy 338.166205 -218.173469) (xy 338.119981 -218.200156)
			(xy 338.070296 -218.219656) (xy 338.018259 -218.231533) (xy 337.965034 -218.235522) (xy 337.911809 -218.231533)
			(xy 337.859772 -218.219656) (xy 337.810087 -218.200156) (xy 337.763863 -218.173469) (xy 337.722133 -218.140191)
			(xy 337.685829 -218.101064) (xy 337.655762 -218.056964) (xy 337.632604 -218.008875) (xy 337.616872 -217.957872)
			(xy 337.608917 -217.905093) (xy 337.608418 -217.878406) (xy 337.38185 -217.878406) (xy 337.381468 -217.901745)
			(xy 337.375374 -217.948023) (xy 337.363278 -217.993106) (xy 337.354672 -218.014804) (xy 337.34502 -218.038172)
			(xy 337.516978 -218.335352) (xy 337.54187 -218.338654) (xy 337.567241 -218.34255) (xy 337.616623 -218.356544)
			(xy 337.663489 -218.377472) (xy 337.706871 -218.404901) (xy 337.745875 -218.438265) (xy 337.779693 -218.476874)
			(xy 337.807629 -218.519932) (xy 337.829104 -218.56655) (xy 337.843677 -218.615764) (xy 337.851044 -218.666559)
			(xy 337.851496 -218.692222) (xy 337.850997 -218.718909) (xy 337.843042 -218.771688) (xy 337.82731 -218.822691)
			(xy 337.804152 -218.87078) (xy 337.774085 -218.91488) (xy 337.737781 -218.954007) (xy 337.696051 -218.987285)
			(xy 337.649827 -219.013972) (xy 337.600142 -219.033472) (xy 337.548105 -219.045349) (xy 337.49488 -219.049338)
			(xy 337.441655 -219.045349) (xy 337.389618 -219.033472) (xy 337.339933 -219.013972) (xy 337.293709 -218.987285)
			(xy 337.251979 -218.954007) (xy 337.215675 -218.91488) (xy 337.185608 -218.87078) (xy 337.16245 -218.822691)
			(xy 337.146718 -218.771688) (xy 337.138763 -218.718909) (xy 337.138264 -218.692222) (xy 337.138622 -218.668882)
			(xy 337.144726 -218.622603) (xy 337.156832 -218.577521) (xy 337.165442 -218.555824) (xy 337.175094 -218.532456)
			(xy 337.003136 -218.235276) (xy 336.978244 -218.231974) (xy 336.95285 -218.228215) (xy 336.903462 -218.214205)
			(xy 336.856592 -218.193262) (xy 336.813208 -218.165817) (xy 336.774205 -218.132437) (xy 336.740388 -218.093812)
			(xy 336.712457 -218.050739) (xy 336.690988 -218.004108) (xy 336.676423 -217.954881) (xy 336.669065 -217.904074)
			(xy 336.668618 -217.878406) (xy 134.552182 -217.878406) (xy 134.551683 -217.905093) (xy 134.543728 -217.957872)
			(xy 134.527996 -218.008875) (xy 134.504838 -218.056964) (xy 134.474771 -218.101064) (xy 134.438467 -218.140191)
			(xy 134.396737 -218.173469) (xy 134.350513 -218.200156) (xy 134.300828 -218.219656) (xy 134.248791 -218.231533)
			(xy 134.195566 -218.235522) (xy 134.142341 -218.231533) (xy 134.090304 -218.219656) (xy 134.040619 -218.200156)
			(xy 133.994395 -218.173469) (xy 133.952665 -218.140191) (xy 133.916361 -218.101064) (xy 133.886294 -218.056964)
			(xy 133.863136 -218.008875) (xy 133.847404 -217.957872) (xy 133.839449 -217.905093) (xy 133.83895 -217.878406)
			(xy 133.839304 -217.855066) (xy 133.84541 -217.808787) (xy 133.857517 -217.763705) (xy 133.866128 -217.742008)
			(xy 133.87578 -217.71864) (xy 133.704076 -217.421206) (xy 133.679184 -217.417904) (xy 133.653755 -217.414138)
			(xy 133.604265 -217.400236) (xy 133.557284 -217.37937) (xy 133.513788 -217.351973) (xy 133.474678 -217.318613)
			(xy 133.440765 -217.279981) (xy 133.412752 -217.236879) (xy 133.391219 -217.1902) (xy 133.376615 -217.140913)
			(xy 133.369241 -217.090039) (xy 133.368796 -217.064336) (xy 132.202428 -217.064336) (xy 132.202428 -217.064844)
			(xy 132.202021 -217.088045) (xy 132.195964 -217.134052) (xy 132.183998 -217.178886) (xy 132.175504 -217.20048)
			(xy 132.165852 -217.223594) (xy 132.338064 -217.521536) (xy 132.362956 -217.524838) (xy 132.388335 -217.528682)
			(xy 132.437716 -217.542687) (xy 132.484581 -217.563624) (xy 132.527962 -217.59106) (xy 132.566963 -217.62443)
			(xy 132.600779 -217.663045) (xy 132.628713 -217.706107) (xy 132.650188 -217.752728) (xy 132.66476 -217.801945)
			(xy 132.672129 -217.852742) (xy 132.672582 -217.878406) (xy 132.672083 -217.905093) (xy 132.664128 -217.957872)
			(xy 132.648396 -218.008875) (xy 132.625238 -218.056964) (xy 132.595171 -218.101064) (xy 132.558867 -218.140191)
			(xy 132.517137 -218.173469) (xy 132.470913 -218.200156) (xy 132.421228 -218.219656) (xy 132.369191 -218.231533)
			(xy 132.315966 -218.235522) (xy 132.262741 -218.231533) (xy 132.210704 -218.219656) (xy 132.161019 -218.200156)
			(xy 132.114795 -218.173469) (xy 132.073065 -218.140191) (xy 132.036761 -218.101064) (xy 132.006694 -218.056964)
			(xy 131.983536 -218.008875) (xy 131.967804 -217.957872) (xy 131.959849 -217.905093) (xy 131.95935 -217.878406)
			(xy 131.959704 -217.855066) (xy 131.96581 -217.808787) (xy 131.977917 -217.763705) (xy 131.986528 -217.742008)
			(xy 131.99618 -217.71864) (xy 131.824476 -217.421206) (xy 131.799584 -217.417904) (xy 131.774155 -217.414138)
			(xy 131.724665 -217.400236) (xy 131.677684 -217.37937) (xy 131.634188 -217.351973) (xy 131.595078 -217.318613)
			(xy 131.561165 -217.279981) (xy 131.533152 -217.236879) (xy 131.511619 -217.1902) (xy 131.497015 -217.140913)
			(xy 131.489641 -217.090039) (xy 131.489196 -217.064336) (xy 130.322828 -217.064336) (xy 130.322828 -217.064844)
			(xy 130.322421 -217.088045) (xy 130.316364 -217.134052) (xy 130.304398 -217.178886) (xy 130.295904 -217.20048)
			(xy 130.286252 -217.223594) (xy 130.458464 -217.521536) (xy 130.483356 -217.524838) (xy 130.508735 -217.528682)
			(xy 130.558116 -217.542687) (xy 130.604981 -217.563624) (xy 130.648362 -217.59106) (xy 130.687363 -217.62443)
			(xy 130.721179 -217.663045) (xy 130.749113 -217.706107) (xy 130.770588 -217.752728) (xy 130.78516 -217.801945)
			(xy 130.792529 -217.852742) (xy 130.792982 -217.878406) (xy 130.792483 -217.905093) (xy 130.784528 -217.957872)
			(xy 130.768796 -218.008875) (xy 130.745638 -218.056964) (xy 130.715571 -218.101064) (xy 130.679267 -218.140191)
			(xy 130.637537 -218.173469) (xy 130.591313 -218.200156) (xy 130.541628 -218.219656) (xy 130.489591 -218.231533)
			(xy 130.436366 -218.235522) (xy 130.383141 -218.231533) (xy 130.331104 -218.219656) (xy 130.281419 -218.200156)
			(xy 130.235195 -218.173469) (xy 130.193465 -218.140191) (xy 130.157161 -218.101064) (xy 130.127094 -218.056964)
			(xy 130.103936 -218.008875) (xy 130.088204 -217.957872) (xy 130.080249 -217.905093) (xy 130.07975 -217.878406)
			(xy 130.080104 -217.855066) (xy 130.08621 -217.808787) (xy 130.098317 -217.763705) (xy 130.106928 -217.742008)
			(xy 130.11658 -217.71864) (xy 129.944876 -217.421206) (xy 129.919984 -217.417904) (xy 129.894555 -217.414138)
			(xy 129.845065 -217.400236) (xy 129.798084 -217.37937) (xy 129.754588 -217.351973) (xy 129.715478 -217.318613)
			(xy 129.681565 -217.279981) (xy 129.653552 -217.236879) (xy 129.632019 -217.1902) (xy 129.617415 -217.140913)
			(xy 129.610041 -217.090039) (xy 129.609596 -217.064336) (xy 128.443228 -217.064336) (xy 128.443228 -217.064844)
			(xy 128.442821 -217.088045) (xy 128.436764 -217.134052) (xy 128.424798 -217.178886) (xy 128.416304 -217.20048)
			(xy 128.406652 -217.223594) (xy 128.578864 -217.521536) (xy 128.603756 -217.524838) (xy 128.629135 -217.528682)
			(xy 128.678516 -217.542687) (xy 128.725381 -217.563624) (xy 128.768762 -217.59106) (xy 128.807763 -217.62443)
			(xy 128.841579 -217.663045) (xy 128.869513 -217.706107) (xy 128.890988 -217.752728) (xy 128.90556 -217.801945)
			(xy 128.912929 -217.852742) (xy 128.913382 -217.878406) (xy 128.912883 -217.905093) (xy 128.904928 -217.957872)
			(xy 128.889196 -218.008875) (xy 128.866038 -218.056964) (xy 128.835971 -218.101064) (xy 128.799667 -218.140191)
			(xy 128.757937 -218.173469) (xy 128.711713 -218.200156) (xy 128.662028 -218.219656) (xy 128.609991 -218.231533)
			(xy 128.556766 -218.235522) (xy 128.503541 -218.231533) (xy 128.451504 -218.219656) (xy 128.401819 -218.200156)
			(xy 128.355595 -218.173469) (xy 128.313865 -218.140191) (xy 128.277561 -218.101064) (xy 128.247494 -218.056964)
			(xy 128.224336 -218.008875) (xy 128.208604 -217.957872) (xy 128.200649 -217.905093) (xy 128.20015 -217.878406)
			(xy 128.200504 -217.855066) (xy 128.20661 -217.808787) (xy 128.218717 -217.763705) (xy 128.227328 -217.742008)
			(xy 128.23698 -217.71864) (xy 128.065276 -217.421206) (xy 128.040384 -217.417904) (xy 128.014955 -217.414138)
			(xy 127.965465 -217.400236) (xy 127.918484 -217.37937) (xy 127.874988 -217.351973) (xy 127.835878 -217.318613)
			(xy 127.801965 -217.279981) (xy 127.773952 -217.236879) (xy 127.752419 -217.1902) (xy 127.737815 -217.140913)
			(xy 127.730441 -217.090039) (xy 127.729996 -217.064336) (xy 126.563628 -217.064336) (xy 126.563628 -217.064844)
			(xy 126.563221 -217.088045) (xy 126.557164 -217.134052) (xy 126.545198 -217.178886) (xy 126.536704 -217.20048)
			(xy 126.527052 -217.223594) (xy 126.699264 -217.521536) (xy 126.724156 -217.524838) (xy 126.749535 -217.528682)
			(xy 126.798916 -217.542687) (xy 126.845781 -217.563624) (xy 126.889162 -217.59106) (xy 126.928163 -217.62443)
			(xy 126.961979 -217.663045) (xy 126.989913 -217.706107) (xy 127.011388 -217.752728) (xy 127.02596 -217.801945)
			(xy 127.033329 -217.852742) (xy 127.033782 -217.878406) (xy 127.033283 -217.905093) (xy 127.025328 -217.957872)
			(xy 127.009596 -218.008875) (xy 126.986438 -218.056964) (xy 126.956371 -218.101064) (xy 126.920067 -218.140191)
			(xy 126.878337 -218.173469) (xy 126.832113 -218.200156) (xy 126.782428 -218.219656) (xy 126.730391 -218.231533)
			(xy 126.677166 -218.235522) (xy 126.623941 -218.231533) (xy 126.571904 -218.219656) (xy 126.522219 -218.200156)
			(xy 126.475995 -218.173469) (xy 126.434265 -218.140191) (xy 126.397961 -218.101064) (xy 126.367894 -218.056964)
			(xy 126.344736 -218.008875) (xy 126.329004 -217.957872) (xy 126.321049 -217.905093) (xy 126.32055 -217.878406)
			(xy 126.320904 -217.855066) (xy 126.32701 -217.808787) (xy 126.339117 -217.763705) (xy 126.347728 -217.742008)
			(xy 126.35738 -217.71864) (xy 126.185676 -217.421206) (xy 126.160784 -217.417904) (xy 126.135355 -217.414138)
			(xy 126.085865 -217.400236) (xy 126.038884 -217.37937) (xy 125.995388 -217.351973) (xy 125.956278 -217.318613)
			(xy 125.922365 -217.279981) (xy 125.894352 -217.236879) (xy 125.872819 -217.1902) (xy 125.858215 -217.140913)
			(xy 125.850841 -217.090039) (xy 125.850396 -217.064336) (xy 124.684028 -217.064336) (xy 124.684028 -217.064844)
			(xy 124.683621 -217.088045) (xy 124.677564 -217.134052) (xy 124.665598 -217.178886) (xy 124.657104 -217.20048)
			(xy 124.647452 -217.223594) (xy 124.819664 -217.521536) (xy 124.844556 -217.524838) (xy 124.869935 -217.528682)
			(xy 124.919316 -217.542687) (xy 124.966181 -217.563624) (xy 125.009562 -217.59106) (xy 125.048563 -217.62443)
			(xy 125.082379 -217.663045) (xy 125.110313 -217.706107) (xy 125.131788 -217.752728) (xy 125.14636 -217.801945)
			(xy 125.153729 -217.852742) (xy 125.154182 -217.878406) (xy 125.153683 -217.905093) (xy 125.145728 -217.957872)
			(xy 125.129996 -218.008875) (xy 125.106838 -218.056964) (xy 125.076771 -218.101064) (xy 125.040467 -218.140191)
			(xy 124.998737 -218.173469) (xy 124.952513 -218.200156) (xy 124.902828 -218.219656) (xy 124.850791 -218.231533)
			(xy 124.797566 -218.235522) (xy 124.744341 -218.231533) (xy 124.692304 -218.219656) (xy 124.642619 -218.200156)
			(xy 124.596395 -218.173469) (xy 124.554665 -218.140191) (xy 124.518361 -218.101064) (xy 124.488294 -218.056964)
			(xy 124.465136 -218.008875) (xy 124.449404 -217.957872) (xy 124.441449 -217.905093) (xy 124.44095 -217.878406)
			(xy 124.441304 -217.855066) (xy 124.44741 -217.808787) (xy 124.459517 -217.763705) (xy 124.468128 -217.742008)
			(xy 124.47778 -217.71864) (xy 124.306076 -217.421206) (xy 124.281184 -217.417904) (xy 124.255755 -217.414138)
			(xy 124.206265 -217.400236) (xy 124.159284 -217.37937) (xy 124.115788 -217.351973) (xy 124.076678 -217.318613)
			(xy 124.042765 -217.279981) (xy 124.014752 -217.236879) (xy 123.993219 -217.1902) (xy 123.978615 -217.140913)
			(xy 123.971241 -217.090039) (xy 123.970796 -217.064336) (xy 122.804428 -217.064336) (xy 122.804428 -217.064844)
			(xy 122.804021 -217.088045) (xy 122.797964 -217.134052) (xy 122.785998 -217.178886) (xy 122.777504 -217.20048)
			(xy 122.767852 -217.223594) (xy 122.940064 -217.521536) (xy 122.964956 -217.524838) (xy 122.990335 -217.528682)
			(xy 123.039716 -217.542687) (xy 123.086581 -217.563624) (xy 123.129962 -217.59106) (xy 123.168963 -217.62443)
			(xy 123.202779 -217.663045) (xy 123.230713 -217.706107) (xy 123.252188 -217.752728) (xy 123.26676 -217.801945)
			(xy 123.274129 -217.852742) (xy 123.274582 -217.878406) (xy 123.274083 -217.905093) (xy 123.266128 -217.957872)
			(xy 123.250396 -218.008875) (xy 123.227238 -218.056964) (xy 123.197171 -218.101064) (xy 123.160867 -218.140191)
			(xy 123.119137 -218.173469) (xy 123.072913 -218.200156) (xy 123.023228 -218.219656) (xy 122.971191 -218.231533)
			(xy 122.917966 -218.235522) (xy 122.864741 -218.231533) (xy 122.812704 -218.219656) (xy 122.763019 -218.200156)
			(xy 122.716795 -218.173469) (xy 122.675065 -218.140191) (xy 122.638761 -218.101064) (xy 122.608694 -218.056964)
			(xy 122.585536 -218.008875) (xy 122.569804 -217.957872) (xy 122.561849 -217.905093) (xy 122.56135 -217.878406)
			(xy 122.561704 -217.855066) (xy 122.56781 -217.808787) (xy 122.579917 -217.763705) (xy 122.588528 -217.742008)
			(xy 122.59818 -217.71864) (xy 122.426476 -217.421206) (xy 122.401584 -217.417904) (xy 122.376155 -217.414138)
			(xy 122.326665 -217.400236) (xy 122.279684 -217.37937) (xy 122.236188 -217.351973) (xy 122.197078 -217.318613)
			(xy 122.163165 -217.279981) (xy 122.135152 -217.236879) (xy 122.113619 -217.1902) (xy 122.099015 -217.140913)
			(xy 122.091641 -217.090039) (xy 122.091196 -217.064336) (xy 120.924828 -217.064336) (xy 120.924828 -217.064844)
			(xy 120.924421 -217.088045) (xy 120.918364 -217.134052) (xy 120.906398 -217.178886) (xy 120.897904 -217.20048)
			(xy 120.888252 -217.223594) (xy 121.060464 -217.521536) (xy 121.085356 -217.524838) (xy 121.110735 -217.528682)
			(xy 121.160116 -217.542687) (xy 121.206981 -217.563624) (xy 121.250362 -217.59106) (xy 121.289363 -217.62443)
			(xy 121.323179 -217.663045) (xy 121.351113 -217.706107) (xy 121.372588 -217.752728) (xy 121.38716 -217.801945)
			(xy 121.394529 -217.852742) (xy 121.394982 -217.878406) (xy 121.394483 -217.905093) (xy 121.386528 -217.957872)
			(xy 121.370796 -218.008875) (xy 121.347638 -218.056964) (xy 121.317571 -218.101064) (xy 121.281267 -218.140191)
			(xy 121.239537 -218.173469) (xy 121.193313 -218.200156) (xy 121.143628 -218.219656) (xy 121.091591 -218.231533)
			(xy 121.038366 -218.235522) (xy 120.985141 -218.231533) (xy 120.933104 -218.219656) (xy 120.883419 -218.200156)
			(xy 120.837195 -218.173469) (xy 120.795465 -218.140191) (xy 120.759161 -218.101064) (xy 120.729094 -218.056964)
			(xy 120.705936 -218.008875) (xy 120.690204 -217.957872) (xy 120.682249 -217.905093) (xy 120.68175 -217.878406)
			(xy 120.682104 -217.855066) (xy 120.68821 -217.808787) (xy 120.700317 -217.763705) (xy 120.708928 -217.742008)
			(xy 120.71858 -217.71864) (xy 120.546876 -217.421206) (xy 120.521984 -217.417904) (xy 120.496555 -217.414138)
			(xy 120.447065 -217.400236) (xy 120.400084 -217.37937) (xy 120.356588 -217.351973) (xy 120.317478 -217.318613)
			(xy 120.283565 -217.279981) (xy 120.255552 -217.236879) (xy 120.234019 -217.1902) (xy 120.219415 -217.140913)
			(xy 120.212041 -217.090039) (xy 120.211596 -217.064336) (xy 119.045228 -217.064336) (xy 119.045228 -217.064844)
			(xy 119.044821 -217.088045) (xy 119.038764 -217.134052) (xy 119.026798 -217.178886) (xy 119.018304 -217.20048)
			(xy 119.008652 -217.223594) (xy 119.180864 -217.521536) (xy 119.205756 -217.524838) (xy 119.231135 -217.528682)
			(xy 119.280516 -217.542687) (xy 119.327381 -217.563624) (xy 119.370762 -217.59106) (xy 119.409763 -217.62443)
			(xy 119.443579 -217.663045) (xy 119.471513 -217.706107) (xy 119.492988 -217.752728) (xy 119.50756 -217.801945)
			(xy 119.514929 -217.852742) (xy 119.515382 -217.878406) (xy 119.514883 -217.905093) (xy 119.506928 -217.957872)
			(xy 119.491196 -218.008875) (xy 119.468038 -218.056964) (xy 119.437971 -218.101064) (xy 119.401667 -218.140191)
			(xy 119.359937 -218.173469) (xy 119.313713 -218.200156) (xy 119.264028 -218.219656) (xy 119.211991 -218.231533)
			(xy 119.158766 -218.235522) (xy 119.105541 -218.231533) (xy 119.053504 -218.219656) (xy 119.003819 -218.200156)
			(xy 118.957595 -218.173469) (xy 118.915865 -218.140191) (xy 118.879561 -218.101064) (xy 118.849494 -218.056964)
			(xy 118.826336 -218.008875) (xy 118.810604 -217.957872) (xy 118.802649 -217.905093) (xy 118.80215 -217.878406)
			(xy 118.802504 -217.855066) (xy 118.80861 -217.808787) (xy 118.820717 -217.763705) (xy 118.829328 -217.742008)
			(xy 118.83898 -217.71864) (xy 118.667276 -217.421206) (xy 118.642384 -217.417904) (xy 118.616955 -217.414138)
			(xy 118.567465 -217.400236) (xy 118.520484 -217.37937) (xy 118.476988 -217.351973) (xy 118.437878 -217.318613)
			(xy 118.403965 -217.279981) (xy 118.375952 -217.236879) (xy 118.354419 -217.1902) (xy 118.339815 -217.140913)
			(xy 118.332441 -217.090039) (xy 118.331996 -217.064336) (xy 117.165628 -217.064336) (xy 117.165628 -217.064844)
			(xy 117.165221 -217.088045) (xy 117.159164 -217.134052) (xy 117.147198 -217.178886) (xy 117.138704 -217.20048)
			(xy 117.129052 -217.223594) (xy 117.301264 -217.521536) (xy 117.326156 -217.524838) (xy 117.351535 -217.528682)
			(xy 117.400916 -217.542687) (xy 117.447781 -217.563624) (xy 117.491162 -217.59106) (xy 117.530163 -217.62443)
			(xy 117.563979 -217.663045) (xy 117.591913 -217.706107) (xy 117.613388 -217.752728) (xy 117.62796 -217.801945)
			(xy 117.635329 -217.852742) (xy 117.635782 -217.878406) (xy 117.635283 -217.905093) (xy 117.627328 -217.957872)
			(xy 117.611596 -218.008875) (xy 117.588438 -218.056964) (xy 117.558371 -218.101064) (xy 117.522067 -218.140191)
			(xy 117.480337 -218.173469) (xy 117.434113 -218.200156) (xy 117.384428 -218.219656) (xy 117.332391 -218.231533)
			(xy 117.279166 -218.235522) (xy 117.225941 -218.231533) (xy 117.173904 -218.219656) (xy 117.124219 -218.200156)
			(xy 117.077995 -218.173469) (xy 117.036265 -218.140191) (xy 116.999961 -218.101064) (xy 116.969894 -218.056964)
			(xy 116.946736 -218.008875) (xy 116.931004 -217.957872) (xy 116.923049 -217.905093) (xy 116.92255 -217.878406)
			(xy 116.922904 -217.855066) (xy 116.92901 -217.808787) (xy 116.941117 -217.763705) (xy 116.949728 -217.742008)
			(xy 116.95938 -217.71864) (xy 116.787676 -217.421206) (xy 116.762784 -217.417904) (xy 116.737355 -217.414138)
			(xy 116.687865 -217.400236) (xy 116.640884 -217.37937) (xy 116.597388 -217.351973) (xy 116.558278 -217.318613)
			(xy 116.524365 -217.279981) (xy 116.496352 -217.236879) (xy 116.474819 -217.1902) (xy 116.460215 -217.140913)
			(xy 116.452841 -217.090039) (xy 116.452396 -217.064336) (xy 115.286028 -217.064336) (xy 115.286028 -217.064844)
			(xy 115.285621 -217.088045) (xy 115.279564 -217.134052) (xy 115.267598 -217.178886) (xy 115.259104 -217.20048)
			(xy 115.249452 -217.223594) (xy 115.421664 -217.521536) (xy 115.446556 -217.524838) (xy 115.471935 -217.528682)
			(xy 115.521316 -217.542687) (xy 115.568181 -217.563624) (xy 115.611562 -217.59106) (xy 115.650563 -217.62443)
			(xy 115.684379 -217.663045) (xy 115.712313 -217.706107) (xy 115.733788 -217.752728) (xy 115.74836 -217.801945)
			(xy 115.755729 -217.852742) (xy 115.756182 -217.878406) (xy 115.755683 -217.905093) (xy 115.747728 -217.957872)
			(xy 115.731996 -218.008875) (xy 115.708838 -218.056964) (xy 115.678771 -218.101064) (xy 115.642467 -218.140191)
			(xy 115.600737 -218.173469) (xy 115.554513 -218.200156) (xy 115.504828 -218.219656) (xy 115.452791 -218.231533)
			(xy 115.399566 -218.235522) (xy 115.346341 -218.231533) (xy 115.294304 -218.219656) (xy 115.244619 -218.200156)
			(xy 115.198395 -218.173469) (xy 115.156665 -218.140191) (xy 115.120361 -218.101064) (xy 115.090294 -218.056964)
			(xy 115.067136 -218.008875) (xy 115.051404 -217.957872) (xy 115.043449 -217.905093) (xy 115.04295 -217.878406)
			(xy 115.043304 -217.855066) (xy 115.04941 -217.808787) (xy 115.061517 -217.763705) (xy 115.070128 -217.742008)
			(xy 115.07978 -217.71864) (xy 114.908076 -217.421206) (xy 114.883184 -217.417904) (xy 114.857755 -217.414138)
			(xy 114.808265 -217.400236) (xy 114.761284 -217.37937) (xy 114.717788 -217.351973) (xy 114.678678 -217.318613)
			(xy 114.644765 -217.279981) (xy 114.616752 -217.236879) (xy 114.595219 -217.1902) (xy 114.580615 -217.140913)
			(xy 114.573241 -217.090039) (xy 114.572796 -217.064336) (xy 113.406428 -217.064336) (xy 113.406428 -217.064844)
			(xy 113.406021 -217.088045) (xy 113.399964 -217.134052) (xy 113.387998 -217.178886) (xy 113.379504 -217.20048)
			(xy 113.369852 -217.223594) (xy 113.542064 -217.521536) (xy 113.566956 -217.524838) (xy 113.592335 -217.528682)
			(xy 113.641716 -217.542687) (xy 113.688581 -217.563624) (xy 113.731962 -217.59106) (xy 113.770963 -217.62443)
			(xy 113.804779 -217.663045) (xy 113.832713 -217.706107) (xy 113.854188 -217.752728) (xy 113.86876 -217.801945)
			(xy 113.876129 -217.852742) (xy 113.876582 -217.878406) (xy 113.876083 -217.905093) (xy 113.868128 -217.957872)
			(xy 113.852396 -218.008875) (xy 113.829238 -218.056964) (xy 113.799171 -218.101064) (xy 113.762867 -218.140191)
			(xy 113.721137 -218.173469) (xy 113.674913 -218.200156) (xy 113.625228 -218.219656) (xy 113.573191 -218.231533)
			(xy 113.519966 -218.235522) (xy 113.466741 -218.231533) (xy 113.414704 -218.219656) (xy 113.365019 -218.200156)
			(xy 113.318795 -218.173469) (xy 113.277065 -218.140191) (xy 113.240761 -218.101064) (xy 113.210694 -218.056964)
			(xy 113.187536 -218.008875) (xy 113.171804 -217.957872) (xy 113.163849 -217.905093) (xy 113.16335 -217.878406)
			(xy 113.163704 -217.855066) (xy 113.16981 -217.808787) (xy 113.181917 -217.763705) (xy 113.190528 -217.742008)
			(xy 113.20018 -217.71864) (xy 113.028476 -217.421206) (xy 113.003584 -217.417904) (xy 112.978155 -217.414138)
			(xy 112.928665 -217.400236) (xy 112.881684 -217.37937) (xy 112.838188 -217.351973) (xy 112.799078 -217.318613)
			(xy 112.765165 -217.279981) (xy 112.737152 -217.236879) (xy 112.715619 -217.1902) (xy 112.701015 -217.140913)
			(xy 112.693641 -217.090039) (xy 112.693196 -217.064336) (xy 111.527082 -217.064336) (xy 111.526633 -217.090015)
			(xy 111.519274 -217.140843) (xy 111.504699 -217.190089) (xy 111.483209 -217.236735) (xy 111.45525 -217.279815)
			(xy 111.4214 -217.318439) (xy 111.382359 -217.351806) (xy 111.338934 -217.379228) (xy 111.292025 -217.400135)
			(xy 111.242601 -217.414097) (xy 111.217202 -217.417904) (xy 111.19231 -217.421206) (xy 111.020352 -217.71864)
			(xy 111.030004 -217.742008) (xy 111.038569 -217.76372) (xy 111.050657 -217.8088) (xy 111.056779 -217.85507)
			(xy 111.057182 -217.878406) (xy 111.056683 -217.905093) (xy 111.048728 -217.957872) (xy 111.032996 -218.008875)
			(xy 111.009838 -218.056964) (xy 110.979771 -218.101064) (xy 110.943467 -218.140191) (xy 110.901737 -218.173469)
			(xy 110.855513 -218.200156) (xy 110.805828 -218.219656) (xy 110.753791 -218.231533) (xy 110.700566 -218.235522)
			(xy 110.647341 -218.231533) (xy 110.595304 -218.219656) (xy 110.545619 -218.200156) (xy 110.499395 -218.173469)
			(xy 110.457665 -218.140191) (xy 110.421361 -218.101064) (xy 110.391294 -218.056964) (xy 110.368136 -218.008875)
			(xy 110.352404 -217.957872) (xy 110.344449 -217.905093) (xy 110.34395 -217.878406) (xy 110.117382 -217.878406)
			(xy 110.117382 -217.878914) (xy 110.116993 -217.902116) (xy 110.110928 -217.948123) (xy 110.098955 -217.992956)
			(xy 110.090458 -218.01455) (xy 110.080806 -218.037664) (xy 110.252764 -218.335352) (xy 110.277656 -218.338654)
			(xy 110.303038 -218.342483) (xy 110.35242 -218.356488) (xy 110.399286 -218.377426) (xy 110.442667 -218.404865)
			(xy 110.481669 -218.438236) (xy 110.515485 -218.476853) (xy 110.543419 -218.519917) (xy 110.564892 -218.566539)
			(xy 110.579463 -218.615758) (xy 110.58683 -218.666557) (xy 110.587282 -218.692222) (xy 111.753396 -218.692222)
			(xy 111.753797 -218.666552) (xy 111.761144 -218.615739) (xy 111.775702 -218.566506) (xy 111.797172 -218.519871)
			(xy 111.825108 -218.476796) (xy 111.858934 -218.438175) (xy 111.89795 -218.404804) (xy 111.941349 -218.377374)
			(xy 111.988233 -218.356453) (xy 112.037633 -218.342472) (xy 112.063022 -218.338654) (xy 112.087914 -218.335352)
			(xy 112.260126 -218.037664) (xy 112.250474 -218.01455) (xy 112.241972 -217.992958) (xy 112.229993 -217.948125)
			(xy 112.223938 -217.902116) (xy 112.22355 -217.878914) (xy 112.22355 -217.878406) (xy 112.224049 -217.851719)
			(xy 112.232004 -217.79894) (xy 112.247736 -217.747937) (xy 112.270894 -217.699848) (xy 112.300961 -217.655748)
			(xy 112.337265 -217.616621) (xy 112.378995 -217.583343) (xy 112.425219 -217.556656) (xy 112.474904 -217.537156)
			(xy 112.526941 -217.525279) (xy 112.580166 -217.52129) (xy 112.633391 -217.525279) (xy 112.685428 -217.537156)
			(xy 112.735113 -217.556656) (xy 112.781337 -217.583343) (xy 112.823067 -217.616621) (xy 112.859371 -217.655748)
			(xy 112.889438 -217.699848) (xy 112.912596 -217.747937) (xy 112.928328 -217.79894) (xy 112.936283 -217.851719)
			(xy 112.936782 -217.878406) (xy 112.936301 -217.904116) (xy 112.928901 -217.955001) (xy 112.914271 -218.004297)
			(xy 112.892713 -218.05098) (xy 112.864675 -218.094083) (xy 112.830737 -218.132714) (xy 112.791604 -218.16607)
			(xy 112.748086 -218.193461) (xy 112.701086 -218.214318) (xy 112.651577 -218.228209) (xy 112.62614 -218.231974)
			(xy 112.601248 -218.235276) (xy 112.429798 -218.532456) (xy 112.43945 -218.55557) (xy 112.448031 -218.577276)
			(xy 112.460113 -218.622359) (xy 112.466228 -218.668631) (xy 112.466628 -218.691968) (xy 112.466628 -218.692222)
			(xy 113.63325 -218.692222) (xy 113.633691 -218.666553) (xy 113.641036 -218.615745) (xy 113.655592 -218.566515)
			(xy 113.677059 -218.519882) (xy 113.704991 -218.476809) (xy 113.738812 -218.438188) (xy 113.777822 -218.404816)
			(xy 113.821216 -218.377385) (xy 113.868095 -218.35646) (xy 113.91749 -218.342475) (xy 113.942876 -218.338654)
			(xy 113.967768 -218.335352) (xy 114.139726 -218.037664) (xy 114.130074 -218.01455) (xy 114.121572 -217.992958)
			(xy 114.109593 -217.948125) (xy 114.103538 -217.902116) (xy 114.10315 -217.878914) (xy 114.10315 -217.878406)
			(xy 114.103649 -217.851719) (xy 114.111604 -217.79894) (xy 114.127336 -217.747937) (xy 114.150494 -217.699848)
			(xy 114.180561 -217.655748) (xy 114.216865 -217.616621) (xy 114.258595 -217.583343) (xy 114.304819 -217.556656)
			(xy 114.354504 -217.537156) (xy 114.406541 -217.525279) (xy 114.459766 -217.52129) (xy 114.512991 -217.525279)
			(xy 114.565028 -217.537156) (xy 114.614713 -217.556656) (xy 114.660937 -217.583343) (xy 114.702667 -217.616621)
			(xy 114.738971 -217.655748) (xy 114.769038 -217.699848) (xy 114.792196 -217.747937) (xy 114.807928 -217.79894)
			(xy 114.815883 -217.851719) (xy 114.816382 -217.878406) (xy 114.815963 -217.904097) (xy 114.808588 -217.954947)
			(xy 114.793991 -218.004212) (xy 114.772475 -218.050872) (xy 114.744485 -218.093962) (xy 114.710601 -218.132588)
			(xy 114.671524 -218.165951) (xy 114.628063 -218.19336) (xy 114.581118 -218.214249) (xy 114.531662 -218.228183)
			(xy 114.506248 -218.231974) (xy 114.481356 -218.235276) (xy 114.309652 -218.532456) (xy 114.319304 -218.555824)
			(xy 114.327873 -218.577534) (xy 114.33996 -218.622615) (xy 114.34608 -218.668886) (xy 114.346482 -218.692222)
			(xy 115.512596 -218.692222) (xy 115.512997 -218.666552) (xy 115.520344 -218.615739) (xy 115.534902 -218.566506)
			(xy 115.556372 -218.519871) (xy 115.584308 -218.476796) (xy 115.618134 -218.438175) (xy 115.65715 -218.404804)
			(xy 115.700549 -218.377374) (xy 115.747433 -218.356453) (xy 115.796833 -218.342472) (xy 115.822222 -218.338654)
			(xy 115.847114 -218.335352) (xy 116.019326 -218.037664) (xy 116.009674 -218.01455) (xy 116.001172 -217.992958)
			(xy 115.989193 -217.948125) (xy 115.983138 -217.902116) (xy 115.98275 -217.878914) (xy 115.98275 -217.878406)
			(xy 115.983249 -217.851719) (xy 115.991204 -217.79894) (xy 116.006936 -217.747937) (xy 116.030094 -217.699848)
			(xy 116.060161 -217.655748) (xy 116.096465 -217.616621) (xy 116.138195 -217.583343) (xy 116.184419 -217.556656)
			(xy 116.234104 -217.537156) (xy 116.286141 -217.525279) (xy 116.339366 -217.52129) (xy 116.392591 -217.525279)
			(xy 116.444628 -217.537156) (xy 116.494313 -217.556656) (xy 116.540537 -217.583343) (xy 116.582267 -217.616621)
			(xy 116.618571 -217.655748) (xy 116.648638 -217.699848) (xy 116.671796 -217.747937) (xy 116.687528 -217.79894)
			(xy 116.695483 -217.851719) (xy 116.695982 -217.878406) (xy 116.695501 -217.904116) (xy 116.688101 -217.955001)
			(xy 116.673471 -218.004297) (xy 116.651913 -218.05098) (xy 116.623875 -218.094083) (xy 116.589937 -218.132714)
			(xy 116.550804 -218.16607) (xy 116.507286 -218.193461) (xy 116.460286 -218.214318) (xy 116.410777 -218.228209)
			(xy 116.38534 -218.231974) (xy 116.360448 -218.235276) (xy 116.188998 -218.532456) (xy 116.19865 -218.55557)
			(xy 116.207231 -218.577276) (xy 116.219313 -218.622359) (xy 116.225428 -218.668631) (xy 116.225828 -218.691968)
			(xy 116.225828 -218.692222) (xy 117.392196 -218.692222) (xy 117.392597 -218.666552) (xy 117.399944 -218.615739)
			(xy 117.414502 -218.566506) (xy 117.435972 -218.519871) (xy 117.463908 -218.476796) (xy 117.497734 -218.438175)
			(xy 117.53675 -218.404804) (xy 117.580149 -218.377374) (xy 117.627033 -218.356453) (xy 117.676433 -218.342472)
			(xy 117.701822 -218.338654) (xy 117.726714 -218.335352) (xy 117.898926 -218.037664) (xy 117.889274 -218.01455)
			(xy 117.880772 -217.992958) (xy 117.868793 -217.948125) (xy 117.862738 -217.902116) (xy 117.86235 -217.878914)
			(xy 117.86235 -217.878406) (xy 117.862849 -217.851719) (xy 117.870804 -217.79894) (xy 117.886536 -217.747937)
			(xy 117.909694 -217.699848) (xy 117.939761 -217.655748) (xy 117.976065 -217.616621) (xy 118.017795 -217.583343)
			(xy 118.064019 -217.556656) (xy 118.113704 -217.537156) (xy 118.165741 -217.525279) (xy 118.218966 -217.52129)
			(xy 118.272191 -217.525279) (xy 118.324228 -217.537156) (xy 118.373913 -217.556656) (xy 118.420137 -217.583343)
			(xy 118.461867 -217.616621) (xy 118.498171 -217.655748) (xy 118.528238 -217.699848) (xy 118.551396 -217.747937)
			(xy 118.567128 -217.79894) (xy 118.575083 -217.851719) (xy 118.575582 -217.878406) (xy 118.575101 -217.904116)
			(xy 118.567701 -217.955001) (xy 118.553071 -218.004297) (xy 118.531513 -218.05098) (xy 118.503475 -218.094083)
			(xy 118.469537 -218.132714) (xy 118.430404 -218.16607) (xy 118.386886 -218.193461) (xy 118.339886 -218.214318)
			(xy 118.290377 -218.228209) (xy 118.26494 -218.231974) (xy 118.240048 -218.235276) (xy 118.068598 -218.532456)
			(xy 118.07825 -218.55557) (xy 118.086831 -218.577276) (xy 118.098913 -218.622359) (xy 118.105028 -218.668631)
			(xy 118.105428 -218.691968) (xy 118.105428 -218.692222) (xy 119.271796 -218.692222) (xy 119.272197 -218.666552)
			(xy 119.279544 -218.615739) (xy 119.294102 -218.566506) (xy 119.315572 -218.519871) (xy 119.343508 -218.476796)
			(xy 119.377334 -218.438175) (xy 119.41635 -218.404804) (xy 119.459749 -218.377374) (xy 119.506633 -218.356453)
			(xy 119.556033 -218.342472) (xy 119.581422 -218.338654) (xy 119.606314 -218.335352) (xy 119.778526 -218.037664)
			(xy 119.768874 -218.01455) (xy 119.760372 -217.992958) (xy 119.748393 -217.948125) (xy 119.742338 -217.902116)
			(xy 119.74195 -217.878914) (xy 119.74195 -217.878406) (xy 119.742449 -217.851719) (xy 119.750404 -217.79894)
			(xy 119.766136 -217.747937) (xy 119.789294 -217.699848) (xy 119.819361 -217.655748) (xy 119.855665 -217.616621)
			(xy 119.897395 -217.583343) (xy 119.943619 -217.556656) (xy 119.993304 -217.537156) (xy 120.045341 -217.525279)
			(xy 120.098566 -217.52129) (xy 120.151791 -217.525279) (xy 120.203828 -217.537156) (xy 120.253513 -217.556656)
			(xy 120.299737 -217.583343) (xy 120.341467 -217.616621) (xy 120.377771 -217.655748) (xy 120.407838 -217.699848)
			(xy 120.430996 -217.747937) (xy 120.446728 -217.79894) (xy 120.454683 -217.851719) (xy 120.455182 -217.878406)
			(xy 120.454701 -217.904116) (xy 120.447301 -217.955001) (xy 120.432671 -218.004297) (xy 120.411113 -218.05098)
			(xy 120.383075 -218.094083) (xy 120.349137 -218.132714) (xy 120.310004 -218.16607) (xy 120.266486 -218.193461)
			(xy 120.219486 -218.214318) (xy 120.169977 -218.228209) (xy 120.14454 -218.231974) (xy 120.119648 -218.235276)
			(xy 119.948198 -218.532456) (xy 119.95785 -218.55557) (xy 119.966431 -218.577276) (xy 119.978513 -218.622359)
			(xy 119.984628 -218.668631) (xy 119.985028 -218.691968) (xy 119.985028 -218.692222) (xy 121.151396 -218.692222)
			(xy 121.151797 -218.666552) (xy 121.159144 -218.615739) (xy 121.173702 -218.566506) (xy 121.195172 -218.519871)
			(xy 121.223108 -218.476796) (xy 121.256934 -218.438175) (xy 121.29595 -218.404804) (xy 121.339349 -218.377374)
			(xy 121.386233 -218.356453) (xy 121.435633 -218.342472) (xy 121.461022 -218.338654) (xy 121.485914 -218.335352)
			(xy 121.658126 -218.037664) (xy 121.648474 -218.01455) (xy 121.639972 -217.992958) (xy 121.627993 -217.948125)
			(xy 121.621938 -217.902116) (xy 121.62155 -217.878914) (xy 121.62155 -217.878406) (xy 121.622049 -217.851719)
			(xy 121.630004 -217.79894) (xy 121.645736 -217.747937) (xy 121.668894 -217.699848) (xy 121.698961 -217.655748)
			(xy 121.735265 -217.616621) (xy 121.776995 -217.583343) (xy 121.823219 -217.556656) (xy 121.872904 -217.537156)
			(xy 121.924941 -217.525279) (xy 121.978166 -217.52129) (xy 122.031391 -217.525279) (xy 122.083428 -217.537156)
			(xy 122.133113 -217.556656) (xy 122.179337 -217.583343) (xy 122.221067 -217.616621) (xy 122.257371 -217.655748)
			(xy 122.287438 -217.699848) (xy 122.310596 -217.747937) (xy 122.326328 -217.79894) (xy 122.334283 -217.851719)
			(xy 122.334782 -217.878406) (xy 122.334301 -217.904116) (xy 122.326901 -217.955001) (xy 122.312271 -218.004297)
			(xy 122.290713 -218.05098) (xy 122.262675 -218.094083) (xy 122.228737 -218.132714) (xy 122.189604 -218.16607)
			(xy 122.146086 -218.193461) (xy 122.099086 -218.214318) (xy 122.049577 -218.228209) (xy 122.02414 -218.231974)
			(xy 121.999248 -218.235276) (xy 121.827798 -218.532456) (xy 121.83745 -218.55557) (xy 121.846031 -218.577276)
			(xy 121.858113 -218.622359) (xy 121.864228 -218.668631) (xy 121.864628 -218.691968) (xy 121.864628 -218.692222)
			(xy 123.030996 -218.692222) (xy 123.031397 -218.666552) (xy 123.038744 -218.615739) (xy 123.053302 -218.566506)
			(xy 123.074772 -218.519871) (xy 123.102708 -218.476796) (xy 123.136534 -218.438175) (xy 123.17555 -218.404804)
			(xy 123.218949 -218.377374) (xy 123.265833 -218.356453) (xy 123.315233 -218.342472) (xy 123.340622 -218.338654)
			(xy 123.365514 -218.335352) (xy 123.537726 -218.037664) (xy 123.528074 -218.01455) (xy 123.519572 -217.992958)
			(xy 123.507593 -217.948125) (xy 123.501538 -217.902116) (xy 123.50115 -217.878914) (xy 123.50115 -217.878406)
			(xy 123.501649 -217.851719) (xy 123.509604 -217.79894) (xy 123.525336 -217.747937) (xy 123.548494 -217.699848)
			(xy 123.578561 -217.655748) (xy 123.614865 -217.616621) (xy 123.656595 -217.583343) (xy 123.702819 -217.556656)
			(xy 123.752504 -217.537156) (xy 123.804541 -217.525279) (xy 123.857766 -217.52129) (xy 123.910991 -217.525279)
			(xy 123.963028 -217.537156) (xy 124.012713 -217.556656) (xy 124.058937 -217.583343) (xy 124.100667 -217.616621)
			(xy 124.136971 -217.655748) (xy 124.167038 -217.699848) (xy 124.190196 -217.747937) (xy 124.205928 -217.79894)
			(xy 124.213883 -217.851719) (xy 124.214382 -217.878406) (xy 124.213901 -217.904116) (xy 124.206501 -217.955001)
			(xy 124.191871 -218.004297) (xy 124.170313 -218.05098) (xy 124.142275 -218.094083) (xy 124.108337 -218.132714)
			(xy 124.069204 -218.16607) (xy 124.025686 -218.193461) (xy 123.978686 -218.214318) (xy 123.929177 -218.228209)
			(xy 123.90374 -218.231974) (xy 123.878848 -218.235276) (xy 123.707398 -218.532456) (xy 123.71705 -218.55557)
			(xy 123.725631 -218.577276) (xy 123.737713 -218.622359) (xy 123.743828 -218.668631) (xy 123.744228 -218.691968)
			(xy 123.744228 -218.692222) (xy 124.910596 -218.692222) (xy 124.910997 -218.666552) (xy 124.918344 -218.615739)
			(xy 124.932902 -218.566506) (xy 124.954372 -218.519871) (xy 124.982308 -218.476796) (xy 125.016134 -218.438175)
			(xy 125.05515 -218.404804) (xy 125.098549 -218.377374) (xy 125.145433 -218.356453) (xy 125.194833 -218.342472)
			(xy 125.220222 -218.338654) (xy 125.245114 -218.335352) (xy 125.417326 -218.037664) (xy 125.407674 -218.01455)
			(xy 125.399172 -217.992958) (xy 125.387193 -217.948125) (xy 125.381138 -217.902116) (xy 125.38075 -217.878914)
			(xy 125.38075 -217.878406) (xy 125.381249 -217.851719) (xy 125.389204 -217.79894) (xy 125.404936 -217.747937)
			(xy 125.428094 -217.699848) (xy 125.458161 -217.655748) (xy 125.494465 -217.616621) (xy 125.536195 -217.583343)
			(xy 125.582419 -217.556656) (xy 125.632104 -217.537156) (xy 125.684141 -217.525279) (xy 125.737366 -217.52129)
			(xy 125.790591 -217.525279) (xy 125.842628 -217.537156) (xy 125.892313 -217.556656) (xy 125.938537 -217.583343)
			(xy 125.980267 -217.616621) (xy 126.016571 -217.655748) (xy 126.046638 -217.699848) (xy 126.069796 -217.747937)
			(xy 126.085528 -217.79894) (xy 126.093483 -217.851719) (xy 126.093982 -217.878406) (xy 126.093501 -217.904116)
			(xy 126.086101 -217.955001) (xy 126.071471 -218.004297) (xy 126.049913 -218.05098) (xy 126.021875 -218.094083)
			(xy 125.987937 -218.132714) (xy 125.948804 -218.16607) (xy 125.905286 -218.193461) (xy 125.858286 -218.214318)
			(xy 125.808777 -218.228209) (xy 125.78334 -218.231974) (xy 125.758448 -218.235276) (xy 125.586998 -218.532456)
			(xy 125.59665 -218.55557) (xy 125.605231 -218.577276) (xy 125.617313 -218.622359) (xy 125.623428 -218.668631)
			(xy 125.623828 -218.691968) (xy 125.623828 -218.692222) (xy 126.790196 -218.692222) (xy 126.790597 -218.666552)
			(xy 126.797944 -218.615739) (xy 126.812502 -218.566506) (xy 126.833972 -218.519871) (xy 126.861908 -218.476796)
			(xy 126.895734 -218.438175) (xy 126.93475 -218.404804) (xy 126.978149 -218.377374) (xy 127.025033 -218.356453)
			(xy 127.074433 -218.342472) (xy 127.099822 -218.338654) (xy 127.124714 -218.335352) (xy 127.296926 -218.037664)
			(xy 127.287274 -218.01455) (xy 127.278772 -217.992958) (xy 127.266793 -217.948125) (xy 127.260738 -217.902116)
			(xy 127.26035 -217.878914) (xy 127.26035 -217.878406) (xy 127.260849 -217.851719) (xy 127.268804 -217.79894)
			(xy 127.284536 -217.747937) (xy 127.307694 -217.699848) (xy 127.337761 -217.655748) (xy 127.374065 -217.616621)
			(xy 127.415795 -217.583343) (xy 127.462019 -217.556656) (xy 127.511704 -217.537156) (xy 127.563741 -217.525279)
			(xy 127.616966 -217.52129) (xy 127.670191 -217.525279) (xy 127.722228 -217.537156) (xy 127.771913 -217.556656)
			(xy 127.818137 -217.583343) (xy 127.859867 -217.616621) (xy 127.896171 -217.655748) (xy 127.926238 -217.699848)
			(xy 127.949396 -217.747937) (xy 127.965128 -217.79894) (xy 127.973083 -217.851719) (xy 127.973582 -217.878406)
			(xy 127.973101 -217.904116) (xy 127.965701 -217.955001) (xy 127.951071 -218.004297) (xy 127.929513 -218.05098)
			(xy 127.901475 -218.094083) (xy 127.867537 -218.132714) (xy 127.828404 -218.16607) (xy 127.784886 -218.193461)
			(xy 127.737886 -218.214318) (xy 127.688377 -218.228209) (xy 127.66294 -218.231974) (xy 127.638048 -218.235276)
			(xy 127.466598 -218.532456) (xy 127.47625 -218.55557) (xy 127.484831 -218.577276) (xy 127.496913 -218.622359)
			(xy 127.503028 -218.668631) (xy 127.503428 -218.691968) (xy 127.503428 -218.692222) (xy 128.669796 -218.692222)
			(xy 128.670197 -218.666552) (xy 128.677544 -218.615739) (xy 128.692102 -218.566506) (xy 128.713572 -218.519871)
			(xy 128.741508 -218.476796) (xy 128.775334 -218.438175) (xy 128.81435 -218.404804) (xy 128.857749 -218.377374)
			(xy 128.904633 -218.356453) (xy 128.954033 -218.342472) (xy 128.979422 -218.338654) (xy 129.004314 -218.335352)
			(xy 129.176526 -218.037664) (xy 129.166874 -218.01455) (xy 129.158372 -217.992958) (xy 129.146393 -217.948125)
			(xy 129.140338 -217.902116) (xy 129.13995 -217.878914) (xy 129.13995 -217.878406) (xy 129.140449 -217.851719)
			(xy 129.148404 -217.79894) (xy 129.164136 -217.747937) (xy 129.187294 -217.699848) (xy 129.217361 -217.655748)
			(xy 129.253665 -217.616621) (xy 129.295395 -217.583343) (xy 129.341619 -217.556656) (xy 129.391304 -217.537156)
			(xy 129.443341 -217.525279) (xy 129.496566 -217.52129) (xy 129.549791 -217.525279) (xy 129.601828 -217.537156)
			(xy 129.651513 -217.556656) (xy 129.697737 -217.583343) (xy 129.739467 -217.616621) (xy 129.775771 -217.655748)
			(xy 129.805838 -217.699848) (xy 129.828996 -217.747937) (xy 129.844728 -217.79894) (xy 129.852683 -217.851719)
			(xy 129.853182 -217.878406) (xy 129.852701 -217.904116) (xy 129.845301 -217.955001) (xy 129.830671 -218.004297)
			(xy 129.809113 -218.05098) (xy 129.781075 -218.094083) (xy 129.747137 -218.132714) (xy 129.708004 -218.16607)
			(xy 129.664486 -218.193461) (xy 129.617486 -218.214318) (xy 129.567977 -218.228209) (xy 129.54254 -218.231974)
			(xy 129.517648 -218.235276) (xy 129.346198 -218.532456) (xy 129.35585 -218.55557) (xy 129.364431 -218.577276)
			(xy 129.376513 -218.622359) (xy 129.382628 -218.668631) (xy 129.383028 -218.691968) (xy 129.383028 -218.692222)
			(xy 130.549396 -218.692222) (xy 130.549797 -218.666552) (xy 130.557144 -218.615739) (xy 130.571702 -218.566506)
			(xy 130.593172 -218.519871) (xy 130.621108 -218.476796) (xy 130.654934 -218.438175) (xy 130.69395 -218.404804)
			(xy 130.737349 -218.377374) (xy 130.784233 -218.356453) (xy 130.833633 -218.342472) (xy 130.859022 -218.338654)
			(xy 130.883914 -218.335352) (xy 131.056126 -218.037664) (xy 131.046474 -218.01455) (xy 131.037972 -217.992958)
			(xy 131.025993 -217.948125) (xy 131.019938 -217.902116) (xy 131.01955 -217.878914) (xy 131.01955 -217.878406)
			(xy 131.020049 -217.851719) (xy 131.028004 -217.79894) (xy 131.043736 -217.747937) (xy 131.066894 -217.699848)
			(xy 131.096961 -217.655748) (xy 131.133265 -217.616621) (xy 131.174995 -217.583343) (xy 131.221219 -217.556656)
			(xy 131.270904 -217.537156) (xy 131.322941 -217.525279) (xy 131.376166 -217.52129) (xy 131.429391 -217.525279)
			(xy 131.481428 -217.537156) (xy 131.531113 -217.556656) (xy 131.577337 -217.583343) (xy 131.619067 -217.616621)
			(xy 131.655371 -217.655748) (xy 131.685438 -217.699848) (xy 131.708596 -217.747937) (xy 131.724328 -217.79894)
			(xy 131.732283 -217.851719) (xy 131.732782 -217.878406) (xy 131.732301 -217.904116) (xy 131.724901 -217.955001)
			(xy 131.710271 -218.004297) (xy 131.688713 -218.05098) (xy 131.660675 -218.094083) (xy 131.626737 -218.132714)
			(xy 131.587604 -218.16607) (xy 131.544086 -218.193461) (xy 131.497086 -218.214318) (xy 131.447577 -218.228209)
			(xy 131.42214 -218.231974) (xy 131.397248 -218.235276) (xy 131.225798 -218.532456) (xy 131.23545 -218.55557)
			(xy 131.244031 -218.577276) (xy 131.256113 -218.622359) (xy 131.262228 -218.668631) (xy 131.262628 -218.691968)
			(xy 131.262628 -218.692222) (xy 132.428996 -218.692222) (xy 132.429397 -218.666552) (xy 132.436744 -218.615739)
			(xy 132.451302 -218.566506) (xy 132.472772 -218.519871) (xy 132.500708 -218.476796) (xy 132.534534 -218.438175)
			(xy 132.57355 -218.404804) (xy 132.616949 -218.377374) (xy 132.663833 -218.356453) (xy 132.713233 -218.342472)
			(xy 132.738622 -218.338654) (xy 132.763514 -218.335352) (xy 132.935726 -218.037664) (xy 132.926074 -218.01455)
			(xy 132.917572 -217.992958) (xy 132.905593 -217.948125) (xy 132.899538 -217.902116) (xy 132.89915 -217.878914)
			(xy 132.89915 -217.878406) (xy 132.899649 -217.851719) (xy 132.907604 -217.79894) (xy 132.923336 -217.747937)
			(xy 132.946494 -217.699848) (xy 132.976561 -217.655748) (xy 133.012865 -217.616621) (xy 133.054595 -217.583343)
			(xy 133.100819 -217.556656) (xy 133.150504 -217.537156) (xy 133.202541 -217.525279) (xy 133.255766 -217.52129)
			(xy 133.308991 -217.525279) (xy 133.361028 -217.537156) (xy 133.410713 -217.556656) (xy 133.456937 -217.583343)
			(xy 133.498667 -217.616621) (xy 133.534971 -217.655748) (xy 133.565038 -217.699848) (xy 133.588196 -217.747937)
			(xy 133.603928 -217.79894) (xy 133.611883 -217.851719) (xy 133.612382 -217.878406) (xy 133.611901 -217.904116)
			(xy 133.604501 -217.955001) (xy 133.589871 -218.004297) (xy 133.568313 -218.05098) (xy 133.540275 -218.094083)
			(xy 133.506337 -218.132714) (xy 133.467204 -218.16607) (xy 133.423686 -218.193461) (xy 133.376686 -218.214318)
			(xy 133.327177 -218.228209) (xy 133.30174 -218.231974) (xy 133.276848 -218.235276) (xy 133.105398 -218.532456)
			(xy 133.11505 -218.55557) (xy 133.123631 -218.577276) (xy 133.135713 -218.622359) (xy 133.141828 -218.668631)
			(xy 133.142228 -218.691968) (xy 133.142228 -218.692222) (xy 133.141729 -218.718909) (xy 133.133774 -218.771688)
			(xy 133.118042 -218.822691) (xy 133.094884 -218.87078) (xy 133.064817 -218.91488) (xy 133.028513 -218.954007)
			(xy 132.986783 -218.987285) (xy 132.940559 -219.013972) (xy 132.890874 -219.033472) (xy 132.838837 -219.045349)
			(xy 132.785612 -219.049338) (xy 132.732387 -219.045349) (xy 132.68035 -219.033472) (xy 132.630665 -219.013972)
			(xy 132.584441 -218.987285) (xy 132.542711 -218.954007) (xy 132.506407 -218.91488) (xy 132.47634 -218.87078)
			(xy 132.453182 -218.822691) (xy 132.43745 -218.771688) (xy 132.429495 -218.718909) (xy 132.428996 -218.692222)
			(xy 131.262628 -218.692222) (xy 131.262129 -218.718909) (xy 131.254174 -218.771688) (xy 131.238442 -218.822691)
			(xy 131.215284 -218.87078) (xy 131.185217 -218.91488) (xy 131.148913 -218.954007) (xy 131.107183 -218.987285)
			(xy 131.060959 -219.013972) (xy 131.011274 -219.033472) (xy 130.959237 -219.045349) (xy 130.906012 -219.049338)
			(xy 130.852787 -219.045349) (xy 130.80075 -219.033472) (xy 130.751065 -219.013972) (xy 130.704841 -218.987285)
			(xy 130.663111 -218.954007) (xy 130.626807 -218.91488) (xy 130.59674 -218.87078) (xy 130.573582 -218.822691)
			(xy 130.55785 -218.771688) (xy 130.549895 -218.718909) (xy 130.549396 -218.692222) (xy 129.383028 -218.692222)
			(xy 129.382529 -218.718909) (xy 129.374574 -218.771688) (xy 129.358842 -218.822691) (xy 129.335684 -218.87078)
			(xy 129.305617 -218.91488) (xy 129.269313 -218.954007) (xy 129.227583 -218.987285) (xy 129.181359 -219.013972)
			(xy 129.131674 -219.033472) (xy 129.079637 -219.045349) (xy 129.026412 -219.049338) (xy 128.973187 -219.045349)
			(xy 128.92115 -219.033472) (xy 128.871465 -219.013972) (xy 128.825241 -218.987285) (xy 128.783511 -218.954007)
			(xy 128.747207 -218.91488) (xy 128.71714 -218.87078) (xy 128.693982 -218.822691) (xy 128.67825 -218.771688)
			(xy 128.670295 -218.718909) (xy 128.669796 -218.692222) (xy 127.503428 -218.692222) (xy 127.502929 -218.718909)
			(xy 127.494974 -218.771688) (xy 127.479242 -218.822691) (xy 127.456084 -218.87078) (xy 127.426017 -218.91488)
			(xy 127.389713 -218.954007) (xy 127.347983 -218.987285) (xy 127.301759 -219.013972) (xy 127.252074 -219.033472)
			(xy 127.200037 -219.045349) (xy 127.146812 -219.049338) (xy 127.093587 -219.045349) (xy 127.04155 -219.033472)
			(xy 126.991865 -219.013972) (xy 126.945641 -218.987285) (xy 126.903911 -218.954007) (xy 126.867607 -218.91488)
			(xy 126.83754 -218.87078) (xy 126.814382 -218.822691) (xy 126.79865 -218.771688) (xy 126.790695 -218.718909)
			(xy 126.790196 -218.692222) (xy 125.623828 -218.692222) (xy 125.623329 -218.718909) (xy 125.615374 -218.771688)
			(xy 125.599642 -218.822691) (xy 125.576484 -218.87078) (xy 125.546417 -218.91488) (xy 125.510113 -218.954007)
			(xy 125.468383 -218.987285) (xy 125.422159 -219.013972) (xy 125.372474 -219.033472) (xy 125.320437 -219.045349)
			(xy 125.267212 -219.049338) (xy 125.213987 -219.045349) (xy 125.16195 -219.033472) (xy 125.112265 -219.013972)
			(xy 125.066041 -218.987285) (xy 125.024311 -218.954007) (xy 124.988007 -218.91488) (xy 124.95794 -218.87078)
			(xy 124.934782 -218.822691) (xy 124.91905 -218.771688) (xy 124.911095 -218.718909) (xy 124.910596 -218.692222)
			(xy 123.744228 -218.692222) (xy 123.743729 -218.718909) (xy 123.735774 -218.771688) (xy 123.720042 -218.822691)
			(xy 123.696884 -218.87078) (xy 123.666817 -218.91488) (xy 123.630513 -218.954007) (xy 123.588783 -218.987285)
			(xy 123.542559 -219.013972) (xy 123.492874 -219.033472) (xy 123.440837 -219.045349) (xy 123.387612 -219.049338)
			(xy 123.334387 -219.045349) (xy 123.28235 -219.033472) (xy 123.232665 -219.013972) (xy 123.186441 -218.987285)
			(xy 123.144711 -218.954007) (xy 123.108407 -218.91488) (xy 123.07834 -218.87078) (xy 123.055182 -218.822691)
			(xy 123.03945 -218.771688) (xy 123.031495 -218.718909) (xy 123.030996 -218.692222) (xy 121.864628 -218.692222)
			(xy 121.864129 -218.718909) (xy 121.856174 -218.771688) (xy 121.840442 -218.822691) (xy 121.817284 -218.87078)
			(xy 121.787217 -218.91488) (xy 121.750913 -218.954007) (xy 121.709183 -218.987285) (xy 121.662959 -219.013972)
			(xy 121.613274 -219.033472) (xy 121.561237 -219.045349) (xy 121.508012 -219.049338) (xy 121.454787 -219.045349)
			(xy 121.40275 -219.033472) (xy 121.353065 -219.013972) (xy 121.306841 -218.987285) (xy 121.265111 -218.954007)
			(xy 121.228807 -218.91488) (xy 121.19874 -218.87078) (xy 121.175582 -218.822691) (xy 121.15985 -218.771688)
			(xy 121.151895 -218.718909) (xy 121.151396 -218.692222) (xy 119.985028 -218.692222) (xy 119.984529 -218.718909)
			(xy 119.976574 -218.771688) (xy 119.960842 -218.822691) (xy 119.937684 -218.87078) (xy 119.907617 -218.91488)
			(xy 119.871313 -218.954007) (xy 119.829583 -218.987285) (xy 119.783359 -219.013972) (xy 119.733674 -219.033472)
			(xy 119.681637 -219.045349) (xy 119.628412 -219.049338) (xy 119.575187 -219.045349) (xy 119.52315 -219.033472)
			(xy 119.473465 -219.013972) (xy 119.427241 -218.987285) (xy 119.385511 -218.954007) (xy 119.349207 -218.91488)
			(xy 119.31914 -218.87078) (xy 119.295982 -218.822691) (xy 119.28025 -218.771688) (xy 119.272295 -218.718909)
			(xy 119.271796 -218.692222) (xy 118.105428 -218.692222) (xy 118.104929 -218.718909) (xy 118.096974 -218.771688)
			(xy 118.081242 -218.822691) (xy 118.058084 -218.87078) (xy 118.028017 -218.91488) (xy 117.991713 -218.954007)
			(xy 117.949983 -218.987285) (xy 117.903759 -219.013972) (xy 117.854074 -219.033472) (xy 117.802037 -219.045349)
			(xy 117.748812 -219.049338) (xy 117.695587 -219.045349) (xy 117.64355 -219.033472) (xy 117.593865 -219.013972)
			(xy 117.547641 -218.987285) (xy 117.505911 -218.954007) (xy 117.469607 -218.91488) (xy 117.43954 -218.87078)
			(xy 117.416382 -218.822691) (xy 117.40065 -218.771688) (xy 117.392695 -218.718909) (xy 117.392196 -218.692222)
			(xy 116.225828 -218.692222) (xy 116.225329 -218.718909) (xy 116.217374 -218.771688) (xy 116.201642 -218.822691)
			(xy 116.178484 -218.87078) (xy 116.148417 -218.91488) (xy 116.112113 -218.954007) (xy 116.070383 -218.987285)
			(xy 116.024159 -219.013972) (xy 115.974474 -219.033472) (xy 115.922437 -219.045349) (xy 115.869212 -219.049338)
			(xy 115.815987 -219.045349) (xy 115.76395 -219.033472) (xy 115.714265 -219.013972) (xy 115.668041 -218.987285)
			(xy 115.626311 -218.954007) (xy 115.590007 -218.91488) (xy 115.55994 -218.87078) (xy 115.536782 -218.822691)
			(xy 115.52105 -218.771688) (xy 115.513095 -218.718909) (xy 115.512596 -218.692222) (xy 114.346482 -218.692222)
			(xy 114.345983 -218.718909) (xy 114.338028 -218.771688) (xy 114.322296 -218.822691) (xy 114.299138 -218.87078)
			(xy 114.269071 -218.91488) (xy 114.232767 -218.954007) (xy 114.191037 -218.987285) (xy 114.144813 -219.013972)
			(xy 114.095128 -219.033472) (xy 114.043091 -219.045349) (xy 113.989866 -219.049338) (xy 113.936641 -219.045349)
			(xy 113.884604 -219.033472) (xy 113.834919 -219.013972) (xy 113.788695 -218.987285) (xy 113.746965 -218.954007)
			(xy 113.710661 -218.91488) (xy 113.680594 -218.87078) (xy 113.657436 -218.822691) (xy 113.641704 -218.771688)
			(xy 113.633749 -218.718909) (xy 113.63325 -218.692222) (xy 112.466628 -218.692222) (xy 112.466129 -218.718909)
			(xy 112.458174 -218.771688) (xy 112.442442 -218.822691) (xy 112.419284 -218.87078) (xy 112.389217 -218.91488)
			(xy 112.352913 -218.954007) (xy 112.311183 -218.987285) (xy 112.264959 -219.013972) (xy 112.215274 -219.033472)
			(xy 112.163237 -219.045349) (xy 112.110012 -219.049338) (xy 112.056787 -219.045349) (xy 112.00475 -219.033472)
			(xy 111.955065 -219.013972) (xy 111.908841 -218.987285) (xy 111.867111 -218.954007) (xy 111.830807 -218.91488)
			(xy 111.80074 -218.87078) (xy 111.777582 -218.822691) (xy 111.76185 -218.771688) (xy 111.753895 -218.718909)
			(xy 111.753396 -218.692222) (xy 110.587282 -218.692222) (xy 110.586783 -218.718909) (xy 110.578828 -218.771688)
			(xy 110.563096 -218.822691) (xy 110.539938 -218.87078) (xy 110.509871 -218.91488) (xy 110.473567 -218.954007)
			(xy 110.431837 -218.987285) (xy 110.385613 -219.013972) (xy 110.335928 -219.033472) (xy 110.283891 -219.045349)
			(xy 110.230666 -219.049338) (xy 110.177441 -219.045349) (xy 110.125404 -219.033472) (xy 110.075719 -219.013972)
			(xy 110.029495 -218.987285) (xy 109.987765 -218.954007) (xy 109.951461 -218.91488) (xy 109.921394 -218.87078)
			(xy 109.898236 -218.822691) (xy 109.882504 -218.771688) (xy 109.874549 -218.718909) (xy 109.87405 -218.692222)
			(xy 109.874409 -218.668882) (xy 109.880513 -218.622603) (xy 109.892618 -218.577521) (xy 109.901228 -218.555824)
			(xy 109.91088 -218.532456) (xy 109.738922 -218.235276) (xy 109.71403 -218.231974) (xy 109.688633 -218.228159)
			(xy 109.639213 -218.214192) (xy 109.592308 -218.193281) (xy 109.548886 -218.165858) (xy 109.509847 -218.132491)
			(xy 109.475998 -218.09387) (xy 109.448037 -218.050793) (xy 109.426545 -218.004151) (xy 109.411965 -217.954908)
			(xy 109.404598 -217.904084) (xy 109.40415 -217.878406) (xy 109.177582 -217.878406) (xy 109.177083 -217.905093)
			(xy 109.169128 -217.957872) (xy 109.153396 -218.008875) (xy 109.130238 -218.056964) (xy 109.100171 -218.101064)
			(xy 109.063867 -218.140191) (xy 109.022137 -218.173469) (xy 108.975913 -218.200156) (xy 108.926228 -218.219656)
			(xy 108.874191 -218.231533) (xy 108.820966 -218.235522) (xy 108.767741 -218.231533) (xy 108.715704 -218.219656)
			(xy 108.666019 -218.200156) (xy 108.619795 -218.173469) (xy 108.578065 -218.140191) (xy 108.541761 -218.101064)
			(xy 108.511694 -218.056964) (xy 108.488536 -218.008875) (xy 108.472804 -217.957872) (xy 108.464849 -217.905093)
			(xy 108.46435 -217.878406) (xy 108.237782 -217.878406) (xy 108.237398 -217.901745) (xy 108.231304 -217.948023)
			(xy 108.219209 -217.993106) (xy 108.210604 -218.014804) (xy 108.200952 -218.038172) (xy 108.37291 -218.335352)
			(xy 108.397802 -218.338654) (xy 108.423177 -218.342525) (xy 108.472559 -218.356524) (xy 108.519425 -218.377455)
			(xy 108.562807 -218.404887) (xy 108.60181 -218.438254) (xy 108.635628 -218.476866) (xy 108.663562 -218.519927)
			(xy 108.685037 -218.566546) (xy 108.699609 -218.615762) (xy 108.706976 -218.666558) (xy 108.707428 -218.692222)
			(xy 108.706929 -218.718909) (xy 108.698974 -218.771688) (xy 108.683242 -218.822691) (xy 108.660084 -218.87078)
			(xy 108.630017 -218.91488) (xy 108.593713 -218.954007) (xy 108.551983 -218.987285) (xy 108.505759 -219.013972)
			(xy 108.456074 -219.033472) (xy 108.404037 -219.045349) (xy 108.350812 -219.049338) (xy 108.297587 -219.045349)
			(xy 108.24555 -219.033472) (xy 108.195865 -219.013972) (xy 108.149641 -218.987285) (xy 108.107911 -218.954007)
			(xy 108.071607 -218.91488) (xy 108.04154 -218.87078) (xy 108.018382 -218.822691) (xy 108.00265 -218.771688)
			(xy 107.994695 -218.718909) (xy 107.994196 -218.692222) (xy 107.994551 -218.668882) (xy 108.000656 -218.622603)
			(xy 108.012763 -218.577521) (xy 108.021374 -218.555824) (xy 108.031026 -218.532456) (xy 107.859068 -218.235276)
			(xy 107.834176 -218.231974) (xy 107.808786 -218.22819) (xy 107.759398 -218.214184) (xy 107.712528 -218.193245)
			(xy 107.669143 -218.165803) (xy 107.63014 -218.132427) (xy 107.596323 -218.093804) (xy 107.568391 -218.050733)
			(xy 107.54692 -218.004104) (xy 107.532356 -217.954878) (xy 107.524997 -217.904074) (xy 107.52455 -217.878406)
			(xy 107.297982 -217.878406) (xy 107.297483 -217.905093) (xy 107.289528 -217.957872) (xy 107.273796 -218.008875)
			(xy 107.250638 -218.056964) (xy 107.220571 -218.101064) (xy 107.184267 -218.140191) (xy 107.142537 -218.173469)
			(xy 107.096313 -218.200156) (xy 107.046628 -218.219656) (xy 106.994591 -218.231533) (xy 106.941366 -218.235522)
			(xy 106.888141 -218.231533) (xy 106.836104 -218.219656) (xy 106.786419 -218.200156) (xy 106.740195 -218.173469)
			(xy 106.698465 -218.140191) (xy 106.662161 -218.101064) (xy 106.632094 -218.056964) (xy 106.608936 -218.008875)
			(xy 106.593204 -217.957872) (xy 106.585249 -217.905093) (xy 106.58475 -217.878406) (xy 106.358182 -217.878406)
			(xy 106.357798 -217.901745) (xy 106.351704 -217.948023) (xy 106.339609 -217.993106) (xy 106.331004 -218.014804)
			(xy 106.321352 -218.038172) (xy 106.49331 -218.335352) (xy 106.518202 -218.338654) (xy 106.543577 -218.342525)
			(xy 106.592959 -218.356524) (xy 106.639825 -218.377455) (xy 106.683207 -218.404887) (xy 106.72221 -218.438254)
			(xy 106.756028 -218.476866) (xy 106.783962 -218.519927) (xy 106.805437 -218.566546) (xy 106.820009 -218.615762)
			(xy 106.827376 -218.666558) (xy 106.827828 -218.692222) (xy 106.827329 -218.718909) (xy 106.819374 -218.771688)
			(xy 106.803642 -218.822691) (xy 106.780484 -218.87078) (xy 106.750417 -218.91488) (xy 106.714113 -218.954007)
			(xy 106.672383 -218.987285) (xy 106.626159 -219.013972) (xy 106.576474 -219.033472) (xy 106.524437 -219.045349)
			(xy 106.471212 -219.049338) (xy 106.417987 -219.045349) (xy 106.36595 -219.033472) (xy 106.316265 -219.013972)
			(xy 106.270041 -218.987285) (xy 106.228311 -218.954007) (xy 106.192007 -218.91488) (xy 106.16194 -218.87078)
			(xy 106.138782 -218.822691) (xy 106.12305 -218.771688) (xy 106.115095 -218.718909) (xy 106.114596 -218.692222)
			(xy 106.114951 -218.668882) (xy 106.121056 -218.622603) (xy 106.133163 -218.577521) (xy 106.141774 -218.555824)
			(xy 106.151426 -218.532456) (xy 105.979468 -218.235276) (xy 105.954576 -218.231974) (xy 105.929186 -218.22819)
			(xy 105.879798 -218.214184) (xy 105.832928 -218.193245) (xy 105.789543 -218.165803) (xy 105.75054 -218.132427)
			(xy 105.716723 -218.093804) (xy 105.688791 -218.050733) (xy 105.66732 -218.004104) (xy 105.652756 -217.954878)
			(xy 105.645397 -217.904074) (xy 105.64495 -217.878406) (xy 105.418382 -217.878406) (xy 105.417883 -217.905093)
			(xy 105.409928 -217.957872) (xy 105.394196 -218.008875) (xy 105.371038 -218.056964) (xy 105.340971 -218.101064)
			(xy 105.304667 -218.140191) (xy 105.262937 -218.173469) (xy 105.216713 -218.200156) (xy 105.167028 -218.219656)
			(xy 105.114991 -218.231533) (xy 105.061766 -218.235522) (xy 105.008541 -218.231533) (xy 104.956504 -218.219656)
			(xy 104.906819 -218.200156) (xy 104.860595 -218.173469) (xy 104.818865 -218.140191) (xy 104.782561 -218.101064)
			(xy 104.752494 -218.056964) (xy 104.729336 -218.008875) (xy 104.713604 -217.957872) (xy 104.705649 -217.905093)
			(xy 104.70515 -217.878406) (xy 104.478582 -217.878406) (xy 104.478198 -217.901745) (xy 104.472104 -217.948023)
			(xy 104.460009 -217.993106) (xy 104.451404 -218.014804) (xy 104.441752 -218.038172) (xy 104.61371 -218.335352)
			(xy 104.638602 -218.338654) (xy 104.663977 -218.342525) (xy 104.713359 -218.356524) (xy 104.760225 -218.377455)
			(xy 104.803607 -218.404887) (xy 104.84261 -218.438254) (xy 104.876428 -218.476866) (xy 104.904362 -218.519927)
			(xy 104.925837 -218.566546) (xy 104.940409 -218.615762) (xy 104.947776 -218.666558) (xy 104.948228 -218.692222)
			(xy 104.947729 -218.718909) (xy 104.939774 -218.771688) (xy 104.924042 -218.822691) (xy 104.900884 -218.87078)
			(xy 104.870817 -218.91488) (xy 104.834513 -218.954007) (xy 104.792783 -218.987285) (xy 104.746559 -219.013972)
			(xy 104.696874 -219.033472) (xy 104.644837 -219.045349) (xy 104.591612 -219.049338) (xy 104.538387 -219.045349)
			(xy 104.48635 -219.033472) (xy 104.436665 -219.013972) (xy 104.390441 -218.987285) (xy 104.348711 -218.954007)
			(xy 104.312407 -218.91488) (xy 104.28234 -218.87078) (xy 104.259182 -218.822691) (xy 104.24345 -218.771688)
			(xy 104.235495 -218.718909) (xy 104.234996 -218.692222) (xy 104.235351 -218.668882) (xy 104.241456 -218.622603)
			(xy 104.253563 -218.577521) (xy 104.262174 -218.555824) (xy 104.271826 -218.532456) (xy 104.099868 -218.235276)
			(xy 104.074976 -218.231974) (xy 104.049586 -218.22819) (xy 104.000198 -218.214184) (xy 103.953328 -218.193245)
			(xy 103.909943 -218.165803) (xy 103.87094 -218.132427) (xy 103.837123 -218.093804) (xy 103.809191 -218.050733)
			(xy 103.78772 -218.004104) (xy 103.773156 -217.954878) (xy 103.765797 -217.904074) (xy 103.76535 -217.878406)
			(xy 103.538782 -217.878406) (xy 103.538283 -217.905093) (xy 103.530328 -217.957872) (xy 103.514596 -218.008875)
			(xy 103.491438 -218.056964) (xy 103.461371 -218.101064) (xy 103.425067 -218.140191) (xy 103.383337 -218.173469)
			(xy 103.337113 -218.200156) (xy 103.287428 -218.219656) (xy 103.235391 -218.231533) (xy 103.182166 -218.235522)
			(xy 103.128941 -218.231533) (xy 103.076904 -218.219656) (xy 103.027219 -218.200156) (xy 102.980995 -218.173469)
			(xy 102.939265 -218.140191) (xy 102.902961 -218.101064) (xy 102.872894 -218.056964) (xy 102.849736 -218.008875)
			(xy 102.834004 -217.957872) (xy 102.826049 -217.905093) (xy 102.82555 -217.878406) (xy 102.598982 -217.878406)
			(xy 102.598598 -217.901745) (xy 102.592504 -217.948023) (xy 102.580409 -217.993106) (xy 102.571804 -218.014804)
			(xy 102.562152 -218.038172) (xy 102.73411 -218.335352) (xy 102.759002 -218.338654) (xy 102.784377 -218.342525)
			(xy 102.833759 -218.356524) (xy 102.880625 -218.377455) (xy 102.924007 -218.404887) (xy 102.96301 -218.438254)
			(xy 102.996828 -218.476866) (xy 103.024762 -218.519927) (xy 103.046237 -218.566546) (xy 103.060809 -218.615762)
			(xy 103.068176 -218.666558) (xy 103.068628 -218.692222) (xy 103.068129 -218.718909) (xy 103.060174 -218.771688)
			(xy 103.044442 -218.822691) (xy 103.021284 -218.87078) (xy 102.991217 -218.91488) (xy 102.954913 -218.954007)
			(xy 102.913183 -218.987285) (xy 102.866959 -219.013972) (xy 102.817274 -219.033472) (xy 102.765237 -219.045349)
			(xy 102.712012 -219.049338) (xy 102.658787 -219.045349) (xy 102.60675 -219.033472) (xy 102.557065 -219.013972)
			(xy 102.510841 -218.987285) (xy 102.469111 -218.954007) (xy 102.432807 -218.91488) (xy 102.40274 -218.87078)
			(xy 102.379582 -218.822691) (xy 102.36385 -218.771688) (xy 102.355895 -218.718909) (xy 102.355396 -218.692222)
			(xy 102.355751 -218.668882) (xy 102.361856 -218.622603) (xy 102.373963 -218.577521) (xy 102.382574 -218.555824)
			(xy 102.392226 -218.532456) (xy 102.220268 -218.235276) (xy 102.195376 -218.231974) (xy 102.169986 -218.22819)
			(xy 102.120598 -218.214184) (xy 102.073728 -218.193245) (xy 102.030343 -218.165803) (xy 101.99134 -218.132427)
			(xy 101.957523 -218.093804) (xy 101.929591 -218.050733) (xy 101.90812 -218.004104) (xy 101.893556 -217.954878)
			(xy 101.886197 -217.904074) (xy 101.88575 -217.878406) (xy 101.659182 -217.878406) (xy 101.658683 -217.905093)
			(xy 101.650728 -217.957872) (xy 101.634996 -218.008875) (xy 101.611838 -218.056964) (xy 101.581771 -218.101064)
			(xy 101.545467 -218.140191) (xy 101.503737 -218.173469) (xy 101.457513 -218.200156) (xy 101.407828 -218.219656)
			(xy 101.355791 -218.231533) (xy 101.302566 -218.235522) (xy 101.249341 -218.231533) (xy 101.197304 -218.219656)
			(xy 101.147619 -218.200156) (xy 101.101395 -218.173469) (xy 101.059665 -218.140191) (xy 101.023361 -218.101064)
			(xy 100.993294 -218.056964) (xy 100.970136 -218.008875) (xy 100.954404 -217.957872) (xy 100.946449 -217.905093)
			(xy 100.94595 -217.878406) (xy 100.719382 -217.878406) (xy 100.718998 -217.901745) (xy 100.712904 -217.948023)
			(xy 100.700809 -217.993106) (xy 100.692204 -218.014804) (xy 100.682552 -218.038172) (xy 100.85451 -218.335352)
			(xy 100.879402 -218.338654) (xy 100.904777 -218.342525) (xy 100.954159 -218.356524) (xy 101.001025 -218.377455)
			(xy 101.044407 -218.404887) (xy 101.08341 -218.438254) (xy 101.117228 -218.476866) (xy 101.145162 -218.519927)
			(xy 101.166637 -218.566546) (xy 101.181209 -218.615762) (xy 101.188576 -218.666558) (xy 101.189028 -218.692222)
			(xy 101.188529 -218.718909) (xy 101.180574 -218.771688) (xy 101.164842 -218.822691) (xy 101.141684 -218.87078)
			(xy 101.111617 -218.91488) (xy 101.075313 -218.954007) (xy 101.033583 -218.987285) (xy 100.987359 -219.013972)
			(xy 100.937674 -219.033472) (xy 100.885637 -219.045349) (xy 100.832412 -219.049338) (xy 100.779187 -219.045349)
			(xy 100.72715 -219.033472) (xy 100.677465 -219.013972) (xy 100.631241 -218.987285) (xy 100.589511 -218.954007)
			(xy 100.553207 -218.91488) (xy 100.52314 -218.87078) (xy 100.499982 -218.822691) (xy 100.48425 -218.771688)
			(xy 100.476295 -218.718909) (xy 100.475796 -218.692222) (xy 100.476151 -218.668882) (xy 100.482256 -218.622603)
			(xy 100.494363 -218.577521) (xy 100.502974 -218.555824) (xy 100.512626 -218.532456) (xy 100.340668 -218.235276)
			(xy 100.315776 -218.231974) (xy 100.290386 -218.22819) (xy 100.240998 -218.214184) (xy 100.194128 -218.193245)
			(xy 100.150743 -218.165803) (xy 100.11174 -218.132427) (xy 100.077923 -218.093804) (xy 100.049991 -218.050733)
			(xy 100.02852 -218.004104) (xy 100.013956 -217.954878) (xy 100.006597 -217.904074) (xy 100.00615 -217.878406)
			(xy 99.779582 -217.878406) (xy 99.779083 -217.905093) (xy 99.771128 -217.957872) (xy 99.755396 -218.008875)
			(xy 99.732238 -218.056964) (xy 99.702171 -218.101064) (xy 99.665867 -218.140191) (xy 99.624137 -218.173469)
			(xy 99.577913 -218.200156) (xy 99.528228 -218.219656) (xy 99.476191 -218.231533) (xy 99.422966 -218.235522)
			(xy 99.369741 -218.231533) (xy 99.317704 -218.219656) (xy 99.268019 -218.200156) (xy 99.221795 -218.173469)
			(xy 99.180065 -218.140191) (xy 99.143761 -218.101064) (xy 99.113694 -218.056964) (xy 99.090536 -218.008875)
			(xy 99.074804 -217.957872) (xy 99.066849 -217.905093) (xy 99.06635 -217.878406) (xy 98.839782 -217.878406)
			(xy 98.839398 -217.901745) (xy 98.833304 -217.948023) (xy 98.821209 -217.993106) (xy 98.812604 -218.014804)
			(xy 98.802952 -218.038172) (xy 98.97491 -218.335352) (xy 98.999802 -218.338654) (xy 99.025177 -218.342525)
			(xy 99.074559 -218.356524) (xy 99.121425 -218.377455) (xy 99.164807 -218.404887) (xy 99.20381 -218.438254)
			(xy 99.237628 -218.476866) (xy 99.265562 -218.519927) (xy 99.287037 -218.566546) (xy 99.301609 -218.615762)
			(xy 99.308976 -218.666558) (xy 99.309428 -218.692222) (xy 99.308929 -218.718909) (xy 99.300974 -218.771688)
			(xy 99.285242 -218.822691) (xy 99.262084 -218.87078) (xy 99.232017 -218.91488) (xy 99.195713 -218.954007)
			(xy 99.153983 -218.987285) (xy 99.107759 -219.013972) (xy 99.058074 -219.033472) (xy 99.006037 -219.045349)
			(xy 98.952812 -219.049338) (xy 98.899587 -219.045349) (xy 98.84755 -219.033472) (xy 98.797865 -219.013972)
			(xy 98.751641 -218.987285) (xy 98.709911 -218.954007) (xy 98.673607 -218.91488) (xy 98.64354 -218.87078)
			(xy 98.620382 -218.822691) (xy 98.60465 -218.771688) (xy 98.596695 -218.718909) (xy 98.596196 -218.692222)
			(xy 98.596551 -218.668882) (xy 98.602656 -218.622603) (xy 98.614763 -218.577521) (xy 98.623374 -218.555824)
			(xy 98.633026 -218.532456) (xy 98.461068 -218.235276) (xy 98.436176 -218.231974) (xy 98.410786 -218.22819)
			(xy 98.361398 -218.214184) (xy 98.314528 -218.193245) (xy 98.271143 -218.165803) (xy 98.23214 -218.132427)
			(xy 98.198323 -218.093804) (xy 98.170391 -218.050733) (xy 98.14892 -218.004104) (xy 98.134356 -217.954878)
			(xy 98.126997 -217.904074) (xy 98.12655 -217.878406) (xy 97.899982 -217.878406) (xy 97.899483 -217.905093)
			(xy 97.891528 -217.957872) (xy 97.875796 -218.008875) (xy 97.852638 -218.056964) (xy 97.822571 -218.101064)
			(xy 97.786267 -218.140191) (xy 97.744537 -218.173469) (xy 97.698313 -218.200156) (xy 97.648628 -218.219656)
			(xy 97.596591 -218.231533) (xy 97.543366 -218.235522) (xy 97.490141 -218.231533) (xy 97.438104 -218.219656)
			(xy 97.388419 -218.200156) (xy 97.342195 -218.173469) (xy 97.300465 -218.140191) (xy 97.264161 -218.101064)
			(xy 97.234094 -218.056964) (xy 97.210936 -218.008875) (xy 97.195204 -217.957872) (xy 97.187249 -217.905093)
			(xy 97.18675 -217.878406) (xy 96.960182 -217.878406) (xy 96.959798 -217.901745) (xy 96.953704 -217.948023)
			(xy 96.941609 -217.993106) (xy 96.933004 -218.014804) (xy 96.923352 -218.038172) (xy 97.09531 -218.335352)
			(xy 97.120202 -218.338654) (xy 97.145577 -218.342525) (xy 97.194959 -218.356524) (xy 97.241825 -218.377455)
			(xy 97.285207 -218.404887) (xy 97.32421 -218.438254) (xy 97.358028 -218.476866) (xy 97.385962 -218.519927)
			(xy 97.407437 -218.566546) (xy 97.422009 -218.615762) (xy 97.429376 -218.666558) (xy 97.429828 -218.692222)
			(xy 97.429329 -218.718909) (xy 97.421374 -218.771688) (xy 97.405642 -218.822691) (xy 97.382484 -218.87078)
			(xy 97.352417 -218.91488) (xy 97.316113 -218.954007) (xy 97.274383 -218.987285) (xy 97.228159 -219.013972)
			(xy 97.178474 -219.033472) (xy 97.126437 -219.045349) (xy 97.073212 -219.049338) (xy 97.019987 -219.045349)
			(xy 96.96795 -219.033472) (xy 96.918265 -219.013972) (xy 96.872041 -218.987285) (xy 96.830311 -218.954007)
			(xy 96.794007 -218.91488) (xy 96.76394 -218.87078) (xy 96.740782 -218.822691) (xy 96.72505 -218.771688)
			(xy 96.717095 -218.718909) (xy 96.716596 -218.692222) (xy 96.716951 -218.668882) (xy 96.723056 -218.622603)
			(xy 96.735163 -218.577521) (xy 96.743774 -218.555824) (xy 96.753426 -218.532456) (xy 96.581468 -218.235276)
			(xy 96.556576 -218.231974) (xy 96.531186 -218.22819) (xy 96.481798 -218.214184) (xy 96.434928 -218.193245)
			(xy 96.391543 -218.165803) (xy 96.35254 -218.132427) (xy 96.318723 -218.093804) (xy 96.290791 -218.050733)
			(xy 96.26932 -218.004104) (xy 96.254756 -217.954878) (xy 96.247397 -217.904074) (xy 96.24695 -217.878406)
			(xy 96.020382 -217.878406) (xy 96.019883 -217.905093) (xy 96.011928 -217.957872) (xy 95.996196 -218.008875)
			(xy 95.973038 -218.056964) (xy 95.942971 -218.101064) (xy 95.906667 -218.140191) (xy 95.864937 -218.173469)
			(xy 95.818713 -218.200156) (xy 95.769028 -218.219656) (xy 95.716991 -218.231533) (xy 95.663766 -218.235522)
			(xy 95.610541 -218.231533) (xy 95.558504 -218.219656) (xy 95.508819 -218.200156) (xy 95.462595 -218.173469)
			(xy 95.420865 -218.140191) (xy 95.384561 -218.101064) (xy 95.354494 -218.056964) (xy 95.331336 -218.008875)
			(xy 95.315604 -217.957872) (xy 95.307649 -217.905093) (xy 95.30715 -217.878406) (xy 95.080582 -217.878406)
			(xy 95.080198 -217.901745) (xy 95.074104 -217.948023) (xy 95.062009 -217.993106) (xy 95.053404 -218.014804)
			(xy 95.043752 -218.038172) (xy 95.21571 -218.335352) (xy 95.240602 -218.338654) (xy 95.265977 -218.342525)
			(xy 95.315359 -218.356524) (xy 95.362225 -218.377455) (xy 95.405607 -218.404887) (xy 95.44461 -218.438254)
			(xy 95.478428 -218.476866) (xy 95.506362 -218.519927) (xy 95.527837 -218.566546) (xy 95.542409 -218.615762)
			(xy 95.549776 -218.666558) (xy 95.550228 -218.692222) (xy 95.549729 -218.718909) (xy 95.541774 -218.771688)
			(xy 95.526042 -218.822691) (xy 95.502884 -218.87078) (xy 95.472817 -218.91488) (xy 95.436513 -218.954007)
			(xy 95.394783 -218.987285) (xy 95.348559 -219.013972) (xy 95.298874 -219.033472) (xy 95.246837 -219.045349)
			(xy 95.193612 -219.049338) (xy 95.140387 -219.045349) (xy 95.08835 -219.033472) (xy 95.038665 -219.013972)
			(xy 94.992441 -218.987285) (xy 94.950711 -218.954007) (xy 94.914407 -218.91488) (xy 94.88434 -218.87078)
			(xy 94.861182 -218.822691) (xy 94.84545 -218.771688) (xy 94.837495 -218.718909) (xy 94.836996 -218.692222)
			(xy 94.837351 -218.668882) (xy 94.843456 -218.622603) (xy 94.855563 -218.577521) (xy 94.864174 -218.555824)
			(xy 94.873826 -218.532456) (xy 94.701868 -218.235276) (xy 94.676976 -218.231974) (xy 94.651586 -218.22819)
			(xy 94.602198 -218.214184) (xy 94.555328 -218.193245) (xy 94.511943 -218.165803) (xy 94.47294 -218.132427)
			(xy 94.439123 -218.093804) (xy 94.411191 -218.050733) (xy 94.38972 -218.004104) (xy 94.375156 -217.954878)
			(xy 94.367797 -217.904074) (xy 94.36735 -217.878406) (xy 94.140782 -217.878406) (xy 94.140283 -217.905093)
			(xy 94.132328 -217.957872) (xy 94.116596 -218.008875) (xy 94.093438 -218.056964) (xy 94.063371 -218.101064)
			(xy 94.027067 -218.140191) (xy 93.985337 -218.173469) (xy 93.939113 -218.200156) (xy 93.889428 -218.219656)
			(xy 93.837391 -218.231533) (xy 93.784166 -218.235522) (xy 93.730941 -218.231533) (xy 93.678904 -218.219656)
			(xy 93.629219 -218.200156) (xy 93.582995 -218.173469) (xy 93.541265 -218.140191) (xy 93.504961 -218.101064)
			(xy 93.474894 -218.056964) (xy 93.451736 -218.008875) (xy 93.436004 -217.957872) (xy 93.428049 -217.905093)
			(xy 93.42755 -217.878406) (xy 93.200982 -217.878406) (xy 93.200598 -217.901745) (xy 93.194504 -217.948023)
			(xy 93.182409 -217.993106) (xy 93.173804 -218.014804) (xy 93.164152 -218.038172) (xy 93.33611 -218.335352)
			(xy 93.361002 -218.338654) (xy 93.386377 -218.342525) (xy 93.435759 -218.356524) (xy 93.482625 -218.377455)
			(xy 93.526007 -218.404887) (xy 93.56501 -218.438254) (xy 93.598828 -218.476866) (xy 93.626762 -218.519927)
			(xy 93.648237 -218.566546) (xy 93.662809 -218.615762) (xy 93.670176 -218.666558) (xy 93.670628 -218.692222)
			(xy 93.670129 -218.718909) (xy 93.662174 -218.771688) (xy 93.646442 -218.822691) (xy 93.623284 -218.87078)
			(xy 93.593217 -218.91488) (xy 93.556913 -218.954007) (xy 93.515183 -218.987285) (xy 93.468959 -219.013972)
			(xy 93.419274 -219.033472) (xy 93.367237 -219.045349) (xy 93.314012 -219.049338) (xy 93.260787 -219.045349)
			(xy 93.20875 -219.033472) (xy 93.159065 -219.013972) (xy 93.112841 -218.987285) (xy 93.071111 -218.954007)
			(xy 93.034807 -218.91488) (xy 93.00474 -218.87078) (xy 92.981582 -218.822691) (xy 92.96585 -218.771688)
			(xy 92.957895 -218.718909) (xy 92.957396 -218.692222) (xy 92.957751 -218.668882) (xy 92.963856 -218.622603)
			(xy 92.975963 -218.577521) (xy 92.984574 -218.555824) (xy 92.994226 -218.532456) (xy 92.822268 -218.235276)
			(xy 92.797376 -218.231974) (xy 92.771986 -218.22819) (xy 92.722598 -218.214184) (xy 92.675728 -218.193245)
			(xy 92.632343 -218.165803) (xy 92.59334 -218.132427) (xy 92.559523 -218.093804) (xy 92.531591 -218.050733)
			(xy 92.51012 -218.004104) (xy 92.495556 -217.954878) (xy 92.488197 -217.904074) (xy 92.48775 -217.878406)
			(xy 92.261182 -217.878406) (xy 92.260683 -217.905093) (xy 92.252728 -217.957872) (xy 92.236996 -218.008875)
			(xy 92.213838 -218.056964) (xy 92.183771 -218.101064) (xy 92.147467 -218.140191) (xy 92.105737 -218.173469)
			(xy 92.059513 -218.200156) (xy 92.009828 -218.219656) (xy 91.957791 -218.231533) (xy 91.904566 -218.235522)
			(xy 91.851341 -218.231533) (xy 91.799304 -218.219656) (xy 91.749619 -218.200156) (xy 91.703395 -218.173469)
			(xy 91.661665 -218.140191) (xy 91.625361 -218.101064) (xy 91.595294 -218.056964) (xy 91.572136 -218.008875)
			(xy 91.556404 -217.957872) (xy 91.548449 -217.905093) (xy 91.54795 -217.878406) (xy 91.321382 -217.878406)
			(xy 91.320998 -217.901745) (xy 91.314904 -217.948023) (xy 91.302809 -217.993106) (xy 91.294204 -218.014804)
			(xy 91.284552 -218.038172) (xy 91.45651 -218.335352) (xy 91.481402 -218.338654) (xy 91.506777 -218.342525)
			(xy 91.556159 -218.356524) (xy 91.603025 -218.377455) (xy 91.646407 -218.404887) (xy 91.68541 -218.438254)
			(xy 91.719228 -218.476866) (xy 91.747162 -218.519927) (xy 91.768637 -218.566546) (xy 91.783209 -218.615762)
			(xy 91.790576 -218.666558) (xy 91.791028 -218.692222) (xy 91.790529 -218.718909) (xy 91.782574 -218.771688)
			(xy 91.766842 -218.822691) (xy 91.743684 -218.87078) (xy 91.713617 -218.91488) (xy 91.677313 -218.954007)
			(xy 91.635583 -218.987285) (xy 91.589359 -219.013972) (xy 91.539674 -219.033472) (xy 91.487637 -219.045349)
			(xy 91.434412 -219.049338) (xy 91.381187 -219.045349) (xy 91.32915 -219.033472) (xy 91.279465 -219.013972)
			(xy 91.233241 -218.987285) (xy 91.191511 -218.954007) (xy 91.155207 -218.91488) (xy 91.12514 -218.87078)
			(xy 91.101982 -218.822691) (xy 91.08625 -218.771688) (xy 91.078295 -218.718909) (xy 91.077796 -218.692222)
			(xy 91.078151 -218.668882) (xy 91.084256 -218.622603) (xy 91.096363 -218.577521) (xy 91.104974 -218.555824)
			(xy 91.114626 -218.532456) (xy 90.942668 -218.235276) (xy 90.917776 -218.231974) (xy 90.892386 -218.22819)
			(xy 90.842998 -218.214184) (xy 90.796128 -218.193245) (xy 90.752743 -218.165803) (xy 90.71374 -218.132427)
			(xy 90.679923 -218.093804) (xy 90.651991 -218.050733) (xy 90.63052 -218.004104) (xy 90.615956 -217.954878)
			(xy 90.608597 -217.904074) (xy 90.60815 -217.878406) (xy 90.381582 -217.878406) (xy 90.381083 -217.905093)
			(xy 90.373128 -217.957872) (xy 90.357396 -218.008875) (xy 90.334238 -218.056964) (xy 90.304171 -218.101064)
			(xy 90.267867 -218.140191) (xy 90.226137 -218.173469) (xy 90.179913 -218.200156) (xy 90.130228 -218.219656)
			(xy 90.078191 -218.231533) (xy 90.024966 -218.235522) (xy 89.971741 -218.231533) (xy 89.919704 -218.219656)
			(xy 89.870019 -218.200156) (xy 89.823795 -218.173469) (xy 89.782065 -218.140191) (xy 89.745761 -218.101064)
			(xy 89.715694 -218.056964) (xy 89.692536 -218.008875) (xy 89.676804 -217.957872) (xy 89.668849 -217.905093)
			(xy 89.66835 -217.878406) (xy 89.441782 -217.878406) (xy 89.441398 -217.901745) (xy 89.435304 -217.948023)
			(xy 89.423209 -217.993106) (xy 89.414604 -218.014804) (xy 89.404952 -218.038172) (xy 89.57691 -218.335352)
			(xy 89.601802 -218.338654) (xy 89.627177 -218.342525) (xy 89.676559 -218.356524) (xy 89.723425 -218.377455)
			(xy 89.766807 -218.404887) (xy 89.80581 -218.438254) (xy 89.839628 -218.476866) (xy 89.867562 -218.519927)
			(xy 89.889037 -218.566546) (xy 89.903609 -218.615762) (xy 89.910976 -218.666558) (xy 89.911428 -218.692222)
			(xy 89.910929 -218.718909) (xy 89.902974 -218.771688) (xy 89.887242 -218.822691) (xy 89.864084 -218.87078)
			(xy 89.834017 -218.91488) (xy 89.797713 -218.954007) (xy 89.755983 -218.987285) (xy 89.709759 -219.013972)
			(xy 89.660074 -219.033472) (xy 89.608037 -219.045349) (xy 89.554812 -219.049338) (xy 89.501587 -219.045349)
			(xy 89.44955 -219.033472) (xy 89.399865 -219.013972) (xy 89.353641 -218.987285) (xy 89.311911 -218.954007)
			(xy 89.275607 -218.91488) (xy 89.24554 -218.87078) (xy 89.222382 -218.822691) (xy 89.20665 -218.771688)
			(xy 89.198695 -218.718909) (xy 89.198196 -218.692222) (xy 89.198551 -218.668882) (xy 89.204656 -218.622603)
			(xy 89.216763 -218.577521) (xy 89.225374 -218.555824) (xy 89.235026 -218.532456) (xy 89.063068 -218.235276)
			(xy 89.038176 -218.231974) (xy 89.012786 -218.22819) (xy 88.963398 -218.214184) (xy 88.916528 -218.193245)
			(xy 88.873143 -218.165803) (xy 88.83414 -218.132427) (xy 88.800323 -218.093804) (xy 88.772391 -218.050733)
			(xy 88.75092 -218.004104) (xy 88.736356 -217.954878) (xy 88.728997 -217.904074) (xy 88.72855 -217.878406)
			(xy 2.509012 -217.878406) (xy 2.509012 -221.133924) (xy 88.755728 -221.133924) (xy 88.756236 -221.108037)
			(xy 88.764335 -221.056899) (xy 88.780334 -221.007659) (xy 88.80384 -220.961527) (xy 88.834272 -220.91964)
			(xy 88.870882 -220.88303) (xy 88.912769 -220.852598) (xy 88.958901 -220.829092) (xy 89.008141 -220.813093)
			(xy 89.059279 -220.804994) (xy 89.111053 -220.804994) (xy 89.162191 -220.813093) (xy 89.211431 -220.829092)
			(xy 89.257563 -220.852598) (xy 89.29945 -220.88303) (xy 89.33606 -220.91964) (xy 89.366492 -220.961527)
			(xy 89.389998 -221.007659) (xy 89.405997 -221.056899) (xy 89.414096 -221.108037) (xy 89.414604 -221.133924)
			(xy 89.695528 -221.133924) (xy 89.69601 -221.108589) (xy 89.70376 -221.058515) (xy 89.71908 -221.010217)
			(xy 89.741611 -220.964832) (xy 89.770821 -220.923429) (xy 89.806022 -220.886984) (xy 89.846386 -220.856354)
			(xy 89.890961 -220.83226) (xy 89.938698 -220.815272) (xy 89.963498 -220.810074) (xy 89.986358 -220.805756)
			(xy 90.191336 -220.450664) (xy 90.183462 -220.42882) (xy 90.174829 -220.402408) (xy 90.1655 -220.347635)
			(xy 90.16492 -220.319854) (xy 90.165428 -220.293947) (xy 90.173534 -220.24277) (xy 90.189546 -220.193491)
			(xy 90.213069 -220.147324) (xy 90.243525 -220.105405) (xy 90.280163 -220.068767) (xy 90.322082 -220.038311)
			(xy 90.368249 -220.014788) (xy 90.417528 -219.998776) (xy 90.468705 -219.99067) (xy 90.520519 -219.99067)
			(xy 90.571696 -219.998776) (xy 90.620975 -220.014788) (xy 90.667142 -220.038311) (xy 90.709061 -220.068767)
			(xy 90.745699 -220.105405) (xy 90.776155 -220.147324) (xy 90.799678 -220.193491) (xy 90.81569 -220.24277)
			(xy 90.823796 -220.293947) (xy 90.824304 -220.319854) (xy 90.823828 -220.345199) (xy 90.816049 -220.395289)
			(xy 90.800697 -220.443599) (xy 90.778134 -220.48899) (xy 90.748891 -220.530396) (xy 90.713657 -220.566839)
			(xy 90.673262 -220.597461) (xy 90.628657 -220.621543) (xy 90.580893 -220.638516) (xy 90.55608 -220.643704)
			(xy 90.53322 -220.648022) (xy 90.328242 -221.003114) (xy 90.336116 -221.024958) (xy 90.34471 -221.051373)
			(xy 90.353897 -221.106151) (xy 90.354404 -221.133924) (xy 90.635328 -221.133924) (xy 90.635836 -221.108037)
			(xy 90.643935 -221.056899) (xy 90.659934 -221.007659) (xy 90.68344 -220.961527) (xy 90.713872 -220.91964)
			(xy 90.750482 -220.88303) (xy 90.792369 -220.852598) (xy 90.838501 -220.829092) (xy 90.887741 -220.813093)
			(xy 90.938879 -220.804994) (xy 90.990653 -220.804994) (xy 91.041791 -220.813093) (xy 91.091031 -220.829092)
			(xy 91.137163 -220.852598) (xy 91.17905 -220.88303) (xy 91.21566 -220.91964) (xy 91.246092 -220.961527)
			(xy 91.269598 -221.007659) (xy 91.285597 -221.056899) (xy 91.293696 -221.108037) (xy 91.294204 -221.133924)
			(xy 91.575128 -221.133924) (xy 91.57561 -221.108589) (xy 91.58336 -221.058515) (xy 91.59868 -221.010217)
			(xy 91.621211 -220.964832) (xy 91.650421 -220.923429) (xy 91.685622 -220.886984) (xy 91.725986 -220.856354)
			(xy 91.770561 -220.83226) (xy 91.818298 -220.815272) (xy 91.843098 -220.810074) (xy 91.865958 -220.805756)
			(xy 92.070936 -220.450664) (xy 92.063062 -220.42882) (xy 92.054429 -220.402408) (xy 92.0451 -220.347635)
			(xy 92.04452 -220.319854) (xy 92.045028 -220.293947) (xy 92.053134 -220.24277) (xy 92.069146 -220.193491)
			(xy 92.092669 -220.147324) (xy 92.123125 -220.105405) (xy 92.159763 -220.068767) (xy 92.201682 -220.038311)
			(xy 92.247849 -220.014788) (xy 92.297128 -219.998776) (xy 92.348305 -219.99067) (xy 92.400119 -219.99067)
			(xy 92.451296 -219.998776) (xy 92.500575 -220.014788) (xy 92.546742 -220.038311) (xy 92.588661 -220.068767)
			(xy 92.625299 -220.105405) (xy 92.655755 -220.147324) (xy 92.679278 -220.193491) (xy 92.69529 -220.24277)
			(xy 92.703396 -220.293947) (xy 92.703904 -220.319854) (xy 92.703428 -220.345199) (xy 92.695649 -220.395289)
			(xy 92.680297 -220.443599) (xy 92.657734 -220.48899) (xy 92.628491 -220.530396) (xy 92.593257 -220.566839)
			(xy 92.552862 -220.597461) (xy 92.508257 -220.621543) (xy 92.460493 -220.638516) (xy 92.43568 -220.643704)
			(xy 92.41282 -220.648022) (xy 92.207842 -221.003114) (xy 92.215716 -221.024958) (xy 92.22431 -221.051373)
			(xy 92.233497 -221.106151) (xy 92.234004 -221.133924) (xy 92.514928 -221.133924) (xy 92.515436 -221.108037)
			(xy 92.523535 -221.056899) (xy 92.539534 -221.007659) (xy 92.56304 -220.961527) (xy 92.593472 -220.91964)
			(xy 92.630082 -220.88303) (xy 92.671969 -220.852598) (xy 92.718101 -220.829092) (xy 92.767341 -220.813093)
			(xy 92.818479 -220.804994) (xy 92.870253 -220.804994) (xy 92.921391 -220.813093) (xy 92.970631 -220.829092)
			(xy 93.016763 -220.852598) (xy 93.05865 -220.88303) (xy 93.09526 -220.91964) (xy 93.125692 -220.961527)
			(xy 93.149198 -221.007659) (xy 93.165197 -221.056899) (xy 93.173296 -221.108037) (xy 93.173804 -221.133924)
			(xy 93.454728 -221.133924) (xy 93.45521 -221.108589) (xy 93.46296 -221.058515) (xy 93.47828 -221.010217)
			(xy 93.500811 -220.964832) (xy 93.530021 -220.923429) (xy 93.565222 -220.886984) (xy 93.605586 -220.856354)
			(xy 93.650161 -220.83226) (xy 93.697898 -220.815272) (xy 93.722698 -220.810074) (xy 93.745558 -220.805756)
			(xy 93.950536 -220.450664) (xy 93.942662 -220.42882) (xy 93.934029 -220.402408) (xy 93.9247 -220.347635)
			(xy 93.92412 -220.319854) (xy 93.924628 -220.293947) (xy 93.932734 -220.24277) (xy 93.948746 -220.193491)
			(xy 93.972269 -220.147324) (xy 94.002725 -220.105405) (xy 94.039363 -220.068767) (xy 94.081282 -220.038311)
			(xy 94.127449 -220.014788) (xy 94.176728 -219.998776) (xy 94.227905 -219.99067) (xy 94.279719 -219.99067)
			(xy 94.330896 -219.998776) (xy 94.380175 -220.014788) (xy 94.426342 -220.038311) (xy 94.468261 -220.068767)
			(xy 94.504899 -220.105405) (xy 94.535355 -220.147324) (xy 94.558878 -220.193491) (xy 94.57489 -220.24277)
			(xy 94.582996 -220.293947) (xy 94.583504 -220.319854) (xy 94.583028 -220.345199) (xy 94.575249 -220.395289)
			(xy 94.559897 -220.443599) (xy 94.537334 -220.48899) (xy 94.508091 -220.530396) (xy 94.472857 -220.566839)
			(xy 94.432462 -220.597461) (xy 94.387857 -220.621543) (xy 94.340093 -220.638516) (xy 94.31528 -220.643704)
			(xy 94.29242 -220.648022) (xy 94.087442 -221.003114) (xy 94.095316 -221.024958) (xy 94.10391 -221.051373)
			(xy 94.113097 -221.106151) (xy 94.113604 -221.133924) (xy 94.394528 -221.133924) (xy 94.395036 -221.108037)
			(xy 94.403135 -221.056899) (xy 94.419134 -221.007659) (xy 94.44264 -220.961527) (xy 94.473072 -220.91964)
			(xy 94.509682 -220.88303) (xy 94.551569 -220.852598) (xy 94.597701 -220.829092) (xy 94.646941 -220.813093)
			(xy 94.698079 -220.804994) (xy 94.749853 -220.804994) (xy 94.800991 -220.813093) (xy 94.850231 -220.829092)
			(xy 94.896363 -220.852598) (xy 94.93825 -220.88303) (xy 94.97486 -220.91964) (xy 95.005292 -220.961527)
			(xy 95.028798 -221.007659) (xy 95.044797 -221.056899) (xy 95.052896 -221.108037) (xy 95.053404 -221.133924)
			(xy 95.334328 -221.133924) (xy 95.33481 -221.108589) (xy 95.34256 -221.058515) (xy 95.35788 -221.010217)
			(xy 95.380411 -220.964832) (xy 95.409621 -220.923429) (xy 95.444822 -220.886984) (xy 95.485186 -220.856354)
			(xy 95.529761 -220.83226) (xy 95.577498 -220.815272) (xy 95.602298 -220.810074) (xy 95.625158 -220.805756)
			(xy 95.830136 -220.450664) (xy 95.822262 -220.42882) (xy 95.813629 -220.402408) (xy 95.8043 -220.347635)
			(xy 95.80372 -220.319854) (xy 95.804228 -220.293947) (xy 95.812334 -220.24277) (xy 95.828346 -220.193491)
			(xy 95.851869 -220.147324) (xy 95.882325 -220.105405) (xy 95.918963 -220.068767) (xy 95.960882 -220.038311)
			(xy 96.007049 -220.014788) (xy 96.056328 -219.998776) (xy 96.107505 -219.99067) (xy 96.159319 -219.99067)
			(xy 96.210496 -219.998776) (xy 96.259775 -220.014788) (xy 96.305942 -220.038311) (xy 96.347861 -220.068767)
			(xy 96.384499 -220.105405) (xy 96.414955 -220.147324) (xy 96.438478 -220.193491) (xy 96.45449 -220.24277)
			(xy 96.462596 -220.293947) (xy 96.463104 -220.319854) (xy 96.462628 -220.345199) (xy 96.454849 -220.395289)
			(xy 96.439497 -220.443599) (xy 96.416934 -220.48899) (xy 96.387691 -220.530396) (xy 96.352457 -220.566839)
			(xy 96.312062 -220.597461) (xy 96.267457 -220.621543) (xy 96.219693 -220.638516) (xy 96.19488 -220.643704)
			(xy 96.17202 -220.648022) (xy 95.967042 -221.003114) (xy 95.974916 -221.024958) (xy 95.98351 -221.051373)
			(xy 95.992697 -221.106151) (xy 95.993204 -221.133924) (xy 96.274128 -221.133924) (xy 96.274636 -221.108037)
			(xy 96.282735 -221.056899) (xy 96.298734 -221.007659) (xy 96.32224 -220.961527) (xy 96.352672 -220.91964)
			(xy 96.389282 -220.88303) (xy 96.431169 -220.852598) (xy 96.477301 -220.829092) (xy 96.526541 -220.813093)
			(xy 96.577679 -220.804994) (xy 96.629453 -220.804994) (xy 96.680591 -220.813093) (xy 96.729831 -220.829092)
			(xy 96.775963 -220.852598) (xy 96.81785 -220.88303) (xy 96.85446 -220.91964) (xy 96.884892 -220.961527)
			(xy 96.908398 -221.007659) (xy 96.924397 -221.056899) (xy 96.932496 -221.108037) (xy 96.933004 -221.133924)
			(xy 97.213928 -221.133924) (xy 97.21441 -221.108589) (xy 97.22216 -221.058515) (xy 97.23748 -221.010217)
			(xy 97.260011 -220.964832) (xy 97.289221 -220.923429) (xy 97.324422 -220.886984) (xy 97.364786 -220.856354)
			(xy 97.409361 -220.83226) (xy 97.457098 -220.815272) (xy 97.481898 -220.810074) (xy 97.504758 -220.805756)
			(xy 97.709736 -220.450664) (xy 97.701862 -220.42882) (xy 97.693229 -220.402408) (xy 97.6839 -220.347635)
			(xy 97.68332 -220.319854) (xy 97.683828 -220.293947) (xy 97.691934 -220.24277) (xy 97.707946 -220.193491)
			(xy 97.731469 -220.147324) (xy 97.761925 -220.105405) (xy 97.798563 -220.068767) (xy 97.840482 -220.038311)
			(xy 97.886649 -220.014788) (xy 97.935928 -219.998776) (xy 97.987105 -219.99067) (xy 98.038919 -219.99067)
			(xy 98.090096 -219.998776) (xy 98.139375 -220.014788) (xy 98.185542 -220.038311) (xy 98.227461 -220.068767)
			(xy 98.264099 -220.105405) (xy 98.294555 -220.147324) (xy 98.318078 -220.193491) (xy 98.33409 -220.24277)
			(xy 98.342196 -220.293947) (xy 98.342704 -220.319854) (xy 98.342228 -220.345199) (xy 98.334449 -220.395289)
			(xy 98.319097 -220.443599) (xy 98.296534 -220.48899) (xy 98.267291 -220.530396) (xy 98.232057 -220.566839)
			(xy 98.191662 -220.597461) (xy 98.147057 -220.621543) (xy 98.099293 -220.638516) (xy 98.07448 -220.643704)
			(xy 98.05162 -220.648022) (xy 97.846642 -221.003114) (xy 97.854516 -221.024958) (xy 97.86311 -221.051373)
			(xy 97.872297 -221.106151) (xy 97.872804 -221.133924) (xy 98.153728 -221.133924) (xy 98.154236 -221.108037)
			(xy 98.162335 -221.056899) (xy 98.178334 -221.007659) (xy 98.20184 -220.961527) (xy 98.232272 -220.91964)
			(xy 98.268882 -220.88303) (xy 98.310769 -220.852598) (xy 98.356901 -220.829092) (xy 98.406141 -220.813093)
			(xy 98.457279 -220.804994) (xy 98.509053 -220.804994) (xy 98.560191 -220.813093) (xy 98.609431 -220.829092)
			(xy 98.655563 -220.852598) (xy 98.69745 -220.88303) (xy 98.73406 -220.91964) (xy 98.764492 -220.961527)
			(xy 98.787998 -221.007659) (xy 98.803997 -221.056899) (xy 98.812096 -221.108037) (xy 98.812604 -221.133924)
			(xy 99.093528 -221.133924) (xy 99.09401 -221.108589) (xy 99.10176 -221.058515) (xy 99.11708 -221.010217)
			(xy 99.139611 -220.964832) (xy 99.168821 -220.923429) (xy 99.204022 -220.886984) (xy 99.244386 -220.856354)
			(xy 99.288961 -220.83226) (xy 99.336698 -220.815272) (xy 99.361498 -220.810074) (xy 99.384358 -220.805756)
			(xy 99.589336 -220.450664) (xy 99.581462 -220.42882) (xy 99.572829 -220.402408) (xy 99.5635 -220.347635)
			(xy 99.56292 -220.319854) (xy 99.563428 -220.293947) (xy 99.571534 -220.24277) (xy 99.587546 -220.193491)
			(xy 99.611069 -220.147324) (xy 99.641525 -220.105405) (xy 99.678163 -220.068767) (xy 99.720082 -220.038311)
			(xy 99.766249 -220.014788) (xy 99.815528 -219.998776) (xy 99.866705 -219.99067) (xy 99.918519 -219.99067)
			(xy 99.969696 -219.998776) (xy 100.018975 -220.014788) (xy 100.065142 -220.038311) (xy 100.107061 -220.068767)
			(xy 100.143699 -220.105405) (xy 100.174155 -220.147324) (xy 100.197678 -220.193491) (xy 100.21369 -220.24277)
			(xy 100.221796 -220.293947) (xy 100.222304 -220.319854) (xy 100.221828 -220.345199) (xy 100.214049 -220.395289)
			(xy 100.198697 -220.443599) (xy 100.176134 -220.48899) (xy 100.146891 -220.530396) (xy 100.111657 -220.566839)
			(xy 100.071262 -220.597461) (xy 100.026657 -220.621543) (xy 99.978893 -220.638516) (xy 99.95408 -220.643704)
			(xy 99.93122 -220.648022) (xy 99.726242 -221.003114) (xy 99.734116 -221.024958) (xy 99.74271 -221.051373)
			(xy 99.751897 -221.106151) (xy 99.752404 -221.133924) (xy 100.033328 -221.133924) (xy 100.033836 -221.108037)
			(xy 100.041935 -221.056899) (xy 100.057934 -221.007659) (xy 100.08144 -220.961527) (xy 100.111872 -220.91964)
			(xy 100.148482 -220.88303) (xy 100.190369 -220.852598) (xy 100.236501 -220.829092) (xy 100.285741 -220.813093)
			(xy 100.336879 -220.804994) (xy 100.388653 -220.804994) (xy 100.439791 -220.813093) (xy 100.489031 -220.829092)
			(xy 100.535163 -220.852598) (xy 100.57705 -220.88303) (xy 100.61366 -220.91964) (xy 100.644092 -220.961527)
			(xy 100.667598 -221.007659) (xy 100.683597 -221.056899) (xy 100.691696 -221.108037) (xy 100.692204 -221.133924)
			(xy 100.973128 -221.133924) (xy 100.97361 -221.108589) (xy 100.98136 -221.058515) (xy 100.99668 -221.010217)
			(xy 101.019211 -220.964832) (xy 101.048421 -220.923429) (xy 101.083622 -220.886984) (xy 101.123986 -220.856354)
			(xy 101.168561 -220.83226) (xy 101.216298 -220.815272) (xy 101.241098 -220.810074) (xy 101.263958 -220.805756)
			(xy 101.468936 -220.450664) (xy 101.461062 -220.42882) (xy 101.452429 -220.402408) (xy 101.4431 -220.347635)
			(xy 101.44252 -220.319854) (xy 101.443028 -220.293947) (xy 101.451134 -220.24277) (xy 101.467146 -220.193491)
			(xy 101.490669 -220.147324) (xy 101.521125 -220.105405) (xy 101.557763 -220.068767) (xy 101.599682 -220.038311)
			(xy 101.645849 -220.014788) (xy 101.695128 -219.998776) (xy 101.746305 -219.99067) (xy 101.798119 -219.99067)
			(xy 101.849296 -219.998776) (xy 101.898575 -220.014788) (xy 101.944742 -220.038311) (xy 101.986661 -220.068767)
			(xy 102.023299 -220.105405) (xy 102.053755 -220.147324) (xy 102.077278 -220.193491) (xy 102.09329 -220.24277)
			(xy 102.101396 -220.293947) (xy 102.101904 -220.319854) (xy 102.101428 -220.345199) (xy 102.093649 -220.395289)
			(xy 102.078297 -220.443599) (xy 102.055734 -220.48899) (xy 102.026491 -220.530396) (xy 101.991257 -220.566839)
			(xy 101.950862 -220.597461) (xy 101.906257 -220.621543) (xy 101.858493 -220.638516) (xy 101.83368 -220.643704)
			(xy 101.81082 -220.648022) (xy 101.605842 -221.003114) (xy 101.613716 -221.024958) (xy 101.62231 -221.051373)
			(xy 101.631497 -221.106151) (xy 101.632004 -221.133924) (xy 101.912928 -221.133924) (xy 101.913436 -221.108037)
			(xy 101.921535 -221.056899) (xy 101.937534 -221.007659) (xy 101.96104 -220.961527) (xy 101.991472 -220.91964)
			(xy 102.028082 -220.88303) (xy 102.069969 -220.852598) (xy 102.116101 -220.829092) (xy 102.165341 -220.813093)
			(xy 102.216479 -220.804994) (xy 102.268253 -220.804994) (xy 102.319391 -220.813093) (xy 102.368631 -220.829092)
			(xy 102.414763 -220.852598) (xy 102.45665 -220.88303) (xy 102.49326 -220.91964) (xy 102.523692 -220.961527)
			(xy 102.547198 -221.007659) (xy 102.563197 -221.056899) (xy 102.571296 -221.108037) (xy 102.571804 -221.133924)
			(xy 102.852728 -221.133924) (xy 102.85321 -221.108589) (xy 102.86096 -221.058515) (xy 102.87628 -221.010217)
			(xy 102.898811 -220.964832) (xy 102.928021 -220.923429) (xy 102.963222 -220.886984) (xy 103.003586 -220.856354)
			(xy 103.048161 -220.83226) (xy 103.095898 -220.815272) (xy 103.120698 -220.810074) (xy 103.143558 -220.805756)
			(xy 103.348536 -220.450664) (xy 103.340662 -220.42882) (xy 103.332029 -220.402408) (xy 103.3227 -220.347635)
			(xy 103.32212 -220.319854) (xy 103.322628 -220.293947) (xy 103.330734 -220.24277) (xy 103.346746 -220.193491)
			(xy 103.370269 -220.147324) (xy 103.400725 -220.105405) (xy 103.437363 -220.068767) (xy 103.479282 -220.038311)
			(xy 103.525449 -220.014788) (xy 103.574728 -219.998776) (xy 103.625905 -219.99067) (xy 103.677719 -219.99067)
			(xy 103.728896 -219.998776) (xy 103.778175 -220.014788) (xy 103.824342 -220.038311) (xy 103.866261 -220.068767)
			(xy 103.902899 -220.105405) (xy 103.933355 -220.147324) (xy 103.956878 -220.193491) (xy 103.97289 -220.24277)
			(xy 103.980996 -220.293947) (xy 103.981504 -220.319854) (xy 105.20172 -220.319854) (xy 105.202228 -220.293947)
			(xy 105.210334 -220.24277) (xy 105.226346 -220.193491) (xy 105.249869 -220.147324) (xy 105.280325 -220.105405)
			(xy 105.316963 -220.068767) (xy 105.358882 -220.038311) (xy 105.405049 -220.014788) (xy 105.454328 -219.998776)
			(xy 105.505505 -219.99067) (xy 105.557319 -219.99067) (xy 105.608496 -219.998776) (xy 105.657775 -220.014788)
			(xy 105.703942 -220.038311) (xy 105.745861 -220.068767) (xy 105.782499 -220.105405) (xy 105.812955 -220.147324)
			(xy 105.836478 -220.193491) (xy 105.85249 -220.24277) (xy 105.860596 -220.293947) (xy 105.861104 -220.319854)
			(xy 107.08132 -220.319854) (xy 107.081828 -220.293947) (xy 107.089934 -220.24277) (xy 107.105946 -220.193491)
			(xy 107.129469 -220.147324) (xy 107.159925 -220.105405) (xy 107.196563 -220.068767) (xy 107.238482 -220.038311)
			(xy 107.284649 -220.014788) (xy 107.333928 -219.998776) (xy 107.385105 -219.99067) (xy 107.436919 -219.99067)
			(xy 107.488096 -219.998776) (xy 107.537375 -220.014788) (xy 107.583542 -220.038311) (xy 107.625461 -220.068767)
			(xy 107.662099 -220.105405) (xy 107.692555 -220.147324) (xy 107.716078 -220.193491) (xy 107.73209 -220.24277)
			(xy 107.740196 -220.293947) (xy 107.740704 -220.319854) (xy 108.96092 -220.319854) (xy 108.961428 -220.293947)
			(xy 108.969534 -220.24277) (xy 108.985546 -220.193491) (xy 109.009069 -220.147324) (xy 109.039525 -220.105405)
			(xy 109.076163 -220.068767) (xy 109.118082 -220.038311) (xy 109.164249 -220.014788) (xy 109.213528 -219.998776)
			(xy 109.264705 -219.99067) (xy 109.316519 -219.99067) (xy 109.367696 -219.998776) (xy 109.416975 -220.014788)
			(xy 109.463142 -220.038311) (xy 109.505061 -220.068767) (xy 109.541699 -220.105405) (xy 109.572155 -220.147324)
			(xy 109.595678 -220.193491) (xy 109.61169 -220.24277) (xy 109.619796 -220.293947) (xy 109.620304 -220.319854)
			(xy 110.84052 -220.319854) (xy 110.841028 -220.293947) (xy 110.849134 -220.24277) (xy 110.865146 -220.193491)
			(xy 110.888669 -220.147324) (xy 110.919125 -220.105405) (xy 110.955763 -220.068767) (xy 110.997682 -220.038311)
			(xy 111.043849 -220.014788) (xy 111.093128 -219.998776) (xy 111.144305 -219.99067) (xy 111.196119 -219.99067)
			(xy 111.247296 -219.998776) (xy 111.296575 -220.014788) (xy 111.342742 -220.038311) (xy 111.384661 -220.068767)
			(xy 111.421299 -220.105405) (xy 111.451755 -220.147324) (xy 111.475278 -220.193491) (xy 111.49129 -220.24277)
			(xy 111.499396 -220.293947) (xy 111.499904 -220.319854) (xy 112.72012 -220.319854) (xy 112.720628 -220.293947)
			(xy 112.728734 -220.24277) (xy 112.744746 -220.193491) (xy 112.768269 -220.147324) (xy 112.798725 -220.105405)
			(xy 112.835363 -220.068767) (xy 112.877282 -220.038311) (xy 112.923449 -220.014788) (xy 112.972728 -219.998776)
			(xy 113.023905 -219.99067) (xy 113.075719 -219.99067) (xy 113.126896 -219.998776) (xy 113.176175 -220.014788)
			(xy 113.222342 -220.038311) (xy 113.264261 -220.068767) (xy 113.300899 -220.105405) (xy 113.331355 -220.147324)
			(xy 113.354878 -220.193491) (xy 113.37089 -220.24277) (xy 113.378996 -220.293947) (xy 113.379504 -220.319854)
			(xy 114.59972 -220.319854) (xy 114.600228 -220.293947) (xy 114.608334 -220.24277) (xy 114.624346 -220.193491)
			(xy 114.647869 -220.147324) (xy 114.678325 -220.105405) (xy 114.714963 -220.068767) (xy 114.756882 -220.038311)
			(xy 114.803049 -220.014788) (xy 114.852328 -219.998776) (xy 114.903505 -219.99067) (xy 114.955319 -219.99067)
			(xy 115.006496 -219.998776) (xy 115.055775 -220.014788) (xy 115.101942 -220.038311) (xy 115.143861 -220.068767)
			(xy 115.180499 -220.105405) (xy 115.210955 -220.147324) (xy 115.234478 -220.193491) (xy 115.25049 -220.24277)
			(xy 115.258596 -220.293947) (xy 115.259104 -220.319854) (xy 116.47932 -220.319854) (xy 116.479828 -220.293947)
			(xy 116.487934 -220.24277) (xy 116.503946 -220.193491) (xy 116.527469 -220.147324) (xy 116.557925 -220.105405)
			(xy 116.594563 -220.068767) (xy 116.636482 -220.038311) (xy 116.682649 -220.014788) (xy 116.731928 -219.998776)
			(xy 116.783105 -219.99067) (xy 116.834919 -219.99067) (xy 116.886096 -219.998776) (xy 116.935375 -220.014788)
			(xy 116.981542 -220.038311) (xy 117.023461 -220.068767) (xy 117.060099 -220.105405) (xy 117.090555 -220.147324)
			(xy 117.114078 -220.193491) (xy 117.13009 -220.24277) (xy 117.138196 -220.293947) (xy 117.138704 -220.319854)
			(xy 118.35892 -220.319854) (xy 118.359428 -220.293947) (xy 118.367534 -220.24277) (xy 118.383546 -220.193491)
			(xy 118.407069 -220.147324) (xy 118.437525 -220.105405) (xy 118.474163 -220.068767) (xy 118.516082 -220.038311)
			(xy 118.562249 -220.014788) (xy 118.611528 -219.998776) (xy 118.662705 -219.99067) (xy 118.714519 -219.99067)
			(xy 118.765696 -219.998776) (xy 118.814975 -220.014788) (xy 118.861142 -220.038311) (xy 118.903061 -220.068767)
			(xy 118.939699 -220.105405) (xy 118.970155 -220.147324) (xy 118.993678 -220.193491) (xy 119.00969 -220.24277)
			(xy 119.017796 -220.293947) (xy 119.018304 -220.319854) (xy 120.23852 -220.319854) (xy 120.239028 -220.293947)
			(xy 120.247134 -220.24277) (xy 120.263146 -220.193491) (xy 120.286669 -220.147324) (xy 120.317125 -220.105405)
			(xy 120.353763 -220.068767) (xy 120.395682 -220.038311) (xy 120.441849 -220.014788) (xy 120.491128 -219.998776)
			(xy 120.542305 -219.99067) (xy 120.594119 -219.99067) (xy 120.645296 -219.998776) (xy 120.694575 -220.014788)
			(xy 120.740742 -220.038311) (xy 120.782661 -220.068767) (xy 120.819299 -220.105405) (xy 120.849755 -220.147324)
			(xy 120.873278 -220.193491) (xy 120.88929 -220.24277) (xy 120.897396 -220.293947) (xy 120.897904 -220.319854)
			(xy 122.11812 -220.319854) (xy 122.118628 -220.293947) (xy 122.126734 -220.24277) (xy 122.142746 -220.193491)
			(xy 122.166269 -220.147324) (xy 122.196725 -220.105405) (xy 122.233363 -220.068767) (xy 122.275282 -220.038311)
			(xy 122.321449 -220.014788) (xy 122.370728 -219.998776) (xy 122.421905 -219.99067) (xy 122.473719 -219.99067)
			(xy 122.524896 -219.998776) (xy 122.574175 -220.014788) (xy 122.620342 -220.038311) (xy 122.662261 -220.068767)
			(xy 122.698899 -220.105405) (xy 122.729355 -220.147324) (xy 122.752878 -220.193491) (xy 122.76889 -220.24277)
			(xy 122.776996 -220.293947) (xy 122.777504 -220.319854) (xy 123.99772 -220.319854) (xy 123.998228 -220.293947)
			(xy 124.006334 -220.24277) (xy 124.022346 -220.193491) (xy 124.045869 -220.147324) (xy 124.076325 -220.105405)
			(xy 124.112963 -220.068767) (xy 124.154882 -220.038311) (xy 124.201049 -220.014788) (xy 124.250328 -219.998776)
			(xy 124.301505 -219.99067) (xy 124.353319 -219.99067) (xy 124.404496 -219.998776) (xy 124.453775 -220.014788)
			(xy 124.499942 -220.038311) (xy 124.541861 -220.068767) (xy 124.578499 -220.105405) (xy 124.608955 -220.147324)
			(xy 124.632478 -220.193491) (xy 124.64849 -220.24277) (xy 124.656596 -220.293947) (xy 124.657104 -220.319854)
			(xy 125.87732 -220.319854) (xy 125.877828 -220.293947) (xy 125.885934 -220.24277) (xy 125.901946 -220.193491)
			(xy 125.925469 -220.147324) (xy 125.955925 -220.105405) (xy 125.992563 -220.068767) (xy 126.034482 -220.038311)
			(xy 126.080649 -220.014788) (xy 126.129928 -219.998776) (xy 126.181105 -219.99067) (xy 126.232919 -219.99067)
			(xy 126.284096 -219.998776) (xy 126.333375 -220.014788) (xy 126.379542 -220.038311) (xy 126.421461 -220.068767)
			(xy 126.458099 -220.105405) (xy 126.488555 -220.147324) (xy 126.512078 -220.193491) (xy 126.52809 -220.24277)
			(xy 126.536196 -220.293947) (xy 126.536704 -220.319854) (xy 127.75692 -220.319854) (xy 127.757428 -220.293947)
			(xy 127.765534 -220.24277) (xy 127.781546 -220.193491) (xy 127.805069 -220.147324) (xy 127.835525 -220.105405)
			(xy 127.872163 -220.068767) (xy 127.914082 -220.038311) (xy 127.960249 -220.014788) (xy 128.009528 -219.998776)
			(xy 128.060705 -219.99067) (xy 128.112519 -219.99067) (xy 128.163696 -219.998776) (xy 128.212975 -220.014788)
			(xy 128.259142 -220.038311) (xy 128.301061 -220.068767) (xy 128.337699 -220.105405) (xy 128.368155 -220.147324)
			(xy 128.391678 -220.193491) (xy 128.40769 -220.24277) (xy 128.415796 -220.293947) (xy 128.416304 -220.319854)
			(xy 129.63652 -220.319854) (xy 129.637028 -220.293947) (xy 129.645134 -220.24277) (xy 129.661146 -220.193491)
			(xy 129.684669 -220.147324) (xy 129.715125 -220.105405) (xy 129.751763 -220.068767) (xy 129.793682 -220.038311)
			(xy 129.839849 -220.014788) (xy 129.889128 -219.998776) (xy 129.940305 -219.99067) (xy 129.992119 -219.99067)
			(xy 130.043296 -219.998776) (xy 130.092575 -220.014788) (xy 130.138742 -220.038311) (xy 130.180661 -220.068767)
			(xy 130.217299 -220.105405) (xy 130.247755 -220.147324) (xy 130.271278 -220.193491) (xy 130.28729 -220.24277)
			(xy 130.295396 -220.293947) (xy 130.295904 -220.319854) (xy 131.51612 -220.319854) (xy 131.516628 -220.293947)
			(xy 131.524734 -220.24277) (xy 131.540746 -220.193491) (xy 131.564269 -220.147324) (xy 131.594725 -220.105405)
			(xy 131.631363 -220.068767) (xy 131.673282 -220.038311) (xy 131.719449 -220.014788) (xy 131.768728 -219.998776)
			(xy 131.819905 -219.99067) (xy 131.871719 -219.99067) (xy 131.922896 -219.998776) (xy 131.972175 -220.014788)
			(xy 132.018342 -220.038311) (xy 132.060261 -220.068767) (xy 132.096899 -220.105405) (xy 132.127355 -220.147324)
			(xy 132.150878 -220.193491) (xy 132.16689 -220.24277) (xy 132.174996 -220.293947) (xy 132.175504 -220.319854)
			(xy 133.396228 -220.319854) (xy 133.396736 -220.293967) (xy 133.404835 -220.242829) (xy 133.420834 -220.193589)
			(xy 133.44434 -220.147457) (xy 133.474772 -220.10557) (xy 133.511382 -220.06896) (xy 133.553269 -220.038528)
			(xy 133.599401 -220.015022) (xy 133.648641 -219.999023) (xy 133.699779 -219.990924) (xy 133.751553 -219.990924)
			(xy 133.802691 -219.999023) (xy 133.851931 -220.015022) (xy 133.898063 -220.038528) (xy 133.93995 -220.06896)
			(xy 133.97656 -220.10557) (xy 134.006992 -220.147457) (xy 134.030498 -220.193589) (xy 134.046497 -220.242829)
			(xy 134.054596 -220.293967) (xy 134.055104 -220.319854) (xy 134.054563 -220.347562) (xy 134.045375 -220.402208)
			(xy 134.036816 -220.428566) (xy 134.029196 -220.450664) (xy 134.234174 -220.805756) (xy 134.257034 -220.810074)
			(xy 134.281845 -220.815229) (xy 134.329584 -220.832223) (xy 134.374162 -220.856322) (xy 134.414527 -220.886957)
			(xy 134.44973 -220.923408) (xy 134.47894 -220.964816) (xy 134.501472 -221.010206) (xy 134.516792 -221.058509)
			(xy 134.524542 -221.108587) (xy 134.525004 -221.133924) (xy 134.524496 -221.159811) (xy 134.516397 -221.210949)
			(xy 134.500398 -221.260189) (xy 134.476892 -221.306321) (xy 134.44646 -221.348208) (xy 134.40985 -221.384818)
			(xy 134.367963 -221.41525) (xy 134.321831 -221.438756) (xy 134.272591 -221.454755) (xy 134.221453 -221.462854)
			(xy 134.169679 -221.462854) (xy 134.118541 -221.454755) (xy 134.069301 -221.438756) (xy 134.023169 -221.41525)
			(xy 133.981282 -221.384818) (xy 133.944672 -221.348208) (xy 133.91424 -221.306321) (xy 133.890734 -221.260189)
			(xy 133.874735 -221.210949) (xy 133.866636 -221.159811) (xy 133.866128 -221.133924) (xy 133.866667 -221.106216)
			(xy 133.875856 -221.05157) (xy 133.884416 -221.025212) (xy 133.89229 -221.003114) (xy 133.687312 -220.648022)
			(xy 133.664452 -220.643704) (xy 133.639631 -220.638536) (xy 133.591852 -220.621582) (xy 133.547233 -220.59751)
			(xy 133.506826 -220.56689) (xy 133.471585 -220.530444) (xy 133.442341 -220.48903) (xy 133.419784 -220.443627)
			(xy 133.404447 -220.395304) (xy 133.39669 -220.345203) (xy 133.396228 -220.319854) (xy 132.175504 -220.319854)
			(xy 132.174894 -220.347507) (xy 132.165571 -220.402025) (xy 132.156962 -220.428312) (xy 132.149342 -220.45041)
			(xy 132.354574 -220.805756) (xy 132.377434 -220.810074) (xy 132.402245 -220.815229) (xy 132.449984 -220.832223)
			(xy 132.494562 -220.856322) (xy 132.534927 -220.886957) (xy 132.57013 -220.923408) (xy 132.59934 -220.964816)
			(xy 132.621872 -221.010206) (xy 132.637192 -221.058509) (xy 132.644942 -221.108587) (xy 132.645404 -221.133924)
			(xy 132.644896 -221.159811) (xy 132.636797 -221.210949) (xy 132.620798 -221.260189) (xy 132.597292 -221.306321)
			(xy 132.56686 -221.348208) (xy 132.53025 -221.384818) (xy 132.488363 -221.41525) (xy 132.442231 -221.438756)
			(xy 132.392991 -221.454755) (xy 132.341853 -221.462854) (xy 132.290079 -221.462854) (xy 132.238941 -221.454755)
			(xy 132.189701 -221.438756) (xy 132.143569 -221.41525) (xy 132.101682 -221.384818) (xy 132.065072 -221.348208)
			(xy 132.03464 -221.306321) (xy 132.011134 -221.260189) (xy 131.995135 -221.210949) (xy 131.987036 -221.159811)
			(xy 131.986528 -221.133924) (xy 131.987067 -221.106216) (xy 131.996256 -221.05157) (xy 132.004816 -221.025212)
			(xy 132.01269 -221.003114) (xy 131.807712 -220.648022) (xy 131.784852 -220.643704) (xy 131.76 -220.63857)
			(xy 131.712153 -220.621668) (xy 131.667462 -220.597632) (xy 131.626984 -220.567029) (xy 131.591674 -220.530584)
			(xy 131.562368 -220.489157) (xy 131.539757 -220.443728) (xy 131.524377 -220.39537) (xy 131.516591 -220.345226)
			(xy 131.51612 -220.319854) (xy 130.295904 -220.319854) (xy 130.295294 -220.347507) (xy 130.285971 -220.402025)
			(xy 130.277362 -220.428312) (xy 130.269742 -220.45041) (xy 130.474974 -220.805756) (xy 130.497834 -220.810074)
			(xy 130.522645 -220.815229) (xy 130.570384 -220.832223) (xy 130.614962 -220.856322) (xy 130.655327 -220.886957)
			(xy 130.69053 -220.923408) (xy 130.71974 -220.964816) (xy 130.742272 -221.010206) (xy 130.757592 -221.058509)
			(xy 130.765342 -221.108587) (xy 130.765804 -221.133924) (xy 130.765296 -221.159811) (xy 130.757197 -221.210949)
			(xy 130.741198 -221.260189) (xy 130.717692 -221.306321) (xy 130.68726 -221.348208) (xy 130.65065 -221.384818)
			(xy 130.608763 -221.41525) (xy 130.562631 -221.438756) (xy 130.513391 -221.454755) (xy 130.462253 -221.462854)
			(xy 130.410479 -221.462854) (xy 130.359341 -221.454755) (xy 130.310101 -221.438756) (xy 130.263969 -221.41525)
			(xy 130.222082 -221.384818) (xy 130.185472 -221.348208) (xy 130.15504 -221.306321) (xy 130.131534 -221.260189)
			(xy 130.115535 -221.210949) (xy 130.107436 -221.159811) (xy 130.106928 -221.133924) (xy 130.107467 -221.106216)
			(xy 130.116656 -221.05157) (xy 130.125216 -221.025212) (xy 130.13309 -221.003114) (xy 129.928112 -220.648022)
			(xy 129.905252 -220.643704) (xy 129.8804 -220.63857) (xy 129.832553 -220.621668) (xy 129.787862 -220.597632)
			(xy 129.747384 -220.567029) (xy 129.712074 -220.530584) (xy 129.682768 -220.489157) (xy 129.660157 -220.443728)
			(xy 129.644777 -220.39537) (xy 129.636991 -220.345226) (xy 129.63652 -220.319854) (xy 128.416304 -220.319854)
			(xy 128.415694 -220.347507) (xy 128.406371 -220.402025) (xy 128.397762 -220.428312) (xy 128.390142 -220.45041)
			(xy 128.595374 -220.805756) (xy 128.618234 -220.810074) (xy 128.643045 -220.815229) (xy 128.690784 -220.832223)
			(xy 128.735362 -220.856322) (xy 128.775727 -220.886957) (xy 128.81093 -220.923408) (xy 128.84014 -220.964816)
			(xy 128.862672 -221.010206) (xy 128.877992 -221.058509) (xy 128.885742 -221.108587) (xy 128.886204 -221.133924)
			(xy 128.885696 -221.159811) (xy 128.877597 -221.210949) (xy 128.861598 -221.260189) (xy 128.838092 -221.306321)
			(xy 128.80766 -221.348208) (xy 128.77105 -221.384818) (xy 128.729163 -221.41525) (xy 128.683031 -221.438756)
			(xy 128.633791 -221.454755) (xy 128.582653 -221.462854) (xy 128.530879 -221.462854) (xy 128.479741 -221.454755)
			(xy 128.430501 -221.438756) (xy 128.384369 -221.41525) (xy 128.342482 -221.384818) (xy 128.305872 -221.348208)
			(xy 128.27544 -221.306321) (xy 128.251934 -221.260189) (xy 128.235935 -221.210949) (xy 128.227836 -221.159811)
			(xy 128.227328 -221.133924) (xy 128.227867 -221.106216) (xy 128.237056 -221.05157) (xy 128.245616 -221.025212)
			(xy 128.25349 -221.003114) (xy 128.048512 -220.648022) (xy 128.025652 -220.643704) (xy 128.0008 -220.63857)
			(xy 127.952953 -220.621668) (xy 127.908262 -220.597632) (xy 127.867784 -220.567029) (xy 127.832474 -220.530584)
			(xy 127.803168 -220.489157) (xy 127.780557 -220.443728) (xy 127.765177 -220.39537) (xy 127.757391 -220.345226)
			(xy 127.75692 -220.319854) (xy 126.536704 -220.319854) (xy 126.536094 -220.347507) (xy 126.526771 -220.402025)
			(xy 126.518162 -220.428312) (xy 126.510542 -220.45041) (xy 126.715774 -220.805756) (xy 126.738634 -220.810074)
			(xy 126.763445 -220.815229) (xy 126.811184 -220.832223) (xy 126.855762 -220.856322) (xy 126.896127 -220.886957)
			(xy 126.93133 -220.923408) (xy 126.96054 -220.964816) (xy 126.983072 -221.010206) (xy 126.998392 -221.058509)
			(xy 127.006142 -221.108587) (xy 127.006604 -221.133924) (xy 127.006096 -221.159811) (xy 126.997997 -221.210949)
			(xy 126.981998 -221.260189) (xy 126.958492 -221.306321) (xy 126.92806 -221.348208) (xy 126.89145 -221.384818)
			(xy 126.849563 -221.41525) (xy 126.803431 -221.438756) (xy 126.754191 -221.454755) (xy 126.703053 -221.462854)
			(xy 126.651279 -221.462854) (xy 126.600141 -221.454755) (xy 126.550901 -221.438756) (xy 126.504769 -221.41525)
			(xy 126.462882 -221.384818) (xy 126.426272 -221.348208) (xy 126.39584 -221.306321) (xy 126.372334 -221.260189)
			(xy 126.356335 -221.210949) (xy 126.348236 -221.159811) (xy 126.347728 -221.133924) (xy 126.348267 -221.106216)
			(xy 126.357456 -221.05157) (xy 126.366016 -221.025212) (xy 126.37389 -221.003114) (xy 126.168912 -220.648022)
			(xy 126.146052 -220.643704) (xy 126.1212 -220.63857) (xy 126.073353 -220.621668) (xy 126.028662 -220.597632)
			(xy 125.988184 -220.567029) (xy 125.952874 -220.530584) (xy 125.923568 -220.489157) (xy 125.900957 -220.443728)
			(xy 125.885577 -220.39537) (xy 125.877791 -220.345226) (xy 125.87732 -220.319854) (xy 124.657104 -220.319854)
			(xy 124.656494 -220.347507) (xy 124.647171 -220.402025) (xy 124.638562 -220.428312) (xy 124.630942 -220.45041)
			(xy 124.836174 -220.805756) (xy 124.859034 -220.810074) (xy 124.883845 -220.815229) (xy 124.931584 -220.832223)
			(xy 124.976162 -220.856322) (xy 125.016527 -220.886957) (xy 125.05173 -220.923408) (xy 125.08094 -220.964816)
			(xy 125.103472 -221.010206) (xy 125.118792 -221.058509) (xy 125.126542 -221.108587) (xy 125.127004 -221.133924)
			(xy 125.126496 -221.159811) (xy 125.118397 -221.210949) (xy 125.102398 -221.260189) (xy 125.078892 -221.306321)
			(xy 125.04846 -221.348208) (xy 125.01185 -221.384818) (xy 124.969963 -221.41525) (xy 124.923831 -221.438756)
			(xy 124.874591 -221.454755) (xy 124.823453 -221.462854) (xy 124.771679 -221.462854) (xy 124.720541 -221.454755)
			(xy 124.671301 -221.438756) (xy 124.625169 -221.41525) (xy 124.583282 -221.384818) (xy 124.546672 -221.348208)
			(xy 124.51624 -221.306321) (xy 124.492734 -221.260189) (xy 124.476735 -221.210949) (xy 124.468636 -221.159811)
			(xy 124.468128 -221.133924) (xy 124.468667 -221.106216) (xy 124.477856 -221.05157) (xy 124.486416 -221.025212)
			(xy 124.49429 -221.003114) (xy 124.289312 -220.648022) (xy 124.266452 -220.643704) (xy 124.2416 -220.63857)
			(xy 124.193753 -220.621668) (xy 124.149062 -220.597632) (xy 124.108584 -220.567029) (xy 124.073274 -220.530584)
			(xy 124.043968 -220.489157) (xy 124.021357 -220.443728) (xy 124.005977 -220.39537) (xy 123.998191 -220.345226)
			(xy 123.99772 -220.319854) (xy 122.777504 -220.319854) (xy 122.776894 -220.347507) (xy 122.767571 -220.402025)
			(xy 122.758962 -220.428312) (xy 122.751342 -220.45041) (xy 122.956574 -220.805756) (xy 122.979434 -220.810074)
			(xy 123.004245 -220.815229) (xy 123.051984 -220.832223) (xy 123.096562 -220.856322) (xy 123.136927 -220.886957)
			(xy 123.17213 -220.923408) (xy 123.20134 -220.964816) (xy 123.223872 -221.010206) (xy 123.239192 -221.058509)
			(xy 123.246942 -221.108587) (xy 123.247404 -221.133924) (xy 123.246896 -221.159811) (xy 123.238797 -221.210949)
			(xy 123.222798 -221.260189) (xy 123.199292 -221.306321) (xy 123.16886 -221.348208) (xy 123.13225 -221.384818)
			(xy 123.090363 -221.41525) (xy 123.044231 -221.438756) (xy 122.994991 -221.454755) (xy 122.943853 -221.462854)
			(xy 122.892079 -221.462854) (xy 122.840941 -221.454755) (xy 122.791701 -221.438756) (xy 122.745569 -221.41525)
			(xy 122.703682 -221.384818) (xy 122.667072 -221.348208) (xy 122.63664 -221.306321) (xy 122.613134 -221.260189)
			(xy 122.597135 -221.210949) (xy 122.589036 -221.159811) (xy 122.588528 -221.133924) (xy 122.589067 -221.106216)
			(xy 122.598256 -221.05157) (xy 122.606816 -221.025212) (xy 122.61469 -221.003114) (xy 122.409712 -220.648022)
			(xy 122.386852 -220.643704) (xy 122.362 -220.63857) (xy 122.314153 -220.621668) (xy 122.269462 -220.597632)
			(xy 122.228984 -220.567029) (xy 122.193674 -220.530584) (xy 122.164368 -220.489157) (xy 122.141757 -220.443728)
			(xy 122.126377 -220.39537) (xy 122.118591 -220.345226) (xy 122.11812 -220.319854) (xy 120.897904 -220.319854)
			(xy 120.897294 -220.347507) (xy 120.887971 -220.402025) (xy 120.879362 -220.428312) (xy 120.871742 -220.45041)
			(xy 121.076974 -220.805756) (xy 121.099834 -220.810074) (xy 121.124645 -220.815229) (xy 121.172384 -220.832223)
			(xy 121.216962 -220.856322) (xy 121.257327 -220.886957) (xy 121.29253 -220.923408) (xy 121.32174 -220.964816)
			(xy 121.344272 -221.010206) (xy 121.359592 -221.058509) (xy 121.367342 -221.108587) (xy 121.367804 -221.133924)
			(xy 121.367296 -221.159811) (xy 121.359197 -221.210949) (xy 121.343198 -221.260189) (xy 121.319692 -221.306321)
			(xy 121.28926 -221.348208) (xy 121.25265 -221.384818) (xy 121.210763 -221.41525) (xy 121.164631 -221.438756)
			(xy 121.115391 -221.454755) (xy 121.064253 -221.462854) (xy 121.012479 -221.462854) (xy 120.961341 -221.454755)
			(xy 120.912101 -221.438756) (xy 120.865969 -221.41525) (xy 120.824082 -221.384818) (xy 120.787472 -221.348208)
			(xy 120.75704 -221.306321) (xy 120.733534 -221.260189) (xy 120.717535 -221.210949) (xy 120.709436 -221.159811)
			(xy 120.708928 -221.133924) (xy 120.709467 -221.106216) (xy 120.718656 -221.05157) (xy 120.727216 -221.025212)
			(xy 120.73509 -221.003114) (xy 120.530112 -220.648022) (xy 120.507252 -220.643704) (xy 120.4824 -220.63857)
			(xy 120.434553 -220.621668) (xy 120.389862 -220.597632) (xy 120.349384 -220.567029) (xy 120.314074 -220.530584)
			(xy 120.284768 -220.489157) (xy 120.262157 -220.443728) (xy 120.246777 -220.39537) (xy 120.238991 -220.345226)
			(xy 120.23852 -220.319854) (xy 119.018304 -220.319854) (xy 119.017694 -220.347507) (xy 119.008371 -220.402025)
			(xy 118.999762 -220.428312) (xy 118.992142 -220.45041) (xy 119.197374 -220.805756) (xy 119.220234 -220.810074)
			(xy 119.245045 -220.815229) (xy 119.292784 -220.832223) (xy 119.337362 -220.856322) (xy 119.377727 -220.886957)
			(xy 119.41293 -220.923408) (xy 119.44214 -220.964816) (xy 119.464672 -221.010206) (xy 119.479992 -221.058509)
			(xy 119.487742 -221.108587) (xy 119.488204 -221.133924) (xy 119.487696 -221.159811) (xy 119.479597 -221.210949)
			(xy 119.463598 -221.260189) (xy 119.440092 -221.306321) (xy 119.40966 -221.348208) (xy 119.37305 -221.384818)
			(xy 119.331163 -221.41525) (xy 119.285031 -221.438756) (xy 119.235791 -221.454755) (xy 119.184653 -221.462854)
			(xy 119.132879 -221.462854) (xy 119.081741 -221.454755) (xy 119.032501 -221.438756) (xy 118.986369 -221.41525)
			(xy 118.944482 -221.384818) (xy 118.907872 -221.348208) (xy 118.87744 -221.306321) (xy 118.853934 -221.260189)
			(xy 118.837935 -221.210949) (xy 118.829836 -221.159811) (xy 118.829328 -221.133924) (xy 118.829867 -221.106216)
			(xy 118.839056 -221.05157) (xy 118.847616 -221.025212) (xy 118.85549 -221.003114) (xy 118.650512 -220.648022)
			(xy 118.627652 -220.643704) (xy 118.6028 -220.63857) (xy 118.554953 -220.621668) (xy 118.510262 -220.597632)
			(xy 118.469784 -220.567029) (xy 118.434474 -220.530584) (xy 118.405168 -220.489157) (xy 118.382557 -220.443728)
			(xy 118.367177 -220.39537) (xy 118.359391 -220.345226) (xy 118.35892 -220.319854) (xy 117.138704 -220.319854)
			(xy 117.138094 -220.347507) (xy 117.128771 -220.402025) (xy 117.120162 -220.428312) (xy 117.112542 -220.45041)
			(xy 117.317774 -220.805756) (xy 117.340634 -220.810074) (xy 117.365445 -220.815229) (xy 117.413184 -220.832223)
			(xy 117.457762 -220.856322) (xy 117.498127 -220.886957) (xy 117.53333 -220.923408) (xy 117.56254 -220.964816)
			(xy 117.585072 -221.010206) (xy 117.600392 -221.058509) (xy 117.608142 -221.108587) (xy 117.608604 -221.133924)
			(xy 117.608096 -221.159811) (xy 117.599997 -221.210949) (xy 117.583998 -221.260189) (xy 117.560492 -221.306321)
			(xy 117.53006 -221.348208) (xy 117.49345 -221.384818) (xy 117.451563 -221.41525) (xy 117.405431 -221.438756)
			(xy 117.356191 -221.454755) (xy 117.305053 -221.462854) (xy 117.253279 -221.462854) (xy 117.202141 -221.454755)
			(xy 117.152901 -221.438756) (xy 117.106769 -221.41525) (xy 117.064882 -221.384818) (xy 117.028272 -221.348208)
			(xy 116.99784 -221.306321) (xy 116.974334 -221.260189) (xy 116.958335 -221.210949) (xy 116.950236 -221.159811)
			(xy 116.949728 -221.133924) (xy 116.950267 -221.106216) (xy 116.959456 -221.05157) (xy 116.968016 -221.025212)
			(xy 116.97589 -221.003114) (xy 116.770912 -220.648022) (xy 116.748052 -220.643704) (xy 116.7232 -220.63857)
			(xy 116.675353 -220.621668) (xy 116.630662 -220.597632) (xy 116.590184 -220.567029) (xy 116.554874 -220.530584)
			(xy 116.525568 -220.489157) (xy 116.502957 -220.443728) (xy 116.487577 -220.39537) (xy 116.479791 -220.345226)
			(xy 116.47932 -220.319854) (xy 115.259104 -220.319854) (xy 115.258494 -220.347507) (xy 115.249171 -220.402025)
			(xy 115.240562 -220.428312) (xy 115.232942 -220.45041) (xy 115.438174 -220.805756) (xy 115.461034 -220.810074)
			(xy 115.485845 -220.815229) (xy 115.533584 -220.832223) (xy 115.578162 -220.856322) (xy 115.618527 -220.886957)
			(xy 115.65373 -220.923408) (xy 115.68294 -220.964816) (xy 115.705472 -221.010206) (xy 115.720792 -221.058509)
			(xy 115.728542 -221.108587) (xy 115.729004 -221.133924) (xy 115.728496 -221.159811) (xy 115.720397 -221.210949)
			(xy 115.704398 -221.260189) (xy 115.680892 -221.306321) (xy 115.65046 -221.348208) (xy 115.61385 -221.384818)
			(xy 115.571963 -221.41525) (xy 115.525831 -221.438756) (xy 115.476591 -221.454755) (xy 115.425453 -221.462854)
			(xy 115.373679 -221.462854) (xy 115.322541 -221.454755) (xy 115.273301 -221.438756) (xy 115.227169 -221.41525)
			(xy 115.185282 -221.384818) (xy 115.148672 -221.348208) (xy 115.11824 -221.306321) (xy 115.094734 -221.260189)
			(xy 115.078735 -221.210949) (xy 115.070636 -221.159811) (xy 115.070128 -221.133924) (xy 115.070667 -221.106216)
			(xy 115.079856 -221.05157) (xy 115.088416 -221.025212) (xy 115.09629 -221.003114) (xy 114.891312 -220.648022)
			(xy 114.868452 -220.643704) (xy 114.8436 -220.63857) (xy 114.795753 -220.621668) (xy 114.751062 -220.597632)
			(xy 114.710584 -220.567029) (xy 114.675274 -220.530584) (xy 114.645968 -220.489157) (xy 114.623357 -220.443728)
			(xy 114.607977 -220.39537) (xy 114.600191 -220.345226) (xy 114.59972 -220.319854) (xy 113.379504 -220.319854)
			(xy 113.378894 -220.347507) (xy 113.369571 -220.402025) (xy 113.360962 -220.428312) (xy 113.353342 -220.45041)
			(xy 113.558574 -220.805756) (xy 113.581434 -220.810074) (xy 113.606245 -220.815229) (xy 113.653984 -220.832223)
			(xy 113.698562 -220.856322) (xy 113.738927 -220.886957) (xy 113.77413 -220.923408) (xy 113.80334 -220.964816)
			(xy 113.825872 -221.010206) (xy 113.841192 -221.058509) (xy 113.848942 -221.108587) (xy 113.849404 -221.133924)
			(xy 113.848896 -221.159811) (xy 113.840797 -221.210949) (xy 113.824798 -221.260189) (xy 113.801292 -221.306321)
			(xy 113.77086 -221.348208) (xy 113.73425 -221.384818) (xy 113.692363 -221.41525) (xy 113.646231 -221.438756)
			(xy 113.596991 -221.454755) (xy 113.545853 -221.462854) (xy 113.494079 -221.462854) (xy 113.442941 -221.454755)
			(xy 113.393701 -221.438756) (xy 113.347569 -221.41525) (xy 113.305682 -221.384818) (xy 113.269072 -221.348208)
			(xy 113.23864 -221.306321) (xy 113.215134 -221.260189) (xy 113.199135 -221.210949) (xy 113.191036 -221.159811)
			(xy 113.190528 -221.133924) (xy 113.191067 -221.106216) (xy 113.200256 -221.05157) (xy 113.208816 -221.025212)
			(xy 113.21669 -221.003114) (xy 113.011712 -220.648022) (xy 112.988852 -220.643704) (xy 112.964 -220.63857)
			(xy 112.916153 -220.621668) (xy 112.871462 -220.597632) (xy 112.830984 -220.567029) (xy 112.795674 -220.530584)
			(xy 112.766368 -220.489157) (xy 112.743757 -220.443728) (xy 112.728377 -220.39537) (xy 112.720591 -220.345226)
			(xy 112.72012 -220.319854) (xy 111.499904 -220.319854) (xy 111.499294 -220.347507) (xy 111.489971 -220.402025)
			(xy 111.481362 -220.428312) (xy 111.473742 -220.45041) (xy 111.678974 -220.805756) (xy 111.701834 -220.810074)
			(xy 111.726645 -220.815229) (xy 111.774384 -220.832223) (xy 111.818962 -220.856322) (xy 111.859327 -220.886957)
			(xy 111.89453 -220.923408) (xy 111.92374 -220.964816) (xy 111.946272 -221.010206) (xy 111.961592 -221.058509)
			(xy 111.969342 -221.108587) (xy 111.969804 -221.133924) (xy 111.969296 -221.159811) (xy 111.961197 -221.210949)
			(xy 111.945198 -221.260189) (xy 111.921692 -221.306321) (xy 111.89126 -221.348208) (xy 111.85465 -221.384818)
			(xy 111.812763 -221.41525) (xy 111.766631 -221.438756) (xy 111.717391 -221.454755) (xy 111.666253 -221.462854)
			(xy 111.614479 -221.462854) (xy 111.563341 -221.454755) (xy 111.514101 -221.438756) (xy 111.467969 -221.41525)
			(xy 111.426082 -221.384818) (xy 111.389472 -221.348208) (xy 111.35904 -221.306321) (xy 111.335534 -221.260189)
			(xy 111.319535 -221.210949) (xy 111.311436 -221.159811) (xy 111.310928 -221.133924) (xy 111.311467 -221.106216)
			(xy 111.320656 -221.05157) (xy 111.329216 -221.025212) (xy 111.33709 -221.003114) (xy 111.132112 -220.648022)
			(xy 111.109252 -220.643704) (xy 111.0844 -220.63857) (xy 111.036553 -220.621668) (xy 110.991862 -220.597632)
			(xy 110.951384 -220.567029) (xy 110.916074 -220.530584) (xy 110.886768 -220.489157) (xy 110.864157 -220.443728)
			(xy 110.848777 -220.39537) (xy 110.840991 -220.345226) (xy 110.84052 -220.319854) (xy 109.620304 -220.319854)
			(xy 109.619694 -220.347507) (xy 109.610371 -220.402025) (xy 109.601762 -220.428312) (xy 109.594142 -220.45041)
			(xy 109.799374 -220.805756) (xy 109.822234 -220.810074) (xy 109.847045 -220.815229) (xy 109.894784 -220.832223)
			(xy 109.939362 -220.856322) (xy 109.979727 -220.886957) (xy 110.01493 -220.923408) (xy 110.04414 -220.964816)
			(xy 110.066672 -221.010206) (xy 110.081992 -221.058509) (xy 110.089742 -221.108587) (xy 110.090204 -221.133924)
			(xy 110.089696 -221.159811) (xy 110.081597 -221.210949) (xy 110.065598 -221.260189) (xy 110.042092 -221.306321)
			(xy 110.01166 -221.348208) (xy 109.97505 -221.384818) (xy 109.933163 -221.41525) (xy 109.887031 -221.438756)
			(xy 109.837791 -221.454755) (xy 109.786653 -221.462854) (xy 109.734879 -221.462854) (xy 109.683741 -221.454755)
			(xy 109.634501 -221.438756) (xy 109.588369 -221.41525) (xy 109.546482 -221.384818) (xy 109.509872 -221.348208)
			(xy 109.47944 -221.306321) (xy 109.455934 -221.260189) (xy 109.439935 -221.210949) (xy 109.431836 -221.159811)
			(xy 109.431328 -221.133924) (xy 109.431867 -221.106216) (xy 109.441056 -221.05157) (xy 109.449616 -221.025212)
			(xy 109.45749 -221.003114) (xy 109.252512 -220.648022) (xy 109.229652 -220.643704) (xy 109.2048 -220.63857)
			(xy 109.156953 -220.621668) (xy 109.112262 -220.597632) (xy 109.071784 -220.567029) (xy 109.036474 -220.530584)
			(xy 109.007168 -220.489157) (xy 108.984557 -220.443728) (xy 108.969177 -220.39537) (xy 108.961391 -220.345226)
			(xy 108.96092 -220.319854) (xy 107.740704 -220.319854) (xy 107.740094 -220.347507) (xy 107.730771 -220.402025)
			(xy 107.722162 -220.428312) (xy 107.714542 -220.45041) (xy 107.919774 -220.805756) (xy 107.942634 -220.810074)
			(xy 107.967445 -220.815229) (xy 108.015184 -220.832223) (xy 108.059762 -220.856322) (xy 108.100127 -220.886957)
			(xy 108.13533 -220.923408) (xy 108.16454 -220.964816) (xy 108.187072 -221.010206) (xy 108.202392 -221.058509)
			(xy 108.210142 -221.108587) (xy 108.210604 -221.133924) (xy 108.210096 -221.159811) (xy 108.201997 -221.210949)
			(xy 108.185998 -221.260189) (xy 108.162492 -221.306321) (xy 108.13206 -221.348208) (xy 108.09545 -221.384818)
			(xy 108.053563 -221.41525) (xy 108.007431 -221.438756) (xy 107.958191 -221.454755) (xy 107.907053 -221.462854)
			(xy 107.855279 -221.462854) (xy 107.804141 -221.454755) (xy 107.754901 -221.438756) (xy 107.708769 -221.41525)
			(xy 107.666882 -221.384818) (xy 107.630272 -221.348208) (xy 107.59984 -221.306321) (xy 107.576334 -221.260189)
			(xy 107.560335 -221.210949) (xy 107.552236 -221.159811) (xy 107.551728 -221.133924) (xy 107.552267 -221.106216)
			(xy 107.561456 -221.05157) (xy 107.570016 -221.025212) (xy 107.57789 -221.003114) (xy 107.372912 -220.648022)
			(xy 107.350052 -220.643704) (xy 107.3252 -220.63857) (xy 107.277353 -220.621668) (xy 107.232662 -220.597632)
			(xy 107.192184 -220.567029) (xy 107.156874 -220.530584) (xy 107.127568 -220.489157) (xy 107.104957 -220.443728)
			(xy 107.089577 -220.39537) (xy 107.081791 -220.345226) (xy 107.08132 -220.319854) (xy 105.861104 -220.319854)
			(xy 105.860494 -220.347507) (xy 105.851171 -220.402025) (xy 105.842562 -220.428312) (xy 105.834942 -220.45041)
			(xy 106.040174 -220.805756) (xy 106.063034 -220.810074) (xy 106.087845 -220.815229) (xy 106.135584 -220.832223)
			(xy 106.180162 -220.856322) (xy 106.220527 -220.886957) (xy 106.25573 -220.923408) (xy 106.28494 -220.964816)
			(xy 106.307472 -221.010206) (xy 106.322792 -221.058509) (xy 106.330542 -221.108587) (xy 106.331004 -221.133924)
			(xy 106.330496 -221.159811) (xy 106.322397 -221.210949) (xy 106.306398 -221.260189) (xy 106.282892 -221.306321)
			(xy 106.25246 -221.348208) (xy 106.21585 -221.384818) (xy 106.173963 -221.41525) (xy 106.127831 -221.438756)
			(xy 106.078591 -221.454755) (xy 106.027453 -221.462854) (xy 105.975679 -221.462854) (xy 105.924541 -221.454755)
			(xy 105.875301 -221.438756) (xy 105.829169 -221.41525) (xy 105.787282 -221.384818) (xy 105.750672 -221.348208)
			(xy 105.72024 -221.306321) (xy 105.696734 -221.260189) (xy 105.680735 -221.210949) (xy 105.672636 -221.159811)
			(xy 105.672128 -221.133924) (xy 105.672667 -221.106216) (xy 105.681856 -221.05157) (xy 105.690416 -221.025212)
			(xy 105.69829 -221.003114) (xy 105.493312 -220.648022) (xy 105.470452 -220.643704) (xy 105.4456 -220.63857)
			(xy 105.397753 -220.621668) (xy 105.353062 -220.597632) (xy 105.312584 -220.567029) (xy 105.277274 -220.530584)
			(xy 105.247968 -220.489157) (xy 105.225357 -220.443728) (xy 105.209977 -220.39537) (xy 105.202191 -220.345226)
			(xy 105.20172 -220.319854) (xy 103.981504 -220.319854) (xy 103.981028 -220.345199) (xy 103.973249 -220.395289)
			(xy 103.957897 -220.443599) (xy 103.935334 -220.48899) (xy 103.906091 -220.530396) (xy 103.870857 -220.566839)
			(xy 103.830462 -220.597461) (xy 103.785857 -220.621543) (xy 103.738093 -220.638516) (xy 103.71328 -220.643704)
			(xy 103.69042 -220.648022) (xy 103.485442 -221.003114) (xy 103.493316 -221.024958) (xy 103.50191 -221.051373)
			(xy 103.511097 -221.106151) (xy 103.511604 -221.133924) (xy 103.511096 -221.159811) (xy 103.502997 -221.210949)
			(xy 103.486998 -221.260189) (xy 103.463492 -221.306321) (xy 103.43306 -221.348208) (xy 103.39645 -221.384818)
			(xy 103.354563 -221.41525) (xy 103.308431 -221.438756) (xy 103.259191 -221.454755) (xy 103.208053 -221.462854)
			(xy 103.156279 -221.462854) (xy 103.105141 -221.454755) (xy 103.055901 -221.438756) (xy 103.009769 -221.41525)
			(xy 102.967882 -221.384818) (xy 102.931272 -221.348208) (xy 102.90084 -221.306321) (xy 102.877334 -221.260189)
			(xy 102.861335 -221.210949) (xy 102.853236 -221.159811) (xy 102.852728 -221.133924) (xy 102.571804 -221.133924)
			(xy 102.57128 -221.161632) (xy 102.562081 -221.216279) (xy 102.553516 -221.242636) (xy 102.545642 -221.264734)
			(xy 102.75062 -221.619572) (xy 102.77348 -221.62389) (xy 102.798305 -221.629041) (xy 102.846083 -221.645999)
			(xy 102.890702 -221.670074) (xy 102.931107 -221.700696) (xy 102.966347 -221.737145) (xy 102.99559 -221.778561)
			(xy 103.018147 -221.823965) (xy 103.033485 -221.872289) (xy 103.041242 -221.92239) (xy 103.041704 -221.94774)
			(xy 104.26192 -221.94774) (xy 104.262371 -221.922394) (xy 104.270152 -221.872302) (xy 104.285506 -221.82399)
			(xy 104.308072 -221.778597) (xy 104.337318 -221.737192) (xy 104.372555 -221.700749) (xy 104.412954 -221.670127)
			(xy 104.457562 -221.646047) (xy 104.50533 -221.629076) (xy 104.530144 -221.62389) (xy 104.553004 -221.619572)
			(xy 104.758236 -221.264226) (xy 104.750362 -221.242128) (xy 104.741898 -221.215883) (xy 104.732825 -221.161495)
			(xy 104.732328 -221.133924) (xy 104.732836 -221.108037) (xy 104.740935 -221.056899) (xy 104.756934 -221.007659)
			(xy 104.78044 -220.961527) (xy 104.810872 -220.91964) (xy 104.847482 -220.88303) (xy 104.889369 -220.852598)
			(xy 104.935501 -220.829092) (xy 104.984741 -220.813093) (xy 105.035879 -220.804994) (xy 105.087653 -220.804994)
			(xy 105.138791 -220.813093) (xy 105.188031 -220.829092) (xy 105.234163 -220.852598) (xy 105.27605 -220.88303)
			(xy 105.31266 -220.91964) (xy 105.343092 -220.961527) (xy 105.366598 -221.007659) (xy 105.382597 -221.056899)
			(xy 105.390696 -221.108037) (xy 105.391204 -221.133924) (xy 105.390748 -221.159299) (xy 105.382976 -221.20945)
			(xy 105.367604 -221.257815) (xy 105.344997 -221.303251) (xy 105.315689 -221.344682) (xy 105.280373 -221.381128)
			(xy 105.239885 -221.411727) (xy 105.195184 -221.435754) (xy 105.147326 -221.452641) (xy 105.122472 -221.457774)
			(xy 105.099612 -221.462092) (xy 104.894888 -221.81693) (xy 104.902762 -221.838774) (xy 104.911419 -221.865179)
			(xy 104.920732 -221.919958) (xy 104.921304 -221.94774) (xy 106.14152 -221.94774) (xy 106.141971 -221.922394)
			(xy 106.149752 -221.872302) (xy 106.165106 -221.82399) (xy 106.187672 -221.778597) (xy 106.216918 -221.737192)
			(xy 106.252155 -221.700749) (xy 106.292554 -221.670127) (xy 106.337162 -221.646047) (xy 106.38493 -221.629076)
			(xy 106.409744 -221.62389) (xy 106.432604 -221.619572) (xy 106.637836 -221.264226) (xy 106.629962 -221.242128)
			(xy 106.621498 -221.215883) (xy 106.612425 -221.161495) (xy 106.611928 -221.133924) (xy 106.612436 -221.108037)
			(xy 106.620535 -221.056899) (xy 106.636534 -221.007659) (xy 106.66004 -220.961527) (xy 106.690472 -220.91964)
			(xy 106.727082 -220.88303) (xy 106.768969 -220.852598) (xy 106.815101 -220.829092) (xy 106.864341 -220.813093)
			(xy 106.915479 -220.804994) (xy 106.967253 -220.804994) (xy 107.018391 -220.813093) (xy 107.067631 -220.829092)
			(xy 107.113763 -220.852598) (xy 107.15565 -220.88303) (xy 107.19226 -220.91964) (xy 107.222692 -220.961527)
			(xy 107.246198 -221.007659) (xy 107.262197 -221.056899) (xy 107.270296 -221.108037) (xy 107.270804 -221.133924)
			(xy 107.270348 -221.159299) (xy 107.262576 -221.20945) (xy 107.247204 -221.257815) (xy 107.224597 -221.303251)
			(xy 107.195289 -221.344682) (xy 107.159973 -221.381128) (xy 107.119485 -221.411727) (xy 107.074784 -221.435754)
			(xy 107.026926 -221.452641) (xy 107.002072 -221.457774) (xy 106.979212 -221.462092) (xy 106.774488 -221.81693)
			(xy 106.782362 -221.838774) (xy 106.791019 -221.865179) (xy 106.800332 -221.919958) (xy 106.800904 -221.94774)
			(xy 108.02112 -221.94774) (xy 108.021571 -221.922394) (xy 108.029352 -221.872302) (xy 108.044706 -221.82399)
			(xy 108.067272 -221.778597) (xy 108.096518 -221.737192) (xy 108.131755 -221.700749) (xy 108.172154 -221.670127)
			(xy 108.216762 -221.646047) (xy 108.26453 -221.629076) (xy 108.289344 -221.62389) (xy 108.312204 -221.619572)
			(xy 108.517436 -221.264226) (xy 108.509562 -221.242128) (xy 108.501098 -221.215883) (xy 108.492025 -221.161495)
			(xy 108.491528 -221.133924) (xy 108.492036 -221.108037) (xy 108.500135 -221.056899) (xy 108.516134 -221.007659)
			(xy 108.53964 -220.961527) (xy 108.570072 -220.91964) (xy 108.606682 -220.88303) (xy 108.648569 -220.852598)
			(xy 108.694701 -220.829092) (xy 108.743941 -220.813093) (xy 108.795079 -220.804994) (xy 108.846853 -220.804994)
			(xy 108.897991 -220.813093) (xy 108.947231 -220.829092) (xy 108.993363 -220.852598) (xy 109.03525 -220.88303)
			(xy 109.07186 -220.91964) (xy 109.102292 -220.961527) (xy 109.125798 -221.007659) (xy 109.141797 -221.056899)
			(xy 109.149896 -221.108037) (xy 109.150404 -221.133924) (xy 109.149948 -221.159299) (xy 109.142176 -221.20945)
			(xy 109.126804 -221.257815) (xy 109.104197 -221.303251) (xy 109.074889 -221.344682) (xy 109.039573 -221.381128)
			(xy 108.999085 -221.411727) (xy 108.954384 -221.435754) (xy 108.906526 -221.452641) (xy 108.881672 -221.457774)
			(xy 108.858812 -221.462092) (xy 108.654088 -221.81693) (xy 108.661962 -221.838774) (xy 108.670619 -221.865179)
			(xy 108.679932 -221.919958) (xy 108.680504 -221.94774) (xy 109.901228 -221.94774) (xy 109.901634 -221.922403)
			(xy 109.909396 -221.872326) (xy 109.924728 -221.824026) (xy 109.947269 -221.77864) (xy 109.976489 -221.737238)
			(xy 110.011699 -221.700794) (xy 110.05207 -221.670165) (xy 110.096652 -221.646074) (xy 110.144395 -221.629087)
			(xy 110.169198 -221.62389) (xy 110.192058 -221.619572) (xy 110.397036 -221.26448) (xy 110.389416 -221.242382)
			(xy 110.380897 -221.216211) (xy 110.371703 -221.161949) (xy 110.371128 -221.134432) (xy 110.371128 -221.133924)
			(xy 110.371636 -221.108037) (xy 110.379735 -221.056899) (xy 110.395734 -221.007659) (xy 110.41924 -220.961527)
			(xy 110.449672 -220.91964) (xy 110.486282 -220.88303) (xy 110.528169 -220.852598) (xy 110.574301 -220.829092)
			(xy 110.623541 -220.813093) (xy 110.674679 -220.804994) (xy 110.726453 -220.804994) (xy 110.777591 -220.813093)
			(xy 110.826831 -220.829092) (xy 110.872963 -220.852598) (xy 110.91485 -220.88303) (xy 110.95146 -220.91964)
			(xy 110.981892 -220.961527) (xy 111.005398 -221.007659) (xy 111.021397 -221.056899) (xy 111.029496 -221.108037)
			(xy 111.030004 -221.133924) (xy 111.029585 -221.15929) (xy 111.021833 -221.209425) (xy 111.006484 -221.257778)
			(xy 110.983902 -221.303206) (xy 110.954621 -221.344633) (xy 110.919333 -221.381081) (xy 110.878874 -221.411686)
			(xy 110.8342 -221.435725) (xy 110.786369 -221.45263) (xy 110.761526 -221.457774) (xy 110.738666 -221.462092)
			(xy 110.533942 -221.81693) (xy 110.541816 -221.838774) (xy 110.550414 -221.865187) (xy 110.559598 -221.919967)
			(xy 110.560104 -221.94774) (xy 111.78032 -221.94774) (xy 111.780771 -221.922394) (xy 111.788552 -221.872302)
			(xy 111.803906 -221.82399) (xy 111.826472 -221.778597) (xy 111.855718 -221.737192) (xy 111.890955 -221.700749)
			(xy 111.931354 -221.670127) (xy 111.975962 -221.646047) (xy 112.02373 -221.629076) (xy 112.048544 -221.62389)
			(xy 112.071404 -221.619572) (xy 112.276636 -221.264226) (xy 112.268762 -221.242128) (xy 112.260298 -221.215883)
			(xy 112.251225 -221.161495) (xy 112.250728 -221.133924) (xy 112.251236 -221.108037) (xy 112.259335 -221.056899)
			(xy 112.275334 -221.007659) (xy 112.29884 -220.961527) (xy 112.329272 -220.91964) (xy 112.365882 -220.88303)
			(xy 112.407769 -220.852598) (xy 112.453901 -220.829092) (xy 112.503141 -220.813093) (xy 112.554279 -220.804994)
			(xy 112.606053 -220.804994) (xy 112.657191 -220.813093) (xy 112.706431 -220.829092) (xy 112.752563 -220.852598)
			(xy 112.79445 -220.88303) (xy 112.83106 -220.91964) (xy 112.861492 -220.961527) (xy 112.884998 -221.007659)
			(xy 112.900997 -221.056899) (xy 112.909096 -221.108037) (xy 112.909604 -221.133924) (xy 112.909148 -221.159299)
			(xy 112.901376 -221.20945) (xy 112.886004 -221.257815) (xy 112.863397 -221.303251) (xy 112.834089 -221.344682)
			(xy 112.798773 -221.381128) (xy 112.758285 -221.411727) (xy 112.713584 -221.435754) (xy 112.665726 -221.452641)
			(xy 112.640872 -221.457774) (xy 112.618012 -221.462092) (xy 112.413288 -221.81693) (xy 112.421162 -221.838774)
			(xy 112.429819 -221.865179) (xy 112.439132 -221.919958) (xy 112.439704 -221.94774) (xy 113.660428 -221.94774)
			(xy 113.660834 -221.922403) (xy 113.668596 -221.872326) (xy 113.683928 -221.824026) (xy 113.706469 -221.77864)
			(xy 113.735689 -221.737238) (xy 113.770899 -221.700794) (xy 113.81127 -221.670165) (xy 113.855852 -221.646074)
			(xy 113.903595 -221.629087) (xy 113.928398 -221.62389) (xy 113.951258 -221.619572) (xy 114.156236 -221.26448)
			(xy 114.148616 -221.242382) (xy 114.140097 -221.216211) (xy 114.130903 -221.161949) (xy 114.130328 -221.134432)
			(xy 114.130328 -221.133924) (xy 114.130836 -221.108037) (xy 114.138935 -221.056899) (xy 114.154934 -221.007659)
			(xy 114.17844 -220.961527) (xy 114.208872 -220.91964) (xy 114.245482 -220.88303) (xy 114.287369 -220.852598)
			(xy 114.333501 -220.829092) (xy 114.382741 -220.813093) (xy 114.433879 -220.804994) (xy 114.485653 -220.804994)
			(xy 114.536791 -220.813093) (xy 114.586031 -220.829092) (xy 114.632163 -220.852598) (xy 114.67405 -220.88303)
			(xy 114.71066 -220.91964) (xy 114.741092 -220.961527) (xy 114.764598 -221.007659) (xy 114.780597 -221.056899)
			(xy 114.788696 -221.108037) (xy 114.789204 -221.133924) (xy 114.788785 -221.15929) (xy 114.781033 -221.209425)
			(xy 114.765684 -221.257778) (xy 114.743102 -221.303206) (xy 114.713821 -221.344633) (xy 114.678533 -221.381081)
			(xy 114.638074 -221.411686) (xy 114.5934 -221.435725) (xy 114.545569 -221.45263) (xy 114.520726 -221.457774)
			(xy 114.497866 -221.462092) (xy 114.293142 -221.81693) (xy 114.301016 -221.838774) (xy 114.309614 -221.865187)
			(xy 114.318798 -221.919967) (xy 114.319304 -221.94774) (xy 115.53952 -221.94774) (xy 115.539971 -221.922394)
			(xy 115.547752 -221.872302) (xy 115.563106 -221.82399) (xy 115.585672 -221.778597) (xy 115.614918 -221.737192)
			(xy 115.650155 -221.700749) (xy 115.690554 -221.670127) (xy 115.735162 -221.646047) (xy 115.78293 -221.629076)
			(xy 115.807744 -221.62389) (xy 115.830604 -221.619572) (xy 116.035836 -221.264226) (xy 116.027962 -221.242128)
			(xy 116.019498 -221.215883) (xy 116.010425 -221.161495) (xy 116.009928 -221.133924) (xy 116.010436 -221.108037)
			(xy 116.018535 -221.056899) (xy 116.034534 -221.007659) (xy 116.05804 -220.961527) (xy 116.088472 -220.91964)
			(xy 116.125082 -220.88303) (xy 116.166969 -220.852598) (xy 116.213101 -220.829092) (xy 116.262341 -220.813093)
			(xy 116.313479 -220.804994) (xy 116.365253 -220.804994) (xy 116.416391 -220.813093) (xy 116.465631 -220.829092)
			(xy 116.511763 -220.852598) (xy 116.55365 -220.88303) (xy 116.59026 -220.91964) (xy 116.620692 -220.961527)
			(xy 116.644198 -221.007659) (xy 116.660197 -221.056899) (xy 116.668296 -221.108037) (xy 116.668804 -221.133924)
			(xy 116.668348 -221.159299) (xy 116.660576 -221.20945) (xy 116.645204 -221.257815) (xy 116.622597 -221.303251)
			(xy 116.593289 -221.344682) (xy 116.557973 -221.381128) (xy 116.517485 -221.411727) (xy 116.472784 -221.435754)
			(xy 116.424926 -221.452641) (xy 116.400072 -221.457774) (xy 116.377212 -221.462092) (xy 116.172488 -221.81693)
			(xy 116.180362 -221.838774) (xy 116.189019 -221.865179) (xy 116.198332 -221.919958) (xy 116.198904 -221.94774)
			(xy 117.41912 -221.94774) (xy 117.419571 -221.922394) (xy 117.427352 -221.872302) (xy 117.442706 -221.82399)
			(xy 117.465272 -221.778597) (xy 117.494518 -221.737192) (xy 117.529755 -221.700749) (xy 117.570154 -221.670127)
			(xy 117.614762 -221.646047) (xy 117.66253 -221.629076) (xy 117.687344 -221.62389) (xy 117.710204 -221.619572)
			(xy 117.915436 -221.264226) (xy 117.907562 -221.242128) (xy 117.899098 -221.215883) (xy 117.890025 -221.161495)
			(xy 117.889528 -221.133924) (xy 117.890036 -221.108037) (xy 117.898135 -221.056899) (xy 117.914134 -221.007659)
			(xy 117.93764 -220.961527) (xy 117.968072 -220.91964) (xy 118.004682 -220.88303) (xy 118.046569 -220.852598)
			(xy 118.092701 -220.829092) (xy 118.141941 -220.813093) (xy 118.193079 -220.804994) (xy 118.244853 -220.804994)
			(xy 118.295991 -220.813093) (xy 118.345231 -220.829092) (xy 118.391363 -220.852598) (xy 118.43325 -220.88303)
			(xy 118.46986 -220.91964) (xy 118.500292 -220.961527) (xy 118.523798 -221.007659) (xy 118.539797 -221.056899)
			(xy 118.547896 -221.108037) (xy 118.548404 -221.133924) (xy 118.547948 -221.159299) (xy 118.540176 -221.20945)
			(xy 118.524804 -221.257815) (xy 118.502197 -221.303251) (xy 118.472889 -221.344682) (xy 118.437573 -221.381128)
			(xy 118.397085 -221.411727) (xy 118.352384 -221.435754) (xy 118.304526 -221.452641) (xy 118.279672 -221.457774)
			(xy 118.256812 -221.462092) (xy 118.052088 -221.81693) (xy 118.059962 -221.838774) (xy 118.068619 -221.865179)
			(xy 118.077932 -221.919958) (xy 118.078504 -221.94774) (xy 121.17832 -221.94774) (xy 121.178771 -221.922394)
			(xy 121.186552 -221.872302) (xy 121.201906 -221.82399) (xy 121.224472 -221.778597) (xy 121.253718 -221.737192)
			(xy 121.288955 -221.700749) (xy 121.329354 -221.670127) (xy 121.373962 -221.646047) (xy 121.42173 -221.629076)
			(xy 121.446544 -221.62389) (xy 121.469404 -221.619572) (xy 121.674636 -221.264226) (xy 121.666762 -221.242128)
			(xy 121.658298 -221.215883) (xy 121.649225 -221.161495) (xy 121.648728 -221.133924) (xy 121.649236 -221.108037)
			(xy 121.657335 -221.056899) (xy 121.673334 -221.007659) (xy 121.69684 -220.961527) (xy 121.727272 -220.91964)
			(xy 121.763882 -220.88303) (xy 121.805769 -220.852598) (xy 121.851901 -220.829092) (xy 121.901141 -220.813093)
			(xy 121.952279 -220.804994) (xy 122.004053 -220.804994) (xy 122.055191 -220.813093) (xy 122.104431 -220.829092)
			(xy 122.150563 -220.852598) (xy 122.19245 -220.88303) (xy 122.22906 -220.91964) (xy 122.259492 -220.961527)
			(xy 122.282998 -221.007659) (xy 122.298997 -221.056899) (xy 122.307096 -221.108037) (xy 122.307604 -221.133924)
			(xy 122.307148 -221.159299) (xy 122.299376 -221.20945) (xy 122.284004 -221.257815) (xy 122.261397 -221.303251)
			(xy 122.232089 -221.344682) (xy 122.196773 -221.381128) (xy 122.156285 -221.411727) (xy 122.111584 -221.435754)
			(xy 122.063726 -221.452641) (xy 122.038872 -221.457774) (xy 122.016012 -221.462092) (xy 121.811288 -221.81693)
			(xy 121.819162 -221.838774) (xy 121.827819 -221.865179) (xy 121.837132 -221.919958) (xy 121.837704 -221.94774)
			(xy 123.05792 -221.94774) (xy 123.058371 -221.922394) (xy 123.066152 -221.872302) (xy 123.081506 -221.82399)
			(xy 123.104072 -221.778597) (xy 123.133318 -221.737192) (xy 123.168555 -221.700749) (xy 123.208954 -221.670127)
			(xy 123.253562 -221.646047) (xy 123.30133 -221.629076) (xy 123.326144 -221.62389) (xy 123.349004 -221.619572)
			(xy 123.554236 -221.264226) (xy 123.546362 -221.242128) (xy 123.537898 -221.215883) (xy 123.528825 -221.161495)
			(xy 123.528328 -221.133924) (xy 123.528836 -221.108037) (xy 123.536935 -221.056899) (xy 123.552934 -221.007659)
			(xy 123.57644 -220.961527) (xy 123.606872 -220.91964) (xy 123.643482 -220.88303) (xy 123.685369 -220.852598)
			(xy 123.731501 -220.829092) (xy 123.780741 -220.813093) (xy 123.831879 -220.804994) (xy 123.883653 -220.804994)
			(xy 123.934791 -220.813093) (xy 123.984031 -220.829092) (xy 124.030163 -220.852598) (xy 124.07205 -220.88303)
			(xy 124.10866 -220.91964) (xy 124.139092 -220.961527) (xy 124.162598 -221.007659) (xy 124.178597 -221.056899)
			(xy 124.186696 -221.108037) (xy 124.187204 -221.133924) (xy 124.186748 -221.159299) (xy 124.178976 -221.20945)
			(xy 124.163604 -221.257815) (xy 124.140997 -221.303251) (xy 124.111689 -221.344682) (xy 124.076373 -221.381128)
			(xy 124.035885 -221.411727) (xy 123.991184 -221.435754) (xy 123.943326 -221.452641) (xy 123.918472 -221.457774)
			(xy 123.895612 -221.462092) (xy 123.690888 -221.81693) (xy 123.698762 -221.838774) (xy 123.707419 -221.865179)
			(xy 123.716732 -221.919958) (xy 123.717304 -221.94774) (xy 124.93752 -221.94774) (xy 124.937971 -221.922394)
			(xy 124.945752 -221.872302) (xy 124.961106 -221.82399) (xy 124.983672 -221.778597) (xy 125.012918 -221.737192)
			(xy 125.048155 -221.700749) (xy 125.088554 -221.670127) (xy 125.133162 -221.646047) (xy 125.18093 -221.629076)
			(xy 125.205744 -221.62389) (xy 125.228604 -221.619572) (xy 125.433836 -221.264226) (xy 125.425962 -221.242128)
			(xy 125.417498 -221.215883) (xy 125.408425 -221.161495) (xy 125.407928 -221.133924) (xy 125.408436 -221.108037)
			(xy 125.416535 -221.056899) (xy 125.432534 -221.007659) (xy 125.45604 -220.961527) (xy 125.486472 -220.91964)
			(xy 125.523082 -220.88303) (xy 125.564969 -220.852598) (xy 125.611101 -220.829092) (xy 125.660341 -220.813093)
			(xy 125.711479 -220.804994) (xy 125.763253 -220.804994) (xy 125.814391 -220.813093) (xy 125.863631 -220.829092)
			(xy 125.909763 -220.852598) (xy 125.95165 -220.88303) (xy 125.98826 -220.91964) (xy 126.018692 -220.961527)
			(xy 126.042198 -221.007659) (xy 126.058197 -221.056899) (xy 126.066296 -221.108037) (xy 126.066804 -221.133924)
			(xy 126.066348 -221.159299) (xy 126.058576 -221.20945) (xy 126.043204 -221.257815) (xy 126.020597 -221.303251)
			(xy 125.991289 -221.344682) (xy 125.955973 -221.381128) (xy 125.915485 -221.411727) (xy 125.870784 -221.435754)
			(xy 125.822926 -221.452641) (xy 125.798072 -221.457774) (xy 125.775212 -221.462092) (xy 125.570488 -221.81693)
			(xy 125.578362 -221.838774) (xy 125.587019 -221.865179) (xy 125.596332 -221.919958) (xy 125.596904 -221.94774)
			(xy 126.81712 -221.94774) (xy 126.817571 -221.922394) (xy 126.825352 -221.872302) (xy 126.840706 -221.82399)
			(xy 126.863272 -221.778597) (xy 126.892518 -221.737192) (xy 126.927755 -221.700749) (xy 126.968154 -221.670127)
			(xy 127.012762 -221.646047) (xy 127.06053 -221.629076) (xy 127.085344 -221.62389) (xy 127.108204 -221.619572)
			(xy 127.313436 -221.264226) (xy 127.305562 -221.242128) (xy 127.297098 -221.215883) (xy 127.288025 -221.161495)
			(xy 127.287528 -221.133924) (xy 127.288036 -221.108037) (xy 127.296135 -221.056899) (xy 127.312134 -221.007659)
			(xy 127.33564 -220.961527) (xy 127.366072 -220.91964) (xy 127.402682 -220.88303) (xy 127.444569 -220.852598)
			(xy 127.490701 -220.829092) (xy 127.539941 -220.813093) (xy 127.591079 -220.804994) (xy 127.642853 -220.804994)
			(xy 127.693991 -220.813093) (xy 127.743231 -220.829092) (xy 127.789363 -220.852598) (xy 127.83125 -220.88303)
			(xy 127.86786 -220.91964) (xy 127.898292 -220.961527) (xy 127.921798 -221.007659) (xy 127.937797 -221.056899)
			(xy 127.945896 -221.108037) (xy 127.946404 -221.133924) (xy 127.945948 -221.159299) (xy 127.938176 -221.20945)
			(xy 127.922804 -221.257815) (xy 127.900197 -221.303251) (xy 127.870889 -221.344682) (xy 127.835573 -221.381128)
			(xy 127.795085 -221.411727) (xy 127.750384 -221.435754) (xy 127.702526 -221.452641) (xy 127.677672 -221.457774)
			(xy 127.654812 -221.462092) (xy 127.450088 -221.81693) (xy 127.457962 -221.838774) (xy 127.466619 -221.865179)
			(xy 127.475932 -221.919958) (xy 127.476504 -221.94774) (xy 128.69672 -221.94774) (xy 128.697171 -221.922394)
			(xy 128.704952 -221.872302) (xy 128.720306 -221.82399) (xy 128.742872 -221.778597) (xy 128.772118 -221.737192)
			(xy 128.807355 -221.700749) (xy 128.847754 -221.670127) (xy 128.892362 -221.646047) (xy 128.94013 -221.629076)
			(xy 128.964944 -221.62389) (xy 128.987804 -221.619572) (xy 129.193036 -221.264226) (xy 129.185162 -221.242128)
			(xy 129.176698 -221.215883) (xy 129.167625 -221.161495) (xy 129.167128 -221.133924) (xy 129.167636 -221.108037)
			(xy 129.175735 -221.056899) (xy 129.191734 -221.007659) (xy 129.21524 -220.961527) (xy 129.245672 -220.91964)
			(xy 129.282282 -220.88303) (xy 129.324169 -220.852598) (xy 129.370301 -220.829092) (xy 129.419541 -220.813093)
			(xy 129.470679 -220.804994) (xy 129.522453 -220.804994) (xy 129.573591 -220.813093) (xy 129.622831 -220.829092)
			(xy 129.668963 -220.852598) (xy 129.71085 -220.88303) (xy 129.74746 -220.91964) (xy 129.777892 -220.961527)
			(xy 129.801398 -221.007659) (xy 129.817397 -221.056899) (xy 129.825496 -221.108037) (xy 129.826004 -221.133924)
			(xy 129.825548 -221.159299) (xy 129.817776 -221.20945) (xy 129.802404 -221.257815) (xy 129.779797 -221.303251)
			(xy 129.750489 -221.344682) (xy 129.715173 -221.381128) (xy 129.674685 -221.411727) (xy 129.629984 -221.435754)
			(xy 129.582126 -221.452641) (xy 129.557272 -221.457774) (xy 129.534412 -221.462092) (xy 129.329688 -221.81693)
			(xy 129.337562 -221.838774) (xy 129.346219 -221.865179) (xy 129.355532 -221.919958) (xy 129.356104 -221.94774)
			(xy 130.57632 -221.94774) (xy 130.576771 -221.922394) (xy 130.584552 -221.872302) (xy 130.599906 -221.82399)
			(xy 130.622472 -221.778597) (xy 130.651718 -221.737192) (xy 130.686955 -221.700749) (xy 130.727354 -221.670127)
			(xy 130.771962 -221.646047) (xy 130.81973 -221.629076) (xy 130.844544 -221.62389) (xy 130.867404 -221.619572)
			(xy 131.072636 -221.264226) (xy 131.064762 -221.242128) (xy 131.056298 -221.215883) (xy 131.047225 -221.161495)
			(xy 131.046728 -221.133924) (xy 131.047236 -221.108037) (xy 131.055335 -221.056899) (xy 131.071334 -221.007659)
			(xy 131.09484 -220.961527) (xy 131.125272 -220.91964) (xy 131.161882 -220.88303) (xy 131.203769 -220.852598)
			(xy 131.249901 -220.829092) (xy 131.299141 -220.813093) (xy 131.350279 -220.804994) (xy 131.402053 -220.804994)
			(xy 131.453191 -220.813093) (xy 131.502431 -220.829092) (xy 131.548563 -220.852598) (xy 131.59045 -220.88303)
			(xy 131.62706 -220.91964) (xy 131.657492 -220.961527) (xy 131.680998 -221.007659) (xy 131.696997 -221.056899)
			(xy 131.705096 -221.108037) (xy 131.705604 -221.133924) (xy 131.705148 -221.159299) (xy 131.697376 -221.20945)
			(xy 131.682004 -221.257815) (xy 131.659397 -221.303251) (xy 131.630089 -221.344682) (xy 131.594773 -221.381128)
			(xy 131.554285 -221.411727) (xy 131.509584 -221.435754) (xy 131.461726 -221.452641) (xy 131.436872 -221.457774)
			(xy 131.414012 -221.462092) (xy 131.209288 -221.81693) (xy 131.217162 -221.838774) (xy 131.225819 -221.865179)
			(xy 131.235132 -221.919958) (xy 131.235704 -221.94774) (xy 132.45592 -221.94774) (xy 132.456371 -221.922394)
			(xy 132.464152 -221.872302) (xy 132.479506 -221.82399) (xy 132.502072 -221.778597) (xy 132.531318 -221.737192)
			(xy 132.566555 -221.700749) (xy 132.606954 -221.670127) (xy 132.651562 -221.646047) (xy 132.69933 -221.629076)
			(xy 132.724144 -221.62389) (xy 132.747004 -221.619572) (xy 132.951982 -221.263972) (xy 132.944362 -221.242128)
			(xy 132.935911 -221.215946) (xy 132.92684 -221.161685) (xy 132.926328 -221.134178) (xy 132.926328 -221.133924)
			(xy 132.926836 -221.108037) (xy 132.934935 -221.056899) (xy 132.950934 -221.007659) (xy 132.97444 -220.961527)
			(xy 133.004872 -220.91964) (xy 133.041482 -220.88303) (xy 133.083369 -220.852598) (xy 133.129501 -220.829092)
			(xy 133.178741 -220.813093) (xy 133.229879 -220.804994) (xy 133.281653 -220.804994) (xy 133.332791 -220.813093)
			(xy 133.382031 -220.829092) (xy 133.428163 -220.852598) (xy 133.47005 -220.88303) (xy 133.50666 -220.91964)
			(xy 133.537092 -220.961527) (xy 133.560598 -221.007659) (xy 133.576597 -221.056899) (xy 133.584696 -221.108037)
			(xy 133.585204 -221.133924) (xy 133.584785 -221.15929) (xy 133.577033 -221.209425) (xy 133.561684 -221.257778)
			(xy 133.539102 -221.303206) (xy 133.509821 -221.344633) (xy 133.474533 -221.381081) (xy 133.434074 -221.411686)
			(xy 133.3894 -221.435725) (xy 133.341569 -221.45263) (xy 133.316726 -221.457774) (xy 133.293866 -221.462092)
			(xy 133.089142 -221.81693) (xy 133.096762 -221.838774) (xy 133.105377 -221.865059) (xy 133.114698 -221.919578)
			(xy 133.115304 -221.947232) (xy 133.115304 -221.94774) (xy 134.33552 -221.94774) (xy 134.335971 -221.922394)
			(xy 134.343752 -221.872302) (xy 134.359106 -221.82399) (xy 134.381672 -221.778597) (xy 134.410918 -221.737192)
			(xy 134.446155 -221.700749) (xy 134.486554 -221.670127) (xy 134.531162 -221.646047) (xy 134.57893 -221.629076)
			(xy 134.603744 -221.62389) (xy 134.626604 -221.619572) (xy 134.831582 -221.263972) (xy 134.823962 -221.242128)
			(xy 134.815511 -221.215946) (xy 134.80644 -221.161685) (xy 134.805928 -221.134178) (xy 134.805928 -221.133924)
			(xy 134.806436 -221.108037) (xy 134.814535 -221.056899) (xy 134.830534 -221.007659) (xy 134.85404 -220.961527)
			(xy 134.884472 -220.91964) (xy 134.921082 -220.88303) (xy 134.962969 -220.852598) (xy 135.009101 -220.829092)
			(xy 135.058341 -220.813093) (xy 135.109479 -220.804994) (xy 135.161253 -220.804994) (xy 135.212391 -220.813093)
			(xy 135.261631 -220.829092) (xy 135.307763 -220.852598) (xy 135.34965 -220.88303) (xy 135.38626 -220.91964)
			(xy 135.416692 -220.961527) (xy 135.440198 -221.007659) (xy 135.456197 -221.056899) (xy 135.464296 -221.108037)
			(xy 135.464804 -221.133924) (xy 336.695796 -221.133924) (xy 336.696304 -221.108037) (xy 336.704403 -221.056899)
			(xy 336.720402 -221.007659) (xy 336.743908 -220.961527) (xy 336.77434 -220.91964) (xy 336.81095 -220.88303)
			(xy 336.852837 -220.852598) (xy 336.898969 -220.829092) (xy 336.948209 -220.813093) (xy 336.999347 -220.804994)
			(xy 337.051121 -220.804994) (xy 337.102259 -220.813093) (xy 337.151499 -220.829092) (xy 337.197631 -220.852598)
			(xy 337.239518 -220.88303) (xy 337.276128 -220.91964) (xy 337.30656 -220.961527) (xy 337.330066 -221.007659)
			(xy 337.346065 -221.056899) (xy 337.354164 -221.108037) (xy 337.354672 -221.133924) (xy 337.635596 -221.133924)
			(xy 337.636104 -221.10859) (xy 337.643853 -221.058519) (xy 337.659172 -221.010223) (xy 337.6817 -220.96484)
			(xy 337.710906 -220.923438) (xy 337.746104 -220.886992) (xy 337.786463 -220.856361) (xy 337.831034 -220.832266)
			(xy 337.878767 -220.815274) (xy 337.903566 -220.810074) (xy 337.926426 -220.805756) (xy 338.131404 -220.450664)
			(xy 338.12353 -220.42882) (xy 338.114896 -220.402408) (xy 338.105568 -220.347635) (xy 338.104988 -220.319854)
			(xy 338.105496 -220.293947) (xy 338.113602 -220.24277) (xy 338.129614 -220.193491) (xy 338.153137 -220.147324)
			(xy 338.183593 -220.105405) (xy 338.220231 -220.068767) (xy 338.26215 -220.038311) (xy 338.308317 -220.014788)
			(xy 338.357596 -219.998776) (xy 338.408773 -219.99067) (xy 338.460587 -219.99067) (xy 338.511764 -219.998776)
			(xy 338.561043 -220.014788) (xy 338.60721 -220.038311) (xy 338.649129 -220.068767) (xy 338.685767 -220.105405)
			(xy 338.716223 -220.147324) (xy 338.739746 -220.193491) (xy 338.755758 -220.24277) (xy 338.763864 -220.293947)
			(xy 338.764372 -220.319854) (xy 338.763922 -220.3452) (xy 338.756142 -220.395293) (xy 338.740788 -220.443604)
			(xy 338.718222 -220.488998) (xy 338.688976 -220.530404) (xy 338.653739 -220.566847) (xy 338.61334 -220.597469)
			(xy 338.568731 -220.621548) (xy 338.520963 -220.638518) (xy 338.496148 -220.643704) (xy 338.473288 -220.648022)
			(xy 338.26831 -221.003114) (xy 338.276184 -221.024958) (xy 338.284777 -221.051373) (xy 338.293965 -221.106151)
			(xy 338.294472 -221.133924) (xy 338.575396 -221.133924) (xy 338.575904 -221.108037) (xy 338.584003 -221.056899)
			(xy 338.600002 -221.007659) (xy 338.623508 -220.961527) (xy 338.65394 -220.91964) (xy 338.69055 -220.88303)
			(xy 338.732437 -220.852598) (xy 338.778569 -220.829092) (xy 338.827809 -220.813093) (xy 338.878947 -220.804994)
			(xy 338.930721 -220.804994) (xy 338.981859 -220.813093) (xy 339.031099 -220.829092) (xy 339.077231 -220.852598)
			(xy 339.119118 -220.88303) (xy 339.155728 -220.91964) (xy 339.18616 -220.961527) (xy 339.209666 -221.007659)
			(xy 339.225665 -221.056899) (xy 339.233764 -221.108037) (xy 339.234272 -221.133924) (xy 339.515196 -221.133924)
			(xy 339.515704 -221.10859) (xy 339.523453 -221.058519) (xy 339.538772 -221.010223) (xy 339.5613 -220.96484)
			(xy 339.590506 -220.923438) (xy 339.625704 -220.886992) (xy 339.666063 -220.856361) (xy 339.710634 -220.832266)
			(xy 339.758367 -220.815274) (xy 339.783166 -220.810074) (xy 339.806026 -220.805756) (xy 340.011004 -220.450664)
			(xy 340.00313 -220.42882) (xy 339.994496 -220.402408) (xy 339.985168 -220.347635) (xy 339.984588 -220.319854)
			(xy 339.985096 -220.293947) (xy 339.993202 -220.24277) (xy 340.009214 -220.193491) (xy 340.032737 -220.147324)
			(xy 340.063193 -220.105405) (xy 340.099831 -220.068767) (xy 340.14175 -220.038311) (xy 340.187917 -220.014788)
			(xy 340.237196 -219.998776) (xy 340.288373 -219.99067) (xy 340.340187 -219.99067) (xy 340.391364 -219.998776)
			(xy 340.440643 -220.014788) (xy 340.48681 -220.038311) (xy 340.528729 -220.068767) (xy 340.565367 -220.105405)
			(xy 340.595823 -220.147324) (xy 340.619346 -220.193491) (xy 340.635358 -220.24277) (xy 340.643464 -220.293947)
			(xy 340.643972 -220.319854) (xy 340.643522 -220.3452) (xy 340.635742 -220.395293) (xy 340.620388 -220.443604)
			(xy 340.597822 -220.488998) (xy 340.568576 -220.530404) (xy 340.533339 -220.566847) (xy 340.49294 -220.597469)
			(xy 340.448331 -220.621548) (xy 340.400563 -220.638518) (xy 340.375748 -220.643704) (xy 340.352888 -220.648022)
			(xy 340.14791 -221.003114) (xy 340.155784 -221.024958) (xy 340.164377 -221.051373) (xy 340.173565 -221.106151)
			(xy 340.174072 -221.133924) (xy 340.454996 -221.133924) (xy 340.455504 -221.108037) (xy 340.463603 -221.056899)
			(xy 340.479602 -221.007659) (xy 340.503108 -220.961527) (xy 340.53354 -220.91964) (xy 340.57015 -220.88303)
			(xy 340.612037 -220.852598) (xy 340.658169 -220.829092) (xy 340.707409 -220.813093) (xy 340.758547 -220.804994)
			(xy 340.810321 -220.804994) (xy 340.861459 -220.813093) (xy 340.910699 -220.829092) (xy 340.956831 -220.852598)
			(xy 340.998718 -220.88303) (xy 341.035328 -220.91964) (xy 341.06576 -220.961527) (xy 341.089266 -221.007659)
			(xy 341.105265 -221.056899) (xy 341.113364 -221.108037) (xy 341.113872 -221.133924) (xy 341.394796 -221.133924)
			(xy 341.395304 -221.10859) (xy 341.403053 -221.058519) (xy 341.418372 -221.010223) (xy 341.4409 -220.96484)
			(xy 341.470106 -220.923438) (xy 341.505304 -220.886992) (xy 341.545663 -220.856361) (xy 341.590234 -220.832266)
			(xy 341.637967 -220.815274) (xy 341.662766 -220.810074) (xy 341.685626 -220.805756) (xy 341.890604 -220.450664)
			(xy 341.88273 -220.42882) (xy 341.874096 -220.402408) (xy 341.864768 -220.347635) (xy 341.864188 -220.319854)
			(xy 341.864696 -220.293947) (xy 341.872802 -220.24277) (xy 341.888814 -220.193491) (xy 341.912337 -220.147324)
			(xy 341.942793 -220.105405) (xy 341.979431 -220.068767) (xy 342.02135 -220.038311) (xy 342.067517 -220.014788)
			(xy 342.116796 -219.998776) (xy 342.167973 -219.99067) (xy 342.219787 -219.99067) (xy 342.270964 -219.998776)
			(xy 342.320243 -220.014788) (xy 342.36641 -220.038311) (xy 342.408329 -220.068767) (xy 342.444967 -220.105405)
			(xy 342.475423 -220.147324) (xy 342.498946 -220.193491) (xy 342.514958 -220.24277) (xy 342.523064 -220.293947)
			(xy 342.523572 -220.319854) (xy 342.523122 -220.3452) (xy 342.515342 -220.395293) (xy 342.499988 -220.443604)
			(xy 342.477422 -220.488998) (xy 342.448176 -220.530404) (xy 342.412939 -220.566847) (xy 342.37254 -220.597469)
			(xy 342.327931 -220.621548) (xy 342.280163 -220.638518) (xy 342.255348 -220.643704) (xy 342.232488 -220.648022)
			(xy 342.02751 -221.003114) (xy 342.035384 -221.024958) (xy 342.043977 -221.051373) (xy 342.053165 -221.106151)
			(xy 342.053672 -221.133924) (xy 342.334596 -221.133924) (xy 342.335104 -221.108037) (xy 342.343203 -221.056899)
			(xy 342.359202 -221.007659) (xy 342.382708 -220.961527) (xy 342.41314 -220.91964) (xy 342.44975 -220.88303)
			(xy 342.491637 -220.852598) (xy 342.537769 -220.829092) (xy 342.587009 -220.813093) (xy 342.638147 -220.804994)
			(xy 342.689921 -220.804994) (xy 342.741059 -220.813093) (xy 342.790299 -220.829092) (xy 342.836431 -220.852598)
			(xy 342.878318 -220.88303) (xy 342.914928 -220.91964) (xy 342.94536 -220.961527) (xy 342.968866 -221.007659)
			(xy 342.984865 -221.056899) (xy 342.992964 -221.108037) (xy 342.993472 -221.133924) (xy 343.274396 -221.133924)
			(xy 343.274904 -221.10859) (xy 343.282653 -221.058519) (xy 343.297972 -221.010223) (xy 343.3205 -220.96484)
			(xy 343.349706 -220.923438) (xy 343.384904 -220.886992) (xy 343.425263 -220.856361) (xy 343.469834 -220.832266)
			(xy 343.517567 -220.815274) (xy 343.542366 -220.810074) (xy 343.565226 -220.805756) (xy 343.770204 -220.450664)
			(xy 343.76233 -220.42882) (xy 343.753696 -220.402408) (xy 343.744368 -220.347635) (xy 343.743788 -220.319854)
			(xy 343.744296 -220.293947) (xy 343.752402 -220.24277) (xy 343.768414 -220.193491) (xy 343.791937 -220.147324)
			(xy 343.822393 -220.105405) (xy 343.859031 -220.068767) (xy 343.90095 -220.038311) (xy 343.947117 -220.014788)
			(xy 343.996396 -219.998776) (xy 344.047573 -219.99067) (xy 344.099387 -219.99067) (xy 344.150564 -219.998776)
			(xy 344.199843 -220.014788) (xy 344.24601 -220.038311) (xy 344.287929 -220.068767) (xy 344.324567 -220.105405)
			(xy 344.355023 -220.147324) (xy 344.378546 -220.193491) (xy 344.394558 -220.24277) (xy 344.402664 -220.293947)
			(xy 344.403172 -220.319854) (xy 344.402722 -220.3452) (xy 344.394942 -220.395293) (xy 344.379588 -220.443604)
			(xy 344.357022 -220.488998) (xy 344.327776 -220.530404) (xy 344.292539 -220.566847) (xy 344.25214 -220.597469)
			(xy 344.207531 -220.621548) (xy 344.159763 -220.638518) (xy 344.134948 -220.643704) (xy 344.112088 -220.648022)
			(xy 343.90711 -221.003114) (xy 343.914984 -221.024958) (xy 343.923577 -221.051373) (xy 343.932765 -221.106151)
			(xy 343.933272 -221.133924) (xy 344.214196 -221.133924) (xy 344.214704 -221.108037) (xy 344.222803 -221.056899)
			(xy 344.238802 -221.007659) (xy 344.262308 -220.961527) (xy 344.29274 -220.91964) (xy 344.32935 -220.88303)
			(xy 344.371237 -220.852598) (xy 344.417369 -220.829092) (xy 344.466609 -220.813093) (xy 344.517747 -220.804994)
			(xy 344.569521 -220.804994) (xy 344.620659 -220.813093) (xy 344.669899 -220.829092) (xy 344.716031 -220.852598)
			(xy 344.757918 -220.88303) (xy 344.794528 -220.91964) (xy 344.82496 -220.961527) (xy 344.848466 -221.007659)
			(xy 344.864465 -221.056899) (xy 344.872564 -221.108037) (xy 344.873072 -221.133924) (xy 345.153996 -221.133924)
			(xy 345.154504 -221.10859) (xy 345.162253 -221.058519) (xy 345.177572 -221.010223) (xy 345.2001 -220.96484)
			(xy 345.229306 -220.923438) (xy 345.264504 -220.886992) (xy 345.304863 -220.856361) (xy 345.349434 -220.832266)
			(xy 345.397167 -220.815274) (xy 345.421966 -220.810074) (xy 345.444826 -220.805756) (xy 345.649804 -220.450664)
			(xy 345.64193 -220.42882) (xy 345.633296 -220.402408) (xy 345.623968 -220.347635) (xy 345.623388 -220.319854)
			(xy 345.623896 -220.293947) (xy 345.632002 -220.24277) (xy 345.648014 -220.193491) (xy 345.671537 -220.147324)
			(xy 345.701993 -220.105405) (xy 345.738631 -220.068767) (xy 345.78055 -220.038311) (xy 345.826717 -220.014788)
			(xy 345.875996 -219.998776) (xy 345.927173 -219.99067) (xy 345.978987 -219.99067) (xy 346.030164 -219.998776)
			(xy 346.079443 -220.014788) (xy 346.12561 -220.038311) (xy 346.167529 -220.068767) (xy 346.204167 -220.105405)
			(xy 346.234623 -220.147324) (xy 346.258146 -220.193491) (xy 346.274158 -220.24277) (xy 346.282264 -220.293947)
			(xy 346.282772 -220.319854) (xy 346.282322 -220.3452) (xy 346.274542 -220.395293) (xy 346.259188 -220.443604)
			(xy 346.236622 -220.488998) (xy 346.207376 -220.530404) (xy 346.172139 -220.566847) (xy 346.13174 -220.597469)
			(xy 346.087131 -220.621548) (xy 346.039363 -220.638518) (xy 346.014548 -220.643704) (xy 345.991688 -220.648022)
			(xy 345.78671 -221.003114) (xy 345.794584 -221.024958) (xy 345.803177 -221.051373) (xy 345.812365 -221.106151)
			(xy 345.812872 -221.133924) (xy 346.093796 -221.133924) (xy 346.094304 -221.108037) (xy 346.102403 -221.056899)
			(xy 346.118402 -221.007659) (xy 346.141908 -220.961527) (xy 346.17234 -220.91964) (xy 346.20895 -220.88303)
			(xy 346.250837 -220.852598) (xy 346.296969 -220.829092) (xy 346.346209 -220.813093) (xy 346.397347 -220.804994)
			(xy 346.449121 -220.804994) (xy 346.500259 -220.813093) (xy 346.549499 -220.829092) (xy 346.595631 -220.852598)
			(xy 346.637518 -220.88303) (xy 346.674128 -220.91964) (xy 346.70456 -220.961527) (xy 346.728066 -221.007659)
			(xy 346.744065 -221.056899) (xy 346.752164 -221.108037) (xy 346.752672 -221.133924) (xy 347.033596 -221.133924)
			(xy 347.034104 -221.10859) (xy 347.041853 -221.058519) (xy 347.057172 -221.010223) (xy 347.0797 -220.96484)
			(xy 347.108906 -220.923438) (xy 347.144104 -220.886992) (xy 347.184463 -220.856361) (xy 347.229034 -220.832266)
			(xy 347.276767 -220.815274) (xy 347.301566 -220.810074) (xy 347.324426 -220.805756) (xy 347.529404 -220.450664)
			(xy 347.52153 -220.42882) (xy 347.512896 -220.402408) (xy 347.503568 -220.347635) (xy 347.502988 -220.319854)
			(xy 347.503496 -220.293947) (xy 347.511602 -220.24277) (xy 347.527614 -220.193491) (xy 347.551137 -220.147324)
			(xy 347.581593 -220.105405) (xy 347.618231 -220.068767) (xy 347.66015 -220.038311) (xy 347.706317 -220.014788)
			(xy 347.755596 -219.998776) (xy 347.806773 -219.99067) (xy 347.858587 -219.99067) (xy 347.909764 -219.998776)
			(xy 347.959043 -220.014788) (xy 348.00521 -220.038311) (xy 348.047129 -220.068767) (xy 348.083767 -220.105405)
			(xy 348.114223 -220.147324) (xy 348.137746 -220.193491) (xy 348.153758 -220.24277) (xy 348.161864 -220.293947)
			(xy 348.162372 -220.319854) (xy 348.161922 -220.3452) (xy 348.154142 -220.395293) (xy 348.138788 -220.443604)
			(xy 348.116222 -220.488998) (xy 348.086976 -220.530404) (xy 348.051739 -220.566847) (xy 348.01134 -220.597469)
			(xy 347.966731 -220.621548) (xy 347.918963 -220.638518) (xy 347.894148 -220.643704) (xy 347.871288 -220.648022)
			(xy 347.66631 -221.003114) (xy 347.674184 -221.024958) (xy 347.682777 -221.051373) (xy 347.691965 -221.106151)
			(xy 347.692472 -221.133924) (xy 347.973396 -221.133924) (xy 347.973904 -221.108037) (xy 347.982003 -221.056899)
			(xy 347.998002 -221.007659) (xy 348.021508 -220.961527) (xy 348.05194 -220.91964) (xy 348.08855 -220.88303)
			(xy 348.130437 -220.852598) (xy 348.176569 -220.829092) (xy 348.225809 -220.813093) (xy 348.276947 -220.804994)
			(xy 348.328721 -220.804994) (xy 348.379859 -220.813093) (xy 348.429099 -220.829092) (xy 348.475231 -220.852598)
			(xy 348.517118 -220.88303) (xy 348.553728 -220.91964) (xy 348.58416 -220.961527) (xy 348.607666 -221.007659)
			(xy 348.623665 -221.056899) (xy 348.631764 -221.108037) (xy 348.632272 -221.133924) (xy 348.913196 -221.133924)
			(xy 348.913704 -221.10859) (xy 348.921453 -221.058519) (xy 348.936772 -221.010223) (xy 348.9593 -220.96484)
			(xy 348.988506 -220.923438) (xy 349.023704 -220.886992) (xy 349.064063 -220.856361) (xy 349.108634 -220.832266)
			(xy 349.156367 -220.815274) (xy 349.181166 -220.810074) (xy 349.204026 -220.805756) (xy 349.409004 -220.450664)
			(xy 349.40113 -220.42882) (xy 349.392496 -220.402408) (xy 349.383168 -220.347635) (xy 349.382588 -220.319854)
			(xy 349.383096 -220.293947) (xy 349.391202 -220.24277) (xy 349.407214 -220.193491) (xy 349.430737 -220.147324)
			(xy 349.461193 -220.105405) (xy 349.497831 -220.068767) (xy 349.53975 -220.038311) (xy 349.585917 -220.014788)
			(xy 349.635196 -219.998776) (xy 349.686373 -219.99067) (xy 349.738187 -219.99067) (xy 349.789364 -219.998776)
			(xy 349.838643 -220.014788) (xy 349.88481 -220.038311) (xy 349.926729 -220.068767) (xy 349.963367 -220.105405)
			(xy 349.993823 -220.147324) (xy 350.017346 -220.193491) (xy 350.033358 -220.24277) (xy 350.041464 -220.293947)
			(xy 350.041972 -220.319854) (xy 350.041522 -220.3452) (xy 350.033742 -220.395293) (xy 350.018388 -220.443604)
			(xy 349.995822 -220.488998) (xy 349.966576 -220.530404) (xy 349.931339 -220.566847) (xy 349.89094 -220.597469)
			(xy 349.846331 -220.621548) (xy 349.798563 -220.638518) (xy 349.773748 -220.643704) (xy 349.750888 -220.648022)
			(xy 349.54591 -221.003114) (xy 349.553784 -221.024958) (xy 349.562377 -221.051373) (xy 349.571565 -221.106151)
			(xy 349.572072 -221.133924) (xy 349.852996 -221.133924) (xy 349.853504 -221.108037) (xy 349.861603 -221.056899)
			(xy 349.877602 -221.007659) (xy 349.901108 -220.961527) (xy 349.93154 -220.91964) (xy 349.96815 -220.88303)
			(xy 350.010037 -220.852598) (xy 350.056169 -220.829092) (xy 350.105409 -220.813093) (xy 350.156547 -220.804994)
			(xy 350.208321 -220.804994) (xy 350.259459 -220.813093) (xy 350.308699 -220.829092) (xy 350.354831 -220.852598)
			(xy 350.396718 -220.88303) (xy 350.433328 -220.91964) (xy 350.46376 -220.961527) (xy 350.487266 -221.007659)
			(xy 350.503265 -221.056899) (xy 350.511364 -221.108037) (xy 350.511872 -221.133924) (xy 350.792796 -221.133924)
			(xy 350.793304 -221.10859) (xy 350.801053 -221.058519) (xy 350.816372 -221.010223) (xy 350.8389 -220.96484)
			(xy 350.868106 -220.923438) (xy 350.903304 -220.886992) (xy 350.943663 -220.856361) (xy 350.988234 -220.832266)
			(xy 351.035967 -220.815274) (xy 351.060766 -220.810074) (xy 351.083626 -220.805756) (xy 351.288604 -220.450664)
			(xy 351.28073 -220.42882) (xy 351.272096 -220.402408) (xy 351.262768 -220.347635) (xy 351.262188 -220.319854)
			(xy 351.262696 -220.293947) (xy 351.270802 -220.24277) (xy 351.286814 -220.193491) (xy 351.310337 -220.147324)
			(xy 351.340793 -220.105405) (xy 351.377431 -220.068767) (xy 351.41935 -220.038311) (xy 351.465517 -220.014788)
			(xy 351.514796 -219.998776) (xy 351.565973 -219.99067) (xy 351.617787 -219.99067) (xy 351.668964 -219.998776)
			(xy 351.718243 -220.014788) (xy 351.76441 -220.038311) (xy 351.806329 -220.068767) (xy 351.842967 -220.105405)
			(xy 351.873423 -220.147324) (xy 351.896946 -220.193491) (xy 351.912958 -220.24277) (xy 351.921064 -220.293947)
			(xy 351.921572 -220.319854) (xy 353.141788 -220.319854) (xy 353.142296 -220.293947) (xy 353.150402 -220.24277)
			(xy 353.166414 -220.193491) (xy 353.189937 -220.147324) (xy 353.220393 -220.105405) (xy 353.257031 -220.068767)
			(xy 353.29895 -220.038311) (xy 353.345117 -220.014788) (xy 353.394396 -219.998776) (xy 353.445573 -219.99067)
			(xy 353.497387 -219.99067) (xy 353.548564 -219.998776) (xy 353.597843 -220.014788) (xy 353.64401 -220.038311)
			(xy 353.685929 -220.068767) (xy 353.722567 -220.105405) (xy 353.753023 -220.147324) (xy 353.776546 -220.193491)
			(xy 353.792558 -220.24277) (xy 353.800664 -220.293947) (xy 353.801172 -220.319854) (xy 355.021388 -220.319854)
			(xy 355.021896 -220.293947) (xy 355.030002 -220.24277) (xy 355.046014 -220.193491) (xy 355.069537 -220.147324)
			(xy 355.099993 -220.105405) (xy 355.136631 -220.068767) (xy 355.17855 -220.038311) (xy 355.224717 -220.014788)
			(xy 355.273996 -219.998776) (xy 355.325173 -219.99067) (xy 355.376987 -219.99067) (xy 355.428164 -219.998776)
			(xy 355.477443 -220.014788) (xy 355.52361 -220.038311) (xy 355.565529 -220.068767) (xy 355.602167 -220.105405)
			(xy 355.632623 -220.147324) (xy 355.656146 -220.193491) (xy 355.672158 -220.24277) (xy 355.680264 -220.293947)
			(xy 355.680772 -220.319854) (xy 356.900988 -220.319854) (xy 356.901496 -220.293947) (xy 356.909602 -220.24277)
			(xy 356.925614 -220.193491) (xy 356.949137 -220.147324) (xy 356.979593 -220.105405) (xy 357.016231 -220.068767)
			(xy 357.05815 -220.038311) (xy 357.104317 -220.014788) (xy 357.153596 -219.998776) (xy 357.204773 -219.99067)
			(xy 357.256587 -219.99067) (xy 357.307764 -219.998776) (xy 357.357043 -220.014788) (xy 357.40321 -220.038311)
			(xy 357.445129 -220.068767) (xy 357.481767 -220.105405) (xy 357.512223 -220.147324) (xy 357.535746 -220.193491)
			(xy 357.551758 -220.24277) (xy 357.559864 -220.293947) (xy 357.560372 -220.319854) (xy 358.780588 -220.319854)
			(xy 358.781096 -220.293947) (xy 358.789202 -220.24277) (xy 358.805214 -220.193491) (xy 358.828737 -220.147324)
			(xy 358.859193 -220.105405) (xy 358.895831 -220.068767) (xy 358.93775 -220.038311) (xy 358.983917 -220.014788)
			(xy 359.033196 -219.998776) (xy 359.084373 -219.99067) (xy 359.136187 -219.99067) (xy 359.187364 -219.998776)
			(xy 359.236643 -220.014788) (xy 359.28281 -220.038311) (xy 359.324729 -220.068767) (xy 359.361367 -220.105405)
			(xy 359.391823 -220.147324) (xy 359.415346 -220.193491) (xy 359.431358 -220.24277) (xy 359.439464 -220.293947)
			(xy 359.439972 -220.319854) (xy 360.660188 -220.319854) (xy 360.660696 -220.293947) (xy 360.668802 -220.24277)
			(xy 360.684814 -220.193491) (xy 360.708337 -220.147324) (xy 360.738793 -220.105405) (xy 360.775431 -220.068767)
			(xy 360.81735 -220.038311) (xy 360.863517 -220.014788) (xy 360.912796 -219.998776) (xy 360.963973 -219.99067)
			(xy 361.015787 -219.99067) (xy 361.066964 -219.998776) (xy 361.116243 -220.014788) (xy 361.16241 -220.038311)
			(xy 361.204329 -220.068767) (xy 361.240967 -220.105405) (xy 361.271423 -220.147324) (xy 361.294946 -220.193491)
			(xy 361.310958 -220.24277) (xy 361.319064 -220.293947) (xy 361.319572 -220.319854) (xy 362.539788 -220.319854)
			(xy 362.540296 -220.293947) (xy 362.548402 -220.24277) (xy 362.564414 -220.193491) (xy 362.587937 -220.147324)
			(xy 362.618393 -220.105405) (xy 362.655031 -220.068767) (xy 362.69695 -220.038311) (xy 362.743117 -220.014788)
			(xy 362.792396 -219.998776) (xy 362.843573 -219.99067) (xy 362.895387 -219.99067) (xy 362.946564 -219.998776)
			(xy 362.995843 -220.014788) (xy 363.04201 -220.038311) (xy 363.083929 -220.068767) (xy 363.120567 -220.105405)
			(xy 363.151023 -220.147324) (xy 363.174546 -220.193491) (xy 363.190558 -220.24277) (xy 363.198664 -220.293947)
			(xy 363.199172 -220.319854) (xy 364.419388 -220.319854) (xy 364.419896 -220.293947) (xy 364.428002 -220.24277)
			(xy 364.444014 -220.193491) (xy 364.467537 -220.147324) (xy 364.497993 -220.105405) (xy 364.534631 -220.068767)
			(xy 364.57655 -220.038311) (xy 364.622717 -220.014788) (xy 364.671996 -219.998776) (xy 364.723173 -219.99067)
			(xy 364.774987 -219.99067) (xy 364.826164 -219.998776) (xy 364.875443 -220.014788) (xy 364.92161 -220.038311)
			(xy 364.963529 -220.068767) (xy 365.000167 -220.105405) (xy 365.030623 -220.147324) (xy 365.054146 -220.193491)
			(xy 365.070158 -220.24277) (xy 365.078264 -220.293947) (xy 365.078772 -220.319854) (xy 366.298988 -220.319854)
			(xy 366.299496 -220.293947) (xy 366.307602 -220.24277) (xy 366.323614 -220.193491) (xy 366.347137 -220.147324)
			(xy 366.377593 -220.105405) (xy 366.414231 -220.068767) (xy 366.45615 -220.038311) (xy 366.502317 -220.014788)
			(xy 366.551596 -219.998776) (xy 366.602773 -219.99067) (xy 366.654587 -219.99067) (xy 366.705764 -219.998776)
			(xy 366.755043 -220.014788) (xy 366.80121 -220.038311) (xy 366.843129 -220.068767) (xy 366.879767 -220.105405)
			(xy 366.910223 -220.147324) (xy 366.933746 -220.193491) (xy 366.949758 -220.24277) (xy 366.957864 -220.293947)
			(xy 366.958372 -220.319854) (xy 368.178588 -220.319854) (xy 368.179096 -220.293947) (xy 368.187202 -220.24277)
			(xy 368.203214 -220.193491) (xy 368.226737 -220.147324) (xy 368.257193 -220.105405) (xy 368.293831 -220.068767)
			(xy 368.33575 -220.038311) (xy 368.381917 -220.014788) (xy 368.431196 -219.998776) (xy 368.482373 -219.99067)
			(xy 368.534187 -219.99067) (xy 368.585364 -219.998776) (xy 368.634643 -220.014788) (xy 368.68081 -220.038311)
			(xy 368.722729 -220.068767) (xy 368.759367 -220.105405) (xy 368.789823 -220.147324) (xy 368.813346 -220.193491)
			(xy 368.829358 -220.24277) (xy 368.837464 -220.293947) (xy 368.837972 -220.319854) (xy 370.058188 -220.319854)
			(xy 370.058696 -220.293947) (xy 370.066802 -220.24277) (xy 370.082814 -220.193491) (xy 370.106337 -220.147324)
			(xy 370.136793 -220.105405) (xy 370.173431 -220.068767) (xy 370.21535 -220.038311) (xy 370.261517 -220.014788)
			(xy 370.310796 -219.998776) (xy 370.361973 -219.99067) (xy 370.413787 -219.99067) (xy 370.464964 -219.998776)
			(xy 370.514243 -220.014788) (xy 370.56041 -220.038311) (xy 370.602329 -220.068767) (xy 370.638967 -220.105405)
			(xy 370.669423 -220.147324) (xy 370.692946 -220.193491) (xy 370.708958 -220.24277) (xy 370.717064 -220.293947)
			(xy 370.717572 -220.319854) (xy 371.937788 -220.319854) (xy 371.938296 -220.293947) (xy 371.946402 -220.24277)
			(xy 371.962414 -220.193491) (xy 371.985937 -220.147324) (xy 372.016393 -220.105405) (xy 372.053031 -220.068767)
			(xy 372.09495 -220.038311) (xy 372.141117 -220.014788) (xy 372.190396 -219.998776) (xy 372.241573 -219.99067)
			(xy 372.293387 -219.99067) (xy 372.344564 -219.998776) (xy 372.393843 -220.014788) (xy 372.44001 -220.038311)
			(xy 372.481929 -220.068767) (xy 372.518567 -220.105405) (xy 372.549023 -220.147324) (xy 372.572546 -220.193491)
			(xy 372.588558 -220.24277) (xy 372.596664 -220.293947) (xy 372.597172 -220.319854) (xy 373.817388 -220.319854)
			(xy 373.817896 -220.293947) (xy 373.826002 -220.24277) (xy 373.842014 -220.193491) (xy 373.865537 -220.147324)
			(xy 373.895993 -220.105405) (xy 373.932631 -220.068767) (xy 373.97455 -220.038311) (xy 374.020717 -220.014788)
			(xy 374.069996 -219.998776) (xy 374.121173 -219.99067) (xy 374.172987 -219.99067) (xy 374.224164 -219.998776)
			(xy 374.273443 -220.014788) (xy 374.31961 -220.038311) (xy 374.361529 -220.068767) (xy 374.398167 -220.105405)
			(xy 374.428623 -220.147324) (xy 374.452146 -220.193491) (xy 374.468158 -220.24277) (xy 374.476264 -220.293947)
			(xy 374.476772 -220.319854) (xy 375.696988 -220.319854) (xy 375.697496 -220.293947) (xy 375.705602 -220.24277)
			(xy 375.721614 -220.193491) (xy 375.745137 -220.147324) (xy 375.775593 -220.105405) (xy 375.812231 -220.068767)
			(xy 375.85415 -220.038311) (xy 375.900317 -220.014788) (xy 375.949596 -219.998776) (xy 376.000773 -219.99067)
			(xy 376.052587 -219.99067) (xy 376.103764 -219.998776) (xy 376.153043 -220.014788) (xy 376.19921 -220.038311)
			(xy 376.241129 -220.068767) (xy 376.277767 -220.105405) (xy 376.308223 -220.147324) (xy 376.331746 -220.193491)
			(xy 376.347758 -220.24277) (xy 376.355864 -220.293947) (xy 376.356372 -220.319854) (xy 377.576588 -220.319854)
			(xy 377.577096 -220.293947) (xy 377.585202 -220.24277) (xy 377.601214 -220.193491) (xy 377.624737 -220.147324)
			(xy 377.655193 -220.105405) (xy 377.691831 -220.068767) (xy 377.73375 -220.038311) (xy 377.779917 -220.014788)
			(xy 377.829196 -219.998776) (xy 377.880373 -219.99067) (xy 377.932187 -219.99067) (xy 377.983364 -219.998776)
			(xy 378.032643 -220.014788) (xy 378.07881 -220.038311) (xy 378.120729 -220.068767) (xy 378.157367 -220.105405)
			(xy 378.187823 -220.147324) (xy 378.211346 -220.193491) (xy 378.227358 -220.24277) (xy 378.235464 -220.293947)
			(xy 378.235972 -220.319854) (xy 379.456188 -220.319854) (xy 379.456696 -220.293947) (xy 379.464802 -220.24277)
			(xy 379.480814 -220.193491) (xy 379.504337 -220.147324) (xy 379.534793 -220.105405) (xy 379.571431 -220.068767)
			(xy 379.61335 -220.038311) (xy 379.659517 -220.014788) (xy 379.708796 -219.998776) (xy 379.759973 -219.99067)
			(xy 379.811787 -219.99067) (xy 379.862964 -219.998776) (xy 379.912243 -220.014788) (xy 379.95841 -220.038311)
			(xy 380.000329 -220.068767) (xy 380.036967 -220.105405) (xy 380.067423 -220.147324) (xy 380.090946 -220.193491)
			(xy 380.106958 -220.24277) (xy 380.115064 -220.293947) (xy 380.115572 -220.319854) (xy 381.336296 -220.319854)
			(xy 381.336804 -220.293967) (xy 381.344903 -220.242829) (xy 381.360902 -220.193589) (xy 381.384408 -220.147457)
			(xy 381.41484 -220.10557) (xy 381.45145 -220.06896) (xy 381.493337 -220.038528) (xy 381.539469 -220.015022)
			(xy 381.588709 -219.999023) (xy 381.639847 -219.990924) (xy 381.691621 -219.990924) (xy 381.742759 -219.999023)
			(xy 381.791999 -220.015022) (xy 381.838131 -220.038528) (xy 381.880018 -220.06896) (xy 381.916628 -220.10557)
			(xy 381.94706 -220.147457) (xy 381.970566 -220.193589) (xy 381.986565 -220.242829) (xy 381.994664 -220.293967)
			(xy 381.995172 -220.319854) (xy 381.994628 -220.347561) (xy 381.985442 -220.402208) (xy 381.976884 -220.428566)
			(xy 381.969264 -220.450664) (xy 382.174242 -220.805756) (xy 382.197102 -220.810074) (xy 382.221908 -220.815252)
			(xy 382.269647 -220.832242) (xy 382.314225 -220.856337) (xy 382.354591 -220.886969) (xy 382.389795 -220.923417)
			(xy 382.419006 -220.964822) (xy 382.441538 -221.01021) (xy 382.45686 -221.058511) (xy 382.46461 -221.108588)
			(xy 382.465072 -221.133924) (xy 382.464564 -221.159811) (xy 382.456465 -221.210949) (xy 382.440466 -221.260189)
			(xy 382.41696 -221.306321) (xy 382.386528 -221.348208) (xy 382.349918 -221.384818) (xy 382.308031 -221.41525)
			(xy 382.261899 -221.438756) (xy 382.212659 -221.454755) (xy 382.161521 -221.462854) (xy 382.109747 -221.462854)
			(xy 382.058609 -221.454755) (xy 382.009369 -221.438756) (xy 381.963237 -221.41525) (xy 381.92135 -221.384818)
			(xy 381.88474 -221.348208) (xy 381.854308 -221.306321) (xy 381.830802 -221.260189) (xy 381.814803 -221.210949)
			(xy 381.806704 -221.159811) (xy 381.806196 -221.133924) (xy 381.806732 -221.106216) (xy 381.815923 -221.051569)
			(xy 381.824484 -221.025212) (xy 381.832358 -221.003114) (xy 381.62738 -220.648022) (xy 381.60452 -220.643704)
			(xy 381.579694 -220.638559) (xy 381.531915 -220.6216) (xy 381.487296 -220.597525) (xy 381.446891 -220.566902)
			(xy 381.41165 -220.530452) (xy 381.382408 -220.489036) (xy 381.359851 -220.44363) (xy 381.344514 -220.395306)
			(xy 381.336758 -220.345204) (xy 381.336296 -220.319854) (xy 380.115572 -220.319854) (xy 380.114963 -220.347508)
			(xy 380.105639 -220.402026) (xy 380.09703 -220.428312) (xy 380.08941 -220.45041) (xy 380.294642 -220.805756)
			(xy 380.317502 -220.810074) (xy 380.342308 -220.815252) (xy 380.390047 -220.832242) (xy 380.434625 -220.856337)
			(xy 380.474991 -220.886969) (xy 380.510195 -220.923417) (xy 380.539406 -220.964822) (xy 380.561938 -221.01021)
			(xy 380.57726 -221.058511) (xy 380.58501 -221.108588) (xy 380.585472 -221.133924) (xy 380.584964 -221.159811)
			(xy 380.576865 -221.210949) (xy 380.560866 -221.260189) (xy 380.53736 -221.306321) (xy 380.506928 -221.348208)
			(xy 380.470318 -221.384818) (xy 380.428431 -221.41525) (xy 380.382299 -221.438756) (xy 380.333059 -221.454755)
			(xy 380.281921 -221.462854) (xy 380.230147 -221.462854) (xy 380.179009 -221.454755) (xy 380.129769 -221.438756)
			(xy 380.083637 -221.41525) (xy 380.04175 -221.384818) (xy 380.00514 -221.348208) (xy 379.974708 -221.306321)
			(xy 379.951202 -221.260189) (xy 379.935203 -221.210949) (xy 379.927104 -221.159811) (xy 379.926596 -221.133924)
			(xy 379.927132 -221.106216) (xy 379.936323 -221.051569) (xy 379.944884 -221.025212) (xy 379.952758 -221.003114)
			(xy 379.74778 -220.648022) (xy 379.72492 -220.643704) (xy 379.700079 -220.638521) (xy 379.652232 -220.621628)
			(xy 379.60754 -220.5976) (xy 379.567059 -220.567005) (xy 379.531748 -220.530566) (xy 379.502439 -220.489145)
			(xy 379.479827 -220.44372) (xy 379.464446 -220.395365) (xy 379.456659 -220.345225) (xy 379.456188 -220.319854)
			(xy 378.235972 -220.319854) (xy 378.235363 -220.347508) (xy 378.226039 -220.402026) (xy 378.21743 -220.428312)
			(xy 378.20981 -220.45041) (xy 378.415042 -220.805756) (xy 378.437902 -220.810074) (xy 378.462708 -220.815252)
			(xy 378.510447 -220.832242) (xy 378.555025 -220.856337) (xy 378.595391 -220.886969) (xy 378.630595 -220.923417)
			(xy 378.659806 -220.964822) (xy 378.682338 -221.01021) (xy 378.69766 -221.058511) (xy 378.70541 -221.108588)
			(xy 378.705872 -221.133924) (xy 378.705364 -221.159811) (xy 378.697265 -221.210949) (xy 378.681266 -221.260189)
			(xy 378.65776 -221.306321) (xy 378.627328 -221.348208) (xy 378.590718 -221.384818) (xy 378.548831 -221.41525)
			(xy 378.502699 -221.438756) (xy 378.453459 -221.454755) (xy 378.402321 -221.462854) (xy 378.350547 -221.462854)
			(xy 378.299409 -221.454755) (xy 378.250169 -221.438756) (xy 378.204037 -221.41525) (xy 378.16215 -221.384818)
			(xy 378.12554 -221.348208) (xy 378.095108 -221.306321) (xy 378.071602 -221.260189) (xy 378.055603 -221.210949)
			(xy 378.047504 -221.159811) (xy 378.046996 -221.133924) (xy 378.047532 -221.106216) (xy 378.056723 -221.051569)
			(xy 378.065284 -221.025212) (xy 378.073158 -221.003114) (xy 377.86818 -220.648022) (xy 377.84532 -220.643704)
			(xy 377.820479 -220.638521) (xy 377.772632 -220.621628) (xy 377.72794 -220.5976) (xy 377.687459 -220.567005)
			(xy 377.652148 -220.530566) (xy 377.622839 -220.489145) (xy 377.600227 -220.44372) (xy 377.584846 -220.395365)
			(xy 377.577059 -220.345225) (xy 377.576588 -220.319854) (xy 376.356372 -220.319854) (xy 376.355763 -220.347508)
			(xy 376.346439 -220.402026) (xy 376.33783 -220.428312) (xy 376.33021 -220.45041) (xy 376.535442 -220.805756)
			(xy 376.558302 -220.810074) (xy 376.583108 -220.815252) (xy 376.630847 -220.832242) (xy 376.675425 -220.856337)
			(xy 376.715791 -220.886969) (xy 376.750995 -220.923417) (xy 376.780206 -220.964822) (xy 376.802738 -221.01021)
			(xy 376.81806 -221.058511) (xy 376.82581 -221.108588) (xy 376.826272 -221.133924) (xy 376.825764 -221.159811)
			(xy 376.817665 -221.210949) (xy 376.801666 -221.260189) (xy 376.77816 -221.306321) (xy 376.747728 -221.348208)
			(xy 376.711118 -221.384818) (xy 376.669231 -221.41525) (xy 376.623099 -221.438756) (xy 376.573859 -221.454755)
			(xy 376.522721 -221.462854) (xy 376.470947 -221.462854) (xy 376.419809 -221.454755) (xy 376.370569 -221.438756)
			(xy 376.324437 -221.41525) (xy 376.28255 -221.384818) (xy 376.24594 -221.348208) (xy 376.215508 -221.306321)
			(xy 376.192002 -221.260189) (xy 376.176003 -221.210949) (xy 376.167904 -221.159811) (xy 376.167396 -221.133924)
			(xy 376.167932 -221.106216) (xy 376.177123 -221.051569) (xy 376.185684 -221.025212) (xy 376.193558 -221.003114)
			(xy 375.98858 -220.648022) (xy 375.96572 -220.643704) (xy 375.940879 -220.638521) (xy 375.893032 -220.621628)
			(xy 375.84834 -220.5976) (xy 375.807859 -220.567005) (xy 375.772548 -220.530566) (xy 375.743239 -220.489145)
			(xy 375.720627 -220.44372) (xy 375.705246 -220.395365) (xy 375.697459 -220.345225) (xy 375.696988 -220.319854)
			(xy 374.476772 -220.319854) (xy 374.476163 -220.347508) (xy 374.466839 -220.402026) (xy 374.45823 -220.428312)
			(xy 374.45061 -220.45041) (xy 374.655842 -220.805756) (xy 374.678702 -220.810074) (xy 374.703508 -220.815252)
			(xy 374.751247 -220.832242) (xy 374.795825 -220.856337) (xy 374.836191 -220.886969) (xy 374.871395 -220.923417)
			(xy 374.900606 -220.964822) (xy 374.923138 -221.01021) (xy 374.93846 -221.058511) (xy 374.94621 -221.108588)
			(xy 374.946672 -221.133924) (xy 374.946164 -221.159811) (xy 374.938065 -221.210949) (xy 374.922066 -221.260189)
			(xy 374.89856 -221.306321) (xy 374.868128 -221.348208) (xy 374.831518 -221.384818) (xy 374.789631 -221.41525)
			(xy 374.743499 -221.438756) (xy 374.694259 -221.454755) (xy 374.643121 -221.462854) (xy 374.591347 -221.462854)
			(xy 374.540209 -221.454755) (xy 374.490969 -221.438756) (xy 374.444837 -221.41525) (xy 374.40295 -221.384818)
			(xy 374.36634 -221.348208) (xy 374.335908 -221.306321) (xy 374.312402 -221.260189) (xy 374.296403 -221.210949)
			(xy 374.288304 -221.159811) (xy 374.287796 -221.133924) (xy 374.288332 -221.106216) (xy 374.297523 -221.051569)
			(xy 374.306084 -221.025212) (xy 374.313958 -221.003114) (xy 374.10898 -220.648022) (xy 374.08612 -220.643704)
			(xy 374.061279 -220.638521) (xy 374.013432 -220.621628) (xy 373.96874 -220.5976) (xy 373.928259 -220.567005)
			(xy 373.892948 -220.530566) (xy 373.863639 -220.489145) (xy 373.841027 -220.44372) (xy 373.825646 -220.395365)
			(xy 373.817859 -220.345225) (xy 373.817388 -220.319854) (xy 372.597172 -220.319854) (xy 372.596563 -220.347508)
			(xy 372.587239 -220.402026) (xy 372.57863 -220.428312) (xy 372.57101 -220.45041) (xy 372.776242 -220.805756)
			(xy 372.799102 -220.810074) (xy 372.823908 -220.815252) (xy 372.871647 -220.832242) (xy 372.916225 -220.856337)
			(xy 372.956591 -220.886969) (xy 372.991795 -220.923417) (xy 373.021006 -220.964822) (xy 373.043538 -221.01021)
			(xy 373.05886 -221.058511) (xy 373.06661 -221.108588) (xy 373.067072 -221.133924) (xy 373.066564 -221.159811)
			(xy 373.058465 -221.210949) (xy 373.042466 -221.260189) (xy 373.01896 -221.306321) (xy 372.988528 -221.348208)
			(xy 372.951918 -221.384818) (xy 372.910031 -221.41525) (xy 372.863899 -221.438756) (xy 372.814659 -221.454755)
			(xy 372.763521 -221.462854) (xy 372.711747 -221.462854) (xy 372.660609 -221.454755) (xy 372.611369 -221.438756)
			(xy 372.565237 -221.41525) (xy 372.52335 -221.384818) (xy 372.48674 -221.348208) (xy 372.456308 -221.306321)
			(xy 372.432802 -221.260189) (xy 372.416803 -221.210949) (xy 372.408704 -221.159811) (xy 372.408196 -221.133924)
			(xy 372.408732 -221.106216) (xy 372.417923 -221.051569) (xy 372.426484 -221.025212) (xy 372.434358 -221.003114)
			(xy 372.22938 -220.648022) (xy 372.20652 -220.643704) (xy 372.181679 -220.638521) (xy 372.133832 -220.621628)
			(xy 372.08914 -220.5976) (xy 372.048659 -220.567005) (xy 372.013348 -220.530566) (xy 371.984039 -220.489145)
			(xy 371.961427 -220.44372) (xy 371.946046 -220.395365) (xy 371.938259 -220.345225) (xy 371.937788 -220.319854)
			(xy 370.717572 -220.319854) (xy 370.716963 -220.347508) (xy 370.707639 -220.402026) (xy 370.69903 -220.428312)
			(xy 370.69141 -220.45041) (xy 370.896642 -220.805756) (xy 370.919502 -220.810074) (xy 370.944308 -220.815252)
			(xy 370.992047 -220.832242) (xy 371.036625 -220.856337) (xy 371.076991 -220.886969) (xy 371.112195 -220.923417)
			(xy 371.141406 -220.964822) (xy 371.163938 -221.01021) (xy 371.17926 -221.058511) (xy 371.18701 -221.108588)
			(xy 371.187472 -221.133924) (xy 371.186964 -221.159811) (xy 371.178865 -221.210949) (xy 371.162866 -221.260189)
			(xy 371.13936 -221.306321) (xy 371.108928 -221.348208) (xy 371.072318 -221.384818) (xy 371.030431 -221.41525)
			(xy 370.984299 -221.438756) (xy 370.935059 -221.454755) (xy 370.883921 -221.462854) (xy 370.832147 -221.462854)
			(xy 370.781009 -221.454755) (xy 370.731769 -221.438756) (xy 370.685637 -221.41525) (xy 370.64375 -221.384818)
			(xy 370.60714 -221.348208) (xy 370.576708 -221.306321) (xy 370.553202 -221.260189) (xy 370.537203 -221.210949)
			(xy 370.529104 -221.159811) (xy 370.528596 -221.133924) (xy 370.529132 -221.106216) (xy 370.538323 -221.051569)
			(xy 370.546884 -221.025212) (xy 370.554758 -221.003114) (xy 370.34978 -220.648022) (xy 370.32692 -220.643704)
			(xy 370.302079 -220.638521) (xy 370.254232 -220.621628) (xy 370.20954 -220.5976) (xy 370.169059 -220.567005)
			(xy 370.133748 -220.530566) (xy 370.104439 -220.489145) (xy 370.081827 -220.44372) (xy 370.066446 -220.395365)
			(xy 370.058659 -220.345225) (xy 370.058188 -220.319854) (xy 368.837972 -220.319854) (xy 368.837363 -220.347508)
			(xy 368.828039 -220.402026) (xy 368.81943 -220.428312) (xy 368.81181 -220.45041) (xy 369.017042 -220.805756)
			(xy 369.039902 -220.810074) (xy 369.064708 -220.815252) (xy 369.112447 -220.832242) (xy 369.157025 -220.856337)
			(xy 369.197391 -220.886969) (xy 369.232595 -220.923417) (xy 369.261806 -220.964822) (xy 369.284338 -221.01021)
			(xy 369.29966 -221.058511) (xy 369.30741 -221.108588) (xy 369.307872 -221.133924) (xy 369.307364 -221.159811)
			(xy 369.299265 -221.210949) (xy 369.283266 -221.260189) (xy 369.25976 -221.306321) (xy 369.229328 -221.348208)
			(xy 369.192718 -221.384818) (xy 369.150831 -221.41525) (xy 369.104699 -221.438756) (xy 369.055459 -221.454755)
			(xy 369.004321 -221.462854) (xy 368.952547 -221.462854) (xy 368.901409 -221.454755) (xy 368.852169 -221.438756)
			(xy 368.806037 -221.41525) (xy 368.76415 -221.384818) (xy 368.72754 -221.348208) (xy 368.697108 -221.306321)
			(xy 368.673602 -221.260189) (xy 368.657603 -221.210949) (xy 368.649504 -221.159811) (xy 368.648996 -221.133924)
			(xy 368.649532 -221.106216) (xy 368.658723 -221.051569) (xy 368.667284 -221.025212) (xy 368.675158 -221.003114)
			(xy 368.47018 -220.648022) (xy 368.44732 -220.643704) (xy 368.422479 -220.638521) (xy 368.374632 -220.621628)
			(xy 368.32994 -220.5976) (xy 368.289459 -220.567005) (xy 368.254148 -220.530566) (xy 368.224839 -220.489145)
			(xy 368.202227 -220.44372) (xy 368.186846 -220.395365) (xy 368.179059 -220.345225) (xy 368.178588 -220.319854)
			(xy 366.958372 -220.319854) (xy 366.957763 -220.347508) (xy 366.948439 -220.402026) (xy 366.93983 -220.428312)
			(xy 366.93221 -220.45041) (xy 367.137442 -220.805756) (xy 367.160302 -220.810074) (xy 367.185108 -220.815252)
			(xy 367.232847 -220.832242) (xy 367.277425 -220.856337) (xy 367.317791 -220.886969) (xy 367.352995 -220.923417)
			(xy 367.382206 -220.964822) (xy 367.404738 -221.01021) (xy 367.42006 -221.058511) (xy 367.42781 -221.108588)
			(xy 367.428272 -221.133924) (xy 367.427764 -221.159811) (xy 367.419665 -221.210949) (xy 367.403666 -221.260189)
			(xy 367.38016 -221.306321) (xy 367.349728 -221.348208) (xy 367.313118 -221.384818) (xy 367.271231 -221.41525)
			(xy 367.225099 -221.438756) (xy 367.175859 -221.454755) (xy 367.124721 -221.462854) (xy 367.072947 -221.462854)
			(xy 367.021809 -221.454755) (xy 366.972569 -221.438756) (xy 366.926437 -221.41525) (xy 366.88455 -221.384818)
			(xy 366.84794 -221.348208) (xy 366.817508 -221.306321) (xy 366.794002 -221.260189) (xy 366.778003 -221.210949)
			(xy 366.769904 -221.159811) (xy 366.769396 -221.133924) (xy 366.769932 -221.106216) (xy 366.779123 -221.051569)
			(xy 366.787684 -221.025212) (xy 366.795558 -221.003114) (xy 366.59058 -220.648022) (xy 366.56772 -220.643704)
			(xy 366.542879 -220.638521) (xy 366.495032 -220.621628) (xy 366.45034 -220.5976) (xy 366.409859 -220.567005)
			(xy 366.374548 -220.530566) (xy 366.345239 -220.489145) (xy 366.322627 -220.44372) (xy 366.307246 -220.395365)
			(xy 366.299459 -220.345225) (xy 366.298988 -220.319854) (xy 365.078772 -220.319854) (xy 365.078163 -220.347508)
			(xy 365.068839 -220.402026) (xy 365.06023 -220.428312) (xy 365.05261 -220.45041) (xy 365.257842 -220.805756)
			(xy 365.280702 -220.810074) (xy 365.305508 -220.815252) (xy 365.353247 -220.832242) (xy 365.397825 -220.856337)
			(xy 365.438191 -220.886969) (xy 365.473395 -220.923417) (xy 365.502606 -220.964822) (xy 365.525138 -221.01021)
			(xy 365.54046 -221.058511) (xy 365.54821 -221.108588) (xy 365.548672 -221.133924) (xy 365.548164 -221.159811)
			(xy 365.540065 -221.210949) (xy 365.524066 -221.260189) (xy 365.50056 -221.306321) (xy 365.470128 -221.348208)
			(xy 365.433518 -221.384818) (xy 365.391631 -221.41525) (xy 365.345499 -221.438756) (xy 365.296259 -221.454755)
			(xy 365.245121 -221.462854) (xy 365.193347 -221.462854) (xy 365.142209 -221.454755) (xy 365.092969 -221.438756)
			(xy 365.046837 -221.41525) (xy 365.00495 -221.384818) (xy 364.96834 -221.348208) (xy 364.937908 -221.306321)
			(xy 364.914402 -221.260189) (xy 364.898403 -221.210949) (xy 364.890304 -221.159811) (xy 364.889796 -221.133924)
			(xy 364.890332 -221.106216) (xy 364.899523 -221.051569) (xy 364.908084 -221.025212) (xy 364.915958 -221.003114)
			(xy 364.71098 -220.648022) (xy 364.68812 -220.643704) (xy 364.663279 -220.638521) (xy 364.615432 -220.621628)
			(xy 364.57074 -220.5976) (xy 364.530259 -220.567005) (xy 364.494948 -220.530566) (xy 364.465639 -220.489145)
			(xy 364.443027 -220.44372) (xy 364.427646 -220.395365) (xy 364.419859 -220.345225) (xy 364.419388 -220.319854)
			(xy 363.199172 -220.319854) (xy 363.198563 -220.347508) (xy 363.189239 -220.402026) (xy 363.18063 -220.428312)
			(xy 363.17301 -220.45041) (xy 363.378242 -220.805756) (xy 363.401102 -220.810074) (xy 363.425908 -220.815252)
			(xy 363.473647 -220.832242) (xy 363.518225 -220.856337) (xy 363.558591 -220.886969) (xy 363.593795 -220.923417)
			(xy 363.623006 -220.964822) (xy 363.645538 -221.01021) (xy 363.66086 -221.058511) (xy 363.66861 -221.108588)
			(xy 363.669072 -221.133924) (xy 363.668564 -221.159811) (xy 363.660465 -221.210949) (xy 363.644466 -221.260189)
			(xy 363.62096 -221.306321) (xy 363.590528 -221.348208) (xy 363.553918 -221.384818) (xy 363.512031 -221.41525)
			(xy 363.465899 -221.438756) (xy 363.416659 -221.454755) (xy 363.365521 -221.462854) (xy 363.313747 -221.462854)
			(xy 363.262609 -221.454755) (xy 363.213369 -221.438756) (xy 363.167237 -221.41525) (xy 363.12535 -221.384818)
			(xy 363.08874 -221.348208) (xy 363.058308 -221.306321) (xy 363.034802 -221.260189) (xy 363.018803 -221.210949)
			(xy 363.010704 -221.159811) (xy 363.010196 -221.133924) (xy 363.010732 -221.106216) (xy 363.019923 -221.051569)
			(xy 363.028484 -221.025212) (xy 363.036358 -221.003114) (xy 362.83138 -220.648022) (xy 362.80852 -220.643704)
			(xy 362.783679 -220.638521) (xy 362.735832 -220.621628) (xy 362.69114 -220.5976) (xy 362.650659 -220.567005)
			(xy 362.615348 -220.530566) (xy 362.586039 -220.489145) (xy 362.563427 -220.44372) (xy 362.548046 -220.395365)
			(xy 362.540259 -220.345225) (xy 362.539788 -220.319854) (xy 361.319572 -220.319854) (xy 361.318963 -220.347508)
			(xy 361.309639 -220.402026) (xy 361.30103 -220.428312) (xy 361.29341 -220.45041) (xy 361.498642 -220.805756)
			(xy 361.521502 -220.810074) (xy 361.546308 -220.815252) (xy 361.594047 -220.832242) (xy 361.638625 -220.856337)
			(xy 361.678991 -220.886969) (xy 361.714195 -220.923417) (xy 361.743406 -220.964822) (xy 361.765938 -221.01021)
			(xy 361.78126 -221.058511) (xy 361.78901 -221.108588) (xy 361.789472 -221.133924) (xy 361.788964 -221.159811)
			(xy 361.780865 -221.210949) (xy 361.764866 -221.260189) (xy 361.74136 -221.306321) (xy 361.710928 -221.348208)
			(xy 361.674318 -221.384818) (xy 361.632431 -221.41525) (xy 361.586299 -221.438756) (xy 361.537059 -221.454755)
			(xy 361.485921 -221.462854) (xy 361.434147 -221.462854) (xy 361.383009 -221.454755) (xy 361.333769 -221.438756)
			(xy 361.287637 -221.41525) (xy 361.24575 -221.384818) (xy 361.20914 -221.348208) (xy 361.178708 -221.306321)
			(xy 361.155202 -221.260189) (xy 361.139203 -221.210949) (xy 361.131104 -221.159811) (xy 361.130596 -221.133924)
			(xy 361.131132 -221.106216) (xy 361.140323 -221.051569) (xy 361.148884 -221.025212) (xy 361.156758 -221.003114)
			(xy 360.95178 -220.648022) (xy 360.92892 -220.643704) (xy 360.904079 -220.638521) (xy 360.856232 -220.621628)
			(xy 360.81154 -220.5976) (xy 360.771059 -220.567005) (xy 360.735748 -220.530566) (xy 360.706439 -220.489145)
			(xy 360.683827 -220.44372) (xy 360.668446 -220.395365) (xy 360.660659 -220.345225) (xy 360.660188 -220.319854)
			(xy 359.439972 -220.319854) (xy 359.439363 -220.347508) (xy 359.430039 -220.402026) (xy 359.42143 -220.428312)
			(xy 359.41381 -220.45041) (xy 359.619042 -220.805756) (xy 359.641902 -220.810074) (xy 359.666708 -220.815252)
			(xy 359.714447 -220.832242) (xy 359.759025 -220.856337) (xy 359.799391 -220.886969) (xy 359.834595 -220.923417)
			(xy 359.863806 -220.964822) (xy 359.886338 -221.01021) (xy 359.90166 -221.058511) (xy 359.90941 -221.108588)
			(xy 359.909872 -221.133924) (xy 359.909364 -221.159811) (xy 359.901265 -221.210949) (xy 359.885266 -221.260189)
			(xy 359.86176 -221.306321) (xy 359.831328 -221.348208) (xy 359.794718 -221.384818) (xy 359.752831 -221.41525)
			(xy 359.706699 -221.438756) (xy 359.657459 -221.454755) (xy 359.606321 -221.462854) (xy 359.554547 -221.462854)
			(xy 359.503409 -221.454755) (xy 359.454169 -221.438756) (xy 359.408037 -221.41525) (xy 359.36615 -221.384818)
			(xy 359.32954 -221.348208) (xy 359.299108 -221.306321) (xy 359.275602 -221.260189) (xy 359.259603 -221.210949)
			(xy 359.251504 -221.159811) (xy 359.250996 -221.133924) (xy 359.251532 -221.106216) (xy 359.260723 -221.051569)
			(xy 359.269284 -221.025212) (xy 359.277158 -221.003114) (xy 359.07218 -220.648022) (xy 359.04932 -220.643704)
			(xy 359.024479 -220.638521) (xy 358.976632 -220.621628) (xy 358.93194 -220.5976) (xy 358.891459 -220.567005)
			(xy 358.856148 -220.530566) (xy 358.826839 -220.489145) (xy 358.804227 -220.44372) (xy 358.788846 -220.395365)
			(xy 358.781059 -220.345225) (xy 358.780588 -220.319854) (xy 357.560372 -220.319854) (xy 357.559763 -220.347508)
			(xy 357.550439 -220.402026) (xy 357.54183 -220.428312) (xy 357.53421 -220.45041) (xy 357.739442 -220.805756)
			(xy 357.762302 -220.810074) (xy 357.787108 -220.815252) (xy 357.834847 -220.832242) (xy 357.879425 -220.856337)
			(xy 357.919791 -220.886969) (xy 357.954995 -220.923417) (xy 357.984206 -220.964822) (xy 358.006738 -221.01021)
			(xy 358.02206 -221.058511) (xy 358.02981 -221.108588) (xy 358.030272 -221.133924) (xy 358.029764 -221.159811)
			(xy 358.021665 -221.210949) (xy 358.005666 -221.260189) (xy 357.98216 -221.306321) (xy 357.951728 -221.348208)
			(xy 357.915118 -221.384818) (xy 357.873231 -221.41525) (xy 357.827099 -221.438756) (xy 357.777859 -221.454755)
			(xy 357.726721 -221.462854) (xy 357.674947 -221.462854) (xy 357.623809 -221.454755) (xy 357.574569 -221.438756)
			(xy 357.528437 -221.41525) (xy 357.48655 -221.384818) (xy 357.44994 -221.348208) (xy 357.419508 -221.306321)
			(xy 357.396002 -221.260189) (xy 357.380003 -221.210949) (xy 357.371904 -221.159811) (xy 357.371396 -221.133924)
			(xy 357.371932 -221.106216) (xy 357.381123 -221.051569) (xy 357.389684 -221.025212) (xy 357.397558 -221.003114)
			(xy 357.19258 -220.648022) (xy 357.16972 -220.643704) (xy 357.144879 -220.638521) (xy 357.097032 -220.621628)
			(xy 357.05234 -220.5976) (xy 357.011859 -220.567005) (xy 356.976548 -220.530566) (xy 356.947239 -220.489145)
			(xy 356.924627 -220.44372) (xy 356.909246 -220.395365) (xy 356.901459 -220.345225) (xy 356.900988 -220.319854)
			(xy 355.680772 -220.319854) (xy 355.680163 -220.347508) (xy 355.670839 -220.402026) (xy 355.66223 -220.428312)
			(xy 355.65461 -220.45041) (xy 355.859842 -220.805756) (xy 355.882702 -220.810074) (xy 355.907508 -220.815252)
			(xy 355.955247 -220.832242) (xy 355.999825 -220.856337) (xy 356.040191 -220.886969) (xy 356.075395 -220.923417)
			(xy 356.104606 -220.964822) (xy 356.127138 -221.01021) (xy 356.14246 -221.058511) (xy 356.15021 -221.108588)
			(xy 356.150672 -221.133924) (xy 356.150164 -221.159811) (xy 356.142065 -221.210949) (xy 356.126066 -221.260189)
			(xy 356.10256 -221.306321) (xy 356.072128 -221.348208) (xy 356.035518 -221.384818) (xy 355.993631 -221.41525)
			(xy 355.947499 -221.438756) (xy 355.898259 -221.454755) (xy 355.847121 -221.462854) (xy 355.795347 -221.462854)
			(xy 355.744209 -221.454755) (xy 355.694969 -221.438756) (xy 355.648837 -221.41525) (xy 355.60695 -221.384818)
			(xy 355.57034 -221.348208) (xy 355.539908 -221.306321) (xy 355.516402 -221.260189) (xy 355.500403 -221.210949)
			(xy 355.492304 -221.159811) (xy 355.491796 -221.133924) (xy 355.492332 -221.106216) (xy 355.501523 -221.051569)
			(xy 355.510084 -221.025212) (xy 355.517958 -221.003114) (xy 355.31298 -220.648022) (xy 355.29012 -220.643704)
			(xy 355.265279 -220.638521) (xy 355.217432 -220.621628) (xy 355.17274 -220.5976) (xy 355.132259 -220.567005)
			(xy 355.096948 -220.530566) (xy 355.067639 -220.489145) (xy 355.045027 -220.44372) (xy 355.029646 -220.395365)
			(xy 355.021859 -220.345225) (xy 355.021388 -220.319854) (xy 353.801172 -220.319854) (xy 353.800563 -220.347508)
			(xy 353.791239 -220.402026) (xy 353.78263 -220.428312) (xy 353.77501 -220.45041) (xy 353.980242 -220.805756)
			(xy 354.003102 -220.810074) (xy 354.027908 -220.815252) (xy 354.075647 -220.832242) (xy 354.120225 -220.856337)
			(xy 354.160591 -220.886969) (xy 354.195795 -220.923417) (xy 354.225006 -220.964822) (xy 354.247538 -221.01021)
			(xy 354.26286 -221.058511) (xy 354.27061 -221.108588) (xy 354.271072 -221.133924) (xy 354.270564 -221.159811)
			(xy 354.262465 -221.210949) (xy 354.246466 -221.260189) (xy 354.22296 -221.306321) (xy 354.192528 -221.348208)
			(xy 354.155918 -221.384818) (xy 354.114031 -221.41525) (xy 354.067899 -221.438756) (xy 354.018659 -221.454755)
			(xy 353.967521 -221.462854) (xy 353.915747 -221.462854) (xy 353.864609 -221.454755) (xy 353.815369 -221.438756)
			(xy 353.769237 -221.41525) (xy 353.72735 -221.384818) (xy 353.69074 -221.348208) (xy 353.660308 -221.306321)
			(xy 353.636802 -221.260189) (xy 353.620803 -221.210949) (xy 353.612704 -221.159811) (xy 353.612196 -221.133924)
			(xy 353.612732 -221.106216) (xy 353.621923 -221.051569) (xy 353.630484 -221.025212) (xy 353.638358 -221.003114)
			(xy 353.43338 -220.648022) (xy 353.41052 -220.643704) (xy 353.385679 -220.638521) (xy 353.337832 -220.621628)
			(xy 353.29314 -220.5976) (xy 353.252659 -220.567005) (xy 353.217348 -220.530566) (xy 353.188039 -220.489145)
			(xy 353.165427 -220.44372) (xy 353.150046 -220.395365) (xy 353.142259 -220.345225) (xy 353.141788 -220.319854)
			(xy 351.921572 -220.319854) (xy 351.921122 -220.3452) (xy 351.913342 -220.395293) (xy 351.897988 -220.443604)
			(xy 351.875422 -220.488998) (xy 351.846176 -220.530404) (xy 351.810939 -220.566847) (xy 351.77054 -220.597469)
			(xy 351.725931 -220.621548) (xy 351.678163 -220.638518) (xy 351.653348 -220.643704) (xy 351.630488 -220.648022)
			(xy 351.42551 -221.003114) (xy 351.433384 -221.024958) (xy 351.441977 -221.051373) (xy 351.451165 -221.106151)
			(xy 351.451672 -221.133924) (xy 351.451164 -221.159811) (xy 351.443065 -221.210949) (xy 351.427066 -221.260189)
			(xy 351.40356 -221.306321) (xy 351.373128 -221.348208) (xy 351.336518 -221.384818) (xy 351.294631 -221.41525)
			(xy 351.248499 -221.438756) (xy 351.199259 -221.454755) (xy 351.148121 -221.462854) (xy 351.096347 -221.462854)
			(xy 351.045209 -221.454755) (xy 350.995969 -221.438756) (xy 350.949837 -221.41525) (xy 350.90795 -221.384818)
			(xy 350.87134 -221.348208) (xy 350.840908 -221.306321) (xy 350.817402 -221.260189) (xy 350.801403 -221.210949)
			(xy 350.793304 -221.159811) (xy 350.792796 -221.133924) (xy 350.511872 -221.133924) (xy 350.511345 -221.161632)
			(xy 350.502148 -221.216279) (xy 350.493584 -221.242636) (xy 350.48571 -221.264734) (xy 350.690688 -221.619572)
			(xy 350.713548 -221.62389) (xy 350.738367 -221.629064) (xy 350.786146 -221.646018) (xy 350.830765 -221.670088)
			(xy 350.871172 -221.700708) (xy 350.906413 -221.737154) (xy 350.935657 -221.778566) (xy 350.958214 -221.823969)
			(xy 350.973552 -221.872291) (xy 350.98131 -221.922391) (xy 350.981772 -221.94774) (xy 352.201988 -221.94774)
			(xy 352.202465 -221.922395) (xy 352.210245 -221.872306) (xy 352.225597 -221.823996) (xy 352.24816 -221.778605)
			(xy 352.277403 -221.7372) (xy 352.312637 -221.700757) (xy 352.353031 -221.670134) (xy 352.397636 -221.646052)
			(xy 352.445399 -221.629078) (xy 352.470212 -221.62389) (xy 352.493072 -221.619572) (xy 352.698304 -221.264226)
			(xy 352.69043 -221.242128) (xy 352.681965 -221.215883) (xy 352.672893 -221.161495) (xy 352.672396 -221.133924)
			(xy 352.672904 -221.108037) (xy 352.681003 -221.056899) (xy 352.697002 -221.007659) (xy 352.720508 -220.961527)
			(xy 352.75094 -220.91964) (xy 352.78755 -220.88303) (xy 352.829437 -220.852598) (xy 352.875569 -220.829092)
			(xy 352.924809 -220.813093) (xy 352.975947 -220.804994) (xy 353.027721 -220.804994) (xy 353.078859 -220.813093)
			(xy 353.128099 -220.829092) (xy 353.174231 -220.852598) (xy 353.216118 -220.88303) (xy 353.252728 -220.91964)
			(xy 353.28316 -220.961527) (xy 353.306666 -221.007659) (xy 353.322665 -221.056899) (xy 353.330764 -221.108037)
			(xy 353.331272 -221.133924) (xy 353.330842 -221.1593) (xy 353.323069 -221.209454) (xy 353.307696 -221.257821)
			(xy 353.285086 -221.303259) (xy 353.255774 -221.344691) (xy 353.220455 -221.381137) (xy 353.179963 -221.411734)
			(xy 353.135258 -221.435759) (xy 353.087396 -221.452643) (xy 353.06254 -221.457774) (xy 353.03968 -221.462092)
			(xy 352.834956 -221.81693) (xy 352.84283 -221.838774) (xy 352.851486 -221.865179) (xy 352.8608 -221.919958)
			(xy 352.861372 -221.94774) (xy 354.081588 -221.94774) (xy 354.082065 -221.922395) (xy 354.089845 -221.872306)
			(xy 354.105197 -221.823996) (xy 354.12776 -221.778605) (xy 354.157003 -221.7372) (xy 354.192237 -221.700757)
			(xy 354.232631 -221.670134) (xy 354.277236 -221.646052) (xy 354.324999 -221.629078) (xy 354.349812 -221.62389)
			(xy 354.372672 -221.619572) (xy 354.577904 -221.264226) (xy 354.57003 -221.242128) (xy 354.561565 -221.215883)
			(xy 354.552493 -221.161495) (xy 354.551996 -221.133924) (xy 354.552504 -221.108037) (xy 354.560603 -221.056899)
			(xy 354.576602 -221.007659) (xy 354.600108 -220.961527) (xy 354.63054 -220.91964) (xy 354.66715 -220.88303)
			(xy 354.709037 -220.852598) (xy 354.755169 -220.829092) (xy 354.804409 -220.813093) (xy 354.855547 -220.804994)
			(xy 354.907321 -220.804994) (xy 354.958459 -220.813093) (xy 355.007699 -220.829092) (xy 355.053831 -220.852598)
			(xy 355.095718 -220.88303) (xy 355.132328 -220.91964) (xy 355.16276 -220.961527) (xy 355.186266 -221.007659)
			(xy 355.202265 -221.056899) (xy 355.210364 -221.108037) (xy 355.210872 -221.133924) (xy 355.210442 -221.1593)
			(xy 355.202669 -221.209454) (xy 355.187296 -221.257821) (xy 355.164686 -221.303259) (xy 355.135374 -221.344691)
			(xy 355.100055 -221.381137) (xy 355.059563 -221.411734) (xy 355.014858 -221.435759) (xy 354.966996 -221.452643)
			(xy 354.94214 -221.457774) (xy 354.91928 -221.462092) (xy 354.714556 -221.81693) (xy 354.72243 -221.838774)
			(xy 354.731086 -221.865179) (xy 354.7404 -221.919958) (xy 354.740972 -221.94774) (xy 355.961188 -221.94774)
			(xy 355.961665 -221.922395) (xy 355.969445 -221.872306) (xy 355.984797 -221.823996) (xy 356.00736 -221.778605)
			(xy 356.036603 -221.7372) (xy 356.071837 -221.700757) (xy 356.112231 -221.670134) (xy 356.156836 -221.646052)
			(xy 356.204599 -221.629078) (xy 356.229412 -221.62389) (xy 356.252272 -221.619572) (xy 356.457504 -221.264226)
			(xy 356.44963 -221.242128) (xy 356.441165 -221.215883) (xy 356.432093 -221.161495) (xy 356.431596 -221.133924)
			(xy 356.432104 -221.108037) (xy 356.440203 -221.056899) (xy 356.456202 -221.007659) (xy 356.479708 -220.961527)
			(xy 356.51014 -220.91964) (xy 356.54675 -220.88303) (xy 356.588637 -220.852598) (xy 356.634769 -220.829092)
			(xy 356.684009 -220.813093) (xy 356.735147 -220.804994) (xy 356.786921 -220.804994) (xy 356.838059 -220.813093)
			(xy 356.887299 -220.829092) (xy 356.933431 -220.852598) (xy 356.975318 -220.88303) (xy 357.011928 -220.91964)
			(xy 357.04236 -220.961527) (xy 357.065866 -221.007659) (xy 357.081865 -221.056899) (xy 357.089964 -221.108037)
			(xy 357.090472 -221.133924) (xy 357.090042 -221.1593) (xy 357.082269 -221.209454) (xy 357.066896 -221.257821)
			(xy 357.044286 -221.303259) (xy 357.014974 -221.344691) (xy 356.979655 -221.381137) (xy 356.939163 -221.411734)
			(xy 356.894458 -221.435759) (xy 356.846596 -221.452643) (xy 356.82174 -221.457774) (xy 356.79888 -221.462092)
			(xy 356.594156 -221.81693) (xy 356.60203 -221.838774) (xy 356.610686 -221.865179) (xy 356.62 -221.919958)
			(xy 356.620572 -221.94774) (xy 357.841296 -221.94774) (xy 357.841727 -221.922404) (xy 357.849489 -221.872329)
			(xy 357.864819 -221.824032) (xy 357.887358 -221.778648) (xy 357.916574 -221.737246) (xy 357.95178 -221.700802)
			(xy 357.992148 -221.670172) (xy 358.036725 -221.646079) (xy 358.084465 -221.629089) (xy 358.109266 -221.62389)
			(xy 358.132126 -221.619572) (xy 358.337104 -221.26448) (xy 358.329484 -221.242382) (xy 358.320964 -221.216211)
			(xy 358.311771 -221.161949) (xy 358.311196 -221.134432) (xy 358.311196 -221.133924) (xy 358.311704 -221.108037)
			(xy 358.319803 -221.056899) (xy 358.335802 -221.007659) (xy 358.359308 -220.961527) (xy 358.38974 -220.91964)
			(xy 358.42635 -220.88303) (xy 358.468237 -220.852598) (xy 358.514369 -220.829092) (xy 358.563609 -220.813093)
			(xy 358.614747 -220.804994) (xy 358.666521 -220.804994) (xy 358.717659 -220.813093) (xy 358.766899 -220.829092)
			(xy 358.813031 -220.852598) (xy 358.854918 -220.88303) (xy 358.891528 -220.91964) (xy 358.92196 -220.961527)
			(xy 358.945466 -221.007659) (xy 358.961465 -221.056899) (xy 358.969564 -221.108037) (xy 358.970072 -221.133924)
			(xy 358.969679 -221.159291) (xy 358.961926 -221.209429) (xy 358.946575 -221.257784) (xy 358.923991 -221.303213)
			(xy 358.894706 -221.344642) (xy 358.859415 -221.381089) (xy 358.818952 -221.411694) (xy 358.774274 -221.435731)
			(xy 358.726438 -221.452632) (xy 358.701594 -221.457774) (xy 358.678734 -221.462092) (xy 358.47401 -221.81693)
			(xy 358.481884 -221.838774) (xy 358.490481 -221.865188) (xy 358.499666 -221.919967) (xy 358.500172 -221.94774)
			(xy 359.720388 -221.94774) (xy 359.720865 -221.922395) (xy 359.728645 -221.872306) (xy 359.743997 -221.823996)
			(xy 359.76656 -221.778605) (xy 359.795803 -221.7372) (xy 359.831037 -221.700757) (xy 359.871431 -221.670134)
			(xy 359.916036 -221.646052) (xy 359.963799 -221.629078) (xy 359.988612 -221.62389) (xy 360.011472 -221.619572)
			(xy 360.216704 -221.264226) (xy 360.20883 -221.242128) (xy 360.200365 -221.215883) (xy 360.191293 -221.161495)
			(xy 360.190796 -221.133924) (xy 360.191304 -221.108037) (xy 360.199403 -221.056899) (xy 360.215402 -221.007659)
			(xy 360.238908 -220.961527) (xy 360.26934 -220.91964) (xy 360.30595 -220.88303) (xy 360.347837 -220.852598)
			(xy 360.393969 -220.829092) (xy 360.443209 -220.813093) (xy 360.494347 -220.804994) (xy 360.546121 -220.804994)
			(xy 360.597259 -220.813093) (xy 360.646499 -220.829092) (xy 360.692631 -220.852598) (xy 360.734518 -220.88303)
			(xy 360.771128 -220.91964) (xy 360.80156 -220.961527) (xy 360.825066 -221.007659) (xy 360.841065 -221.056899)
			(xy 360.849164 -221.108037) (xy 360.849672 -221.133924) (xy 360.849242 -221.1593) (xy 360.841469 -221.209454)
			(xy 360.826096 -221.257821) (xy 360.803486 -221.303259) (xy 360.774174 -221.344691) (xy 360.738855 -221.381137)
			(xy 360.698363 -221.411734) (xy 360.653658 -221.435759) (xy 360.605796 -221.452643) (xy 360.58094 -221.457774)
			(xy 360.55808 -221.462092) (xy 360.353356 -221.81693) (xy 360.36123 -221.838774) (xy 360.369886 -221.865179)
			(xy 360.3792 -221.919958) (xy 360.379772 -221.94774) (xy 361.600496 -221.94774) (xy 361.600927 -221.922404)
			(xy 361.608689 -221.872329) (xy 361.624019 -221.824032) (xy 361.646558 -221.778648) (xy 361.675774 -221.737246)
			(xy 361.71098 -221.700802) (xy 361.751348 -221.670172) (xy 361.795925 -221.646079) (xy 361.843665 -221.629089)
			(xy 361.868466 -221.62389) (xy 361.891326 -221.619572) (xy 362.096304 -221.26448) (xy 362.088684 -221.242382)
			(xy 362.080164 -221.216211) (xy 362.070971 -221.161949) (xy 362.070396 -221.134432) (xy 362.070396 -221.133924)
			(xy 362.070904 -221.108037) (xy 362.079003 -221.056899) (xy 362.095002 -221.007659) (xy 362.118508 -220.961527)
			(xy 362.14894 -220.91964) (xy 362.18555 -220.88303) (xy 362.227437 -220.852598) (xy 362.273569 -220.829092)
			(xy 362.322809 -220.813093) (xy 362.373947 -220.804994) (xy 362.425721 -220.804994) (xy 362.476859 -220.813093)
			(xy 362.526099 -220.829092) (xy 362.572231 -220.852598) (xy 362.614118 -220.88303) (xy 362.650728 -220.91964)
			(xy 362.68116 -220.961527) (xy 362.704666 -221.007659) (xy 362.720665 -221.056899) (xy 362.728764 -221.108037)
			(xy 362.729272 -221.133924) (xy 362.728879 -221.159291) (xy 362.721126 -221.209429) (xy 362.705775 -221.257784)
			(xy 362.683191 -221.303213) (xy 362.653906 -221.344642) (xy 362.618615 -221.381089) (xy 362.578152 -221.411694)
			(xy 362.533474 -221.435731) (xy 362.485638 -221.452632) (xy 362.460794 -221.457774) (xy 362.437934 -221.462092)
			(xy 362.23321 -221.81693) (xy 362.241084 -221.838774) (xy 362.249681 -221.865188) (xy 362.258866 -221.919967)
			(xy 362.259372 -221.94774) (xy 363.479588 -221.94774) (xy 363.480065 -221.922395) (xy 363.487845 -221.872306)
			(xy 363.503197 -221.823996) (xy 363.52576 -221.778605) (xy 363.555003 -221.7372) (xy 363.590237 -221.700757)
			(xy 363.630631 -221.670134) (xy 363.675236 -221.646052) (xy 363.722999 -221.629078) (xy 363.747812 -221.62389)
			(xy 363.770672 -221.619572) (xy 363.975904 -221.264226) (xy 363.96803 -221.242128) (xy 363.959565 -221.215883)
			(xy 363.950493 -221.161495) (xy 363.949996 -221.133924) (xy 363.950504 -221.108037) (xy 363.958603 -221.056899)
			(xy 363.974602 -221.007659) (xy 363.998108 -220.961527) (xy 364.02854 -220.91964) (xy 364.06515 -220.88303)
			(xy 364.107037 -220.852598) (xy 364.153169 -220.829092) (xy 364.202409 -220.813093) (xy 364.253547 -220.804994)
			(xy 364.305321 -220.804994) (xy 364.356459 -220.813093) (xy 364.405699 -220.829092) (xy 364.451831 -220.852598)
			(xy 364.493718 -220.88303) (xy 364.530328 -220.91964) (xy 364.56076 -220.961527) (xy 364.584266 -221.007659)
			(xy 364.600265 -221.056899) (xy 364.608364 -221.108037) (xy 364.608872 -221.133924) (xy 364.608442 -221.1593)
			(xy 364.600669 -221.209454) (xy 364.585296 -221.257821) (xy 364.562686 -221.303259) (xy 364.533374 -221.344691)
			(xy 364.498055 -221.381137) (xy 364.457563 -221.411734) (xy 364.412858 -221.435759) (xy 364.364996 -221.452643)
			(xy 364.34014 -221.457774) (xy 364.31728 -221.462092) (xy 364.112556 -221.81693) (xy 364.12043 -221.838774)
			(xy 364.129086 -221.865179) (xy 364.1384 -221.919958) (xy 364.138972 -221.94774) (xy 365.359188 -221.94774)
			(xy 365.359665 -221.922395) (xy 365.367445 -221.872306) (xy 365.382797 -221.823996) (xy 365.40536 -221.778605)
			(xy 365.434603 -221.7372) (xy 365.469837 -221.700757) (xy 365.510231 -221.670134) (xy 365.554836 -221.646052)
			(xy 365.602599 -221.629078) (xy 365.627412 -221.62389) (xy 365.650272 -221.619572) (xy 365.855504 -221.264226)
			(xy 365.84763 -221.242128) (xy 365.839165 -221.215883) (xy 365.830093 -221.161495) (xy 365.829596 -221.133924)
			(xy 365.830104 -221.108037) (xy 365.838203 -221.056899) (xy 365.854202 -221.007659) (xy 365.877708 -220.961527)
			(xy 365.90814 -220.91964) (xy 365.94475 -220.88303) (xy 365.986637 -220.852598) (xy 366.032769 -220.829092)
			(xy 366.082009 -220.813093) (xy 366.133147 -220.804994) (xy 366.184921 -220.804994) (xy 366.236059 -220.813093)
			(xy 366.285299 -220.829092) (xy 366.331431 -220.852598) (xy 366.373318 -220.88303) (xy 366.409928 -220.91964)
			(xy 366.44036 -220.961527) (xy 366.463866 -221.007659) (xy 366.479865 -221.056899) (xy 366.487964 -221.108037)
			(xy 366.488472 -221.133924) (xy 366.488042 -221.1593) (xy 366.480269 -221.209454) (xy 366.464896 -221.257821)
			(xy 366.442286 -221.303259) (xy 366.412974 -221.344691) (xy 366.377655 -221.381137) (xy 366.337163 -221.411734)
			(xy 366.292458 -221.435759) (xy 366.244596 -221.452643) (xy 366.21974 -221.457774) (xy 366.19688 -221.462092)
			(xy 365.992156 -221.81693) (xy 366.00003 -221.838774) (xy 366.008686 -221.865179) (xy 366.018 -221.919958)
			(xy 366.018572 -221.94774) (xy 369.118388 -221.94774) (xy 369.118865 -221.922395) (xy 369.126645 -221.872306)
			(xy 369.141997 -221.823996) (xy 369.16456 -221.778605) (xy 369.193803 -221.7372) (xy 369.229037 -221.700757)
			(xy 369.269431 -221.670134) (xy 369.314036 -221.646052) (xy 369.361799 -221.629078) (xy 369.386612 -221.62389)
			(xy 369.409472 -221.619572) (xy 369.614704 -221.264226) (xy 369.60683 -221.242128) (xy 369.598365 -221.215883)
			(xy 369.589293 -221.161495) (xy 369.588796 -221.133924) (xy 369.589304 -221.108037) (xy 369.597403 -221.056899)
			(xy 369.613402 -221.007659) (xy 369.636908 -220.961527) (xy 369.66734 -220.91964) (xy 369.70395 -220.88303)
			(xy 369.745837 -220.852598) (xy 369.791969 -220.829092) (xy 369.841209 -220.813093) (xy 369.892347 -220.804994)
			(xy 369.944121 -220.804994) (xy 369.995259 -220.813093) (xy 370.044499 -220.829092) (xy 370.090631 -220.852598)
			(xy 370.132518 -220.88303) (xy 370.169128 -220.91964) (xy 370.19956 -220.961527) (xy 370.223066 -221.007659)
			(xy 370.239065 -221.056899) (xy 370.247164 -221.108037) (xy 370.247672 -221.133924) (xy 370.247242 -221.1593)
			(xy 370.239469 -221.209454) (xy 370.224096 -221.257821) (xy 370.201486 -221.303259) (xy 370.172174 -221.344691)
			(xy 370.136855 -221.381137) (xy 370.096363 -221.411734) (xy 370.051658 -221.435759) (xy 370.003796 -221.452643)
			(xy 369.97894 -221.457774) (xy 369.95608 -221.462092) (xy 369.751356 -221.81693) (xy 369.75923 -221.838774)
			(xy 369.767886 -221.865179) (xy 369.7772 -221.919958) (xy 369.777772 -221.94774) (xy 370.997988 -221.94774)
			(xy 370.998465 -221.922395) (xy 371.006245 -221.872306) (xy 371.021597 -221.823996) (xy 371.04416 -221.778605)
			(xy 371.073403 -221.7372) (xy 371.108637 -221.700757) (xy 371.149031 -221.670134) (xy 371.193636 -221.646052)
			(xy 371.241399 -221.629078) (xy 371.266212 -221.62389) (xy 371.289072 -221.619572) (xy 371.494304 -221.264226)
			(xy 371.48643 -221.242128) (xy 371.477965 -221.215883) (xy 371.468893 -221.161495) (xy 371.468396 -221.133924)
			(xy 371.468904 -221.108037) (xy 371.477003 -221.056899) (xy 371.493002 -221.007659) (xy 371.516508 -220.961527)
			(xy 371.54694 -220.91964) (xy 371.58355 -220.88303) (xy 371.625437 -220.852598) (xy 371.671569 -220.829092)
			(xy 371.720809 -220.813093) (xy 371.771947 -220.804994) (xy 371.823721 -220.804994) (xy 371.874859 -220.813093)
			(xy 371.924099 -220.829092) (xy 371.970231 -220.852598) (xy 372.012118 -220.88303) (xy 372.048728 -220.91964)
			(xy 372.07916 -220.961527) (xy 372.102666 -221.007659) (xy 372.118665 -221.056899) (xy 372.126764 -221.108037)
			(xy 372.127272 -221.133924) (xy 372.126842 -221.1593) (xy 372.119069 -221.209454) (xy 372.103696 -221.257821)
			(xy 372.081086 -221.303259) (xy 372.051774 -221.344691) (xy 372.016455 -221.381137) (xy 371.975963 -221.411734)
			(xy 371.931258 -221.435759) (xy 371.883396 -221.452643) (xy 371.85854 -221.457774) (xy 371.83568 -221.462092)
			(xy 371.630956 -221.81693) (xy 371.63883 -221.838774) (xy 371.647486 -221.865179) (xy 371.6568 -221.919958)
			(xy 371.657372 -221.94774) (xy 372.877588 -221.94774) (xy 372.878065 -221.922395) (xy 372.885845 -221.872306)
			(xy 372.901197 -221.823996) (xy 372.92376 -221.778605) (xy 372.953003 -221.7372) (xy 372.988237 -221.700757)
			(xy 373.028631 -221.670134) (xy 373.073236 -221.646052) (xy 373.120999 -221.629078) (xy 373.145812 -221.62389)
			(xy 373.168672 -221.619572) (xy 373.373904 -221.264226) (xy 373.36603 -221.242128) (xy 373.357565 -221.215883)
			(xy 373.348493 -221.161495) (xy 373.347996 -221.133924) (xy 373.348504 -221.108037) (xy 373.356603 -221.056899)
			(xy 373.372602 -221.007659) (xy 373.396108 -220.961527) (xy 373.42654 -220.91964) (xy 373.46315 -220.88303)
			(xy 373.505037 -220.852598) (xy 373.551169 -220.829092) (xy 373.600409 -220.813093) (xy 373.651547 -220.804994)
			(xy 373.703321 -220.804994) (xy 373.754459 -220.813093) (xy 373.803699 -220.829092) (xy 373.849831 -220.852598)
			(xy 373.891718 -220.88303) (xy 373.928328 -220.91964) (xy 373.95876 -220.961527) (xy 373.982266 -221.007659)
			(xy 373.998265 -221.056899) (xy 374.006364 -221.108037) (xy 374.006872 -221.133924) (xy 374.006442 -221.1593)
			(xy 373.998669 -221.209454) (xy 373.983296 -221.257821) (xy 373.960686 -221.303259) (xy 373.931374 -221.344691)
			(xy 373.896055 -221.381137) (xy 373.855563 -221.411734) (xy 373.810858 -221.435759) (xy 373.762996 -221.452643)
			(xy 373.73814 -221.457774) (xy 373.71528 -221.462092) (xy 373.510556 -221.81693) (xy 373.51843 -221.838774)
			(xy 373.527086 -221.865179) (xy 373.5364 -221.919958) (xy 373.536972 -221.94774) (xy 374.757188 -221.94774)
			(xy 374.757665 -221.922395) (xy 374.765445 -221.872306) (xy 374.780797 -221.823996) (xy 374.80336 -221.778605)
			(xy 374.832603 -221.7372) (xy 374.867837 -221.700757) (xy 374.908231 -221.670134) (xy 374.952836 -221.646052)
			(xy 375.000599 -221.629078) (xy 375.025412 -221.62389) (xy 375.048272 -221.619572) (xy 375.253504 -221.264226)
			(xy 375.24563 -221.242128) (xy 375.237165 -221.215883) (xy 375.228093 -221.161495) (xy 375.227596 -221.133924)
			(xy 375.228104 -221.108037) (xy 375.236203 -221.056899) (xy 375.252202 -221.007659) (xy 375.275708 -220.961527)
			(xy 375.30614 -220.91964) (xy 375.34275 -220.88303) (xy 375.384637 -220.852598) (xy 375.430769 -220.829092)
			(xy 375.480009 -220.813093) (xy 375.531147 -220.804994) (xy 375.582921 -220.804994) (xy 375.634059 -220.813093)
			(xy 375.683299 -220.829092) (xy 375.729431 -220.852598) (xy 375.771318 -220.88303) (xy 375.807928 -220.91964)
			(xy 375.83836 -220.961527) (xy 375.861866 -221.007659) (xy 375.877865 -221.056899) (xy 375.885964 -221.108037)
			(xy 375.886472 -221.133924) (xy 375.886042 -221.1593) (xy 375.878269 -221.209454) (xy 375.862896 -221.257821)
			(xy 375.840286 -221.303259) (xy 375.810974 -221.344691) (xy 375.775655 -221.381137) (xy 375.735163 -221.411734)
			(xy 375.690458 -221.435759) (xy 375.642596 -221.452643) (xy 375.61774 -221.457774) (xy 375.59488 -221.462092)
			(xy 375.390156 -221.81693) (xy 375.39803 -221.838774) (xy 375.406686 -221.865179) (xy 375.416 -221.919958)
			(xy 375.416572 -221.94774) (xy 376.636788 -221.94774) (xy 376.637265 -221.922395) (xy 376.645045 -221.872306)
			(xy 376.660397 -221.823996) (xy 376.68296 -221.778605) (xy 376.712203 -221.7372) (xy 376.747437 -221.700757)
			(xy 376.787831 -221.670134) (xy 376.832436 -221.646052) (xy 376.880199 -221.629078) (xy 376.905012 -221.62389)
			(xy 376.927872 -221.619572) (xy 377.133104 -221.264226) (xy 377.12523 -221.242128) (xy 377.116765 -221.215883)
			(xy 377.107693 -221.161495) (xy 377.107196 -221.133924) (xy 377.107704 -221.108037) (xy 377.115803 -221.056899)
			(xy 377.131802 -221.007659) (xy 377.155308 -220.961527) (xy 377.18574 -220.91964) (xy 377.22235 -220.88303)
			(xy 377.264237 -220.852598) (xy 377.310369 -220.829092) (xy 377.359609 -220.813093) (xy 377.410747 -220.804994)
			(xy 377.462521 -220.804994) (xy 377.513659 -220.813093) (xy 377.562899 -220.829092) (xy 377.609031 -220.852598)
			(xy 377.650918 -220.88303) (xy 377.687528 -220.91964) (xy 377.71796 -220.961527) (xy 377.741466 -221.007659)
			(xy 377.757465 -221.056899) (xy 377.765564 -221.108037) (xy 377.766072 -221.133924) (xy 377.765642 -221.1593)
			(xy 377.757869 -221.209454) (xy 377.742496 -221.257821) (xy 377.719886 -221.303259) (xy 377.690574 -221.344691)
			(xy 377.655255 -221.381137) (xy 377.614763 -221.411734) (xy 377.570058 -221.435759) (xy 377.522196 -221.452643)
			(xy 377.49734 -221.457774) (xy 377.47448 -221.462092) (xy 377.269756 -221.81693) (xy 377.27763 -221.838774)
			(xy 377.286286 -221.865179) (xy 377.2956 -221.919958) (xy 377.296172 -221.94774) (xy 378.516388 -221.94774)
			(xy 378.516865 -221.922395) (xy 378.524645 -221.872306) (xy 378.539997 -221.823996) (xy 378.56256 -221.778605)
			(xy 378.591803 -221.7372) (xy 378.627037 -221.700757) (xy 378.667431 -221.670134) (xy 378.712036 -221.646052)
			(xy 378.759799 -221.629078) (xy 378.784612 -221.62389) (xy 378.807472 -221.619572) (xy 379.012704 -221.264226)
			(xy 379.00483 -221.242128) (xy 378.996365 -221.215883) (xy 378.987293 -221.161495) (xy 378.986796 -221.133924)
			(xy 378.987304 -221.108037) (xy 378.995403 -221.056899) (xy 379.011402 -221.007659) (xy 379.034908 -220.961527)
			(xy 379.06534 -220.91964) (xy 379.10195 -220.88303) (xy 379.143837 -220.852598) (xy 379.189969 -220.829092)
			(xy 379.239209 -220.813093) (xy 379.290347 -220.804994) (xy 379.342121 -220.804994) (xy 379.393259 -220.813093)
			(xy 379.442499 -220.829092) (xy 379.488631 -220.852598) (xy 379.530518 -220.88303) (xy 379.567128 -220.91964)
			(xy 379.59756 -220.961527) (xy 379.621066 -221.007659) (xy 379.637065 -221.056899) (xy 379.645164 -221.108037)
			(xy 379.645672 -221.133924) (xy 379.645242 -221.1593) (xy 379.637469 -221.209454) (xy 379.622096 -221.257821)
			(xy 379.599486 -221.303259) (xy 379.570174 -221.344691) (xy 379.534855 -221.381137) (xy 379.494363 -221.411734)
			(xy 379.449658 -221.435759) (xy 379.401796 -221.452643) (xy 379.37694 -221.457774) (xy 379.35408 -221.462092)
			(xy 379.149356 -221.81693) (xy 379.15723 -221.838774) (xy 379.165886 -221.865179) (xy 379.1752 -221.919958)
			(xy 379.175772 -221.94774) (xy 380.395988 -221.94774) (xy 380.396465 -221.922395) (xy 380.404245 -221.872306)
			(xy 380.419597 -221.823996) (xy 380.44216 -221.778605) (xy 380.471403 -221.7372) (xy 380.506637 -221.700757)
			(xy 380.547031 -221.670134) (xy 380.591636 -221.646052) (xy 380.639399 -221.629078) (xy 380.664212 -221.62389)
			(xy 380.687072 -221.619572) (xy 380.89205 -221.263972) (xy 380.88443 -221.242128) (xy 380.875981 -221.215945)
			(xy 380.866909 -221.161685) (xy 380.866396 -221.134178) (xy 380.866396 -221.133924) (xy 380.866904 -221.108037)
			(xy 380.875003 -221.056899) (xy 380.891002 -221.007659) (xy 380.914508 -220.961527) (xy 380.94494 -220.91964)
			(xy 380.98155 -220.88303) (xy 381.023437 -220.852598) (xy 381.069569 -220.829092) (xy 381.118809 -220.813093)
			(xy 381.169947 -220.804994) (xy 381.221721 -220.804994) (xy 381.272859 -220.813093) (xy 381.322099 -220.829092)
			(xy 381.368231 -220.852598) (xy 381.410118 -220.88303) (xy 381.446728 -220.91964) (xy 381.47716 -220.961527)
			(xy 381.500666 -221.007659) (xy 381.516665 -221.056899) (xy 381.524764 -221.108037) (xy 381.525272 -221.133924)
			(xy 381.524879 -221.159291) (xy 381.517126 -221.209429) (xy 381.501775 -221.257784) (xy 381.479191 -221.303213)
			(xy 381.449906 -221.344642) (xy 381.414615 -221.381089) (xy 381.374152 -221.411694) (xy 381.329474 -221.435731)
			(xy 381.281638 -221.452632) (xy 381.256794 -221.457774) (xy 381.233934 -221.462092) (xy 381.02921 -221.81693)
			(xy 381.03683 -221.838774) (xy 381.045444 -221.865059) (xy 381.054766 -221.919578) (xy 381.055372 -221.947232)
			(xy 381.055372 -221.94774) (xy 382.275588 -221.94774) (xy 382.276065 -221.922395) (xy 382.283845 -221.872306)
			(xy 382.299197 -221.823996) (xy 382.32176 -221.778605) (xy 382.351003 -221.7372) (xy 382.386237 -221.700757)
			(xy 382.426631 -221.670134) (xy 382.471236 -221.646052) (xy 382.518999 -221.629078) (xy 382.543812 -221.62389)
			(xy 382.566672 -221.619572) (xy 382.77165 -221.263972) (xy 382.76403 -221.242128) (xy 382.755581 -221.215945)
			(xy 382.746509 -221.161685) (xy 382.745996 -221.134178) (xy 382.745996 -221.133924) (xy 382.746504 -221.108037)
			(xy 382.754603 -221.056899) (xy 382.770602 -221.007659) (xy 382.794108 -220.961527) (xy 382.82454 -220.91964)
			(xy 382.86115 -220.88303) (xy 382.903037 -220.852598) (xy 382.949169 -220.829092) (xy 382.998409 -220.813093)
			(xy 383.049547 -220.804994) (xy 383.101321 -220.804994) (xy 383.152459 -220.813093) (xy 383.201699 -220.829092)
			(xy 383.247831 -220.852598) (xy 383.289718 -220.88303) (xy 383.326328 -220.91964) (xy 383.35676 -220.961527)
			(xy 383.380266 -221.007659) (xy 383.396265 -221.056899) (xy 383.404364 -221.108037) (xy 383.404872 -221.133924)
			(xy 383.404479 -221.159291) (xy 383.396726 -221.209429) (xy 383.381375 -221.257784) (xy 383.358791 -221.303213)
			(xy 383.329506 -221.344642) (xy 383.294215 -221.381089) (xy 383.253752 -221.411694) (xy 383.209074 -221.435731)
			(xy 383.161238 -221.452632) (xy 383.136394 -221.457774) (xy 383.113534 -221.462092) (xy 382.90881 -221.81693)
			(xy 382.91643 -221.838774) (xy 382.925044 -221.865059) (xy 382.934366 -221.919578) (xy 382.934972 -221.947232)
			(xy 382.934972 -221.94774) (xy 382.934464 -221.973647) (xy 382.926358 -222.024824) (xy 382.910346 -222.074103)
			(xy 382.886823 -222.12027) (xy 382.856367 -222.162189) (xy 382.819729 -222.198827) (xy 382.77781 -222.229283)
			(xy 382.731643 -222.252806) (xy 382.682364 -222.268818) (xy 382.631187 -222.276924) (xy 382.579373 -222.276924)
			(xy 382.528196 -222.268818) (xy 382.478917 -222.252806) (xy 382.43275 -222.229283) (xy 382.390831 -222.198827)
			(xy 382.354193 -222.162189) (xy 382.323737 -222.12027) (xy 382.300214 -222.074103) (xy 382.284202 -222.024824)
			(xy 382.276096 -221.973647) (xy 382.275588 -221.94774) (xy 381.055372 -221.94774) (xy 381.054864 -221.973647)
			(xy 381.046758 -222.024824) (xy 381.030746 -222.074103) (xy 381.007223 -222.12027) (xy 380.976767 -222.162189)
			(xy 380.940129 -222.198827) (xy 380.89821 -222.229283) (xy 380.852043 -222.252806) (xy 380.802764 -222.268818)
			(xy 380.751587 -222.276924) (xy 380.699773 -222.276924) (xy 380.648596 -222.268818) (xy 380.599317 -222.252806)
			(xy 380.55315 -222.229283) (xy 380.511231 -222.198827) (xy 380.474593 -222.162189) (xy 380.444137 -222.12027)
			(xy 380.420614 -222.074103) (xy 380.404602 -222.024824) (xy 380.396496 -221.973647) (xy 380.395988 -221.94774)
			(xy 379.175772 -221.94774) (xy 379.175264 -221.973647) (xy 379.167158 -222.024824) (xy 379.151146 -222.074103)
			(xy 379.127623 -222.12027) (xy 379.097167 -222.162189) (xy 379.060529 -222.198827) (xy 379.01861 -222.229283)
			(xy 378.972443 -222.252806) (xy 378.923164 -222.268818) (xy 378.871987 -222.276924) (xy 378.820173 -222.276924)
			(xy 378.768996 -222.268818) (xy 378.719717 -222.252806) (xy 378.67355 -222.229283) (xy 378.631631 -222.198827)
			(xy 378.594993 -222.162189) (xy 378.564537 -222.12027) (xy 378.541014 -222.074103) (xy 378.525002 -222.024824)
			(xy 378.516896 -221.973647) (xy 378.516388 -221.94774) (xy 377.296172 -221.94774) (xy 377.295664 -221.973647)
			(xy 377.287558 -222.024824) (xy 377.271546 -222.074103) (xy 377.248023 -222.12027) (xy 377.217567 -222.162189)
			(xy 377.180929 -222.198827) (xy 377.13901 -222.229283) (xy 377.092843 -222.252806) (xy 377.043564 -222.268818)
			(xy 376.992387 -222.276924) (xy 376.940573 -222.276924) (xy 376.889396 -222.268818) (xy 376.840117 -222.252806)
			(xy 376.79395 -222.229283) (xy 376.752031 -222.198827) (xy 376.715393 -222.162189) (xy 376.684937 -222.12027)
			(xy 376.661414 -222.074103) (xy 376.645402 -222.024824) (xy 376.637296 -221.973647) (xy 376.636788 -221.94774)
			(xy 375.416572 -221.94774) (xy 375.416064 -221.973647) (xy 375.407958 -222.024824) (xy 375.391946 -222.074103)
			(xy 375.368423 -222.12027) (xy 375.337967 -222.162189) (xy 375.301329 -222.198827) (xy 375.25941 -222.229283)
			(xy 375.213243 -222.252806) (xy 375.163964 -222.268818) (xy 375.112787 -222.276924) (xy 375.060973 -222.276924)
			(xy 375.009796 -222.268818) (xy 374.960517 -222.252806) (xy 374.91435 -222.229283) (xy 374.872431 -222.198827)
			(xy 374.835793 -222.162189) (xy 374.805337 -222.12027) (xy 374.781814 -222.074103) (xy 374.765802 -222.024824)
			(xy 374.757696 -221.973647) (xy 374.757188 -221.94774) (xy 373.536972 -221.94774) (xy 373.536464 -221.973647)
			(xy 373.528358 -222.024824) (xy 373.512346 -222.074103) (xy 373.488823 -222.12027) (xy 373.458367 -222.162189)
			(xy 373.421729 -222.198827) (xy 373.37981 -222.229283) (xy 373.333643 -222.252806) (xy 373.284364 -222.268818)
			(xy 373.233187 -222.276924) (xy 373.181373 -222.276924) (xy 373.130196 -222.268818) (xy 373.080917 -222.252806)
			(xy 373.03475 -222.229283) (xy 372.992831 -222.198827) (xy 372.956193 -222.162189) (xy 372.925737 -222.12027)
			(xy 372.902214 -222.074103) (xy 372.886202 -222.024824) (xy 372.878096 -221.973647) (xy 372.877588 -221.94774)
			(xy 371.657372 -221.94774) (xy 371.656864 -221.973647) (xy 371.648758 -222.024824) (xy 371.632746 -222.074103)
			(xy 371.609223 -222.12027) (xy 371.578767 -222.162189) (xy 371.542129 -222.198827) (xy 371.50021 -222.229283)
			(xy 371.454043 -222.252806) (xy 371.404764 -222.268818) (xy 371.353587 -222.276924) (xy 371.301773 -222.276924)
			(xy 371.250596 -222.268818) (xy 371.201317 -222.252806) (xy 371.15515 -222.229283) (xy 371.113231 -222.198827)
			(xy 371.076593 -222.162189) (xy 371.046137 -222.12027) (xy 371.022614 -222.074103) (xy 371.006602 -222.024824)
			(xy 370.998496 -221.973647) (xy 370.997988 -221.94774) (xy 369.777772 -221.94774) (xy 369.777264 -221.973647)
			(xy 369.769158 -222.024824) (xy 369.753146 -222.074103) (xy 369.729623 -222.12027) (xy 369.699167 -222.162189)
			(xy 369.662529 -222.198827) (xy 369.62061 -222.229283) (xy 369.574443 -222.252806) (xy 369.525164 -222.268818)
			(xy 369.473987 -222.276924) (xy 369.422173 -222.276924) (xy 369.370996 -222.268818) (xy 369.321717 -222.252806)
			(xy 369.27555 -222.229283) (xy 369.233631 -222.198827) (xy 369.196993 -222.162189) (xy 369.166537 -222.12027)
			(xy 369.143014 -222.074103) (xy 369.127002 -222.024824) (xy 369.118896 -221.973647) (xy 369.118388 -221.94774)
			(xy 366.018572 -221.94774) (xy 366.018064 -221.973647) (xy 366.009958 -222.024824) (xy 365.993946 -222.074103)
			(xy 365.970423 -222.12027) (xy 365.939967 -222.162189) (xy 365.903329 -222.198827) (xy 365.86141 -222.229283)
			(xy 365.815243 -222.252806) (xy 365.765964 -222.268818) (xy 365.714787 -222.276924) (xy 365.662973 -222.276924)
			(xy 365.611796 -222.268818) (xy 365.562517 -222.252806) (xy 365.51635 -222.229283) (xy 365.474431 -222.198827)
			(xy 365.437793 -222.162189) (xy 365.407337 -222.12027) (xy 365.383814 -222.074103) (xy 365.367802 -222.024824)
			(xy 365.359696 -221.973647) (xy 365.359188 -221.94774) (xy 364.138972 -221.94774) (xy 364.138464 -221.973647)
			(xy 364.130358 -222.024824) (xy 364.114346 -222.074103) (xy 364.090823 -222.12027) (xy 364.060367 -222.162189)
			(xy 364.023729 -222.198827) (xy 363.98181 -222.229283) (xy 363.935643 -222.252806) (xy 363.886364 -222.268818)
			(xy 363.835187 -222.276924) (xy 363.783373 -222.276924) (xy 363.732196 -222.268818) (xy 363.682917 -222.252806)
			(xy 363.63675 -222.229283) (xy 363.594831 -222.198827) (xy 363.558193 -222.162189) (xy 363.527737 -222.12027)
			(xy 363.504214 -222.074103) (xy 363.488202 -222.024824) (xy 363.480096 -221.973647) (xy 363.479588 -221.94774)
			(xy 362.259372 -221.94774) (xy 362.258864 -221.973627) (xy 362.250765 -222.024765) (xy 362.234766 -222.074005)
			(xy 362.21126 -222.120137) (xy 362.180828 -222.162024) (xy 362.144218 -222.198634) (xy 362.102331 -222.229066)
			(xy 362.056199 -222.252572) (xy 362.006959 -222.268571) (xy 361.955821 -222.27667) (xy 361.904047 -222.27667)
			(xy 361.852909 -222.268571) (xy 361.803669 -222.252572) (xy 361.757537 -222.229066) (xy 361.71565 -222.198634)
			(xy 361.67904 -222.162024) (xy 361.648608 -222.120137) (xy 361.625102 -222.074005) (xy 361.609103 -222.024765)
			(xy 361.601004 -221.973627) (xy 361.600496 -221.94774) (xy 360.379772 -221.94774) (xy 360.379264 -221.973647)
			(xy 360.371158 -222.024824) (xy 360.355146 -222.074103) (xy 360.331623 -222.12027) (xy 360.301167 -222.162189)
			(xy 360.264529 -222.198827) (xy 360.22261 -222.229283) (xy 360.176443 -222.252806) (xy 360.127164 -222.268818)
			(xy 360.075987 -222.276924) (xy 360.024173 -222.276924) (xy 359.972996 -222.268818) (xy 359.923717 -222.252806)
			(xy 359.87755 -222.229283) (xy 359.835631 -222.198827) (xy 359.798993 -222.162189) (xy 359.768537 -222.12027)
			(xy 359.745014 -222.074103) (xy 359.729002 -222.024824) (xy 359.720896 -221.973647) (xy 359.720388 -221.94774)
			(xy 358.500172 -221.94774) (xy 358.499664 -221.973627) (xy 358.491565 -222.024765) (xy 358.475566 -222.074005)
			(xy 358.45206 -222.120137) (xy 358.421628 -222.162024) (xy 358.385018 -222.198634) (xy 358.343131 -222.229066)
			(xy 358.296999 -222.252572) (xy 358.247759 -222.268571) (xy 358.196621 -222.27667) (xy 358.144847 -222.27667)
			(xy 358.093709 -222.268571) (xy 358.044469 -222.252572) (xy 357.998337 -222.229066) (xy 357.95645 -222.198634)
			(xy 357.91984 -222.162024) (xy 357.889408 -222.120137) (xy 357.865902 -222.074005) (xy 357.849903 -222.024765)
			(xy 357.841804 -221.973627) (xy 357.841296 -221.94774) (xy 356.620572 -221.94774) (xy 356.620064 -221.973647)
			(xy 356.611958 -222.024824) (xy 356.595946 -222.074103) (xy 356.572423 -222.12027) (xy 356.541967 -222.162189)
			(xy 356.505329 -222.198827) (xy 356.46341 -222.229283) (xy 356.417243 -222.252806) (xy 356.367964 -222.268818)
			(xy 356.316787 -222.276924) (xy 356.264973 -222.276924) (xy 356.213796 -222.268818) (xy 356.164517 -222.252806)
			(xy 356.11835 -222.229283) (xy 356.076431 -222.198827) (xy 356.039793 -222.162189) (xy 356.009337 -222.12027)
			(xy 355.985814 -222.074103) (xy 355.969802 -222.024824) (xy 355.961696 -221.973647) (xy 355.961188 -221.94774)
			(xy 354.740972 -221.94774) (xy 354.740464 -221.973647) (xy 354.732358 -222.024824) (xy 354.716346 -222.074103)
			(xy 354.692823 -222.12027) (xy 354.662367 -222.162189) (xy 354.625729 -222.198827) (xy 354.58381 -222.229283)
			(xy 354.537643 -222.252806) (xy 354.488364 -222.268818) (xy 354.437187 -222.276924) (xy 354.385373 -222.276924)
			(xy 354.334196 -222.268818) (xy 354.284917 -222.252806) (xy 354.23875 -222.229283) (xy 354.196831 -222.198827)
			(xy 354.160193 -222.162189) (xy 354.129737 -222.12027) (xy 354.106214 -222.074103) (xy 354.090202 -222.024824)
			(xy 354.082096 -221.973647) (xy 354.081588 -221.94774) (xy 352.861372 -221.94774) (xy 352.860864 -221.973647)
			(xy 352.852758 -222.024824) (xy 352.836746 -222.074103) (xy 352.813223 -222.12027) (xy 352.782767 -222.162189)
			(xy 352.746129 -222.198827) (xy 352.70421 -222.229283) (xy 352.658043 -222.252806) (xy 352.608764 -222.268818)
			(xy 352.557587 -222.276924) (xy 352.505773 -222.276924) (xy 352.454596 -222.268818) (xy 352.405317 -222.252806)
			(xy 352.35915 -222.229283) (xy 352.317231 -222.198827) (xy 352.280593 -222.162189) (xy 352.250137 -222.12027)
			(xy 352.226614 -222.074103) (xy 352.210602 -222.024824) (xy 352.202496 -221.973647) (xy 352.201988 -221.94774)
			(xy 350.981772 -221.94774) (xy 350.981264 -221.973647) (xy 350.973158 -222.024824) (xy 350.957146 -222.074103)
			(xy 350.933623 -222.12027) (xy 350.903167 -222.162189) (xy 350.866529 -222.198827) (xy 350.82461 -222.229283)
			(xy 350.778443 -222.252806) (xy 350.729164 -222.268818) (xy 350.677987 -222.276924) (xy 350.626173 -222.276924)
			(xy 350.574996 -222.268818) (xy 350.525717 -222.252806) (xy 350.47955 -222.229283) (xy 350.437631 -222.198827)
			(xy 350.400993 -222.162189) (xy 350.370537 -222.12027) (xy 350.347014 -222.074103) (xy 350.331002 -222.024824)
			(xy 350.322896 -221.973647) (xy 350.322388 -221.94774) (xy 350.322992 -221.920023) (xy 350.332309 -221.865377)
			(xy 350.34093 -221.839028) (xy 350.348804 -221.81693) (xy 350.143826 -221.462092) (xy 350.120966 -221.457774)
			(xy 350.096166 -221.452574) (xy 350.04843 -221.435583) (xy 350.003855 -221.411489) (xy 349.963491 -221.380859)
			(xy 349.928289 -221.344414) (xy 349.899076 -221.303012) (xy 349.876542 -221.257629) (xy 349.861217 -221.209332)
			(xy 349.853461 -221.159259) (xy 349.852996 -221.133924) (xy 349.572072 -221.133924) (xy 349.571564 -221.159811)
			(xy 349.563465 -221.210949) (xy 349.547466 -221.260189) (xy 349.52396 -221.306321) (xy 349.493528 -221.348208)
			(xy 349.456918 -221.384818) (xy 349.415031 -221.41525) (xy 349.368899 -221.438756) (xy 349.319659 -221.454755)
			(xy 349.268521 -221.462854) (xy 349.216747 -221.462854) (xy 349.165609 -221.454755) (xy 349.116369 -221.438756)
			(xy 349.070237 -221.41525) (xy 349.02835 -221.384818) (xy 348.99174 -221.348208) (xy 348.961308 -221.306321)
			(xy 348.937802 -221.260189) (xy 348.921803 -221.210949) (xy 348.913704 -221.159811) (xy 348.913196 -221.133924)
			(xy 348.632272 -221.133924) (xy 348.631745 -221.161632) (xy 348.622548 -221.216279) (xy 348.613984 -221.242636)
			(xy 348.60611 -221.264734) (xy 348.811088 -221.619572) (xy 348.833948 -221.62389) (xy 348.858767 -221.629064)
			(xy 348.906546 -221.646018) (xy 348.951165 -221.670088) (xy 348.991572 -221.700708) (xy 349.026813 -221.737154)
			(xy 349.056057 -221.778566) (xy 349.078614 -221.823969) (xy 349.093952 -221.872291) (xy 349.10171 -221.922391)
			(xy 349.102172 -221.94774) (xy 349.101664 -221.973647) (xy 349.093558 -222.024824) (xy 349.077546 -222.074103)
			(xy 349.054023 -222.12027) (xy 349.023567 -222.162189) (xy 348.986929 -222.198827) (xy 348.94501 -222.229283)
			(xy 348.898843 -222.252806) (xy 348.849564 -222.268818) (xy 348.798387 -222.276924) (xy 348.746573 -222.276924)
			(xy 348.695396 -222.268818) (xy 348.646117 -222.252806) (xy 348.59995 -222.229283) (xy 348.558031 -222.198827)
			(xy 348.521393 -222.162189) (xy 348.490937 -222.12027) (xy 348.467414 -222.074103) (xy 348.451402 -222.024824)
			(xy 348.443296 -221.973647) (xy 348.442788 -221.94774) (xy 348.443392 -221.920023) (xy 348.452709 -221.865377)
			(xy 348.46133 -221.839028) (xy 348.469204 -221.81693) (xy 348.264226 -221.462092) (xy 348.241366 -221.457774)
			(xy 348.216566 -221.452574) (xy 348.16883 -221.435583) (xy 348.124255 -221.411489) (xy 348.083891 -221.380859)
			(xy 348.048689 -221.344414) (xy 348.019476 -221.303012) (xy 347.996942 -221.257629) (xy 347.981617 -221.209332)
			(xy 347.973861 -221.159259) (xy 347.973396 -221.133924) (xy 347.692472 -221.133924) (xy 347.691964 -221.159811)
			(xy 347.683865 -221.210949) (xy 347.667866 -221.260189) (xy 347.64436 -221.306321) (xy 347.613928 -221.348208)
			(xy 347.577318 -221.384818) (xy 347.535431 -221.41525) (xy 347.489299 -221.438756) (xy 347.440059 -221.454755)
			(xy 347.388921 -221.462854) (xy 347.337147 -221.462854) (xy 347.286009 -221.454755) (xy 347.236769 -221.438756)
			(xy 347.190637 -221.41525) (xy 347.14875 -221.384818) (xy 347.11214 -221.348208) (xy 347.081708 -221.306321)
			(xy 347.058202 -221.260189) (xy 347.042203 -221.210949) (xy 347.034104 -221.159811) (xy 347.033596 -221.133924)
			(xy 346.752672 -221.133924) (xy 346.752145 -221.161632) (xy 346.742948 -221.216279) (xy 346.734384 -221.242636)
			(xy 346.72651 -221.264734) (xy 346.931488 -221.619572) (xy 346.954348 -221.62389) (xy 346.979167 -221.629064)
			(xy 347.026946 -221.646018) (xy 347.071565 -221.670088) (xy 347.111972 -221.700708) (xy 347.147213 -221.737154)
			(xy 347.176457 -221.778566) (xy 347.199014 -221.823969) (xy 347.214352 -221.872291) (xy 347.22211 -221.922391)
			(xy 347.222572 -221.94774) (xy 347.222064 -221.973647) (xy 347.213958 -222.024824) (xy 347.197946 -222.074103)
			(xy 347.174423 -222.12027) (xy 347.143967 -222.162189) (xy 347.107329 -222.198827) (xy 347.06541 -222.229283)
			(xy 347.019243 -222.252806) (xy 346.969964 -222.268818) (xy 346.918787 -222.276924) (xy 346.866973 -222.276924)
			(xy 346.815796 -222.268818) (xy 346.766517 -222.252806) (xy 346.72035 -222.229283) (xy 346.678431 -222.198827)
			(xy 346.641793 -222.162189) (xy 346.611337 -222.12027) (xy 346.587814 -222.074103) (xy 346.571802 -222.024824)
			(xy 346.563696 -221.973647) (xy 346.563188 -221.94774) (xy 346.563792 -221.920023) (xy 346.573109 -221.865377)
			(xy 346.58173 -221.839028) (xy 346.589604 -221.81693) (xy 346.384626 -221.462092) (xy 346.361766 -221.457774)
			(xy 346.336966 -221.452574) (xy 346.28923 -221.435583) (xy 346.244655 -221.411489) (xy 346.204291 -221.380859)
			(xy 346.169089 -221.344414) (xy 346.139876 -221.303012) (xy 346.117342 -221.257629) (xy 346.102017 -221.209332)
			(xy 346.094261 -221.159259) (xy 346.093796 -221.133924) (xy 345.812872 -221.133924) (xy 345.812364 -221.159811)
			(xy 345.804265 -221.210949) (xy 345.788266 -221.260189) (xy 345.76476 -221.306321) (xy 345.734328 -221.348208)
			(xy 345.697718 -221.384818) (xy 345.655831 -221.41525) (xy 345.609699 -221.438756) (xy 345.560459 -221.454755)
			(xy 345.509321 -221.462854) (xy 345.457547 -221.462854) (xy 345.406409 -221.454755) (xy 345.357169 -221.438756)
			(xy 345.311037 -221.41525) (xy 345.26915 -221.384818) (xy 345.23254 -221.348208) (xy 345.202108 -221.306321)
			(xy 345.178602 -221.260189) (xy 345.162603 -221.210949) (xy 345.154504 -221.159811) (xy 345.153996 -221.133924)
			(xy 344.873072 -221.133924) (xy 344.872545 -221.161632) (xy 344.863348 -221.216279) (xy 344.854784 -221.242636)
			(xy 344.84691 -221.264734) (xy 345.051888 -221.619572) (xy 345.074748 -221.62389) (xy 345.099567 -221.629064)
			(xy 345.147346 -221.646018) (xy 345.191965 -221.670088) (xy 345.232372 -221.700708) (xy 345.267613 -221.737154)
			(xy 345.296857 -221.778566) (xy 345.319414 -221.823969) (xy 345.334752 -221.872291) (xy 345.34251 -221.922391)
			(xy 345.342972 -221.94774) (xy 345.342464 -221.973647) (xy 345.334358 -222.024824) (xy 345.318346 -222.074103)
			(xy 345.294823 -222.12027) (xy 345.264367 -222.162189) (xy 345.227729 -222.198827) (xy 345.18581 -222.229283)
			(xy 345.139643 -222.252806) (xy 345.090364 -222.268818) (xy 345.039187 -222.276924) (xy 344.987373 -222.276924)
			(xy 344.936196 -222.268818) (xy 344.886917 -222.252806) (xy 344.84075 -222.229283) (xy 344.798831 -222.198827)
			(xy 344.762193 -222.162189) (xy 344.731737 -222.12027) (xy 344.708214 -222.074103) (xy 344.692202 -222.024824)
			(xy 344.684096 -221.973647) (xy 344.683588 -221.94774) (xy 344.684192 -221.920023) (xy 344.693509 -221.865377)
			(xy 344.70213 -221.839028) (xy 344.710004 -221.81693) (xy 344.505026 -221.462092) (xy 344.482166 -221.457774)
			(xy 344.457366 -221.452574) (xy 344.40963 -221.435583) (xy 344.365055 -221.411489) (xy 344.324691 -221.380859)
			(xy 344.289489 -221.344414) (xy 344.260276 -221.303012) (xy 344.237742 -221.257629) (xy 344.222417 -221.209332)
			(xy 344.214661 -221.159259) (xy 344.214196 -221.133924) (xy 343.933272 -221.133924) (xy 343.932764 -221.159811)
			(xy 343.924665 -221.210949) (xy 343.908666 -221.260189) (xy 343.88516 -221.306321) (xy 343.854728 -221.348208)
			(xy 343.818118 -221.384818) (xy 343.776231 -221.41525) (xy 343.730099 -221.438756) (xy 343.680859 -221.454755)
			(xy 343.629721 -221.462854) (xy 343.577947 -221.462854) (xy 343.526809 -221.454755) (xy 343.477569 -221.438756)
			(xy 343.431437 -221.41525) (xy 343.38955 -221.384818) (xy 343.35294 -221.348208) (xy 343.322508 -221.306321)
			(xy 343.299002 -221.260189) (xy 343.283003 -221.210949) (xy 343.274904 -221.159811) (xy 343.274396 -221.133924)
			(xy 342.993472 -221.133924) (xy 342.992945 -221.161632) (xy 342.983748 -221.216279) (xy 342.975184 -221.242636)
			(xy 342.96731 -221.264734) (xy 343.172288 -221.619572) (xy 343.195148 -221.62389) (xy 343.219967 -221.629064)
			(xy 343.267746 -221.646018) (xy 343.312365 -221.670088) (xy 343.352772 -221.700708) (xy 343.388013 -221.737154)
			(xy 343.417257 -221.778566) (xy 343.439814 -221.823969) (xy 343.455152 -221.872291) (xy 343.46291 -221.922391)
			(xy 343.463372 -221.94774) (xy 343.462864 -221.973647) (xy 343.454758 -222.024824) (xy 343.438746 -222.074103)
			(xy 343.415223 -222.12027) (xy 343.384767 -222.162189) (xy 343.348129 -222.198827) (xy 343.30621 -222.229283)
			(xy 343.260043 -222.252806) (xy 343.210764 -222.268818) (xy 343.159587 -222.276924) (xy 343.107773 -222.276924)
			(xy 343.056596 -222.268818) (xy 343.007317 -222.252806) (xy 342.96115 -222.229283) (xy 342.919231 -222.198827)
			(xy 342.882593 -222.162189) (xy 342.852137 -222.12027) (xy 342.828614 -222.074103) (xy 342.812602 -222.024824)
			(xy 342.804496 -221.973647) (xy 342.803988 -221.94774) (xy 342.804592 -221.920023) (xy 342.813909 -221.865377)
			(xy 342.82253 -221.839028) (xy 342.830404 -221.81693) (xy 342.625426 -221.462092) (xy 342.602566 -221.457774)
			(xy 342.577766 -221.452574) (xy 342.53003 -221.435583) (xy 342.485455 -221.411489) (xy 342.445091 -221.380859)
			(xy 342.409889 -221.344414) (xy 342.380676 -221.303012) (xy 342.358142 -221.257629) (xy 342.342817 -221.209332)
			(xy 342.335061 -221.159259) (xy 342.334596 -221.133924) (xy 342.053672 -221.133924) (xy 342.053164 -221.159811)
			(xy 342.045065 -221.210949) (xy 342.029066 -221.260189) (xy 342.00556 -221.306321) (xy 341.975128 -221.348208)
			(xy 341.938518 -221.384818) (xy 341.896631 -221.41525) (xy 341.850499 -221.438756) (xy 341.801259 -221.454755)
			(xy 341.750121 -221.462854) (xy 341.698347 -221.462854) (xy 341.647209 -221.454755) (xy 341.597969 -221.438756)
			(xy 341.551837 -221.41525) (xy 341.50995 -221.384818) (xy 341.47334 -221.348208) (xy 341.442908 -221.306321)
			(xy 341.419402 -221.260189) (xy 341.403403 -221.210949) (xy 341.395304 -221.159811) (xy 341.394796 -221.133924)
			(xy 341.113872 -221.133924) (xy 341.113345 -221.161632) (xy 341.104148 -221.216279) (xy 341.095584 -221.242636)
			(xy 341.08771 -221.264734) (xy 341.292688 -221.619572) (xy 341.315548 -221.62389) (xy 341.340367 -221.629064)
			(xy 341.388146 -221.646018) (xy 341.432765 -221.670088) (xy 341.473172 -221.700708) (xy 341.508413 -221.737154)
			(xy 341.537657 -221.778566) (xy 341.560214 -221.823969) (xy 341.575552 -221.872291) (xy 341.58331 -221.922391)
			(xy 341.583772 -221.94774) (xy 341.583264 -221.973647) (xy 341.575158 -222.024824) (xy 341.559146 -222.074103)
			(xy 341.535623 -222.12027) (xy 341.505167 -222.162189) (xy 341.468529 -222.198827) (xy 341.42661 -222.229283)
			(xy 341.380443 -222.252806) (xy 341.331164 -222.268818) (xy 341.279987 -222.276924) (xy 341.228173 -222.276924)
			(xy 341.176996 -222.268818) (xy 341.127717 -222.252806) (xy 341.08155 -222.229283) (xy 341.039631 -222.198827)
			(xy 341.002993 -222.162189) (xy 340.972537 -222.12027) (xy 340.949014 -222.074103) (xy 340.933002 -222.024824)
			(xy 340.924896 -221.973647) (xy 340.924388 -221.94774) (xy 340.924992 -221.920023) (xy 340.934309 -221.865377)
			(xy 340.94293 -221.839028) (xy 340.950804 -221.81693) (xy 340.745826 -221.462092) (xy 340.722966 -221.457774)
			(xy 340.698166 -221.452574) (xy 340.65043 -221.435583) (xy 340.605855 -221.411489) (xy 340.565491 -221.380859)
			(xy 340.530289 -221.344414) (xy 340.501076 -221.303012) (xy 340.478542 -221.257629) (xy 340.463217 -221.209332)
			(xy 340.455461 -221.159259) (xy 340.454996 -221.133924) (xy 340.174072 -221.133924) (xy 340.173564 -221.159811)
			(xy 340.165465 -221.210949) (xy 340.149466 -221.260189) (xy 340.12596 -221.306321) (xy 340.095528 -221.348208)
			(xy 340.058918 -221.384818) (xy 340.017031 -221.41525) (xy 339.970899 -221.438756) (xy 339.921659 -221.454755)
			(xy 339.870521 -221.462854) (xy 339.818747 -221.462854) (xy 339.767609 -221.454755) (xy 339.718369 -221.438756)
			(xy 339.672237 -221.41525) (xy 339.63035 -221.384818) (xy 339.59374 -221.348208) (xy 339.563308 -221.306321)
			(xy 339.539802 -221.260189) (xy 339.523803 -221.210949) (xy 339.515704 -221.159811) (xy 339.515196 -221.133924)
			(xy 339.234272 -221.133924) (xy 339.233745 -221.161632) (xy 339.224548 -221.216279) (xy 339.215984 -221.242636)
			(xy 339.20811 -221.264734) (xy 339.413088 -221.619572) (xy 339.435948 -221.62389) (xy 339.460767 -221.629064)
			(xy 339.508546 -221.646018) (xy 339.553165 -221.670088) (xy 339.593572 -221.700708) (xy 339.628813 -221.737154)
			(xy 339.658057 -221.778566) (xy 339.680614 -221.823969) (xy 339.695952 -221.872291) (xy 339.70371 -221.922391)
			(xy 339.704172 -221.94774) (xy 339.703664 -221.973647) (xy 339.695558 -222.024824) (xy 339.679546 -222.074103)
			(xy 339.656023 -222.12027) (xy 339.625567 -222.162189) (xy 339.588929 -222.198827) (xy 339.54701 -222.229283)
			(xy 339.500843 -222.252806) (xy 339.451564 -222.268818) (xy 339.400387 -222.276924) (xy 339.348573 -222.276924)
			(xy 339.297396 -222.268818) (xy 339.248117 -222.252806) (xy 339.20195 -222.229283) (xy 339.160031 -222.198827)
			(xy 339.123393 -222.162189) (xy 339.092937 -222.12027) (xy 339.069414 -222.074103) (xy 339.053402 -222.024824)
			(xy 339.045296 -221.973647) (xy 339.044788 -221.94774) (xy 339.045392 -221.920023) (xy 339.054709 -221.865377)
			(xy 339.06333 -221.839028) (xy 339.071204 -221.81693) (xy 338.866226 -221.462092) (xy 338.843366 -221.457774)
			(xy 338.818566 -221.452574) (xy 338.77083 -221.435583) (xy 338.726255 -221.411489) (xy 338.685891 -221.380859)
			(xy 338.650689 -221.344414) (xy 338.621476 -221.303012) (xy 338.598942 -221.257629) (xy 338.583617 -221.209332)
			(xy 338.575861 -221.159259) (xy 338.575396 -221.133924) (xy 338.294472 -221.133924) (xy 338.293964 -221.159811)
			(xy 338.285865 -221.210949) (xy 338.269866 -221.260189) (xy 338.24636 -221.306321) (xy 338.215928 -221.348208)
			(xy 338.179318 -221.384818) (xy 338.137431 -221.41525) (xy 338.091299 -221.438756) (xy 338.042059 -221.454755)
			(xy 337.990921 -221.462854) (xy 337.939147 -221.462854) (xy 337.888009 -221.454755) (xy 337.838769 -221.438756)
			(xy 337.792637 -221.41525) (xy 337.75075 -221.384818) (xy 337.71414 -221.348208) (xy 337.683708 -221.306321)
			(xy 337.660202 -221.260189) (xy 337.644203 -221.210949) (xy 337.636104 -221.159811) (xy 337.635596 -221.133924)
			(xy 337.354672 -221.133924) (xy 337.354145 -221.161632) (xy 337.344948 -221.216279) (xy 337.336384 -221.242636)
			(xy 337.32851 -221.264734) (xy 337.533488 -221.619572) (xy 337.556348 -221.62389) (xy 337.581167 -221.629064)
			(xy 337.628946 -221.646018) (xy 337.673565 -221.670088) (xy 337.713972 -221.700708) (xy 337.749213 -221.737154)
			(xy 337.778457 -221.778566) (xy 337.801014 -221.823969) (xy 337.816352 -221.872291) (xy 337.82411 -221.922391)
			(xy 337.824572 -221.94774) (xy 337.824064 -221.973647) (xy 337.815958 -222.024824) (xy 337.799946 -222.074103)
			(xy 337.776423 -222.12027) (xy 337.745967 -222.162189) (xy 337.709329 -222.198827) (xy 337.66741 -222.229283)
			(xy 337.621243 -222.252806) (xy 337.571964 -222.268818) (xy 337.520787 -222.276924) (xy 337.468973 -222.276924)
			(xy 337.417796 -222.268818) (xy 337.368517 -222.252806) (xy 337.32235 -222.229283) (xy 337.280431 -222.198827)
			(xy 337.243793 -222.162189) (xy 337.213337 -222.12027) (xy 337.189814 -222.074103) (xy 337.173802 -222.024824)
			(xy 337.165696 -221.973647) (xy 337.165188 -221.94774) (xy 337.165792 -221.920023) (xy 337.175109 -221.865377)
			(xy 337.18373 -221.839028) (xy 337.191604 -221.81693) (xy 336.986626 -221.462092) (xy 336.963766 -221.457774)
			(xy 336.938966 -221.452574) (xy 336.89123 -221.435583) (xy 336.846655 -221.411489) (xy 336.806291 -221.380859)
			(xy 336.771089 -221.344414) (xy 336.741876 -221.303012) (xy 336.719342 -221.257629) (xy 336.704017 -221.209332)
			(xy 336.696261 -221.159259) (xy 336.695796 -221.133924) (xy 135.464804 -221.133924) (xy 135.464385 -221.15929)
			(xy 135.456633 -221.209425) (xy 135.441284 -221.257778) (xy 135.418702 -221.303206) (xy 135.389421 -221.344633)
			(xy 135.354133 -221.381081) (xy 135.313674 -221.411686) (xy 135.269 -221.435725) (xy 135.221169 -221.45263)
			(xy 135.196326 -221.457774) (xy 135.173466 -221.462092) (xy 134.968742 -221.81693) (xy 134.976362 -221.838774)
			(xy 134.984977 -221.865059) (xy 134.994298 -221.919578) (xy 134.994904 -221.947232) (xy 134.994904 -221.94774)
			(xy 134.994396 -221.973647) (xy 134.98629 -222.024824) (xy 134.970278 -222.074103) (xy 134.946755 -222.12027)
			(xy 134.916299 -222.162189) (xy 134.879661 -222.198827) (xy 134.837742 -222.229283) (xy 134.791575 -222.252806)
			(xy 134.742296 -222.268818) (xy 134.691119 -222.276924) (xy 134.639305 -222.276924) (xy 134.588128 -222.268818)
			(xy 134.538849 -222.252806) (xy 134.492682 -222.229283) (xy 134.450763 -222.198827) (xy 134.414125 -222.162189)
			(xy 134.383669 -222.12027) (xy 134.360146 -222.074103) (xy 134.344134 -222.024824) (xy 134.336028 -221.973647)
			(xy 134.33552 -221.94774) (xy 133.115304 -221.94774) (xy 133.114796 -221.973647) (xy 133.10669 -222.024824)
			(xy 133.090678 -222.074103) (xy 133.067155 -222.12027) (xy 133.036699 -222.162189) (xy 133.000061 -222.198827)
			(xy 132.958142 -222.229283) (xy 132.911975 -222.252806) (xy 132.862696 -222.268818) (xy 132.811519 -222.276924)
			(xy 132.759705 -222.276924) (xy 132.708528 -222.268818) (xy 132.659249 -222.252806) (xy 132.613082 -222.229283)
			(xy 132.571163 -222.198827) (xy 132.534525 -222.162189) (xy 132.504069 -222.12027) (xy 132.480546 -222.074103)
			(xy 132.464534 -222.024824) (xy 132.456428 -221.973647) (xy 132.45592 -221.94774) (xy 131.235704 -221.94774)
			(xy 131.235196 -221.973647) (xy 131.22709 -222.024824) (xy 131.211078 -222.074103) (xy 131.187555 -222.12027)
			(xy 131.157099 -222.162189) (xy 131.120461 -222.198827) (xy 131.078542 -222.229283) (xy 131.032375 -222.252806)
			(xy 130.983096 -222.268818) (xy 130.931919 -222.276924) (xy 130.880105 -222.276924) (xy 130.828928 -222.268818)
			(xy 130.779649 -222.252806) (xy 130.733482 -222.229283) (xy 130.691563 -222.198827) (xy 130.654925 -222.162189)
			(xy 130.624469 -222.12027) (xy 130.600946 -222.074103) (xy 130.584934 -222.024824) (xy 130.576828 -221.973647)
			(xy 130.57632 -221.94774) (xy 129.356104 -221.94774) (xy 129.355596 -221.973647) (xy 129.34749 -222.024824)
			(xy 129.331478 -222.074103) (xy 129.307955 -222.12027) (xy 129.277499 -222.162189) (xy 129.240861 -222.198827)
			(xy 129.198942 -222.229283) (xy 129.152775 -222.252806) (xy 129.103496 -222.268818) (xy 129.052319 -222.276924)
			(xy 129.000505 -222.276924) (xy 128.949328 -222.268818) (xy 128.900049 -222.252806) (xy 128.853882 -222.229283)
			(xy 128.811963 -222.198827) (xy 128.775325 -222.162189) (xy 128.744869 -222.12027) (xy 128.721346 -222.074103)
			(xy 128.705334 -222.024824) (xy 128.697228 -221.973647) (xy 128.69672 -221.94774) (xy 127.476504 -221.94774)
			(xy 127.475996 -221.973647) (xy 127.46789 -222.024824) (xy 127.451878 -222.074103) (xy 127.428355 -222.12027)
			(xy 127.397899 -222.162189) (xy 127.361261 -222.198827) (xy 127.319342 -222.229283) (xy 127.273175 -222.252806)
			(xy 127.223896 -222.268818) (xy 127.172719 -222.276924) (xy 127.120905 -222.276924) (xy 127.069728 -222.268818)
			(xy 127.020449 -222.252806) (xy 126.974282 -222.229283) (xy 126.932363 -222.198827) (xy 126.895725 -222.162189)
			(xy 126.865269 -222.12027) (xy 126.841746 -222.074103) (xy 126.825734 -222.024824) (xy 126.817628 -221.973647)
			(xy 126.81712 -221.94774) (xy 125.596904 -221.94774) (xy 125.596396 -221.973647) (xy 125.58829 -222.024824)
			(xy 125.572278 -222.074103) (xy 125.548755 -222.12027) (xy 125.518299 -222.162189) (xy 125.481661 -222.198827)
			(xy 125.439742 -222.229283) (xy 125.393575 -222.252806) (xy 125.344296 -222.268818) (xy 125.293119 -222.276924)
			(xy 125.241305 -222.276924) (xy 125.190128 -222.268818) (xy 125.140849 -222.252806) (xy 125.094682 -222.229283)
			(xy 125.052763 -222.198827) (xy 125.016125 -222.162189) (xy 124.985669 -222.12027) (xy 124.962146 -222.074103)
			(xy 124.946134 -222.024824) (xy 124.938028 -221.973647) (xy 124.93752 -221.94774) (xy 123.717304 -221.94774)
			(xy 123.716796 -221.973647) (xy 123.70869 -222.024824) (xy 123.692678 -222.074103) (xy 123.669155 -222.12027)
			(xy 123.638699 -222.162189) (xy 123.602061 -222.198827) (xy 123.560142 -222.229283) (xy 123.513975 -222.252806)
			(xy 123.464696 -222.268818) (xy 123.413519 -222.276924) (xy 123.361705 -222.276924) (xy 123.310528 -222.268818)
			(xy 123.261249 -222.252806) (xy 123.215082 -222.229283) (xy 123.173163 -222.198827) (xy 123.136525 -222.162189)
			(xy 123.106069 -222.12027) (xy 123.082546 -222.074103) (xy 123.066534 -222.024824) (xy 123.058428 -221.973647)
			(xy 123.05792 -221.94774) (xy 121.837704 -221.94774) (xy 121.837196 -221.973647) (xy 121.82909 -222.024824)
			(xy 121.813078 -222.074103) (xy 121.789555 -222.12027) (xy 121.759099 -222.162189) (xy 121.722461 -222.198827)
			(xy 121.680542 -222.229283) (xy 121.634375 -222.252806) (xy 121.585096 -222.268818) (xy 121.533919 -222.276924)
			(xy 121.482105 -222.276924) (xy 121.430928 -222.268818) (xy 121.381649 -222.252806) (xy 121.335482 -222.229283)
			(xy 121.293563 -222.198827) (xy 121.256925 -222.162189) (xy 121.226469 -222.12027) (xy 121.202946 -222.074103)
			(xy 121.186934 -222.024824) (xy 121.178828 -221.973647) (xy 121.17832 -221.94774) (xy 118.078504 -221.94774)
			(xy 118.077996 -221.973647) (xy 118.06989 -222.024824) (xy 118.053878 -222.074103) (xy 118.030355 -222.12027)
			(xy 117.999899 -222.162189) (xy 117.963261 -222.198827) (xy 117.921342 -222.229283) (xy 117.875175 -222.252806)
			(xy 117.825896 -222.268818) (xy 117.774719 -222.276924) (xy 117.722905 -222.276924) (xy 117.671728 -222.268818)
			(xy 117.622449 -222.252806) (xy 117.576282 -222.229283) (xy 117.534363 -222.198827) (xy 117.497725 -222.162189)
			(xy 117.467269 -222.12027) (xy 117.443746 -222.074103) (xy 117.427734 -222.024824) (xy 117.419628 -221.973647)
			(xy 117.41912 -221.94774) (xy 116.198904 -221.94774) (xy 116.198396 -221.973647) (xy 116.19029 -222.024824)
			(xy 116.174278 -222.074103) (xy 116.150755 -222.12027) (xy 116.120299 -222.162189) (xy 116.083661 -222.198827)
			(xy 116.041742 -222.229283) (xy 115.995575 -222.252806) (xy 115.946296 -222.268818) (xy 115.895119 -222.276924)
			(xy 115.843305 -222.276924) (xy 115.792128 -222.268818) (xy 115.742849 -222.252806) (xy 115.696682 -222.229283)
			(xy 115.654763 -222.198827) (xy 115.618125 -222.162189) (xy 115.587669 -222.12027) (xy 115.564146 -222.074103)
			(xy 115.548134 -222.024824) (xy 115.540028 -221.973647) (xy 115.53952 -221.94774) (xy 114.319304 -221.94774)
			(xy 114.318796 -221.973627) (xy 114.310697 -222.024765) (xy 114.294698 -222.074005) (xy 114.271192 -222.120137)
			(xy 114.24076 -222.162024) (xy 114.20415 -222.198634) (xy 114.162263 -222.229066) (xy 114.116131 -222.252572)
			(xy 114.066891 -222.268571) (xy 114.015753 -222.27667) (xy 113.963979 -222.27667) (xy 113.912841 -222.268571)
			(xy 113.863601 -222.252572) (xy 113.817469 -222.229066) (xy 113.775582 -222.198634) (xy 113.738972 -222.162024)
			(xy 113.70854 -222.120137) (xy 113.685034 -222.074005) (xy 113.669035 -222.024765) (xy 113.660936 -221.973627)
			(xy 113.660428 -221.94774) (xy 112.439704 -221.94774) (xy 112.439196 -221.973647) (xy 112.43109 -222.024824)
			(xy 112.415078 -222.074103) (xy 112.391555 -222.12027) (xy 112.361099 -222.162189) (xy 112.324461 -222.198827)
			(xy 112.282542 -222.229283) (xy 112.236375 -222.252806) (xy 112.187096 -222.268818) (xy 112.135919 -222.276924)
			(xy 112.084105 -222.276924) (xy 112.032928 -222.268818) (xy 111.983649 -222.252806) (xy 111.937482 -222.229283)
			(xy 111.895563 -222.198827) (xy 111.858925 -222.162189) (xy 111.828469 -222.12027) (xy 111.804946 -222.074103)
			(xy 111.788934 -222.024824) (xy 111.780828 -221.973647) (xy 111.78032 -221.94774) (xy 110.560104 -221.94774)
			(xy 110.559596 -221.973627) (xy 110.551497 -222.024765) (xy 110.535498 -222.074005) (xy 110.511992 -222.120137)
			(xy 110.48156 -222.162024) (xy 110.44495 -222.198634) (xy 110.403063 -222.229066) (xy 110.356931 -222.252572)
			(xy 110.307691 -222.268571) (xy 110.256553 -222.27667) (xy 110.204779 -222.27667) (xy 110.153641 -222.268571)
			(xy 110.104401 -222.252572) (xy 110.058269 -222.229066) (xy 110.016382 -222.198634) (xy 109.979772 -222.162024)
			(xy 109.94934 -222.120137) (xy 109.925834 -222.074005) (xy 109.909835 -222.024765) (xy 109.901736 -221.973627)
			(xy 109.901228 -221.94774) (xy 108.680504 -221.94774) (xy 108.679996 -221.973647) (xy 108.67189 -222.024824)
			(xy 108.655878 -222.074103) (xy 108.632355 -222.12027) (xy 108.601899 -222.162189) (xy 108.565261 -222.198827)
			(xy 108.523342 -222.229283) (xy 108.477175 -222.252806) (xy 108.427896 -222.268818) (xy 108.376719 -222.276924)
			(xy 108.324905 -222.276924) (xy 108.273728 -222.268818) (xy 108.224449 -222.252806) (xy 108.178282 -222.229283)
			(xy 108.136363 -222.198827) (xy 108.099725 -222.162189) (xy 108.069269 -222.12027) (xy 108.045746 -222.074103)
			(xy 108.029734 -222.024824) (xy 108.021628 -221.973647) (xy 108.02112 -221.94774) (xy 106.800904 -221.94774)
			(xy 106.800396 -221.973647) (xy 106.79229 -222.024824) (xy 106.776278 -222.074103) (xy 106.752755 -222.12027)
			(xy 106.722299 -222.162189) (xy 106.685661 -222.198827) (xy 106.643742 -222.229283) (xy 106.597575 -222.252806)
			(xy 106.548296 -222.268818) (xy 106.497119 -222.276924) (xy 106.445305 -222.276924) (xy 106.394128 -222.268818)
			(xy 106.344849 -222.252806) (xy 106.298682 -222.229283) (xy 106.256763 -222.198827) (xy 106.220125 -222.162189)
			(xy 106.189669 -222.12027) (xy 106.166146 -222.074103) (xy 106.150134 -222.024824) (xy 106.142028 -221.973647)
			(xy 106.14152 -221.94774) (xy 104.921304 -221.94774) (xy 104.920796 -221.973647) (xy 104.91269 -222.024824)
			(xy 104.896678 -222.074103) (xy 104.873155 -222.12027) (xy 104.842699 -222.162189) (xy 104.806061 -222.198827)
			(xy 104.764142 -222.229283) (xy 104.717975 -222.252806) (xy 104.668696 -222.268818) (xy 104.617519 -222.276924)
			(xy 104.565705 -222.276924) (xy 104.514528 -222.268818) (xy 104.465249 -222.252806) (xy 104.419082 -222.229283)
			(xy 104.377163 -222.198827) (xy 104.340525 -222.162189) (xy 104.310069 -222.12027) (xy 104.286546 -222.074103)
			(xy 104.270534 -222.024824) (xy 104.262428 -221.973647) (xy 104.26192 -221.94774) (xy 103.041704 -221.94774)
			(xy 103.041196 -221.973647) (xy 103.03309 -222.024824) (xy 103.017078 -222.074103) (xy 102.993555 -222.12027)
			(xy 102.963099 -222.162189) (xy 102.926461 -222.198827) (xy 102.884542 -222.229283) (xy 102.838375 -222.252806)
			(xy 102.789096 -222.268818) (xy 102.737919 -222.276924) (xy 102.686105 -222.276924) (xy 102.634928 -222.268818)
			(xy 102.585649 -222.252806) (xy 102.539482 -222.229283) (xy 102.497563 -222.198827) (xy 102.460925 -222.162189)
			(xy 102.430469 -222.12027) (xy 102.406946 -222.074103) (xy 102.390934 -222.024824) (xy 102.382828 -221.973647)
			(xy 102.38232 -221.94774) (xy 102.382923 -221.920023) (xy 102.39224 -221.865377) (xy 102.400862 -221.839028)
			(xy 102.408736 -221.81693) (xy 102.203758 -221.462092) (xy 102.180898 -221.457774) (xy 102.156103 -221.45255)
			(xy 102.108367 -221.435564) (xy 102.063792 -221.411474) (xy 102.023427 -221.380847) (xy 101.988224 -221.344405)
			(xy 101.959011 -221.303006) (xy 101.936476 -221.257625) (xy 101.92115 -221.20933) (xy 101.913394 -221.159258)
			(xy 101.912928 -221.133924) (xy 101.632004 -221.133924) (xy 101.631496 -221.159811) (xy 101.623397 -221.210949)
			(xy 101.607398 -221.260189) (xy 101.583892 -221.306321) (xy 101.55346 -221.348208) (xy 101.51685 -221.384818)
			(xy 101.474963 -221.41525) (xy 101.428831 -221.438756) (xy 101.379591 -221.454755) (xy 101.328453 -221.462854)
			(xy 101.276679 -221.462854) (xy 101.225541 -221.454755) (xy 101.176301 -221.438756) (xy 101.130169 -221.41525)
			(xy 101.088282 -221.384818) (xy 101.051672 -221.348208) (xy 101.02124 -221.306321) (xy 100.997734 -221.260189)
			(xy 100.981735 -221.210949) (xy 100.973636 -221.159811) (xy 100.973128 -221.133924) (xy 100.692204 -221.133924)
			(xy 100.69168 -221.161632) (xy 100.682481 -221.216279) (xy 100.673916 -221.242636) (xy 100.666042 -221.264734)
			(xy 100.87102 -221.619572) (xy 100.89388 -221.62389) (xy 100.918705 -221.629041) (xy 100.966483 -221.645999)
			(xy 101.011102 -221.670074) (xy 101.051507 -221.700696) (xy 101.086747 -221.737145) (xy 101.11599 -221.778561)
			(xy 101.138547 -221.823965) (xy 101.153885 -221.872289) (xy 101.161642 -221.92239) (xy 101.162104 -221.94774)
			(xy 101.161596 -221.973647) (xy 101.15349 -222.024824) (xy 101.137478 -222.074103) (xy 101.113955 -222.12027)
			(xy 101.083499 -222.162189) (xy 101.046861 -222.198827) (xy 101.004942 -222.229283) (xy 100.958775 -222.252806)
			(xy 100.909496 -222.268818) (xy 100.858319 -222.276924) (xy 100.806505 -222.276924) (xy 100.755328 -222.268818)
			(xy 100.706049 -222.252806) (xy 100.659882 -222.229283) (xy 100.617963 -222.198827) (xy 100.581325 -222.162189)
			(xy 100.550869 -222.12027) (xy 100.527346 -222.074103) (xy 100.511334 -222.024824) (xy 100.503228 -221.973647)
			(xy 100.50272 -221.94774) (xy 100.503323 -221.920023) (xy 100.51264 -221.865377) (xy 100.521262 -221.839028)
			(xy 100.529136 -221.81693) (xy 100.324158 -221.462092) (xy 100.301298 -221.457774) (xy 100.276503 -221.45255)
			(xy 100.228767 -221.435564) (xy 100.184192 -221.411474) (xy 100.143827 -221.380847) (xy 100.108624 -221.344405)
			(xy 100.079411 -221.303006) (xy 100.056876 -221.257625) (xy 100.04155 -221.20933) (xy 100.033794 -221.159258)
			(xy 100.033328 -221.133924) (xy 99.752404 -221.133924) (xy 99.751896 -221.159811) (xy 99.743797 -221.210949)
			(xy 99.727798 -221.260189) (xy 99.704292 -221.306321) (xy 99.67386 -221.348208) (xy 99.63725 -221.384818)
			(xy 99.595363 -221.41525) (xy 99.549231 -221.438756) (xy 99.499991 -221.454755) (xy 99.448853 -221.462854)
			(xy 99.397079 -221.462854) (xy 99.345941 -221.454755) (xy 99.296701 -221.438756) (xy 99.250569 -221.41525)
			(xy 99.208682 -221.384818) (xy 99.172072 -221.348208) (xy 99.14164 -221.306321) (xy 99.118134 -221.260189)
			(xy 99.102135 -221.210949) (xy 99.094036 -221.159811) (xy 99.093528 -221.133924) (xy 98.812604 -221.133924)
			(xy 98.81208 -221.161632) (xy 98.802881 -221.216279) (xy 98.794316 -221.242636) (xy 98.786442 -221.264734)
			(xy 98.99142 -221.619572) (xy 99.01428 -221.62389) (xy 99.039105 -221.629041) (xy 99.086883 -221.645999)
			(xy 99.131502 -221.670074) (xy 99.171907 -221.700696) (xy 99.207147 -221.737145) (xy 99.23639 -221.778561)
			(xy 99.258947 -221.823965) (xy 99.274285 -221.872289) (xy 99.282042 -221.92239) (xy 99.282504 -221.94774)
			(xy 99.281996 -221.973647) (xy 99.27389 -222.024824) (xy 99.257878 -222.074103) (xy 99.234355 -222.12027)
			(xy 99.203899 -222.162189) (xy 99.167261 -222.198827) (xy 99.125342 -222.229283) (xy 99.079175 -222.252806)
			(xy 99.029896 -222.268818) (xy 98.978719 -222.276924) (xy 98.926905 -222.276924) (xy 98.875728 -222.268818)
			(xy 98.826449 -222.252806) (xy 98.780282 -222.229283) (xy 98.738363 -222.198827) (xy 98.701725 -222.162189)
			(xy 98.671269 -222.12027) (xy 98.647746 -222.074103) (xy 98.631734 -222.024824) (xy 98.623628 -221.973647)
			(xy 98.62312 -221.94774) (xy 98.623723 -221.920023) (xy 98.63304 -221.865377) (xy 98.641662 -221.839028)
			(xy 98.649536 -221.81693) (xy 98.444558 -221.462092) (xy 98.421698 -221.457774) (xy 98.396903 -221.45255)
			(xy 98.349167 -221.435564) (xy 98.304592 -221.411474) (xy 98.264227 -221.380847) (xy 98.229024 -221.344405)
			(xy 98.199811 -221.303006) (xy 98.177276 -221.257625) (xy 98.16195 -221.20933) (xy 98.154194 -221.159258)
			(xy 98.153728 -221.133924) (xy 97.872804 -221.133924) (xy 97.872296 -221.159811) (xy 97.864197 -221.210949)
			(xy 97.848198 -221.260189) (xy 97.824692 -221.306321) (xy 97.79426 -221.348208) (xy 97.75765 -221.384818)
			(xy 97.715763 -221.41525) (xy 97.669631 -221.438756) (xy 97.620391 -221.454755) (xy 97.569253 -221.462854)
			(xy 97.517479 -221.462854) (xy 97.466341 -221.454755) (xy 97.417101 -221.438756) (xy 97.370969 -221.41525)
			(xy 97.329082 -221.384818) (xy 97.292472 -221.348208) (xy 97.26204 -221.306321) (xy 97.238534 -221.260189)
			(xy 97.222535 -221.210949) (xy 97.214436 -221.159811) (xy 97.213928 -221.133924) (xy 96.933004 -221.133924)
			(xy 96.93248 -221.161632) (xy 96.923281 -221.216279) (xy 96.914716 -221.242636) (xy 96.906842 -221.264734)
			(xy 97.11182 -221.619572) (xy 97.13468 -221.62389) (xy 97.159505 -221.629041) (xy 97.207283 -221.645999)
			(xy 97.251902 -221.670074) (xy 97.292307 -221.700696) (xy 97.327547 -221.737145) (xy 97.35679 -221.778561)
			(xy 97.379347 -221.823965) (xy 97.394685 -221.872289) (xy 97.402442 -221.92239) (xy 97.402904 -221.94774)
			(xy 97.402396 -221.973647) (xy 97.39429 -222.024824) (xy 97.378278 -222.074103) (xy 97.354755 -222.12027)
			(xy 97.324299 -222.162189) (xy 97.287661 -222.198827) (xy 97.245742 -222.229283) (xy 97.199575 -222.252806)
			(xy 97.150296 -222.268818) (xy 97.099119 -222.276924) (xy 97.047305 -222.276924) (xy 96.996128 -222.268818)
			(xy 96.946849 -222.252806) (xy 96.900682 -222.229283) (xy 96.858763 -222.198827) (xy 96.822125 -222.162189)
			(xy 96.791669 -222.12027) (xy 96.768146 -222.074103) (xy 96.752134 -222.024824) (xy 96.744028 -221.973647)
			(xy 96.74352 -221.94774) (xy 96.744123 -221.920023) (xy 96.75344 -221.865377) (xy 96.762062 -221.839028)
			(xy 96.769936 -221.81693) (xy 96.564958 -221.462092) (xy 96.542098 -221.457774) (xy 96.517303 -221.45255)
			(xy 96.469567 -221.435564) (xy 96.424992 -221.411474) (xy 96.384627 -221.380847) (xy 96.349424 -221.344405)
			(xy 96.320211 -221.303006) (xy 96.297676 -221.257625) (xy 96.28235 -221.20933) (xy 96.274594 -221.159258)
			(xy 96.274128 -221.133924) (xy 95.993204 -221.133924) (xy 95.992696 -221.159811) (xy 95.984597 -221.210949)
			(xy 95.968598 -221.260189) (xy 95.945092 -221.306321) (xy 95.91466 -221.348208) (xy 95.87805 -221.384818)
			(xy 95.836163 -221.41525) (xy 95.790031 -221.438756) (xy 95.740791 -221.454755) (xy 95.689653 -221.462854)
			(xy 95.637879 -221.462854) (xy 95.586741 -221.454755) (xy 95.537501 -221.438756) (xy 95.491369 -221.41525)
			(xy 95.449482 -221.384818) (xy 95.412872 -221.348208) (xy 95.38244 -221.306321) (xy 95.358934 -221.260189)
			(xy 95.342935 -221.210949) (xy 95.334836 -221.159811) (xy 95.334328 -221.133924) (xy 95.053404 -221.133924)
			(xy 95.05288 -221.161632) (xy 95.043681 -221.216279) (xy 95.035116 -221.242636) (xy 95.027242 -221.264734)
			(xy 95.23222 -221.619572) (xy 95.25508 -221.62389) (xy 95.279905 -221.629041) (xy 95.327683 -221.645999)
			(xy 95.372302 -221.670074) (xy 95.412707 -221.700696) (xy 95.447947 -221.737145) (xy 95.47719 -221.778561)
			(xy 95.499747 -221.823965) (xy 95.515085 -221.872289) (xy 95.522842 -221.92239) (xy 95.523304 -221.94774)
			(xy 95.522796 -221.973647) (xy 95.51469 -222.024824) (xy 95.498678 -222.074103) (xy 95.475155 -222.12027)
			(xy 95.444699 -222.162189) (xy 95.408061 -222.198827) (xy 95.366142 -222.229283) (xy 95.319975 -222.252806)
			(xy 95.270696 -222.268818) (xy 95.219519 -222.276924) (xy 95.167705 -222.276924) (xy 95.116528 -222.268818)
			(xy 95.067249 -222.252806) (xy 95.021082 -222.229283) (xy 94.979163 -222.198827) (xy 94.942525 -222.162189)
			(xy 94.912069 -222.12027) (xy 94.888546 -222.074103) (xy 94.872534 -222.024824) (xy 94.864428 -221.973647)
			(xy 94.86392 -221.94774) (xy 94.864523 -221.920023) (xy 94.87384 -221.865377) (xy 94.882462 -221.839028)
			(xy 94.890336 -221.81693) (xy 94.685358 -221.462092) (xy 94.662498 -221.457774) (xy 94.637703 -221.45255)
			(xy 94.589967 -221.435564) (xy 94.545392 -221.411474) (xy 94.505027 -221.380847) (xy 94.469824 -221.344405)
			(xy 94.440611 -221.303006) (xy 94.418076 -221.257625) (xy 94.40275 -221.20933) (xy 94.394994 -221.159258)
			(xy 94.394528 -221.133924) (xy 94.113604 -221.133924) (xy 94.113096 -221.159811) (xy 94.104997 -221.210949)
			(xy 94.088998 -221.260189) (xy 94.065492 -221.306321) (xy 94.03506 -221.348208) (xy 93.99845 -221.384818)
			(xy 93.956563 -221.41525) (xy 93.910431 -221.438756) (xy 93.861191 -221.454755) (xy 93.810053 -221.462854)
			(xy 93.758279 -221.462854) (xy 93.707141 -221.454755) (xy 93.657901 -221.438756) (xy 93.611769 -221.41525)
			(xy 93.569882 -221.384818) (xy 93.533272 -221.348208) (xy 93.50284 -221.306321) (xy 93.479334 -221.260189)
			(xy 93.463335 -221.210949) (xy 93.455236 -221.159811) (xy 93.454728 -221.133924) (xy 93.173804 -221.133924)
			(xy 93.17328 -221.161632) (xy 93.164081 -221.216279) (xy 93.155516 -221.242636) (xy 93.147642 -221.264734)
			(xy 93.35262 -221.619572) (xy 93.37548 -221.62389) (xy 93.400305 -221.629041) (xy 93.448083 -221.645999)
			(xy 93.492702 -221.670074) (xy 93.533107 -221.700696) (xy 93.568347 -221.737145) (xy 93.59759 -221.778561)
			(xy 93.620147 -221.823965) (xy 93.635485 -221.872289) (xy 93.643242 -221.92239) (xy 93.643704 -221.94774)
			(xy 93.643196 -221.973647) (xy 93.63509 -222.024824) (xy 93.619078 -222.074103) (xy 93.595555 -222.12027)
			(xy 93.565099 -222.162189) (xy 93.528461 -222.198827) (xy 93.486542 -222.229283) (xy 93.440375 -222.252806)
			(xy 93.391096 -222.268818) (xy 93.339919 -222.276924) (xy 93.288105 -222.276924) (xy 93.236928 -222.268818)
			(xy 93.187649 -222.252806) (xy 93.141482 -222.229283) (xy 93.099563 -222.198827) (xy 93.062925 -222.162189)
			(xy 93.032469 -222.12027) (xy 93.008946 -222.074103) (xy 92.992934 -222.024824) (xy 92.984828 -221.973647)
			(xy 92.98432 -221.94774) (xy 92.984923 -221.920023) (xy 92.99424 -221.865377) (xy 93.002862 -221.839028)
			(xy 93.010736 -221.81693) (xy 92.805758 -221.462092) (xy 92.782898 -221.457774) (xy 92.758103 -221.45255)
			(xy 92.710367 -221.435564) (xy 92.665792 -221.411474) (xy 92.625427 -221.380847) (xy 92.590224 -221.344405)
			(xy 92.561011 -221.303006) (xy 92.538476 -221.257625) (xy 92.52315 -221.20933) (xy 92.515394 -221.159258)
			(xy 92.514928 -221.133924) (xy 92.234004 -221.133924) (xy 92.233496 -221.159811) (xy 92.225397 -221.210949)
			(xy 92.209398 -221.260189) (xy 92.185892 -221.306321) (xy 92.15546 -221.348208) (xy 92.11885 -221.384818)
			(xy 92.076963 -221.41525) (xy 92.030831 -221.438756) (xy 91.981591 -221.454755) (xy 91.930453 -221.462854)
			(xy 91.878679 -221.462854) (xy 91.827541 -221.454755) (xy 91.778301 -221.438756) (xy 91.732169 -221.41525)
			(xy 91.690282 -221.384818) (xy 91.653672 -221.348208) (xy 91.62324 -221.306321) (xy 91.599734 -221.260189)
			(xy 91.583735 -221.210949) (xy 91.575636 -221.159811) (xy 91.575128 -221.133924) (xy 91.294204 -221.133924)
			(xy 91.29368 -221.161632) (xy 91.284481 -221.216279) (xy 91.275916 -221.242636) (xy 91.268042 -221.264734)
			(xy 91.47302 -221.619572) (xy 91.49588 -221.62389) (xy 91.520705 -221.629041) (xy 91.568483 -221.645999)
			(xy 91.613102 -221.670074) (xy 91.653507 -221.700696) (xy 91.688747 -221.737145) (xy 91.71799 -221.778561)
			(xy 91.740547 -221.823965) (xy 91.755885 -221.872289) (xy 91.763642 -221.92239) (xy 91.764104 -221.94774)
			(xy 91.763596 -221.973647) (xy 91.75549 -222.024824) (xy 91.739478 -222.074103) (xy 91.715955 -222.12027)
			(xy 91.685499 -222.162189) (xy 91.648861 -222.198827) (xy 91.606942 -222.229283) (xy 91.560775 -222.252806)
			(xy 91.511496 -222.268818) (xy 91.460319 -222.276924) (xy 91.408505 -222.276924) (xy 91.357328 -222.268818)
			(xy 91.308049 -222.252806) (xy 91.261882 -222.229283) (xy 91.219963 -222.198827) (xy 91.183325 -222.162189)
			(xy 91.152869 -222.12027) (xy 91.129346 -222.074103) (xy 91.113334 -222.024824) (xy 91.105228 -221.973647)
			(xy 91.10472 -221.94774) (xy 91.105323 -221.920023) (xy 91.11464 -221.865377) (xy 91.123262 -221.839028)
			(xy 91.131136 -221.81693) (xy 90.926158 -221.462092) (xy 90.903298 -221.457774) (xy 90.878503 -221.45255)
			(xy 90.830767 -221.435564) (xy 90.786192 -221.411474) (xy 90.745827 -221.380847) (xy 90.710624 -221.344405)
			(xy 90.681411 -221.303006) (xy 90.658876 -221.257625) (xy 90.64355 -221.20933) (xy 90.635794 -221.159258)
			(xy 90.635328 -221.133924) (xy 90.354404 -221.133924) (xy 90.353896 -221.159811) (xy 90.345797 -221.210949)
			(xy 90.329798 -221.260189) (xy 90.306292 -221.306321) (xy 90.27586 -221.348208) (xy 90.23925 -221.384818)
			(xy 90.197363 -221.41525) (xy 90.151231 -221.438756) (xy 90.101991 -221.454755) (xy 90.050853 -221.462854)
			(xy 89.999079 -221.462854) (xy 89.947941 -221.454755) (xy 89.898701 -221.438756) (xy 89.852569 -221.41525)
			(xy 89.810682 -221.384818) (xy 89.774072 -221.348208) (xy 89.74364 -221.306321) (xy 89.720134 -221.260189)
			(xy 89.704135 -221.210949) (xy 89.696036 -221.159811) (xy 89.695528 -221.133924) (xy 89.414604 -221.133924)
			(xy 89.41408 -221.161632) (xy 89.404881 -221.216279) (xy 89.396316 -221.242636) (xy 89.388442 -221.264734)
			(xy 89.59342 -221.619572) (xy 89.61628 -221.62389) (xy 89.641105 -221.629041) (xy 89.688883 -221.645999)
			(xy 89.733502 -221.670074) (xy 89.773907 -221.700696) (xy 89.809147 -221.737145) (xy 89.83839 -221.778561)
			(xy 89.860947 -221.823965) (xy 89.876285 -221.872289) (xy 89.884042 -221.92239) (xy 89.884504 -221.94774)
			(xy 89.883996 -221.973647) (xy 89.87589 -222.024824) (xy 89.859878 -222.074103) (xy 89.836355 -222.12027)
			(xy 89.805899 -222.162189) (xy 89.769261 -222.198827) (xy 89.727342 -222.229283) (xy 89.681175 -222.252806)
			(xy 89.631896 -222.268818) (xy 89.580719 -222.276924) (xy 89.528905 -222.276924) (xy 89.477728 -222.268818)
			(xy 89.428449 -222.252806) (xy 89.382282 -222.229283) (xy 89.340363 -222.198827) (xy 89.303725 -222.162189)
			(xy 89.273269 -222.12027) (xy 89.249746 -222.074103) (xy 89.233734 -222.024824) (xy 89.225628 -221.973647)
			(xy 89.22512 -221.94774) (xy 89.225723 -221.920023) (xy 89.23504 -221.865377) (xy 89.243662 -221.839028)
			(xy 89.251536 -221.81693) (xy 89.046558 -221.462092) (xy 89.023698 -221.457774) (xy 88.998903 -221.45255)
			(xy 88.951167 -221.435564) (xy 88.906592 -221.411474) (xy 88.866227 -221.380847) (xy 88.831024 -221.344405)
			(xy 88.801811 -221.303006) (xy 88.779276 -221.257625) (xy 88.76395 -221.20933) (xy 88.756194 -221.159258)
			(xy 88.755728 -221.133924) (xy 2.509012 -221.133924) (xy 2.509012 -224.389442) (xy 93.454728 -224.389442)
			(xy 93.455135 -224.364105) (xy 93.462897 -224.314028) (xy 93.478229 -224.265728) (xy 93.50077 -224.220343)
			(xy 93.529989 -224.17894) (xy 93.565199 -224.142496) (xy 93.60557 -224.111867) (xy 93.650152 -224.087776)
			(xy 93.697895 -224.070789) (xy 93.722698 -224.065592) (xy 93.745558 -224.061274) (xy 93.950282 -223.706436)
			(xy 93.942662 -223.684338) (xy 93.934031 -223.657991) (xy 93.92471 -223.603344) (xy 93.92412 -223.575626)
			(xy 93.924628 -223.549719) (xy 93.932734 -223.498542) (xy 93.948746 -223.449263) (xy 93.972269 -223.403096)
			(xy 94.002725 -223.361177) (xy 94.039363 -223.324539) (xy 94.081282 -223.294083) (xy 94.127449 -223.27056)
			(xy 94.176728 -223.254548) (xy 94.227905 -223.246442) (xy 94.279719 -223.246442) (xy 94.330896 -223.254548)
			(xy 94.380175 -223.27056) (xy 94.426342 -223.294083) (xy 94.468261 -223.324539) (xy 94.504899 -223.361177)
			(xy 94.535355 -223.403096) (xy 94.558878 -223.449263) (xy 94.57489 -223.498542) (xy 94.582996 -223.549719)
			(xy 94.583504 -223.575626) (xy 94.583087 -223.600992) (xy 94.575334 -223.651127) (xy 94.559985 -223.69948)
			(xy 94.537403 -223.744908) (xy 94.508122 -223.786336) (xy 94.472834 -223.822783) (xy 94.432375 -223.853388)
			(xy 94.387701 -223.877427) (xy 94.339869 -223.894332) (xy 94.315026 -223.899476) (xy 94.292166 -223.903794)
			(xy 94.087442 -224.258632) (xy 94.095316 -224.280476) (xy 94.10389 -224.306896) (xy 94.11309 -224.36167)
			(xy 94.113604 -224.389442) (xy 94.394528 -224.389442) (xy 94.395036 -224.363555) (xy 94.403135 -224.312417)
			(xy 94.419134 -224.263177) (xy 94.44264 -224.217045) (xy 94.473072 -224.175158) (xy 94.509682 -224.138548)
			(xy 94.551569 -224.108116) (xy 94.597701 -224.08461) (xy 94.646941 -224.068611) (xy 94.698079 -224.060512)
			(xy 94.749853 -224.060512) (xy 94.800991 -224.068611) (xy 94.850231 -224.08461) (xy 94.896363 -224.108116)
			(xy 94.93825 -224.138548) (xy 94.97486 -224.175158) (xy 95.005292 -224.217045) (xy 95.028798 -224.263177)
			(xy 95.044797 -224.312417) (xy 95.052896 -224.363555) (xy 95.053404 -224.389442) (xy 95.334328 -224.389442)
			(xy 95.334735 -224.364105) (xy 95.342497 -224.314028) (xy 95.357829 -224.265728) (xy 95.38037 -224.220343)
			(xy 95.409589 -224.17894) (xy 95.444799 -224.142496) (xy 95.48517 -224.111867) (xy 95.529752 -224.087776)
			(xy 95.577495 -224.070789) (xy 95.602298 -224.065592) (xy 95.625158 -224.061274) (xy 95.829882 -223.706436)
			(xy 95.822262 -223.684338) (xy 95.813631 -223.657991) (xy 95.80431 -223.603344) (xy 95.80372 -223.575626)
			(xy 95.804228 -223.549719) (xy 95.812334 -223.498542) (xy 95.828346 -223.449263) (xy 95.851869 -223.403096)
			(xy 95.882325 -223.361177) (xy 95.918963 -223.324539) (xy 95.960882 -223.294083) (xy 96.007049 -223.27056)
			(xy 96.056328 -223.254548) (xy 96.107505 -223.246442) (xy 96.159319 -223.246442) (xy 96.210496 -223.254548)
			(xy 96.259775 -223.27056) (xy 96.305942 -223.294083) (xy 96.347861 -223.324539) (xy 96.384499 -223.361177)
			(xy 96.414955 -223.403096) (xy 96.438478 -223.449263) (xy 96.45449 -223.498542) (xy 96.462596 -223.549719)
			(xy 96.463104 -223.575626) (xy 96.462687 -223.600992) (xy 96.454934 -223.651127) (xy 96.439585 -223.69948)
			(xy 96.417003 -223.744908) (xy 96.387722 -223.786336) (xy 96.352434 -223.822783) (xy 96.311975 -223.853388)
			(xy 96.267301 -223.877427) (xy 96.219469 -223.894332) (xy 96.194626 -223.899476) (xy 96.171766 -223.903794)
			(xy 95.967042 -224.258632) (xy 95.974916 -224.280476) (xy 95.98349 -224.306896) (xy 95.99269 -224.36167)
			(xy 95.993204 -224.389442) (xy 96.274128 -224.389442) (xy 96.274636 -224.363555) (xy 96.282735 -224.312417)
			(xy 96.298734 -224.263177) (xy 96.32224 -224.217045) (xy 96.352672 -224.175158) (xy 96.389282 -224.138548)
			(xy 96.431169 -224.108116) (xy 96.477301 -224.08461) (xy 96.526541 -224.068611) (xy 96.577679 -224.060512)
			(xy 96.629453 -224.060512) (xy 96.680591 -224.068611) (xy 96.729831 -224.08461) (xy 96.775963 -224.108116)
			(xy 96.81785 -224.138548) (xy 96.85446 -224.175158) (xy 96.884892 -224.217045) (xy 96.908398 -224.263177)
			(xy 96.924397 -224.312417) (xy 96.932496 -224.363555) (xy 96.933004 -224.389442) (xy 97.213928 -224.389442)
			(xy 97.214335 -224.364105) (xy 97.222097 -224.314028) (xy 97.237429 -224.265728) (xy 97.25997 -224.220343)
			(xy 97.289189 -224.17894) (xy 97.324399 -224.142496) (xy 97.36477 -224.111867) (xy 97.409352 -224.087776)
			(xy 97.457095 -224.070789) (xy 97.481898 -224.065592) (xy 97.504758 -224.061274) (xy 97.709482 -223.706436)
			(xy 97.701862 -223.684338) (xy 97.693231 -223.657991) (xy 97.68391 -223.603344) (xy 97.68332 -223.575626)
			(xy 97.683828 -223.549719) (xy 97.691934 -223.498542) (xy 97.707946 -223.449263) (xy 97.731469 -223.403096)
			(xy 97.761925 -223.361177) (xy 97.798563 -223.324539) (xy 97.840482 -223.294083) (xy 97.886649 -223.27056)
			(xy 97.935928 -223.254548) (xy 97.987105 -223.246442) (xy 98.038919 -223.246442) (xy 98.090096 -223.254548)
			(xy 98.139375 -223.27056) (xy 98.185542 -223.294083) (xy 98.227461 -223.324539) (xy 98.264099 -223.361177)
			(xy 98.294555 -223.403096) (xy 98.318078 -223.449263) (xy 98.33409 -223.498542) (xy 98.342196 -223.549719)
			(xy 98.342704 -223.575626) (xy 98.342287 -223.600992) (xy 98.334534 -223.651127) (xy 98.319185 -223.69948)
			(xy 98.296603 -223.744908) (xy 98.267322 -223.786336) (xy 98.232034 -223.822783) (xy 98.191575 -223.853388)
			(xy 98.146901 -223.877427) (xy 98.099069 -223.894332) (xy 98.074226 -223.899476) (xy 98.051366 -223.903794)
			(xy 97.846642 -224.258632) (xy 97.854516 -224.280476) (xy 97.86309 -224.306896) (xy 97.87229 -224.36167)
			(xy 97.872804 -224.389442) (xy 98.153728 -224.389442) (xy 98.154236 -224.363555) (xy 98.162335 -224.312417)
			(xy 98.178334 -224.263177) (xy 98.20184 -224.217045) (xy 98.232272 -224.175158) (xy 98.268882 -224.138548)
			(xy 98.310769 -224.108116) (xy 98.356901 -224.08461) (xy 98.406141 -224.068611) (xy 98.457279 -224.060512)
			(xy 98.509053 -224.060512) (xy 98.560191 -224.068611) (xy 98.609431 -224.08461) (xy 98.655563 -224.108116)
			(xy 98.69745 -224.138548) (xy 98.73406 -224.175158) (xy 98.764492 -224.217045) (xy 98.787998 -224.263177)
			(xy 98.803997 -224.312417) (xy 98.812096 -224.363555) (xy 98.812604 -224.389442) (xy 99.093528 -224.389442)
			(xy 99.093935 -224.364105) (xy 99.101697 -224.314028) (xy 99.117029 -224.265728) (xy 99.13957 -224.220343)
			(xy 99.168789 -224.17894) (xy 99.203999 -224.142496) (xy 99.24437 -224.111867) (xy 99.288952 -224.087776)
			(xy 99.336695 -224.070789) (xy 99.361498 -224.065592) (xy 99.384358 -224.061274) (xy 99.589082 -223.706436)
			(xy 99.581462 -223.684338) (xy 99.572831 -223.657991) (xy 99.56351 -223.603344) (xy 99.56292 -223.575626)
			(xy 99.563428 -223.549719) (xy 99.571534 -223.498542) (xy 99.587546 -223.449263) (xy 99.611069 -223.403096)
			(xy 99.641525 -223.361177) (xy 99.678163 -223.324539) (xy 99.720082 -223.294083) (xy 99.766249 -223.27056)
			(xy 99.815528 -223.254548) (xy 99.866705 -223.246442) (xy 99.918519 -223.246442) (xy 99.969696 -223.254548)
			(xy 100.018975 -223.27056) (xy 100.065142 -223.294083) (xy 100.107061 -223.324539) (xy 100.143699 -223.361177)
			(xy 100.174155 -223.403096) (xy 100.197678 -223.449263) (xy 100.21369 -223.498542) (xy 100.221796 -223.549719)
			(xy 100.222304 -223.575626) (xy 100.221887 -223.600992) (xy 100.214134 -223.651127) (xy 100.198785 -223.69948)
			(xy 100.176203 -223.744908) (xy 100.146922 -223.786336) (xy 100.111634 -223.822783) (xy 100.071175 -223.853388)
			(xy 100.026501 -223.877427) (xy 99.978669 -223.894332) (xy 99.953826 -223.899476) (xy 99.930966 -223.903794)
			(xy 99.726242 -224.258632) (xy 99.734116 -224.280476) (xy 99.74269 -224.306896) (xy 99.75189 -224.36167)
			(xy 99.752404 -224.389442) (xy 100.033328 -224.389442) (xy 100.033836 -224.363555) (xy 100.041935 -224.312417)
			(xy 100.057934 -224.263177) (xy 100.08144 -224.217045) (xy 100.111872 -224.175158) (xy 100.148482 -224.138548)
			(xy 100.190369 -224.108116) (xy 100.236501 -224.08461) (xy 100.285741 -224.068611) (xy 100.336879 -224.060512)
			(xy 100.388653 -224.060512) (xy 100.439791 -224.068611) (xy 100.489031 -224.08461) (xy 100.535163 -224.108116)
			(xy 100.57705 -224.138548) (xy 100.61366 -224.175158) (xy 100.644092 -224.217045) (xy 100.667598 -224.263177)
			(xy 100.683597 -224.312417) (xy 100.691696 -224.363555) (xy 100.692204 -224.389442) (xy 100.973128 -224.389442)
			(xy 100.973535 -224.364105) (xy 100.981297 -224.314028) (xy 100.996629 -224.265728) (xy 101.01917 -224.220343)
			(xy 101.048389 -224.17894) (xy 101.083599 -224.142496) (xy 101.12397 -224.111867) (xy 101.168552 -224.087776)
			(xy 101.216295 -224.070789) (xy 101.241098 -224.065592) (xy 101.263958 -224.061274) (xy 101.468682 -223.706436)
			(xy 101.461062 -223.684338) (xy 101.452431 -223.657991) (xy 101.44311 -223.603344) (xy 101.44252 -223.575626)
			(xy 101.443028 -223.549719) (xy 101.451134 -223.498542) (xy 101.467146 -223.449263) (xy 101.490669 -223.403096)
			(xy 101.521125 -223.361177) (xy 101.557763 -223.324539) (xy 101.599682 -223.294083) (xy 101.645849 -223.27056)
			(xy 101.695128 -223.254548) (xy 101.746305 -223.246442) (xy 101.798119 -223.246442) (xy 101.849296 -223.254548)
			(xy 101.898575 -223.27056) (xy 101.944742 -223.294083) (xy 101.986661 -223.324539) (xy 102.023299 -223.361177)
			(xy 102.053755 -223.403096) (xy 102.077278 -223.449263) (xy 102.09329 -223.498542) (xy 102.101396 -223.549719)
			(xy 102.101904 -223.575626) (xy 102.101487 -223.600992) (xy 102.093734 -223.651127) (xy 102.078385 -223.69948)
			(xy 102.055803 -223.744908) (xy 102.026522 -223.786336) (xy 101.991234 -223.822783) (xy 101.950775 -223.853388)
			(xy 101.906101 -223.877427) (xy 101.858269 -223.894332) (xy 101.833426 -223.899476) (xy 101.810566 -223.903794)
			(xy 101.605842 -224.258632) (xy 101.613716 -224.280476) (xy 101.62229 -224.306896) (xy 101.63149 -224.36167)
			(xy 101.632004 -224.389442) (xy 101.912928 -224.389442) (xy 101.913436 -224.363555) (xy 101.921535 -224.312417)
			(xy 101.937534 -224.263177) (xy 101.96104 -224.217045) (xy 101.991472 -224.175158) (xy 102.028082 -224.138548)
			(xy 102.069969 -224.108116) (xy 102.116101 -224.08461) (xy 102.165341 -224.068611) (xy 102.216479 -224.060512)
			(xy 102.268253 -224.060512) (xy 102.319391 -224.068611) (xy 102.368631 -224.08461) (xy 102.414763 -224.108116)
			(xy 102.45665 -224.138548) (xy 102.49326 -224.175158) (xy 102.523692 -224.217045) (xy 102.547198 -224.263177)
			(xy 102.563197 -224.312417) (xy 102.571296 -224.363555) (xy 102.571804 -224.389442) (xy 102.852728 -224.389442)
			(xy 102.853135 -224.364105) (xy 102.860897 -224.314028) (xy 102.876229 -224.265728) (xy 102.89877 -224.220343)
			(xy 102.927989 -224.17894) (xy 102.963199 -224.142496) (xy 103.00357 -224.111867) (xy 103.048152 -224.087776)
			(xy 103.095895 -224.070789) (xy 103.120698 -224.065592) (xy 103.143558 -224.061274) (xy 103.348282 -223.706436)
			(xy 103.340662 -223.684338) (xy 103.332031 -223.657991) (xy 103.32271 -223.603344) (xy 103.32212 -223.575626)
			(xy 103.322628 -223.549719) (xy 103.330734 -223.498542) (xy 103.346746 -223.449263) (xy 103.370269 -223.403096)
			(xy 103.400725 -223.361177) (xy 103.437363 -223.324539) (xy 103.479282 -223.294083) (xy 103.525449 -223.27056)
			(xy 103.574728 -223.254548) (xy 103.625905 -223.246442) (xy 103.677719 -223.246442) (xy 103.728896 -223.254548)
			(xy 103.778175 -223.27056) (xy 103.824342 -223.294083) (xy 103.866261 -223.324539) (xy 103.902899 -223.361177)
			(xy 103.933355 -223.403096) (xy 103.956878 -223.449263) (xy 103.97289 -223.498542) (xy 103.980996 -223.549719)
			(xy 103.981504 -223.575626) (xy 103.981087 -223.600992) (xy 103.973334 -223.651127) (xy 103.957985 -223.69948)
			(xy 103.935403 -223.744908) (xy 103.906122 -223.786336) (xy 103.870834 -223.822783) (xy 103.830375 -223.853388)
			(xy 103.785701 -223.877427) (xy 103.737869 -223.894332) (xy 103.713026 -223.899476) (xy 103.690166 -223.903794)
			(xy 103.485442 -224.258632) (xy 103.493316 -224.280476) (xy 103.50189 -224.306896) (xy 103.51109 -224.36167)
			(xy 103.511604 -224.389442) (xy 103.792528 -224.389442) (xy 103.793036 -224.363555) (xy 103.801135 -224.312417)
			(xy 103.817134 -224.263177) (xy 103.84064 -224.217045) (xy 103.871072 -224.175158) (xy 103.907682 -224.138548)
			(xy 103.949569 -224.108116) (xy 103.995701 -224.08461) (xy 104.044941 -224.068611) (xy 104.096079 -224.060512)
			(xy 104.147853 -224.060512) (xy 104.198991 -224.068611) (xy 104.248231 -224.08461) (xy 104.294363 -224.108116)
			(xy 104.33625 -224.138548) (xy 104.37286 -224.175158) (xy 104.403292 -224.217045) (xy 104.426798 -224.263177)
			(xy 104.442797 -224.312417) (xy 104.450896 -224.363555) (xy 104.451404 -224.389442) (xy 104.732328 -224.389442)
			(xy 104.732735 -224.364105) (xy 104.740497 -224.314028) (xy 104.755829 -224.265728) (xy 104.77837 -224.220343)
			(xy 104.807589 -224.17894) (xy 104.842799 -224.142496) (xy 104.88317 -224.111867) (xy 104.927752 -224.087776)
			(xy 104.975495 -224.070789) (xy 105.000298 -224.065592) (xy 105.023158 -224.061274) (xy 105.227882 -223.706436)
			(xy 105.220262 -223.684338) (xy 105.211631 -223.657991) (xy 105.20231 -223.603344) (xy 105.20172 -223.575626)
			(xy 105.202228 -223.549719) (xy 105.210334 -223.498542) (xy 105.226346 -223.449263) (xy 105.249869 -223.403096)
			(xy 105.280325 -223.361177) (xy 105.316963 -223.324539) (xy 105.358882 -223.294083) (xy 105.405049 -223.27056)
			(xy 105.454328 -223.254548) (xy 105.505505 -223.246442) (xy 105.557319 -223.246442) (xy 105.608496 -223.254548)
			(xy 105.657775 -223.27056) (xy 105.703942 -223.294083) (xy 105.745861 -223.324539) (xy 105.782499 -223.361177)
			(xy 105.812955 -223.403096) (xy 105.836478 -223.449263) (xy 105.85249 -223.498542) (xy 105.860596 -223.549719)
			(xy 105.861104 -223.575626) (xy 105.860687 -223.600992) (xy 105.852934 -223.651127) (xy 105.837585 -223.69948)
			(xy 105.815003 -223.744908) (xy 105.785722 -223.786336) (xy 105.750434 -223.822783) (xy 105.709975 -223.853388)
			(xy 105.665301 -223.877427) (xy 105.617469 -223.894332) (xy 105.592626 -223.899476) (xy 105.569766 -223.903794)
			(xy 105.365042 -224.258632) (xy 105.372916 -224.280476) (xy 105.38149 -224.306896) (xy 105.39069 -224.36167)
			(xy 105.391204 -224.389442) (xy 105.672128 -224.389442) (xy 105.672636 -224.363555) (xy 105.680735 -224.312417)
			(xy 105.696734 -224.263177) (xy 105.72024 -224.217045) (xy 105.750672 -224.175158) (xy 105.787282 -224.138548)
			(xy 105.829169 -224.108116) (xy 105.875301 -224.08461) (xy 105.924541 -224.068611) (xy 105.975679 -224.060512)
			(xy 106.027453 -224.060512) (xy 106.078591 -224.068611) (xy 106.127831 -224.08461) (xy 106.173963 -224.108116)
			(xy 106.21585 -224.138548) (xy 106.25246 -224.175158) (xy 106.282892 -224.217045) (xy 106.306398 -224.263177)
			(xy 106.322397 -224.312417) (xy 106.330496 -224.363555) (xy 106.331004 -224.389442) (xy 106.611928 -224.389442)
			(xy 106.612335 -224.364105) (xy 106.620097 -224.314028) (xy 106.635429 -224.265728) (xy 106.65797 -224.220343)
			(xy 106.687189 -224.17894) (xy 106.722399 -224.142496) (xy 106.76277 -224.111867) (xy 106.807352 -224.087776)
			(xy 106.855095 -224.070789) (xy 106.879898 -224.065592) (xy 106.902758 -224.061274) (xy 107.107482 -223.706436)
			(xy 107.099862 -223.684338) (xy 107.091231 -223.657991) (xy 107.08191 -223.603344) (xy 107.08132 -223.575626)
			(xy 107.081828 -223.549719) (xy 107.089934 -223.498542) (xy 107.105946 -223.449263) (xy 107.129469 -223.403096)
			(xy 107.159925 -223.361177) (xy 107.196563 -223.324539) (xy 107.238482 -223.294083) (xy 107.284649 -223.27056)
			(xy 107.333928 -223.254548) (xy 107.385105 -223.246442) (xy 107.436919 -223.246442) (xy 107.488096 -223.254548)
			(xy 107.537375 -223.27056) (xy 107.583542 -223.294083) (xy 107.625461 -223.324539) (xy 107.662099 -223.361177)
			(xy 107.692555 -223.403096) (xy 107.716078 -223.449263) (xy 107.73209 -223.498542) (xy 107.740196 -223.549719)
			(xy 107.740704 -223.575626) (xy 107.740287 -223.600992) (xy 107.732534 -223.651127) (xy 107.717185 -223.69948)
			(xy 107.694603 -223.744908) (xy 107.665322 -223.786336) (xy 107.630034 -223.822783) (xy 107.589575 -223.853388)
			(xy 107.544901 -223.877427) (xy 107.497069 -223.894332) (xy 107.472226 -223.899476) (xy 107.449366 -223.903794)
			(xy 107.244642 -224.258632) (xy 107.252516 -224.280476) (xy 107.26109 -224.306896) (xy 107.27029 -224.36167)
			(xy 107.270804 -224.389442) (xy 107.551728 -224.389442) (xy 107.552236 -224.363555) (xy 107.560335 -224.312417)
			(xy 107.576334 -224.263177) (xy 107.59984 -224.217045) (xy 107.630272 -224.175158) (xy 107.666882 -224.138548)
			(xy 107.708769 -224.108116) (xy 107.754901 -224.08461) (xy 107.804141 -224.068611) (xy 107.855279 -224.060512)
			(xy 107.907053 -224.060512) (xy 107.958191 -224.068611) (xy 108.007431 -224.08461) (xy 108.053563 -224.108116)
			(xy 108.09545 -224.138548) (xy 108.13206 -224.175158) (xy 108.162492 -224.217045) (xy 108.185998 -224.263177)
			(xy 108.201997 -224.312417) (xy 108.210096 -224.363555) (xy 108.210604 -224.389442) (xy 108.491528 -224.389442)
			(xy 108.491935 -224.364105) (xy 108.499697 -224.314028) (xy 108.515029 -224.265728) (xy 108.53757 -224.220343)
			(xy 108.566789 -224.17894) (xy 108.601999 -224.142496) (xy 108.64237 -224.111867) (xy 108.686952 -224.087776)
			(xy 108.734695 -224.070789) (xy 108.759498 -224.065592) (xy 108.782358 -224.061274) (xy 108.987082 -223.706436)
			(xy 108.979462 -223.684338) (xy 108.970831 -223.657991) (xy 108.96151 -223.603344) (xy 108.96092 -223.575626)
			(xy 108.961428 -223.549719) (xy 108.969534 -223.498542) (xy 108.985546 -223.449263) (xy 109.009069 -223.403096)
			(xy 109.039525 -223.361177) (xy 109.076163 -223.324539) (xy 109.118082 -223.294083) (xy 109.164249 -223.27056)
			(xy 109.213528 -223.254548) (xy 109.264705 -223.246442) (xy 109.316519 -223.246442) (xy 109.367696 -223.254548)
			(xy 109.416975 -223.27056) (xy 109.463142 -223.294083) (xy 109.505061 -223.324539) (xy 109.541699 -223.361177)
			(xy 109.572155 -223.403096) (xy 109.595678 -223.449263) (xy 109.61169 -223.498542) (xy 109.619796 -223.549719)
			(xy 109.620304 -223.575626) (xy 109.619887 -223.600992) (xy 109.612134 -223.651127) (xy 109.596785 -223.69948)
			(xy 109.574203 -223.744908) (xy 109.544922 -223.786336) (xy 109.509634 -223.822783) (xy 109.469175 -223.853388)
			(xy 109.424501 -223.877427) (xy 109.376669 -223.894332) (xy 109.351826 -223.899476) (xy 109.328966 -223.903794)
			(xy 109.124242 -224.258632) (xy 109.132116 -224.280476) (xy 109.14069 -224.306896) (xy 109.14989 -224.36167)
			(xy 109.150404 -224.389442) (xy 109.431328 -224.389442) (xy 109.431836 -224.363555) (xy 109.439935 -224.312417)
			(xy 109.455934 -224.263177) (xy 109.47944 -224.217045) (xy 109.509872 -224.175158) (xy 109.546482 -224.138548)
			(xy 109.588369 -224.108116) (xy 109.634501 -224.08461) (xy 109.683741 -224.068611) (xy 109.734879 -224.060512)
			(xy 109.786653 -224.060512) (xy 109.837791 -224.068611) (xy 109.887031 -224.08461) (xy 109.933163 -224.108116)
			(xy 109.97505 -224.138548) (xy 110.01166 -224.175158) (xy 110.042092 -224.217045) (xy 110.065598 -224.263177)
			(xy 110.081597 -224.312417) (xy 110.089696 -224.363555) (xy 110.090204 -224.389442) (xy 110.371128 -224.389442)
			(xy 110.371535 -224.364105) (xy 110.379297 -224.314028) (xy 110.394629 -224.265728) (xy 110.41717 -224.220343)
			(xy 110.446389 -224.17894) (xy 110.481599 -224.142496) (xy 110.52197 -224.111867) (xy 110.566552 -224.087776)
			(xy 110.614295 -224.070789) (xy 110.639098 -224.065592) (xy 110.661958 -224.061274) (xy 110.866682 -223.706436)
			(xy 110.859062 -223.684338) (xy 110.850431 -223.657991) (xy 110.84111 -223.603344) (xy 110.84052 -223.575626)
			(xy 110.841028 -223.549719) (xy 110.849134 -223.498542) (xy 110.865146 -223.449263) (xy 110.888669 -223.403096)
			(xy 110.919125 -223.361177) (xy 110.955763 -223.324539) (xy 110.997682 -223.294083) (xy 111.043849 -223.27056)
			(xy 111.093128 -223.254548) (xy 111.144305 -223.246442) (xy 111.196119 -223.246442) (xy 111.247296 -223.254548)
			(xy 111.296575 -223.27056) (xy 111.342742 -223.294083) (xy 111.384661 -223.324539) (xy 111.421299 -223.361177)
			(xy 111.451755 -223.403096) (xy 111.475278 -223.449263) (xy 111.49129 -223.498542) (xy 111.499396 -223.549719)
			(xy 111.499904 -223.575626) (xy 111.499487 -223.600992) (xy 111.491734 -223.651127) (xy 111.476385 -223.69948)
			(xy 111.453803 -223.744908) (xy 111.424522 -223.786336) (xy 111.389234 -223.822783) (xy 111.348775 -223.853388)
			(xy 111.304101 -223.877427) (xy 111.256269 -223.894332) (xy 111.231426 -223.899476) (xy 111.208566 -223.903794)
			(xy 111.003842 -224.258632) (xy 111.011716 -224.280476) (xy 111.02029 -224.306896) (xy 111.02949 -224.36167)
			(xy 111.030004 -224.389442) (xy 111.310928 -224.389442) (xy 111.311436 -224.363555) (xy 111.319535 -224.312417)
			(xy 111.335534 -224.263177) (xy 111.35904 -224.217045) (xy 111.389472 -224.175158) (xy 111.426082 -224.138548)
			(xy 111.467969 -224.108116) (xy 111.514101 -224.08461) (xy 111.563341 -224.068611) (xy 111.614479 -224.060512)
			(xy 111.666253 -224.060512) (xy 111.717391 -224.068611) (xy 111.766631 -224.08461) (xy 111.812763 -224.108116)
			(xy 111.85465 -224.138548) (xy 111.89126 -224.175158) (xy 111.921692 -224.217045) (xy 111.945198 -224.263177)
			(xy 111.961197 -224.312417) (xy 111.969296 -224.363555) (xy 111.969804 -224.389442) (xy 112.250728 -224.389442)
			(xy 112.251135 -224.364105) (xy 112.258897 -224.314028) (xy 112.274229 -224.265728) (xy 112.29677 -224.220343)
			(xy 112.325989 -224.17894) (xy 112.361199 -224.142496) (xy 112.40157 -224.111867) (xy 112.446152 -224.087776)
			(xy 112.493895 -224.070789) (xy 112.518698 -224.065592) (xy 112.541558 -224.061274) (xy 112.746282 -223.706436)
			(xy 112.738662 -223.684338) (xy 112.730031 -223.657991) (xy 112.72071 -223.603344) (xy 112.72012 -223.575626)
			(xy 112.720628 -223.549719) (xy 112.728734 -223.498542) (xy 112.744746 -223.449263) (xy 112.768269 -223.403096)
			(xy 112.798725 -223.361177) (xy 112.835363 -223.324539) (xy 112.877282 -223.294083) (xy 112.923449 -223.27056)
			(xy 112.972728 -223.254548) (xy 113.023905 -223.246442) (xy 113.075719 -223.246442) (xy 113.126896 -223.254548)
			(xy 113.176175 -223.27056) (xy 113.222342 -223.294083) (xy 113.264261 -223.324539) (xy 113.300899 -223.361177)
			(xy 113.331355 -223.403096) (xy 113.354878 -223.449263) (xy 113.37089 -223.498542) (xy 113.378996 -223.549719)
			(xy 113.379504 -223.575626) (xy 113.379087 -223.600992) (xy 113.371334 -223.651127) (xy 113.355985 -223.69948)
			(xy 113.333403 -223.744908) (xy 113.304122 -223.786336) (xy 113.268834 -223.822783) (xy 113.228375 -223.853388)
			(xy 113.183701 -223.877427) (xy 113.135869 -223.894332) (xy 113.111026 -223.899476) (xy 113.088166 -223.903794)
			(xy 112.883442 -224.258632) (xy 112.891316 -224.280476) (xy 112.89989 -224.306896) (xy 112.90909 -224.36167)
			(xy 112.909604 -224.389442) (xy 113.190528 -224.389442) (xy 113.191036 -224.363555) (xy 113.199135 -224.312417)
			(xy 113.215134 -224.263177) (xy 113.23864 -224.217045) (xy 113.269072 -224.175158) (xy 113.305682 -224.138548)
			(xy 113.347569 -224.108116) (xy 113.393701 -224.08461) (xy 113.442941 -224.068611) (xy 113.494079 -224.060512)
			(xy 113.545853 -224.060512) (xy 113.596991 -224.068611) (xy 113.646231 -224.08461) (xy 113.692363 -224.108116)
			(xy 113.73425 -224.138548) (xy 113.77086 -224.175158) (xy 113.801292 -224.217045) (xy 113.824798 -224.263177)
			(xy 113.840797 -224.312417) (xy 113.848896 -224.363555) (xy 113.849404 -224.389442) (xy 114.130328 -224.389442)
			(xy 114.130735 -224.364105) (xy 114.138497 -224.314028) (xy 114.153829 -224.265728) (xy 114.17637 -224.220343)
			(xy 114.205589 -224.17894) (xy 114.240799 -224.142496) (xy 114.28117 -224.111867) (xy 114.325752 -224.087776)
			(xy 114.373495 -224.070789) (xy 114.398298 -224.065592) (xy 114.421158 -224.061274) (xy 114.626136 -223.706182)
			(xy 114.618516 -223.684084) (xy 114.609997 -223.657912) (xy 114.600803 -223.603651) (xy 114.600228 -223.576134)
			(xy 114.600228 -223.575626) (xy 114.600736 -223.549739) (xy 114.608835 -223.498601) (xy 114.624834 -223.449361)
			(xy 114.64834 -223.403229) (xy 114.678772 -223.361342) (xy 114.715382 -223.324732) (xy 114.757269 -223.2943)
			(xy 114.803401 -223.270794) (xy 114.852641 -223.254795) (xy 114.903779 -223.246696) (xy 114.955553 -223.246696)
			(xy 115.006691 -223.254795) (xy 115.055931 -223.270794) (xy 115.102063 -223.2943) (xy 115.14395 -223.324732)
			(xy 115.18056 -223.361342) (xy 115.210992 -223.403229) (xy 115.234498 -223.449361) (xy 115.250497 -223.498601)
			(xy 115.258596 -223.549739) (xy 115.259104 -223.575626) (xy 115.258687 -223.600992) (xy 115.250934 -223.651127)
			(xy 115.235585 -223.69948) (xy 115.213003 -223.744908) (xy 115.183722 -223.786336) (xy 115.148434 -223.822783)
			(xy 115.107975 -223.853388) (xy 115.063301 -223.877427) (xy 115.015469 -223.894332) (xy 114.990626 -223.899476)
			(xy 114.967766 -223.903794) (xy 114.763042 -224.258632) (xy 114.770916 -224.280476) (xy 114.77949 -224.306896)
			(xy 114.78869 -224.36167) (xy 114.789204 -224.389442) (xy 115.070128 -224.389442) (xy 115.070636 -224.363555)
			(xy 115.078735 -224.312417) (xy 115.094734 -224.263177) (xy 115.11824 -224.217045) (xy 115.148672 -224.175158)
			(xy 115.185282 -224.138548) (xy 115.227169 -224.108116) (xy 115.273301 -224.08461) (xy 115.322541 -224.068611)
			(xy 115.373679 -224.060512) (xy 115.425453 -224.060512) (xy 115.476591 -224.068611) (xy 115.525831 -224.08461)
			(xy 115.571963 -224.108116) (xy 115.61385 -224.138548) (xy 115.65046 -224.175158) (xy 115.680892 -224.217045)
			(xy 115.704398 -224.263177) (xy 115.720397 -224.312417) (xy 115.728496 -224.363555) (xy 115.729004 -224.389442)
			(xy 116.009928 -224.389442) (xy 116.010335 -224.364105) (xy 116.018097 -224.314028) (xy 116.033429 -224.265728)
			(xy 116.05597 -224.220343) (xy 116.085189 -224.17894) (xy 116.120399 -224.142496) (xy 116.16077 -224.111867)
			(xy 116.205352 -224.087776) (xy 116.253095 -224.070789) (xy 116.277898 -224.065592) (xy 116.300758 -224.061274)
			(xy 116.505482 -223.706436) (xy 116.497862 -223.684338) (xy 116.489231 -223.657991) (xy 116.47991 -223.603344)
			(xy 116.47932 -223.575626) (xy 116.479828 -223.549719) (xy 116.487934 -223.498542) (xy 116.503946 -223.449263)
			(xy 116.527469 -223.403096) (xy 116.557925 -223.361177) (xy 116.594563 -223.324539) (xy 116.636482 -223.294083)
			(xy 116.682649 -223.27056) (xy 116.731928 -223.254548) (xy 116.783105 -223.246442) (xy 116.834919 -223.246442)
			(xy 116.886096 -223.254548) (xy 116.935375 -223.27056) (xy 116.981542 -223.294083) (xy 117.023461 -223.324539)
			(xy 117.060099 -223.361177) (xy 117.090555 -223.403096) (xy 117.114078 -223.449263) (xy 117.13009 -223.498542)
			(xy 117.138196 -223.549719) (xy 117.138704 -223.575626) (xy 117.138287 -223.600992) (xy 117.130534 -223.651127)
			(xy 117.115185 -223.69948) (xy 117.092603 -223.744908) (xy 117.063322 -223.786336) (xy 117.028034 -223.822783)
			(xy 116.987575 -223.853388) (xy 116.942901 -223.877427) (xy 116.895069 -223.894332) (xy 116.870226 -223.899476)
			(xy 116.847366 -223.903794) (xy 116.642642 -224.258632) (xy 116.650516 -224.280476) (xy 116.65909 -224.306896)
			(xy 116.66829 -224.36167) (xy 116.668804 -224.389442) (xy 116.949728 -224.389442) (xy 116.950236 -224.363555)
			(xy 116.958335 -224.312417) (xy 116.974334 -224.263177) (xy 116.99784 -224.217045) (xy 117.028272 -224.175158)
			(xy 117.064882 -224.138548) (xy 117.106769 -224.108116) (xy 117.152901 -224.08461) (xy 117.202141 -224.068611)
			(xy 117.253279 -224.060512) (xy 117.305053 -224.060512) (xy 117.356191 -224.068611) (xy 117.405431 -224.08461)
			(xy 117.451563 -224.108116) (xy 117.49345 -224.138548) (xy 117.53006 -224.175158) (xy 117.560492 -224.217045)
			(xy 117.583998 -224.263177) (xy 117.599997 -224.312417) (xy 117.608096 -224.363555) (xy 117.608604 -224.389442)
			(xy 117.889528 -224.389442) (xy 117.889935 -224.364105) (xy 117.897697 -224.314028) (xy 117.913029 -224.265728)
			(xy 117.93557 -224.220343) (xy 117.964789 -224.17894) (xy 117.999999 -224.142496) (xy 118.04037 -224.111867)
			(xy 118.084952 -224.087776) (xy 118.132695 -224.070789) (xy 118.157498 -224.065592) (xy 118.180358 -224.061274)
			(xy 118.385082 -223.706436) (xy 118.377462 -223.684338) (xy 118.368831 -223.657991) (xy 118.35951 -223.603344)
			(xy 118.35892 -223.575626) (xy 118.359428 -223.549719) (xy 118.367534 -223.498542) (xy 118.383546 -223.449263)
			(xy 118.407069 -223.403096) (xy 118.437525 -223.361177) (xy 118.474163 -223.324539) (xy 118.516082 -223.294083)
			(xy 118.562249 -223.27056) (xy 118.611528 -223.254548) (xy 118.662705 -223.246442) (xy 118.714519 -223.246442)
			(xy 118.765696 -223.254548) (xy 118.814975 -223.27056) (xy 118.861142 -223.294083) (xy 118.903061 -223.324539)
			(xy 118.939699 -223.361177) (xy 118.970155 -223.403096) (xy 118.993678 -223.449263) (xy 119.00969 -223.498542)
			(xy 119.017796 -223.549719) (xy 119.018304 -223.575626) (xy 119.017887 -223.600992) (xy 119.010134 -223.651127)
			(xy 118.994785 -223.69948) (xy 118.972203 -223.744908) (xy 118.942922 -223.786336) (xy 118.907634 -223.822783)
			(xy 118.867175 -223.853388) (xy 118.822501 -223.877427) (xy 118.774669 -223.894332) (xy 118.749826 -223.899476)
			(xy 118.726966 -223.903794) (xy 118.522242 -224.258632) (xy 118.530116 -224.280476) (xy 118.53869 -224.306896)
			(xy 118.54789 -224.36167) (xy 118.548404 -224.389442) (xy 118.829328 -224.389442) (xy 118.829836 -224.363555)
			(xy 118.837935 -224.312417) (xy 118.853934 -224.263177) (xy 118.87744 -224.217045) (xy 118.907872 -224.175158)
			(xy 118.944482 -224.138548) (xy 118.986369 -224.108116) (xy 119.032501 -224.08461) (xy 119.081741 -224.068611)
			(xy 119.132879 -224.060512) (xy 119.184653 -224.060512) (xy 119.235791 -224.068611) (xy 119.285031 -224.08461)
			(xy 119.331163 -224.108116) (xy 119.37305 -224.138548) (xy 119.40966 -224.175158) (xy 119.440092 -224.217045)
			(xy 119.463598 -224.263177) (xy 119.479597 -224.312417) (xy 119.487696 -224.363555) (xy 119.488204 -224.389442)
			(xy 119.769128 -224.389442) (xy 119.769535 -224.364105) (xy 119.777297 -224.314028) (xy 119.792629 -224.265728)
			(xy 119.81517 -224.220343) (xy 119.844389 -224.17894) (xy 119.879599 -224.142496) (xy 119.91997 -224.111867)
			(xy 119.964552 -224.087776) (xy 120.012295 -224.070789) (xy 120.037098 -224.065592) (xy 120.059958 -224.061274)
			(xy 120.264682 -223.706436) (xy 120.257062 -223.684338) (xy 120.248431 -223.657991) (xy 120.23911 -223.603344)
			(xy 120.23852 -223.575626) (xy 120.239028 -223.549719) (xy 120.247134 -223.498542) (xy 120.263146 -223.449263)
			(xy 120.286669 -223.403096) (xy 120.317125 -223.361177) (xy 120.353763 -223.324539) (xy 120.395682 -223.294083)
			(xy 120.441849 -223.27056) (xy 120.491128 -223.254548) (xy 120.542305 -223.246442) (xy 120.594119 -223.246442)
			(xy 120.645296 -223.254548) (xy 120.694575 -223.27056) (xy 120.740742 -223.294083) (xy 120.782661 -223.324539)
			(xy 120.819299 -223.361177) (xy 120.849755 -223.403096) (xy 120.873278 -223.449263) (xy 120.88929 -223.498542)
			(xy 120.897396 -223.549719) (xy 120.897904 -223.575626) (xy 120.897487 -223.600992) (xy 120.889734 -223.651127)
			(xy 120.874385 -223.69948) (xy 120.851803 -223.744908) (xy 120.822522 -223.786336) (xy 120.787234 -223.822783)
			(xy 120.746775 -223.853388) (xy 120.702101 -223.877427) (xy 120.654269 -223.894332) (xy 120.629426 -223.899476)
			(xy 120.606566 -223.903794) (xy 120.401842 -224.258632) (xy 120.409716 -224.280476) (xy 120.41829 -224.306896)
			(xy 120.42749 -224.36167) (xy 120.428004 -224.389442) (xy 120.708928 -224.389442) (xy 120.709436 -224.363555)
			(xy 120.717535 -224.312417) (xy 120.733534 -224.263177) (xy 120.75704 -224.217045) (xy 120.787472 -224.175158)
			(xy 120.824082 -224.138548) (xy 120.865969 -224.108116) (xy 120.912101 -224.08461) (xy 120.961341 -224.068611)
			(xy 121.012479 -224.060512) (xy 121.064253 -224.060512) (xy 121.115391 -224.068611) (xy 121.164631 -224.08461)
			(xy 121.210763 -224.108116) (xy 121.25265 -224.138548) (xy 121.28926 -224.175158) (xy 121.319692 -224.217045)
			(xy 121.343198 -224.263177) (xy 121.359197 -224.312417) (xy 121.367296 -224.363555) (xy 121.367804 -224.389442)
			(xy 121.648728 -224.389442) (xy 121.649135 -224.364105) (xy 121.656897 -224.314028) (xy 121.672229 -224.265728)
			(xy 121.69477 -224.220343) (xy 121.723989 -224.17894) (xy 121.759199 -224.142496) (xy 121.79957 -224.111867)
			(xy 121.844152 -224.087776) (xy 121.891895 -224.070789) (xy 121.916698 -224.065592) (xy 121.939558 -224.061274)
			(xy 122.144282 -223.706436) (xy 122.136662 -223.684338) (xy 122.128031 -223.657991) (xy 122.11871 -223.603344)
			(xy 122.11812 -223.575626) (xy 122.118628 -223.549719) (xy 122.126734 -223.498542) (xy 122.142746 -223.449263)
			(xy 122.166269 -223.403096) (xy 122.196725 -223.361177) (xy 122.233363 -223.324539) (xy 122.275282 -223.294083)
			(xy 122.321449 -223.27056) (xy 122.370728 -223.254548) (xy 122.421905 -223.246442) (xy 122.473719 -223.246442)
			(xy 122.524896 -223.254548) (xy 122.574175 -223.27056) (xy 122.620342 -223.294083) (xy 122.662261 -223.324539)
			(xy 122.698899 -223.361177) (xy 122.729355 -223.403096) (xy 122.752878 -223.449263) (xy 122.76889 -223.498542)
			(xy 122.776996 -223.549719) (xy 122.777504 -223.575626) (xy 122.777087 -223.600992) (xy 122.769334 -223.651127)
			(xy 122.753985 -223.69948) (xy 122.731403 -223.744908) (xy 122.702122 -223.786336) (xy 122.666834 -223.822783)
			(xy 122.626375 -223.853388) (xy 122.581701 -223.877427) (xy 122.533869 -223.894332) (xy 122.509026 -223.899476)
			(xy 122.486166 -223.903794) (xy 122.281442 -224.258632) (xy 122.289316 -224.280476) (xy 122.29789 -224.306896)
			(xy 122.30709 -224.36167) (xy 122.307604 -224.389442) (xy 122.588528 -224.389442) (xy 122.589036 -224.363555)
			(xy 122.597135 -224.312417) (xy 122.613134 -224.263177) (xy 122.63664 -224.217045) (xy 122.667072 -224.175158)
			(xy 122.703682 -224.138548) (xy 122.745569 -224.108116) (xy 122.791701 -224.08461) (xy 122.840941 -224.068611)
			(xy 122.892079 -224.060512) (xy 122.943853 -224.060512) (xy 122.994991 -224.068611) (xy 123.044231 -224.08461)
			(xy 123.090363 -224.108116) (xy 123.13225 -224.138548) (xy 123.16886 -224.175158) (xy 123.199292 -224.217045)
			(xy 123.222798 -224.263177) (xy 123.238797 -224.312417) (xy 123.246896 -224.363555) (xy 123.247404 -224.389442)
			(xy 123.528328 -224.389442) (xy 123.528735 -224.364105) (xy 123.536497 -224.314028) (xy 123.551829 -224.265728)
			(xy 123.57437 -224.220343) (xy 123.603589 -224.17894) (xy 123.638799 -224.142496) (xy 123.67917 -224.111867)
			(xy 123.723752 -224.087776) (xy 123.771495 -224.070789) (xy 123.796298 -224.065592) (xy 123.819158 -224.061274)
			(xy 124.023882 -223.706436) (xy 124.016262 -223.684338) (xy 124.007631 -223.657991) (xy 123.99831 -223.603344)
			(xy 123.99772 -223.575626) (xy 123.998228 -223.549719) (xy 124.006334 -223.498542) (xy 124.022346 -223.449263)
			(xy 124.045869 -223.403096) (xy 124.076325 -223.361177) (xy 124.112963 -223.324539) (xy 124.154882 -223.294083)
			(xy 124.201049 -223.27056) (xy 124.250328 -223.254548) (xy 124.301505 -223.246442) (xy 124.353319 -223.246442)
			(xy 124.404496 -223.254548) (xy 124.453775 -223.27056) (xy 124.499942 -223.294083) (xy 124.541861 -223.324539)
			(xy 124.578499 -223.361177) (xy 124.608955 -223.403096) (xy 124.632478 -223.449263) (xy 124.64849 -223.498542)
			(xy 124.656596 -223.549719) (xy 124.657104 -223.575626) (xy 124.656687 -223.600992) (xy 124.648934 -223.651127)
			(xy 124.633585 -223.69948) (xy 124.611003 -223.744908) (xy 124.581722 -223.786336) (xy 124.546434 -223.822783)
			(xy 124.505975 -223.853388) (xy 124.461301 -223.877427) (xy 124.413469 -223.894332) (xy 124.388626 -223.899476)
			(xy 124.365766 -223.903794) (xy 124.161042 -224.258632) (xy 124.168916 -224.280476) (xy 124.17749 -224.306896)
			(xy 124.18669 -224.36167) (xy 124.187204 -224.389442) (xy 124.468128 -224.389442) (xy 124.468636 -224.363555)
			(xy 124.476735 -224.312417) (xy 124.492734 -224.263177) (xy 124.51624 -224.217045) (xy 124.546672 -224.175158)
			(xy 124.583282 -224.138548) (xy 124.625169 -224.108116) (xy 124.671301 -224.08461) (xy 124.720541 -224.068611)
			(xy 124.771679 -224.060512) (xy 124.823453 -224.060512) (xy 124.874591 -224.068611) (xy 124.923831 -224.08461)
			(xy 124.969963 -224.108116) (xy 125.01185 -224.138548) (xy 125.04846 -224.175158) (xy 125.078892 -224.217045)
			(xy 125.102398 -224.263177) (xy 125.118397 -224.312417) (xy 125.126496 -224.363555) (xy 125.127004 -224.389442)
			(xy 125.407928 -224.389442) (xy 125.408335 -224.364105) (xy 125.416097 -224.314028) (xy 125.431429 -224.265728)
			(xy 125.45397 -224.220343) (xy 125.483189 -224.17894) (xy 125.518399 -224.142496) (xy 125.55877 -224.111867)
			(xy 125.603352 -224.087776) (xy 125.651095 -224.070789) (xy 125.675898 -224.065592) (xy 125.698758 -224.061274)
			(xy 125.903482 -223.706436) (xy 125.895862 -223.684338) (xy 125.887231 -223.657991) (xy 125.87791 -223.603344)
			(xy 125.87732 -223.575626) (xy 125.877828 -223.549719) (xy 125.885934 -223.498542) (xy 125.901946 -223.449263)
			(xy 125.925469 -223.403096) (xy 125.955925 -223.361177) (xy 125.992563 -223.324539) (xy 126.034482 -223.294083)
			(xy 126.080649 -223.27056) (xy 126.129928 -223.254548) (xy 126.181105 -223.246442) (xy 126.232919 -223.246442)
			(xy 126.284096 -223.254548) (xy 126.333375 -223.27056) (xy 126.379542 -223.294083) (xy 126.421461 -223.324539)
			(xy 126.458099 -223.361177) (xy 126.488555 -223.403096) (xy 126.512078 -223.449263) (xy 126.52809 -223.498542)
			(xy 126.536196 -223.549719) (xy 126.536704 -223.575626) (xy 126.536287 -223.600992) (xy 126.528534 -223.651127)
			(xy 126.513185 -223.69948) (xy 126.490603 -223.744908) (xy 126.461322 -223.786336) (xy 126.426034 -223.822783)
			(xy 126.385575 -223.853388) (xy 126.340901 -223.877427) (xy 126.293069 -223.894332) (xy 126.268226 -223.899476)
			(xy 126.245366 -223.903794) (xy 126.040642 -224.258632) (xy 126.048516 -224.280476) (xy 126.05709 -224.306896)
			(xy 126.06629 -224.36167) (xy 126.066804 -224.389442) (xy 126.347728 -224.389442) (xy 126.348236 -224.363555)
			(xy 126.356335 -224.312417) (xy 126.372334 -224.263177) (xy 126.39584 -224.217045) (xy 126.426272 -224.175158)
			(xy 126.462882 -224.138548) (xy 126.504769 -224.108116) (xy 126.550901 -224.08461) (xy 126.600141 -224.068611)
			(xy 126.651279 -224.060512) (xy 126.703053 -224.060512) (xy 126.754191 -224.068611) (xy 126.803431 -224.08461)
			(xy 126.849563 -224.108116) (xy 126.89145 -224.138548) (xy 126.92806 -224.175158) (xy 126.958492 -224.217045)
			(xy 126.981998 -224.263177) (xy 126.997997 -224.312417) (xy 127.006096 -224.363555) (xy 127.006604 -224.389442)
			(xy 127.287528 -224.389442) (xy 127.287935 -224.364105) (xy 127.295697 -224.314028) (xy 127.311029 -224.265728)
			(xy 127.33357 -224.220343) (xy 127.362789 -224.17894) (xy 127.397999 -224.142496) (xy 127.43837 -224.111867)
			(xy 127.482952 -224.087776) (xy 127.530695 -224.070789) (xy 127.555498 -224.065592) (xy 127.578358 -224.061274)
			(xy 127.783082 -223.706436) (xy 127.775462 -223.684338) (xy 127.766831 -223.657991) (xy 127.75751 -223.603344)
			(xy 127.75692 -223.575626) (xy 127.757428 -223.549719) (xy 127.765534 -223.498542) (xy 127.781546 -223.449263)
			(xy 127.805069 -223.403096) (xy 127.835525 -223.361177) (xy 127.872163 -223.324539) (xy 127.914082 -223.294083)
			(xy 127.960249 -223.27056) (xy 128.009528 -223.254548) (xy 128.060705 -223.246442) (xy 128.112519 -223.246442)
			(xy 128.163696 -223.254548) (xy 128.212975 -223.27056) (xy 128.259142 -223.294083) (xy 128.301061 -223.324539)
			(xy 128.337699 -223.361177) (xy 128.368155 -223.403096) (xy 128.391678 -223.449263) (xy 128.40769 -223.498542)
			(xy 128.415796 -223.549719) (xy 128.416304 -223.575626) (xy 128.415887 -223.600992) (xy 128.408134 -223.651127)
			(xy 128.392785 -223.69948) (xy 128.370203 -223.744908) (xy 128.340922 -223.786336) (xy 128.305634 -223.822783)
			(xy 128.265175 -223.853388) (xy 128.220501 -223.877427) (xy 128.172669 -223.894332) (xy 128.147826 -223.899476)
			(xy 128.124966 -223.903794) (xy 127.920242 -224.258632) (xy 127.928116 -224.280476) (xy 127.93669 -224.306896)
			(xy 127.94589 -224.36167) (xy 127.946404 -224.389442) (xy 128.227328 -224.389442) (xy 128.227836 -224.363555)
			(xy 128.235935 -224.312417) (xy 128.251934 -224.263177) (xy 128.27544 -224.217045) (xy 128.305872 -224.175158)
			(xy 128.342482 -224.138548) (xy 128.384369 -224.108116) (xy 128.430501 -224.08461) (xy 128.479741 -224.068611)
			(xy 128.530879 -224.060512) (xy 128.582653 -224.060512) (xy 128.633791 -224.068611) (xy 128.683031 -224.08461)
			(xy 128.729163 -224.108116) (xy 128.77105 -224.138548) (xy 128.80766 -224.175158) (xy 128.838092 -224.217045)
			(xy 128.861598 -224.263177) (xy 128.877597 -224.312417) (xy 128.885696 -224.363555) (xy 128.886204 -224.389442)
			(xy 129.167128 -224.389442) (xy 129.167535 -224.364105) (xy 129.175297 -224.314028) (xy 129.190629 -224.265728)
			(xy 129.21317 -224.220343) (xy 129.242389 -224.17894) (xy 129.277599 -224.142496) (xy 129.31797 -224.111867)
			(xy 129.362552 -224.087776) (xy 129.410295 -224.070789) (xy 129.435098 -224.065592) (xy 129.457958 -224.061274)
			(xy 129.662682 -223.706436) (xy 129.655062 -223.684338) (xy 129.646431 -223.657991) (xy 129.63711 -223.603344)
			(xy 129.63652 -223.575626) (xy 129.637028 -223.549719) (xy 129.645134 -223.498542) (xy 129.661146 -223.449263)
			(xy 129.684669 -223.403096) (xy 129.715125 -223.361177) (xy 129.751763 -223.324539) (xy 129.793682 -223.294083)
			(xy 129.839849 -223.27056) (xy 129.889128 -223.254548) (xy 129.940305 -223.246442) (xy 129.992119 -223.246442)
			(xy 130.043296 -223.254548) (xy 130.092575 -223.27056) (xy 130.138742 -223.294083) (xy 130.180661 -223.324539)
			(xy 130.217299 -223.361177) (xy 130.247755 -223.403096) (xy 130.271278 -223.449263) (xy 130.28729 -223.498542)
			(xy 130.295396 -223.549719) (xy 130.295904 -223.575626) (xy 130.295487 -223.600992) (xy 130.287734 -223.651127)
			(xy 130.272385 -223.69948) (xy 130.249803 -223.744908) (xy 130.220522 -223.786336) (xy 130.185234 -223.822783)
			(xy 130.144775 -223.853388) (xy 130.100101 -223.877427) (xy 130.052269 -223.894332) (xy 130.027426 -223.899476)
			(xy 130.004566 -223.903794) (xy 129.799842 -224.258632) (xy 129.807716 -224.280476) (xy 129.81629 -224.306896)
			(xy 129.82549 -224.36167) (xy 129.826004 -224.389442) (xy 130.106928 -224.389442) (xy 130.107436 -224.363555)
			(xy 130.115535 -224.312417) (xy 130.131534 -224.263177) (xy 130.15504 -224.217045) (xy 130.185472 -224.175158)
			(xy 130.222082 -224.138548) (xy 130.263969 -224.108116) (xy 130.310101 -224.08461) (xy 130.359341 -224.068611)
			(xy 130.410479 -224.060512) (xy 130.462253 -224.060512) (xy 130.513391 -224.068611) (xy 130.562631 -224.08461)
			(xy 130.608763 -224.108116) (xy 130.65065 -224.138548) (xy 130.68726 -224.175158) (xy 130.717692 -224.217045)
			(xy 130.741198 -224.263177) (xy 130.757197 -224.312417) (xy 130.765296 -224.363555) (xy 130.765804 -224.389442)
			(xy 131.046728 -224.389442) (xy 131.047135 -224.364105) (xy 131.054897 -224.314028) (xy 131.070229 -224.265728)
			(xy 131.09277 -224.220343) (xy 131.121989 -224.17894) (xy 131.157199 -224.142496) (xy 131.19757 -224.111867)
			(xy 131.242152 -224.087776) (xy 131.289895 -224.070789) (xy 131.314698 -224.065592) (xy 131.337558 -224.061274)
			(xy 131.542282 -223.706182) (xy 131.534662 -223.684338) (xy 131.526017 -223.657995) (xy 131.516704 -223.603345)
			(xy 131.51612 -223.575626) (xy 131.516628 -223.549719) (xy 131.524734 -223.498542) (xy 131.540746 -223.449263)
			(xy 131.564269 -223.403096) (xy 131.594725 -223.361177) (xy 131.631363 -223.324539) (xy 131.673282 -223.294083)
			(xy 131.719449 -223.27056) (xy 131.768728 -223.254548) (xy 131.819905 -223.246442) (xy 131.871719 -223.246442)
			(xy 131.922896 -223.254548) (xy 131.972175 -223.27056) (xy 132.018342 -223.294083) (xy 132.060261 -223.324539)
			(xy 132.096899 -223.361177) (xy 132.127355 -223.403096) (xy 132.150878 -223.449263) (xy 132.16689 -223.498542)
			(xy 132.174996 -223.549719) (xy 132.175504 -223.575626) (xy 132.175003 -223.60097) (xy 132.167228 -223.651059)
			(xy 132.151879 -223.699368) (xy 132.12932 -223.74476) (xy 132.10008 -223.786165) (xy 132.064849 -223.822609)
			(xy 132.024457 -223.853232) (xy 131.979854 -223.877314) (xy 131.932092 -223.894288) (xy 131.90728 -223.899476)
			(xy 131.88442 -223.903794) (xy 131.679696 -224.258632) (xy 131.687316 -224.280476) (xy 131.695872 -224.306769)
			(xy 131.705065 -224.361289) (xy 131.705604 -224.388934) (xy 131.705604 -224.389442) (xy 131.986528 -224.389442)
			(xy 131.987036 -224.363555) (xy 131.995135 -224.312417) (xy 132.011134 -224.263177) (xy 132.03464 -224.217045)
			(xy 132.065072 -224.175158) (xy 132.101682 -224.138548) (xy 132.143569 -224.108116) (xy 132.189701 -224.08461)
			(xy 132.238941 -224.068611) (xy 132.290079 -224.060512) (xy 132.341853 -224.060512) (xy 132.392991 -224.068611)
			(xy 132.442231 -224.08461) (xy 132.488363 -224.108116) (xy 132.53025 -224.138548) (xy 132.56686 -224.175158)
			(xy 132.597292 -224.217045) (xy 132.620798 -224.263177) (xy 132.636797 -224.312417) (xy 132.644896 -224.363555)
			(xy 132.645404 -224.389442) (xy 132.926328 -224.389442) (xy 132.926735 -224.364105) (xy 132.934497 -224.314028)
			(xy 132.949829 -224.265728) (xy 132.97237 -224.220343) (xy 133.001589 -224.17894) (xy 133.036799 -224.142496)
			(xy 133.07717 -224.111867) (xy 133.121752 -224.087776) (xy 133.169495 -224.070789) (xy 133.194298 -224.065592)
			(xy 133.217158 -224.061274) (xy 133.422136 -223.705928) (xy 133.414516 -223.684084) (xy 133.405997 -223.657912)
			(xy 133.396803 -223.603651) (xy 133.396228 -223.576134) (xy 133.396228 -223.575626) (xy 133.396736 -223.549739)
			(xy 133.404835 -223.498601) (xy 133.420834 -223.449361) (xy 133.44434 -223.403229) (xy 133.474772 -223.361342)
			(xy 133.511382 -223.324732) (xy 133.553269 -223.2943) (xy 133.599401 -223.270794) (xy 133.648641 -223.254795)
			(xy 133.699779 -223.246696) (xy 133.751553 -223.246696) (xy 133.802691 -223.254795) (xy 133.851931 -223.270794)
			(xy 133.898063 -223.2943) (xy 133.93995 -223.324732) (xy 133.97656 -223.361342) (xy 134.006992 -223.403229)
			(xy 134.030498 -223.449361) (xy 134.046497 -223.498601) (xy 134.054596 -223.549739) (xy 134.055104 -223.575626)
			(xy 134.054603 -223.60097) (xy 134.046828 -223.651059) (xy 134.031479 -223.699368) (xy 134.00892 -223.74476)
			(xy 133.97968 -223.786165) (xy 133.944449 -223.822609) (xy 133.904057 -223.853232) (xy 133.859454 -223.877314)
			(xy 133.811692 -223.894288) (xy 133.78688 -223.899476) (xy 133.76402 -223.903794) (xy 133.559296 -224.258632)
			(xy 133.566916 -224.280476) (xy 133.575472 -224.306769) (xy 133.584665 -224.361289) (xy 133.585204 -224.388934)
			(xy 133.585204 -224.389442) (xy 133.866128 -224.389442) (xy 133.866636 -224.363555) (xy 133.874735 -224.312417)
			(xy 133.890734 -224.263177) (xy 133.91424 -224.217045) (xy 133.944672 -224.175158) (xy 133.981282 -224.138548)
			(xy 134.023169 -224.108116) (xy 134.069301 -224.08461) (xy 134.118541 -224.068611) (xy 134.169679 -224.060512)
			(xy 134.221453 -224.060512) (xy 134.272591 -224.068611) (xy 134.321831 -224.08461) (xy 134.367963 -224.108116)
			(xy 134.40985 -224.138548) (xy 134.44646 -224.175158) (xy 134.476892 -224.217045) (xy 134.500398 -224.263177)
			(xy 134.516397 -224.312417) (xy 134.524496 -224.363555) (xy 134.525004 -224.389442) (xy 341.394796 -224.389442)
			(xy 341.395229 -224.364106) (xy 341.40299 -224.314032) (xy 341.41832 -224.265734) (xy 341.440859 -224.22035)
			(xy 341.470075 -224.178949) (xy 341.505281 -224.142504) (xy 341.545648 -224.111874) (xy 341.590226 -224.087781)
			(xy 341.637965 -224.070791) (xy 341.662766 -224.065592) (xy 341.685626 -224.061274) (xy 341.89035 -223.706436)
			(xy 341.88273 -223.684338) (xy 341.874102 -223.657991) (xy 341.864779 -223.603344) (xy 341.864188 -223.575626)
			(xy 341.864696 -223.549719) (xy 341.872802 -223.498542) (xy 341.888814 -223.449263) (xy 341.912337 -223.403096)
			(xy 341.942793 -223.361177) (xy 341.979431 -223.324539) (xy 342.02135 -223.294083) (xy 342.067517 -223.27056)
			(xy 342.116796 -223.254548) (xy 342.167973 -223.246442) (xy 342.219787 -223.246442) (xy 342.270964 -223.254548)
			(xy 342.320243 -223.27056) (xy 342.36641 -223.294083) (xy 342.408329 -223.324539) (xy 342.444967 -223.361177)
			(xy 342.475423 -223.403096) (xy 342.498946 -223.449263) (xy 342.514958 -223.498542) (xy 342.523064 -223.549719)
			(xy 342.523572 -223.575626) (xy 342.523181 -223.600993) (xy 342.515428 -223.651131) (xy 342.500077 -223.699486)
			(xy 342.477492 -223.744915) (xy 342.448207 -223.786344) (xy 342.412916 -223.822791) (xy 342.372452 -223.853396)
			(xy 342.327774 -223.877433) (xy 342.279939 -223.894334) (xy 342.255094 -223.899476) (xy 342.232234 -223.903794)
			(xy 342.02751 -224.258632) (xy 342.035384 -224.280476) (xy 342.043957 -224.306897) (xy 342.053158 -224.36167)
			(xy 342.053672 -224.389442) (xy 342.334596 -224.389442) (xy 342.335104 -224.363555) (xy 342.343203 -224.312417)
			(xy 342.359202 -224.263177) (xy 342.382708 -224.217045) (xy 342.41314 -224.175158) (xy 342.44975 -224.138548)
			(xy 342.491637 -224.108116) (xy 342.537769 -224.08461) (xy 342.587009 -224.068611) (xy 342.638147 -224.060512)
			(xy 342.689921 -224.060512) (xy 342.741059 -224.068611) (xy 342.790299 -224.08461) (xy 342.836431 -224.108116)
			(xy 342.878318 -224.138548) (xy 342.914928 -224.175158) (xy 342.94536 -224.217045) (xy 342.968866 -224.263177)
			(xy 342.984865 -224.312417) (xy 342.992964 -224.363555) (xy 342.993472 -224.389442) (xy 343.274396 -224.389442)
			(xy 343.274829 -224.364106) (xy 343.28259 -224.314032) (xy 343.29792 -224.265734) (xy 343.320459 -224.22035)
			(xy 343.349675 -224.178949) (xy 343.384881 -224.142504) (xy 343.425248 -224.111874) (xy 343.469826 -224.087781)
			(xy 343.517565 -224.070791) (xy 343.542366 -224.065592) (xy 343.565226 -224.061274) (xy 343.76995 -223.706436)
			(xy 343.76233 -223.684338) (xy 343.753702 -223.657991) (xy 343.744379 -223.603344) (xy 343.743788 -223.575626)
			(xy 343.744296 -223.549719) (xy 343.752402 -223.498542) (xy 343.768414 -223.449263) (xy 343.791937 -223.403096)
			(xy 343.822393 -223.361177) (xy 343.859031 -223.324539) (xy 343.90095 -223.294083) (xy 343.947117 -223.27056)
			(xy 343.996396 -223.254548) (xy 344.047573 -223.246442) (xy 344.099387 -223.246442) (xy 344.150564 -223.254548)
			(xy 344.199843 -223.27056) (xy 344.24601 -223.294083) (xy 344.287929 -223.324539) (xy 344.324567 -223.361177)
			(xy 344.355023 -223.403096) (xy 344.378546 -223.449263) (xy 344.394558 -223.498542) (xy 344.402664 -223.549719)
			(xy 344.403172 -223.575626) (xy 344.402781 -223.600993) (xy 344.395028 -223.651131) (xy 344.379677 -223.699486)
			(xy 344.357092 -223.744915) (xy 344.327807 -223.786344) (xy 344.292516 -223.822791) (xy 344.252052 -223.853396)
			(xy 344.207374 -223.877433) (xy 344.159539 -223.894334) (xy 344.134694 -223.899476) (xy 344.111834 -223.903794)
			(xy 343.90711 -224.258632) (xy 343.914984 -224.280476) (xy 343.923557 -224.306897) (xy 343.932758 -224.36167)
			(xy 343.933272 -224.389442) (xy 344.214196 -224.389442) (xy 344.214704 -224.363555) (xy 344.222803 -224.312417)
			(xy 344.238802 -224.263177) (xy 344.262308 -224.217045) (xy 344.29274 -224.175158) (xy 344.32935 -224.138548)
			(xy 344.371237 -224.108116) (xy 344.417369 -224.08461) (xy 344.466609 -224.068611) (xy 344.517747 -224.060512)
			(xy 344.569521 -224.060512) (xy 344.620659 -224.068611) (xy 344.669899 -224.08461) (xy 344.716031 -224.108116)
			(xy 344.757918 -224.138548) (xy 344.794528 -224.175158) (xy 344.82496 -224.217045) (xy 344.848466 -224.263177)
			(xy 344.864465 -224.312417) (xy 344.872564 -224.363555) (xy 344.873072 -224.389442) (xy 345.153996 -224.389442)
			(xy 345.154429 -224.364106) (xy 345.16219 -224.314032) (xy 345.17752 -224.265734) (xy 345.200059 -224.22035)
			(xy 345.229275 -224.178949) (xy 345.264481 -224.142504) (xy 345.304848 -224.111874) (xy 345.349426 -224.087781)
			(xy 345.397165 -224.070791) (xy 345.421966 -224.065592) (xy 345.444826 -224.061274) (xy 345.64955 -223.706436)
			(xy 345.64193 -223.684338) (xy 345.633302 -223.657991) (xy 345.623979 -223.603344) (xy 345.623388 -223.575626)
			(xy 345.623896 -223.549719) (xy 345.632002 -223.498542) (xy 345.648014 -223.449263) (xy 345.671537 -223.403096)
			(xy 345.701993 -223.361177) (xy 345.738631 -223.324539) (xy 345.78055 -223.294083) (xy 345.826717 -223.27056)
			(xy 345.875996 -223.254548) (xy 345.927173 -223.246442) (xy 345.978987 -223.246442) (xy 346.030164 -223.254548)
			(xy 346.079443 -223.27056) (xy 346.12561 -223.294083) (xy 346.167529 -223.324539) (xy 346.204167 -223.361177)
			(xy 346.234623 -223.403096) (xy 346.258146 -223.449263) (xy 346.274158 -223.498542) (xy 346.282264 -223.549719)
			(xy 346.282772 -223.575626) (xy 346.282381 -223.600993) (xy 346.274628 -223.651131) (xy 346.259277 -223.699486)
			(xy 346.236692 -223.744915) (xy 346.207407 -223.786344) (xy 346.172116 -223.822791) (xy 346.131652 -223.853396)
			(xy 346.086974 -223.877433) (xy 346.039139 -223.894334) (xy 346.014294 -223.899476) (xy 345.991434 -223.903794)
			(xy 345.78671 -224.258632) (xy 345.794584 -224.280476) (xy 345.803157 -224.306897) (xy 345.812358 -224.36167)
			(xy 345.812872 -224.389442) (xy 346.093796 -224.389442) (xy 346.094304 -224.363555) (xy 346.102403 -224.312417)
			(xy 346.118402 -224.263177) (xy 346.141908 -224.217045) (xy 346.17234 -224.175158) (xy 346.20895 -224.138548)
			(xy 346.250837 -224.108116) (xy 346.296969 -224.08461) (xy 346.346209 -224.068611) (xy 346.397347 -224.060512)
			(xy 346.449121 -224.060512) (xy 346.500259 -224.068611) (xy 346.549499 -224.08461) (xy 346.595631 -224.108116)
			(xy 346.637518 -224.138548) (xy 346.674128 -224.175158) (xy 346.70456 -224.217045) (xy 346.728066 -224.263177)
			(xy 346.744065 -224.312417) (xy 346.752164 -224.363555) (xy 346.752672 -224.389442) (xy 347.033596 -224.389442)
			(xy 347.034029 -224.364106) (xy 347.04179 -224.314032) (xy 347.05712 -224.265734) (xy 347.079659 -224.22035)
			(xy 347.108875 -224.178949) (xy 347.144081 -224.142504) (xy 347.184448 -224.111874) (xy 347.229026 -224.087781)
			(xy 347.276765 -224.070791) (xy 347.301566 -224.065592) (xy 347.324426 -224.061274) (xy 347.52915 -223.706436)
			(xy 347.52153 -223.684338) (xy 347.512902 -223.657991) (xy 347.503579 -223.603344) (xy 347.502988 -223.575626)
			(xy 347.503496 -223.549719) (xy 347.511602 -223.498542) (xy 347.527614 -223.449263) (xy 347.551137 -223.403096)
			(xy 347.581593 -223.361177) (xy 347.618231 -223.324539) (xy 347.66015 -223.294083) (xy 347.706317 -223.27056)
			(xy 347.755596 -223.254548) (xy 347.806773 -223.246442) (xy 347.858587 -223.246442) (xy 347.909764 -223.254548)
			(xy 347.959043 -223.27056) (xy 348.00521 -223.294083) (xy 348.047129 -223.324539) (xy 348.083767 -223.361177)
			(xy 348.114223 -223.403096) (xy 348.137746 -223.449263) (xy 348.153758 -223.498542) (xy 348.161864 -223.549719)
			(xy 348.162372 -223.575626) (xy 348.161981 -223.600993) (xy 348.154228 -223.651131) (xy 348.138877 -223.699486)
			(xy 348.116292 -223.744915) (xy 348.087007 -223.786344) (xy 348.051716 -223.822791) (xy 348.011252 -223.853396)
			(xy 347.966574 -223.877433) (xy 347.918739 -223.894334) (xy 347.893894 -223.899476) (xy 347.871034 -223.903794)
			(xy 347.66631 -224.258632) (xy 347.674184 -224.280476) (xy 347.682757 -224.306897) (xy 347.691958 -224.36167)
			(xy 347.692472 -224.389442) (xy 347.973396 -224.389442) (xy 347.973904 -224.363555) (xy 347.982003 -224.312417)
			(xy 347.998002 -224.263177) (xy 348.021508 -224.217045) (xy 348.05194 -224.175158) (xy 348.08855 -224.138548)
			(xy 348.130437 -224.108116) (xy 348.176569 -224.08461) (xy 348.225809 -224.068611) (xy 348.276947 -224.060512)
			(xy 348.328721 -224.060512) (xy 348.379859 -224.068611) (xy 348.429099 -224.08461) (xy 348.475231 -224.108116)
			(xy 348.517118 -224.138548) (xy 348.553728 -224.175158) (xy 348.58416 -224.217045) (xy 348.607666 -224.263177)
			(xy 348.623665 -224.312417) (xy 348.631764 -224.363555) (xy 348.632272 -224.389442) (xy 348.913196 -224.389442)
			(xy 348.913629 -224.364106) (xy 348.92139 -224.314032) (xy 348.93672 -224.265734) (xy 348.959259 -224.22035)
			(xy 348.988475 -224.178949) (xy 349.023681 -224.142504) (xy 349.064048 -224.111874) (xy 349.108626 -224.087781)
			(xy 349.156365 -224.070791) (xy 349.181166 -224.065592) (xy 349.204026 -224.061274) (xy 349.40875 -223.706436)
			(xy 349.40113 -223.684338) (xy 349.392502 -223.657991) (xy 349.383179 -223.603344) (xy 349.382588 -223.575626)
			(xy 349.383096 -223.549719) (xy 349.391202 -223.498542) (xy 349.407214 -223.449263) (xy 349.430737 -223.403096)
			(xy 349.461193 -223.361177) (xy 349.497831 -223.324539) (xy 349.53975 -223.294083) (xy 349.585917 -223.27056)
			(xy 349.635196 -223.254548) (xy 349.686373 -223.246442) (xy 349.738187 -223.246442) (xy 349.789364 -223.254548)
			(xy 349.838643 -223.27056) (xy 349.88481 -223.294083) (xy 349.926729 -223.324539) (xy 349.963367 -223.361177)
			(xy 349.993823 -223.403096) (xy 350.017346 -223.449263) (xy 350.033358 -223.498542) (xy 350.041464 -223.549719)
			(xy 350.041972 -223.575626) (xy 350.041581 -223.600993) (xy 350.033828 -223.651131) (xy 350.018477 -223.699486)
			(xy 349.995892 -223.744915) (xy 349.966607 -223.786344) (xy 349.931316 -223.822791) (xy 349.890852 -223.853396)
			(xy 349.846174 -223.877433) (xy 349.798339 -223.894334) (xy 349.773494 -223.899476) (xy 349.750634 -223.903794)
			(xy 349.54591 -224.258632) (xy 349.553784 -224.280476) (xy 349.562357 -224.306897) (xy 349.571558 -224.36167)
			(xy 349.572072 -224.389442) (xy 349.852996 -224.389442) (xy 349.853504 -224.363555) (xy 349.861603 -224.312417)
			(xy 349.877602 -224.263177) (xy 349.901108 -224.217045) (xy 349.93154 -224.175158) (xy 349.96815 -224.138548)
			(xy 350.010037 -224.108116) (xy 350.056169 -224.08461) (xy 350.105409 -224.068611) (xy 350.156547 -224.060512)
			(xy 350.208321 -224.060512) (xy 350.259459 -224.068611) (xy 350.308699 -224.08461) (xy 350.354831 -224.108116)
			(xy 350.396718 -224.138548) (xy 350.433328 -224.175158) (xy 350.46376 -224.217045) (xy 350.487266 -224.263177)
			(xy 350.503265 -224.312417) (xy 350.511364 -224.363555) (xy 350.511872 -224.389442) (xy 350.792796 -224.389442)
			(xy 350.793229 -224.364106) (xy 350.80099 -224.314032) (xy 350.81632 -224.265734) (xy 350.838859 -224.22035)
			(xy 350.868075 -224.178949) (xy 350.903281 -224.142504) (xy 350.943648 -224.111874) (xy 350.988226 -224.087781)
			(xy 351.035965 -224.070791) (xy 351.060766 -224.065592) (xy 351.083626 -224.061274) (xy 351.28835 -223.706436)
			(xy 351.28073 -223.684338) (xy 351.272102 -223.657991) (xy 351.262779 -223.603344) (xy 351.262188 -223.575626)
			(xy 351.262696 -223.549719) (xy 351.270802 -223.498542) (xy 351.286814 -223.449263) (xy 351.310337 -223.403096)
			(xy 351.340793 -223.361177) (xy 351.377431 -223.324539) (xy 351.41935 -223.294083) (xy 351.465517 -223.27056)
			(xy 351.514796 -223.254548) (xy 351.565973 -223.246442) (xy 351.617787 -223.246442) (xy 351.668964 -223.254548)
			(xy 351.718243 -223.27056) (xy 351.76441 -223.294083) (xy 351.806329 -223.324539) (xy 351.842967 -223.361177)
			(xy 351.873423 -223.403096) (xy 351.896946 -223.449263) (xy 351.912958 -223.498542) (xy 351.921064 -223.549719)
			(xy 351.921572 -223.575626) (xy 351.921181 -223.600993) (xy 351.913428 -223.651131) (xy 351.898077 -223.699486)
			(xy 351.875492 -223.744915) (xy 351.846207 -223.786344) (xy 351.810916 -223.822791) (xy 351.770452 -223.853396)
			(xy 351.725774 -223.877433) (xy 351.677939 -223.894334) (xy 351.653094 -223.899476) (xy 351.630234 -223.903794)
			(xy 351.42551 -224.258632) (xy 351.433384 -224.280476) (xy 351.441957 -224.306897) (xy 351.451158 -224.36167)
			(xy 351.451672 -224.389442) (xy 351.732596 -224.389442) (xy 351.733104 -224.363555) (xy 351.741203 -224.312417)
			(xy 351.757202 -224.263177) (xy 351.780708 -224.217045) (xy 351.81114 -224.175158) (xy 351.84775 -224.138548)
			(xy 351.889637 -224.108116) (xy 351.935769 -224.08461) (xy 351.985009 -224.068611) (xy 352.036147 -224.060512)
			(xy 352.087921 -224.060512) (xy 352.139059 -224.068611) (xy 352.188299 -224.08461) (xy 352.234431 -224.108116)
			(xy 352.276318 -224.138548) (xy 352.312928 -224.175158) (xy 352.34336 -224.217045) (xy 352.366866 -224.263177)
			(xy 352.382865 -224.312417) (xy 352.390964 -224.363555) (xy 352.391472 -224.389442) (xy 352.672396 -224.389442)
			(xy 352.672829 -224.364106) (xy 352.68059 -224.314032) (xy 352.69592 -224.265734) (xy 352.718459 -224.22035)
			(xy 352.747675 -224.178949) (xy 352.782881 -224.142504) (xy 352.823248 -224.111874) (xy 352.867826 -224.087781)
			(xy 352.915565 -224.070791) (xy 352.940366 -224.065592) (xy 352.963226 -224.061274) (xy 353.16795 -223.706436)
			(xy 353.16033 -223.684338) (xy 353.151702 -223.657991) (xy 353.142379 -223.603344) (xy 353.141788 -223.575626)
			(xy 353.142296 -223.549719) (xy 353.150402 -223.498542) (xy 353.166414 -223.449263) (xy 353.189937 -223.403096)
			(xy 353.220393 -223.361177) (xy 353.257031 -223.324539) (xy 353.29895 -223.294083) (xy 353.345117 -223.27056)
			(xy 353.394396 -223.254548) (xy 353.445573 -223.246442) (xy 353.497387 -223.246442) (xy 353.548564 -223.254548)
			(xy 353.597843 -223.27056) (xy 353.64401 -223.294083) (xy 353.685929 -223.324539) (xy 353.722567 -223.361177)
			(xy 353.753023 -223.403096) (xy 353.776546 -223.449263) (xy 353.792558 -223.498542) (xy 353.800664 -223.549719)
			(xy 353.801172 -223.575626) (xy 353.800781 -223.600993) (xy 353.793028 -223.651131) (xy 353.777677 -223.699486)
			(xy 353.755092 -223.744915) (xy 353.725807 -223.786344) (xy 353.690516 -223.822791) (xy 353.650052 -223.853396)
			(xy 353.605374 -223.877433) (xy 353.557539 -223.894334) (xy 353.532694 -223.899476) (xy 353.509834 -223.903794)
			(xy 353.30511 -224.258632) (xy 353.312984 -224.280476) (xy 353.321557 -224.306897) (xy 353.330758 -224.36167)
			(xy 353.331272 -224.389442) (xy 353.612196 -224.389442) (xy 353.612704 -224.363555) (xy 353.620803 -224.312417)
			(xy 353.636802 -224.263177) (xy 353.660308 -224.217045) (xy 353.69074 -224.175158) (xy 353.72735 -224.138548)
			(xy 353.769237 -224.108116) (xy 353.815369 -224.08461) (xy 353.864609 -224.068611) (xy 353.915747 -224.060512)
			(xy 353.967521 -224.060512) (xy 354.018659 -224.068611) (xy 354.067899 -224.08461) (xy 354.114031 -224.108116)
			(xy 354.155918 -224.138548) (xy 354.192528 -224.175158) (xy 354.22296 -224.217045) (xy 354.246466 -224.263177)
			(xy 354.262465 -224.312417) (xy 354.270564 -224.363555) (xy 354.271072 -224.389442) (xy 354.551996 -224.389442)
			(xy 354.552429 -224.364106) (xy 354.56019 -224.314032) (xy 354.57552 -224.265734) (xy 354.598059 -224.22035)
			(xy 354.627275 -224.178949) (xy 354.662481 -224.142504) (xy 354.702848 -224.111874) (xy 354.747426 -224.087781)
			(xy 354.795165 -224.070791) (xy 354.819966 -224.065592) (xy 354.842826 -224.061274) (xy 355.04755 -223.706436)
			(xy 355.03993 -223.684338) (xy 355.031302 -223.657991) (xy 355.021979 -223.603344) (xy 355.021388 -223.575626)
			(xy 355.021896 -223.549719) (xy 355.030002 -223.498542) (xy 355.046014 -223.449263) (xy 355.069537 -223.403096)
			(xy 355.099993 -223.361177) (xy 355.136631 -223.324539) (xy 355.17855 -223.294083) (xy 355.224717 -223.27056)
			(xy 355.273996 -223.254548) (xy 355.325173 -223.246442) (xy 355.376987 -223.246442) (xy 355.428164 -223.254548)
			(xy 355.477443 -223.27056) (xy 355.52361 -223.294083) (xy 355.565529 -223.324539) (xy 355.602167 -223.361177)
			(xy 355.632623 -223.403096) (xy 355.656146 -223.449263) (xy 355.672158 -223.498542) (xy 355.680264 -223.549719)
			(xy 355.680772 -223.575626) (xy 355.680381 -223.600993) (xy 355.672628 -223.651131) (xy 355.657277 -223.699486)
			(xy 355.634692 -223.744915) (xy 355.605407 -223.786344) (xy 355.570116 -223.822791) (xy 355.529652 -223.853396)
			(xy 355.484974 -223.877433) (xy 355.437139 -223.894334) (xy 355.412294 -223.899476) (xy 355.389434 -223.903794)
			(xy 355.18471 -224.258632) (xy 355.192584 -224.280476) (xy 355.201157 -224.306897) (xy 355.210358 -224.36167)
			(xy 355.210872 -224.389442) (xy 355.491796 -224.389442) (xy 355.492304 -224.363555) (xy 355.500403 -224.312417)
			(xy 355.516402 -224.263177) (xy 355.539908 -224.217045) (xy 355.57034 -224.175158) (xy 355.60695 -224.138548)
			(xy 355.648837 -224.108116) (xy 355.694969 -224.08461) (xy 355.744209 -224.068611) (xy 355.795347 -224.060512)
			(xy 355.847121 -224.060512) (xy 355.898259 -224.068611) (xy 355.947499 -224.08461) (xy 355.993631 -224.108116)
			(xy 356.035518 -224.138548) (xy 356.072128 -224.175158) (xy 356.10256 -224.217045) (xy 356.126066 -224.263177)
			(xy 356.142065 -224.312417) (xy 356.150164 -224.363555) (xy 356.150672 -224.389442) (xy 356.431596 -224.389442)
			(xy 356.432029 -224.364106) (xy 356.43979 -224.314032) (xy 356.45512 -224.265734) (xy 356.477659 -224.22035)
			(xy 356.506875 -224.178949) (xy 356.542081 -224.142504) (xy 356.582448 -224.111874) (xy 356.627026 -224.087781)
			(xy 356.674765 -224.070791) (xy 356.699566 -224.065592) (xy 356.722426 -224.061274) (xy 356.92715 -223.706436)
			(xy 356.91953 -223.684338) (xy 356.910902 -223.657991) (xy 356.901579 -223.603344) (xy 356.900988 -223.575626)
			(xy 356.901496 -223.549719) (xy 356.909602 -223.498542) (xy 356.925614 -223.449263) (xy 356.949137 -223.403096)
			(xy 356.979593 -223.361177) (xy 357.016231 -223.324539) (xy 357.05815 -223.294083) (xy 357.104317 -223.27056)
			(xy 357.153596 -223.254548) (xy 357.204773 -223.246442) (xy 357.256587 -223.246442) (xy 357.307764 -223.254548)
			(xy 357.357043 -223.27056) (xy 357.40321 -223.294083) (xy 357.445129 -223.324539) (xy 357.481767 -223.361177)
			(xy 357.512223 -223.403096) (xy 357.535746 -223.449263) (xy 357.551758 -223.498542) (xy 357.559864 -223.549719)
			(xy 357.560372 -223.575626) (xy 357.559981 -223.600993) (xy 357.552228 -223.651131) (xy 357.536877 -223.699486)
			(xy 357.514292 -223.744915) (xy 357.485007 -223.786344) (xy 357.449716 -223.822791) (xy 357.409252 -223.853396)
			(xy 357.364574 -223.877433) (xy 357.316739 -223.894334) (xy 357.291894 -223.899476) (xy 357.269034 -223.903794)
			(xy 357.06431 -224.258632) (xy 357.072184 -224.280476) (xy 357.080757 -224.306897) (xy 357.089958 -224.36167)
			(xy 357.090472 -224.389442) (xy 357.371396 -224.389442) (xy 357.371904 -224.363555) (xy 357.380003 -224.312417)
			(xy 357.396002 -224.263177) (xy 357.419508 -224.217045) (xy 357.44994 -224.175158) (xy 357.48655 -224.138548)
			(xy 357.528437 -224.108116) (xy 357.574569 -224.08461) (xy 357.623809 -224.068611) (xy 357.674947 -224.060512)
			(xy 357.726721 -224.060512) (xy 357.777859 -224.068611) (xy 357.827099 -224.08461) (xy 357.873231 -224.108116)
			(xy 357.915118 -224.138548) (xy 357.951728 -224.175158) (xy 357.98216 -224.217045) (xy 358.005666 -224.263177)
			(xy 358.021665 -224.312417) (xy 358.029764 -224.363555) (xy 358.030272 -224.389442) (xy 358.311196 -224.389442)
			(xy 358.311629 -224.364106) (xy 358.31939 -224.314032) (xy 358.33472 -224.265734) (xy 358.357259 -224.22035)
			(xy 358.386475 -224.178949) (xy 358.421681 -224.142504) (xy 358.462048 -224.111874) (xy 358.506626 -224.087781)
			(xy 358.554365 -224.070791) (xy 358.579166 -224.065592) (xy 358.602026 -224.061274) (xy 358.80675 -223.706436)
			(xy 358.79913 -223.684338) (xy 358.790502 -223.657991) (xy 358.781179 -223.603344) (xy 358.780588 -223.575626)
			(xy 358.781096 -223.549719) (xy 358.789202 -223.498542) (xy 358.805214 -223.449263) (xy 358.828737 -223.403096)
			(xy 358.859193 -223.361177) (xy 358.895831 -223.324539) (xy 358.93775 -223.294083) (xy 358.983917 -223.27056)
			(xy 359.033196 -223.254548) (xy 359.084373 -223.246442) (xy 359.136187 -223.246442) (xy 359.187364 -223.254548)
			(xy 359.236643 -223.27056) (xy 359.28281 -223.294083) (xy 359.324729 -223.324539) (xy 359.361367 -223.361177)
			(xy 359.391823 -223.403096) (xy 359.415346 -223.449263) (xy 359.431358 -223.498542) (xy 359.439464 -223.549719)
			(xy 359.439972 -223.575626) (xy 359.439581 -223.600993) (xy 359.431828 -223.651131) (xy 359.416477 -223.699486)
			(xy 359.393892 -223.744915) (xy 359.364607 -223.786344) (xy 359.329316 -223.822791) (xy 359.288852 -223.853396)
			(xy 359.244174 -223.877433) (xy 359.196339 -223.894334) (xy 359.171494 -223.899476) (xy 359.148634 -223.903794)
			(xy 358.94391 -224.258632) (xy 358.951784 -224.280476) (xy 358.960357 -224.306897) (xy 358.969558 -224.36167)
			(xy 358.970072 -224.389442) (xy 359.250996 -224.389442) (xy 359.251504 -224.363555) (xy 359.259603 -224.312417)
			(xy 359.275602 -224.263177) (xy 359.299108 -224.217045) (xy 359.32954 -224.175158) (xy 359.36615 -224.138548)
			(xy 359.408037 -224.108116) (xy 359.454169 -224.08461) (xy 359.503409 -224.068611) (xy 359.554547 -224.060512)
			(xy 359.606321 -224.060512) (xy 359.657459 -224.068611) (xy 359.706699 -224.08461) (xy 359.752831 -224.108116)
			(xy 359.794718 -224.138548) (xy 359.831328 -224.175158) (xy 359.86176 -224.217045) (xy 359.885266 -224.263177)
			(xy 359.901265 -224.312417) (xy 359.909364 -224.363555) (xy 359.909872 -224.389442) (xy 360.190796 -224.389442)
			(xy 360.191229 -224.364106) (xy 360.19899 -224.314032) (xy 360.21432 -224.265734) (xy 360.236859 -224.22035)
			(xy 360.266075 -224.178949) (xy 360.301281 -224.142504) (xy 360.341648 -224.111874) (xy 360.386226 -224.087781)
			(xy 360.433965 -224.070791) (xy 360.458766 -224.065592) (xy 360.481626 -224.061274) (xy 360.68635 -223.706436)
			(xy 360.67873 -223.684338) (xy 360.670102 -223.657991) (xy 360.660779 -223.603344) (xy 360.660188 -223.575626)
			(xy 360.660696 -223.549719) (xy 360.668802 -223.498542) (xy 360.684814 -223.449263) (xy 360.708337 -223.403096)
			(xy 360.738793 -223.361177) (xy 360.775431 -223.324539) (xy 360.81735 -223.294083) (xy 360.863517 -223.27056)
			(xy 360.912796 -223.254548) (xy 360.963973 -223.246442) (xy 361.015787 -223.246442) (xy 361.066964 -223.254548)
			(xy 361.116243 -223.27056) (xy 361.16241 -223.294083) (xy 361.204329 -223.324539) (xy 361.240967 -223.361177)
			(xy 361.271423 -223.403096) (xy 361.294946 -223.449263) (xy 361.310958 -223.498542) (xy 361.319064 -223.549719)
			(xy 361.319572 -223.575626) (xy 361.319181 -223.600993) (xy 361.311428 -223.651131) (xy 361.296077 -223.699486)
			(xy 361.273492 -223.744915) (xy 361.244207 -223.786344) (xy 361.208916 -223.822791) (xy 361.168452 -223.853396)
			(xy 361.123774 -223.877433) (xy 361.075939 -223.894334) (xy 361.051094 -223.899476) (xy 361.028234 -223.903794)
			(xy 360.82351 -224.258632) (xy 360.831384 -224.280476) (xy 360.839957 -224.306897) (xy 360.849158 -224.36167)
			(xy 360.849672 -224.389442) (xy 361.130596 -224.389442) (xy 361.131104 -224.363555) (xy 361.139203 -224.312417)
			(xy 361.155202 -224.263177) (xy 361.178708 -224.217045) (xy 361.20914 -224.175158) (xy 361.24575 -224.138548)
			(xy 361.287637 -224.108116) (xy 361.333769 -224.08461) (xy 361.383009 -224.068611) (xy 361.434147 -224.060512)
			(xy 361.485921 -224.060512) (xy 361.537059 -224.068611) (xy 361.586299 -224.08461) (xy 361.632431 -224.108116)
			(xy 361.674318 -224.138548) (xy 361.710928 -224.175158) (xy 361.74136 -224.217045) (xy 361.764866 -224.263177)
			(xy 361.780865 -224.312417) (xy 361.788964 -224.363555) (xy 361.789472 -224.389442) (xy 362.070396 -224.389442)
			(xy 362.070829 -224.364106) (xy 362.07859 -224.314032) (xy 362.09392 -224.265734) (xy 362.116459 -224.22035)
			(xy 362.145675 -224.178949) (xy 362.180881 -224.142504) (xy 362.221248 -224.111874) (xy 362.265826 -224.087781)
			(xy 362.313565 -224.070791) (xy 362.338366 -224.065592) (xy 362.361226 -224.061274) (xy 362.566204 -223.706182)
			(xy 362.558584 -223.684084) (xy 362.550064 -223.657913) (xy 362.540871 -223.603651) (xy 362.540296 -223.576134)
			(xy 362.540296 -223.575626) (xy 362.540804 -223.549739) (xy 362.548903 -223.498601) (xy 362.564902 -223.449361)
			(xy 362.588408 -223.403229) (xy 362.61884 -223.361342) (xy 362.65545 -223.324732) (xy 362.697337 -223.2943)
			(xy 362.743469 -223.270794) (xy 362.792709 -223.254795) (xy 362.843847 -223.246696) (xy 362.895621 -223.246696)
			(xy 362.946759 -223.254795) (xy 362.995999 -223.270794) (xy 363.042131 -223.2943) (xy 363.084018 -223.324732)
			(xy 363.120628 -223.361342) (xy 363.15106 -223.403229) (xy 363.174566 -223.449361) (xy 363.190565 -223.498601)
			(xy 363.198664 -223.549739) (xy 363.199172 -223.575626) (xy 363.198781 -223.600993) (xy 363.191028 -223.651131)
			(xy 363.175677 -223.699486) (xy 363.153092 -223.744915) (xy 363.123807 -223.786344) (xy 363.088516 -223.822791)
			(xy 363.048052 -223.853396) (xy 363.003374 -223.877433) (xy 362.955539 -223.894334) (xy 362.930694 -223.899476)
			(xy 362.907834 -223.903794) (xy 362.70311 -224.258632) (xy 362.710984 -224.280476) (xy 362.719557 -224.306897)
			(xy 362.728758 -224.36167) (xy 362.729272 -224.389442) (xy 363.010196 -224.389442) (xy 363.010704 -224.363555)
			(xy 363.018803 -224.312417) (xy 363.034802 -224.263177) (xy 363.058308 -224.217045) (xy 363.08874 -224.175158)
			(xy 363.12535 -224.138548) (xy 363.167237 -224.108116) (xy 363.213369 -224.08461) (xy 363.262609 -224.068611)
			(xy 363.313747 -224.060512) (xy 363.365521 -224.060512) (xy 363.416659 -224.068611) (xy 363.465899 -224.08461)
			(xy 363.512031 -224.108116) (xy 363.553918 -224.138548) (xy 363.590528 -224.175158) (xy 363.62096 -224.217045)
			(xy 363.644466 -224.263177) (xy 363.660465 -224.312417) (xy 363.668564 -224.363555) (xy 363.669072 -224.389442)
			(xy 363.949996 -224.389442) (xy 363.950429 -224.364106) (xy 363.95819 -224.314032) (xy 363.97352 -224.265734)
			(xy 363.996059 -224.22035) (xy 364.025275 -224.178949) (xy 364.060481 -224.142504) (xy 364.100848 -224.111874)
			(xy 364.145426 -224.087781) (xy 364.193165 -224.070791) (xy 364.217966 -224.065592) (xy 364.240826 -224.061274)
			(xy 364.44555 -223.706436) (xy 364.43793 -223.684338) (xy 364.429302 -223.657991) (xy 364.419979 -223.603344)
			(xy 364.419388 -223.575626) (xy 364.419896 -223.549719) (xy 364.428002 -223.498542) (xy 364.444014 -223.449263)
			(xy 364.467537 -223.403096) (xy 364.497993 -223.361177) (xy 364.534631 -223.324539) (xy 364.57655 -223.294083)
			(xy 364.622717 -223.27056) (xy 364.671996 -223.254548) (xy 364.723173 -223.246442) (xy 364.774987 -223.246442)
			(xy 364.826164 -223.254548) (xy 364.875443 -223.27056) (xy 364.92161 -223.294083) (xy 364.963529 -223.324539)
			(xy 365.000167 -223.361177) (xy 365.030623 -223.403096) (xy 365.054146 -223.449263) (xy 365.070158 -223.498542)
			(xy 365.078264 -223.549719) (xy 365.078772 -223.575626) (xy 365.078381 -223.600993) (xy 365.070628 -223.651131)
			(xy 365.055277 -223.699486) (xy 365.032692 -223.744915) (xy 365.003407 -223.786344) (xy 364.968116 -223.822791)
			(xy 364.927652 -223.853396) (xy 364.882974 -223.877433) (xy 364.835139 -223.894334) (xy 364.810294 -223.899476)
			(xy 364.787434 -223.903794) (xy 364.58271 -224.258632) (xy 364.590584 -224.280476) (xy 364.599157 -224.306897)
			(xy 364.608358 -224.36167) (xy 364.608872 -224.389442) (xy 364.889796 -224.389442) (xy 364.890304 -224.363555)
			(xy 364.898403 -224.312417) (xy 364.914402 -224.263177) (xy 364.937908 -224.217045) (xy 364.96834 -224.175158)
			(xy 365.00495 -224.138548) (xy 365.046837 -224.108116) (xy 365.092969 -224.08461) (xy 365.142209 -224.068611)
			(xy 365.193347 -224.060512) (xy 365.245121 -224.060512) (xy 365.296259 -224.068611) (xy 365.345499 -224.08461)
			(xy 365.391631 -224.108116) (xy 365.433518 -224.138548) (xy 365.470128 -224.175158) (xy 365.50056 -224.217045)
			(xy 365.524066 -224.263177) (xy 365.540065 -224.312417) (xy 365.548164 -224.363555) (xy 365.548672 -224.389442)
			(xy 365.829596 -224.389442) (xy 365.830029 -224.364106) (xy 365.83779 -224.314032) (xy 365.85312 -224.265734)
			(xy 365.875659 -224.22035) (xy 365.904875 -224.178949) (xy 365.940081 -224.142504) (xy 365.980448 -224.111874)
			(xy 366.025026 -224.087781) (xy 366.072765 -224.070791) (xy 366.097566 -224.065592) (xy 366.120426 -224.061274)
			(xy 366.32515 -223.706436) (xy 366.31753 -223.684338) (xy 366.308902 -223.657991) (xy 366.299579 -223.603344)
			(xy 366.298988 -223.575626) (xy 366.299496 -223.549719) (xy 366.307602 -223.498542) (xy 366.323614 -223.449263)
			(xy 366.347137 -223.403096) (xy 366.377593 -223.361177) (xy 366.414231 -223.324539) (xy 366.45615 -223.294083)
			(xy 366.502317 -223.27056) (xy 366.551596 -223.254548) (xy 366.602773 -223.246442) (xy 366.654587 -223.246442)
			(xy 366.705764 -223.254548) (xy 366.755043 -223.27056) (xy 366.80121 -223.294083) (xy 366.843129 -223.324539)
			(xy 366.879767 -223.361177) (xy 366.910223 -223.403096) (xy 366.933746 -223.449263) (xy 366.949758 -223.498542)
			(xy 366.957864 -223.549719) (xy 366.958372 -223.575626) (xy 366.957981 -223.600993) (xy 366.950228 -223.651131)
			(xy 366.934877 -223.699486) (xy 366.912292 -223.744915) (xy 366.883007 -223.786344) (xy 366.847716 -223.822791)
			(xy 366.807252 -223.853396) (xy 366.762574 -223.877433) (xy 366.714739 -223.894334) (xy 366.689894 -223.899476)
			(xy 366.667034 -223.903794) (xy 366.46231 -224.258632) (xy 366.470184 -224.280476) (xy 366.478757 -224.306897)
			(xy 366.487958 -224.36167) (xy 366.488472 -224.389442) (xy 366.769396 -224.389442) (xy 366.769904 -224.363555)
			(xy 366.778003 -224.312417) (xy 366.794002 -224.263177) (xy 366.817508 -224.217045) (xy 366.84794 -224.175158)
			(xy 366.88455 -224.138548) (xy 366.926437 -224.108116) (xy 366.972569 -224.08461) (xy 367.021809 -224.068611)
			(xy 367.072947 -224.060512) (xy 367.124721 -224.060512) (xy 367.175859 -224.068611) (xy 367.225099 -224.08461)
			(xy 367.271231 -224.108116) (xy 367.313118 -224.138548) (xy 367.349728 -224.175158) (xy 367.38016 -224.217045)
			(xy 367.403666 -224.263177) (xy 367.419665 -224.312417) (xy 367.427764 -224.363555) (xy 367.428272 -224.389442)
			(xy 367.709196 -224.389442) (xy 367.709629 -224.364106) (xy 367.71739 -224.314032) (xy 367.73272 -224.265734)
			(xy 367.755259 -224.22035) (xy 367.784475 -224.178949) (xy 367.819681 -224.142504) (xy 367.860048 -224.111874)
			(xy 367.904626 -224.087781) (xy 367.952365 -224.070791) (xy 367.977166 -224.065592) (xy 368.000026 -224.061274)
			(xy 368.20475 -223.706436) (xy 368.19713 -223.684338) (xy 368.188502 -223.657991) (xy 368.179179 -223.603344)
			(xy 368.178588 -223.575626) (xy 368.179096 -223.549719) (xy 368.187202 -223.498542) (xy 368.203214 -223.449263)
			(xy 368.226737 -223.403096) (xy 368.257193 -223.361177) (xy 368.293831 -223.324539) (xy 368.33575 -223.294083)
			(xy 368.381917 -223.27056) (xy 368.431196 -223.254548) (xy 368.482373 -223.246442) (xy 368.534187 -223.246442)
			(xy 368.585364 -223.254548) (xy 368.634643 -223.27056) (xy 368.68081 -223.294083) (xy 368.722729 -223.324539)
			(xy 368.759367 -223.361177) (xy 368.789823 -223.403096) (xy 368.813346 -223.449263) (xy 368.829358 -223.498542)
			(xy 368.837464 -223.549719) (xy 368.837972 -223.575626) (xy 368.837581 -223.600993) (xy 368.829828 -223.651131)
			(xy 368.814477 -223.699486) (xy 368.791892 -223.744915) (xy 368.762607 -223.786344) (xy 368.727316 -223.822791)
			(xy 368.686852 -223.853396) (xy 368.642174 -223.877433) (xy 368.594339 -223.894334) (xy 368.569494 -223.899476)
			(xy 368.546634 -223.903794) (xy 368.34191 -224.258632) (xy 368.349784 -224.280476) (xy 368.358357 -224.306897)
			(xy 368.367558 -224.36167) (xy 368.368072 -224.389442) (xy 368.648996 -224.389442) (xy 368.649504 -224.363555)
			(xy 368.657603 -224.312417) (xy 368.673602 -224.263177) (xy 368.697108 -224.217045) (xy 368.72754 -224.175158)
			(xy 368.76415 -224.138548) (xy 368.806037 -224.108116) (xy 368.852169 -224.08461) (xy 368.901409 -224.068611)
			(xy 368.952547 -224.060512) (xy 369.004321 -224.060512) (xy 369.055459 -224.068611) (xy 369.104699 -224.08461)
			(xy 369.150831 -224.108116) (xy 369.192718 -224.138548) (xy 369.229328 -224.175158) (xy 369.25976 -224.217045)
			(xy 369.283266 -224.263177) (xy 369.299265 -224.312417) (xy 369.307364 -224.363555) (xy 369.307872 -224.389442)
			(xy 369.588796 -224.389442) (xy 369.589229 -224.364106) (xy 369.59699 -224.314032) (xy 369.61232 -224.265734)
			(xy 369.634859 -224.22035) (xy 369.664075 -224.178949) (xy 369.699281 -224.142504) (xy 369.739648 -224.111874)
			(xy 369.784226 -224.087781) (xy 369.831965 -224.070791) (xy 369.856766 -224.065592) (xy 369.879626 -224.061274)
			(xy 370.08435 -223.706436) (xy 370.07673 -223.684338) (xy 370.068102 -223.657991) (xy 370.058779 -223.603344)
			(xy 370.058188 -223.575626) (xy 370.058696 -223.549719) (xy 370.066802 -223.498542) (xy 370.082814 -223.449263)
			(xy 370.106337 -223.403096) (xy 370.136793 -223.361177) (xy 370.173431 -223.324539) (xy 370.21535 -223.294083)
			(xy 370.261517 -223.27056) (xy 370.310796 -223.254548) (xy 370.361973 -223.246442) (xy 370.413787 -223.246442)
			(xy 370.464964 -223.254548) (xy 370.514243 -223.27056) (xy 370.56041 -223.294083) (xy 370.602329 -223.324539)
			(xy 370.638967 -223.361177) (xy 370.669423 -223.403096) (xy 370.692946 -223.449263) (xy 370.708958 -223.498542)
			(xy 370.717064 -223.549719) (xy 370.717572 -223.575626) (xy 370.717181 -223.600993) (xy 370.709428 -223.651131)
			(xy 370.694077 -223.699486) (xy 370.671492 -223.744915) (xy 370.642207 -223.786344) (xy 370.606916 -223.822791)
			(xy 370.566452 -223.853396) (xy 370.521774 -223.877433) (xy 370.473939 -223.894334) (xy 370.449094 -223.899476)
			(xy 370.426234 -223.903794) (xy 370.22151 -224.258632) (xy 370.229384 -224.280476) (xy 370.237957 -224.306897)
			(xy 370.247158 -224.36167) (xy 370.247672 -224.389442) (xy 370.528596 -224.389442) (xy 370.529104 -224.363555)
			(xy 370.537203 -224.312417) (xy 370.553202 -224.263177) (xy 370.576708 -224.217045) (xy 370.60714 -224.175158)
			(xy 370.64375 -224.138548) (xy 370.685637 -224.108116) (xy 370.731769 -224.08461) (xy 370.781009 -224.068611)
			(xy 370.832147 -224.060512) (xy 370.883921 -224.060512) (xy 370.935059 -224.068611) (xy 370.984299 -224.08461)
			(xy 371.030431 -224.108116) (xy 371.072318 -224.138548) (xy 371.108928 -224.175158) (xy 371.13936 -224.217045)
			(xy 371.162866 -224.263177) (xy 371.178865 -224.312417) (xy 371.186964 -224.363555) (xy 371.187472 -224.389442)
			(xy 371.468396 -224.389442) (xy 371.468829 -224.364106) (xy 371.47659 -224.314032) (xy 371.49192 -224.265734)
			(xy 371.514459 -224.22035) (xy 371.543675 -224.178949) (xy 371.578881 -224.142504) (xy 371.619248 -224.111874)
			(xy 371.663826 -224.087781) (xy 371.711565 -224.070791) (xy 371.736366 -224.065592) (xy 371.759226 -224.061274)
			(xy 371.96395 -223.706436) (xy 371.95633 -223.684338) (xy 371.947702 -223.657991) (xy 371.938379 -223.603344)
			(xy 371.937788 -223.575626) (xy 371.938296 -223.549719) (xy 371.946402 -223.498542) (xy 371.962414 -223.449263)
			(xy 371.985937 -223.403096) (xy 372.016393 -223.361177) (xy 372.053031 -223.324539) (xy 372.09495 -223.294083)
			(xy 372.141117 -223.27056) (xy 372.190396 -223.254548) (xy 372.241573 -223.246442) (xy 372.293387 -223.246442)
			(xy 372.344564 -223.254548) (xy 372.393843 -223.27056) (xy 372.44001 -223.294083) (xy 372.481929 -223.324539)
			(xy 372.518567 -223.361177) (xy 372.549023 -223.403096) (xy 372.572546 -223.449263) (xy 372.588558 -223.498542)
			(xy 372.596664 -223.549719) (xy 372.597172 -223.575626) (xy 372.596781 -223.600993) (xy 372.589028 -223.651131)
			(xy 372.573677 -223.699486) (xy 372.551092 -223.744915) (xy 372.521807 -223.786344) (xy 372.486516 -223.822791)
			(xy 372.446052 -223.853396) (xy 372.401374 -223.877433) (xy 372.353539 -223.894334) (xy 372.328694 -223.899476)
			(xy 372.305834 -223.903794) (xy 372.10111 -224.258632) (xy 372.108984 -224.280476) (xy 372.117557 -224.306897)
			(xy 372.126758 -224.36167) (xy 372.127272 -224.389442) (xy 372.408196 -224.389442) (xy 372.408704 -224.363555)
			(xy 372.416803 -224.312417) (xy 372.432802 -224.263177) (xy 372.456308 -224.217045) (xy 372.48674 -224.175158)
			(xy 372.52335 -224.138548) (xy 372.565237 -224.108116) (xy 372.611369 -224.08461) (xy 372.660609 -224.068611)
			(xy 372.711747 -224.060512) (xy 372.763521 -224.060512) (xy 372.814659 -224.068611) (xy 372.863899 -224.08461)
			(xy 372.910031 -224.108116) (xy 372.951918 -224.138548) (xy 372.988528 -224.175158) (xy 373.01896 -224.217045)
			(xy 373.042466 -224.263177) (xy 373.058465 -224.312417) (xy 373.066564 -224.363555) (xy 373.067072 -224.389442)
			(xy 373.347996 -224.389442) (xy 373.348429 -224.364106) (xy 373.35619 -224.314032) (xy 373.37152 -224.265734)
			(xy 373.394059 -224.22035) (xy 373.423275 -224.178949) (xy 373.458481 -224.142504) (xy 373.498848 -224.111874)
			(xy 373.543426 -224.087781) (xy 373.591165 -224.070791) (xy 373.615966 -224.065592) (xy 373.638826 -224.061274)
			(xy 373.84355 -223.706436) (xy 373.83593 -223.684338) (xy 373.827302 -223.657991) (xy 373.817979 -223.603344)
			(xy 373.817388 -223.575626) (xy 373.817896 -223.549719) (xy 373.826002 -223.498542) (xy 373.842014 -223.449263)
			(xy 373.865537 -223.403096) (xy 373.895993 -223.361177) (xy 373.932631 -223.324539) (xy 373.97455 -223.294083)
			(xy 374.020717 -223.27056) (xy 374.069996 -223.254548) (xy 374.121173 -223.246442) (xy 374.172987 -223.246442)
			(xy 374.224164 -223.254548) (xy 374.273443 -223.27056) (xy 374.31961 -223.294083) (xy 374.361529 -223.324539)
			(xy 374.398167 -223.361177) (xy 374.428623 -223.403096) (xy 374.452146 -223.449263) (xy 374.468158 -223.498542)
			(xy 374.476264 -223.549719) (xy 374.476772 -223.575626) (xy 374.476381 -223.600993) (xy 374.468628 -223.651131)
			(xy 374.453277 -223.699486) (xy 374.430692 -223.744915) (xy 374.401407 -223.786344) (xy 374.366116 -223.822791)
			(xy 374.325652 -223.853396) (xy 374.280974 -223.877433) (xy 374.233139 -223.894334) (xy 374.208294 -223.899476)
			(xy 374.185434 -223.903794) (xy 373.98071 -224.258632) (xy 373.988584 -224.280476) (xy 373.997157 -224.306897)
			(xy 374.006358 -224.36167) (xy 374.006872 -224.389442) (xy 374.287796 -224.389442) (xy 374.288304 -224.363555)
			(xy 374.296403 -224.312417) (xy 374.312402 -224.263177) (xy 374.335908 -224.217045) (xy 374.36634 -224.175158)
			(xy 374.40295 -224.138548) (xy 374.444837 -224.108116) (xy 374.490969 -224.08461) (xy 374.540209 -224.068611)
			(xy 374.591347 -224.060512) (xy 374.643121 -224.060512) (xy 374.694259 -224.068611) (xy 374.743499 -224.08461)
			(xy 374.789631 -224.108116) (xy 374.831518 -224.138548) (xy 374.868128 -224.175158) (xy 374.89856 -224.217045)
			(xy 374.922066 -224.263177) (xy 374.938065 -224.312417) (xy 374.946164 -224.363555) (xy 374.946672 -224.389442)
			(xy 375.227596 -224.389442) (xy 375.228029 -224.364106) (xy 375.23579 -224.314032) (xy 375.25112 -224.265734)
			(xy 375.273659 -224.22035) (xy 375.302875 -224.178949) (xy 375.338081 -224.142504) (xy 375.378448 -224.111874)
			(xy 375.423026 -224.087781) (xy 375.470765 -224.070791) (xy 375.495566 -224.065592) (xy 375.518426 -224.061274)
			(xy 375.72315 -223.706436) (xy 375.71553 -223.684338) (xy 375.706902 -223.657991) (xy 375.697579 -223.603344)
			(xy 375.696988 -223.575626) (xy 375.697496 -223.549719) (xy 375.705602 -223.498542) (xy 375.721614 -223.449263)
			(xy 375.745137 -223.403096) (xy 375.775593 -223.361177) (xy 375.812231 -223.324539) (xy 375.85415 -223.294083)
			(xy 375.900317 -223.27056) (xy 375.949596 -223.254548) (xy 376.000773 -223.246442) (xy 376.052587 -223.246442)
			(xy 376.103764 -223.254548) (xy 376.153043 -223.27056) (xy 376.19921 -223.294083) (xy 376.241129 -223.324539)
			(xy 376.277767 -223.361177) (xy 376.308223 -223.403096) (xy 376.331746 -223.449263) (xy 376.347758 -223.498542)
			(xy 376.355864 -223.549719) (xy 376.356372 -223.575626) (xy 376.355981 -223.600993) (xy 376.348228 -223.651131)
			(xy 376.332877 -223.699486) (xy 376.310292 -223.744915) (xy 376.281007 -223.786344) (xy 376.245716 -223.822791)
			(xy 376.205252 -223.853396) (xy 376.160574 -223.877433) (xy 376.112739 -223.894334) (xy 376.087894 -223.899476)
			(xy 376.065034 -223.903794) (xy 375.86031 -224.258632) (xy 375.868184 -224.280476) (xy 375.876757 -224.306897)
			(xy 375.885958 -224.36167) (xy 375.886472 -224.389442) (xy 376.167396 -224.389442) (xy 376.167904 -224.363555)
			(xy 376.176003 -224.312417) (xy 376.192002 -224.263177) (xy 376.215508 -224.217045) (xy 376.24594 -224.175158)
			(xy 376.28255 -224.138548) (xy 376.324437 -224.108116) (xy 376.370569 -224.08461) (xy 376.419809 -224.068611)
			(xy 376.470947 -224.060512) (xy 376.522721 -224.060512) (xy 376.573859 -224.068611) (xy 376.623099 -224.08461)
			(xy 376.669231 -224.108116) (xy 376.711118 -224.138548) (xy 376.747728 -224.175158) (xy 376.77816 -224.217045)
			(xy 376.801666 -224.263177) (xy 376.817665 -224.312417) (xy 376.825764 -224.363555) (xy 376.826272 -224.389442)
			(xy 377.107196 -224.389442) (xy 377.107629 -224.364106) (xy 377.11539 -224.314032) (xy 377.13072 -224.265734)
			(xy 377.153259 -224.22035) (xy 377.182475 -224.178949) (xy 377.217681 -224.142504) (xy 377.258048 -224.111874)
			(xy 377.302626 -224.087781) (xy 377.350365 -224.070791) (xy 377.375166 -224.065592) (xy 377.398026 -224.061274)
			(xy 377.60275 -223.706436) (xy 377.59513 -223.684338) (xy 377.586502 -223.657991) (xy 377.577179 -223.603344)
			(xy 377.576588 -223.575626) (xy 377.577096 -223.549719) (xy 377.585202 -223.498542) (xy 377.601214 -223.449263)
			(xy 377.624737 -223.403096) (xy 377.655193 -223.361177) (xy 377.691831 -223.324539) (xy 377.73375 -223.294083)
			(xy 377.779917 -223.27056) (xy 377.829196 -223.254548) (xy 377.880373 -223.246442) (xy 377.932187 -223.246442)
			(xy 377.983364 -223.254548) (xy 378.032643 -223.27056) (xy 378.07881 -223.294083) (xy 378.120729 -223.324539)
			(xy 378.157367 -223.361177) (xy 378.187823 -223.403096) (xy 378.211346 -223.449263) (xy 378.227358 -223.498542)
			(xy 378.235464 -223.549719) (xy 378.235972 -223.575626) (xy 378.235581 -223.600993) (xy 378.227828 -223.651131)
			(xy 378.212477 -223.699486) (xy 378.189892 -223.744915) (xy 378.160607 -223.786344) (xy 378.125316 -223.822791)
			(xy 378.084852 -223.853396) (xy 378.040174 -223.877433) (xy 377.992339 -223.894334) (xy 377.967494 -223.899476)
			(xy 377.944634 -223.903794) (xy 377.73991 -224.258632) (xy 377.747784 -224.280476) (xy 377.756357 -224.306897)
			(xy 377.765558 -224.36167) (xy 377.766072 -224.389442) (xy 378.046996 -224.389442) (xy 378.047504 -224.363555)
			(xy 378.055603 -224.312417) (xy 378.071602 -224.263177) (xy 378.095108 -224.217045) (xy 378.12554 -224.175158)
			(xy 378.16215 -224.138548) (xy 378.204037 -224.108116) (xy 378.250169 -224.08461) (xy 378.299409 -224.068611)
			(xy 378.350547 -224.060512) (xy 378.402321 -224.060512) (xy 378.453459 -224.068611) (xy 378.502699 -224.08461)
			(xy 378.548831 -224.108116) (xy 378.590718 -224.138548) (xy 378.627328 -224.175158) (xy 378.65776 -224.217045)
			(xy 378.681266 -224.263177) (xy 378.697265 -224.312417) (xy 378.705364 -224.363555) (xy 378.705872 -224.389442)
			(xy 378.986796 -224.389442) (xy 378.987229 -224.364106) (xy 378.99499 -224.314032) (xy 379.01032 -224.265734)
			(xy 379.032859 -224.22035) (xy 379.062075 -224.178949) (xy 379.097281 -224.142504) (xy 379.137648 -224.111874)
			(xy 379.182226 -224.087781) (xy 379.229965 -224.070791) (xy 379.254766 -224.065592) (xy 379.277626 -224.061274)
			(xy 379.48235 -223.706182) (xy 379.47473 -223.684338) (xy 379.466087 -223.657995) (xy 379.456772 -223.603345)
			(xy 379.456188 -223.575626) (xy 379.456696 -223.549719) (xy 379.464802 -223.498542) (xy 379.480814 -223.449263)
			(xy 379.504337 -223.403096) (xy 379.534793 -223.361177) (xy 379.571431 -223.324539) (xy 379.61335 -223.294083)
			(xy 379.659517 -223.27056) (xy 379.708796 -223.254548) (xy 379.759973 -223.246442) (xy 379.811787 -223.246442)
			(xy 379.862964 -223.254548) (xy 379.912243 -223.27056) (xy 379.95841 -223.294083) (xy 380.000329 -223.324539)
			(xy 380.036967 -223.361177) (xy 380.067423 -223.403096) (xy 380.090946 -223.449263) (xy 380.106958 -223.498542)
			(xy 380.115064 -223.549719) (xy 380.115572 -223.575626) (xy 380.115097 -223.600971) (xy 380.107321 -223.651063)
			(xy 380.091971 -223.699374) (xy 380.069408 -223.744767) (xy 380.040166 -223.786173) (xy 380.004931 -223.822617)
			(xy 379.964535 -223.853239) (xy 379.919928 -223.877319) (xy 379.872162 -223.89429) (xy 379.847348 -223.899476)
			(xy 379.824488 -223.903794) (xy 379.619764 -224.258632) (xy 379.627384 -224.280476) (xy 379.635939 -224.306769)
			(xy 379.645132 -224.361289) (xy 379.645672 -224.388934) (xy 379.645672 -224.389442) (xy 379.926596 -224.389442)
			(xy 379.927104 -224.363555) (xy 379.935203 -224.312417) (xy 379.951202 -224.263177) (xy 379.974708 -224.217045)
			(xy 380.00514 -224.175158) (xy 380.04175 -224.138548) (xy 380.083637 -224.108116) (xy 380.129769 -224.08461)
			(xy 380.179009 -224.068611) (xy 380.230147 -224.060512) (xy 380.281921 -224.060512) (xy 380.333059 -224.068611)
			(xy 380.382299 -224.08461) (xy 380.428431 -224.108116) (xy 380.470318 -224.138548) (xy 380.506928 -224.175158)
			(xy 380.53736 -224.217045) (xy 380.560866 -224.263177) (xy 380.576865 -224.312417) (xy 380.584964 -224.363555)
			(xy 380.585472 -224.389442) (xy 380.866396 -224.389442) (xy 380.866829 -224.364106) (xy 380.87459 -224.314032)
			(xy 380.88992 -224.265734) (xy 380.912459 -224.22035) (xy 380.941675 -224.178949) (xy 380.976881 -224.142504)
			(xy 381.017248 -224.111874) (xy 381.061826 -224.087781) (xy 381.109565 -224.070791) (xy 381.134366 -224.065592)
			(xy 381.157226 -224.061274) (xy 381.362204 -223.705928) (xy 381.354584 -223.684084) (xy 381.346064 -223.657913)
			(xy 381.336871 -223.603651) (xy 381.336296 -223.576134) (xy 381.336296 -223.575626) (xy 381.336804 -223.549739)
			(xy 381.344903 -223.498601) (xy 381.360902 -223.449361) (xy 381.384408 -223.403229) (xy 381.41484 -223.361342)
			(xy 381.45145 -223.324732) (xy 381.493337 -223.2943) (xy 381.539469 -223.270794) (xy 381.588709 -223.254795)
			(xy 381.639847 -223.246696) (xy 381.691621 -223.246696) (xy 381.742759 -223.254795) (xy 381.791999 -223.270794)
			(xy 381.838131 -223.2943) (xy 381.880018 -223.324732) (xy 381.916628 -223.361342) (xy 381.94706 -223.403229)
			(xy 381.970566 -223.449361) (xy 381.986565 -223.498601) (xy 381.994664 -223.549739) (xy 381.995172 -223.575626)
			(xy 381.994697 -223.600971) (xy 381.986921 -223.651063) (xy 381.971571 -223.699374) (xy 381.949008 -223.744767)
			(xy 381.919766 -223.786173) (xy 381.884531 -223.822617) (xy 381.844135 -223.853239) (xy 381.799528 -223.877319)
			(xy 381.751762 -223.89429) (xy 381.726948 -223.899476) (xy 381.704088 -223.903794) (xy 381.499364 -224.258632)
			(xy 381.506984 -224.280476) (xy 381.515539 -224.306769) (xy 381.524732 -224.361289) (xy 381.525272 -224.388934)
			(xy 381.525272 -224.389442) (xy 381.806196 -224.389442) (xy 381.806704 -224.363555) (xy 381.814803 -224.312417)
			(xy 381.830802 -224.263177) (xy 381.854308 -224.217045) (xy 381.88474 -224.175158) (xy 381.92135 -224.138548)
			(xy 381.963237 -224.108116) (xy 382.009369 -224.08461) (xy 382.058609 -224.068611) (xy 382.109747 -224.060512)
			(xy 382.161521 -224.060512) (xy 382.212659 -224.068611) (xy 382.261899 -224.08461) (xy 382.308031 -224.108116)
			(xy 382.349918 -224.138548) (xy 382.386528 -224.175158) (xy 382.41696 -224.217045) (xy 382.440466 -224.263177)
			(xy 382.456465 -224.312417) (xy 382.464564 -224.363555) (xy 382.465072 -224.389442) (xy 382.464539 -224.41715)
			(xy 382.455342 -224.471795) (xy 382.446784 -224.498154) (xy 382.439164 -224.519998) (xy 382.644142 -224.87509)
			(xy 382.667002 -224.879408) (xy 382.691815 -224.884555) (xy 382.739557 -224.901547) (xy 382.784137 -224.925644)
			(xy 382.824504 -224.95628) (xy 382.859707 -224.992732) (xy 382.888918 -225.034142) (xy 382.911448 -225.079534)
			(xy 382.926766 -225.12784) (xy 382.934512 -225.17792) (xy 382.934972 -225.203258) (xy 382.934464 -225.229145)
			(xy 382.926365 -225.280283) (xy 382.910366 -225.329523) (xy 382.88686 -225.375655) (xy 382.856428 -225.417542)
			(xy 382.819818 -225.454152) (xy 382.777931 -225.484584) (xy 382.731799 -225.50809) (xy 382.682559 -225.524089)
			(xy 382.631421 -225.532188) (xy 382.579647 -225.532188) (xy 382.528509 -225.524089) (xy 382.479269 -225.50809)
			(xy 382.433137 -225.484584) (xy 382.39125 -225.454152) (xy 382.35464 -225.417542) (xy 382.324208 -225.375655)
			(xy 382.300702 -225.329523) (xy 382.284703 -225.280283) (xy 382.276604 -225.229145) (xy 382.276096 -225.203258)
			(xy 382.276096 -225.20275) (xy 382.276653 -225.175107) (xy 382.285844 -225.120589) (xy 382.294384 -225.094292)
			(xy 382.302004 -225.072448) (xy 382.09728 -224.71761) (xy 382.07442 -224.713292) (xy 382.049591 -224.708158)
			(xy 382.001812 -224.691199) (xy 381.957192 -224.667122) (xy 381.916786 -224.636498) (xy 381.881546 -224.600046)
			(xy 381.852303 -224.558629) (xy 381.829748 -224.513222) (xy 381.814412 -224.464896) (xy 381.806657 -224.414792)
			(xy 381.806196 -224.389442) (xy 381.525272 -224.389442) (xy 381.524764 -224.415329) (xy 381.516665 -224.466467)
			(xy 381.500666 -224.515707) (xy 381.47716 -224.561839) (xy 381.446728 -224.603726) (xy 381.410118 -224.640336)
			(xy 381.368231 -224.670768) (xy 381.322099 -224.694274) (xy 381.272859 -224.710273) (xy 381.221721 -224.718372)
			(xy 381.169947 -224.718372) (xy 381.118809 -224.710273) (xy 381.069569 -224.694274) (xy 381.023437 -224.670768)
			(xy 380.98155 -224.640336) (xy 380.94494 -224.603726) (xy 380.914508 -224.561839) (xy 380.891002 -224.515707)
			(xy 380.875003 -224.466467) (xy 380.866904 -224.415329) (xy 380.866396 -224.389442) (xy 380.585472 -224.389442)
			(xy 380.584925 -224.417149) (xy 380.575741 -224.471796) (xy 380.567184 -224.498154) (xy 380.55931 -224.520252)
			(xy 380.764288 -224.87509) (xy 380.787148 -224.879408) (xy 380.811971 -224.884565) (xy 380.859751 -224.90152)
			(xy 380.904371 -224.925592) (xy 380.944778 -224.956214) (xy 380.980019 -224.992662) (xy 381.009263 -225.034077)
			(xy 381.031819 -225.079482) (xy 381.047156 -225.127806) (xy 381.054911 -225.177908) (xy 381.055372 -225.203258)
			(xy 381.054864 -225.229165) (xy 381.046758 -225.280342) (xy 381.030746 -225.329621) (xy 381.007223 -225.375788)
			(xy 380.976767 -225.417707) (xy 380.940129 -225.454345) (xy 380.89821 -225.484801) (xy 380.852043 -225.508324)
			(xy 380.802764 -225.524336) (xy 380.751587 -225.532442) (xy 380.699773 -225.532442) (xy 380.648596 -225.524336)
			(xy 380.599317 -225.508324) (xy 380.55315 -225.484801) (xy 380.511231 -225.454345) (xy 380.474593 -225.417707)
			(xy 380.444137 -225.375788) (xy 380.420614 -225.329621) (xy 380.404602 -225.280342) (xy 380.396496 -225.229165)
			(xy 380.395988 -225.203258) (xy 380.396597 -225.175541) (xy 380.40591 -225.120895) (xy 380.41453 -225.094546)
			(xy 380.422404 -225.072448) (xy 380.217426 -224.71761) (xy 380.194566 -224.713292) (xy 380.169748 -224.708169)
			(xy 380.122005 -224.691172) (xy 380.077426 -224.667071) (xy 380.03706 -224.636431) (xy 380.001857 -224.599976)
			(xy 379.972648 -224.558564) (xy 379.950119 -224.51317) (xy 379.934801 -224.464863) (xy 379.927055 -224.414781)
			(xy 379.926596 -224.389442) (xy 379.645672 -224.389442) (xy 379.645164 -224.415329) (xy 379.637065 -224.466467)
			(xy 379.621066 -224.515707) (xy 379.59756 -224.561839) (xy 379.567128 -224.603726) (xy 379.530518 -224.640336)
			(xy 379.488631 -224.670768) (xy 379.442499 -224.694274) (xy 379.393259 -224.710273) (xy 379.342121 -224.718372)
			(xy 379.290347 -224.718372) (xy 379.239209 -224.710273) (xy 379.189969 -224.694274) (xy 379.143837 -224.670768)
			(xy 379.10195 -224.640336) (xy 379.06534 -224.603726) (xy 379.034908 -224.561839) (xy 379.011402 -224.515707)
			(xy 378.995403 -224.466467) (xy 378.987304 -224.415329) (xy 378.986796 -224.389442) (xy 378.705872 -224.389442)
			(xy 378.705325 -224.417149) (xy 378.696141 -224.471796) (xy 378.687584 -224.498154) (xy 378.67971 -224.520252)
			(xy 378.884688 -224.87509) (xy 378.907548 -224.879408) (xy 378.932371 -224.884565) (xy 378.980151 -224.90152)
			(xy 379.024771 -224.925592) (xy 379.065178 -224.956214) (xy 379.100419 -224.992662) (xy 379.129663 -225.034077)
			(xy 379.152219 -225.079482) (xy 379.167556 -225.127806) (xy 379.175311 -225.177908) (xy 379.175772 -225.203258)
			(xy 379.175264 -225.229165) (xy 379.167158 -225.280342) (xy 379.151146 -225.329621) (xy 379.127623 -225.375788)
			(xy 379.097167 -225.417707) (xy 379.060529 -225.454345) (xy 379.01861 -225.484801) (xy 378.972443 -225.508324)
			(xy 378.923164 -225.524336) (xy 378.871987 -225.532442) (xy 378.820173 -225.532442) (xy 378.768996 -225.524336)
			(xy 378.719717 -225.508324) (xy 378.67355 -225.484801) (xy 378.631631 -225.454345) (xy 378.594993 -225.417707)
			(xy 378.564537 -225.375788) (xy 378.541014 -225.329621) (xy 378.525002 -225.280342) (xy 378.516896 -225.229165)
			(xy 378.516388 -225.203258) (xy 378.516997 -225.175541) (xy 378.52631 -225.120895) (xy 378.53493 -225.094546)
			(xy 378.542804 -225.072448) (xy 378.337826 -224.71761) (xy 378.314966 -224.713292) (xy 378.290148 -224.708169)
			(xy 378.242405 -224.691172) (xy 378.197826 -224.667071) (xy 378.15746 -224.636431) (xy 378.122257 -224.599976)
			(xy 378.093048 -224.558564) (xy 378.070519 -224.51317) (xy 378.055201 -224.464863) (xy 378.047455 -224.414781)
			(xy 378.046996 -224.389442) (xy 377.766072 -224.389442) (xy 377.765564 -224.415329) (xy 377.757465 -224.466467)
			(xy 377.741466 -224.515707) (xy 377.71796 -224.561839) (xy 377.687528 -224.603726) (xy 377.650918 -224.640336)
			(xy 377.609031 -224.670768) (xy 377.562899 -224.694274) (xy 377.513659 -224.710273) (xy 377.462521 -224.718372)
			(xy 377.410747 -224.718372) (xy 377.359609 -224.710273) (xy 377.310369 -224.694274) (xy 377.264237 -224.670768)
			(xy 377.22235 -224.640336) (xy 377.18574 -224.603726) (xy 377.155308 -224.561839) (xy 377.131802 -224.515707)
			(xy 377.115803 -224.466467) (xy 377.107704 -224.415329) (xy 377.107196 -224.389442) (xy 376.826272 -224.389442)
			(xy 376.825725 -224.417149) (xy 376.816541 -224.471796) (xy 376.807984 -224.498154) (xy 376.80011 -224.520252)
			(xy 377.005088 -224.87509) (xy 377.027948 -224.879408) (xy 377.052771 -224.884565) (xy 377.100551 -224.90152)
			(xy 377.145171 -224.925592) (xy 377.185578 -224.956214) (xy 377.220819 -224.992662) (xy 377.250063 -225.034077)
			(xy 377.272619 -225.079482) (xy 377.287956 -225.127806) (xy 377.295711 -225.177908) (xy 377.296172 -225.203258)
			(xy 377.295664 -225.229165) (xy 377.287558 -225.280342) (xy 377.271546 -225.329621) (xy 377.248023 -225.375788)
			(xy 377.217567 -225.417707) (xy 377.180929 -225.454345) (xy 377.13901 -225.484801) (xy 377.092843 -225.508324)
			(xy 377.043564 -225.524336) (xy 376.992387 -225.532442) (xy 376.940573 -225.532442) (xy 376.889396 -225.524336)
			(xy 376.840117 -225.508324) (xy 376.79395 -225.484801) (xy 376.752031 -225.454345) (xy 376.715393 -225.417707)
			(xy 376.684937 -225.375788) (xy 376.661414 -225.329621) (xy 376.645402 -225.280342) (xy 376.637296 -225.229165)
			(xy 376.636788 -225.203258) (xy 376.637397 -225.175541) (xy 376.64671 -225.120895) (xy 376.65533 -225.094546)
			(xy 376.663204 -225.072448) (xy 376.458226 -224.71761) (xy 376.435366 -224.713292) (xy 376.410548 -224.708169)
			(xy 376.362805 -224.691172) (xy 376.318226 -224.667071) (xy 376.27786 -224.636431) (xy 376.242657 -224.599976)
			(xy 376.213448 -224.558564) (xy 376.190919 -224.51317) (xy 376.175601 -224.464863) (xy 376.167855 -224.414781)
			(xy 376.167396 -224.389442) (xy 375.886472 -224.389442) (xy 375.885964 -224.415329) (xy 375.877865 -224.466467)
			(xy 375.861866 -224.515707) (xy 375.83836 -224.561839) (xy 375.807928 -224.603726) (xy 375.771318 -224.640336)
			(xy 375.729431 -224.670768) (xy 375.683299 -224.694274) (xy 375.634059 -224.710273) (xy 375.582921 -224.718372)
			(xy 375.531147 -224.718372) (xy 375.480009 -224.710273) (xy 375.430769 -224.694274) (xy 375.384637 -224.670768)
			(xy 375.34275 -224.640336) (xy 375.30614 -224.603726) (xy 375.275708 -224.561839) (xy 375.252202 -224.515707)
			(xy 375.236203 -224.466467) (xy 375.228104 -224.415329) (xy 375.227596 -224.389442) (xy 374.946672 -224.389442)
			(xy 374.946125 -224.417149) (xy 374.936941 -224.471796) (xy 374.928384 -224.498154) (xy 374.92051 -224.520252)
			(xy 375.125488 -224.87509) (xy 375.148348 -224.879408) (xy 375.173171 -224.884565) (xy 375.220951 -224.90152)
			(xy 375.265571 -224.925592) (xy 375.305978 -224.956214) (xy 375.341219 -224.992662) (xy 375.370463 -225.034077)
			(xy 375.393019 -225.079482) (xy 375.408356 -225.127806) (xy 375.416111 -225.177908) (xy 375.416572 -225.203258)
			(xy 375.416064 -225.229165) (xy 375.407958 -225.280342) (xy 375.391946 -225.329621) (xy 375.368423 -225.375788)
			(xy 375.337967 -225.417707) (xy 375.301329 -225.454345) (xy 375.25941 -225.484801) (xy 375.213243 -225.508324)
			(xy 375.163964 -225.524336) (xy 375.112787 -225.532442) (xy 375.060973 -225.532442) (xy 375.009796 -225.524336)
			(xy 374.960517 -225.508324) (xy 374.91435 -225.484801) (xy 374.872431 -225.454345) (xy 374.835793 -225.417707)
			(xy 374.805337 -225.375788) (xy 374.781814 -225.329621) (xy 374.765802 -225.280342) (xy 374.757696 -225.229165)
			(xy 374.757188 -225.203258) (xy 374.757797 -225.175541) (xy 374.76711 -225.120895) (xy 374.77573 -225.094546)
			(xy 374.783604 -225.072448) (xy 374.578626 -224.71761) (xy 374.555766 -224.713292) (xy 374.530948 -224.708169)
			(xy 374.483205 -224.691172) (xy 374.438626 -224.667071) (xy 374.39826 -224.636431) (xy 374.363057 -224.599976)
			(xy 374.333848 -224.558564) (xy 374.311319 -224.51317) (xy 374.296001 -224.464863) (xy 374.288255 -224.414781)
			(xy 374.287796 -224.389442) (xy 374.006872 -224.389442) (xy 374.006364 -224.415329) (xy 373.998265 -224.466467)
			(xy 373.982266 -224.515707) (xy 373.95876 -224.561839) (xy 373.928328 -224.603726) (xy 373.891718 -224.640336)
			(xy 373.849831 -224.670768) (xy 373.803699 -224.694274) (xy 373.754459 -224.710273) (xy 373.703321 -224.718372)
			(xy 373.651547 -224.718372) (xy 373.600409 -224.710273) (xy 373.551169 -224.694274) (xy 373.505037 -224.670768)
			(xy 373.46315 -224.640336) (xy 373.42654 -224.603726) (xy 373.396108 -224.561839) (xy 373.372602 -224.515707)
			(xy 373.356603 -224.466467) (xy 373.348504 -224.415329) (xy 373.347996 -224.389442) (xy 373.067072 -224.389442)
			(xy 373.066525 -224.417149) (xy 373.057341 -224.471796) (xy 373.048784 -224.498154) (xy 373.04091 -224.520252)
			(xy 373.245888 -224.87509) (xy 373.268748 -224.879408) (xy 373.293571 -224.884565) (xy 373.341351 -224.90152)
			(xy 373.385971 -224.925592) (xy 373.426378 -224.956214) (xy 373.461619 -224.992662) (xy 373.490863 -225.034077)
			(xy 373.513419 -225.079482) (xy 373.528756 -225.127806) (xy 373.536511 -225.177908) (xy 373.536972 -225.203258)
			(xy 373.536464 -225.229165) (xy 373.528358 -225.280342) (xy 373.512346 -225.329621) (xy 373.488823 -225.375788)
			(xy 373.458367 -225.417707) (xy 373.421729 -225.454345) (xy 373.37981 -225.484801) (xy 373.333643 -225.508324)
			(xy 373.284364 -225.524336) (xy 373.233187 -225.532442) (xy 373.181373 -225.532442) (xy 373.130196 -225.524336)
			(xy 373.080917 -225.508324) (xy 373.03475 -225.484801) (xy 372.992831 -225.454345) (xy 372.956193 -225.417707)
			(xy 372.925737 -225.375788) (xy 372.902214 -225.329621) (xy 372.886202 -225.280342) (xy 372.878096 -225.229165)
			(xy 372.877588 -225.203258) (xy 372.878197 -225.175541) (xy 372.88751 -225.120895) (xy 372.89613 -225.094546)
			(xy 372.904004 -225.072448) (xy 372.699026 -224.71761) (xy 372.676166 -224.713292) (xy 372.651348 -224.708169)
			(xy 372.603605 -224.691172) (xy 372.559026 -224.667071) (xy 372.51866 -224.636431) (xy 372.483457 -224.599976)
			(xy 372.454248 -224.558564) (xy 372.431719 -224.51317) (xy 372.416401 -224.464863) (xy 372.408655 -224.414781)
			(xy 372.408196 -224.389442) (xy 372.127272 -224.389442) (xy 372.126764 -224.415329) (xy 372.118665 -224.466467)
			(xy 372.102666 -224.515707) (xy 372.07916 -224.561839) (xy 372.048728 -224.603726) (xy 372.012118 -224.640336)
			(xy 371.970231 -224.670768) (xy 371.924099 -224.694274) (xy 371.874859 -224.710273) (xy 371.823721 -224.718372)
			(xy 371.771947 -224.718372) (xy 371.720809 -224.710273) (xy 371.671569 -224.694274) (xy 371.625437 -224.670768)
			(xy 371.58355 -224.640336) (xy 371.54694 -224.603726) (xy 371.516508 -224.561839) (xy 371.493002 -224.515707)
			(xy 371.477003 -224.466467) (xy 371.468904 -224.415329) (xy 371.468396 -224.389442) (xy 371.187472 -224.389442)
			(xy 371.186925 -224.417149) (xy 371.177741 -224.471796) (xy 371.169184 -224.498154) (xy 371.16131 -224.520252)
			(xy 371.366288 -224.87509) (xy 371.389148 -224.879408) (xy 371.413971 -224.884565) (xy 371.461751 -224.90152)
			(xy 371.506371 -224.925592) (xy 371.546778 -224.956214) (xy 371.582019 -224.992662) (xy 371.611263 -225.034077)
			(xy 371.633819 -225.079482) (xy 371.649156 -225.127806) (xy 371.656911 -225.177908) (xy 371.657372 -225.203258)
			(xy 371.656864 -225.229165) (xy 371.648758 -225.280342) (xy 371.632746 -225.329621) (xy 371.609223 -225.375788)
			(xy 371.578767 -225.417707) (xy 371.542129 -225.454345) (xy 371.50021 -225.484801) (xy 371.454043 -225.508324)
			(xy 371.404764 -225.524336) (xy 371.353587 -225.532442) (xy 371.301773 -225.532442) (xy 371.250596 -225.524336)
			(xy 371.201317 -225.508324) (xy 371.15515 -225.484801) (xy 371.113231 -225.454345) (xy 371.076593 -225.417707)
			(xy 371.046137 -225.375788) (xy 371.022614 -225.329621) (xy 371.006602 -225.280342) (xy 370.998496 -225.229165)
			(xy 370.997988 -225.203258) (xy 370.998597 -225.175541) (xy 371.00791 -225.120895) (xy 371.01653 -225.094546)
			(xy 371.024404 -225.072448) (xy 370.819426 -224.71761) (xy 370.796566 -224.713292) (xy 370.771748 -224.708169)
			(xy 370.724005 -224.691172) (xy 370.679426 -224.667071) (xy 370.63906 -224.636431) (xy 370.603857 -224.599976)
			(xy 370.574648 -224.558564) (xy 370.552119 -224.51317) (xy 370.536801 -224.464863) (xy 370.529055 -224.414781)
			(xy 370.528596 -224.389442) (xy 370.247672 -224.389442) (xy 370.247164 -224.415329) (xy 370.239065 -224.466467)
			(xy 370.223066 -224.515707) (xy 370.19956 -224.561839) (xy 370.169128 -224.603726) (xy 370.132518 -224.640336)
			(xy 370.090631 -224.670768) (xy 370.044499 -224.694274) (xy 369.995259 -224.710273) (xy 369.944121 -224.718372)
			(xy 369.892347 -224.718372) (xy 369.841209 -224.710273) (xy 369.791969 -224.694274) (xy 369.745837 -224.670768)
			(xy 369.70395 -224.640336) (xy 369.66734 -224.603726) (xy 369.636908 -224.561839) (xy 369.613402 -224.515707)
			(xy 369.597403 -224.466467) (xy 369.589304 -224.415329) (xy 369.588796 -224.389442) (xy 369.307872 -224.389442)
			(xy 369.307325 -224.417149) (xy 369.298141 -224.471796) (xy 369.289584 -224.498154) (xy 369.28171 -224.520252)
			(xy 369.486688 -224.87509) (xy 369.509548 -224.879408) (xy 369.534371 -224.884565) (xy 369.582151 -224.90152)
			(xy 369.626771 -224.925592) (xy 369.667178 -224.956214) (xy 369.702419 -224.992662) (xy 369.731663 -225.034077)
			(xy 369.754219 -225.079482) (xy 369.769556 -225.127806) (xy 369.777311 -225.177908) (xy 369.777772 -225.203258)
			(xy 369.777264 -225.229165) (xy 369.769158 -225.280342) (xy 369.753146 -225.329621) (xy 369.729623 -225.375788)
			(xy 369.699167 -225.417707) (xy 369.662529 -225.454345) (xy 369.62061 -225.484801) (xy 369.574443 -225.508324)
			(xy 369.525164 -225.524336) (xy 369.473987 -225.532442) (xy 369.422173 -225.532442) (xy 369.370996 -225.524336)
			(xy 369.321717 -225.508324) (xy 369.27555 -225.484801) (xy 369.233631 -225.454345) (xy 369.196993 -225.417707)
			(xy 369.166537 -225.375788) (xy 369.143014 -225.329621) (xy 369.127002 -225.280342) (xy 369.118896 -225.229165)
			(xy 369.118388 -225.203258) (xy 369.118997 -225.175541) (xy 369.12831 -225.120895) (xy 369.13693 -225.094546)
			(xy 369.144804 -225.072448) (xy 368.939826 -224.71761) (xy 368.916966 -224.713292) (xy 368.892148 -224.708169)
			(xy 368.844405 -224.691172) (xy 368.799826 -224.667071) (xy 368.75946 -224.636431) (xy 368.724257 -224.599976)
			(xy 368.695048 -224.558564) (xy 368.672519 -224.51317) (xy 368.657201 -224.464863) (xy 368.649455 -224.414781)
			(xy 368.648996 -224.389442) (xy 368.368072 -224.389442) (xy 368.367564 -224.415329) (xy 368.359465 -224.466467)
			(xy 368.343466 -224.515707) (xy 368.31996 -224.561839) (xy 368.289528 -224.603726) (xy 368.252918 -224.640336)
			(xy 368.211031 -224.670768) (xy 368.164899 -224.694274) (xy 368.115659 -224.710273) (xy 368.064521 -224.718372)
			(xy 368.012747 -224.718372) (xy 367.961609 -224.710273) (xy 367.912369 -224.694274) (xy 367.866237 -224.670768)
			(xy 367.82435 -224.640336) (xy 367.78774 -224.603726) (xy 367.757308 -224.561839) (xy 367.733802 -224.515707)
			(xy 367.717803 -224.466467) (xy 367.709704 -224.415329) (xy 367.709196 -224.389442) (xy 367.428272 -224.389442)
			(xy 367.427725 -224.417149) (xy 367.418541 -224.471796) (xy 367.409984 -224.498154) (xy 367.40211 -224.520252)
			(xy 367.607088 -224.87509) (xy 367.629948 -224.879408) (xy 367.654771 -224.884565) (xy 367.702551 -224.90152)
			(xy 367.747171 -224.925592) (xy 367.787578 -224.956214) (xy 367.822819 -224.992662) (xy 367.852063 -225.034077)
			(xy 367.874619 -225.079482) (xy 367.889956 -225.127806) (xy 367.897711 -225.177908) (xy 367.898172 -225.203258)
			(xy 367.897664 -225.229165) (xy 367.889558 -225.280342) (xy 367.873546 -225.329621) (xy 367.850023 -225.375788)
			(xy 367.819567 -225.417707) (xy 367.782929 -225.454345) (xy 367.74101 -225.484801) (xy 367.694843 -225.508324)
			(xy 367.645564 -225.524336) (xy 367.594387 -225.532442) (xy 367.542573 -225.532442) (xy 367.491396 -225.524336)
			(xy 367.442117 -225.508324) (xy 367.39595 -225.484801) (xy 367.354031 -225.454345) (xy 367.317393 -225.417707)
			(xy 367.286937 -225.375788) (xy 367.263414 -225.329621) (xy 367.247402 -225.280342) (xy 367.239296 -225.229165)
			(xy 367.238788 -225.203258) (xy 367.239397 -225.175541) (xy 367.24871 -225.120895) (xy 367.25733 -225.094546)
			(xy 367.265204 -225.072448) (xy 367.060226 -224.71761) (xy 367.037366 -224.713292) (xy 367.012548 -224.708169)
			(xy 366.964805 -224.691172) (xy 366.920226 -224.667071) (xy 366.87986 -224.636431) (xy 366.844657 -224.599976)
			(xy 366.815448 -224.558564) (xy 366.792919 -224.51317) (xy 366.777601 -224.464863) (xy 366.769855 -224.414781)
			(xy 366.769396 -224.389442) (xy 366.488472 -224.389442) (xy 366.487964 -224.415329) (xy 366.479865 -224.466467)
			(xy 366.463866 -224.515707) (xy 366.44036 -224.561839) (xy 366.409928 -224.603726) (xy 366.373318 -224.640336)
			(xy 366.331431 -224.670768) (xy 366.285299 -224.694274) (xy 366.236059 -224.710273) (xy 366.184921 -224.718372)
			(xy 366.133147 -224.718372) (xy 366.082009 -224.710273) (xy 366.032769 -224.694274) (xy 365.986637 -224.670768)
			(xy 365.94475 -224.640336) (xy 365.90814 -224.603726) (xy 365.877708 -224.561839) (xy 365.854202 -224.515707)
			(xy 365.838203 -224.466467) (xy 365.830104 -224.415329) (xy 365.829596 -224.389442) (xy 365.548672 -224.389442)
			(xy 365.548125 -224.417149) (xy 365.538941 -224.471796) (xy 365.530384 -224.498154) (xy 365.52251 -224.520252)
			(xy 365.727488 -224.87509) (xy 365.750348 -224.879408) (xy 365.775171 -224.884565) (xy 365.822951 -224.90152)
			(xy 365.867571 -224.925592) (xy 365.907978 -224.956214) (xy 365.943219 -224.992662) (xy 365.972463 -225.034077)
			(xy 365.995019 -225.079482) (xy 366.010356 -225.127806) (xy 366.018111 -225.177908) (xy 366.018572 -225.203258)
			(xy 366.018064 -225.229165) (xy 366.009958 -225.280342) (xy 365.993946 -225.329621) (xy 365.970423 -225.375788)
			(xy 365.939967 -225.417707) (xy 365.903329 -225.454345) (xy 365.86141 -225.484801) (xy 365.815243 -225.508324)
			(xy 365.765964 -225.524336) (xy 365.714787 -225.532442) (xy 365.662973 -225.532442) (xy 365.611796 -225.524336)
			(xy 365.562517 -225.508324) (xy 365.51635 -225.484801) (xy 365.474431 -225.454345) (xy 365.437793 -225.417707)
			(xy 365.407337 -225.375788) (xy 365.383814 -225.329621) (xy 365.367802 -225.280342) (xy 365.359696 -225.229165)
			(xy 365.359188 -225.203258) (xy 365.359797 -225.175541) (xy 365.36911 -225.120895) (xy 365.37773 -225.094546)
			(xy 365.385604 -225.072448) (xy 365.180626 -224.71761) (xy 365.157766 -224.713292) (xy 365.132948 -224.708169)
			(xy 365.085205 -224.691172) (xy 365.040626 -224.667071) (xy 365.00026 -224.636431) (xy 364.965057 -224.599976)
			(xy 364.935848 -224.558564) (xy 364.913319 -224.51317) (xy 364.898001 -224.464863) (xy 364.890255 -224.414781)
			(xy 364.889796 -224.389442) (xy 364.608872 -224.389442) (xy 364.608364 -224.415329) (xy 364.600265 -224.466467)
			(xy 364.584266 -224.515707) (xy 364.56076 -224.561839) (xy 364.530328 -224.603726) (xy 364.493718 -224.640336)
			(xy 364.451831 -224.670768) (xy 364.405699 -224.694274) (xy 364.356459 -224.710273) (xy 364.305321 -224.718372)
			(xy 364.253547 -224.718372) (xy 364.202409 -224.710273) (xy 364.153169 -224.694274) (xy 364.107037 -224.670768)
			(xy 364.06515 -224.640336) (xy 364.02854 -224.603726) (xy 363.998108 -224.561839) (xy 363.974602 -224.515707)
			(xy 363.958603 -224.466467) (xy 363.950504 -224.415329) (xy 363.949996 -224.389442) (xy 363.669072 -224.389442)
			(xy 363.668525 -224.417149) (xy 363.659341 -224.471796) (xy 363.650784 -224.498154) (xy 363.64291 -224.520252)
			(xy 363.847888 -224.87509) (xy 363.870748 -224.879408) (xy 363.895571 -224.884565) (xy 363.943351 -224.90152)
			(xy 363.987971 -224.925592) (xy 364.028378 -224.956214) (xy 364.063619 -224.992662) (xy 364.092863 -225.034077)
			(xy 364.115419 -225.079482) (xy 364.130756 -225.127806) (xy 364.138511 -225.177908) (xy 364.138972 -225.203258)
			(xy 364.138464 -225.229165) (xy 364.130358 -225.280342) (xy 364.114346 -225.329621) (xy 364.090823 -225.375788)
			(xy 364.060367 -225.417707) (xy 364.023729 -225.454345) (xy 363.98181 -225.484801) (xy 363.935643 -225.508324)
			(xy 363.886364 -225.524336) (xy 363.835187 -225.532442) (xy 363.783373 -225.532442) (xy 363.732196 -225.524336)
			(xy 363.682917 -225.508324) (xy 363.63675 -225.484801) (xy 363.594831 -225.454345) (xy 363.558193 -225.417707)
			(xy 363.527737 -225.375788) (xy 363.504214 -225.329621) (xy 363.488202 -225.280342) (xy 363.480096 -225.229165)
			(xy 363.479588 -225.203258) (xy 363.480197 -225.175541) (xy 363.48951 -225.120895) (xy 363.49813 -225.094546)
			(xy 363.506004 -225.072448) (xy 363.301026 -224.71761) (xy 363.278166 -224.713292) (xy 363.253348 -224.708169)
			(xy 363.205605 -224.691172) (xy 363.161026 -224.667071) (xy 363.12066 -224.636431) (xy 363.085457 -224.599976)
			(xy 363.056248 -224.558564) (xy 363.033719 -224.51317) (xy 363.018401 -224.464863) (xy 363.010655 -224.414781)
			(xy 363.010196 -224.389442) (xy 362.729272 -224.389442) (xy 362.728764 -224.415329) (xy 362.720665 -224.466467)
			(xy 362.704666 -224.515707) (xy 362.68116 -224.561839) (xy 362.650728 -224.603726) (xy 362.614118 -224.640336)
			(xy 362.572231 -224.670768) (xy 362.526099 -224.694274) (xy 362.476859 -224.710273) (xy 362.425721 -224.718372)
			(xy 362.373947 -224.718372) (xy 362.322809 -224.710273) (xy 362.273569 -224.694274) (xy 362.227437 -224.670768)
			(xy 362.18555 -224.640336) (xy 362.14894 -224.603726) (xy 362.118508 -224.561839) (xy 362.095002 -224.515707)
			(xy 362.079003 -224.466467) (xy 362.070904 -224.415329) (xy 362.070396 -224.389442) (xy 361.789472 -224.389442)
			(xy 361.788925 -224.417149) (xy 361.779741 -224.471796) (xy 361.771184 -224.498154) (xy 361.76331 -224.520252)
			(xy 361.968288 -224.87509) (xy 361.991148 -224.879408) (xy 362.015971 -224.884565) (xy 362.063751 -224.90152)
			(xy 362.108371 -224.925592) (xy 362.148778 -224.956214) (xy 362.184019 -224.992662) (xy 362.213263 -225.034077)
			(xy 362.235819 -225.079482) (xy 362.251156 -225.127806) (xy 362.258911 -225.177908) (xy 362.259372 -225.203258)
			(xy 362.258864 -225.229165) (xy 362.250758 -225.280342) (xy 362.234746 -225.329621) (xy 362.211223 -225.375788)
			(xy 362.180767 -225.417707) (xy 362.144129 -225.454345) (xy 362.10221 -225.484801) (xy 362.056043 -225.508324)
			(xy 362.006764 -225.524336) (xy 361.955587 -225.532442) (xy 361.903773 -225.532442) (xy 361.852596 -225.524336)
			(xy 361.803317 -225.508324) (xy 361.75715 -225.484801) (xy 361.715231 -225.454345) (xy 361.678593 -225.417707)
			(xy 361.648137 -225.375788) (xy 361.624614 -225.329621) (xy 361.608602 -225.280342) (xy 361.600496 -225.229165)
			(xy 361.599988 -225.203258) (xy 361.600597 -225.175541) (xy 361.60991 -225.120895) (xy 361.61853 -225.094546)
			(xy 361.626404 -225.072448) (xy 361.421426 -224.71761) (xy 361.398566 -224.713292) (xy 361.373748 -224.708169)
			(xy 361.326005 -224.691172) (xy 361.281426 -224.667071) (xy 361.24106 -224.636431) (xy 361.205857 -224.599976)
			(xy 361.176648 -224.558564) (xy 361.154119 -224.51317) (xy 361.138801 -224.464863) (xy 361.131055 -224.414781)
			(xy 361.130596 -224.389442) (xy 360.849672 -224.389442) (xy 360.849164 -224.415329) (xy 360.841065 -224.466467)
			(xy 360.825066 -224.515707) (xy 360.80156 -224.561839) (xy 360.771128 -224.603726) (xy 360.734518 -224.640336)
			(xy 360.692631 -224.670768) (xy 360.646499 -224.694274) (xy 360.597259 -224.710273) (xy 360.546121 -224.718372)
			(xy 360.494347 -224.718372) (xy 360.443209 -224.710273) (xy 360.393969 -224.694274) (xy 360.347837 -224.670768)
			(xy 360.30595 -224.640336) (xy 360.26934 -224.603726) (xy 360.238908 -224.561839) (xy 360.215402 -224.515707)
			(xy 360.199403 -224.466467) (xy 360.191304 -224.415329) (xy 360.190796 -224.389442) (xy 359.909872 -224.389442)
			(xy 359.909325 -224.417149) (xy 359.900141 -224.471796) (xy 359.891584 -224.498154) (xy 359.88371 -224.520252)
			(xy 360.088688 -224.87509) (xy 360.111548 -224.879408) (xy 360.136371 -224.884565) (xy 360.184151 -224.90152)
			(xy 360.228771 -224.925592) (xy 360.269178 -224.956214) (xy 360.304419 -224.992662) (xy 360.333663 -225.034077)
			(xy 360.356219 -225.079482) (xy 360.371556 -225.127806) (xy 360.379311 -225.177908) (xy 360.379772 -225.203258)
			(xy 360.379264 -225.229165) (xy 360.371158 -225.280342) (xy 360.355146 -225.329621) (xy 360.331623 -225.375788)
			(xy 360.301167 -225.417707) (xy 360.264529 -225.454345) (xy 360.22261 -225.484801) (xy 360.176443 -225.508324)
			(xy 360.127164 -225.524336) (xy 360.075987 -225.532442) (xy 360.024173 -225.532442) (xy 359.972996 -225.524336)
			(xy 359.923717 -225.508324) (xy 359.87755 -225.484801) (xy 359.835631 -225.454345) (xy 359.798993 -225.417707)
			(xy 359.768537 -225.375788) (xy 359.745014 -225.329621) (xy 359.729002 -225.280342) (xy 359.720896 -225.229165)
			(xy 359.720388 -225.203258) (xy 359.720997 -225.175541) (xy 359.73031 -225.120895) (xy 359.73893 -225.094546)
			(xy 359.746804 -225.072448) (xy 359.541826 -224.71761) (xy 359.518966 -224.713292) (xy 359.494148 -224.708169)
			(xy 359.446405 -224.691172) (xy 359.401826 -224.667071) (xy 359.36146 -224.636431) (xy 359.326257 -224.599976)
			(xy 359.297048 -224.558564) (xy 359.274519 -224.51317) (xy 359.259201 -224.464863) (xy 359.251455 -224.414781)
			(xy 359.250996 -224.389442) (xy 358.970072 -224.389442) (xy 358.969564 -224.415329) (xy 358.961465 -224.466467)
			(xy 358.945466 -224.515707) (xy 358.92196 -224.561839) (xy 358.891528 -224.603726) (xy 358.854918 -224.640336)
			(xy 358.813031 -224.670768) (xy 358.766899 -224.694274) (xy 358.717659 -224.710273) (xy 358.666521 -224.718372)
			(xy 358.614747 -224.718372) (xy 358.563609 -224.710273) (xy 358.514369 -224.694274) (xy 358.468237 -224.670768)
			(xy 358.42635 -224.640336) (xy 358.38974 -224.603726) (xy 358.359308 -224.561839) (xy 358.335802 -224.515707)
			(xy 358.319803 -224.466467) (xy 358.311704 -224.415329) (xy 358.311196 -224.389442) (xy 358.030272 -224.389442)
			(xy 358.029725 -224.417149) (xy 358.020541 -224.471796) (xy 358.011984 -224.498154) (xy 358.00411 -224.520252)
			(xy 358.209088 -224.87509) (xy 358.231948 -224.879408) (xy 358.256771 -224.884565) (xy 358.304551 -224.90152)
			(xy 358.349171 -224.925592) (xy 358.389578 -224.956214) (xy 358.424819 -224.992662) (xy 358.454063 -225.034077)
			(xy 358.476619 -225.079482) (xy 358.491956 -225.127806) (xy 358.499711 -225.177908) (xy 358.500172 -225.203258)
			(xy 358.499664 -225.229165) (xy 358.491558 -225.280342) (xy 358.475546 -225.329621) (xy 358.452023 -225.375788)
			(xy 358.421567 -225.417707) (xy 358.384929 -225.454345) (xy 358.34301 -225.484801) (xy 358.296843 -225.508324)
			(xy 358.247564 -225.524336) (xy 358.196387 -225.532442) (xy 358.144573 -225.532442) (xy 358.093396 -225.524336)
			(xy 358.044117 -225.508324) (xy 357.99795 -225.484801) (xy 357.956031 -225.454345) (xy 357.919393 -225.417707)
			(xy 357.888937 -225.375788) (xy 357.865414 -225.329621) (xy 357.849402 -225.280342) (xy 357.841296 -225.229165)
			(xy 357.840788 -225.203258) (xy 357.841397 -225.175541) (xy 357.85071 -225.120895) (xy 357.85933 -225.094546)
			(xy 357.867204 -225.072448) (xy 357.662226 -224.71761) (xy 357.639366 -224.713292) (xy 357.614548 -224.708169)
			(xy 357.566805 -224.691172) (xy 357.522226 -224.667071) (xy 357.48186 -224.636431) (xy 357.446657 -224.599976)
			(xy 357.417448 -224.558564) (xy 357.394919 -224.51317) (xy 357.379601 -224.464863) (xy 357.371855 -224.414781)
			(xy 357.371396 -224.389442) (xy 357.090472 -224.389442) (xy 357.089964 -224.415329) (xy 357.081865 -224.466467)
			(xy 357.065866 -224.515707) (xy 357.04236 -224.561839) (xy 357.011928 -224.603726) (xy 356.975318 -224.640336)
			(xy 356.933431 -224.670768) (xy 356.887299 -224.694274) (xy 356.838059 -224.710273) (xy 356.786921 -224.718372)
			(xy 356.735147 -224.718372) (xy 356.684009 -224.710273) (xy 356.634769 -224.694274) (xy 356.588637 -224.670768)
			(xy 356.54675 -224.640336) (xy 356.51014 -224.603726) (xy 356.479708 -224.561839) (xy 356.456202 -224.515707)
			(xy 356.440203 -224.466467) (xy 356.432104 -224.415329) (xy 356.431596 -224.389442) (xy 356.150672 -224.389442)
			(xy 356.150125 -224.417149) (xy 356.140941 -224.471796) (xy 356.132384 -224.498154) (xy 356.12451 -224.520252)
			(xy 356.329488 -224.87509) (xy 356.352348 -224.879408) (xy 356.377171 -224.884565) (xy 356.424951 -224.90152)
			(xy 356.469571 -224.925592) (xy 356.509978 -224.956214) (xy 356.545219 -224.992662) (xy 356.574463 -225.034077)
			(xy 356.597019 -225.079482) (xy 356.612356 -225.127806) (xy 356.620111 -225.177908) (xy 356.620572 -225.203258)
			(xy 356.620064 -225.229165) (xy 356.611958 -225.280342) (xy 356.595946 -225.329621) (xy 356.572423 -225.375788)
			(xy 356.541967 -225.417707) (xy 356.505329 -225.454345) (xy 356.46341 -225.484801) (xy 356.417243 -225.508324)
			(xy 356.367964 -225.524336) (xy 356.316787 -225.532442) (xy 356.264973 -225.532442) (xy 356.213796 -225.524336)
			(xy 356.164517 -225.508324) (xy 356.11835 -225.484801) (xy 356.076431 -225.454345) (xy 356.039793 -225.417707)
			(xy 356.009337 -225.375788) (xy 355.985814 -225.329621) (xy 355.969802 -225.280342) (xy 355.961696 -225.229165)
			(xy 355.961188 -225.203258) (xy 355.961797 -225.175541) (xy 355.97111 -225.120895) (xy 355.97973 -225.094546)
			(xy 355.987604 -225.072448) (xy 355.782626 -224.71761) (xy 355.759766 -224.713292) (xy 355.734948 -224.708169)
			(xy 355.687205 -224.691172) (xy 355.642626 -224.667071) (xy 355.60226 -224.636431) (xy 355.567057 -224.599976)
			(xy 355.537848 -224.558564) (xy 355.515319 -224.51317) (xy 355.500001 -224.464863) (xy 355.492255 -224.414781)
			(xy 355.491796 -224.389442) (xy 355.210872 -224.389442) (xy 355.210364 -224.415329) (xy 355.202265 -224.466467)
			(xy 355.186266 -224.515707) (xy 355.16276 -224.561839) (xy 355.132328 -224.603726) (xy 355.095718 -224.640336)
			(xy 355.053831 -224.670768) (xy 355.007699 -224.694274) (xy 354.958459 -224.710273) (xy 354.907321 -224.718372)
			(xy 354.855547 -224.718372) (xy 354.804409 -224.710273) (xy 354.755169 -224.694274) (xy 354.709037 -224.670768)
			(xy 354.66715 -224.640336) (xy 354.63054 -224.603726) (xy 354.600108 -224.561839) (xy 354.576602 -224.515707)
			(xy 354.560603 -224.466467) (xy 354.552504 -224.415329) (xy 354.551996 -224.389442) (xy 354.271072 -224.389442)
			(xy 354.270525 -224.417149) (xy 354.261341 -224.471796) (xy 354.252784 -224.498154) (xy 354.24491 -224.520252)
			(xy 354.449888 -224.87509) (xy 354.472748 -224.879408) (xy 354.497571 -224.884565) (xy 354.545351 -224.90152)
			(xy 354.589971 -224.925592) (xy 354.630378 -224.956214) (xy 354.665619 -224.992662) (xy 354.694863 -225.034077)
			(xy 354.717419 -225.079482) (xy 354.732756 -225.127806) (xy 354.740511 -225.177908) (xy 354.740972 -225.203258)
			(xy 354.740464 -225.229165) (xy 354.732358 -225.280342) (xy 354.716346 -225.329621) (xy 354.692823 -225.375788)
			(xy 354.662367 -225.417707) (xy 354.625729 -225.454345) (xy 354.58381 -225.484801) (xy 354.537643 -225.508324)
			(xy 354.488364 -225.524336) (xy 354.437187 -225.532442) (xy 354.385373 -225.532442) (xy 354.334196 -225.524336)
			(xy 354.284917 -225.508324) (xy 354.23875 -225.484801) (xy 354.196831 -225.454345) (xy 354.160193 -225.417707)
			(xy 354.129737 -225.375788) (xy 354.106214 -225.329621) (xy 354.090202 -225.280342) (xy 354.082096 -225.229165)
			(xy 354.081588 -225.203258) (xy 354.082197 -225.175541) (xy 354.09151 -225.120895) (xy 354.10013 -225.094546)
			(xy 354.108004 -225.072448) (xy 353.903026 -224.71761) (xy 353.880166 -224.713292) (xy 353.855348 -224.708169)
			(xy 353.807605 -224.691172) (xy 353.763026 -224.667071) (xy 353.72266 -224.636431) (xy 353.687457 -224.599976)
			(xy 353.658248 -224.558564) (xy 353.635719 -224.51317) (xy 353.620401 -224.464863) (xy 353.612655 -224.414781)
			(xy 353.612196 -224.389442) (xy 353.331272 -224.389442) (xy 353.330764 -224.415329) (xy 353.322665 -224.466467)
			(xy 353.306666 -224.515707) (xy 353.28316 -224.561839) (xy 353.252728 -224.603726) (xy 353.216118 -224.640336)
			(xy 353.174231 -224.670768) (xy 353.128099 -224.694274) (xy 353.078859 -224.710273) (xy 353.027721 -224.718372)
			(xy 352.975947 -224.718372) (xy 352.924809 -224.710273) (xy 352.875569 -224.694274) (xy 352.829437 -224.670768)
			(xy 352.78755 -224.640336) (xy 352.75094 -224.603726) (xy 352.720508 -224.561839) (xy 352.697002 -224.515707)
			(xy 352.681003 -224.466467) (xy 352.672904 -224.415329) (xy 352.672396 -224.389442) (xy 352.391472 -224.389442)
			(xy 352.390925 -224.417149) (xy 352.381741 -224.471796) (xy 352.373184 -224.498154) (xy 352.36531 -224.520252)
			(xy 352.570288 -224.87509) (xy 352.593148 -224.879408) (xy 352.617971 -224.884565) (xy 352.665751 -224.90152)
			(xy 352.710371 -224.925592) (xy 352.750778 -224.956214) (xy 352.786019 -224.992662) (xy 352.815263 -225.034077)
			(xy 352.837819 -225.079482) (xy 352.853156 -225.127806) (xy 352.860911 -225.177908) (xy 352.861372 -225.203258)
			(xy 352.860864 -225.229165) (xy 352.852758 -225.280342) (xy 352.836746 -225.329621) (xy 352.813223 -225.375788)
			(xy 352.782767 -225.417707) (xy 352.746129 -225.454345) (xy 352.70421 -225.484801) (xy 352.658043 -225.508324)
			(xy 352.608764 -225.524336) (xy 352.557587 -225.532442) (xy 352.505773 -225.532442) (xy 352.454596 -225.524336)
			(xy 352.405317 -225.508324) (xy 352.35915 -225.484801) (xy 352.317231 -225.454345) (xy 352.280593 -225.417707)
			(xy 352.250137 -225.375788) (xy 352.226614 -225.329621) (xy 352.210602 -225.280342) (xy 352.202496 -225.229165)
			(xy 352.201988 -225.203258) (xy 352.202597 -225.175541) (xy 352.21191 -225.120895) (xy 352.22053 -225.094546)
			(xy 352.228404 -225.072448) (xy 352.023426 -224.71761) (xy 352.000566 -224.713292) (xy 351.975748 -224.708169)
			(xy 351.928005 -224.691172) (xy 351.883426 -224.667071) (xy 351.84306 -224.636431) (xy 351.807857 -224.599976)
			(xy 351.778648 -224.558564) (xy 351.756119 -224.51317) (xy 351.740801 -224.464863) (xy 351.733055 -224.414781)
			(xy 351.732596 -224.389442) (xy 351.451672 -224.389442) (xy 351.451164 -224.415329) (xy 351.443065 -224.466467)
			(xy 351.427066 -224.515707) (xy 351.40356 -224.561839) (xy 351.373128 -224.603726) (xy 351.336518 -224.640336)
			(xy 351.294631 -224.670768) (xy 351.248499 -224.694274) (xy 351.199259 -224.710273) (xy 351.148121 -224.718372)
			(xy 351.096347 -224.718372) (xy 351.045209 -224.710273) (xy 350.995969 -224.694274) (xy 350.949837 -224.670768)
			(xy 350.90795 -224.640336) (xy 350.87134 -224.603726) (xy 350.840908 -224.561839) (xy 350.817402 -224.515707)
			(xy 350.801403 -224.466467) (xy 350.793304 -224.415329) (xy 350.792796 -224.389442) (xy 350.511872 -224.389442)
			(xy 350.511325 -224.417149) (xy 350.502141 -224.471796) (xy 350.493584 -224.498154) (xy 350.48571 -224.520252)
			(xy 350.690688 -224.87509) (xy 350.713548 -224.879408) (xy 350.738371 -224.884565) (xy 350.786151 -224.90152)
			(xy 350.830771 -224.925592) (xy 350.871178 -224.956214) (xy 350.906419 -224.992662) (xy 350.935663 -225.034077)
			(xy 350.958219 -225.079482) (xy 350.973556 -225.127806) (xy 350.981311 -225.177908) (xy 350.981772 -225.203258)
			(xy 350.981264 -225.229165) (xy 350.973158 -225.280342) (xy 350.957146 -225.329621) (xy 350.933623 -225.375788)
			(xy 350.903167 -225.417707) (xy 350.866529 -225.454345) (xy 350.82461 -225.484801) (xy 350.778443 -225.508324)
			(xy 350.729164 -225.524336) (xy 350.677987 -225.532442) (xy 350.626173 -225.532442) (xy 350.574996 -225.524336)
			(xy 350.525717 -225.508324) (xy 350.47955 -225.484801) (xy 350.437631 -225.454345) (xy 350.400993 -225.417707)
			(xy 350.370537 -225.375788) (xy 350.347014 -225.329621) (xy 350.331002 -225.280342) (xy 350.322896 -225.229165)
			(xy 350.322388 -225.203258) (xy 350.322997 -225.175541) (xy 350.33231 -225.120895) (xy 350.34093 -225.094546)
			(xy 350.348804 -225.072448) (xy 350.143826 -224.71761) (xy 350.120966 -224.713292) (xy 350.096148 -224.708169)
			(xy 350.048405 -224.691172) (xy 350.003826 -224.667071) (xy 349.96346 -224.636431) (xy 349.928257 -224.599976)
			(xy 349.899048 -224.558564) (xy 349.876519 -224.51317) (xy 349.861201 -224.464863) (xy 349.853455 -224.414781)
			(xy 349.852996 -224.389442) (xy 349.572072 -224.389442) (xy 349.571564 -224.415329) (xy 349.563465 -224.466467)
			(xy 349.547466 -224.515707) (xy 349.52396 -224.561839) (xy 349.493528 -224.603726) (xy 349.456918 -224.640336)
			(xy 349.415031 -224.670768) (xy 349.368899 -224.694274) (xy 349.319659 -224.710273) (xy 349.268521 -224.718372)
			(xy 349.216747 -224.718372) (xy 349.165609 -224.710273) (xy 349.116369 -224.694274) (xy 349.070237 -224.670768)
			(xy 349.02835 -224.640336) (xy 348.99174 -224.603726) (xy 348.961308 -224.561839) (xy 348.937802 -224.515707)
			(xy 348.921803 -224.466467) (xy 348.913704 -224.415329) (xy 348.913196 -224.389442) (xy 348.632272 -224.389442)
			(xy 348.631725 -224.417149) (xy 348.622541 -224.471796) (xy 348.613984 -224.498154) (xy 348.60611 -224.520252)
			(xy 348.811088 -224.87509) (xy 348.833948 -224.879408) (xy 348.858771 -224.884565) (xy 348.906551 -224.90152)
			(xy 348.951171 -224.925592) (xy 348.991578 -224.956214) (xy 349.026819 -224.992662) (xy 349.056063 -225.034077)
			(xy 349.078619 -225.079482) (xy 349.093956 -225.127806) (xy 349.101711 -225.177908) (xy 349.102172 -225.203258)
			(xy 349.101664 -225.229165) (xy 349.093558 -225.280342) (xy 349.077546 -225.329621) (xy 349.054023 -225.375788)
			(xy 349.023567 -225.417707) (xy 348.986929 -225.454345) (xy 348.94501 -225.484801) (xy 348.898843 -225.508324)
			(xy 348.849564 -225.524336) (xy 348.798387 -225.532442) (xy 348.746573 -225.532442) (xy 348.695396 -225.524336)
			(xy 348.646117 -225.508324) (xy 348.59995 -225.484801) (xy 348.558031 -225.454345) (xy 348.521393 -225.417707)
			(xy 348.490937 -225.375788) (xy 348.467414 -225.329621) (xy 348.451402 -225.280342) (xy 348.443296 -225.229165)
			(xy 348.442788 -225.203258) (xy 348.443397 -225.175541) (xy 348.45271 -225.120895) (xy 348.46133 -225.094546)
			(xy 348.469204 -225.072448) (xy 348.264226 -224.71761) (xy 348.241366 -224.713292) (xy 348.216548 -224.708169)
			(xy 348.168805 -224.691172) (xy 348.124226 -224.667071) (xy 348.08386 -224.636431) (xy 348.048657 -224.599976)
			(xy 348.019448 -224.558564) (xy 347.996919 -224.51317) (xy 347.981601 -224.464863) (xy 347.973855 -224.414781)
			(xy 347.973396 -224.389442) (xy 347.692472 -224.389442) (xy 347.691964 -224.415329) (xy 347.683865 -224.466467)
			(xy 347.667866 -224.515707) (xy 347.64436 -224.561839) (xy 347.613928 -224.603726) (xy 347.577318 -224.640336)
			(xy 347.535431 -224.670768) (xy 347.489299 -224.694274) (xy 347.440059 -224.710273) (xy 347.388921 -224.718372)
			(xy 347.337147 -224.718372) (xy 347.286009 -224.710273) (xy 347.236769 -224.694274) (xy 347.190637 -224.670768)
			(xy 347.14875 -224.640336) (xy 347.11214 -224.603726) (xy 347.081708 -224.561839) (xy 347.058202 -224.515707)
			(xy 347.042203 -224.466467) (xy 347.034104 -224.415329) (xy 347.033596 -224.389442) (xy 346.752672 -224.389442)
			(xy 346.752125 -224.417149) (xy 346.742941 -224.471796) (xy 346.734384 -224.498154) (xy 346.72651 -224.520252)
			(xy 346.931488 -224.87509) (xy 346.954348 -224.879408) (xy 346.979171 -224.884565) (xy 347.026951 -224.90152)
			(xy 347.071571 -224.925592) (xy 347.111978 -224.956214) (xy 347.147219 -224.992662) (xy 347.176463 -225.034077)
			(xy 347.199019 -225.079482) (xy 347.214356 -225.127806) (xy 347.222111 -225.177908) (xy 347.222572 -225.203258)
			(xy 347.222064 -225.229165) (xy 347.213958 -225.280342) (xy 347.197946 -225.329621) (xy 347.174423 -225.375788)
			(xy 347.143967 -225.417707) (xy 347.107329 -225.454345) (xy 347.06541 -225.484801) (xy 347.019243 -225.508324)
			(xy 346.969964 -225.524336) (xy 346.918787 -225.532442) (xy 346.866973 -225.532442) (xy 346.815796 -225.524336)
			(xy 346.766517 -225.508324) (xy 346.72035 -225.484801) (xy 346.678431 -225.454345) (xy 346.641793 -225.417707)
			(xy 346.611337 -225.375788) (xy 346.587814 -225.329621) (xy 346.571802 -225.280342) (xy 346.563696 -225.229165)
			(xy 346.563188 -225.203258) (xy 346.563797 -225.175541) (xy 346.57311 -225.120895) (xy 346.58173 -225.094546)
			(xy 346.589604 -225.072448) (xy 346.384626 -224.71761) (xy 346.361766 -224.713292) (xy 346.336948 -224.708169)
			(xy 346.289205 -224.691172) (xy 346.244626 -224.667071) (xy 346.20426 -224.636431) (xy 346.169057 -224.599976)
			(xy 346.139848 -224.558564) (xy 346.117319 -224.51317) (xy 346.102001 -224.464863) (xy 346.094255 -224.414781)
			(xy 346.093796 -224.389442) (xy 345.812872 -224.389442) (xy 345.812364 -224.415329) (xy 345.804265 -224.466467)
			(xy 345.788266 -224.515707) (xy 345.76476 -224.561839) (xy 345.734328 -224.603726) (xy 345.697718 -224.640336)
			(xy 345.655831 -224.670768) (xy 345.609699 -224.694274) (xy 345.560459 -224.710273) (xy 345.509321 -224.718372)
			(xy 345.457547 -224.718372) (xy 345.406409 -224.710273) (xy 345.357169 -224.694274) (xy 345.311037 -224.670768)
			(xy 345.26915 -224.640336) (xy 345.23254 -224.603726) (xy 345.202108 -224.561839) (xy 345.178602 -224.515707)
			(xy 345.162603 -224.466467) (xy 345.154504 -224.415329) (xy 345.153996 -224.389442) (xy 344.873072 -224.389442)
			(xy 344.872525 -224.417149) (xy 344.863341 -224.471796) (xy 344.854784 -224.498154) (xy 344.84691 -224.520252)
			(xy 345.051888 -224.87509) (xy 345.074748 -224.879408) (xy 345.099571 -224.884565) (xy 345.147351 -224.90152)
			(xy 345.191971 -224.925592) (xy 345.232378 -224.956214) (xy 345.267619 -224.992662) (xy 345.296863 -225.034077)
			(xy 345.319419 -225.079482) (xy 345.334756 -225.127806) (xy 345.342511 -225.177908) (xy 345.342972 -225.203258)
			(xy 345.342464 -225.229165) (xy 345.334358 -225.280342) (xy 345.318346 -225.329621) (xy 345.294823 -225.375788)
			(xy 345.264367 -225.417707) (xy 345.227729 -225.454345) (xy 345.18581 -225.484801) (xy 345.139643 -225.508324)
			(xy 345.090364 -225.524336) (xy 345.039187 -225.532442) (xy 344.987373 -225.532442) (xy 344.936196 -225.524336)
			(xy 344.886917 -225.508324) (xy 344.84075 -225.484801) (xy 344.798831 -225.454345) (xy 344.762193 -225.417707)
			(xy 344.731737 -225.375788) (xy 344.708214 -225.329621) (xy 344.692202 -225.280342) (xy 344.684096 -225.229165)
			(xy 344.683588 -225.203258) (xy 344.684197 -225.175541) (xy 344.69351 -225.120895) (xy 344.70213 -225.094546)
			(xy 344.710004 -225.072448) (xy 344.505026 -224.71761) (xy 344.482166 -224.713292) (xy 344.457348 -224.708169)
			(xy 344.409605 -224.691172) (xy 344.365026 -224.667071) (xy 344.32466 -224.636431) (xy 344.289457 -224.599976)
			(xy 344.260248 -224.558564) (xy 344.237719 -224.51317) (xy 344.222401 -224.464863) (xy 344.214655 -224.414781)
			(xy 344.214196 -224.389442) (xy 343.933272 -224.389442) (xy 343.932764 -224.415329) (xy 343.924665 -224.466467)
			(xy 343.908666 -224.515707) (xy 343.88516 -224.561839) (xy 343.854728 -224.603726) (xy 343.818118 -224.640336)
			(xy 343.776231 -224.670768) (xy 343.730099 -224.694274) (xy 343.680859 -224.710273) (xy 343.629721 -224.718372)
			(xy 343.577947 -224.718372) (xy 343.526809 -224.710273) (xy 343.477569 -224.694274) (xy 343.431437 -224.670768)
			(xy 343.38955 -224.640336) (xy 343.35294 -224.603726) (xy 343.322508 -224.561839) (xy 343.299002 -224.515707)
			(xy 343.283003 -224.466467) (xy 343.274904 -224.415329) (xy 343.274396 -224.389442) (xy 342.993472 -224.389442)
			(xy 342.992925 -224.417149) (xy 342.983741 -224.471796) (xy 342.975184 -224.498154) (xy 342.96731 -224.520252)
			(xy 343.172288 -224.87509) (xy 343.195148 -224.879408) (xy 343.219971 -224.884565) (xy 343.267751 -224.90152)
			(xy 343.312371 -224.925592) (xy 343.352778 -224.956214) (xy 343.388019 -224.992662) (xy 343.417263 -225.034077)
			(xy 343.439819 -225.079482) (xy 343.455156 -225.127806) (xy 343.462911 -225.177908) (xy 343.463372 -225.203258)
			(xy 343.462864 -225.229165) (xy 343.454758 -225.280342) (xy 343.438746 -225.329621) (xy 343.415223 -225.375788)
			(xy 343.384767 -225.417707) (xy 343.348129 -225.454345) (xy 343.30621 -225.484801) (xy 343.260043 -225.508324)
			(xy 343.210764 -225.524336) (xy 343.159587 -225.532442) (xy 343.107773 -225.532442) (xy 343.056596 -225.524336)
			(xy 343.007317 -225.508324) (xy 342.96115 -225.484801) (xy 342.919231 -225.454345) (xy 342.882593 -225.417707)
			(xy 342.852137 -225.375788) (xy 342.828614 -225.329621) (xy 342.812602 -225.280342) (xy 342.804496 -225.229165)
			(xy 342.803988 -225.203258) (xy 342.804597 -225.175541) (xy 342.81391 -225.120895) (xy 342.82253 -225.094546)
			(xy 342.830404 -225.072448) (xy 342.625426 -224.71761) (xy 342.602566 -224.713292) (xy 342.577748 -224.708169)
			(xy 342.530005 -224.691172) (xy 342.485426 -224.667071) (xy 342.44506 -224.636431) (xy 342.409857 -224.599976)
			(xy 342.380648 -224.558564) (xy 342.358119 -224.51317) (xy 342.342801 -224.464863) (xy 342.335055 -224.414781)
			(xy 342.334596 -224.389442) (xy 342.053672 -224.389442) (xy 342.053164 -224.415329) (xy 342.045065 -224.466467)
			(xy 342.029066 -224.515707) (xy 342.00556 -224.561839) (xy 341.975128 -224.603726) (xy 341.938518 -224.640336)
			(xy 341.896631 -224.670768) (xy 341.850499 -224.694274) (xy 341.801259 -224.710273) (xy 341.750121 -224.718372)
			(xy 341.698347 -224.718372) (xy 341.647209 -224.710273) (xy 341.597969 -224.694274) (xy 341.551837 -224.670768)
			(xy 341.50995 -224.640336) (xy 341.47334 -224.603726) (xy 341.442908 -224.561839) (xy 341.419402 -224.515707)
			(xy 341.403403 -224.466467) (xy 341.395304 -224.415329) (xy 341.394796 -224.389442) (xy 134.525004 -224.389442)
			(xy 134.524474 -224.41715) (xy 134.515275 -224.471796) (xy 134.506716 -224.498154) (xy 134.499096 -224.519998)
			(xy 134.704074 -224.87509) (xy 134.726934 -224.879408) (xy 134.751752 -224.884531) (xy 134.799495 -224.901528)
			(xy 134.844074 -224.925629) (xy 134.88444 -224.956269) (xy 134.919643 -224.992724) (xy 134.948852 -225.034136)
			(xy 134.971381 -225.07953) (xy 134.986699 -225.127837) (xy 134.994445 -225.177919) (xy 134.994904 -225.203258)
			(xy 134.994396 -225.229145) (xy 134.986297 -225.280283) (xy 134.970298 -225.329523) (xy 134.946792 -225.375655)
			(xy 134.91636 -225.417542) (xy 134.87975 -225.454152) (xy 134.837863 -225.484584) (xy 134.791731 -225.50809)
			(xy 134.742491 -225.524089) (xy 134.691353 -225.532188) (xy 134.639579 -225.532188) (xy 134.588441 -225.524089)
			(xy 134.539201 -225.50809) (xy 134.493069 -225.484584) (xy 134.451182 -225.454152) (xy 134.414572 -225.417542)
			(xy 134.38414 -225.375655) (xy 134.360634 -225.329523) (xy 134.344635 -225.280283) (xy 134.336536 -225.229145)
			(xy 134.336028 -225.203258) (xy 134.336028 -225.20275) (xy 134.336589 -225.175107) (xy 134.345778 -225.120589)
			(xy 134.354316 -225.094292) (xy 134.361936 -225.072448) (xy 134.157212 -224.71761) (xy 134.134352 -224.713292)
			(xy 134.109529 -224.708135) (xy 134.061749 -224.69118) (xy 134.017129 -224.667108) (xy 133.976722 -224.636486)
			(xy 133.941481 -224.600038) (xy 133.912237 -224.558623) (xy 133.889681 -224.513218) (xy 133.874344 -224.464894)
			(xy 133.866589 -224.414792) (xy 133.866128 -224.389442) (xy 133.585204 -224.389442) (xy 133.584696 -224.415329)
			(xy 133.576597 -224.466467) (xy 133.560598 -224.515707) (xy 133.537092 -224.561839) (xy 133.50666 -224.603726)
			(xy 133.47005 -224.640336) (xy 133.428163 -224.670768) (xy 133.382031 -224.694274) (xy 133.332791 -224.710273)
			(xy 133.281653 -224.718372) (xy 133.229879 -224.718372) (xy 133.178741 -224.710273) (xy 133.129501 -224.694274)
			(xy 133.083369 -224.670768) (xy 133.041482 -224.640336) (xy 133.004872 -224.603726) (xy 132.97444 -224.561839)
			(xy 132.950934 -224.515707) (xy 132.934935 -224.466467) (xy 132.926836 -224.415329) (xy 132.926328 -224.389442)
			(xy 132.645404 -224.389442) (xy 132.64486 -224.417149) (xy 132.635674 -224.471796) (xy 132.627116 -224.498154)
			(xy 132.619242 -224.520252) (xy 132.82422 -224.87509) (xy 132.84708 -224.879408) (xy 132.871909 -224.884542)
			(xy 132.919688 -224.901501) (xy 132.964308 -224.925578) (xy 133.004714 -224.956202) (xy 133.039954 -224.992654)
			(xy 133.069197 -225.034071) (xy 133.091752 -225.079478) (xy 133.107088 -225.127804) (xy 133.114843 -225.177908)
			(xy 133.115304 -225.203258) (xy 133.114796 -225.229165) (xy 133.10669 -225.280342) (xy 133.090678 -225.329621)
			(xy 133.067155 -225.375788) (xy 133.036699 -225.417707) (xy 133.000061 -225.454345) (xy 132.958142 -225.484801)
			(xy 132.911975 -225.508324) (xy 132.862696 -225.524336) (xy 132.811519 -225.532442) (xy 132.759705 -225.532442)
			(xy 132.708528 -225.524336) (xy 132.659249 -225.508324) (xy 132.613082 -225.484801) (xy 132.571163 -225.454345)
			(xy 132.534525 -225.417707) (xy 132.504069 -225.375788) (xy 132.480546 -225.329621) (xy 132.464534 -225.280342)
			(xy 132.456428 -225.229165) (xy 132.45592 -225.203258) (xy 132.456527 -225.175541) (xy 132.465842 -225.120895)
			(xy 132.474462 -225.094546) (xy 132.482336 -225.072448) (xy 132.277358 -224.71761) (xy 132.254498 -224.713292)
			(xy 132.229685 -224.708145) (xy 132.181943 -224.691153) (xy 132.137363 -224.667056) (xy 132.096996 -224.63642)
			(xy 132.061793 -224.599968) (xy 132.032582 -224.558558) (xy 132.010052 -224.513166) (xy 131.994734 -224.46486)
			(xy 131.986988 -224.41478) (xy 131.986528 -224.389442) (xy 131.705604 -224.389442) (xy 131.705096 -224.415329)
			(xy 131.696997 -224.466467) (xy 131.680998 -224.515707) (xy 131.657492 -224.561839) (xy 131.62706 -224.603726)
			(xy 131.59045 -224.640336) (xy 131.548563 -224.670768) (xy 131.502431 -224.694274) (xy 131.453191 -224.710273)
			(xy 131.402053 -224.718372) (xy 131.350279 -224.718372) (xy 131.299141 -224.710273) (xy 131.249901 -224.694274)
			(xy 131.203769 -224.670768) (xy 131.161882 -224.640336) (xy 131.125272 -224.603726) (xy 131.09484 -224.561839)
			(xy 131.071334 -224.515707) (xy 131.055335 -224.466467) (xy 131.047236 -224.415329) (xy 131.046728 -224.389442)
			(xy 130.765804 -224.389442) (xy 130.76526 -224.417149) (xy 130.756074 -224.471796) (xy 130.747516 -224.498154)
			(xy 130.739642 -224.520252) (xy 130.94462 -224.87509) (xy 130.96748 -224.879408) (xy 130.992309 -224.884542)
			(xy 131.040088 -224.901501) (xy 131.084708 -224.925578) (xy 131.125114 -224.956202) (xy 131.160354 -224.992654)
			(xy 131.189597 -225.034071) (xy 131.212152 -225.079478) (xy 131.227488 -225.127804) (xy 131.235243 -225.177908)
			(xy 131.235704 -225.203258) (xy 131.235196 -225.229165) (xy 131.22709 -225.280342) (xy 131.211078 -225.329621)
			(xy 131.187555 -225.375788) (xy 131.157099 -225.417707) (xy 131.120461 -225.454345) (xy 131.078542 -225.484801)
			(xy 131.032375 -225.508324) (xy 130.983096 -225.524336) (xy 130.931919 -225.532442) (xy 130.880105 -225.532442)
			(xy 130.828928 -225.524336) (xy 130.779649 -225.508324) (xy 130.733482 -225.484801) (xy 130.691563 -225.454345)
			(xy 130.654925 -225.417707) (xy 130.624469 -225.375788) (xy 130.600946 -225.329621) (xy 130.584934 -225.280342)
			(xy 130.576828 -225.229165) (xy 130.57632 -225.203258) (xy 130.576927 -225.175541) (xy 130.586242 -225.120895)
			(xy 130.594862 -225.094546) (xy 130.602736 -225.072448) (xy 130.397758 -224.71761) (xy 130.374898 -224.713292)
			(xy 130.350085 -224.708145) (xy 130.302343 -224.691153) (xy 130.257763 -224.667056) (xy 130.217396 -224.63642)
			(xy 130.182193 -224.599968) (xy 130.152982 -224.558558) (xy 130.130452 -224.513166) (xy 130.115134 -224.46486)
			(xy 130.107388 -224.41478) (xy 130.106928 -224.389442) (xy 129.826004 -224.389442) (xy 129.825496 -224.415329)
			(xy 129.817397 -224.466467) (xy 129.801398 -224.515707) (xy 129.777892 -224.561839) (xy 129.74746 -224.603726)
			(xy 129.71085 -224.640336) (xy 129.668963 -224.670768) (xy 129.622831 -224.694274) (xy 129.573591 -224.710273)
			(xy 129.522453 -224.718372) (xy 129.470679 -224.718372) (xy 129.419541 -224.710273) (xy 129.370301 -224.694274)
			(xy 129.324169 -224.670768) (xy 129.282282 -224.640336) (xy 129.245672 -224.603726) (xy 129.21524 -224.561839)
			(xy 129.191734 -224.515707) (xy 129.175735 -224.466467) (xy 129.167636 -224.415329) (xy 129.167128 -224.389442)
			(xy 128.886204 -224.389442) (xy 128.88566 -224.417149) (xy 128.876474 -224.471796) (xy 128.867916 -224.498154)
			(xy 128.860042 -224.520252) (xy 129.06502 -224.87509) (xy 129.08788 -224.879408) (xy 129.112709 -224.884542)
			(xy 129.160488 -224.901501) (xy 129.205108 -224.925578) (xy 129.245514 -224.956202) (xy 129.280754 -224.992654)
			(xy 129.309997 -225.034071) (xy 129.332552 -225.079478) (xy 129.347888 -225.127804) (xy 129.355643 -225.177908)
			(xy 129.356104 -225.203258) (xy 129.355596 -225.229165) (xy 129.34749 -225.280342) (xy 129.331478 -225.329621)
			(xy 129.307955 -225.375788) (xy 129.277499 -225.417707) (xy 129.240861 -225.454345) (xy 129.198942 -225.484801)
			(xy 129.152775 -225.508324) (xy 129.103496 -225.524336) (xy 129.052319 -225.532442) (xy 129.000505 -225.532442)
			(xy 128.949328 -225.524336) (xy 128.900049 -225.508324) (xy 128.853882 -225.484801) (xy 128.811963 -225.454345)
			(xy 128.775325 -225.417707) (xy 128.744869 -225.375788) (xy 128.721346 -225.329621) (xy 128.705334 -225.280342)
			(xy 128.697228 -225.229165) (xy 128.69672 -225.203258) (xy 128.697327 -225.175541) (xy 128.706642 -225.120895)
			(xy 128.715262 -225.094546) (xy 128.723136 -225.072448) (xy 128.518158 -224.71761) (xy 128.495298 -224.713292)
			(xy 128.470485 -224.708145) (xy 128.422743 -224.691153) (xy 128.378163 -224.667056) (xy 128.337796 -224.63642)
			(xy 128.302593 -224.599968) (xy 128.273382 -224.558558) (xy 128.250852 -224.513166) (xy 128.235534 -224.46486)
			(xy 128.227788 -224.41478) (xy 128.227328 -224.389442) (xy 127.946404 -224.389442) (xy 127.945896 -224.415329)
			(xy 127.937797 -224.466467) (xy 127.921798 -224.515707) (xy 127.898292 -224.561839) (xy 127.86786 -224.603726)
			(xy 127.83125 -224.640336) (xy 127.789363 -224.670768) (xy 127.743231 -224.694274) (xy 127.693991 -224.710273)
			(xy 127.642853 -224.718372) (xy 127.591079 -224.718372) (xy 127.539941 -224.710273) (xy 127.490701 -224.694274)
			(xy 127.444569 -224.670768) (xy 127.402682 -224.640336) (xy 127.366072 -224.603726) (xy 127.33564 -224.561839)
			(xy 127.312134 -224.515707) (xy 127.296135 -224.466467) (xy 127.288036 -224.415329) (xy 127.287528 -224.389442)
			(xy 127.006604 -224.389442) (xy 127.00606 -224.417149) (xy 126.996874 -224.471796) (xy 126.988316 -224.498154)
			(xy 126.980442 -224.520252) (xy 127.18542 -224.87509) (xy 127.20828 -224.879408) (xy 127.233109 -224.884542)
			(xy 127.280888 -224.901501) (xy 127.325508 -224.925578) (xy 127.365914 -224.956202) (xy 127.401154 -224.992654)
			(xy 127.430397 -225.034071) (xy 127.452952 -225.079478) (xy 127.468288 -225.127804) (xy 127.476043 -225.177908)
			(xy 127.476504 -225.203258) (xy 127.475996 -225.229165) (xy 127.46789 -225.280342) (xy 127.451878 -225.329621)
			(xy 127.428355 -225.375788) (xy 127.397899 -225.417707) (xy 127.361261 -225.454345) (xy 127.319342 -225.484801)
			(xy 127.273175 -225.508324) (xy 127.223896 -225.524336) (xy 127.172719 -225.532442) (xy 127.120905 -225.532442)
			(xy 127.069728 -225.524336) (xy 127.020449 -225.508324) (xy 126.974282 -225.484801) (xy 126.932363 -225.454345)
			(xy 126.895725 -225.417707) (xy 126.865269 -225.375788) (xy 126.841746 -225.329621) (xy 126.825734 -225.280342)
			(xy 126.817628 -225.229165) (xy 126.81712 -225.203258) (xy 126.817727 -225.175541) (xy 126.827042 -225.120895)
			(xy 126.835662 -225.094546) (xy 126.843536 -225.072448) (xy 126.638558 -224.71761) (xy 126.615698 -224.713292)
			(xy 126.590885 -224.708145) (xy 126.543143 -224.691153) (xy 126.498563 -224.667056) (xy 126.458196 -224.63642)
			(xy 126.422993 -224.599968) (xy 126.393782 -224.558558) (xy 126.371252 -224.513166) (xy 126.355934 -224.46486)
			(xy 126.348188 -224.41478) (xy 126.347728 -224.389442) (xy 126.066804 -224.389442) (xy 126.066296 -224.415329)
			(xy 126.058197 -224.466467) (xy 126.042198 -224.515707) (xy 126.018692 -224.561839) (xy 125.98826 -224.603726)
			(xy 125.95165 -224.640336) (xy 125.909763 -224.670768) (xy 125.863631 -224.694274) (xy 125.814391 -224.710273)
			(xy 125.763253 -224.718372) (xy 125.711479 -224.718372) (xy 125.660341 -224.710273) (xy 125.611101 -224.694274)
			(xy 125.564969 -224.670768) (xy 125.523082 -224.640336) (xy 125.486472 -224.603726) (xy 125.45604 -224.561839)
			(xy 125.432534 -224.515707) (xy 125.416535 -224.466467) (xy 125.408436 -224.415329) (xy 125.407928 -224.389442)
			(xy 125.127004 -224.389442) (xy 125.12646 -224.417149) (xy 125.117274 -224.471796) (xy 125.108716 -224.498154)
			(xy 125.100842 -224.520252) (xy 125.30582 -224.87509) (xy 125.32868 -224.879408) (xy 125.353509 -224.884542)
			(xy 125.401288 -224.901501) (xy 125.445908 -224.925578) (xy 125.486314 -224.956202) (xy 125.521554 -224.992654)
			(xy 125.550797 -225.034071) (xy 125.573352 -225.079478) (xy 125.588688 -225.127804) (xy 125.596443 -225.177908)
			(xy 125.596904 -225.203258) (xy 125.596396 -225.229165) (xy 125.58829 -225.280342) (xy 125.572278 -225.329621)
			(xy 125.548755 -225.375788) (xy 125.518299 -225.417707) (xy 125.481661 -225.454345) (xy 125.439742 -225.484801)
			(xy 125.393575 -225.508324) (xy 125.344296 -225.524336) (xy 125.293119 -225.532442) (xy 125.241305 -225.532442)
			(xy 125.190128 -225.524336) (xy 125.140849 -225.508324) (xy 125.094682 -225.484801) (xy 125.052763 -225.454345)
			(xy 125.016125 -225.417707) (xy 124.985669 -225.375788) (xy 124.962146 -225.329621) (xy 124.946134 -225.280342)
			(xy 124.938028 -225.229165) (xy 124.93752 -225.203258) (xy 124.938127 -225.175541) (xy 124.947442 -225.120895)
			(xy 124.956062 -225.094546) (xy 124.963936 -225.072448) (xy 124.758958 -224.71761) (xy 124.736098 -224.713292)
			(xy 124.711285 -224.708145) (xy 124.663543 -224.691153) (xy 124.618963 -224.667056) (xy 124.578596 -224.63642)
			(xy 124.543393 -224.599968) (xy 124.514182 -224.558558) (xy 124.491652 -224.513166) (xy 124.476334 -224.46486)
			(xy 124.468588 -224.41478) (xy 124.468128 -224.389442) (xy 124.187204 -224.389442) (xy 124.186696 -224.415329)
			(xy 124.178597 -224.466467) (xy 124.162598 -224.515707) (xy 124.139092 -224.561839) (xy 124.10866 -224.603726)
			(xy 124.07205 -224.640336) (xy 124.030163 -224.670768) (xy 123.984031 -224.694274) (xy 123.934791 -224.710273)
			(xy 123.883653 -224.718372) (xy 123.831879 -224.718372) (xy 123.780741 -224.710273) (xy 123.731501 -224.694274)
			(xy 123.685369 -224.670768) (xy 123.643482 -224.640336) (xy 123.606872 -224.603726) (xy 123.57644 -224.561839)
			(xy 123.552934 -224.515707) (xy 123.536935 -224.466467) (xy 123.528836 -224.415329) (xy 123.528328 -224.389442)
			(xy 123.247404 -224.389442) (xy 123.24686 -224.417149) (xy 123.237674 -224.471796) (xy 123.229116 -224.498154)
			(xy 123.221242 -224.520252) (xy 123.42622 -224.87509) (xy 123.44908 -224.879408) (xy 123.473909 -224.884542)
			(xy 123.521688 -224.901501) (xy 123.566308 -224.925578) (xy 123.606714 -224.956202) (xy 123.641954 -224.992654)
			(xy 123.671197 -225.034071) (xy 123.693752 -225.079478) (xy 123.709088 -225.127804) (xy 123.716843 -225.177908)
			(xy 123.717304 -225.203258) (xy 123.716796 -225.229165) (xy 123.70869 -225.280342) (xy 123.692678 -225.329621)
			(xy 123.669155 -225.375788) (xy 123.638699 -225.417707) (xy 123.602061 -225.454345) (xy 123.560142 -225.484801)
			(xy 123.513975 -225.508324) (xy 123.464696 -225.524336) (xy 123.413519 -225.532442) (xy 123.361705 -225.532442)
			(xy 123.310528 -225.524336) (xy 123.261249 -225.508324) (xy 123.215082 -225.484801) (xy 123.173163 -225.454345)
			(xy 123.136525 -225.417707) (xy 123.106069 -225.375788) (xy 123.082546 -225.329621) (xy 123.066534 -225.280342)
			(xy 123.058428 -225.229165) (xy 123.05792 -225.203258) (xy 123.058527 -225.175541) (xy 123.067842 -225.120895)
			(xy 123.076462 -225.094546) (xy 123.084336 -225.072448) (xy 122.879358 -224.71761) (xy 122.856498 -224.713292)
			(xy 122.831685 -224.708145) (xy 122.783943 -224.691153) (xy 122.739363 -224.667056) (xy 122.698996 -224.63642)
			(xy 122.663793 -224.599968) (xy 122.634582 -224.558558) (xy 122.612052 -224.513166) (xy 122.596734 -224.46486)
			(xy 122.588988 -224.41478) (xy 122.588528 -224.389442) (xy 122.307604 -224.389442) (xy 122.307096 -224.415329)
			(xy 122.298997 -224.466467) (xy 122.282998 -224.515707) (xy 122.259492 -224.561839) (xy 122.22906 -224.603726)
			(xy 122.19245 -224.640336) (xy 122.150563 -224.670768) (xy 122.104431 -224.694274) (xy 122.055191 -224.710273)
			(xy 122.004053 -224.718372) (xy 121.952279 -224.718372) (xy 121.901141 -224.710273) (xy 121.851901 -224.694274)
			(xy 121.805769 -224.670768) (xy 121.763882 -224.640336) (xy 121.727272 -224.603726) (xy 121.69684 -224.561839)
			(xy 121.673334 -224.515707) (xy 121.657335 -224.466467) (xy 121.649236 -224.415329) (xy 121.648728 -224.389442)
			(xy 121.367804 -224.389442) (xy 121.36726 -224.417149) (xy 121.358074 -224.471796) (xy 121.349516 -224.498154)
			(xy 121.341642 -224.520252) (xy 121.54662 -224.87509) (xy 121.56948 -224.879408) (xy 121.594309 -224.884542)
			(xy 121.642088 -224.901501) (xy 121.686708 -224.925578) (xy 121.727114 -224.956202) (xy 121.762354 -224.992654)
			(xy 121.791597 -225.034071) (xy 121.814152 -225.079478) (xy 121.829488 -225.127804) (xy 121.837243 -225.177908)
			(xy 121.837704 -225.203258) (xy 121.837196 -225.229165) (xy 121.82909 -225.280342) (xy 121.813078 -225.329621)
			(xy 121.789555 -225.375788) (xy 121.759099 -225.417707) (xy 121.722461 -225.454345) (xy 121.680542 -225.484801)
			(xy 121.634375 -225.508324) (xy 121.585096 -225.524336) (xy 121.533919 -225.532442) (xy 121.482105 -225.532442)
			(xy 121.430928 -225.524336) (xy 121.381649 -225.508324) (xy 121.335482 -225.484801) (xy 121.293563 -225.454345)
			(xy 121.256925 -225.417707) (xy 121.226469 -225.375788) (xy 121.202946 -225.329621) (xy 121.186934 -225.280342)
			(xy 121.178828 -225.229165) (xy 121.17832 -225.203258) (xy 121.178927 -225.175541) (xy 121.188242 -225.120895)
			(xy 121.196862 -225.094546) (xy 121.204736 -225.072448) (xy 120.999758 -224.71761) (xy 120.976898 -224.713292)
			(xy 120.952085 -224.708145) (xy 120.904343 -224.691153) (xy 120.859763 -224.667056) (xy 120.819396 -224.63642)
			(xy 120.784193 -224.599968) (xy 120.754982 -224.558558) (xy 120.732452 -224.513166) (xy 120.717134 -224.46486)
			(xy 120.709388 -224.41478) (xy 120.708928 -224.389442) (xy 120.428004 -224.389442) (xy 120.427496 -224.415329)
			(xy 120.419397 -224.466467) (xy 120.403398 -224.515707) (xy 120.379892 -224.561839) (xy 120.34946 -224.603726)
			(xy 120.31285 -224.640336) (xy 120.270963 -224.670768) (xy 120.224831 -224.694274) (xy 120.175591 -224.710273)
			(xy 120.124453 -224.718372) (xy 120.072679 -224.718372) (xy 120.021541 -224.710273) (xy 119.972301 -224.694274)
			(xy 119.926169 -224.670768) (xy 119.884282 -224.640336) (xy 119.847672 -224.603726) (xy 119.81724 -224.561839)
			(xy 119.793734 -224.515707) (xy 119.777735 -224.466467) (xy 119.769636 -224.415329) (xy 119.769128 -224.389442)
			(xy 119.488204 -224.389442) (xy 119.48766 -224.417149) (xy 119.478474 -224.471796) (xy 119.469916 -224.498154)
			(xy 119.462042 -224.520252) (xy 119.66702 -224.87509) (xy 119.68988 -224.879408) (xy 119.714709 -224.884542)
			(xy 119.762488 -224.901501) (xy 119.807108 -224.925578) (xy 119.847514 -224.956202) (xy 119.882754 -224.992654)
			(xy 119.911997 -225.034071) (xy 119.934552 -225.079478) (xy 119.949888 -225.127804) (xy 119.957643 -225.177908)
			(xy 119.958104 -225.203258) (xy 119.957596 -225.229165) (xy 119.94949 -225.280342) (xy 119.933478 -225.329621)
			(xy 119.909955 -225.375788) (xy 119.879499 -225.417707) (xy 119.842861 -225.454345) (xy 119.800942 -225.484801)
			(xy 119.754775 -225.508324) (xy 119.705496 -225.524336) (xy 119.654319 -225.532442) (xy 119.602505 -225.532442)
			(xy 119.551328 -225.524336) (xy 119.502049 -225.508324) (xy 119.455882 -225.484801) (xy 119.413963 -225.454345)
			(xy 119.377325 -225.417707) (xy 119.346869 -225.375788) (xy 119.323346 -225.329621) (xy 119.307334 -225.280342)
			(xy 119.299228 -225.229165) (xy 119.29872 -225.203258) (xy 119.299327 -225.175541) (xy 119.308642 -225.120895)
			(xy 119.317262 -225.094546) (xy 119.325136 -225.072448) (xy 119.120158 -224.71761) (xy 119.097298 -224.713292)
			(xy 119.072485 -224.708145) (xy 119.024743 -224.691153) (xy 118.980163 -224.667056) (xy 118.939796 -224.63642)
			(xy 118.904593 -224.599968) (xy 118.875382 -224.558558) (xy 118.852852 -224.513166) (xy 118.837534 -224.46486)
			(xy 118.829788 -224.41478) (xy 118.829328 -224.389442) (xy 118.548404 -224.389442) (xy 118.547896 -224.415329)
			(xy 118.539797 -224.466467) (xy 118.523798 -224.515707) (xy 118.500292 -224.561839) (xy 118.46986 -224.603726)
			(xy 118.43325 -224.640336) (xy 118.391363 -224.670768) (xy 118.345231 -224.694274) (xy 118.295991 -224.710273)
			(xy 118.244853 -224.718372) (xy 118.193079 -224.718372) (xy 118.141941 -224.710273) (xy 118.092701 -224.694274)
			(xy 118.046569 -224.670768) (xy 118.004682 -224.640336) (xy 117.968072 -224.603726) (xy 117.93764 -224.561839)
			(xy 117.914134 -224.515707) (xy 117.898135 -224.466467) (xy 117.890036 -224.415329) (xy 117.889528 -224.389442)
			(xy 117.608604 -224.389442) (xy 117.60806 -224.417149) (xy 117.598874 -224.471796) (xy 117.590316 -224.498154)
			(xy 117.582442 -224.520252) (xy 117.78742 -224.87509) (xy 117.81028 -224.879408) (xy 117.835109 -224.884542)
			(xy 117.882888 -224.901501) (xy 117.927508 -224.925578) (xy 117.967914 -224.956202) (xy 118.003154 -224.992654)
			(xy 118.032397 -225.034071) (xy 118.054952 -225.079478) (xy 118.070288 -225.127804) (xy 118.078043 -225.177908)
			(xy 118.078504 -225.203258) (xy 118.077996 -225.229165) (xy 118.06989 -225.280342) (xy 118.053878 -225.329621)
			(xy 118.030355 -225.375788) (xy 117.999899 -225.417707) (xy 117.963261 -225.454345) (xy 117.921342 -225.484801)
			(xy 117.875175 -225.508324) (xy 117.825896 -225.524336) (xy 117.774719 -225.532442) (xy 117.722905 -225.532442)
			(xy 117.671728 -225.524336) (xy 117.622449 -225.508324) (xy 117.576282 -225.484801) (xy 117.534363 -225.454345)
			(xy 117.497725 -225.417707) (xy 117.467269 -225.375788) (xy 117.443746 -225.329621) (xy 117.427734 -225.280342)
			(xy 117.419628 -225.229165) (xy 117.41912 -225.203258) (xy 117.419727 -225.175541) (xy 117.429042 -225.120895)
			(xy 117.437662 -225.094546) (xy 117.445536 -225.072448) (xy 117.240558 -224.71761) (xy 117.217698 -224.713292)
			(xy 117.192885 -224.708145) (xy 117.145143 -224.691153) (xy 117.100563 -224.667056) (xy 117.060196 -224.63642)
			(xy 117.024993 -224.599968) (xy 116.995782 -224.558558) (xy 116.973252 -224.513166) (xy 116.957934 -224.46486)
			(xy 116.950188 -224.41478) (xy 116.949728 -224.389442) (xy 116.668804 -224.389442) (xy 116.668296 -224.415329)
			(xy 116.660197 -224.466467) (xy 116.644198 -224.515707) (xy 116.620692 -224.561839) (xy 116.59026 -224.603726)
			(xy 116.55365 -224.640336) (xy 116.511763 -224.670768) (xy 116.465631 -224.694274) (xy 116.416391 -224.710273)
			(xy 116.365253 -224.718372) (xy 116.313479 -224.718372) (xy 116.262341 -224.710273) (xy 116.213101 -224.694274)
			(xy 116.166969 -224.670768) (xy 116.125082 -224.640336) (xy 116.088472 -224.603726) (xy 116.05804 -224.561839)
			(xy 116.034534 -224.515707) (xy 116.018535 -224.466467) (xy 116.010436 -224.415329) (xy 116.009928 -224.389442)
			(xy 115.729004 -224.389442) (xy 115.72846 -224.417149) (xy 115.719274 -224.471796) (xy 115.710716 -224.498154)
			(xy 115.702842 -224.520252) (xy 115.90782 -224.87509) (xy 115.93068 -224.879408) (xy 115.955509 -224.884542)
			(xy 116.003288 -224.901501) (xy 116.047908 -224.925578) (xy 116.088314 -224.956202) (xy 116.123554 -224.992654)
			(xy 116.152797 -225.034071) (xy 116.175352 -225.079478) (xy 116.190688 -225.127804) (xy 116.198443 -225.177908)
			(xy 116.198904 -225.203258) (xy 116.198396 -225.229165) (xy 116.19029 -225.280342) (xy 116.174278 -225.329621)
			(xy 116.150755 -225.375788) (xy 116.120299 -225.417707) (xy 116.083661 -225.454345) (xy 116.041742 -225.484801)
			(xy 115.995575 -225.508324) (xy 115.946296 -225.524336) (xy 115.895119 -225.532442) (xy 115.843305 -225.532442)
			(xy 115.792128 -225.524336) (xy 115.742849 -225.508324) (xy 115.696682 -225.484801) (xy 115.654763 -225.454345)
			(xy 115.618125 -225.417707) (xy 115.587669 -225.375788) (xy 115.564146 -225.329621) (xy 115.548134 -225.280342)
			(xy 115.540028 -225.229165) (xy 115.53952 -225.203258) (xy 115.540127 -225.175541) (xy 115.549442 -225.120895)
			(xy 115.558062 -225.094546) (xy 115.565936 -225.072448) (xy 115.360958 -224.71761) (xy 115.338098 -224.713292)
			(xy 115.313285 -224.708145) (xy 115.265543 -224.691153) (xy 115.220963 -224.667056) (xy 115.180596 -224.63642)
			(xy 115.145393 -224.599968) (xy 115.116182 -224.558558) (xy 115.093652 -224.513166) (xy 115.078334 -224.46486)
			(xy 115.070588 -224.41478) (xy 115.070128 -224.389442) (xy 114.789204 -224.389442) (xy 114.788696 -224.415329)
			(xy 114.780597 -224.466467) (xy 114.764598 -224.515707) (xy 114.741092 -224.561839) (xy 114.71066 -224.603726)
			(xy 114.67405 -224.640336) (xy 114.632163 -224.670768) (xy 114.586031 -224.694274) (xy 114.536791 -224.710273)
			(xy 114.485653 -224.718372) (xy 114.433879 -224.718372) (xy 114.382741 -224.710273) (xy 114.333501 -224.694274)
			(xy 114.287369 -224.670768) (xy 114.245482 -224.640336) (xy 114.208872 -224.603726) (xy 114.17844 -224.561839)
			(xy 114.154934 -224.515707) (xy 114.138935 -224.466467) (xy 114.130836 -224.415329) (xy 114.130328 -224.389442)
			(xy 113.849404 -224.389442) (xy 113.84886 -224.417149) (xy 113.839674 -224.471796) (xy 113.831116 -224.498154)
			(xy 113.823242 -224.520252) (xy 114.02822 -224.87509) (xy 114.05108 -224.879408) (xy 114.075909 -224.884542)
			(xy 114.123688 -224.901501) (xy 114.168308 -224.925578) (xy 114.208714 -224.956202) (xy 114.243954 -224.992654)
			(xy 114.273197 -225.034071) (xy 114.295752 -225.079478) (xy 114.311088 -225.127804) (xy 114.318843 -225.177908)
			(xy 114.319304 -225.203258) (xy 114.318796 -225.229165) (xy 114.31069 -225.280342) (xy 114.294678 -225.329621)
			(xy 114.271155 -225.375788) (xy 114.240699 -225.417707) (xy 114.204061 -225.454345) (xy 114.162142 -225.484801)
			(xy 114.115975 -225.508324) (xy 114.066696 -225.524336) (xy 114.015519 -225.532442) (xy 113.963705 -225.532442)
			(xy 113.912528 -225.524336) (xy 113.863249 -225.508324) (xy 113.817082 -225.484801) (xy 113.775163 -225.454345)
			(xy 113.738525 -225.417707) (xy 113.708069 -225.375788) (xy 113.684546 -225.329621) (xy 113.668534 -225.280342)
			(xy 113.660428 -225.229165) (xy 113.65992 -225.203258) (xy 113.660527 -225.175541) (xy 113.669842 -225.120895)
			(xy 113.678462 -225.094546) (xy 113.686336 -225.072448) (xy 113.481358 -224.71761) (xy 113.458498 -224.713292)
			(xy 113.433685 -224.708145) (xy 113.385943 -224.691153) (xy 113.341363 -224.667056) (xy 113.300996 -224.63642)
			(xy 113.265793 -224.599968) (xy 113.236582 -224.558558) (xy 113.214052 -224.513166) (xy 113.198734 -224.46486)
			(xy 113.190988 -224.41478) (xy 113.190528 -224.389442) (xy 112.909604 -224.389442) (xy 112.909096 -224.415329)
			(xy 112.900997 -224.466467) (xy 112.884998 -224.515707) (xy 112.861492 -224.561839) (xy 112.83106 -224.603726)
			(xy 112.79445 -224.640336) (xy 112.752563 -224.670768) (xy 112.706431 -224.694274) (xy 112.657191 -224.710273)
			(xy 112.606053 -224.718372) (xy 112.554279 -224.718372) (xy 112.503141 -224.710273) (xy 112.453901 -224.694274)
			(xy 112.407769 -224.670768) (xy 112.365882 -224.640336) (xy 112.329272 -224.603726) (xy 112.29884 -224.561839)
			(xy 112.275334 -224.515707) (xy 112.259335 -224.466467) (xy 112.251236 -224.415329) (xy 112.250728 -224.389442)
			(xy 111.969804 -224.389442) (xy 111.96926 -224.417149) (xy 111.960074 -224.471796) (xy 111.951516 -224.498154)
			(xy 111.943642 -224.520252) (xy 112.14862 -224.87509) (xy 112.17148 -224.879408) (xy 112.196309 -224.884542)
			(xy 112.244088 -224.901501) (xy 112.288708 -224.925578) (xy 112.329114 -224.956202) (xy 112.364354 -224.992654)
			(xy 112.393597 -225.034071) (xy 112.416152 -225.079478) (xy 112.431488 -225.127804) (xy 112.439243 -225.177908)
			(xy 112.439704 -225.203258) (xy 112.439196 -225.229165) (xy 112.43109 -225.280342) (xy 112.415078 -225.329621)
			(xy 112.391555 -225.375788) (xy 112.361099 -225.417707) (xy 112.324461 -225.454345) (xy 112.282542 -225.484801)
			(xy 112.236375 -225.508324) (xy 112.187096 -225.524336) (xy 112.135919 -225.532442) (xy 112.084105 -225.532442)
			(xy 112.032928 -225.524336) (xy 111.983649 -225.508324) (xy 111.937482 -225.484801) (xy 111.895563 -225.454345)
			(xy 111.858925 -225.417707) (xy 111.828469 -225.375788) (xy 111.804946 -225.329621) (xy 111.788934 -225.280342)
			(xy 111.780828 -225.229165) (xy 111.78032 -225.203258) (xy 111.780927 -225.175541) (xy 111.790242 -225.120895)
			(xy 111.798862 -225.094546) (xy 111.806736 -225.072448) (xy 111.601758 -224.71761) (xy 111.578898 -224.713292)
			(xy 111.554085 -224.708145) (xy 111.506343 -224.691153) (xy 111.461763 -224.667056) (xy 111.421396 -224.63642)
			(xy 111.386193 -224.599968) (xy 111.356982 -224.558558) (xy 111.334452 -224.513166) (xy 111.319134 -224.46486)
			(xy 111.311388 -224.41478) (xy 111.310928 -224.389442) (xy 111.030004 -224.389442) (xy 111.029496 -224.415329)
			(xy 111.021397 -224.466467) (xy 111.005398 -224.515707) (xy 110.981892 -224.561839) (xy 110.95146 -224.603726)
			(xy 110.91485 -224.640336) (xy 110.872963 -224.670768) (xy 110.826831 -224.694274) (xy 110.777591 -224.710273)
			(xy 110.726453 -224.718372) (xy 110.674679 -224.718372) (xy 110.623541 -224.710273) (xy 110.574301 -224.694274)
			(xy 110.528169 -224.670768) (xy 110.486282 -224.640336) (xy 110.449672 -224.603726) (xy 110.41924 -224.561839)
			(xy 110.395734 -224.515707) (xy 110.379735 -224.466467) (xy 110.371636 -224.415329) (xy 110.371128 -224.389442)
			(xy 110.090204 -224.389442) (xy 110.08966 -224.417149) (xy 110.080474 -224.471796) (xy 110.071916 -224.498154)
			(xy 110.064042 -224.520252) (xy 110.26902 -224.87509) (xy 110.29188 -224.879408) (xy 110.316709 -224.884542)
			(xy 110.364488 -224.901501) (xy 110.409108 -224.925578) (xy 110.449514 -224.956202) (xy 110.484754 -224.992654)
			(xy 110.513997 -225.034071) (xy 110.536552 -225.079478) (xy 110.551888 -225.127804) (xy 110.559643 -225.177908)
			(xy 110.560104 -225.203258) (xy 110.559596 -225.229165) (xy 110.55149 -225.280342) (xy 110.535478 -225.329621)
			(xy 110.511955 -225.375788) (xy 110.481499 -225.417707) (xy 110.444861 -225.454345) (xy 110.402942 -225.484801)
			(xy 110.356775 -225.508324) (xy 110.307496 -225.524336) (xy 110.256319 -225.532442) (xy 110.204505 -225.532442)
			(xy 110.153328 -225.524336) (xy 110.104049 -225.508324) (xy 110.057882 -225.484801) (xy 110.015963 -225.454345)
			(xy 109.979325 -225.417707) (xy 109.948869 -225.375788) (xy 109.925346 -225.329621) (xy 109.909334 -225.280342)
			(xy 109.901228 -225.229165) (xy 109.90072 -225.203258) (xy 109.901327 -225.175541) (xy 109.910642 -225.120895)
			(xy 109.919262 -225.094546) (xy 109.927136 -225.072448) (xy 109.722158 -224.71761) (xy 109.699298 -224.713292)
			(xy 109.674485 -224.708145) (xy 109.626743 -224.691153) (xy 109.582163 -224.667056) (xy 109.541796 -224.63642)
			(xy 109.506593 -224.599968) (xy 109.477382 -224.558558) (xy 109.454852 -224.513166) (xy 109.439534 -224.46486)
			(xy 109.431788 -224.41478) (xy 109.431328 -224.389442) (xy 109.150404 -224.389442) (xy 109.149896 -224.415329)
			(xy 109.141797 -224.466467) (xy 109.125798 -224.515707) (xy 109.102292 -224.561839) (xy 109.07186 -224.603726)
			(xy 109.03525 -224.640336) (xy 108.993363 -224.670768) (xy 108.947231 -224.694274) (xy 108.897991 -224.710273)
			(xy 108.846853 -224.718372) (xy 108.795079 -224.718372) (xy 108.743941 -224.710273) (xy 108.694701 -224.694274)
			(xy 108.648569 -224.670768) (xy 108.606682 -224.640336) (xy 108.570072 -224.603726) (xy 108.53964 -224.561839)
			(xy 108.516134 -224.515707) (xy 108.500135 -224.466467) (xy 108.492036 -224.415329) (xy 108.491528 -224.389442)
			(xy 108.210604 -224.389442) (xy 108.21006 -224.417149) (xy 108.200874 -224.471796) (xy 108.192316 -224.498154)
			(xy 108.184442 -224.520252) (xy 108.38942 -224.87509) (xy 108.41228 -224.879408) (xy 108.437109 -224.884542)
			(xy 108.484888 -224.901501) (xy 108.529508 -224.925578) (xy 108.569914 -224.956202) (xy 108.605154 -224.992654)
			(xy 108.634397 -225.034071) (xy 108.656952 -225.079478) (xy 108.672288 -225.127804) (xy 108.680043 -225.177908)
			(xy 108.680504 -225.203258) (xy 108.679996 -225.229165) (xy 108.67189 -225.280342) (xy 108.655878 -225.329621)
			(xy 108.632355 -225.375788) (xy 108.601899 -225.417707) (xy 108.565261 -225.454345) (xy 108.523342 -225.484801)
			(xy 108.477175 -225.508324) (xy 108.427896 -225.524336) (xy 108.376719 -225.532442) (xy 108.324905 -225.532442)
			(xy 108.273728 -225.524336) (xy 108.224449 -225.508324) (xy 108.178282 -225.484801) (xy 108.136363 -225.454345)
			(xy 108.099725 -225.417707) (xy 108.069269 -225.375788) (xy 108.045746 -225.329621) (xy 108.029734 -225.280342)
			(xy 108.021628 -225.229165) (xy 108.02112 -225.203258) (xy 108.021727 -225.175541) (xy 108.031042 -225.120895)
			(xy 108.039662 -225.094546) (xy 108.047536 -225.072448) (xy 107.842558 -224.71761) (xy 107.819698 -224.713292)
			(xy 107.794885 -224.708145) (xy 107.747143 -224.691153) (xy 107.702563 -224.667056) (xy 107.662196 -224.63642)
			(xy 107.626993 -224.599968) (xy 107.597782 -224.558558) (xy 107.575252 -224.513166) (xy 107.559934 -224.46486)
			(xy 107.552188 -224.41478) (xy 107.551728 -224.389442) (xy 107.270804 -224.389442) (xy 107.270296 -224.415329)
			(xy 107.262197 -224.466467) (xy 107.246198 -224.515707) (xy 107.222692 -224.561839) (xy 107.19226 -224.603726)
			(xy 107.15565 -224.640336) (xy 107.113763 -224.670768) (xy 107.067631 -224.694274) (xy 107.018391 -224.710273)
			(xy 106.967253 -224.718372) (xy 106.915479 -224.718372) (xy 106.864341 -224.710273) (xy 106.815101 -224.694274)
			(xy 106.768969 -224.670768) (xy 106.727082 -224.640336) (xy 106.690472 -224.603726) (xy 106.66004 -224.561839)
			(xy 106.636534 -224.515707) (xy 106.620535 -224.466467) (xy 106.612436 -224.415329) (xy 106.611928 -224.389442)
			(xy 106.331004 -224.389442) (xy 106.33046 -224.417149) (xy 106.321274 -224.471796) (xy 106.312716 -224.498154)
			(xy 106.304842 -224.520252) (xy 106.50982 -224.87509) (xy 106.53268 -224.879408) (xy 106.557509 -224.884542)
			(xy 106.605288 -224.901501) (xy 106.649908 -224.925578) (xy 106.690314 -224.956202) (xy 106.725554 -224.992654)
			(xy 106.754797 -225.034071) (xy 106.777352 -225.079478) (xy 106.792688 -225.127804) (xy 106.800443 -225.177908)
			(xy 106.800904 -225.203258) (xy 106.800396 -225.229165) (xy 106.79229 -225.280342) (xy 106.776278 -225.329621)
			(xy 106.752755 -225.375788) (xy 106.722299 -225.417707) (xy 106.685661 -225.454345) (xy 106.643742 -225.484801)
			(xy 106.597575 -225.508324) (xy 106.548296 -225.524336) (xy 106.497119 -225.532442) (xy 106.445305 -225.532442)
			(xy 106.394128 -225.524336) (xy 106.344849 -225.508324) (xy 106.298682 -225.484801) (xy 106.256763 -225.454345)
			(xy 106.220125 -225.417707) (xy 106.189669 -225.375788) (xy 106.166146 -225.329621) (xy 106.150134 -225.280342)
			(xy 106.142028 -225.229165) (xy 106.14152 -225.203258) (xy 106.142127 -225.175541) (xy 106.151442 -225.120895)
			(xy 106.160062 -225.094546) (xy 106.167936 -225.072448) (xy 105.962958 -224.71761) (xy 105.940098 -224.713292)
			(xy 105.915285 -224.708145) (xy 105.867543 -224.691153) (xy 105.822963 -224.667056) (xy 105.782596 -224.63642)
			(xy 105.747393 -224.599968) (xy 105.718182 -224.558558) (xy 105.695652 -224.513166) (xy 105.680334 -224.46486)
			(xy 105.672588 -224.41478) (xy 105.672128 -224.389442) (xy 105.391204 -224.389442) (xy 105.390696 -224.415329)
			(xy 105.382597 -224.466467) (xy 105.366598 -224.515707) (xy 105.343092 -224.561839) (xy 105.31266 -224.603726)
			(xy 105.27605 -224.640336) (xy 105.234163 -224.670768) (xy 105.188031 -224.694274) (xy 105.138791 -224.710273)
			(xy 105.087653 -224.718372) (xy 105.035879 -224.718372) (xy 104.984741 -224.710273) (xy 104.935501 -224.694274)
			(xy 104.889369 -224.670768) (xy 104.847482 -224.640336) (xy 104.810872 -224.603726) (xy 104.78044 -224.561839)
			(xy 104.756934 -224.515707) (xy 104.740935 -224.466467) (xy 104.732836 -224.415329) (xy 104.732328 -224.389442)
			(xy 104.451404 -224.389442) (xy 104.45086 -224.417149) (xy 104.441674 -224.471796) (xy 104.433116 -224.498154)
			(xy 104.425242 -224.520252) (xy 104.63022 -224.87509) (xy 104.65308 -224.879408) (xy 104.677909 -224.884542)
			(xy 104.725688 -224.901501) (xy 104.770308 -224.925578) (xy 104.810714 -224.956202) (xy 104.845954 -224.992654)
			(xy 104.875197 -225.034071) (xy 104.897752 -225.079478) (xy 104.913088 -225.127804) (xy 104.920843 -225.177908)
			(xy 104.921304 -225.203258) (xy 104.920796 -225.229165) (xy 104.91269 -225.280342) (xy 104.896678 -225.329621)
			(xy 104.873155 -225.375788) (xy 104.842699 -225.417707) (xy 104.806061 -225.454345) (xy 104.764142 -225.484801)
			(xy 104.717975 -225.508324) (xy 104.668696 -225.524336) (xy 104.617519 -225.532442) (xy 104.565705 -225.532442)
			(xy 104.514528 -225.524336) (xy 104.465249 -225.508324) (xy 104.419082 -225.484801) (xy 104.377163 -225.454345)
			(xy 104.340525 -225.417707) (xy 104.310069 -225.375788) (xy 104.286546 -225.329621) (xy 104.270534 -225.280342)
			(xy 104.262428 -225.229165) (xy 104.26192 -225.203258) (xy 104.262527 -225.175541) (xy 104.271842 -225.120895)
			(xy 104.280462 -225.094546) (xy 104.288336 -225.072448) (xy 104.083358 -224.71761) (xy 104.060498 -224.713292)
			(xy 104.035685 -224.708145) (xy 103.987943 -224.691153) (xy 103.943363 -224.667056) (xy 103.902996 -224.63642)
			(xy 103.867793 -224.599968) (xy 103.838582 -224.558558) (xy 103.816052 -224.513166) (xy 103.800734 -224.46486)
			(xy 103.792988 -224.41478) (xy 103.792528 -224.389442) (xy 103.511604 -224.389442) (xy 103.511096 -224.415329)
			(xy 103.502997 -224.466467) (xy 103.486998 -224.515707) (xy 103.463492 -224.561839) (xy 103.43306 -224.603726)
			(xy 103.39645 -224.640336) (xy 103.354563 -224.670768) (xy 103.308431 -224.694274) (xy 103.259191 -224.710273)
			(xy 103.208053 -224.718372) (xy 103.156279 -224.718372) (xy 103.105141 -224.710273) (xy 103.055901 -224.694274)
			(xy 103.009769 -224.670768) (xy 102.967882 -224.640336) (xy 102.931272 -224.603726) (xy 102.90084 -224.561839)
			(xy 102.877334 -224.515707) (xy 102.861335 -224.466467) (xy 102.853236 -224.415329) (xy 102.852728 -224.389442)
			(xy 102.571804 -224.389442) (xy 102.57126 -224.417149) (xy 102.562074 -224.471796) (xy 102.553516 -224.498154)
			(xy 102.545642 -224.520252) (xy 102.75062 -224.87509) (xy 102.77348 -224.879408) (xy 102.798309 -224.884542)
			(xy 102.846088 -224.901501) (xy 102.890708 -224.925578) (xy 102.931114 -224.956202) (xy 102.966354 -224.992654)
			(xy 102.995597 -225.034071) (xy 103.018152 -225.079478) (xy 103.033488 -225.127804) (xy 103.041243 -225.177908)
			(xy 103.041704 -225.203258) (xy 103.041196 -225.229165) (xy 103.03309 -225.280342) (xy 103.017078 -225.329621)
			(xy 102.993555 -225.375788) (xy 102.963099 -225.417707) (xy 102.926461 -225.454345) (xy 102.884542 -225.484801)
			(xy 102.838375 -225.508324) (xy 102.789096 -225.524336) (xy 102.737919 -225.532442) (xy 102.686105 -225.532442)
			(xy 102.634928 -225.524336) (xy 102.585649 -225.508324) (xy 102.539482 -225.484801) (xy 102.497563 -225.454345)
			(xy 102.460925 -225.417707) (xy 102.430469 -225.375788) (xy 102.406946 -225.329621) (xy 102.390934 -225.280342)
			(xy 102.382828 -225.229165) (xy 102.38232 -225.203258) (xy 102.382927 -225.175541) (xy 102.392242 -225.120895)
			(xy 102.400862 -225.094546) (xy 102.408736 -225.072448) (xy 102.203758 -224.71761) (xy 102.180898 -224.713292)
			(xy 102.156085 -224.708145) (xy 102.108343 -224.691153) (xy 102.063763 -224.667056) (xy 102.023396 -224.63642)
			(xy 101.988193 -224.599968) (xy 101.958982 -224.558558) (xy 101.936452 -224.513166) (xy 101.921134 -224.46486)
			(xy 101.913388 -224.41478) (xy 101.912928 -224.389442) (xy 101.632004 -224.389442) (xy 101.631496 -224.415329)
			(xy 101.623397 -224.466467) (xy 101.607398 -224.515707) (xy 101.583892 -224.561839) (xy 101.55346 -224.603726)
			(xy 101.51685 -224.640336) (xy 101.474963 -224.670768) (xy 101.428831 -224.694274) (xy 101.379591 -224.710273)
			(xy 101.328453 -224.718372) (xy 101.276679 -224.718372) (xy 101.225541 -224.710273) (xy 101.176301 -224.694274)
			(xy 101.130169 -224.670768) (xy 101.088282 -224.640336) (xy 101.051672 -224.603726) (xy 101.02124 -224.561839)
			(xy 100.997734 -224.515707) (xy 100.981735 -224.466467) (xy 100.973636 -224.415329) (xy 100.973128 -224.389442)
			(xy 100.692204 -224.389442) (xy 100.69166 -224.417149) (xy 100.682474 -224.471796) (xy 100.673916 -224.498154)
			(xy 100.666042 -224.520252) (xy 100.87102 -224.87509) (xy 100.89388 -224.879408) (xy 100.918709 -224.884542)
			(xy 100.966488 -224.901501) (xy 101.011108 -224.925578) (xy 101.051514 -224.956202) (xy 101.086754 -224.992654)
			(xy 101.115997 -225.034071) (xy 101.138552 -225.079478) (xy 101.153888 -225.127804) (xy 101.161643 -225.177908)
			(xy 101.162104 -225.203258) (xy 101.161596 -225.229165) (xy 101.15349 -225.280342) (xy 101.137478 -225.329621)
			(xy 101.113955 -225.375788) (xy 101.083499 -225.417707) (xy 101.046861 -225.454345) (xy 101.004942 -225.484801)
			(xy 100.958775 -225.508324) (xy 100.909496 -225.524336) (xy 100.858319 -225.532442) (xy 100.806505 -225.532442)
			(xy 100.755328 -225.524336) (xy 100.706049 -225.508324) (xy 100.659882 -225.484801) (xy 100.617963 -225.454345)
			(xy 100.581325 -225.417707) (xy 100.550869 -225.375788) (xy 100.527346 -225.329621) (xy 100.511334 -225.280342)
			(xy 100.503228 -225.229165) (xy 100.50272 -225.203258) (xy 100.503327 -225.175541) (xy 100.512642 -225.120895)
			(xy 100.521262 -225.094546) (xy 100.529136 -225.072448) (xy 100.324158 -224.71761) (xy 100.301298 -224.713292)
			(xy 100.276485 -224.708145) (xy 100.228743 -224.691153) (xy 100.184163 -224.667056) (xy 100.143796 -224.63642)
			(xy 100.108593 -224.599968) (xy 100.079382 -224.558558) (xy 100.056852 -224.513166) (xy 100.041534 -224.46486)
			(xy 100.033788 -224.41478) (xy 100.033328 -224.389442) (xy 99.752404 -224.389442) (xy 99.751896 -224.415329)
			(xy 99.743797 -224.466467) (xy 99.727798 -224.515707) (xy 99.704292 -224.561839) (xy 99.67386 -224.603726)
			(xy 99.63725 -224.640336) (xy 99.595363 -224.670768) (xy 99.549231 -224.694274) (xy 99.499991 -224.710273)
			(xy 99.448853 -224.718372) (xy 99.397079 -224.718372) (xy 99.345941 -224.710273) (xy 99.296701 -224.694274)
			(xy 99.250569 -224.670768) (xy 99.208682 -224.640336) (xy 99.172072 -224.603726) (xy 99.14164 -224.561839)
			(xy 99.118134 -224.515707) (xy 99.102135 -224.466467) (xy 99.094036 -224.415329) (xy 99.093528 -224.389442)
			(xy 98.812604 -224.389442) (xy 98.81206 -224.417149) (xy 98.802874 -224.471796) (xy 98.794316 -224.498154)
			(xy 98.786442 -224.520252) (xy 98.99142 -224.87509) (xy 99.01428 -224.879408) (xy 99.039109 -224.884542)
			(xy 99.086888 -224.901501) (xy 99.131508 -224.925578) (xy 99.171914 -224.956202) (xy 99.207154 -224.992654)
			(xy 99.236397 -225.034071) (xy 99.258952 -225.079478) (xy 99.274288 -225.127804) (xy 99.282043 -225.177908)
			(xy 99.282504 -225.203258) (xy 99.281996 -225.229165) (xy 99.27389 -225.280342) (xy 99.257878 -225.329621)
			(xy 99.234355 -225.375788) (xy 99.203899 -225.417707) (xy 99.167261 -225.454345) (xy 99.125342 -225.484801)
			(xy 99.079175 -225.508324) (xy 99.029896 -225.524336) (xy 98.978719 -225.532442) (xy 98.926905 -225.532442)
			(xy 98.875728 -225.524336) (xy 98.826449 -225.508324) (xy 98.780282 -225.484801) (xy 98.738363 -225.454345)
			(xy 98.701725 -225.417707) (xy 98.671269 -225.375788) (xy 98.647746 -225.329621) (xy 98.631734 -225.280342)
			(xy 98.623628 -225.229165) (xy 98.62312 -225.203258) (xy 98.623727 -225.175541) (xy 98.633042 -225.120895)
			(xy 98.641662 -225.094546) (xy 98.649536 -225.072448) (xy 98.444558 -224.71761) (xy 98.421698 -224.713292)
			(xy 98.396885 -224.708145) (xy 98.349143 -224.691153) (xy 98.304563 -224.667056) (xy 98.264196 -224.63642)
			(xy 98.228993 -224.599968) (xy 98.199782 -224.558558) (xy 98.177252 -224.513166) (xy 98.161934 -224.46486)
			(xy 98.154188 -224.41478) (xy 98.153728 -224.389442) (xy 97.872804 -224.389442) (xy 97.872296 -224.415329)
			(xy 97.864197 -224.466467) (xy 97.848198 -224.515707) (xy 97.824692 -224.561839) (xy 97.79426 -224.603726)
			(xy 97.75765 -224.640336) (xy 97.715763 -224.670768) (xy 97.669631 -224.694274) (xy 97.620391 -224.710273)
			(xy 97.569253 -224.718372) (xy 97.517479 -224.718372) (xy 97.466341 -224.710273) (xy 97.417101 -224.694274)
			(xy 97.370969 -224.670768) (xy 97.329082 -224.640336) (xy 97.292472 -224.603726) (xy 97.26204 -224.561839)
			(xy 97.238534 -224.515707) (xy 97.222535 -224.466467) (xy 97.214436 -224.415329) (xy 97.213928 -224.389442)
			(xy 96.933004 -224.389442) (xy 96.93246 -224.417149) (xy 96.923274 -224.471796) (xy 96.914716 -224.498154)
			(xy 96.906842 -224.520252) (xy 97.11182 -224.87509) (xy 97.13468 -224.879408) (xy 97.159509 -224.884542)
			(xy 97.207288 -224.901501) (xy 97.251908 -224.925578) (xy 97.292314 -224.956202) (xy 97.327554 -224.992654)
			(xy 97.356797 -225.034071) (xy 97.379352 -225.079478) (xy 97.394688 -225.127804) (xy 97.402443 -225.177908)
			(xy 97.402904 -225.203258) (xy 97.402396 -225.229165) (xy 97.39429 -225.280342) (xy 97.378278 -225.329621)
			(xy 97.354755 -225.375788) (xy 97.324299 -225.417707) (xy 97.287661 -225.454345) (xy 97.245742 -225.484801)
			(xy 97.199575 -225.508324) (xy 97.150296 -225.524336) (xy 97.099119 -225.532442) (xy 97.047305 -225.532442)
			(xy 96.996128 -225.524336) (xy 96.946849 -225.508324) (xy 96.900682 -225.484801) (xy 96.858763 -225.454345)
			(xy 96.822125 -225.417707) (xy 96.791669 -225.375788) (xy 96.768146 -225.329621) (xy 96.752134 -225.280342)
			(xy 96.744028 -225.229165) (xy 96.74352 -225.203258) (xy 96.744127 -225.175541) (xy 96.753442 -225.120895)
			(xy 96.762062 -225.094546) (xy 96.769936 -225.072448) (xy 96.564958 -224.71761) (xy 96.542098 -224.713292)
			(xy 96.517285 -224.708145) (xy 96.469543 -224.691153) (xy 96.424963 -224.667056) (xy 96.384596 -224.63642)
			(xy 96.349393 -224.599968) (xy 96.320182 -224.558558) (xy 96.297652 -224.513166) (xy 96.282334 -224.46486)
			(xy 96.274588 -224.41478) (xy 96.274128 -224.389442) (xy 95.993204 -224.389442) (xy 95.992696 -224.415329)
			(xy 95.984597 -224.466467) (xy 95.968598 -224.515707) (xy 95.945092 -224.561839) (xy 95.91466 -224.603726)
			(xy 95.87805 -224.640336) (xy 95.836163 -224.670768) (xy 95.790031 -224.694274) (xy 95.740791 -224.710273)
			(xy 95.689653 -224.718372) (xy 95.637879 -224.718372) (xy 95.586741 -224.710273) (xy 95.537501 -224.694274)
			(xy 95.491369 -224.670768) (xy 95.449482 -224.640336) (xy 95.412872 -224.603726) (xy 95.38244 -224.561839)
			(xy 95.358934 -224.515707) (xy 95.342935 -224.466467) (xy 95.334836 -224.415329) (xy 95.334328 -224.389442)
			(xy 95.053404 -224.389442) (xy 95.05286 -224.417149) (xy 95.043674 -224.471796) (xy 95.035116 -224.498154)
			(xy 95.027242 -224.520252) (xy 95.23222 -224.87509) (xy 95.25508 -224.879408) (xy 95.279909 -224.884542)
			(xy 95.327688 -224.901501) (xy 95.372308 -224.925578) (xy 95.412714 -224.956202) (xy 95.447954 -224.992654)
			(xy 95.477197 -225.034071) (xy 95.499752 -225.079478) (xy 95.515088 -225.127804) (xy 95.522843 -225.177908)
			(xy 95.523304 -225.203258) (xy 95.522796 -225.229165) (xy 95.51469 -225.280342) (xy 95.498678 -225.329621)
			(xy 95.475155 -225.375788) (xy 95.444699 -225.417707) (xy 95.408061 -225.454345) (xy 95.366142 -225.484801)
			(xy 95.319975 -225.508324) (xy 95.270696 -225.524336) (xy 95.219519 -225.532442) (xy 95.167705 -225.532442)
			(xy 95.116528 -225.524336) (xy 95.067249 -225.508324) (xy 95.021082 -225.484801) (xy 94.979163 -225.454345)
			(xy 94.942525 -225.417707) (xy 94.912069 -225.375788) (xy 94.888546 -225.329621) (xy 94.872534 -225.280342)
			(xy 94.864428 -225.229165) (xy 94.86392 -225.203258) (xy 94.864527 -225.175541) (xy 94.873842 -225.120895)
			(xy 94.882462 -225.094546) (xy 94.890336 -225.072448) (xy 94.685358 -224.71761) (xy 94.662498 -224.713292)
			(xy 94.637685 -224.708145) (xy 94.589943 -224.691153) (xy 94.545363 -224.667056) (xy 94.504996 -224.63642)
			(xy 94.469793 -224.599968) (xy 94.440582 -224.558558) (xy 94.418052 -224.513166) (xy 94.402734 -224.46486)
			(xy 94.394988 -224.41478) (xy 94.394528 -224.389442) (xy 94.113604 -224.389442) (xy 94.113096 -224.415329)
			(xy 94.104997 -224.466467) (xy 94.088998 -224.515707) (xy 94.065492 -224.561839) (xy 94.03506 -224.603726)
			(xy 93.99845 -224.640336) (xy 93.956563 -224.670768) (xy 93.910431 -224.694274) (xy 93.861191 -224.710273)
			(xy 93.810053 -224.718372) (xy 93.758279 -224.718372) (xy 93.707141 -224.710273) (xy 93.657901 -224.694274)
			(xy 93.611769 -224.670768) (xy 93.569882 -224.640336) (xy 93.533272 -224.603726) (xy 93.50284 -224.561839)
			(xy 93.479334 -224.515707) (xy 93.463335 -224.466467) (xy 93.455236 -224.415329) (xy 93.454728 -224.389442)
			(xy 2.509012 -224.389442) (xy 2.509012 -247.620536) (xy 228.175312 -247.620536) (xy 228.175312 -246.756936)
			(xy 228.175798 -246.729685) (xy 228.183554 -246.675737) (xy 228.198909 -246.623442) (xy 228.221551 -246.573865)
			(xy 228.251017 -246.528015) (xy 228.286708 -246.486824) (xy 228.327899 -246.451133) (xy 228.373749 -246.421667)
			(xy 228.423326 -246.399025) (xy 228.475621 -246.38367) (xy 228.529569 -246.375914) (xy 228.584071 -246.375914)
			(xy 228.638019 -246.38367) (xy 228.690314 -246.399025) (xy 228.739891 -246.421667) (xy 228.785741 -246.451133)
			(xy 228.826932 -246.486824) (xy 228.862623 -246.528015) (xy 228.892089 -246.573865) (xy 228.914731 -246.623442)
			(xy 228.930086 -246.675737) (xy 228.937842 -246.729685) (xy 228.938328 -246.756936) (xy 228.938328 -247.620536)
			(xy 228.937842 -247.647787) (xy 228.930086 -247.701735) (xy 228.914731 -247.75403) (xy 228.892089 -247.803607)
			(xy 228.862623 -247.849457) (xy 228.826932 -247.890648) (xy 228.785741 -247.926339) (xy 228.739891 -247.955805)
			(xy 228.690314 -247.978447) (xy 228.638019 -247.993802) (xy 228.584071 -248.001558) (xy 228.529569 -248.001558)
			(xy 228.475621 -247.993802) (xy 228.423326 -247.978447) (xy 228.373749 -247.955805) (xy 228.327899 -247.926339)
			(xy 228.286708 -247.890648) (xy 228.251017 -247.849457) (xy 228.221551 -247.803607) (xy 228.198909 -247.75403)
			(xy 228.183554 -247.701735) (xy 228.175798 -247.647787) (xy 228.175312 -247.620536) (xy 2.509012 -247.620536)
			(xy 2.509012 -251.76988) (xy 75.695566 -251.76988) (xy 75.699547 -251.63686) (xy 75.711476 -251.504315)
			(xy 75.731311 -251.372722) (xy 75.75898 -251.24255) (xy 75.794384 -251.114265) (xy 75.837397 -250.988328)
			(xy 75.887864 -250.865189) (xy 75.945605 -250.745288) (xy 76.010414 -250.629055) (xy 76.082058 -250.516905)
			(xy 76.16028 -250.409241) (xy 76.244801 -250.306448) (xy 76.335319 -250.208893) (xy 76.431508 -250.116927)
			(xy 76.533026 -250.030877) (xy 76.639507 -249.951053) (xy 76.750572 -249.87774) (xy 76.865823 -249.8112)
			(xy 76.984847 -249.751671) (xy 77.107218 -249.699367) (xy 77.232497 -249.654475) (xy 77.360238 -249.617156)
			(xy 77.489981 -249.587543) (xy 77.621263 -249.565742) (xy 77.753614 -249.551832) (xy 77.88656 -249.545861)
			(xy 78.019625 -249.547852) (xy 78.152333 -249.557797) (xy 78.284209 -249.575661) (xy 78.41478 -249.601379)
			(xy 78.54358 -249.63486) (xy 78.670146 -249.675984) (xy 78.794027 -249.724604) (xy 78.914778 -249.780545)
			(xy 79.031968 -249.843607) (xy 79.145177 -249.913565) (xy 79.253999 -249.990169) (xy 79.358045 -250.073143)
			(xy 79.456943 -250.162191) (xy 79.550338 -250.256994) (xy 79.637896 -250.357212) (xy 79.719305 -250.462488)
			(xy 79.794271 -250.572444) (xy 79.862528 -250.686686) (xy 79.92383 -250.804806) (xy 79.977959 -250.926381)
			(xy 80.02472 -251.050975) (xy 80.063946 -251.178143) (xy 80.095496 -251.307429) (xy 80.119259 -251.43837)
			(xy 80.135148 -251.570498) (xy 80.143106 -251.70334) (xy 80.143604 -251.76988) (xy 143.715496 -251.76988)
			(xy 143.719477 -251.63686) (xy 143.731406 -251.504315) (xy 143.751241 -251.372722) (xy 143.77891 -251.24255)
			(xy 143.814314 -251.114265) (xy 143.857327 -250.988328) (xy 143.907794 -250.865189) (xy 143.965535 -250.745288)
			(xy 144.030344 -250.629055) (xy 144.101988 -250.516905) (xy 144.18021 -250.409241) (xy 144.264731 -250.306448)
			(xy 144.355249 -250.208893) (xy 144.451438 -250.116927) (xy 144.552956 -250.030877) (xy 144.659437 -249.951053)
			(xy 144.770502 -249.87774) (xy 144.885753 -249.8112) (xy 145.004777 -249.751671) (xy 145.127148 -249.699367)
			(xy 145.252427 -249.654475) (xy 145.380168 -249.617156) (xy 145.509911 -249.587543) (xy 145.641193 -249.565742)
			(xy 145.773544 -249.551832) (xy 145.90649 -249.545861) (xy 146.039555 -249.547852) (xy 146.172263 -249.557797)
			(xy 146.304139 -249.575661) (xy 146.43471 -249.601379) (xy 146.56351 -249.63486) (xy 146.690076 -249.675984)
			(xy 146.813957 -249.724604) (xy 146.934708 -249.780545) (xy 147.051898 -249.843607) (xy 147.165107 -249.913565)
			(xy 147.273929 -249.990169) (xy 147.377975 -250.073143) (xy 147.476873 -250.162191) (xy 147.570268 -250.256994)
			(xy 147.657826 -250.357212) (xy 147.739235 -250.462488) (xy 147.814201 -250.572444) (xy 147.882458 -250.686686)
			(xy 147.94376 -250.804806) (xy 147.997889 -250.926381) (xy 148.04465 -251.050975) (xy 148.083876 -251.178143)
			(xy 148.115426 -251.307429) (xy 148.139189 -251.43837) (xy 148.155078 -251.570498) (xy 148.163036 -251.70334)
			(xy 148.163534 -251.76988) (xy 323.635634 -251.76988) (xy 323.639615 -251.63686) (xy 323.651544 -251.504315)
			(xy 323.671379 -251.372722) (xy 323.699048 -251.24255) (xy 323.734452 -251.114265) (xy 323.777465 -250.988328)
			(xy 323.827932 -250.865189) (xy 323.885673 -250.745288) (xy 323.950482 -250.629055) (xy 324.022126 -250.516905)
			(xy 324.100348 -250.409241) (xy 324.184869 -250.306448) (xy 324.275387 -250.208893) (xy 324.371576 -250.116927)
			(xy 324.473094 -250.030877) (xy 324.579575 -249.951053) (xy 324.69064 -249.87774) (xy 324.805891 -249.8112)
			(xy 324.924915 -249.751671) (xy 325.047286 -249.699367) (xy 325.172565 -249.654475) (xy 325.300306 -249.617156)
			(xy 325.430049 -249.587543) (xy 325.561331 -249.565742) (xy 325.693682 -249.551832) (xy 325.826628 -249.545861)
			(xy 325.959693 -249.547852) (xy 326.092401 -249.557797) (xy 326.224277 -249.575661) (xy 326.354848 -249.601379)
			(xy 326.483648 -249.63486) (xy 326.610214 -249.675984) (xy 326.734095 -249.724604) (xy 326.854846 -249.780545)
			(xy 326.972036 -249.843607) (xy 327.085245 -249.913565) (xy 327.194067 -249.990169) (xy 327.298113 -250.073143)
			(xy 327.397011 -250.162191) (xy 327.490406 -250.256994) (xy 327.577964 -250.357212) (xy 327.659373 -250.462488)
			(xy 327.734339 -250.572444) (xy 327.802596 -250.686686) (xy 327.863898 -250.804806) (xy 327.918027 -250.926381)
			(xy 327.964788 -251.050975) (xy 328.004014 -251.178143) (xy 328.035564 -251.307429) (xy 328.059327 -251.43837)
			(xy 328.075216 -251.570498) (xy 328.083174 -251.70334) (xy 328.083672 -251.76988) (xy 391.655564 -251.76988)
			(xy 391.659545 -251.63686) (xy 391.671474 -251.504315) (xy 391.691309 -251.372722) (xy 391.718978 -251.24255)
			(xy 391.754382 -251.114265) (xy 391.797395 -250.988328) (xy 391.847862 -250.865189) (xy 391.905603 -250.745288)
			(xy 391.970412 -250.629055) (xy 392.042056 -250.516905) (xy 392.120278 -250.409241) (xy 392.204799 -250.306448)
			(xy 392.295317 -250.208893) (xy 392.391506 -250.116927) (xy 392.493024 -250.030877) (xy 392.599505 -249.951053)
			(xy 392.71057 -249.87774) (xy 392.825821 -249.8112) (xy 392.944845 -249.751671) (xy 393.067216 -249.699367)
			(xy 393.192495 -249.654475) (xy 393.320236 -249.617156) (xy 393.449979 -249.587543) (xy 393.581261 -249.565742)
			(xy 393.713612 -249.551832) (xy 393.846558 -249.545861) (xy 393.979623 -249.547852) (xy 394.112331 -249.557797)
			(xy 394.244207 -249.575661) (xy 394.374778 -249.601379) (xy 394.503578 -249.63486) (xy 394.630144 -249.675984)
			(xy 394.754025 -249.724604) (xy 394.874776 -249.780545) (xy 394.991966 -249.843607) (xy 395.105175 -249.913565)
			(xy 395.213997 -249.990169) (xy 395.318043 -250.073143) (xy 395.416941 -250.162191) (xy 395.510336 -250.256994)
			(xy 395.597894 -250.357212) (xy 395.679303 -250.462488) (xy 395.754269 -250.572444) (xy 395.822526 -250.686686)
			(xy 395.883828 -250.804806) (xy 395.937957 -250.926381) (xy 395.984718 -251.050975) (xy 396.023944 -251.178143)
			(xy 396.055494 -251.307429) (xy 396.079257 -251.43837) (xy 396.095146 -251.570498) (xy 396.103104 -251.70334)
			(xy 396.103602 -251.76988) (xy 396.103104 -251.83642) (xy 396.095146 -251.969262) (xy 396.079257 -252.10139)
			(xy 396.055494 -252.232331) (xy 396.023944 -252.361617) (xy 395.984718 -252.488785) (xy 395.937957 -252.613379)
			(xy 395.883828 -252.734954) (xy 395.822526 -252.853074) (xy 395.754269 -252.967316) (xy 395.679303 -253.077272)
			(xy 395.597894 -253.182548) (xy 395.510336 -253.282766) (xy 395.416941 -253.377569) (xy 395.318043 -253.466617)
			(xy 395.213997 -253.549591) (xy 395.105175 -253.626195) (xy 394.991966 -253.696153) (xy 394.874776 -253.759215)
			(xy 394.754025 -253.815156) (xy 394.630144 -253.863776) (xy 394.503578 -253.9049) (xy 394.374778 -253.938381)
			(xy 394.244207 -253.964099) (xy 394.112331 -253.981963) (xy 393.979623 -253.991908) (xy 393.846558 -253.993899)
			(xy 393.713612 -253.987928) (xy 393.581261 -253.974018) (xy 393.449979 -253.952217) (xy 393.320236 -253.922604)
			(xy 393.192495 -253.885285) (xy 393.067216 -253.840393) (xy 392.944845 -253.788089) (xy 392.825821 -253.72856)
			(xy 392.71057 -253.66202) (xy 392.599505 -253.588707) (xy 392.493024 -253.508883) (xy 392.391506 -253.422833)
			(xy 392.295317 -253.330867) (xy 392.204799 -253.233312) (xy 392.120278 -253.130519) (xy 392.042056 -253.022855)
			(xy 391.970412 -252.910705) (xy 391.905603 -252.794472) (xy 391.847862 -252.674571) (xy 391.797395 -252.551432)
			(xy 391.754382 -252.425495) (xy 391.718978 -252.29721) (xy 391.691309 -252.167038) (xy 391.671474 -252.035445)
			(xy 391.659545 -251.9029) (xy 391.655564 -251.76988) (xy 328.083672 -251.76988) (xy 328.083174 -251.83642)
			(xy 328.075216 -251.969262) (xy 328.059327 -252.10139) (xy 328.035564 -252.232331) (xy 328.004014 -252.361617)
			(xy 327.964788 -252.488785) (xy 327.918027 -252.613379) (xy 327.863898 -252.734954) (xy 327.802596 -252.853074)
			(xy 327.734339 -252.967316) (xy 327.659373 -253.077272) (xy 327.577964 -253.182548) (xy 327.490406 -253.282766)
			(xy 327.397011 -253.377569) (xy 327.298113 -253.466617) (xy 327.194067 -253.549591) (xy 327.085245 -253.626195)
			(xy 326.972036 -253.696153) (xy 326.854846 -253.759215) (xy 326.734095 -253.815156) (xy 326.610214 -253.863776)
			(xy 326.483648 -253.9049) (xy 326.354848 -253.938381) (xy 326.224277 -253.964099) (xy 326.092401 -253.981963)
			(xy 325.959693 -253.991908) (xy 325.826628 -253.993899) (xy 325.693682 -253.987928) (xy 325.561331 -253.974018)
			(xy 325.430049 -253.952217) (xy 325.300306 -253.922604) (xy 325.172565 -253.885285) (xy 325.047286 -253.840393)
			(xy 324.924915 -253.788089) (xy 324.805891 -253.72856) (xy 324.69064 -253.66202) (xy 324.579575 -253.588707)
			(xy 324.473094 -253.508883) (xy 324.371576 -253.422833) (xy 324.275387 -253.330867) (xy 324.184869 -253.233312)
			(xy 324.100348 -253.130519) (xy 324.022126 -253.022855) (xy 323.950482 -252.910705) (xy 323.885673 -252.794472)
			(xy 323.827932 -252.674571) (xy 323.777465 -252.551432) (xy 323.734452 -252.425495) (xy 323.699048 -252.29721)
			(xy 323.671379 -252.167038) (xy 323.651544 -252.035445) (xy 323.639615 -251.9029) (xy 323.635634 -251.76988)
			(xy 148.163534 -251.76988) (xy 148.163036 -251.83642) (xy 148.155078 -251.969262) (xy 148.139189 -252.10139)
			(xy 148.115426 -252.232331) (xy 148.083876 -252.361617) (xy 148.04465 -252.488785) (xy 147.997889 -252.613379)
			(xy 147.94376 -252.734954) (xy 147.882458 -252.853074) (xy 147.814201 -252.967316) (xy 147.739235 -253.077272)
			(xy 147.657826 -253.182548) (xy 147.570268 -253.282766) (xy 147.476873 -253.377569) (xy 147.377975 -253.466617)
			(xy 147.273929 -253.549591) (xy 147.165107 -253.626195) (xy 147.051898 -253.696153) (xy 146.934708 -253.759215)
			(xy 146.813957 -253.815156) (xy 146.690076 -253.863776) (xy 146.56351 -253.9049) (xy 146.43471 -253.938381)
			(xy 146.304139 -253.964099) (xy 146.172263 -253.981963) (xy 146.039555 -253.991908) (xy 145.90649 -253.993899)
			(xy 145.773544 -253.987928) (xy 145.641193 -253.974018) (xy 145.509911 -253.952217) (xy 145.380168 -253.922604)
			(xy 145.252427 -253.885285) (xy 145.127148 -253.840393) (xy 145.004777 -253.788089) (xy 144.885753 -253.72856)
			(xy 144.770502 -253.66202) (xy 144.659437 -253.588707) (xy 144.552956 -253.508883) (xy 144.451438 -253.422833)
			(xy 144.355249 -253.330867) (xy 144.264731 -253.233312) (xy 144.18021 -253.130519) (xy 144.101988 -253.022855)
			(xy 144.030344 -252.910705) (xy 143.965535 -252.794472) (xy 143.907794 -252.674571) (xy 143.857327 -252.551432)
			(xy 143.814314 -252.425495) (xy 143.77891 -252.29721) (xy 143.751241 -252.167038) (xy 143.731406 -252.035445)
			(xy 143.719477 -251.9029) (xy 143.715496 -251.76988) (xy 80.143604 -251.76988) (xy 80.143106 -251.83642)
			(xy 80.135148 -251.969262) (xy 80.119259 -252.10139) (xy 80.095496 -252.232331) (xy 80.063946 -252.361617)
			(xy 80.02472 -252.488785) (xy 79.977959 -252.613379) (xy 79.92383 -252.734954) (xy 79.862528 -252.853074)
			(xy 79.794271 -252.967316) (xy 79.719305 -253.077272) (xy 79.637896 -253.182548) (xy 79.550338 -253.282766)
			(xy 79.456943 -253.377569) (xy 79.358045 -253.466617) (xy 79.253999 -253.549591) (xy 79.145177 -253.626195)
			(xy 79.031968 -253.696153) (xy 78.914778 -253.759215) (xy 78.794027 -253.815156) (xy 78.670146 -253.863776)
			(xy 78.54358 -253.9049) (xy 78.41478 -253.938381) (xy 78.284209 -253.964099) (xy 78.152333 -253.981963)
			(xy 78.019625 -253.991908) (xy 77.88656 -253.993899) (xy 77.753614 -253.987928) (xy 77.621263 -253.974018)
			(xy 77.489981 -253.952217) (xy 77.360238 -253.922604) (xy 77.232497 -253.885285) (xy 77.107218 -253.840393)
			(xy 76.984847 -253.788089) (xy 76.865823 -253.72856) (xy 76.750572 -253.66202) (xy 76.639507 -253.588707)
			(xy 76.533026 -253.508883) (xy 76.431508 -253.422833) (xy 76.335319 -253.330867) (xy 76.244801 -253.233312)
			(xy 76.16028 -253.130519) (xy 76.082058 -253.022855) (xy 76.010414 -252.910705) (xy 75.945605 -252.794472)
			(xy 75.887864 -252.674571) (xy 75.837397 -252.551432) (xy 75.794384 -252.425495) (xy 75.75898 -252.29721)
			(xy 75.731311 -252.167038) (xy 75.711476 -252.035445) (xy 75.699547 -251.9029) (xy 75.695566 -251.76988)
			(xy 2.509012 -251.76988) (xy 2.509012 -273.453098) (xy 108.574078 -273.453098) (xy 108.574577 -273.426411)
			(xy 108.582532 -273.373632) (xy 108.598264 -273.322629) (xy 108.621422 -273.27454) (xy 108.651489 -273.23044)
			(xy 108.687793 -273.191313) (xy 108.729523 -273.158035) (xy 108.775747 -273.131348) (xy 108.825432 -273.111848)
			(xy 108.877469 -273.099971) (xy 108.930694 -273.095982) (xy 108.983919 -273.099971) (xy 109.035956 -273.111848)
			(xy 109.085641 -273.131348) (xy 109.131865 -273.158035) (xy 109.173595 -273.191313) (xy 109.209899 -273.23044)
			(xy 109.239966 -273.27454) (xy 109.263124 -273.322629) (xy 109.278856 -273.373632) (xy 109.286811 -273.426411)
			(xy 109.28731 -273.453098) (xy 356.514146 -273.453098) (xy 356.514645 -273.426411) (xy 356.5226 -273.373632)
			(xy 356.538332 -273.322629) (xy 356.56149 -273.27454) (xy 356.591557 -273.23044) (xy 356.627861 -273.191313)
			(xy 356.669591 -273.158035) (xy 356.715815 -273.131348) (xy 356.7655 -273.111848) (xy 356.817537 -273.099971)
			(xy 356.870762 -273.095982) (xy 356.923987 -273.099971) (xy 356.976024 -273.111848) (xy 357.025709 -273.131348)
			(xy 357.071933 -273.158035) (xy 357.113663 -273.191313) (xy 357.149967 -273.23044) (xy 357.180034 -273.27454)
			(xy 357.203192 -273.322629) (xy 357.218924 -273.373632) (xy 357.226879 -273.426411) (xy 357.227378 -273.453098)
			(xy 357.227378 -273.453606) (xy 357.226987 -273.476808) (xy 357.220923 -273.522815) (xy 357.208951 -273.567648)
			(xy 357.200454 -273.589242) (xy 357.190802 -273.612356) (xy 357.36276 -273.910044) (xy 357.387652 -273.913346)
			(xy 357.413032 -273.917185) (xy 357.462414 -273.93119) (xy 357.509279 -273.952127) (xy 357.55266 -273.979564)
			(xy 357.591661 -274.012935) (xy 357.625478 -274.05155) (xy 357.653412 -274.094613) (xy 357.674886 -274.141234)
			(xy 357.689458 -274.190452) (xy 357.696826 -274.241249) (xy 357.697278 -274.266914) (xy 357.696779 -274.293601)
			(xy 357.688824 -274.34638) (xy 357.673092 -274.397383) (xy 357.649934 -274.445472) (xy 357.619867 -274.489572)
			(xy 357.583563 -274.528699) (xy 357.541833 -274.561977) (xy 357.495609 -274.588664) (xy 357.445924 -274.608164)
			(xy 357.393887 -274.620041) (xy 357.340662 -274.62403) (xy 357.287437 -274.620041) (xy 357.2354 -274.608164)
			(xy 357.185715 -274.588664) (xy 357.139491 -274.561977) (xy 357.097761 -274.528699) (xy 357.061457 -274.489572)
			(xy 357.03139 -274.445472) (xy 357.008232 -274.397383) (xy 356.9925 -274.34638) (xy 356.984545 -274.293601)
			(xy 356.984046 -274.266914) (xy 356.984403 -274.243574) (xy 356.990507 -274.197295) (xy 357.002614 -274.152213)
			(xy 357.011224 -274.130516) (xy 357.020876 -274.107148) (xy 356.848918 -273.809968) (xy 356.824026 -273.806666)
			(xy 356.798627 -273.802862) (xy 356.749207 -273.788894) (xy 356.702301 -273.767982) (xy 356.658879 -273.740558)
			(xy 356.61984 -273.70719) (xy 356.58599 -273.668567) (xy 356.558031 -273.625489) (xy 356.536539 -273.578845)
			(xy 356.521959 -273.529602) (xy 356.514593 -273.478776) (xy 356.514146 -273.453098) (xy 109.28731 -273.453098)
			(xy 109.28731 -273.453606) (xy 109.286924 -273.476808) (xy 109.280859 -273.522815) (xy 109.268884 -273.567649)
			(xy 109.260386 -273.589242) (xy 109.250734 -273.612356) (xy 109.422692 -273.910044) (xy 109.447584 -273.913346)
			(xy 109.472955 -273.917239) (xy 109.522337 -273.931235) (xy 109.569202 -273.952163) (xy 109.612584 -273.979593)
			(xy 109.651587 -274.012957) (xy 109.685405 -274.051567) (xy 109.713341 -274.094625) (xy 109.734817 -274.141242)
			(xy 109.749389 -274.190456) (xy 109.756758 -274.241251) (xy 109.75721 -274.266914) (xy 351.345246 -274.266914)
			(xy 351.345745 -274.240227) (xy 351.3537 -274.187448) (xy 351.369432 -274.136445) (xy 351.39259 -274.088356)
			(xy 351.422657 -274.044256) (xy 351.458961 -274.005129) (xy 351.500691 -273.971851) (xy 351.546915 -273.945164)
			(xy 351.5966 -273.925664) (xy 351.648637 -273.913787) (xy 351.701862 -273.909798) (xy 351.755087 -273.913787)
			(xy 351.807124 -273.925664) (xy 351.856809 -273.945164) (xy 351.903033 -273.971851) (xy 351.944763 -274.005129)
			(xy 351.981067 -274.044256) (xy 352.011134 -274.088356) (xy 352.034292 -274.136445) (xy 352.050024 -274.187448)
			(xy 352.057979 -274.240227) (xy 352.058478 -274.266914) (xy 352.058478 -274.267422) (xy 352.058092 -274.290624)
			(xy 352.052026 -274.336631) (xy 352.040052 -274.381464) (xy 352.031554 -274.403058) (xy 352.021902 -274.426172)
			(xy 352.194114 -274.72386) (xy 352.219006 -274.727162) (xy 352.244383 -274.731022) (xy 352.293765 -274.745022)
			(xy 352.340632 -274.765954) (xy 352.384014 -274.793388) (xy 352.423017 -274.826756) (xy 352.456835 -274.865369)
			(xy 352.484769 -274.908431) (xy 352.506243 -274.955051) (xy 352.520814 -275.004268) (xy 352.528181 -275.055066)
			(xy 352.528632 -275.08073) (xy 352.528133 -275.107417) (xy 352.520178 -275.160196) (xy 352.504446 -275.211199)
			(xy 352.481288 -275.259288) (xy 352.451221 -275.303388) (xy 352.414917 -275.342515) (xy 352.373187 -275.375793)
			(xy 352.326963 -275.40248) (xy 352.277278 -275.42198) (xy 352.225241 -275.433857) (xy 352.172016 -275.437846)
			(xy 352.118791 -275.433857) (xy 352.066754 -275.42198) (xy 352.017069 -275.40248) (xy 351.970845 -275.375793)
			(xy 351.929115 -275.342515) (xy 351.892811 -275.303388) (xy 351.862744 -275.259288) (xy 351.839586 -275.211199)
			(xy 351.823854 -275.160196) (xy 351.815899 -275.107417) (xy 351.8154 -275.08073) (xy 351.815758 -275.05739)
			(xy 351.821861 -275.011111) (xy 351.833967 -274.966029) (xy 351.842578 -274.944332) (xy 351.85223 -274.920964)
			(xy 351.680526 -274.623784) (xy 351.655634 -274.620482) (xy 351.630212 -274.61668) (xy 351.580727 -274.602776)
			(xy 351.533752 -274.58191) (xy 351.49026 -274.554514) (xy 351.451152 -274.521158) (xy 351.41724 -274.482531)
			(xy 351.389226 -274.439435) (xy 351.36769 -274.392763) (xy 351.353079 -274.343482) (xy 351.345696 -274.292614)
			(xy 351.345246 -274.266914) (xy 109.75721 -274.266914) (xy 109.756711 -274.293601) (xy 109.748756 -274.34638)
			(xy 109.733024 -274.397383) (xy 109.709866 -274.445472) (xy 109.679799 -274.489572) (xy 109.643495 -274.528699)
			(xy 109.601765 -274.561977) (xy 109.555541 -274.588664) (xy 109.505856 -274.608164) (xy 109.453819 -274.620041)
			(xy 109.400594 -274.62403) (xy 109.347369 -274.620041) (xy 109.295332 -274.608164) (xy 109.245647 -274.588664)
			(xy 109.199423 -274.561977) (xy 109.157693 -274.528699) (xy 109.121389 -274.489572) (xy 109.091322 -274.445472)
			(xy 109.068164 -274.397383) (xy 109.052432 -274.34638) (xy 109.044477 -274.293601) (xy 109.043978 -274.266914)
			(xy 109.044332 -274.243574) (xy 109.050438 -274.197295) (xy 109.062545 -274.152213) (xy 109.071156 -274.130516)
			(xy 109.080808 -274.107148) (xy 108.90885 -273.809968) (xy 108.883958 -273.806666) (xy 108.858563 -273.802837)
			(xy 108.809143 -273.788873) (xy 108.762237 -273.767965) (xy 108.718815 -273.740544) (xy 108.679775 -273.707179)
			(xy 108.645925 -273.668559) (xy 108.617964 -273.625483) (xy 108.596471 -273.578842) (xy 108.581891 -273.5296)
			(xy 108.574525 -273.478776) (xy 108.574078 -273.453098) (xy 2.509012 -273.453098) (xy 2.509012 -274.266914)
			(xy 103.405178 -274.266914) (xy 103.405677 -274.240227) (xy 103.413632 -274.187448) (xy 103.429364 -274.136445)
			(xy 103.452522 -274.088356) (xy 103.482589 -274.044256) (xy 103.518893 -274.005129) (xy 103.560623 -273.971851)
			(xy 103.606847 -273.945164) (xy 103.656532 -273.925664) (xy 103.708569 -273.913787) (xy 103.761794 -273.909798)
			(xy 103.815019 -273.913787) (xy 103.867056 -273.925664) (xy 103.916741 -273.945164) (xy 103.962965 -273.971851)
			(xy 104.004695 -274.005129) (xy 104.040999 -274.044256) (xy 104.071066 -274.088356) (xy 104.094224 -274.136445)
			(xy 104.109956 -274.187448) (xy 104.117911 -274.240227) (xy 104.11841 -274.266914) (xy 104.11841 -274.267422)
			(xy 104.118029 -274.290624) (xy 104.111962 -274.336631) (xy 104.099985 -274.381465) (xy 104.091486 -274.403058)
			(xy 104.081834 -274.426172) (xy 104.254046 -274.72386) (xy 104.278938 -274.727162) (xy 104.304319 -274.730997)
			(xy 104.353702 -274.745001) (xy 104.400568 -274.765937) (xy 104.44395 -274.793374) (xy 104.482952 -274.826745)
			(xy 104.516769 -274.865361) (xy 104.544703 -274.908425) (xy 104.566176 -274.955048) (xy 104.580747 -275.004266)
			(xy 104.588113 -275.055065) (xy 104.588564 -275.08073) (xy 104.588065 -275.107417) (xy 104.58011 -275.160196)
			(xy 104.564378 -275.211199) (xy 104.54122 -275.259288) (xy 104.511153 -275.303388) (xy 104.474849 -275.342515)
			(xy 104.433119 -275.375793) (xy 104.386895 -275.40248) (xy 104.33721 -275.42198) (xy 104.285173 -275.433857)
			(xy 104.231948 -275.437846) (xy 104.178723 -275.433857) (xy 104.126686 -275.42198) (xy 104.077001 -275.40248)
			(xy 104.030777 -275.375793) (xy 103.989047 -275.342515) (xy 103.952743 -275.303388) (xy 103.922676 -275.259288)
			(xy 103.899518 -275.211199) (xy 103.883786 -275.160196) (xy 103.875831 -275.107417) (xy 103.875332 -275.08073)
			(xy 103.875695 -275.05739) (xy 103.881797 -275.011112) (xy 103.893901 -274.966029) (xy 103.90251 -274.944332)
			(xy 103.912162 -274.920964) (xy 103.740458 -274.623784) (xy 103.715566 -274.620482) (xy 103.690148 -274.616655)
			(xy 103.640663 -274.602755) (xy 103.593688 -274.581893) (xy 103.550196 -274.554501) (xy 103.511087 -274.521147)
			(xy 103.477174 -274.482523) (xy 103.449159 -274.439429) (xy 103.427623 -274.392759) (xy 103.413011 -274.34348)
			(xy 103.405628 -274.292614) (xy 103.405178 -274.266914) (xy 2.509012 -274.266914) (xy 2.509012 -275.0807)
			(xy 101.996207 -275.0807) (xy 102.000185 -275.027623) (xy 102.01203 -274.975731) (xy 102.031477 -274.926185)
			(xy 102.058092 -274.880091) (xy 102.091281 -274.838478) (xy 102.130301 -274.802278) (xy 102.174281 -274.772298)
			(xy 102.222239 -274.749209) (xy 102.273102 -274.733526) (xy 102.325735 -274.725599) (xy 102.352348 -274.72513)
			(xy 102.377317 -274.725593) (xy 102.426764 -274.73258) (xy 102.474749 -274.74641) (xy 102.52033 -274.766811)
			(xy 102.562611 -274.793384) (xy 102.600763 -274.825606) (xy 102.634037 -274.862844) (xy 102.648258 -274.883372)
			(xy 102.996238 -274.883372) (xy 103.010431 -274.862821) (xy 103.043701 -274.825569) (xy 103.081853 -274.793337)
			(xy 103.124139 -274.766758) (xy 103.169727 -274.746355) (xy 103.21772 -274.732527) (xy 103.267175 -274.725549)
			(xy 103.292148 -274.72513) (xy 103.318759 -274.725571) (xy 103.371386 -274.73351) (xy 103.422242 -274.749203)
			(xy 103.470192 -274.7723) (xy 103.514164 -274.802285) (xy 103.553176 -274.838488) (xy 103.586357 -274.880101)
			(xy 103.612967 -274.926194) (xy 103.632409 -274.975738) (xy 103.644252 -275.027626) (xy 103.648229 -275.0807)
			(xy 103.644252 -275.133774) (xy 103.632409 -275.185662) (xy 103.612967 -275.235206) (xy 103.586357 -275.281299)
			(xy 103.553176 -275.322912) (xy 103.514164 -275.359115) (xy 103.470192 -275.3891) (xy 103.422242 -275.412197)
			(xy 103.371386 -275.42789) (xy 103.318759 -275.435829) (xy 103.292148 -275.43633) (xy 103.267178 -275.435888)
			(xy 103.217729 -275.4289) (xy 103.169743 -275.415067) (xy 103.124162 -275.394663) (xy 103.08188 -275.368086)
			(xy 103.043729 -275.335861) (xy 103.010458 -275.298618) (xy 102.996238 -275.278088) (xy 102.648258 -275.278088)
			(xy 102.634055 -275.298632) (xy 102.600788 -275.335885) (xy 102.562638 -275.368119) (xy 102.520354 -275.3947)
			(xy 102.474768 -275.415105) (xy 102.426775 -275.428933) (xy 102.37732 -275.435912) (xy 102.352348 -275.43633)
			(xy 102.325735 -275.435801) (xy 102.273102 -275.427874) (xy 102.222239 -275.412191) (xy 102.174281 -275.389102)
			(xy 102.130301 -275.359122) (xy 102.091281 -275.322922) (xy 102.058092 -275.281309) (xy 102.031477 -275.235215)
			(xy 102.01203 -275.185669) (xy 102.000185 -275.133777) (xy 101.996207 -275.0807) (xy 2.509012 -275.0807)
			(xy 2.509012 -276.708616) (xy 101.995478 -276.708616) (xy 101.995889 -276.682946) (xy 102.003236 -276.632135)
			(xy 102.017794 -276.582903) (xy 102.039263 -276.536268) (xy 102.067199 -276.493195) (xy 102.101024 -276.454573)
			(xy 102.140038 -276.421202) (xy 102.183435 -276.393772) (xy 102.230317 -276.372849) (xy 102.279716 -276.358867)
			(xy 102.305104 -276.355048) (xy 102.329996 -276.351746) (xy 102.501954 -276.054058) (xy 102.492302 -276.030944)
			(xy 102.483799 -276.009352) (xy 102.47182 -275.964519) (xy 102.465765 -275.918511) (xy 102.465378 -275.895308)
			(xy 102.465378 -275.8948) (xy 102.465877 -275.868113) (xy 102.473832 -275.815334) (xy 102.489564 -275.764331)
			(xy 102.512722 -275.716242) (xy 102.542789 -275.672142) (xy 102.579093 -275.633015) (xy 102.620823 -275.599737)
			(xy 102.667047 -275.57305) (xy 102.716732 -275.55355) (xy 102.768769 -275.541673) (xy 102.821994 -275.537684)
			(xy 102.875219 -275.541673) (xy 102.927256 -275.55355) (xy 102.976941 -275.57305) (xy 103.023165 -275.599737)
			(xy 103.064895 -275.633015) (xy 103.101199 -275.672142) (xy 103.131266 -275.716242) (xy 103.154424 -275.764331)
			(xy 103.170156 -275.815334) (xy 103.178111 -275.868113) (xy 103.17861 -275.8948) (xy 104.344978 -275.8948)
			(xy 104.345374 -275.86913) (xy 104.352723 -275.818318) (xy 104.367284 -275.769086) (xy 104.388755 -275.722451)
			(xy 104.416692 -275.679378) (xy 104.450518 -275.640756) (xy 104.489534 -275.607385) (xy 104.532932 -275.579955)
			(xy 104.579816 -275.559033) (xy 104.629216 -275.545051) (xy 104.654604 -275.541232) (xy 104.679496 -275.53793)
			(xy 104.851708 -275.239988) (xy 104.842056 -275.216874) (xy 104.83356 -275.195279) (xy 104.821579 -275.150448)
			(xy 104.815521 -275.10444) (xy 104.815132 -275.081238) (xy 104.815132 -275.08073) (xy 104.815631 -275.054043)
			(xy 104.823586 -275.001264) (xy 104.839318 -274.950261) (xy 104.862476 -274.902172) (xy 104.892543 -274.858072)
			(xy 104.928847 -274.818945) (xy 104.970577 -274.785667) (xy 105.016801 -274.75898) (xy 105.066486 -274.73948)
			(xy 105.118523 -274.727603) (xy 105.171748 -274.723614) (xy 105.224973 -274.727603) (xy 105.27701 -274.73948)
			(xy 105.326695 -274.75898) (xy 105.372919 -274.785667) (xy 105.414649 -274.818945) (xy 105.450953 -274.858072)
			(xy 105.48102 -274.902172) (xy 105.504178 -274.950261) (xy 105.51991 -275.001264) (xy 105.527865 -275.054043)
			(xy 105.528364 -275.08073) (xy 107.634532 -275.08073) (xy 107.635031 -275.054043) (xy 107.642986 -275.001264)
			(xy 107.658718 -274.950261) (xy 107.681876 -274.902172) (xy 107.711943 -274.858072) (xy 107.748247 -274.818945)
			(xy 107.789977 -274.785667) (xy 107.836201 -274.75898) (xy 107.885886 -274.73948) (xy 107.937923 -274.727603)
			(xy 107.991148 -274.723614) (xy 108.044373 -274.727603) (xy 108.09641 -274.73948) (xy 108.146095 -274.75898)
			(xy 108.192319 -274.785667) (xy 108.234049 -274.818945) (xy 108.270353 -274.858072) (xy 108.30042 -274.902172)
			(xy 108.323578 -274.950261) (xy 108.33931 -275.001264) (xy 108.347265 -275.054043) (xy 108.347763 -275.0807)
			(xy 349.936307 -275.0807) (xy 349.940284 -275.027626) (xy 349.952128 -274.975737) (xy 349.971573 -274.926193)
			(xy 349.998186 -274.880101) (xy 350.031371 -274.83849) (xy 350.070387 -274.80229) (xy 350.114363 -274.772309)
			(xy 350.162316 -274.749218) (xy 350.213175 -274.733532) (xy 350.265804 -274.725602) (xy 350.292416 -274.72513)
			(xy 350.317387 -274.725541) (xy 350.366836 -274.732537) (xy 350.414822 -274.746376) (xy 350.460403 -274.766787)
			(xy 350.502684 -274.793367) (xy 350.540834 -274.825596) (xy 350.574106 -274.862841) (xy 350.588326 -274.883372)
			(xy 350.936306 -274.883372) (xy 350.95052 -274.862836) (xy 350.983786 -274.825584) (xy 351.021935 -274.793351)
			(xy 351.064217 -274.76677) (xy 351.109801 -274.746364) (xy 351.157792 -274.732533) (xy 351.207244 -274.725551)
			(xy 351.232216 -274.72513) (xy 351.258829 -274.725568) (xy 351.311459 -274.733503) (xy 351.36232 -274.749194)
			(xy 351.410274 -274.772289) (xy 351.45425 -274.802273) (xy 351.493266 -274.838477) (xy 351.526451 -274.880091)
			(xy 351.553063 -274.926186) (xy 351.572508 -274.975732) (xy 351.584351 -275.027623) (xy 351.588329 -275.0807)
			(xy 351.584351 -275.133777) (xy 351.572508 -275.185668) (xy 351.553063 -275.235214) (xy 351.526451 -275.281309)
			(xy 351.493266 -275.322923) (xy 351.45425 -275.359127) (xy 351.410274 -275.389111) (xy 351.36232 -275.412206)
			(xy 351.311459 -275.427897) (xy 351.258829 -275.435832) (xy 351.232216 -275.43633) (xy 351.207245 -275.435912)
			(xy 351.157795 -275.428919) (xy 351.109809 -275.415083) (xy 351.064227 -275.394674) (xy 351.021946 -275.368094)
			(xy 350.983796 -275.335865) (xy 350.950525 -275.298619) (xy 350.936306 -275.278088) (xy 350.588326 -275.278088)
			(xy 350.574079 -275.2986) (xy 350.54082 -275.335855) (xy 350.502677 -275.368091) (xy 350.460401 -275.394675)
			(xy 350.414821 -275.415085) (xy 350.366835 -275.42892) (xy 350.317386 -275.435907) (xy 350.292416 -275.43633)
			(xy 350.265804 -275.435798) (xy 350.213175 -275.427868) (xy 350.162316 -275.412182) (xy 350.114363 -275.389091)
			(xy 350.070387 -275.35911) (xy 350.031371 -275.32291) (xy 349.998186 -275.281299) (xy 349.971573 -275.235207)
			(xy 349.952128 -275.185663) (xy 349.940284 -275.133774) (xy 349.936307 -275.0807) (xy 108.347763 -275.0807)
			(xy 108.347764 -275.08073) (xy 108.347389 -275.104069) (xy 108.341292 -275.150348) (xy 108.329193 -275.195431)
			(xy 108.320586 -275.217128) (xy 108.310934 -275.240496) (xy 108.483146 -275.53793) (xy 108.507784 -275.541232)
			(xy 108.533184 -275.54503) (xy 108.582604 -275.558999) (xy 108.62951 -275.579913) (xy 108.672931 -275.607337)
			(xy 108.71197 -275.640706) (xy 108.745819 -275.679329) (xy 108.773779 -275.722408) (xy 108.795271 -275.769052)
			(xy 108.809851 -275.818296) (xy 108.817217 -275.869122) (xy 108.817664 -275.8948) (xy 108.817165 -275.921487)
			(xy 108.80921 -275.974266) (xy 108.793478 -276.025269) (xy 108.77032 -276.073358) (xy 108.740253 -276.117458)
			(xy 108.703949 -276.156585) (xy 108.662219 -276.189863) (xy 108.615995 -276.21655) (xy 108.56631 -276.23605)
			(xy 108.514273 -276.247927) (xy 108.461048 -276.251916) (xy 108.407823 -276.247927) (xy 108.355786 -276.23605)
			(xy 108.306101 -276.21655) (xy 108.259877 -276.189863) (xy 108.218147 -276.156585) (xy 108.181843 -276.117458)
			(xy 108.151776 -276.073358) (xy 108.128618 -276.025269) (xy 108.112886 -275.974266) (xy 108.104931 -275.921487)
			(xy 108.104432 -275.8948) (xy 108.104785 -275.87146) (xy 108.110891 -275.825181) (xy 108.122999 -275.780099)
			(xy 108.13161 -275.758402) (xy 108.141262 -275.735034) (xy 107.96905 -275.4376) (xy 107.944412 -275.434298)
			(xy 107.919017 -275.430474) (xy 107.869599 -275.416506) (xy 107.822695 -275.395594) (xy 107.779275 -275.368172)
			(xy 107.740237 -275.334806) (xy 107.706387 -275.296186) (xy 107.678427 -275.253111) (xy 107.656933 -275.206471)
			(xy 107.642351 -275.15723) (xy 107.634981 -275.106407) (xy 107.634532 -275.08073) (xy 105.528364 -275.08073)
			(xy 105.527862 -275.106429) (xy 105.520479 -275.157293) (xy 105.505871 -275.20657) (xy 105.484339 -275.25324)
			(xy 105.456331 -275.296335) (xy 105.422426 -275.334963) (xy 105.383327 -275.368324) (xy 105.339843 -275.395726)
			(xy 105.292876 -275.416601) (xy 105.243399 -275.430518) (xy 105.217976 -275.434298) (xy 105.193084 -275.4376)
			(xy 105.02138 -275.735034) (xy 105.031032 -275.758402) (xy 105.039597 -275.780114) (xy 105.051685 -275.825194)
			(xy 105.057807 -275.871464) (xy 105.05821 -275.8948) (xy 106.225101 -275.8948) (xy 106.229079 -275.841727)
			(xy 106.240922 -275.789839) (xy 106.260366 -275.740296) (xy 106.286976 -275.694204) (xy 106.320159 -275.652594)
			(xy 106.359174 -275.616393) (xy 106.403147 -275.586412) (xy 106.451098 -275.563319) (xy 106.501956 -275.547631)
			(xy 106.554583 -275.539698) (xy 106.581194 -275.5392) (xy 106.606141 -275.539565) (xy 106.655546 -275.54654)
			(xy 106.70349 -275.560353) (xy 106.749032 -275.580733) (xy 106.791278 -275.60728) (xy 106.829397 -275.639472)
			(xy 106.862642 -275.676678) (xy 106.87685 -275.697188) (xy 107.225338 -275.697188) (xy 107.239534 -275.676673)
			(xy 107.27279 -275.639483) (xy 107.310916 -275.607305) (xy 107.353165 -275.58077) (xy 107.398707 -275.5604)
			(xy 107.446648 -275.546593) (xy 107.496049 -275.539621) (xy 107.520994 -275.5392) (xy 107.547607 -275.539672)
			(xy 107.60024 -275.547605) (xy 107.651102 -275.563293) (xy 107.699058 -275.586386) (xy 107.743036 -275.61637)
			(xy 107.782055 -275.652573) (xy 107.815241 -275.694187) (xy 107.841855 -275.740282) (xy 107.861301 -275.78983)
			(xy 107.873145 -275.841722) (xy 107.877123 -275.8948) (xy 107.873145 -275.947878) (xy 107.861301 -275.99977)
			(xy 107.841855 -276.049318) (xy 107.815241 -276.095413) (xy 107.782055 -276.137027) (xy 107.743036 -276.17323)
			(xy 107.699058 -276.203214) (xy 107.651102 -276.226307) (xy 107.60024 -276.241995) (xy 107.547607 -276.249928)
			(xy 107.520994 -276.2504) (xy 107.496049 -276.249968) (xy 107.446648 -276.243006) (xy 107.398705 -276.229204)
			(xy 107.353163 -276.208835) (xy 107.310916 -276.182298) (xy 107.272795 -276.150115) (xy 107.239548 -276.112918)
			(xy 107.225338 -276.092412) (xy 106.87685 -276.092412) (xy 106.862661 -276.112933) (xy 106.829404 -276.150123)
			(xy 106.791277 -276.1823) (xy 106.749027 -276.208834) (xy 106.703484 -276.229204) (xy 106.655541 -276.243009)
			(xy 106.606139 -276.24998) (xy 106.581194 -276.2504) (xy 106.554583 -276.249902) (xy 106.501956 -276.241969)
			(xy 106.451098 -276.226281) (xy 106.403147 -276.203188) (xy 106.359174 -276.173207) (xy 106.320159 -276.137006)
			(xy 106.286976 -276.095396) (xy 106.260366 -276.049304) (xy 106.240922 -275.999761) (xy 106.229079 -275.947873)
			(xy 106.225101 -275.8948) (xy 105.05821 -275.8948) (xy 105.057711 -275.921487) (xy 105.049756 -275.974266)
			(xy 105.034024 -276.025269) (xy 105.010866 -276.073358) (xy 104.980799 -276.117458) (xy 104.944495 -276.156585)
			(xy 104.902765 -276.189863) (xy 104.856541 -276.21655) (xy 104.806856 -276.23605) (xy 104.754819 -276.247927)
			(xy 104.701594 -276.251916) (xy 104.648369 -276.247927) (xy 104.596332 -276.23605) (xy 104.546647 -276.21655)
			(xy 104.500423 -276.189863) (xy 104.458693 -276.156585) (xy 104.422389 -276.117458) (xy 104.392322 -276.073358)
			(xy 104.369164 -276.025269) (xy 104.353432 -275.974266) (xy 104.345477 -275.921487) (xy 104.344978 -275.8948)
			(xy 103.17861 -275.8948) (xy 103.178103 -275.920477) (xy 103.17075 -275.971301) (xy 103.156181 -276.020545)
			(xy 103.134698 -276.067189) (xy 103.106746 -276.110268) (xy 103.072902 -276.148892) (xy 103.033867 -276.182261)
			(xy 102.990448 -276.209684) (xy 102.943545 -276.230594) (xy 102.894127 -276.244559) (xy 102.86873 -276.248368)
			(xy 102.843838 -276.25167) (xy 102.67188 -276.54885) (xy 102.681532 -276.572218) (xy 102.690102 -276.593928)
			(xy 102.702188 -276.639009) (xy 102.708308 -276.68528) (xy 102.70871 -276.708616) (xy 102.935532 -276.708616)
			(xy 102.936031 -276.681929) (xy 102.943986 -276.62915) (xy 102.959718 -276.578147) (xy 102.982876 -276.530058)
			(xy 103.012943 -276.485958) (xy 103.049247 -276.446831) (xy 103.090977 -276.413553) (xy 103.137201 -276.386866)
			(xy 103.186886 -276.367366) (xy 103.238923 -276.355489) (xy 103.292148 -276.3515) (xy 103.345373 -276.355489)
			(xy 103.39741 -276.367366) (xy 103.447095 -276.386866) (xy 103.493319 -276.413553) (xy 103.535049 -276.446831)
			(xy 103.571353 -276.485958) (xy 103.60142 -276.530058) (xy 103.624578 -276.578147) (xy 103.64031 -276.62915)
			(xy 103.648265 -276.681929) (xy 103.648764 -276.7086) (xy 103.875793 -276.7086) (xy 103.879771 -276.65552)
			(xy 103.891617 -276.603627) (xy 103.911065 -276.554079) (xy 103.937681 -276.507983) (xy 103.970871 -276.466369)
			(xy 104.009892 -276.430167) (xy 104.053874 -276.400186) (xy 104.101834 -276.377096) (xy 104.152699 -276.361412)
			(xy 104.205334 -276.353485) (xy 104.231948 -276.353016) (xy 104.256892 -276.353453) (xy 104.306292 -276.360419)
			(xy 104.354233 -276.374223) (xy 104.399774 -276.394592) (xy 104.44202 -276.421127) (xy 104.480142 -276.453307)
			(xy 104.513392 -276.4905) (xy 104.527604 -276.511004) (xy 104.876092 -276.511004) (xy 104.890323 -276.490514)
			(xy 104.923572 -276.453323) (xy 104.961692 -276.421142) (xy 105.003935 -276.394605) (xy 105.049471 -276.37423)
			(xy 105.097408 -276.360418) (xy 105.146805 -276.35344) (xy 105.171748 -276.353016) (xy 105.198358 -276.353485)
			(xy 105.250983 -276.361423) (xy 105.301837 -276.377116) (xy 105.349785 -276.400212) (xy 105.393755 -276.430196)
			(xy 105.432766 -276.466397) (xy 105.465946 -276.508009) (xy 105.492554 -276.5541) (xy 105.511996 -276.603642)
			(xy 105.523838 -276.655528) (xy 105.527815 -276.7086) (xy 105.523838 -276.761672) (xy 105.511996 -276.813558)
			(xy 105.492554 -276.8631) (xy 105.465946 -276.909191) (xy 105.432766 -276.950803) (xy 105.393755 -276.987004)
			(xy 105.349785 -277.016988) (xy 105.301837 -277.040084) (xy 105.250983 -277.055777) (xy 105.198358 -277.063715)
			(xy 105.171748 -277.064216) (xy 105.146802 -277.063812) (xy 105.0974 -277.056844) (xy 105.049457 -277.043037)
			(xy 105.003915 -277.022663) (xy 104.961669 -276.996122) (xy 104.923548 -276.963935) (xy 104.890302 -276.926735)
			(xy 104.876092 -276.906228) (xy 104.527604 -276.906228) (xy 104.513386 -276.926727) (xy 104.480133 -276.963917)
			(xy 104.44201 -276.996095) (xy 104.399766 -277.022631) (xy 104.354227 -277.043005) (xy 104.306289 -277.056815)
			(xy 104.256892 -277.063793) (xy 104.231948 -277.064216) (xy 104.205334 -277.063715) (xy 104.152699 -277.055788)
			(xy 104.101834 -277.040104) (xy 104.053874 -277.017014) (xy 104.009892 -276.987033) (xy 103.970871 -276.950831)
			(xy 103.937681 -276.909217) (xy 103.911065 -276.863121) (xy 103.891617 -276.813573) (xy 103.879771 -276.76168)
			(xy 103.875793 -276.7086) (xy 103.648764 -276.7086) (xy 103.648764 -276.708616) (xy 103.648384 -276.731955)
			(xy 103.642289 -276.778233) (xy 103.630192 -276.823316) (xy 103.621586 -276.845014) (xy 103.611934 -276.868382)
			(xy 103.783892 -277.165562) (xy 103.808784 -277.168864) (xy 103.834158 -277.17274) (xy 103.883541 -277.186736)
			(xy 103.930408 -277.207666) (xy 103.973791 -277.235098) (xy 104.012794 -277.268464) (xy 104.046612 -277.307076)
			(xy 104.074547 -277.350136) (xy 104.096022 -277.396755) (xy 104.110592 -277.445972) (xy 104.117959 -277.496768)
			(xy 104.11841 -277.522432) (xy 106.224578 -277.522432) (xy 106.225004 -277.496763) (xy 106.232348 -277.445952)
			(xy 106.246905 -277.396721) (xy 106.268372 -277.350086) (xy 106.296306 -277.307012) (xy 106.330129 -277.26839)
			(xy 106.369142 -277.235019) (xy 106.412537 -277.207589) (xy 106.459419 -277.186666) (xy 106.508817 -277.172683)
			(xy 106.534204 -277.168864) (xy 106.559096 -277.165562) (xy 106.731308 -276.867874) (xy 106.721656 -276.84476)
			(xy 106.713156 -276.823167) (xy 106.701176 -276.778335) (xy 106.69512 -276.732326) (xy 106.694732 -276.709124)
			(xy 106.694732 -276.708616) (xy 106.695231 -276.681929) (xy 106.703186 -276.62915) (xy 106.718918 -276.578147)
			(xy 106.742076 -276.530058) (xy 106.772143 -276.485958) (xy 106.808447 -276.446831) (xy 106.850177 -276.413553)
			(xy 106.896401 -276.386866) (xy 106.946086 -276.367366) (xy 106.998123 -276.355489) (xy 107.051348 -276.3515)
			(xy 107.104573 -276.355489) (xy 107.15661 -276.367366) (xy 107.206295 -276.386866) (xy 107.252519 -276.413553)
			(xy 107.294249 -276.446831) (xy 107.330553 -276.485958) (xy 107.36062 -276.530058) (xy 107.383778 -276.578147)
			(xy 107.39951 -276.62915) (xy 107.407465 -276.681929) (xy 107.407964 -276.708616) (xy 108.574078 -276.708616)
			(xy 108.574489 -276.682946) (xy 108.581836 -276.632135) (xy 108.596394 -276.582903) (xy 108.617863 -276.536268)
			(xy 108.645799 -276.493195) (xy 108.679624 -276.454573) (xy 108.718638 -276.421202) (xy 108.762035 -276.393772)
			(xy 108.808917 -276.372849) (xy 108.858316 -276.358867) (xy 108.883704 -276.355048) (xy 108.908596 -276.351746)
			(xy 109.080554 -276.054566) (xy 109.070902 -276.031198) (xy 109.062339 -276.009486) (xy 109.05025 -275.964406)
			(xy 109.044128 -275.918136) (xy 109.043724 -275.8948) (xy 109.044223 -275.868113) (xy 109.052178 -275.815334)
			(xy 109.06791 -275.764331) (xy 109.091068 -275.716242) (xy 109.121135 -275.672142) (xy 109.157439 -275.633015)
			(xy 109.199169 -275.599737) (xy 109.245393 -275.57305) (xy 109.295078 -275.55355) (xy 109.347115 -275.541673)
			(xy 109.40034 -275.537684) (xy 109.453565 -275.541673) (xy 109.505602 -275.55355) (xy 109.555287 -275.57305)
			(xy 109.601511 -275.599737) (xy 109.643241 -275.633015) (xy 109.679545 -275.672142) (xy 109.709612 -275.716242)
			(xy 109.73277 -275.764331) (xy 109.748502 -275.815334) (xy 109.756457 -275.868113) (xy 109.756956 -275.8948)
			(xy 109.75653 -275.920469) (xy 109.749182 -275.971278) (xy 109.734623 -276.020508) (xy 109.713155 -276.067141)
			(xy 109.685221 -276.110213) (xy 109.651398 -276.148834) (xy 109.612386 -276.182205) (xy 109.568992 -276.209637)
			(xy 109.522113 -276.230561) (xy 109.472717 -276.244547) (xy 109.44733 -276.248368) (xy 109.422438 -276.25167)
			(xy 109.25048 -276.54885) (xy 109.260132 -276.572218) (xy 109.268702 -276.593928) (xy 109.280788 -276.639009)
			(xy 109.286908 -276.68528) (xy 109.28731 -276.708616) (xy 349.935546 -276.708616) (xy 349.935985 -276.682947)
			(xy 349.943331 -276.632139) (xy 349.957888 -276.582909) (xy 349.979354 -276.536276) (xy 350.007287 -276.493204)
			(xy 350.041108 -276.454583) (xy 350.080119 -276.421211) (xy 350.123512 -276.39378) (xy 350.170391 -276.372855)
			(xy 350.219786 -276.358869) (xy 350.245172 -276.355048) (xy 350.270064 -276.351746) (xy 350.442022 -276.054058)
			(xy 350.43237 -276.030944) (xy 350.423866 -276.009353) (xy 350.411887 -275.96452) (xy 350.405833 -275.918511)
			(xy 350.405446 -275.895308) (xy 350.405446 -275.8948) (xy 350.405945 -275.868113) (xy 350.4139 -275.815334)
			(xy 350.429632 -275.764331) (xy 350.45279 -275.716242) (xy 350.482857 -275.672142) (xy 350.519161 -275.633015)
			(xy 350.560891 -275.599737) (xy 350.607115 -275.57305) (xy 350.6568 -275.55355) (xy 350.708837 -275.541673)
			(xy 350.762062 -275.537684) (xy 350.815287 -275.541673) (xy 350.867324 -275.55355) (xy 350.917009 -275.57305)
			(xy 350.963233 -275.599737) (xy 351.004963 -275.633015) (xy 351.041267 -275.672142) (xy 351.071334 -275.716242)
			(xy 351.094492 -275.764331) (xy 351.110224 -275.815334) (xy 351.118179 -275.868113) (xy 351.118678 -275.8948)
			(xy 352.285046 -275.8948) (xy 352.28547 -275.869131) (xy 352.292818 -275.818322) (xy 352.307377 -275.769092)
			(xy 352.328846 -275.722459) (xy 352.35678 -275.679386) (xy 352.390603 -275.640765) (xy 352.429615 -275.607394)
			(xy 352.473009 -275.579963) (xy 352.519889 -275.559038) (xy 352.569285 -275.545053) (xy 352.594672 -275.541232)
			(xy 352.619564 -275.53793) (xy 352.791776 -275.239988) (xy 352.782124 -275.216874) (xy 352.773627 -275.19528)
			(xy 352.761646 -275.150448) (xy 352.755589 -275.10444) (xy 352.7552 -275.081238) (xy 352.7552 -275.08073)
			(xy 352.755699 -275.054043) (xy 352.763654 -275.001264) (xy 352.779386 -274.950261) (xy 352.802544 -274.902172)
			(xy 352.832611 -274.858072) (xy 352.868915 -274.818945) (xy 352.910645 -274.785667) (xy 352.956869 -274.75898)
			(xy 353.006554 -274.73948) (xy 353.058591 -274.727603) (xy 353.111816 -274.723614) (xy 353.165041 -274.727603)
			(xy 353.217078 -274.73948) (xy 353.266763 -274.75898) (xy 353.312987 -274.785667) (xy 353.354717 -274.818945)
			(xy 353.391021 -274.858072) (xy 353.421088 -274.902172) (xy 353.444246 -274.950261) (xy 353.459978 -275.001264)
			(xy 353.467933 -275.054043) (xy 353.468432 -275.08073) (xy 355.5746 -275.08073) (xy 355.575099 -275.054043)
			(xy 355.583054 -275.001264) (xy 355.598786 -274.950261) (xy 355.621944 -274.902172) (xy 355.652011 -274.858072)
			(xy 355.688315 -274.818945) (xy 355.730045 -274.785667) (xy 355.776269 -274.75898) (xy 355.825954 -274.73948)
			(xy 355.877991 -274.727603) (xy 355.931216 -274.723614) (xy 355.984441 -274.727603) (xy 356.036478 -274.73948)
			(xy 356.086163 -274.75898) (xy 356.132387 -274.785667) (xy 356.174117 -274.818945) (xy 356.210421 -274.858072)
			(xy 356.240488 -274.902172) (xy 356.263646 -274.950261) (xy 356.279378 -275.001264) (xy 356.287333 -275.054043)
			(xy 356.287832 -275.08073) (xy 356.287459 -275.104069) (xy 356.281361 -275.150348) (xy 356.269261 -275.195431)
			(xy 356.260654 -275.217128) (xy 356.251002 -275.240496) (xy 356.423214 -275.53793) (xy 356.447852 -275.541232)
			(xy 356.473248 -275.545055) (xy 356.522668 -275.55902) (xy 356.569574 -275.57993) (xy 356.612996 -275.607351)
			(xy 356.652035 -275.640717) (xy 356.685885 -275.679337) (xy 356.713846 -275.722414) (xy 356.735338 -275.769056)
			(xy 356.749918 -275.818298) (xy 356.757285 -275.869122) (xy 356.757732 -275.8948) (xy 356.757233 -275.921487)
			(xy 356.749278 -275.974266) (xy 356.733546 -276.025269) (xy 356.710388 -276.073358) (xy 356.680321 -276.117458)
			(xy 356.644017 -276.156585) (xy 356.602287 -276.189863) (xy 356.556063 -276.21655) (xy 356.506378 -276.23605)
			(xy 356.454341 -276.247927) (xy 356.401116 -276.251916) (xy 356.347891 -276.247927) (xy 356.295854 -276.23605)
			(xy 356.246169 -276.21655) (xy 356.199945 -276.189863) (xy 356.158215 -276.156585) (xy 356.121911 -276.117458)
			(xy 356.091844 -276.073358) (xy 356.068686 -276.025269) (xy 356.052954 -275.974266) (xy 356.044999 -275.921487)
			(xy 356.0445 -275.8948) (xy 356.044848 -275.87146) (xy 356.050956 -275.825181) (xy 356.063066 -275.780098)
			(xy 356.071678 -275.758402) (xy 356.08133 -275.735034) (xy 355.909118 -275.4376) (xy 355.88448 -275.434298)
			(xy 355.859081 -275.4305) (xy 355.809662 -275.416527) (xy 355.762759 -275.395611) (xy 355.719339 -275.368186)
			(xy 355.680302 -275.334817) (xy 355.646453 -275.296194) (xy 355.618493 -275.253116) (xy 355.597 -275.206474)
			(xy 355.582419 -275.157232) (xy 355.575049 -275.106408) (xy 355.5746 -275.08073) (xy 353.468432 -275.08073)
			(xy 353.467958 -275.10643) (xy 353.460574 -275.157297) (xy 353.445964 -275.206576) (xy 353.42443 -275.253248)
			(xy 353.396419 -275.296344) (xy 353.362511 -275.334973) (xy 353.323408 -275.368333) (xy 353.27992 -275.395733)
			(xy 353.23295 -275.416607) (xy 353.183469 -275.43052) (xy 353.158044 -275.434298) (xy 353.133152 -275.4376)
			(xy 352.961448 -275.735034) (xy 352.9711 -275.758402) (xy 352.979663 -275.780114) (xy 352.991752 -275.825194)
			(xy 352.997874 -275.871464) (xy 352.998278 -275.8948) (xy 354.165201 -275.8948) (xy 354.169178 -275.84173)
			(xy 354.18102 -275.789845) (xy 354.200462 -275.740304) (xy 354.227069 -275.694215) (xy 354.260249 -275.652605)
			(xy 354.299259 -275.616405) (xy 354.343229 -275.586422) (xy 354.391176 -275.563328) (xy 354.442029 -275.547637)
			(xy 354.494653 -275.5397) (xy 354.521262 -275.5392) (xy 354.546208 -275.539589) (xy 354.595612 -275.54656)
			(xy 354.643555 -275.560368) (xy 354.689098 -275.580745) (xy 354.731344 -275.607288) (xy 354.769464 -275.639477)
			(xy 354.802709 -275.676679) (xy 354.816918 -275.697188) (xy 355.165406 -275.697188) (xy 355.179623 -275.676688)
			(xy 355.212875 -275.639497) (xy 355.250998 -275.607318) (xy 355.293243 -275.580782) (xy 355.338781 -275.560409)
			(xy 355.38672 -275.546599) (xy 355.436118 -275.539623) (xy 355.461062 -275.5392) (xy 355.487677 -275.53967)
			(xy 355.540313 -275.547598) (xy 355.591179 -275.563284) (xy 355.63914 -275.586376) (xy 355.683122 -275.616358)
			(xy 355.722144 -275.652562) (xy 355.755334 -275.694177) (xy 355.781951 -275.740274) (xy 355.801399 -275.789824)
			(xy 355.813245 -275.841719) (xy 355.817223 -275.8948) (xy 355.813245 -275.947881) (xy 355.801399 -275.999776)
			(xy 355.781951 -276.049326) (xy 355.755334 -276.095423) (xy 355.722144 -276.137038) (xy 355.683122 -276.173242)
			(xy 355.63914 -276.203224) (xy 355.591179 -276.226316) (xy 355.540313 -276.242002) (xy 355.487677 -276.24993)
			(xy 355.461062 -276.2504) (xy 355.436116 -276.249992) (xy 355.386714 -276.243025) (xy 355.33877 -276.22922)
			(xy 355.293228 -276.208847) (xy 355.250982 -276.182306) (xy 355.212861 -276.15012) (xy 355.179615 -276.11292)
			(xy 355.165406 -276.092412) (xy 354.816918 -276.092412) (xy 354.802686 -276.112901) (xy 354.769436 -276.150092)
			(xy 354.731316 -276.182271) (xy 354.689074 -276.208809) (xy 354.643538 -276.229184) (xy 354.595601 -276.242997)
			(xy 354.546205 -276.249976) (xy 354.521262 -276.2504) (xy 354.494653 -276.2499) (xy 354.442029 -276.241963)
			(xy 354.391176 -276.226272) (xy 354.343229 -276.203178) (xy 354.299259 -276.173195) (xy 354.260249 -276.136995)
			(xy 354.227069 -276.095385) (xy 354.200462 -276.049296) (xy 354.18102 -275.999755) (xy 354.169178 -275.94787)
			(xy 354.165201 -275.8948) (xy 352.998278 -275.8948) (xy 352.997779 -275.921487) (xy 352.989824 -275.974266)
			(xy 352.974092 -276.025269) (xy 352.950934 -276.073358) (xy 352.920867 -276.117458) (xy 352.884563 -276.156585)
			(xy 352.842833 -276.189863) (xy 352.796609 -276.21655) (xy 352.746924 -276.23605) (xy 352.694887 -276.247927)
			(xy 352.641662 -276.251916) (xy 352.588437 -276.247927) (xy 352.5364 -276.23605) (xy 352.486715 -276.21655)
			(xy 352.440491 -276.189863) (xy 352.398761 -276.156585) (xy 352.362457 -276.117458) (xy 352.33239 -276.073358)
			(xy 352.309232 -276.025269) (xy 352.2935 -275.974266) (xy 352.285545 -275.921487) (xy 352.285046 -275.8948)
			(xy 351.118678 -275.8948) (xy 351.118199 -275.920478) (xy 351.110845 -275.971305) (xy 351.096274 -276.020551)
			(xy 351.074789 -276.067197) (xy 351.046834 -276.110277) (xy 351.012986 -276.148901) (xy 350.973948 -276.182269)
			(xy 350.930525 -276.209691) (xy 350.883618 -276.230599) (xy 350.834196 -276.244561) (xy 350.808798 -276.248368)
			(xy 350.783906 -276.25167) (xy 350.611948 -276.54885) (xy 350.6216 -276.572218) (xy 350.630167 -276.593929)
			(xy 350.642255 -276.63901) (xy 350.648375 -276.68528) (xy 350.648778 -276.708616) (xy 350.8756 -276.708616)
			(xy 350.876099 -276.681929) (xy 350.884054 -276.62915) (xy 350.899786 -276.578147) (xy 350.922944 -276.530058)
			(xy 350.953011 -276.485958) (xy 350.989315 -276.446831) (xy 351.031045 -276.413553) (xy 351.077269 -276.386866)
			(xy 351.126954 -276.367366) (xy 351.178991 -276.355489) (xy 351.232216 -276.3515) (xy 351.285441 -276.355489)
			(xy 351.337478 -276.367366) (xy 351.387163 -276.386866) (xy 351.433387 -276.413553) (xy 351.475117 -276.446831)
			(xy 351.511421 -276.485958) (xy 351.541488 -276.530058) (xy 351.564646 -276.578147) (xy 351.580378 -276.62915)
			(xy 351.588333 -276.681929) (xy 351.588832 -276.7086) (xy 351.815893 -276.7086) (xy 351.819871 -276.655523)
			(xy 351.831715 -276.603633) (xy 351.851161 -276.554087) (xy 351.877774 -276.507993) (xy 351.91096 -276.46638)
			(xy 351.949978 -276.430179) (xy 351.993956 -276.400197) (xy 352.041911 -276.377105) (xy 352.092772 -276.361418)
			(xy 352.145403 -276.353488) (xy 352.172016 -276.353016) (xy 352.19696 -276.353477) (xy 352.246358 -276.360439)
			(xy 352.294298 -276.374239) (xy 352.339839 -276.394604) (xy 352.382086 -276.421135) (xy 352.420209 -276.453312)
			(xy 352.453459 -276.490502) (xy 352.467672 -276.511004) (xy 352.81616 -276.511004) (xy 352.830347 -276.490482)
			(xy 352.863604 -276.453292) (xy 352.901732 -276.421114) (xy 352.943982 -276.39458) (xy 352.989525 -276.37421)
			(xy 353.037468 -276.360405) (xy 353.08687 -276.353435) (xy 353.111816 -276.353016) (xy 353.138428 -276.353482)
			(xy 353.191056 -276.361417) (xy 353.241915 -276.377107) (xy 353.289867 -276.400201) (xy 353.333841 -276.430184)
			(xy 353.372856 -276.466386) (xy 353.406039 -276.507999) (xy 353.43265 -276.554092) (xy 353.452094 -276.603636)
			(xy 353.463937 -276.655525) (xy 353.467915 -276.7086) (xy 353.463937 -276.761675) (xy 353.452094 -276.813564)
			(xy 353.43265 -276.863108) (xy 353.406039 -276.909201) (xy 353.372856 -276.950814) (xy 353.333841 -276.987016)
			(xy 353.289867 -277.016999) (xy 353.241915 -277.040093) (xy 353.191056 -277.055783) (xy 353.138428 -277.063718)
			(xy 353.111816 -277.064216) (xy 353.086869 -277.063836) (xy 353.037466 -277.056863) (xy 352.989522 -277.043052)
			(xy 352.94398 -277.022674) (xy 352.901735 -276.99613) (xy 352.863615 -276.96394) (xy 352.830369 -276.926737)
			(xy 352.81616 -276.906228) (xy 352.467672 -276.906228) (xy 352.453474 -276.926742) (xy 352.420218 -276.963931)
			(xy 352.382092 -276.996109) (xy 352.339844 -277.022643) (xy 352.294302 -277.043014) (xy 352.246361 -277.056821)
			(xy 352.196961 -277.063795) (xy 352.172016 -277.064216) (xy 352.145403 -277.063712) (xy 352.092772 -277.055782)
			(xy 352.041911 -277.040095) (xy 351.993956 -277.017003) (xy 351.949978 -276.987021) (xy 351.91096 -276.95082)
			(xy 351.877774 -276.909207) (xy 351.851161 -276.863113) (xy 351.831715 -276.813567) (xy 351.819871 -276.761677)
			(xy 351.815893 -276.7086) (xy 351.588832 -276.7086) (xy 351.588832 -276.708616) (xy 351.588455 -276.731955)
			(xy 351.582359 -276.778234) (xy 351.570261 -276.823317) (xy 351.561654 -276.845014) (xy 351.552002 -276.868382)
			(xy 351.72396 -277.165562) (xy 351.748852 -277.168864) (xy 351.774235 -277.172686) (xy 351.823618 -277.186692)
			(xy 351.870484 -277.20763) (xy 351.913866 -277.235069) (xy 351.952868 -277.268441) (xy 351.986685 -277.307059)
			(xy 352.014618 -277.350124) (xy 352.036091 -277.396747) (xy 352.050661 -277.445967) (xy 352.058027 -277.496767)
			(xy 352.058478 -277.522432) (xy 354.164646 -277.522432) (xy 354.1651 -277.496764) (xy 354.172443 -277.445956)
			(xy 354.186998 -277.396727) (xy 354.208463 -277.350094) (xy 354.236394 -277.307021) (xy 354.270213 -277.2684)
			(xy 354.309222 -277.235028) (xy 354.352614 -277.207596) (xy 354.399492 -277.186671) (xy 354.448886 -277.172685)
			(xy 354.474272 -277.168864) (xy 354.499164 -277.165562) (xy 354.671376 -276.867874) (xy 354.661724 -276.84476)
			(xy 354.653222 -276.823168) (xy 354.641244 -276.778335) (xy 354.635188 -276.732326) (xy 354.6348 -276.709124)
			(xy 354.6348 -276.708616) (xy 354.635299 -276.681929) (xy 354.643254 -276.62915) (xy 354.658986 -276.578147)
			(xy 354.682144 -276.530058) (xy 354.712211 -276.485958) (xy 354.748515 -276.446831) (xy 354.790245 -276.413553)
			(xy 354.836469 -276.386866) (xy 354.886154 -276.367366) (xy 354.938191 -276.355489) (xy 354.991416 -276.3515)
			(xy 355.044641 -276.355489) (xy 355.096678 -276.367366) (xy 355.146363 -276.386866) (xy 355.192587 -276.413553)
			(xy 355.234317 -276.446831) (xy 355.270621 -276.485958) (xy 355.300688 -276.530058) (xy 355.323846 -276.578147)
			(xy 355.339578 -276.62915) (xy 355.347533 -276.681929) (xy 355.348032 -276.708616) (xy 356.514146 -276.708616)
			(xy 356.514585 -276.682947) (xy 356.521931 -276.632139) (xy 356.536488 -276.582909) (xy 356.557954 -276.536276)
			(xy 356.585887 -276.493204) (xy 356.619708 -276.454583) (xy 356.658719 -276.421211) (xy 356.702112 -276.39378)
			(xy 356.748991 -276.372855) (xy 356.798386 -276.358869) (xy 356.823772 -276.355048) (xy 356.848664 -276.351746)
			(xy 357.020622 -276.054566) (xy 357.01097 -276.031198) (xy 357.002405 -276.009486) (xy 356.990317 -275.964406)
			(xy 356.984195 -275.918136) (xy 356.983792 -275.8948) (xy 356.984291 -275.868113) (xy 356.992246 -275.815334)
			(xy 357.007978 -275.764331) (xy 357.031136 -275.716242) (xy 357.061203 -275.672142) (xy 357.097507 -275.633015)
			(xy 357.139237 -275.599737) (xy 357.185461 -275.57305) (xy 357.235146 -275.55355) (xy 357.287183 -275.541673)
			(xy 357.340408 -275.537684) (xy 357.393633 -275.541673) (xy 357.44567 -275.55355) (xy 357.495355 -275.57305)
			(xy 357.541579 -275.599737) (xy 357.583309 -275.633015) (xy 357.619613 -275.672142) (xy 357.64968 -275.716242)
			(xy 357.672838 -275.764331) (xy 357.68857 -275.815334) (xy 357.696525 -275.868113) (xy 357.697024 -275.8948)
			(xy 357.696626 -275.92047) (xy 357.689277 -275.971282) (xy 357.674716 -276.020514) (xy 357.653246 -276.067149)
			(xy 357.625309 -276.110222) (xy 357.591483 -276.148843) (xy 357.552467 -276.182214) (xy 357.509069 -276.209644)
			(xy 357.462186 -276.230567) (xy 357.412786 -276.244549) (xy 357.387398 -276.248368) (xy 357.362506 -276.25167)
			(xy 357.190548 -276.54885) (xy 357.2002 -276.572218) (xy 357.208767 -276.593929) (xy 357.220855 -276.63901)
			(xy 357.226975 -276.68528) (xy 357.227378 -276.708616) (xy 357.226879 -276.735303) (xy 357.218924 -276.788082)
			(xy 357.203192 -276.839085) (xy 357.180034 -276.887174) (xy 357.149967 -276.931274) (xy 357.113663 -276.970401)
			(xy 357.071933 -277.003679) (xy 357.025709 -277.030366) (xy 356.976024 -277.049866) (xy 356.923987 -277.061743)
			(xy 356.870762 -277.065732) (xy 356.817537 -277.061743) (xy 356.7655 -277.049866) (xy 356.715815 -277.030366)
			(xy 356.669591 -277.003679) (xy 356.627861 -276.970401) (xy 356.591557 -276.931274) (xy 356.56149 -276.887174)
			(xy 356.538332 -276.839085) (xy 356.5226 -276.788082) (xy 356.514645 -276.735303) (xy 356.514146 -276.708616)
			(xy 355.348032 -276.708616) (xy 355.347637 -276.734318) (xy 355.340241 -276.785188) (xy 355.32562 -276.834469)
			(xy 355.304076 -276.881141) (xy 355.276055 -276.924238) (xy 355.242139 -276.962865) (xy 355.203028 -276.996224)
			(xy 355.159534 -277.023623) (xy 355.112557 -277.044494) (xy 355.063071 -277.058407) (xy 355.037644 -277.062184)
			(xy 355.012752 -277.065486) (xy 354.841048 -277.362666) (xy 354.8507 -277.386034) (xy 354.859272 -277.407743)
			(xy 354.871358 -277.452825) (xy 354.877476 -277.499096) (xy 354.877878 -277.522432) (xy 355.104446 -277.522432)
			(xy 355.104945 -277.495745) (xy 355.1129 -277.442966) (xy 355.128632 -277.391963) (xy 355.15179 -277.343874)
			(xy 355.181857 -277.299774) (xy 355.218161 -277.260647) (xy 355.259891 -277.227369) (xy 355.306115 -277.200682)
			(xy 355.3558 -277.181182) (xy 355.407837 -277.169305) (xy 355.461062 -277.165316) (xy 355.514287 -277.169305)
			(xy 355.566324 -277.181182) (xy 355.616009 -277.200682) (xy 355.662233 -277.227369) (xy 355.703963 -277.260647)
			(xy 355.740267 -277.299774) (xy 355.770334 -277.343874) (xy 355.793492 -277.391963) (xy 355.809224 -277.442966)
			(xy 355.817179 -277.495745) (xy 355.817677 -277.5224) (xy 356.044833 -277.5224) (xy 356.04881 -277.469335)
			(xy 356.06065 -277.417454) (xy 356.08009 -277.367918) (xy 356.106696 -277.321833) (xy 356.139872 -277.280227)
			(xy 356.178879 -277.24403) (xy 356.222845 -277.21405) (xy 356.270787 -277.190958) (xy 356.321636 -277.175268)
			(xy 356.374255 -277.167332) (xy 356.400862 -277.166832) (xy 356.425807 -277.167251) (xy 356.475208 -277.17422)
			(xy 356.523149 -277.188026) (xy 356.56869 -277.208398) (xy 356.610936 -277.234936) (xy 356.649058 -277.267119)
			(xy 356.682307 -277.304315) (xy 356.696518 -277.32482) (xy 357.045006 -277.32482) (xy 357.059233 -277.304327)
			(xy 357.092482 -277.267135) (xy 357.130603 -277.234954) (xy 357.172846 -277.208417) (xy 357.218384 -277.188042)
			(xy 357.266321 -277.174231) (xy 357.315718 -277.167255) (xy 357.340662 -277.166832) (xy 357.367279 -277.167238)
			(xy 357.41992 -277.175167) (xy 357.470791 -277.190854) (xy 357.518756 -277.213948) (xy 357.562742 -277.243933)
			(xy 357.601768 -277.280139) (xy 357.634961 -277.321758) (xy 357.66158 -277.36786) (xy 357.68103 -277.417414)
			(xy 357.692877 -277.469314) (xy 357.696856 -277.5224) (xy 357.692877 -277.575486) (xy 357.68103 -277.627386)
			(xy 357.66158 -277.67694) (xy 357.634961 -277.723042) (xy 357.601768 -277.764661) (xy 357.562742 -277.800867)
			(xy 357.518756 -277.830852) (xy 357.470791 -277.853946) (xy 357.41992 -277.869633) (xy 357.367279 -277.877562)
			(xy 357.340662 -277.878032) (xy 357.315717 -277.87761) (xy 357.266316 -277.870644) (xy 357.218373 -277.85684)
			(xy 357.172832 -277.836469) (xy 357.130585 -277.809931) (xy 357.092464 -277.777747) (xy 357.059216 -277.74055)
			(xy 357.045006 -277.720044) (xy 356.696518 -277.720044) (xy 356.682264 -277.740518) (xy 356.64902 -277.777712)
			(xy 356.610905 -277.809895) (xy 356.568666 -277.836435) (xy 356.523133 -277.856813) (xy 356.475199 -277.870627)
			(xy 356.425804 -277.877607) (xy 356.400862 -277.878032) (xy 356.374255 -277.877468) (xy 356.321636 -277.869532)
			(xy 356.270787 -277.853842) (xy 356.222845 -277.83075) (xy 356.178879 -277.80077) (xy 356.139872 -277.764573)
			(xy 356.106696 -277.722967) (xy 356.08009 -277.676882) (xy 356.06065 -277.627346) (xy 356.04881 -277.575465)
			(xy 356.044833 -277.5224) (xy 355.817677 -277.5224) (xy 355.817678 -277.522432) (xy 355.817678 -277.52294)
			(xy 355.817266 -277.546141) (xy 355.811211 -277.592147) (xy 355.799247 -277.636982) (xy 355.790754 -277.658576)
			(xy 355.781102 -277.68169) (xy 355.953314 -277.979632) (xy 355.978206 -277.982934) (xy 356.003595 -277.986725)
			(xy 356.052983 -278.000728) (xy 356.099854 -278.021666) (xy 356.14324 -278.049106) (xy 356.182244 -278.082482)
			(xy 356.216061 -278.121104) (xy 356.243993 -278.164175) (xy 356.265463 -278.210804) (xy 356.280028 -278.26003)
			(xy 356.287386 -278.310835) (xy 356.287832 -278.336502) (xy 356.287333 -278.363189) (xy 356.279378 -278.415968)
			(xy 356.263646 -278.466971) (xy 356.240488 -278.51506) (xy 356.210421 -278.55916) (xy 356.174117 -278.598287)
			(xy 356.132387 -278.631565) (xy 356.086163 -278.658252) (xy 356.036478 -278.677752) (xy 355.984441 -278.689629)
			(xy 355.931216 -278.693618) (xy 355.877991 -278.689629) (xy 355.825954 -278.677752) (xy 355.776269 -278.658252)
			(xy 355.730045 -278.631565) (xy 355.688315 -278.598287) (xy 355.652011 -278.55916) (xy 355.621944 -278.51506)
			(xy 355.598786 -278.466971) (xy 355.583054 -278.415968) (xy 355.575099 -278.363189) (xy 355.5746 -278.336502)
			(xy 355.574949 -278.313162) (xy 355.581056 -278.266883) (xy 355.593166 -278.2218) (xy 355.601778 -278.200104)
			(xy 355.61143 -278.176736) (xy 355.439726 -277.879302) (xy 355.414834 -277.876) (xy 355.389398 -277.872277)
			(xy 355.339907 -277.858368) (xy 355.292927 -277.837496) (xy 355.249431 -277.810093) (xy 355.210322 -277.776728)
			(xy 355.17641 -277.738091) (xy 355.148398 -277.694985) (xy 355.126867 -277.648303) (xy 355.112264 -277.599013)
			(xy 355.104891 -277.548136) (xy 355.104446 -277.522432) (xy 354.877878 -277.522432) (xy 354.877379 -277.549119)
			(xy 354.869424 -277.601898) (xy 354.853692 -277.652901) (xy 354.830534 -277.70099) (xy 354.800467 -277.74509)
			(xy 354.764163 -277.784217) (xy 354.722433 -277.817495) (xy 354.676209 -277.844182) (xy 354.626524 -277.863682)
			(xy 354.574487 -277.875559) (xy 354.521262 -277.879548) (xy 354.468037 -277.875559) (xy 354.416 -277.863682)
			(xy 354.366315 -277.844182) (xy 354.320091 -277.817495) (xy 354.278361 -277.784217) (xy 354.242057 -277.74509)
			(xy 354.21199 -277.70099) (xy 354.188832 -277.652901) (xy 354.1731 -277.601898) (xy 354.165145 -277.549119)
			(xy 354.164646 -277.522432) (xy 352.058478 -277.522432) (xy 352.057979 -277.549119) (xy 352.050024 -277.601898)
			(xy 352.034292 -277.652901) (xy 352.011134 -277.70099) (xy 351.981067 -277.74509) (xy 351.944763 -277.784217)
			(xy 351.903033 -277.817495) (xy 351.856809 -277.844182) (xy 351.807124 -277.863682) (xy 351.755087 -277.875559)
			(xy 351.701862 -277.879548) (xy 351.648637 -277.875559) (xy 351.5966 -277.863682) (xy 351.546915 -277.844182)
			(xy 351.500691 -277.817495) (xy 351.458961 -277.784217) (xy 351.422657 -277.74509) (xy 351.39259 -277.70099)
			(xy 351.369432 -277.652901) (xy 351.3537 -277.601898) (xy 351.345745 -277.549119) (xy 351.345246 -277.522432)
			(xy 351.345608 -277.499092) (xy 351.351711 -277.452814) (xy 351.363815 -277.407731) (xy 351.372424 -277.386034)
			(xy 351.382076 -277.362666) (xy 351.210118 -277.065486) (xy 351.185226 -277.062184) (xy 351.159844 -277.058351)
			(xy 351.110457 -277.044353) (xy 351.063588 -277.02342) (xy 351.020202 -276.995985) (xy 350.981198 -276.962614)
			(xy 350.94738 -276.923997) (xy 350.919446 -276.880931) (xy 350.897974 -276.834305) (xy 350.883408 -276.785083)
			(xy 350.876047 -276.734282) (xy 350.8756 -276.708616) (xy 350.648778 -276.708616) (xy 350.648279 -276.735303)
			(xy 350.640324 -276.788082) (xy 350.624592 -276.839085) (xy 350.601434 -276.887174) (xy 350.571367 -276.931274)
			(xy 350.535063 -276.970401) (xy 350.493333 -277.003679) (xy 350.447109 -277.030366) (xy 350.397424 -277.049866)
			(xy 350.345387 -277.061743) (xy 350.292162 -277.065732) (xy 350.238937 -277.061743) (xy 350.1869 -277.049866)
			(xy 350.137215 -277.030366) (xy 350.090991 -277.003679) (xy 350.049261 -276.970401) (xy 350.012957 -276.931274)
			(xy 349.98289 -276.887174) (xy 349.959732 -276.839085) (xy 349.944 -276.788082) (xy 349.936045 -276.735303)
			(xy 349.935546 -276.708616) (xy 109.28731 -276.708616) (xy 109.286811 -276.735303) (xy 109.278856 -276.788082)
			(xy 109.263124 -276.839085) (xy 109.239966 -276.887174) (xy 109.209899 -276.931274) (xy 109.173595 -276.970401)
			(xy 109.131865 -277.003679) (xy 109.085641 -277.030366) (xy 109.035956 -277.049866) (xy 108.983919 -277.061743)
			(xy 108.930694 -277.065732) (xy 108.877469 -277.061743) (xy 108.825432 -277.049866) (xy 108.775747 -277.030366)
			(xy 108.729523 -277.003679) (xy 108.687793 -276.970401) (xy 108.651489 -276.931274) (xy 108.621422 -276.887174)
			(xy 108.598264 -276.839085) (xy 108.582532 -276.788082) (xy 108.574577 -276.735303) (xy 108.574078 -276.708616)
			(xy 107.407964 -276.708616) (xy 107.407541 -276.734317) (xy 107.400147 -276.785184) (xy 107.385527 -276.834463)
			(xy 107.363985 -276.881134) (xy 107.335967 -276.924229) (xy 107.302054 -276.962856) (xy 107.262947 -276.996215)
			(xy 107.219457 -277.023615) (xy 107.172484 -277.044489) (xy 107.123002 -277.058405) (xy 107.097576 -277.062184)
			(xy 107.072684 -277.065486) (xy 106.90098 -277.362666) (xy 106.910632 -277.386034) (xy 106.919206 -277.407742)
			(xy 106.931291 -277.452824) (xy 106.937409 -277.499095) (xy 106.93781 -277.522432) (xy 107.164378 -277.522432)
			(xy 107.164877 -277.495745) (xy 107.172832 -277.442966) (xy 107.188564 -277.391963) (xy 107.211722 -277.343874)
			(xy 107.241789 -277.299774) (xy 107.278093 -277.260647) (xy 107.319823 -277.227369) (xy 107.366047 -277.200682)
			(xy 107.415732 -277.181182) (xy 107.467769 -277.169305) (xy 107.520994 -277.165316) (xy 107.574219 -277.169305)
			(xy 107.626256 -277.181182) (xy 107.675941 -277.200682) (xy 107.722165 -277.227369) (xy 107.763895 -277.260647)
			(xy 107.800199 -277.299774) (xy 107.830266 -277.343874) (xy 107.853424 -277.391963) (xy 107.869156 -277.442966)
			(xy 107.877111 -277.495745) (xy 107.877609 -277.5224) (xy 108.104733 -277.5224) (xy 108.10871 -277.469332)
			(xy 108.120552 -277.417449) (xy 108.139994 -277.36791) (xy 108.166603 -277.321822) (xy 108.199783 -277.280215)
			(xy 108.238793 -277.244018) (xy 108.282763 -277.214039) (xy 108.33071 -277.190949) (xy 108.381563 -277.175262)
			(xy 108.434185 -277.16733) (xy 108.460794 -277.166832) (xy 108.48574 -277.167227) (xy 108.535142 -277.1742)
			(xy 108.583084 -277.18801) (xy 108.628625 -277.208386) (xy 108.670871 -277.234928) (xy 108.708992 -277.267114)
			(xy 108.742239 -277.304313) (xy 108.75645 -277.32482) (xy 109.104938 -277.32482) (xy 109.119145 -277.304312)
			(xy 109.152397 -277.26712) (xy 109.190521 -277.234941) (xy 109.232768 -277.208405) (xy 109.278309 -277.188033)
			(xy 109.326249 -277.174225) (xy 109.375649 -277.167253) (xy 109.400594 -277.166832) (xy 109.42721 -277.16724)
			(xy 109.479847 -277.175173) (xy 109.530714 -277.190863) (xy 109.578674 -277.213958) (xy 109.622657 -277.243944)
			(xy 109.661679 -277.280151) (xy 109.694868 -277.321769) (xy 109.721484 -277.367868) (xy 109.740932 -277.41742)
			(xy 109.752777 -277.469317) (xy 109.756756 -277.5224) (xy 109.752777 -277.575483) (xy 109.740932 -277.62738)
			(xy 109.721484 -277.676932) (xy 109.694868 -277.723031) (xy 109.661679 -277.764649) (xy 109.622657 -277.800856)
			(xy 109.578674 -277.830842) (xy 109.530714 -277.853937) (xy 109.479847 -277.869627) (xy 109.42721 -277.87756)
			(xy 109.400594 -277.878032) (xy 109.37565 -277.877586) (xy 109.326249 -277.870624) (xy 109.278308 -277.856824)
			(xy 109.232766 -277.836457) (xy 109.19052 -277.809923) (xy 109.152398 -277.777742) (xy 109.119149 -277.740549)
			(xy 109.104938 -277.720044) (xy 108.75645 -277.720044) (xy 108.742239 -277.740549) (xy 108.708988 -277.777742)
			(xy 108.670866 -277.809923) (xy 108.62862 -277.83646) (xy 108.583079 -277.856832) (xy 108.535139 -277.87064)
			(xy 108.485739 -277.877612) (xy 108.460794 -277.878032) (xy 108.434185 -277.87747) (xy 108.381563 -277.869538)
			(xy 108.33071 -277.853851) (xy 108.282763 -277.830761) (xy 108.238793 -277.800782) (xy 108.199783 -277.764585)
			(xy 108.166603 -277.722978) (xy 108.139994 -277.67689) (xy 108.120552 -277.627351) (xy 108.10871 -277.575468)
			(xy 108.104733 -277.5224) (xy 107.877609 -277.5224) (xy 107.87761 -277.522432) (xy 107.87761 -277.52294)
			(xy 107.877203 -277.546141) (xy 107.871147 -277.592148) (xy 107.85918 -277.636982) (xy 107.850686 -277.658576)
			(xy 107.841034 -277.68169) (xy 108.013246 -277.979632) (xy 108.038138 -277.982934) (xy 108.063531 -277.9867)
			(xy 108.11292 -278.000707) (xy 108.15979 -278.021649) (xy 108.203175 -278.049093) (xy 108.242179 -278.082472)
			(xy 108.275995 -278.121096) (xy 108.303927 -278.164169) (xy 108.325396 -278.2108) (xy 108.33996 -278.260028)
			(xy 108.347318 -278.310834) (xy 108.347764 -278.336502) (xy 108.347265 -278.363189) (xy 108.33931 -278.415968)
			(xy 108.323578 -278.466971) (xy 108.30042 -278.51506) (xy 108.270353 -278.55916) (xy 108.234049 -278.598287)
			(xy 108.192319 -278.631565) (xy 108.146095 -278.658252) (xy 108.09641 -278.677752) (xy 108.044373 -278.689629)
			(xy 107.991148 -278.693618) (xy 107.937923 -278.689629) (xy 107.885886 -278.677752) (xy 107.836201 -278.658252)
			(xy 107.789977 -278.631565) (xy 107.748247 -278.598287) (xy 107.711943 -278.55916) (xy 107.681876 -278.51506)
			(xy 107.658718 -278.466971) (xy 107.642986 -278.415968) (xy 107.635031 -278.363189) (xy 107.634532 -278.336502)
			(xy 107.634886 -278.313162) (xy 107.640992 -278.266883) (xy 107.653099 -278.221801) (xy 107.66171 -278.200104)
			(xy 107.671362 -278.176736) (xy 107.499658 -277.879302) (xy 107.474766 -277.876) (xy 107.449334 -277.872252)
			(xy 107.399843 -277.858348) (xy 107.352863 -277.837479) (xy 107.309367 -277.81008) (xy 107.270257 -277.776717)
			(xy 107.236344 -277.738083) (xy 107.208331 -277.694979) (xy 107.1868 -277.648299) (xy 107.172196 -277.599011)
			(xy 107.164823 -277.548135) (xy 107.164378 -277.522432) (xy 106.93781 -277.522432) (xy 106.937311 -277.549119)
			(xy 106.929356 -277.601898) (xy 106.913624 -277.652901) (xy 106.890466 -277.70099) (xy 106.860399 -277.74509)
			(xy 106.824095 -277.784217) (xy 106.782365 -277.817495) (xy 106.736141 -277.844182) (xy 106.686456 -277.863682)
			(xy 106.634419 -277.875559) (xy 106.581194 -277.879548) (xy 106.527969 -277.875559) (xy 106.475932 -277.863682)
			(xy 106.426247 -277.844182) (xy 106.380023 -277.817495) (xy 106.338293 -277.784217) (xy 106.301989 -277.74509)
			(xy 106.271922 -277.70099) (xy 106.248764 -277.652901) (xy 106.233032 -277.601898) (xy 106.225077 -277.549119)
			(xy 106.224578 -277.522432) (xy 104.11841 -277.522432) (xy 104.117911 -277.549119) (xy 104.109956 -277.601898)
			(xy 104.094224 -277.652901) (xy 104.071066 -277.70099) (xy 104.040999 -277.74509) (xy 104.004695 -277.784217)
			(xy 103.962965 -277.817495) (xy 103.916741 -277.844182) (xy 103.867056 -277.863682) (xy 103.815019 -277.875559)
			(xy 103.761794 -277.879548) (xy 103.708569 -277.875559) (xy 103.656532 -277.863682) (xy 103.606847 -277.844182)
			(xy 103.560623 -277.817495) (xy 103.518893 -277.784217) (xy 103.482589 -277.74509) (xy 103.452522 -277.70099)
			(xy 103.429364 -277.652901) (xy 103.413632 -277.601898) (xy 103.405677 -277.549119) (xy 103.405178 -277.522432)
			(xy 103.405538 -277.499092) (xy 103.411641 -277.452813) (xy 103.423746 -277.407731) (xy 103.432356 -277.386034)
			(xy 103.442008 -277.362666) (xy 103.27005 -277.065486) (xy 103.245158 -277.062184) (xy 103.219767 -277.058404)
			(xy 103.17038 -277.044397) (xy 103.123511 -277.023456) (xy 103.080127 -276.996013) (xy 103.041124 -276.962636)
			(xy 103.007307 -276.924013) (xy 102.979375 -276.880943) (xy 102.957905 -276.834313) (xy 102.943339 -276.785088)
			(xy 102.935979 -276.734283) (xy 102.935532 -276.708616) (xy 102.70871 -276.708616) (xy 102.708211 -276.735303)
			(xy 102.700256 -276.788082) (xy 102.684524 -276.839085) (xy 102.661366 -276.887174) (xy 102.631299 -276.931274)
			(xy 102.594995 -276.970401) (xy 102.553265 -277.003679) (xy 102.507041 -277.030366) (xy 102.457356 -277.049866)
			(xy 102.405319 -277.061743) (xy 102.352094 -277.065732) (xy 102.298869 -277.061743) (xy 102.246832 -277.049866)
			(xy 102.197147 -277.030366) (xy 102.150923 -277.003679) (xy 102.109193 -276.970401) (xy 102.072889 -276.931274)
			(xy 102.042822 -276.887174) (xy 102.019664 -276.839085) (xy 102.003932 -276.788082) (xy 101.995977 -276.735303)
			(xy 101.995478 -276.708616) (xy 2.509012 -276.708616) (xy 2.509012 -279.150318) (xy 101.525578 -279.150318)
			(xy 101.526077 -279.123631) (xy 101.534032 -279.070852) (xy 101.549764 -279.019849) (xy 101.572922 -278.97176)
			(xy 101.602989 -278.92766) (xy 101.639293 -278.888533) (xy 101.681023 -278.855255) (xy 101.727247 -278.828568)
			(xy 101.776932 -278.809068) (xy 101.828969 -278.797191) (xy 101.882194 -278.793202) (xy 101.935419 -278.797191)
			(xy 101.987456 -278.809068) (xy 102.037141 -278.828568) (xy 102.083365 -278.855255) (xy 102.125095 -278.888533)
			(xy 102.161399 -278.92766) (xy 102.191466 -278.97176) (xy 102.214624 -279.019849) (xy 102.230356 -279.070852)
			(xy 102.238311 -279.123631) (xy 102.23881 -279.1503) (xy 102.465919 -279.1503) (xy 102.469897 -279.09723)
			(xy 102.481739 -279.045345) (xy 102.501182 -278.995804) (xy 102.527791 -278.949715) (xy 102.560973 -278.908106)
			(xy 102.599985 -278.871907) (xy 102.643956 -278.841927) (xy 102.691905 -278.818836) (xy 102.74276 -278.803148)
			(xy 102.795384 -278.795216) (xy 102.821994 -278.794718) (xy 102.846964 -278.795151) (xy 102.896412 -278.802144)
			(xy 102.944397 -278.81598) (xy 102.989978 -278.836386) (xy 103.032259 -278.862963) (xy 103.07041 -278.895189)
			(xy 103.103683 -278.932431) (xy 103.117904 -278.95296) (xy 103.465884 -278.95296) (xy 103.480108 -278.932431)
			(xy 103.513373 -278.89518) (xy 103.55152 -278.862947) (xy 103.593801 -278.836365) (xy 103.639383 -278.815958)
			(xy 103.687372 -278.802125) (xy 103.736823 -278.79514) (xy 103.761794 -278.794718) (xy 103.788409 -278.795154)
			(xy 103.841044 -278.803087) (xy 103.891909 -278.818776) (xy 103.939867 -278.84187) (xy 103.983848 -278.871855)
			(xy 104.022868 -278.90806) (xy 104.056057 -278.949676) (xy 104.082672 -278.995774) (xy 104.102119 -279.045324)
			(xy 104.113964 -279.097219) (xy 104.117942 -279.1503) (xy 104.117941 -279.150318) (xy 349.465646 -279.150318)
			(xy 349.466145 -279.123631) (xy 349.4741 -279.070852) (xy 349.489832 -279.019849) (xy 349.51299 -278.97176)
			(xy 349.543057 -278.92766) (xy 349.579361 -278.888533) (xy 349.621091 -278.855255) (xy 349.667315 -278.828568)
			(xy 349.717 -278.809068) (xy 349.769037 -278.797191) (xy 349.822262 -278.793202) (xy 349.875487 -278.797191)
			(xy 349.927524 -278.809068) (xy 349.977209 -278.828568) (xy 350.023433 -278.855255) (xy 350.065163 -278.888533)
			(xy 350.101467 -278.92766) (xy 350.131534 -278.97176) (xy 350.154692 -279.019849) (xy 350.170424 -279.070852)
			(xy 350.178379 -279.123631) (xy 350.178878 -279.1503) (xy 350.406019 -279.1503) (xy 350.409996 -279.097233)
			(xy 350.421837 -279.04535) (xy 350.441278 -278.995812) (xy 350.467884 -278.949725) (xy 350.501062 -278.908117)
			(xy 350.54007 -278.871919) (xy 350.584038 -278.841938) (xy 350.631982 -278.818845) (xy 350.682833 -278.803154)
			(xy 350.735454 -278.795218) (xy 350.762062 -278.794718) (xy 350.787031 -278.795175) (xy 350.836478 -278.802164)
			(xy 350.884463 -278.815995) (xy 350.930044 -278.836398) (xy 350.972325 -278.862971) (xy 351.010477 -278.895194)
			(xy 351.043751 -278.932432) (xy 351.057972 -278.95296) (xy 351.405952 -278.95296) (xy 351.420132 -278.9324)
			(xy 351.453404 -278.895149) (xy 351.49156 -278.862918) (xy 351.533847 -278.83634) (xy 351.579437 -278.815938)
			(xy 351.627432 -278.802113) (xy 351.676889 -278.795136) (xy 351.701862 -278.794718) (xy 351.728478 -278.795152)
			(xy 351.781117 -278.80308) (xy 351.831986 -278.818767) (xy 351.879949 -278.84186) (xy 351.923934 -278.871844)
			(xy 351.962958 -278.908049) (xy 351.99615 -278.949666) (xy 352.022768 -278.995766) (xy 352.042217 -279.045319)
			(xy 352.054063 -279.097216) (xy 352.058042 -279.1503) (xy 352.054063 -279.203384) (xy 352.042217 -279.255281)
			(xy 352.022768 -279.304834) (xy 351.99615 -279.350934) (xy 351.962958 -279.392551) (xy 351.923934 -279.428756)
			(xy 351.879949 -279.45874) (xy 351.831986 -279.481833) (xy 351.781117 -279.49752) (xy 351.728478 -279.505448)
			(xy 351.701862 -279.505918) (xy 351.676892 -279.505471) (xy 351.627443 -279.498484) (xy 351.579457 -279.484653)
			(xy 351.533876 -279.464249) (xy 351.491594 -279.437674) (xy 351.453443 -279.405448) (xy 351.420172 -279.368206)
			(xy 351.405952 -279.347676) (xy 351.057972 -279.347676) (xy 351.043756 -279.368211) (xy 351.010492 -279.405465)
			(xy 350.972344 -279.4377) (xy 350.930062 -279.464282) (xy 350.884478 -279.484688) (xy 350.836487 -279.498518)
			(xy 350.787034 -279.505499) (xy 350.762062 -279.505918) (xy 350.735454 -279.505382) (xy 350.682833 -279.497446)
			(xy 350.631982 -279.481755) (xy 350.584038 -279.458662) (xy 350.54007 -279.428681) (xy 350.501062 -279.392483)
			(xy 350.467884 -279.350875) (xy 350.441278 -279.304788) (xy 350.421837 -279.25525) (xy 350.409996 -279.203367)
			(xy 350.406019 -279.1503) (xy 350.178878 -279.1503) (xy 350.178878 -279.150318) (xy 350.178878 -279.150826)
			(xy 350.178493 -279.174028) (xy 350.172427 -279.220035) (xy 350.160452 -279.264868) (xy 350.151954 -279.286462)
			(xy 350.142302 -279.309576) (xy 350.314514 -279.607264) (xy 350.339406 -279.610566) (xy 350.364784 -279.614422)
			(xy 350.414166 -279.628422) (xy 350.461033 -279.649355) (xy 350.504416 -279.676789) (xy 350.543419 -279.710157)
			(xy 350.577236 -279.748771) (xy 350.60517 -279.791833) (xy 350.626645 -279.838454) (xy 350.641215 -279.887672)
			(xy 350.648581 -279.93847) (xy 350.649032 -279.964134) (xy 350.648533 -279.990821) (xy 350.640578 -280.0436)
			(xy 350.624846 -280.094603) (xy 350.601688 -280.142692) (xy 350.571621 -280.186792) (xy 350.535317 -280.225919)
			(xy 350.493587 -280.259197) (xy 350.447363 -280.285884) (xy 350.397678 -280.305384) (xy 350.345641 -280.317261)
			(xy 350.292416 -280.32125) (xy 350.239191 -280.317261) (xy 350.187154 -280.305384) (xy 350.137469 -280.285884)
			(xy 350.091245 -280.259197) (xy 350.049515 -280.225919) (xy 350.013211 -280.186792) (xy 349.983144 -280.142692)
			(xy 349.959986 -280.094603) (xy 349.944254 -280.0436) (xy 349.936299 -279.990821) (xy 349.9358 -279.964134)
			(xy 349.936159 -279.940794) (xy 349.942262 -279.894515) (xy 349.954368 -279.849433) (xy 349.962978 -279.827736)
			(xy 349.97263 -279.804368) (xy 349.800926 -279.507188) (xy 349.776034 -279.503886) (xy 349.750612 -279.50008)
			(xy 349.701128 -279.486176) (xy 349.654153 -279.46531) (xy 349.610661 -279.437915) (xy 349.571554 -279.404559)
			(xy 349.537641 -279.365933) (xy 349.509627 -279.322838) (xy 349.488091 -279.276166) (xy 349.47348 -279.226886)
			(xy 349.466096 -279.176018) (xy 349.465646 -279.150318) (xy 104.117941 -279.150318) (xy 104.113964 -279.203381)
			(xy 104.102119 -279.255276) (xy 104.082672 -279.304826) (xy 104.056057 -279.350924) (xy 104.022868 -279.39254)
			(xy 103.983848 -279.428745) (xy 103.939867 -279.45873) (xy 103.891909 -279.481824) (xy 103.841044 -279.497513)
			(xy 103.788409 -279.505446) (xy 103.761794 -279.505918) (xy 103.736822 -279.505522) (xy 103.687371 -279.498526)
			(xy 103.639384 -279.484686) (xy 103.593802 -279.464274) (xy 103.551521 -279.437691) (xy 103.513372 -279.405458)
			(xy 103.480102 -279.368209) (xy 103.465884 -279.347676) (xy 103.117904 -279.347676) (xy 103.103668 -279.368196)
			(xy 103.070407 -279.40545) (xy 103.032263 -279.437686) (xy 102.989984 -279.46427) (xy 102.944403 -279.484679)
			(xy 102.896416 -279.498512) (xy 102.846965 -279.505497) (xy 102.821994 -279.505918) (xy 102.795384 -279.505384)
			(xy 102.74276 -279.497452) (xy 102.691905 -279.481764) (xy 102.643956 -279.458673) (xy 102.599985 -279.428693)
			(xy 102.560973 -279.392494) (xy 102.527791 -279.350885) (xy 102.501182 -279.304796) (xy 102.481739 -279.255255)
			(xy 102.469897 -279.20337) (xy 102.465919 -279.1503) (xy 102.23881 -279.1503) (xy 102.23881 -279.150318)
			(xy 102.23881 -279.150826) (xy 102.23843 -279.174028) (xy 102.232363 -279.220036) (xy 102.220386 -279.264869)
			(xy 102.211886 -279.286462) (xy 102.202234 -279.309576) (xy 102.374446 -279.607264) (xy 102.399338 -279.610566)
			(xy 102.42472 -279.614397) (xy 102.474103 -279.628401) (xy 102.520969 -279.649338) (xy 102.564351 -279.676775)
			(xy 102.603353 -279.710147) (xy 102.63717 -279.748763) (xy 102.665104 -279.791827) (xy 102.686577 -279.83845)
			(xy 102.701147 -279.88767) (xy 102.708513 -279.938469) (xy 102.708964 -279.964134) (xy 102.708465 -279.990821)
			(xy 102.70051 -280.0436) (xy 102.684778 -280.094603) (xy 102.66162 -280.142692) (xy 102.631553 -280.186792)
			(xy 102.595249 -280.225919) (xy 102.553519 -280.259197) (xy 102.507295 -280.285884) (xy 102.45761 -280.305384)
			(xy 102.405573 -280.317261) (xy 102.352348 -280.32125) (xy 102.299123 -280.317261) (xy 102.247086 -280.305384)
			(xy 102.197401 -280.285884) (xy 102.151177 -280.259197) (xy 102.109447 -280.225919) (xy 102.073143 -280.186792)
			(xy 102.043076 -280.142692) (xy 102.019918 -280.094603) (xy 102.004186 -280.0436) (xy 101.996231 -279.990821)
			(xy 101.995732 -279.964134) (xy 101.996096 -279.940794) (xy 102.002198 -279.894516) (xy 102.014301 -279.849433)
			(xy 102.02291 -279.827736) (xy 102.032562 -279.804368) (xy 101.860858 -279.507188) (xy 101.835966 -279.503886)
			(xy 101.810548 -279.500055) (xy 101.761064 -279.486155) (xy 101.714089 -279.465293) (xy 101.670597 -279.437902)
			(xy 101.631489 -279.404549) (xy 101.597576 -279.365925) (xy 101.56956 -279.322832) (xy 101.548024 -279.276162)
			(xy 101.533412 -279.226884) (xy 101.526029 -279.176018) (xy 101.525578 -279.150318) (xy 2.509012 -279.150318)
			(xy 2.509012 -279.9641) (xy 88.838835 -279.9641) (xy 88.842812 -279.911032) (xy 88.854654 -279.859149)
			(xy 88.874096 -279.809611) (xy 88.900704 -279.763524) (xy 88.933884 -279.721917) (xy 88.972895 -279.68572)
			(xy 89.016864 -279.655741) (xy 89.064811 -279.632651) (xy 89.115663 -279.616964) (xy 89.168286 -279.609032)
			(xy 89.194894 -279.608534) (xy 89.219864 -279.60896) (xy 89.269313 -279.615953) (xy 89.317299 -279.62979)
			(xy 89.36288 -279.650197) (xy 89.405161 -279.676776) (xy 89.443312 -279.709003) (xy 89.476584 -279.746246)
			(xy 89.490804 -279.766776) (xy 89.838784 -279.766776) (xy 89.853013 -279.746251) (xy 89.886276 -279.708999)
			(xy 89.924423 -279.676765) (xy 89.966702 -279.650182) (xy 90.012284 -279.629774) (xy 90.060272 -279.615942)
			(xy 90.109723 -279.608956) (xy 90.134694 -279.608534) (xy 90.16131 -279.608938) (xy 90.213947 -279.616871)
			(xy 90.264815 -279.632561) (xy 90.312775 -279.655657) (xy 90.356758 -279.685643) (xy 90.39578 -279.721849)
			(xy 90.42897 -279.763467) (xy 90.455586 -279.809568) (xy 90.475034 -279.85912) (xy 90.486879 -279.911017)
			(xy 90.490858 -279.9641) (xy 90.490855 -279.964134) (xy 96.356932 -279.964134) (xy 96.357431 -279.937447)
			(xy 96.365386 -279.884668) (xy 96.381118 -279.833665) (xy 96.404276 -279.785576) (xy 96.434343 -279.741476)
			(xy 96.470647 -279.702349) (xy 96.512377 -279.669071) (xy 96.558601 -279.642384) (xy 96.608286 -279.622884)
			(xy 96.660323 -279.611007) (xy 96.713548 -279.607018) (xy 96.766773 -279.611007) (xy 96.81881 -279.622884)
			(xy 96.868495 -279.642384) (xy 96.914719 -279.669071) (xy 96.956449 -279.702349) (xy 96.992753 -279.741476)
			(xy 97.02282 -279.785576) (xy 97.045978 -279.833665) (xy 97.06171 -279.884668) (xy 97.069665 -279.937447)
			(xy 97.070164 -279.964134) (xy 97.069649 -279.991571) (xy 97.061212 -280.045794) (xy 97.044588 -280.09809)
			(xy 97.032826 -280.122884) (xy 97.205292 -280.421334) (xy 97.230184 -280.424636) (xy 97.255554 -280.428539)
			(xy 97.304934 -280.442534) (xy 97.351799 -280.463462) (xy 97.395181 -280.49089) (xy 97.434183 -280.524253)
			(xy 97.468002 -280.562862) (xy 97.495937 -280.605919) (xy 97.517414 -280.652535) (xy 97.531987 -280.701748)
			(xy 97.539357 -280.752541) (xy 97.53981 -280.778204) (xy 97.539311 -280.804891) (xy 97.531356 -280.85767)
			(xy 97.515624 -280.908673) (xy 97.492466 -280.956762) (xy 97.462399 -281.000862) (xy 97.426095 -281.039989)
			(xy 97.384365 -281.073267) (xy 97.338141 -281.099954) (xy 97.288456 -281.119454) (xy 97.236419 -281.131331)
			(xy 97.183194 -281.13532) (xy 97.129969 -281.131331) (xy 97.077932 -281.119454) (xy 97.028247 -281.099954)
			(xy 96.982023 -281.073267) (xy 96.940293 -281.039989) (xy 96.903989 -281.000862) (xy 96.873922 -280.956762)
			(xy 96.850764 -280.908673) (xy 96.835032 -280.85767) (xy 96.827077 -280.804891) (xy 96.826578 -280.778204)
			(xy 96.826929 -280.754864) (xy 96.833036 -280.708585) (xy 96.845144 -280.663502) (xy 96.853756 -280.641806)
			(xy 96.863408 -280.618438) (xy 96.690688 -280.319988) (xy 96.663891 -280.31783) (xy 96.611364 -280.306374)
			(xy 96.561152 -280.287163) (xy 96.514394 -280.260632) (xy 96.472148 -280.227381) (xy 96.435373 -280.188166)
			(xy 96.404902 -280.143874) (xy 96.381426 -280.095509) (xy 96.365477 -280.044168) (xy 96.357416 -279.991015)
			(xy 96.356932 -279.964134) (xy 90.490855 -279.964134) (xy 90.486879 -280.017183) (xy 90.475034 -280.06908)
			(xy 90.455586 -280.118632) (xy 90.42897 -280.164733) (xy 90.39578 -280.206351) (xy 90.356758 -280.242557)
			(xy 90.312775 -280.272543) (xy 90.264815 -280.295639) (xy 90.213947 -280.311329) (xy 90.16131 -280.319262)
			(xy 90.134694 -280.319734) (xy 90.109723 -280.319331) (xy 90.060272 -280.312336) (xy 90.012285 -280.298496)
			(xy 89.966704 -280.278085) (xy 89.924423 -280.251503) (xy 89.886273 -280.219272) (xy 89.853003 -280.182024)
			(xy 89.838784 -280.161492) (xy 89.490804 -280.161492) (xy 89.476573 -280.182016) (xy 89.443311 -280.219269)
			(xy 89.405165 -280.251504) (xy 89.362886 -280.278088) (xy 89.317304 -280.298496) (xy 89.269316 -280.312328)
			(xy 89.219865 -280.319313) (xy 89.194894 -280.319734) (xy 89.168286 -280.319168) (xy 89.115663 -280.311236)
			(xy 89.064811 -280.295549) (xy 89.016864 -280.272459) (xy 88.972895 -280.24248) (xy 88.933884 -280.206283)
			(xy 88.900704 -280.164676) (xy 88.874096 -280.118589) (xy 88.854654 -280.069051) (xy 88.842812 -280.017168)
			(xy 88.838835 -279.9641) (xy 2.509012 -279.9641) (xy 2.509012 -280.7782) (xy 86.489305 -280.7782)
			(xy 86.493283 -280.725127) (xy 86.505125 -280.67324) (xy 86.524569 -280.623698) (xy 86.55118 -280.577607)
			(xy 86.584362 -280.535996) (xy 86.623376 -280.499796) (xy 86.667349 -280.469815) (xy 86.7153 -280.446723)
			(xy 86.766156 -280.431035) (xy 86.818783 -280.423102) (xy 86.845394 -280.422604) (xy 86.870341 -280.422967)
			(xy 86.919746 -280.429942) (xy 86.96769 -280.443755) (xy 87.013232 -280.464136) (xy 87.055478 -280.490683)
			(xy 87.093598 -280.522876) (xy 87.126842 -280.560082) (xy 87.14105 -280.580592) (xy 87.489538 -280.580592)
			(xy 87.503736 -280.560078) (xy 87.536991 -280.522888) (xy 87.575117 -280.490709) (xy 87.617365 -280.464175)
			(xy 87.662907 -280.443804) (xy 87.710849 -280.429997) (xy 87.760249 -280.423025) (xy 87.785194 -280.422604)
			(xy 87.811808 -280.423068) (xy 87.864441 -280.431001) (xy 87.915304 -280.446689) (xy 87.96326 -280.469783)
			(xy 88.007239 -280.499767) (xy 88.046258 -280.53597) (xy 88.079445 -280.577585) (xy 88.106059 -280.623681)
			(xy 88.125505 -280.673229) (xy 88.137349 -280.725121) (xy 88.141327 -280.7782) (xy 88.137349 -280.831279)
			(xy 88.125505 -280.883171) (xy 88.106059 -280.932719) (xy 88.079445 -280.978815) (xy 88.046258 -281.02043)
			(xy 88.007239 -281.056633) (xy 87.96326 -281.086617) (xy 87.915304 -281.109711) (xy 87.864441 -281.125399)
			(xy 87.811808 -281.133332) (xy 87.785194 -281.133804) (xy 87.760249 -281.13337) (xy 87.710848 -281.126408)
			(xy 87.662905 -281.112607) (xy 87.617363 -281.092238) (xy 87.575117 -281.065701) (xy 87.536995 -281.033519)
			(xy 87.503748 -280.996322) (xy 87.489538 -280.975816) (xy 87.14105 -280.975816) (xy 87.126863 -280.996338)
			(xy 87.093605 -281.033527) (xy 87.055477 -281.065705) (xy 87.013227 -281.092238) (xy 86.967684 -281.112608)
			(xy 86.919741 -281.126413) (xy 86.87034 -281.133384) (xy 86.845394 -281.133804) (xy 86.818783 -281.133298)
			(xy 86.766156 -281.125365) (xy 86.7153 -281.109677) (xy 86.667349 -281.086585) (xy 86.623376 -281.056604)
			(xy 86.584362 -281.020404) (xy 86.55118 -280.978793) (xy 86.524569 -280.932702) (xy 86.505125 -280.88316)
			(xy 86.493283 -280.831273) (xy 86.489305 -280.7782) (xy 2.509012 -280.7782) (xy 2.509012 -282.405836)
			(xy 86.489032 -282.405836) (xy 86.489501 -282.380169) (xy 86.496844 -282.329362) (xy 86.511398 -282.280134)
			(xy 86.532861 -282.233501) (xy 86.56079 -282.190429) (xy 86.594608 -282.151808) (xy 86.633615 -282.118436)
			(xy 86.677005 -282.091004) (xy 86.723881 -282.070077) (xy 86.773273 -282.05609) (xy 86.798658 -282.052268)
			(xy 86.82355 -282.048966) (xy 86.995508 -281.751278) (xy 86.985856 -281.728164) (xy 86.977357 -281.706571)
			(xy 86.965377 -281.661739) (xy 86.959321 -281.61573) (xy 86.958932 -281.592528) (xy 86.958932 -281.59202)
			(xy 86.959431 -281.565333) (xy 86.967386 -281.512554) (xy 86.983118 -281.461551) (xy 87.006276 -281.413462)
			(xy 87.036343 -281.369362) (xy 87.072647 -281.330235) (xy 87.114377 -281.296957) (xy 87.160601 -281.27027)
			(xy 87.210286 -281.25077) (xy 87.262323 -281.238893) (xy 87.315548 -281.234904) (xy 87.368773 -281.238893)
			(xy 87.42081 -281.25077) (xy 87.470495 -281.27027) (xy 87.516719 -281.296957) (xy 87.558449 -281.330235)
			(xy 87.594753 -281.369362) (xy 87.62482 -281.413462) (xy 87.647978 -281.461551) (xy 87.66371 -281.512554)
			(xy 87.671665 -281.565333) (xy 87.672164 -281.59202) (xy 88.838532 -281.59202) (xy 88.838987 -281.566352)
			(xy 88.846332 -281.515545) (xy 88.860887 -281.466316) (xy 88.882352 -281.419684) (xy 88.910283 -281.376612)
			(xy 88.944103 -281.337991) (xy 88.983111 -281.304619) (xy 89.026502 -281.277187) (xy 89.073379 -281.256261)
			(xy 89.122773 -281.242274) (xy 89.148158 -281.238452) (xy 89.17305 -281.23515) (xy 89.345516 -280.936954)
			(xy 89.333735 -280.912167) (xy 89.317092 -280.859873) (xy 89.308679 -280.805643) (xy 89.308178 -280.778204)
			(xy 89.308677 -280.751517) (xy 89.316632 -280.698738) (xy 89.332364 -280.647735) (xy 89.355522 -280.599646)
			(xy 89.385589 -280.555546) (xy 89.421893 -280.516419) (xy 89.463623 -280.483141) (xy 89.509847 -280.456454)
			(xy 89.559532 -280.436954) (xy 89.611569 -280.425077) (xy 89.664794 -280.421088) (xy 89.718019 -280.425077)
			(xy 89.770056 -280.436954) (xy 89.819741 -280.456454) (xy 89.865965 -280.483141) (xy 89.907695 -280.516419)
			(xy 89.943999 -280.555546) (xy 89.974066 -280.599646) (xy 89.997224 -280.647735) (xy 90.012956 -280.698738)
			(xy 90.020911 -280.751517) (xy 90.02141 -280.778204) (xy 92.127832 -280.778204) (xy 92.128331 -280.751517)
			(xy 92.136286 -280.698738) (xy 92.152018 -280.647735) (xy 92.175176 -280.599646) (xy 92.205243 -280.555546)
			(xy 92.241547 -280.516419) (xy 92.283277 -280.483141) (xy 92.329501 -280.456454) (xy 92.379186 -280.436954)
			(xy 92.431223 -280.425077) (xy 92.484448 -280.421088) (xy 92.537673 -280.425077) (xy 92.58971 -280.436954)
			(xy 92.639395 -280.456454) (xy 92.685619 -280.483141) (xy 92.727349 -280.516419) (xy 92.763653 -280.555546)
			(xy 92.79372 -280.599646) (xy 92.816878 -280.647735) (xy 92.83261 -280.698738) (xy 92.840565 -280.751517)
			(xy 92.841064 -280.7782) (xy 94.947505 -280.7782) (xy 94.951483 -280.725127) (xy 94.963325 -280.67324)
			(xy 94.982769 -280.623698) (xy 95.00938 -280.577607) (xy 95.042562 -280.535996) (xy 95.081576 -280.499796)
			(xy 95.125549 -280.469815) (xy 95.1735 -280.446723) (xy 95.224356 -280.431035) (xy 95.276983 -280.423102)
			(xy 95.303594 -280.422604) (xy 95.328541 -280.422967) (xy 95.377946 -280.429942) (xy 95.42589 -280.443755)
			(xy 95.471432 -280.464136) (xy 95.513678 -280.490683) (xy 95.551798 -280.522876) (xy 95.585042 -280.560082)
			(xy 95.59925 -280.580592) (xy 95.947992 -280.580592) (xy 95.962219 -280.560099) (xy 95.99547 -280.522908)
			(xy 96.03359 -280.490729) (xy 96.075834 -280.464192) (xy 96.121371 -280.443817) (xy 96.169308 -280.430006)
			(xy 96.218704 -280.423028) (xy 96.243648 -280.422604) (xy 96.270257 -280.423097) (xy 96.32288 -280.431035)
			(xy 96.373733 -280.446727) (xy 96.421679 -280.469822) (xy 96.465648 -280.499805) (xy 96.504657 -280.536006)
			(xy 96.537836 -280.577615) (xy 96.564443 -280.623705) (xy 96.583885 -280.673246) (xy 96.595726 -280.72513)
			(xy 96.599703 -280.7782) (xy 96.595726 -280.83127) (xy 96.583885 -280.883154) (xy 96.564443 -280.932695)
			(xy 96.537836 -280.978785) (xy 96.504657 -281.020394) (xy 96.465648 -281.056595) (xy 96.421679 -281.086578)
			(xy 96.373733 -281.109673) (xy 96.32288 -281.125365) (xy 96.270257 -281.133303) (xy 96.243648 -281.133804)
			(xy 96.218702 -281.133405) (xy 96.169299 -281.126437) (xy 96.121356 -281.112629) (xy 96.075814 -281.092255)
			(xy 96.033568 -281.065713) (xy 95.995447 -281.033525) (xy 95.962201 -280.996324) (xy 95.947992 -280.975816)
			(xy 95.59925 -280.975816) (xy 95.585063 -280.996338) (xy 95.551805 -281.033527) (xy 95.513677 -281.065705)
			(xy 95.471427 -281.092238) (xy 95.425884 -281.112608) (xy 95.377941 -281.126413) (xy 95.32854 -281.133384)
			(xy 95.303594 -281.133804) (xy 95.276983 -281.133298) (xy 95.224356 -281.125365) (xy 95.1735 -281.109677)
			(xy 95.125549 -281.086585) (xy 95.081576 -281.056604) (xy 95.042562 -281.020404) (xy 95.00938 -280.978793)
			(xy 94.982769 -280.932702) (xy 94.963325 -280.88316) (xy 94.951483 -280.831273) (xy 94.947505 -280.7782)
			(xy 92.841064 -280.7782) (xy 92.841064 -280.778204) (xy 92.840538 -280.805641) (xy 92.832106 -280.859863)
			(xy 92.815486 -280.91216) (xy 92.803726 -280.936954) (xy 92.976192 -281.23515) (xy 93.001084 -281.238452)
			(xy 93.026456 -281.242339) (xy 93.075838 -281.256335) (xy 93.122704 -281.277264) (xy 93.166086 -281.304694)
			(xy 93.205089 -281.338059) (xy 93.238908 -281.37667) (xy 93.266843 -281.419729) (xy 93.288318 -281.466347)
			(xy 93.30289 -281.515561) (xy 93.310258 -281.566357) (xy 93.31071 -281.59202) (xy 93.310211 -281.618707)
			(xy 93.302256 -281.671486) (xy 93.286524 -281.722489) (xy 93.263366 -281.770578) (xy 93.233299 -281.814678)
			(xy 93.196995 -281.853805) (xy 93.155265 -281.887083) (xy 93.109041 -281.91377) (xy 93.059356 -281.93327)
			(xy 93.007319 -281.945147) (xy 92.954094 -281.949136) (xy 92.900869 -281.945147) (xy 92.848832 -281.93327)
			(xy 92.799147 -281.91377) (xy 92.752923 -281.887083) (xy 92.711193 -281.853805) (xy 92.674889 -281.814678)
			(xy 92.644822 -281.770578) (xy 92.621664 -281.722489) (xy 92.605932 -281.671486) (xy 92.597977 -281.618707)
			(xy 92.597478 -281.59202) (xy 92.597478 -281.591512) (xy 92.597871 -281.56831) (xy 92.603933 -281.522303)
			(xy 92.615905 -281.47747) (xy 92.624402 -281.455876) (xy 92.634054 -281.432762) (xy 92.461588 -281.134058)
			(xy 92.434798 -281.131831) (xy 92.382278 -281.120378) (xy 92.332071 -281.101172) (xy 92.285317 -281.074647)
			(xy 92.243073 -281.041404) (xy 92.206299 -281.002197) (xy 92.175826 -280.957914) (xy 92.152346 -280.909559)
			(xy 92.13639 -280.858227) (xy 92.128321 -280.805081) (xy 92.127832 -280.778204) (xy 90.02141 -280.778204)
			(xy 90.020902 -280.805081) (xy 90.012834 -280.858226) (xy 89.996879 -280.909558) (xy 89.973401 -280.957913)
			(xy 89.942931 -281.002197) (xy 89.906159 -281.041406) (xy 89.863919 -281.074651) (xy 89.817167 -281.10118)
			(xy 89.766963 -281.12039) (xy 89.714444 -281.131848) (xy 89.687654 -281.134058) (xy 89.515188 -281.432508)
			(xy 89.52484 -281.455622) (xy 89.533362 -281.477297) (xy 89.545366 -281.522298) (xy 89.551402 -281.568479)
			(xy 89.551764 -281.591766) (xy 89.551764 -281.592) (xy 90.718421 -281.592) (xy 90.722399 -281.53893)
			(xy 90.734241 -281.487045) (xy 90.753684 -281.437505) (xy 90.780293 -281.391416) (xy 90.813474 -281.349807)
			(xy 90.852486 -281.313609) (xy 90.896457 -281.283629) (xy 90.944406 -281.260538) (xy 90.99526 -281.24485)
			(xy 91.047885 -281.236918) (xy 91.074494 -281.23642) (xy 91.09944 -281.23682) (xy 91.148841 -281.243793)
			(xy 91.196783 -281.257603) (xy 91.242324 -281.277978) (xy 91.284569 -281.304519) (xy 91.322691 -281.336704)
			(xy 91.355939 -281.373902) (xy 91.37015 -281.394408) (xy 91.718638 -281.394408) (xy 91.732841 -281.373897)
			(xy 91.766095 -281.336706) (xy 91.80422 -281.304527) (xy 91.846467 -281.277992) (xy 91.892008 -281.257621)
			(xy 91.939949 -281.243813) (xy 91.989349 -281.236841) (xy 92.014294 -281.23642) (xy 92.040909 -281.236852)
			(xy 92.093544 -281.244785) (xy 92.14441 -281.260474) (xy 92.192368 -281.283569) (xy 92.236349 -281.313554)
			(xy 92.27537 -281.349759) (xy 92.308558 -281.391375) (xy 92.335173 -281.437474) (xy 92.354621 -281.487024)
			(xy 92.366466 -281.538919) (xy 92.370444 -281.592) (xy 92.366466 -281.645081) (xy 92.354621 -281.696976)
			(xy 92.335173 -281.746526) (xy 92.308558 -281.792625) (xy 92.27537 -281.834241) (xy 92.236349 -281.870446)
			(xy 92.192368 -281.900431) (xy 92.14441 -281.923526) (xy 92.093544 -281.939215) (xy 92.040909 -281.947148)
			(xy 92.014294 -281.94762) (xy 91.989349 -281.947179) (xy 91.939949 -281.940217) (xy 91.892007 -281.926417)
			(xy 91.846465 -281.906049) (xy 91.804218 -281.879513) (xy 91.766097 -281.847332) (xy 91.732849 -281.810137)
			(xy 91.718638 -281.789632) (xy 91.37015 -281.789632) (xy 91.355968 -281.810157) (xy 91.322709 -281.847346)
			(xy 91.28458 -281.879523) (xy 91.242329 -281.906056) (xy 91.196785 -281.926425) (xy 91.148842 -281.94023)
			(xy 91.09944 -281.9472) (xy 91.074494 -281.94762) (xy 91.047885 -281.947082) (xy 90.99526 -281.93915)
			(xy 90.944406 -281.923462) (xy 90.896457 -281.900371) (xy 90.852486 -281.870391) (xy 90.813474 -281.834193)
			(xy 90.780293 -281.792584) (xy 90.753684 -281.746495) (xy 90.734241 -281.696955) (xy 90.722399 -281.64507)
			(xy 90.718421 -281.592) (xy 89.551764 -281.592) (xy 89.551764 -281.59202) (xy 89.551265 -281.618707)
			(xy 89.54331 -281.671486) (xy 89.527578 -281.722489) (xy 89.50442 -281.770578) (xy 89.474353 -281.814678)
			(xy 89.438049 -281.853805) (xy 89.396319 -281.887083) (xy 89.350095 -281.91377) (xy 89.30041 -281.93327)
			(xy 89.248373 -281.945147) (xy 89.195148 -281.949136) (xy 89.141923 -281.945147) (xy 89.089886 -281.93327)
			(xy 89.040201 -281.91377) (xy 88.993977 -281.887083) (xy 88.952247 -281.853805) (xy 88.915943 -281.814678)
			(xy 88.885876 -281.770578) (xy 88.862718 -281.722489) (xy 88.846986 -281.671486) (xy 88.839031 -281.618707)
			(xy 88.838532 -281.59202) (xy 87.672164 -281.59202) (xy 87.67175 -281.617689) (xy 87.664399 -281.668498)
			(xy 87.649838 -281.717728) (xy 87.628368 -281.764361) (xy 87.600432 -281.807433) (xy 87.566608 -281.846053)
			(xy 87.527596 -281.879424) (xy 87.484201 -281.906856) (xy 87.437321 -281.92778) (xy 87.387925 -281.941766)
			(xy 87.362538 -281.945588) (xy 87.337646 -281.94889) (xy 87.165688 -282.246578) (xy 87.17534 -282.269692)
			(xy 87.183855 -282.291279) (xy 87.195829 -282.336114) (xy 87.201879 -282.382125) (xy 87.202264 -282.405328)
			(xy 87.202264 -282.405836) (xy 87.428578 -282.405836) (xy 87.429077 -282.379149) (xy 87.437032 -282.32637)
			(xy 87.452764 -282.275367) (xy 87.475922 -282.227278) (xy 87.505989 -282.183178) (xy 87.542293 -282.144051)
			(xy 87.584023 -282.110773) (xy 87.630247 -282.084086) (xy 87.679932 -282.064586) (xy 87.731969 -282.052709)
			(xy 87.785194 -282.04872) (xy 87.838419 -282.052709) (xy 87.890456 -282.064586) (xy 87.940141 -282.084086)
			(xy 87.986365 -282.110773) (xy 88.028095 -282.144051) (xy 88.064399 -282.183178) (xy 88.094466 -282.227278)
			(xy 88.117624 -282.275367) (xy 88.133356 -282.32637) (xy 88.141311 -282.379149) (xy 88.141809 -282.4058)
			(xy 88.369113 -282.4058) (xy 88.373091 -282.352723) (xy 88.384936 -282.300833) (xy 88.404383 -282.251287)
			(xy 88.430997 -282.205194) (xy 88.464185 -282.163583) (xy 88.503205 -282.127383) (xy 88.547184 -282.097404)
			(xy 88.595141 -282.074315) (xy 88.646003 -282.058632) (xy 88.698635 -282.050705) (xy 88.725248 -282.050236)
			(xy 88.750193 -282.050664) (xy 88.799593 -282.057631) (xy 88.847535 -282.071435) (xy 88.893076 -282.091806)
			(xy 88.935322 -282.118342) (xy 88.973444 -282.150524) (xy 89.006693 -282.187719) (xy 89.020904 -282.208224)
			(xy 89.369392 -282.208224) (xy 89.383629 -282.187738) (xy 89.416877 -282.150546) (xy 89.454995 -282.118365)
			(xy 89.497237 -282.091826) (xy 89.542773 -282.071451) (xy 89.590709 -282.057638) (xy 89.640105 -282.05066)
			(xy 89.665048 -282.050236) (xy 89.69166 -282.050665) (xy 89.744288 -282.058604) (xy 89.795145 -282.074297)
			(xy 89.843095 -282.097395) (xy 89.887068 -282.12738) (xy 89.926081 -282.163584) (xy 89.959262 -282.205197)
			(xy 89.985872 -282.251291) (xy 90.005315 -282.300836) (xy 90.017157 -282.352725) (xy 90.021135 -282.4058)
			(xy 90.017157 -282.458875) (xy 90.005315 -282.510764) (xy 89.985872 -282.560309) (xy 89.959262 -282.606403)
			(xy 89.926081 -282.648016) (xy 89.887068 -282.68422) (xy 89.843095 -282.714206) (xy 89.795145 -282.737303)
			(xy 89.744288 -282.752996) (xy 89.69166 -282.760935) (xy 89.665048 -282.761436) (xy 89.640103 -282.761023)
			(xy 89.590701 -282.754055) (xy 89.542759 -282.740249) (xy 89.497217 -282.719876) (xy 89.454971 -282.693337)
			(xy 89.41685 -282.661152) (xy 89.383602 -282.623954) (xy 89.369392 -282.603448) (xy 89.020904 -282.603448)
			(xy 89.00666 -282.623929) (xy 88.973415 -282.661123) (xy 88.935298 -282.693305) (xy 88.893057 -282.719845)
			(xy 88.847522 -282.740221) (xy 88.799587 -282.754034) (xy 88.750191 -282.761012) (xy 88.725248 -282.761436)
			(xy 88.698635 -282.760895) (xy 88.646003 -282.752968) (xy 88.595141 -282.737285) (xy 88.547184 -282.714196)
			(xy 88.503205 -282.684217) (xy 88.464185 -282.648017) (xy 88.430997 -282.606406) (xy 88.404383 -282.560313)
			(xy 88.384936 -282.510767) (xy 88.373091 -282.458877) (xy 88.369113 -282.4058) (xy 88.141809 -282.4058)
			(xy 88.14181 -282.405836) (xy 88.141441 -282.429175) (xy 88.135342 -282.475454) (xy 88.12324 -282.520537)
			(xy 88.114632 -282.542234) (xy 88.10498 -282.565602) (xy 88.277192 -282.863036) (xy 88.30183 -282.866338)
			(xy 88.327237 -282.870094) (xy 88.376658 -282.88407) (xy 88.423564 -282.904989) (xy 88.466985 -282.932419)
			(xy 88.506023 -282.965793) (xy 88.539871 -283.004421) (xy 88.567829 -283.047504) (xy 88.58932 -283.094151)
			(xy 88.603898 -283.143398) (xy 88.611263 -283.194226) (xy 88.61171 -283.219906) (xy 90.717878 -283.219906)
			(xy 90.71828 -283.194236) (xy 90.725628 -283.143425) (xy 90.740188 -283.094192) (xy 90.761658 -283.047558)
			(xy 90.789595 -283.004484) (xy 90.82342 -282.965863) (xy 90.862435 -282.932492) (xy 90.905833 -282.905062)
			(xy 90.952717 -282.884139) (xy 91.002116 -282.870157) (xy 91.027504 -282.866338) (xy 91.052396 -282.863036)
			(xy 91.224608 -282.565094) (xy 91.214956 -282.54198) (xy 91.206462 -282.520385) (xy 91.19448 -282.475554)
			(xy 91.188422 -282.429546) (xy 91.188032 -282.406344) (xy 91.188032 -282.405836) (xy 91.188531 -282.379149)
			(xy 91.196486 -282.32637) (xy 91.212218 -282.275367) (xy 91.235376 -282.227278) (xy 91.265443 -282.183178)
			(xy 91.301747 -282.144051) (xy 91.343477 -282.110773) (xy 91.389701 -282.084086) (xy 91.439386 -282.064586)
			(xy 91.491423 -282.052709) (xy 91.544648 -282.04872) (xy 91.597873 -282.052709) (xy 91.64991 -282.064586)
			(xy 91.699595 -282.084086) (xy 91.745819 -282.110773) (xy 91.787549 -282.144051) (xy 91.823853 -282.183178)
			(xy 91.85392 -282.227278) (xy 91.877078 -282.275367) (xy 91.89281 -282.32637) (xy 91.900765 -282.379149)
			(xy 91.901264 -282.405836) (xy 93.067632 -282.405836) (xy 93.068101 -282.380169) (xy 93.075444 -282.329362)
			(xy 93.089998 -282.280134) (xy 93.111461 -282.233501) (xy 93.13939 -282.190429) (xy 93.173208 -282.151808)
			(xy 93.212215 -282.118436) (xy 93.255605 -282.091004) (xy 93.302481 -282.070077) (xy 93.351873 -282.05609)
			(xy 93.377258 -282.052268) (xy 93.40215 -282.048966) (xy 93.574108 -281.751786) (xy 93.564456 -281.728418)
			(xy 93.555872 -281.706714) (xy 93.54379 -281.66163) (xy 93.537677 -281.615357) (xy 93.537278 -281.59202)
			(xy 93.537777 -281.565333) (xy 93.545732 -281.512554) (xy 93.561464 -281.461551) (xy 93.584622 -281.413462)
			(xy 93.614689 -281.369362) (xy 93.650993 -281.330235) (xy 93.692723 -281.296957) (xy 93.738947 -281.27027)
			(xy 93.788632 -281.25077) (xy 93.840669 -281.238893) (xy 93.893894 -281.234904) (xy 93.947119 -281.238893)
			(xy 93.999156 -281.25077) (xy 94.048841 -281.27027) (xy 94.095065 -281.296957) (xy 94.136795 -281.330235)
			(xy 94.173099 -281.369362) (xy 94.203166 -281.413462) (xy 94.226324 -281.461551) (xy 94.242056 -281.512554)
			(xy 94.250011 -281.565333) (xy 94.25051 -281.59202) (xy 94.250142 -281.617691) (xy 94.24279 -281.668504)
			(xy 94.228227 -281.717738) (xy 94.206752 -281.764374) (xy 94.178812 -281.807447) (xy 94.144982 -281.846069)
			(xy 94.105964 -281.879439) (xy 94.062562 -281.906868) (xy 94.015676 -281.927789) (xy 93.966274 -281.94177)
			(xy 93.940884 -281.945588) (xy 93.915992 -281.94889) (xy 93.744034 -282.24607) (xy 93.753686 -282.269438)
			(xy 93.762259 -282.291147) (xy 93.774344 -282.336229) (xy 93.780462 -282.3825) (xy 93.780864 -282.405836)
			(xy 94.946978 -282.405836) (xy 94.947408 -282.380167) (xy 94.954752 -282.329356) (xy 94.969307 -282.280125)
			(xy 94.990774 -282.23349) (xy 95.018707 -282.190417) (xy 95.05253 -282.151795) (xy 95.091543 -282.118423)
			(xy 95.134938 -282.090993) (xy 95.181819 -282.07007) (xy 95.231217 -282.056088) (xy 95.256604 -282.052268)
			(xy 95.281496 -282.048966) (xy 95.453708 -281.751278) (xy 95.444056 -281.728164) (xy 95.435557 -281.706571)
			(xy 95.423577 -281.661739) (xy 95.417521 -281.61573) (xy 95.417132 -281.592528) (xy 95.417132 -281.59202)
			(xy 95.417631 -281.565333) (xy 95.425586 -281.512554) (xy 95.441318 -281.461551) (xy 95.464476 -281.413462)
			(xy 95.494543 -281.369362) (xy 95.530847 -281.330235) (xy 95.572577 -281.296957) (xy 95.618801 -281.27027)
			(xy 95.668486 -281.25077) (xy 95.720523 -281.238893) (xy 95.773748 -281.234904) (xy 95.826973 -281.238893)
			(xy 95.87901 -281.25077) (xy 95.928695 -281.27027) (xy 95.974919 -281.296957) (xy 96.016649 -281.330235)
			(xy 96.052953 -281.369362) (xy 96.08302 -281.413462) (xy 96.106178 -281.461551) (xy 96.12191 -281.512554)
			(xy 96.129865 -281.565333) (xy 96.130364 -281.59202) (xy 97.296732 -281.59202) (xy 97.297187 -281.566352)
			(xy 97.304532 -281.515545) (xy 97.319087 -281.466316) (xy 97.340552 -281.419684) (xy 97.368483 -281.376612)
			(xy 97.402303 -281.337991) (xy 97.441311 -281.304619) (xy 97.484702 -281.277187) (xy 97.531579 -281.256261)
			(xy 97.580973 -281.242274) (xy 97.606358 -281.238452) (xy 97.63125 -281.23515) (xy 97.803208 -280.93797)
			(xy 97.793556 -280.914602) (xy 97.784997 -280.892888) (xy 97.772906 -280.847809) (xy 97.766782 -280.80154)
			(xy 97.766378 -280.778204) (xy 97.766877 -280.751517) (xy 97.774832 -280.698738) (xy 97.790564 -280.647735)
			(xy 97.813722 -280.599646) (xy 97.843789 -280.555546) (xy 97.880093 -280.516419) (xy 97.921823 -280.483141)
			(xy 97.968047 -280.456454) (xy 98.017732 -280.436954) (xy 98.069769 -280.425077) (xy 98.122994 -280.421088)
			(xy 98.176219 -280.425077) (xy 98.228256 -280.436954) (xy 98.277941 -280.456454) (xy 98.324165 -280.483141)
			(xy 98.365895 -280.516419) (xy 98.402199 -280.555546) (xy 98.432266 -280.599646) (xy 98.455424 -280.647735)
			(xy 98.471156 -280.698738) (xy 98.479111 -280.751517) (xy 98.47961 -280.778204) (xy 100.585778 -280.778204)
			(xy 100.586277 -280.751517) (xy 100.594232 -280.698738) (xy 100.609964 -280.647735) (xy 100.633122 -280.599646)
			(xy 100.663189 -280.555546) (xy 100.699493 -280.516419) (xy 100.741223 -280.483141) (xy 100.787447 -280.456454)
			(xy 100.837132 -280.436954) (xy 100.889169 -280.425077) (xy 100.942394 -280.421088) (xy 100.995619 -280.425077)
			(xy 101.047656 -280.436954) (xy 101.097341 -280.456454) (xy 101.143565 -280.483141) (xy 101.185295 -280.516419)
			(xy 101.221599 -280.555546) (xy 101.251666 -280.599646) (xy 101.274824 -280.647735) (xy 101.290556 -280.698738)
			(xy 101.298511 -280.751517) (xy 101.29901 -280.778204) (xy 103.405178 -280.778204) (xy 103.405677 -280.751517)
			(xy 103.413632 -280.698738) (xy 103.429364 -280.647735) (xy 103.452522 -280.599646) (xy 103.482589 -280.555546)
			(xy 103.518893 -280.516419) (xy 103.560623 -280.483141) (xy 103.606847 -280.456454) (xy 103.656532 -280.436954)
			(xy 103.708569 -280.425077) (xy 103.761794 -280.421088) (xy 103.815019 -280.425077) (xy 103.867056 -280.436954)
			(xy 103.916741 -280.456454) (xy 103.962965 -280.483141) (xy 104.004695 -280.516419) (xy 104.040999 -280.555546)
			(xy 104.071066 -280.599646) (xy 104.094224 -280.647735) (xy 104.109956 -280.698738) (xy 104.117911 -280.751517)
			(xy 104.11841 -280.778204) (xy 104.344978 -280.778204) (xy 104.345378 -280.752534) (xy 104.352727 -280.701722)
			(xy 104.367287 -280.65249) (xy 104.388757 -280.605855) (xy 104.416694 -280.562782) (xy 104.45052 -280.52416)
			(xy 104.489535 -280.49079) (xy 104.532933 -280.46336) (xy 104.579816 -280.442437) (xy 104.629216 -280.428455)
			(xy 104.654604 -280.424636) (xy 104.679496 -280.421334) (xy 104.851708 -280.123392) (xy 104.842056 -280.100278)
			(xy 104.833561 -280.078683) (xy 104.82158 -280.033852) (xy 104.815522 -279.987844) (xy 104.815132 -279.964642)
			(xy 104.815132 -279.964134) (xy 104.815631 -279.937447) (xy 104.823586 -279.884668) (xy 104.839318 -279.833665)
			(xy 104.862476 -279.785576) (xy 104.892543 -279.741476) (xy 104.928847 -279.702349) (xy 104.970577 -279.669071)
			(xy 105.016801 -279.642384) (xy 105.066486 -279.622884) (xy 105.118523 -279.611007) (xy 105.171748 -279.607018)
			(xy 105.224973 -279.611007) (xy 105.27701 -279.622884) (xy 105.326695 -279.642384) (xy 105.372919 -279.669071)
			(xy 105.414649 -279.702349) (xy 105.450953 -279.741476) (xy 105.48102 -279.785576) (xy 105.504178 -279.833665)
			(xy 105.51991 -279.884668) (xy 105.527865 -279.937447) (xy 105.528363 -279.9641) (xy 336.778935 -279.9641)
			(xy 336.782912 -279.911035) (xy 336.794752 -279.859155) (xy 336.814192 -279.809619) (xy 336.840798 -279.763534)
			(xy 336.873974 -279.721928) (xy 336.91298 -279.685731) (xy 336.956946 -279.655752) (xy 337.004888 -279.632659)
			(xy 337.055736 -279.61697) (xy 337.108355 -279.609034) (xy 337.134962 -279.608534) (xy 337.159931 -279.608984)
			(xy 337.209379 -279.615973) (xy 337.257364 -279.629805) (xy 337.302945 -279.650209) (xy 337.345227 -279.676784)
			(xy 337.383378 -279.709007) (xy 337.416651 -279.746247) (xy 337.430872 -279.766776) (xy 337.778852 -279.766776)
			(xy 337.793037 -279.746219) (xy 337.826308 -279.708968) (xy 337.864462 -279.676736) (xy 337.906749 -279.650157)
			(xy 337.952338 -279.629755) (xy 338.000332 -279.615929) (xy 338.049789 -279.608952) (xy 338.074762 -279.608534)
			(xy 338.10138 -279.608936) (xy 338.154021 -279.616865) (xy 338.204892 -279.632552) (xy 338.252857 -279.655646)
			(xy 338.296844 -279.685631) (xy 338.33587 -279.721838) (xy 338.369063 -279.763457) (xy 338.395682 -279.809559)
			(xy 338.415132 -279.859114) (xy 338.426979 -279.911014) (xy 338.430958 -279.9641) (xy 338.430955 -279.964134)
			(xy 344.297 -279.964134) (xy 344.297499 -279.937447) (xy 344.305454 -279.884668) (xy 344.321186 -279.833665)
			(xy 344.344344 -279.785576) (xy 344.374411 -279.741476) (xy 344.410715 -279.702349) (xy 344.452445 -279.669071)
			(xy 344.498669 -279.642384) (xy 344.548354 -279.622884) (xy 344.600391 -279.611007) (xy 344.653616 -279.607018)
			(xy 344.706841 -279.611007) (xy 344.758878 -279.622884) (xy 344.808563 -279.642384) (xy 344.854787 -279.669071)
			(xy 344.896517 -279.702349) (xy 344.932821 -279.741476) (xy 344.962888 -279.785576) (xy 344.986046 -279.833665)
			(xy 345.001778 -279.884668) (xy 345.009733 -279.937447) (xy 345.010232 -279.964134) (xy 345.00972 -279.991571)
			(xy 345.001283 -280.045794) (xy 344.984657 -280.098091) (xy 344.972894 -280.122884) (xy 345.14536 -280.421334)
			(xy 345.170252 -280.424636) (xy 345.19563 -280.428485) (xy 345.245011 -280.442489) (xy 345.291876 -280.463426)
			(xy 345.335256 -280.490862) (xy 345.374258 -280.524231) (xy 345.408074 -280.562845) (xy 345.436008 -280.605907)
			(xy 345.457483 -280.652527) (xy 345.472056 -280.701743) (xy 345.479425 -280.75254) (xy 345.479878 -280.778204)
			(xy 345.479379 -280.804891) (xy 345.471424 -280.85767) (xy 345.455692 -280.908673) (xy 345.432534 -280.956762)
			(xy 345.402467 -281.000862) (xy 345.366163 -281.039989) (xy 345.324433 -281.073267) (xy 345.278209 -281.099954)
			(xy 345.228524 -281.119454) (xy 345.176487 -281.131331) (xy 345.123262 -281.13532) (xy 345.070037 -281.131331)
			(xy 345.018 -281.119454) (xy 344.968315 -281.099954) (xy 344.922091 -281.073267) (xy 344.880361 -281.039989)
			(xy 344.844057 -281.000862) (xy 344.81399 -280.956762) (xy 344.790832 -280.908673) (xy 344.7751 -280.85767)
			(xy 344.767145 -280.804891) (xy 344.766646 -280.778204) (xy 344.766999 -280.754864) (xy 344.773105 -280.708585)
			(xy 344.785213 -280.663503) (xy 344.793824 -280.641806) (xy 344.803476 -280.618438) (xy 344.630756 -280.319988)
			(xy 344.603956 -280.317857) (xy 344.551429 -280.306397) (xy 344.501217 -280.287182) (xy 344.454459 -280.260647)
			(xy 344.412214 -280.227393) (xy 344.375439 -280.188175) (xy 344.344969 -280.14388) (xy 344.321494 -280.095513)
			(xy 344.305545 -280.044171) (xy 344.297484 -279.991016) (xy 344.297 -279.964134) (xy 338.430955 -279.964134)
			(xy 338.426979 -280.017186) (xy 338.415132 -280.069086) (xy 338.395682 -280.118641) (xy 338.369063 -280.164743)
			(xy 338.33587 -280.206362) (xy 338.296844 -280.242569) (xy 338.252857 -280.272554) (xy 338.204892 -280.295648)
			(xy 338.154021 -280.311335) (xy 338.10138 -280.319264) (xy 338.074762 -280.319734) (xy 338.049792 -280.31928)
			(xy 338.000344 -280.312293) (xy 337.952359 -280.298463) (xy 337.906777 -280.27806) (xy 337.864496 -280.251486)
			(xy 337.826344 -280.219262) (xy 337.793072 -280.182021) (xy 337.778852 -280.161492) (xy 337.430872 -280.161492)
			(xy 337.416661 -280.18203) (xy 337.383396 -280.219284) (xy 337.345247 -280.251518) (xy 337.302964 -280.278099)
			(xy 337.257379 -280.298505) (xy 337.209388 -280.312334) (xy 337.159934 -280.319315) (xy 337.134962 -280.319734)
			(xy 337.108355 -280.319166) (xy 337.055736 -280.31123) (xy 337.004888 -280.295541) (xy 336.956946 -280.272448)
			(xy 336.91298 -280.242469) (xy 336.873974 -280.206272) (xy 336.840798 -280.164666) (xy 336.814192 -280.118581)
			(xy 336.794752 -280.069045) (xy 336.782912 -280.017165) (xy 336.778935 -279.9641) (xy 105.528363 -279.9641)
			(xy 105.528364 -279.964134) (xy 105.527866 -279.989833) (xy 105.520482 -280.040697) (xy 105.505873 -280.089975)
			(xy 105.484341 -280.136644) (xy 105.456333 -280.17974) (xy 105.422427 -280.218368) (xy 105.383328 -280.251728)
			(xy 105.339844 -280.27913) (xy 105.292877 -280.300005) (xy 105.243399 -280.313922) (xy 105.217976 -280.317702)
			(xy 105.193084 -280.321004) (xy 105.02138 -280.618438) (xy 105.031032 -280.641806) (xy 105.039598 -280.663517)
			(xy 105.051685 -280.708598) (xy 105.057807 -280.754868) (xy 105.05821 -280.7782) (xy 105.285305 -280.7782)
			(xy 105.289283 -280.725127) (xy 105.301125 -280.67324) (xy 105.320569 -280.623698) (xy 105.34718 -280.577607)
			(xy 105.380362 -280.535996) (xy 105.419376 -280.499796) (xy 105.463349 -280.469815) (xy 105.5113 -280.446723)
			(xy 105.562156 -280.431035) (xy 105.614783 -280.423102) (xy 105.641394 -280.422604) (xy 105.666341 -280.422967)
			(xy 105.715746 -280.429942) (xy 105.76369 -280.443755) (xy 105.809232 -280.464136) (xy 105.851478 -280.490683)
			(xy 105.889598 -280.522876) (xy 105.922842 -280.560082) (xy 105.93705 -280.580592) (xy 106.285538 -280.580592)
			(xy 106.299736 -280.560078) (xy 106.332991 -280.522888) (xy 106.371117 -280.490709) (xy 106.413365 -280.464175)
			(xy 106.458907 -280.443804) (xy 106.506849 -280.429997) (xy 106.556249 -280.423025) (xy 106.581194 -280.422604)
			(xy 106.607808 -280.423068) (xy 106.660441 -280.431001) (xy 106.711304 -280.446689) (xy 106.75926 -280.469783)
			(xy 106.803239 -280.499767) (xy 106.842258 -280.53597) (xy 106.875445 -280.577585) (xy 106.902059 -280.623681)
			(xy 106.921505 -280.673229) (xy 106.933349 -280.725121) (xy 106.937327 -280.7782) (xy 334.429405 -280.7782)
			(xy 334.433382 -280.72513) (xy 334.445224 -280.673246) (xy 334.464665 -280.623706) (xy 334.491273 -280.577617)
			(xy 334.524452 -280.536008) (xy 334.563462 -280.499808) (xy 334.607431 -280.469826) (xy 334.655377 -280.446732)
			(xy 334.70623 -280.431041) (xy 334.758853 -280.423104) (xy 334.785462 -280.422604) (xy 334.810408 -280.422992)
			(xy 334.859812 -280.429962) (xy 334.907756 -280.443771) (xy 334.953298 -280.464147) (xy 334.995544 -280.490691)
			(xy 335.033664 -280.52288) (xy 335.066909 -280.560083) (xy 335.081118 -280.580592) (xy 335.429606 -280.580592)
			(xy 335.443824 -280.560092) (xy 335.477076 -280.522902) (xy 335.515198 -280.490723) (xy 335.557443 -280.464186)
			(xy 335.602982 -280.443813) (xy 335.65092 -280.430003) (xy 335.700318 -280.423027) (xy 335.725262 -280.422604)
			(xy 335.751877 -280.423066) (xy 335.804514 -280.430995) (xy 335.855381 -280.44668) (xy 335.903342 -280.469772)
			(xy 335.947325 -280.499755) (xy 335.986347 -280.535959) (xy 336.019538 -280.577575) (xy 336.046155 -280.623672)
			(xy 336.065603 -280.673223) (xy 336.077449 -280.725118) (xy 336.081427 -280.7782) (xy 336.077449 -280.831282)
			(xy 336.065603 -280.883177) (xy 336.046155 -280.932728) (xy 336.019538 -280.978825) (xy 335.986347 -281.020441)
			(xy 335.947325 -281.056645) (xy 335.903342 -281.086628) (xy 335.855381 -281.10972) (xy 335.804514 -281.125405)
			(xy 335.751877 -281.133334) (xy 335.725262 -281.133804) (xy 335.700316 -281.133395) (xy 335.650914 -281.126428)
			(xy 335.602971 -281.112622) (xy 335.557429 -281.092249) (xy 335.515182 -281.065709) (xy 335.477062 -281.033523)
			(xy 335.443816 -280.996323) (xy 335.429606 -280.975816) (xy 335.081118 -280.975816) (xy 335.066887 -280.996306)
			(xy 335.033637 -281.033496) (xy 334.995517 -281.065676) (xy 334.953274 -281.092213) (xy 334.907738 -281.112588)
			(xy 334.859801 -281.126401) (xy 334.810405 -281.13338) (xy 334.785462 -281.133804) (xy 334.758853 -281.133296)
			(xy 334.70623 -281.125359) (xy 334.655377 -281.109668) (xy 334.607431 -281.086574) (xy 334.563462 -281.056592)
			(xy 334.524452 -281.020392) (xy 334.491273 -280.978783) (xy 334.464665 -280.932694) (xy 334.445224 -280.883154)
			(xy 334.433382 -280.83127) (xy 334.429405 -280.7782) (xy 106.937327 -280.7782) (xy 106.933349 -280.831279)
			(xy 106.921505 -280.883171) (xy 106.902059 -280.932719) (xy 106.875445 -280.978815) (xy 106.842258 -281.02043)
			(xy 106.803239 -281.056633) (xy 106.75926 -281.086617) (xy 106.711304 -281.109711) (xy 106.660441 -281.125399)
			(xy 106.607808 -281.133332) (xy 106.581194 -281.133804) (xy 106.556249 -281.13337) (xy 106.506848 -281.126408)
			(xy 106.458905 -281.112607) (xy 106.413363 -281.092238) (xy 106.371117 -281.065701) (xy 106.332995 -281.033519)
			(xy 106.299748 -280.996322) (xy 106.285538 -280.975816) (xy 105.93705 -280.975816) (xy 105.922863 -280.996338)
			(xy 105.889605 -281.033527) (xy 105.851477 -281.065705) (xy 105.809227 -281.092238) (xy 105.763684 -281.112608)
			(xy 105.715741 -281.126413) (xy 105.66634 -281.133384) (xy 105.641394 -281.133804) (xy 105.614783 -281.133298)
			(xy 105.562156 -281.125365) (xy 105.5113 -281.109677) (xy 105.463349 -281.086585) (xy 105.419376 -281.056604)
			(xy 105.380362 -281.020404) (xy 105.34718 -280.978793) (xy 105.320569 -280.932702) (xy 105.301125 -280.88316)
			(xy 105.289283 -280.831273) (xy 105.285305 -280.7782) (xy 105.05821 -280.7782) (xy 105.05821 -280.778204)
			(xy 105.057711 -280.804891) (xy 105.049756 -280.85767) (xy 105.034024 -280.908673) (xy 105.010866 -280.956762)
			(xy 104.980799 -281.000862) (xy 104.944495 -281.039989) (xy 104.902765 -281.073267) (xy 104.856541 -281.099954)
			(xy 104.806856 -281.119454) (xy 104.754819 -281.131331) (xy 104.701594 -281.13532) (xy 104.648369 -281.131331)
			(xy 104.596332 -281.119454) (xy 104.546647 -281.099954) (xy 104.500423 -281.073267) (xy 104.458693 -281.039989)
			(xy 104.422389 -281.000862) (xy 104.392322 -280.956762) (xy 104.369164 -280.908673) (xy 104.353432 -280.85767)
			(xy 104.345477 -280.804891) (xy 104.344978 -280.778204) (xy 104.11841 -280.778204) (xy 104.11841 -280.778712)
			(xy 104.118026 -280.801914) (xy 104.11196 -280.847921) (xy 104.099985 -280.892755) (xy 104.091486 -280.914348)
			(xy 104.081834 -280.937462) (xy 104.254046 -281.23515) (xy 104.278938 -281.238452) (xy 104.304317 -281.242297)
			(xy 104.353699 -281.2563) (xy 104.400565 -281.277236) (xy 104.443946 -281.304672) (xy 104.482948 -281.338042)
			(xy 104.516765 -281.376656) (xy 104.544699 -281.419719) (xy 104.566173 -281.46634) (xy 104.580745 -281.515558)
			(xy 104.588112 -281.566355) (xy 104.588564 -281.59202) (xy 105.754932 -281.59202) (xy 105.755431 -281.565333)
			(xy 105.763386 -281.512554) (xy 105.779118 -281.461551) (xy 105.802276 -281.413462) (xy 105.832343 -281.369362)
			(xy 105.868647 -281.330235) (xy 105.910377 -281.296957) (xy 105.956601 -281.27027) (xy 106.006286 -281.25077)
			(xy 106.058323 -281.238893) (xy 106.111548 -281.234904) (xy 106.164773 -281.238893) (xy 106.21681 -281.25077)
			(xy 106.266495 -281.27027) (xy 106.312719 -281.296957) (xy 106.354449 -281.330235) (xy 106.390753 -281.369362)
			(xy 106.42082 -281.413462) (xy 106.443978 -281.461551) (xy 106.45971 -281.512554) (xy 106.467665 -281.565333)
			(xy 106.468164 -281.59202) (xy 106.467786 -281.615359) (xy 106.46169 -281.661637) (xy 106.449592 -281.706721)
			(xy 106.440986 -281.728418) (xy 106.431334 -281.751786) (xy 106.603292 -282.048966) (xy 106.628184 -282.052268)
			(xy 106.653559 -282.05614) (xy 106.702942 -282.070137) (xy 106.749809 -282.091067) (xy 106.793192 -282.118499)
			(xy 106.832195 -282.151865) (xy 106.866013 -282.190477) (xy 106.893948 -282.233538) (xy 106.915423 -282.280158)
			(xy 106.929993 -282.329375) (xy 106.937359 -282.380172) (xy 106.93781 -282.405836) (xy 334.4291 -282.405836)
			(xy 334.429597 -282.38017) (xy 334.436939 -282.329366) (xy 334.451491 -282.280139) (xy 334.472952 -282.233509)
			(xy 334.500878 -282.190438) (xy 334.534693 -282.151817) (xy 334.573696 -282.118445) (xy 334.617082 -282.091011)
			(xy 334.663954 -282.070083) (xy 334.713343 -282.056092) (xy 334.738726 -282.052268) (xy 334.763618 -282.048966)
			(xy 334.935576 -281.751278) (xy 334.925924 -281.728164) (xy 334.917424 -281.706571) (xy 334.905444 -281.661739)
			(xy 334.899389 -281.61573) (xy 334.899 -281.592528) (xy 334.899 -281.59202) (xy 334.899499 -281.565333)
			(xy 334.907454 -281.512554) (xy 334.923186 -281.461551) (xy 334.946344 -281.413462) (xy 334.976411 -281.369362)
			(xy 335.012715 -281.330235) (xy 335.054445 -281.296957) (xy 335.100669 -281.27027) (xy 335.150354 -281.25077)
			(xy 335.202391 -281.238893) (xy 335.255616 -281.234904) (xy 335.308841 -281.238893) (xy 335.360878 -281.25077)
			(xy 335.410563 -281.27027) (xy 335.456787 -281.296957) (xy 335.498517 -281.330235) (xy 335.534821 -281.369362)
			(xy 335.564888 -281.413462) (xy 335.588046 -281.461551) (xy 335.603778 -281.512554) (xy 335.611733 -281.565333)
			(xy 335.612232 -281.59202) (xy 336.7786 -281.59202) (xy 336.779082 -281.566353) (xy 336.786427 -281.515549)
			(xy 336.800981 -281.466322) (xy 336.822443 -281.419692) (xy 336.850371 -281.376621) (xy 336.884187 -281.338)
			(xy 336.923192 -281.304628) (xy 336.966579 -281.277195) (xy 337.013452 -281.256266) (xy 337.062842 -281.242276)
			(xy 337.088226 -281.238452) (xy 337.113118 -281.23515) (xy 337.285584 -280.936954) (xy 337.273807 -280.912165)
			(xy 337.257162 -280.859872) (xy 337.248747 -280.805643) (xy 337.248246 -280.778204) (xy 337.248745 -280.751517)
			(xy 337.2567 -280.698738) (xy 337.272432 -280.647735) (xy 337.29559 -280.599646) (xy 337.325657 -280.555546)
			(xy 337.361961 -280.516419) (xy 337.403691 -280.483141) (xy 337.449915 -280.456454) (xy 337.4996 -280.436954)
			(xy 337.551637 -280.425077) (xy 337.604862 -280.421088) (xy 337.658087 -280.425077) (xy 337.710124 -280.436954)
			(xy 337.759809 -280.456454) (xy 337.806033 -280.483141) (xy 337.847763 -280.516419) (xy 337.884067 -280.555546)
			(xy 337.914134 -280.599646) (xy 337.937292 -280.647735) (xy 337.953024 -280.698738) (xy 337.960979 -280.751517)
			(xy 337.961478 -280.778204) (xy 340.0679 -280.778204) (xy 340.068399 -280.751517) (xy 340.076354 -280.698738)
			(xy 340.092086 -280.647735) (xy 340.115244 -280.599646) (xy 340.145311 -280.555546) (xy 340.181615 -280.516419)
			(xy 340.223345 -280.483141) (xy 340.269569 -280.456454) (xy 340.319254 -280.436954) (xy 340.371291 -280.425077)
			(xy 340.424516 -280.421088) (xy 340.477741 -280.425077) (xy 340.529778 -280.436954) (xy 340.579463 -280.456454)
			(xy 340.625687 -280.483141) (xy 340.667417 -280.516419) (xy 340.703721 -280.555546) (xy 340.733788 -280.599646)
			(xy 340.756946 -280.647735) (xy 340.772678 -280.698738) (xy 340.780633 -280.751517) (xy 340.781132 -280.7782)
			(xy 342.887605 -280.7782) (xy 342.891582 -280.72513) (xy 342.903424 -280.673246) (xy 342.922865 -280.623706)
			(xy 342.949473 -280.577617) (xy 342.982652 -280.536008) (xy 343.021662 -280.499808) (xy 343.065631 -280.469826)
			(xy 343.113577 -280.446732) (xy 343.16443 -280.431041) (xy 343.217053 -280.423104) (xy 343.243662 -280.422604)
			(xy 343.268608 -280.422992) (xy 343.318012 -280.429962) (xy 343.365956 -280.443771) (xy 343.411498 -280.464147)
			(xy 343.453744 -280.490691) (xy 343.491864 -280.52288) (xy 343.525109 -280.560083) (xy 343.539318 -280.580592)
			(xy 343.88806 -280.580592) (xy 343.902244 -280.560067) (xy 343.935501 -280.522878) (xy 343.97363 -280.4907)
			(xy 344.01588 -280.464167) (xy 344.061424 -280.443798) (xy 344.109368 -280.429993) (xy 344.15877 -280.423023)
			(xy 344.183716 -280.422604) (xy 344.210327 -280.423094) (xy 344.262954 -280.431029) (xy 344.31381 -280.446718)
			(xy 344.361761 -280.469812) (xy 344.405733 -280.499794) (xy 344.444747 -280.535994) (xy 344.477929 -280.577605)
			(xy 344.504539 -280.623697) (xy 344.523983 -280.67324) (xy 344.535825 -280.725127) (xy 344.539803 -280.7782)
			(xy 344.535825 -280.831273) (xy 344.523983 -280.88316) (xy 344.504539 -280.932703) (xy 344.477929 -280.978795)
			(xy 344.444747 -281.020406) (xy 344.405733 -281.056606) (xy 344.361761 -281.086588) (xy 344.31381 -281.109682)
			(xy 344.262954 -281.125371) (xy 344.210327 -281.133306) (xy 344.183716 -281.133804) (xy 344.158769 -281.13343)
			(xy 344.109365 -281.126457) (xy 344.061421 -281.112645) (xy 344.015879 -281.092266) (xy 343.973633 -281.065721)
			(xy 343.935514 -281.03353) (xy 343.902269 -280.996325) (xy 343.88806 -280.975816) (xy 343.539318 -280.975816)
			(xy 343.525087 -280.996306) (xy 343.491837 -281.033496) (xy 343.453717 -281.065676) (xy 343.411474 -281.092213)
			(xy 343.365938 -281.112588) (xy 343.318001 -281.126401) (xy 343.268605 -281.13338) (xy 343.243662 -281.133804)
			(xy 343.217053 -281.133296) (xy 343.16443 -281.125359) (xy 343.113577 -281.109668) (xy 343.065631 -281.086574)
			(xy 343.021662 -281.056592) (xy 342.982652 -281.020392) (xy 342.949473 -280.978783) (xy 342.922865 -280.932694)
			(xy 342.903424 -280.883154) (xy 342.891582 -280.83127) (xy 342.887605 -280.7782) (xy 340.781132 -280.7782)
			(xy 340.781132 -280.778204) (xy 340.780609 -280.805641) (xy 340.772176 -280.859863) (xy 340.755555 -280.91216)
			(xy 340.743794 -280.936954) (xy 340.91626 -281.23515) (xy 340.941152 -281.238452) (xy 340.966533 -281.242286)
			(xy 341.015915 -281.256291) (xy 341.062781 -281.277228) (xy 341.106162 -281.304666) (xy 341.145164 -281.338037)
			(xy 341.17898 -281.376653) (xy 341.206914 -281.419716) (xy 341.228388 -281.466339) (xy 341.242959 -281.515557)
			(xy 341.250326 -281.566355) (xy 341.250778 -281.59202) (xy 341.250279 -281.618707) (xy 341.242324 -281.671486)
			(xy 341.226592 -281.722489) (xy 341.203434 -281.770578) (xy 341.173367 -281.814678) (xy 341.137063 -281.853805)
			(xy 341.095333 -281.887083) (xy 341.049109 -281.91377) (xy 340.999424 -281.93327) (xy 340.947387 -281.945147)
			(xy 340.894162 -281.949136) (xy 340.840937 -281.945147) (xy 340.7889 -281.93327) (xy 340.739215 -281.91377)
			(xy 340.692991 -281.887083) (xy 340.651261 -281.853805) (xy 340.614957 -281.814678) (xy 340.58489 -281.770578)
			(xy 340.561732 -281.722489) (xy 340.546 -281.671486) (xy 340.538045 -281.618707) (xy 340.537546 -281.59202)
			(xy 340.537546 -281.591512) (xy 340.537941 -281.56831) (xy 340.544003 -281.522304) (xy 340.555974 -281.47747)
			(xy 340.56447 -281.455876) (xy 340.574122 -281.432762) (xy 340.401656 -281.134058) (xy 340.374864 -281.131858)
			(xy 340.322342 -281.120401) (xy 340.272136 -281.101191) (xy 340.225382 -281.074662) (xy 340.183139 -281.041416)
			(xy 340.146365 -281.002206) (xy 340.115893 -280.957921) (xy 340.092413 -280.909563) (xy 340.076458 -280.858229)
			(xy 340.068389 -280.805082) (xy 340.0679 -280.778204) (xy 337.961478 -280.778204) (xy 337.960907 -280.805078)
			(xy 337.95284 -280.858217) (xy 337.93689 -280.909544) (xy 337.913417 -280.957895) (xy 337.882954 -281.002176)
			(xy 337.84619 -281.041384) (xy 337.803958 -281.07463) (xy 337.757215 -281.101162) (xy 337.70702 -281.120378)
			(xy 337.654509 -281.131843) (xy 337.627722 -281.134058) (xy 337.455256 -281.432508) (xy 337.464908 -281.455622)
			(xy 337.473428 -281.477298) (xy 337.485433 -281.522298) (xy 337.49147 -281.568479) (xy 337.491832 -281.591766)
			(xy 337.491832 -281.592) (xy 338.658521 -281.592) (xy 338.662498 -281.538933) (xy 338.674339 -281.487051)
			(xy 338.69378 -281.437513) (xy 338.720386 -281.391426) (xy 338.753564 -281.349818) (xy 338.792572 -281.31362)
			(xy 338.836539 -281.28364) (xy 338.884483 -281.260546) (xy 338.935333 -281.244856) (xy 338.987954 -281.23692)
			(xy 339.014562 -281.23642) (xy 339.039507 -281.236845) (xy 339.088907 -281.243813) (xy 339.136848 -281.257618)
			(xy 339.182389 -281.27799) (xy 339.224635 -281.304527) (xy 339.262757 -281.336709) (xy 339.296006 -281.373903)
			(xy 339.310218 -281.394408) (xy 339.658706 -281.394408) (xy 339.672929 -281.373912) (xy 339.70618 -281.336721)
			(xy 339.744301 -281.304541) (xy 339.786545 -281.278004) (xy 339.832083 -281.25763) (xy 339.880021 -281.243819)
			(xy 339.929418 -281.236843) (xy 339.954362 -281.23642) (xy 339.980978 -281.23685) (xy 340.033618 -281.244779)
			(xy 340.084487 -281.260465) (xy 340.13245 -281.283558) (xy 340.176435 -281.313542) (xy 340.215459 -281.349748)
			(xy 340.248651 -281.391365) (xy 340.275269 -281.437465) (xy 340.294719 -281.487018) (xy 340.306565 -281.538916)
			(xy 340.310544 -281.592) (xy 340.306565 -281.645084) (xy 340.294719 -281.696982) (xy 340.275269 -281.746535)
			(xy 340.248651 -281.792635) (xy 340.215459 -281.834252) (xy 340.176435 -281.870458) (xy 340.13245 -281.900442)
			(xy 340.084487 -281.923535) (xy 340.033618 -281.939221) (xy 339.980978 -281.94715) (xy 339.954362 -281.94762)
			(xy 339.929417 -281.947204) (xy 339.880015 -281.940237) (xy 339.832072 -281.926432) (xy 339.78653 -281.90606)
			(xy 339.744284 -281.879521) (xy 339.706163 -281.847337) (xy 339.672916 -281.810139) (xy 339.658706 -281.789632)
			(xy 339.310218 -281.789632) (xy 339.295992 -281.810126) (xy 339.262741 -281.847315) (xy 339.224619 -281.879494)
			(xy 339.182376 -281.906031) (xy 339.136839 -281.926405) (xy 339.088902 -281.940217) (xy 339.039505 -281.947196)
			(xy 339.014562 -281.94762) (xy 338.987954 -281.94708) (xy 338.935333 -281.939144) (xy 338.884483 -281.923454)
			(xy 338.836539 -281.90036) (xy 338.792572 -281.87038) (xy 338.753564 -281.834182) (xy 338.720386 -281.792574)
			(xy 338.69378 -281.746487) (xy 338.674339 -281.696949) (xy 338.662498 -281.645067) (xy 338.658521 -281.592)
			(xy 337.491832 -281.592) (xy 337.491832 -281.59202) (xy 337.491333 -281.618707) (xy 337.483378 -281.671486)
			(xy 337.467646 -281.722489) (xy 337.444488 -281.770578) (xy 337.414421 -281.814678) (xy 337.378117 -281.853805)
			(xy 337.336387 -281.887083) (xy 337.290163 -281.91377) (xy 337.240478 -281.93327) (xy 337.188441 -281.945147)
			(xy 337.135216 -281.949136) (xy 337.081991 -281.945147) (xy 337.029954 -281.93327) (xy 336.980269 -281.91377)
			(xy 336.934045 -281.887083) (xy 336.892315 -281.853805) (xy 336.856011 -281.814678) (xy 336.825944 -281.770578)
			(xy 336.802786 -281.722489) (xy 336.787054 -281.671486) (xy 336.779099 -281.618707) (xy 336.7786 -281.59202)
			(xy 335.612232 -281.59202) (xy 335.611845 -281.61769) (xy 335.604494 -281.668502) (xy 335.589931 -281.717734)
			(xy 335.568459 -281.764368) (xy 335.54052 -281.807441) (xy 335.506693 -281.846062) (xy 335.467677 -281.879433)
			(xy 335.424278 -281.906863) (xy 335.377394 -281.927786) (xy 335.327994 -281.941768) (xy 335.302606 -281.945588)
			(xy 335.277714 -281.94889) (xy 335.105756 -282.246578) (xy 335.115408 -282.269692) (xy 335.123922 -282.29128)
			(xy 335.135897 -282.336115) (xy 335.141947 -282.382125) (xy 335.142332 -282.405328) (xy 335.142332 -282.405836)
			(xy 335.368646 -282.405836) (xy 335.369145 -282.379149) (xy 335.3771 -282.32637) (xy 335.392832 -282.275367)
			(xy 335.41599 -282.227278) (xy 335.446057 -282.183178) (xy 335.482361 -282.144051) (xy 335.524091 -282.110773)
			(xy 335.570315 -282.084086) (xy 335.62 -282.064586) (xy 335.672037 -282.052709) (xy 335.725262 -282.04872)
			(xy 335.778487 -282.052709) (xy 335.830524 -282.064586) (xy 335.880209 -282.084086) (xy 335.926433 -282.110773)
			(xy 335.968163 -282.144051) (xy 336.004467 -282.183178) (xy 336.034534 -282.227278) (xy 336.057692 -282.275367)
			(xy 336.073424 -282.32637) (xy 336.081379 -282.379149) (xy 336.081877 -282.4058) (xy 336.309213 -282.4058)
			(xy 336.31319 -282.352726) (xy 336.325034 -282.300839) (xy 336.344479 -282.251296) (xy 336.371091 -282.205204)
			(xy 336.404275 -282.163594) (xy 336.443291 -282.127394) (xy 336.487266 -282.097414) (xy 336.535218 -282.074323)
			(xy 336.586077 -282.058638) (xy 336.638705 -282.050708) (xy 336.665316 -282.050236) (xy 336.69026 -282.050689)
			(xy 336.739659 -282.057651) (xy 336.7876 -282.071451) (xy 336.833141 -282.091818) (xy 336.875388 -282.11835)
			(xy 336.91351 -282.150529) (xy 336.94676 -282.187721) (xy 336.960972 -282.208224) (xy 337.30946 -282.208224)
			(xy 337.323654 -282.187707) (xy 337.356909 -282.150515) (xy 337.395035 -282.118336) (xy 337.437284 -282.091801)
			(xy 337.482827 -282.071431) (xy 337.530769 -282.057625) (xy 337.580171 -282.050655) (xy 337.605116 -282.050236)
			(xy 337.631729 -282.050662) (xy 337.684361 -282.058598) (xy 337.735222 -282.074288) (xy 337.783177 -282.097384)
			(xy 337.827153 -282.127369) (xy 337.86617 -282.163573) (xy 337.899356 -282.205187) (xy 337.925968 -282.251283)
			(xy 337.945413 -282.30083) (xy 337.957257 -282.352722) (xy 337.961235 -282.4058) (xy 337.957257 -282.458878)
			(xy 337.945413 -282.51077) (xy 337.925968 -282.560317) (xy 337.899356 -282.606413) (xy 337.86617 -282.648027)
			(xy 337.827153 -282.684231) (xy 337.783177 -282.714216) (xy 337.735222 -282.737312) (xy 337.684361 -282.753002)
			(xy 337.631729 -282.760938) (xy 337.605116 -282.761436) (xy 337.58017 -282.761048) (xy 337.530767 -282.754075)
			(xy 337.482824 -282.740265) (xy 337.437283 -282.719888) (xy 337.395037 -282.693345) (xy 337.356916 -282.661157)
			(xy 337.32367 -282.623956) (xy 337.30946 -282.603448) (xy 336.960972 -282.603448) (xy 336.946749 -282.623944)
			(xy 336.9135 -282.661137) (xy 336.875379 -282.693319) (xy 336.833135 -282.719856) (xy 336.787597 -282.74023)
			(xy 336.739658 -282.75404) (xy 336.69026 -282.761014) (xy 336.665316 -282.761436) (xy 336.638705 -282.760892)
			(xy 336.586077 -282.752962) (xy 336.535218 -282.737276) (xy 336.487266 -282.714186) (xy 336.443291 -282.684206)
			(xy 336.404275 -282.648006) (xy 336.371091 -282.606396) (xy 336.344479 -282.560304) (xy 336.325034 -282.510761)
			(xy 336.31319 -282.458874) (xy 336.309213 -282.4058) (xy 336.081877 -282.4058) (xy 336.081878 -282.405836)
			(xy 336.081504 -282.429175) (xy 336.075406 -282.475454) (xy 336.063307 -282.520537) (xy 336.0547 -282.542234)
			(xy 336.045048 -282.565602) (xy 336.21726 -282.863036) (xy 336.241898 -282.866338) (xy 336.267301 -282.870119)
			(xy 336.316721 -282.884091) (xy 336.363628 -282.905006) (xy 336.407049 -282.932433) (xy 336.446088 -282.965804)
			(xy 336.479937 -283.004429) (xy 336.507896 -283.047509) (xy 336.529387 -283.094155) (xy 336.543966 -283.1434)
			(xy 336.551331 -283.194227) (xy 336.551778 -283.219906) (xy 338.657946 -283.219906) (xy 338.658376 -283.194237)
			(xy 338.665723 -283.143428) (xy 338.680281 -283.094198) (xy 338.701749 -283.047565) (xy 338.729683 -283.004493)
			(xy 338.763505 -282.965872) (xy 338.802516 -282.932501) (xy 338.84591 -282.905069) (xy 338.89279 -282.884144)
			(xy 338.942185 -282.870159) (xy 338.967572 -282.866338) (xy 338.992464 -282.863036) (xy 339.164676 -282.565094)
			(xy 339.155024 -282.54198) (xy 339.146528 -282.520385) (xy 339.134547 -282.475554) (xy 339.12849 -282.429546)
			(xy 339.1281 -282.406344) (xy 339.1281 -282.405836) (xy 339.128599 -282.379149) (xy 339.136554 -282.32637)
			(xy 339.152286 -282.275367) (xy 339.175444 -282.227278) (xy 339.205511 -282.183178) (xy 339.241815 -282.144051)
			(xy 339.283545 -282.110773) (xy 339.329769 -282.084086) (xy 339.379454 -282.064586) (xy 339.431491 -282.052709)
			(xy 339.484716 -282.04872) (xy 339.537941 -282.052709) (xy 339.589978 -282.064586) (xy 339.639663 -282.084086)
			(xy 339.685887 -282.110773) (xy 339.727617 -282.144051) (xy 339.763921 -282.183178) (xy 339.793988 -282.227278)
			(xy 339.817146 -282.275367) (xy 339.832878 -282.32637) (xy 339.840833 -282.379149) (xy 339.841332 -282.405836)
			(xy 341.0077 -282.405836) (xy 341.008197 -282.38017) (xy 341.015539 -282.329366) (xy 341.030091 -282.280139)
			(xy 341.051552 -282.233509) (xy 341.079478 -282.190438) (xy 341.113293 -282.151817) (xy 341.152296 -282.118445)
			(xy 341.195682 -282.091011) (xy 341.242554 -282.070083) (xy 341.291943 -282.056092) (xy 341.317326 -282.052268)
			(xy 341.342218 -282.048966) (xy 341.514176 -281.751786) (xy 341.504524 -281.728418) (xy 341.495939 -281.706714)
			(xy 341.483858 -281.66163) (xy 341.477745 -281.615357) (xy 341.477346 -281.59202) (xy 341.477845 -281.565333)
			(xy 341.4858 -281.512554) (xy 341.501532 -281.461551) (xy 341.52469 -281.413462) (xy 341.554757 -281.369362)
			(xy 341.591061 -281.330235) (xy 341.632791 -281.296957) (xy 341.679015 -281.27027) (xy 341.7287 -281.25077)
			(xy 341.780737 -281.238893) (xy 341.833962 -281.234904) (xy 341.887187 -281.238893) (xy 341.939224 -281.25077)
			(xy 341.988909 -281.27027) (xy 342.035133 -281.296957) (xy 342.076863 -281.330235) (xy 342.113167 -281.369362)
			(xy 342.143234 -281.413462) (xy 342.166392 -281.461551) (xy 342.182124 -281.512554) (xy 342.190079 -281.565333)
			(xy 342.190578 -281.59202) (xy 342.190152 -281.617689) (xy 342.182801 -281.668496) (xy 342.168241 -281.717725)
			(xy 342.146772 -281.764357) (xy 342.118837 -281.807429) (xy 342.085015 -281.846049) (xy 342.046004 -281.87942)
			(xy 342.002611 -281.906852) (xy 341.955733 -281.927778) (xy 341.906338 -281.941765) (xy 341.880952 -281.945588)
			(xy 341.85606 -281.94889) (xy 341.684102 -282.24607) (xy 341.693754 -282.269438) (xy 341.702325 -282.291147)
			(xy 341.714411 -282.336229) (xy 341.72053 -282.3825) (xy 341.720932 -282.405836) (xy 342.887046 -282.405836)
			(xy 342.887503 -282.380168) (xy 342.894846 -282.32936) (xy 342.909401 -282.280131) (xy 342.930865 -282.233498)
			(xy 342.958795 -282.190425) (xy 342.992615 -282.151804) (xy 343.031623 -282.118432) (xy 343.075015 -282.091)
			(xy 343.121892 -282.070075) (xy 343.171286 -282.056089) (xy 343.196672 -282.052268) (xy 343.221564 -282.048966)
			(xy 343.393776 -281.751278) (xy 343.384124 -281.728164) (xy 343.375624 -281.706571) (xy 343.363644 -281.661739)
			(xy 343.357589 -281.61573) (xy 343.3572 -281.592528) (xy 343.3572 -281.59202) (xy 343.357699 -281.565333)
			(xy 343.365654 -281.512554) (xy 343.381386 -281.461551) (xy 343.404544 -281.413462) (xy 343.434611 -281.369362)
			(xy 343.470915 -281.330235) (xy 343.512645 -281.296957) (xy 343.558869 -281.27027) (xy 343.608554 -281.25077)
			(xy 343.660591 -281.238893) (xy 343.713816 -281.234904) (xy 343.767041 -281.238893) (xy 343.819078 -281.25077)
			(xy 343.868763 -281.27027) (xy 343.914987 -281.296957) (xy 343.956717 -281.330235) (xy 343.993021 -281.369362)
			(xy 344.023088 -281.413462) (xy 344.046246 -281.461551) (xy 344.061978 -281.512554) (xy 344.069933 -281.565333)
			(xy 344.070432 -281.59202) (xy 345.2368 -281.59202) (xy 345.237282 -281.566353) (xy 345.244627 -281.515549)
			(xy 345.259181 -281.466322) (xy 345.280643 -281.419692) (xy 345.308571 -281.376621) (xy 345.342387 -281.338)
			(xy 345.381392 -281.304628) (xy 345.424779 -281.277195) (xy 345.471652 -281.256266) (xy 345.521042 -281.242276)
			(xy 345.546426 -281.238452) (xy 345.571318 -281.23515) (xy 345.743276 -280.93797) (xy 345.733624 -280.914602)
			(xy 345.725064 -280.892889) (xy 345.712974 -280.847809) (xy 345.70685 -280.80154) (xy 345.706446 -280.778204)
			(xy 345.706945 -280.751517) (xy 345.7149 -280.698738) (xy 345.730632 -280.647735) (xy 345.75379 -280.599646)
			(xy 345.783857 -280.555546) (xy 345.820161 -280.516419) (xy 345.861891 -280.483141) (xy 345.908115 -280.456454)
			(xy 345.9578 -280.436954) (xy 346.009837 -280.425077) (xy 346.063062 -280.421088) (xy 346.116287 -280.425077)
			(xy 346.168324 -280.436954) (xy 346.218009 -280.456454) (xy 346.264233 -280.483141) (xy 346.305963 -280.516419)
			(xy 346.342267 -280.555546) (xy 346.372334 -280.599646) (xy 346.395492 -280.647735) (xy 346.411224 -280.698738)
			(xy 346.419179 -280.751517) (xy 346.419678 -280.778204) (xy 348.525846 -280.778204) (xy 348.526345 -280.751517)
			(xy 348.5343 -280.698738) (xy 348.550032 -280.647735) (xy 348.57319 -280.599646) (xy 348.603257 -280.555546)
			(xy 348.639561 -280.516419) (xy 348.681291 -280.483141) (xy 348.727515 -280.456454) (xy 348.7772 -280.436954)
			(xy 348.829237 -280.425077) (xy 348.882462 -280.421088) (xy 348.935687 -280.425077) (xy 348.987724 -280.436954)
			(xy 349.037409 -280.456454) (xy 349.083633 -280.483141) (xy 349.125363 -280.516419) (xy 349.161667 -280.555546)
			(xy 349.191734 -280.599646) (xy 349.214892 -280.647735) (xy 349.230624 -280.698738) (xy 349.238579 -280.751517)
			(xy 349.239078 -280.778204) (xy 351.345246 -280.778204) (xy 351.345745 -280.751517) (xy 351.3537 -280.698738)
			(xy 351.369432 -280.647735) (xy 351.39259 -280.599646) (xy 351.422657 -280.555546) (xy 351.458961 -280.516419)
			(xy 351.500691 -280.483141) (xy 351.546915 -280.456454) (xy 351.5966 -280.436954) (xy 351.648637 -280.425077)
			(xy 351.701862 -280.421088) (xy 351.755087 -280.425077) (xy 351.807124 -280.436954) (xy 351.856809 -280.456454)
			(xy 351.903033 -280.483141) (xy 351.944763 -280.516419) (xy 351.981067 -280.555546) (xy 352.011134 -280.599646)
			(xy 352.034292 -280.647735) (xy 352.050024 -280.698738) (xy 352.057979 -280.751517) (xy 352.058478 -280.778204)
			(xy 352.285046 -280.778204) (xy 352.285474 -280.752535) (xy 352.292821 -280.701726) (xy 352.30738 -280.652496)
			(xy 352.328848 -280.605863) (xy 352.356782 -280.562791) (xy 352.390604 -280.52417) (xy 352.429616 -280.490799)
			(xy 352.47301 -280.463367) (xy 352.51989 -280.442442) (xy 352.569285 -280.428457) (xy 352.594672 -280.424636)
			(xy 352.619564 -280.421334) (xy 352.791776 -280.123392) (xy 352.782124 -280.100278) (xy 352.773628 -280.078684)
			(xy 352.761647 -280.033852) (xy 352.755589 -279.987844) (xy 352.7552 -279.964642) (xy 352.7552 -279.964134)
			(xy 352.755699 -279.937447) (xy 352.763654 -279.884668) (xy 352.779386 -279.833665) (xy 352.802544 -279.785576)
			(xy 352.832611 -279.741476) (xy 352.868915 -279.702349) (xy 352.910645 -279.669071) (xy 352.956869 -279.642384)
			(xy 353.006554 -279.622884) (xy 353.058591 -279.611007) (xy 353.111816 -279.607018) (xy 353.165041 -279.611007)
			(xy 353.217078 -279.622884) (xy 353.266763 -279.642384) (xy 353.312987 -279.669071) (xy 353.354717 -279.702349)
			(xy 353.391021 -279.741476) (xy 353.421088 -279.785576) (xy 353.444246 -279.833665) (xy 353.459978 -279.884668)
			(xy 353.467933 -279.937447) (xy 353.468432 -279.964134) (xy 353.467962 -279.989834) (xy 353.460577 -280.040701)
			(xy 353.445967 -280.089981) (xy 353.424432 -280.136652) (xy 353.396421 -280.179749) (xy 353.362512 -280.218377)
			(xy 353.323409 -280.251737) (xy 353.279921 -280.279138) (xy 353.23295 -280.300011) (xy 353.183469 -280.313924)
			(xy 353.158044 -280.317702) (xy 353.133152 -280.321004) (xy 352.961448 -280.618438) (xy 352.9711 -280.641806)
			(xy 352.979664 -280.663518) (xy 352.991752 -280.708598) (xy 352.997874 -280.754868) (xy 352.998278 -280.7782)
			(xy 353.225405 -280.7782) (xy 353.229382 -280.72513) (xy 353.241224 -280.673246) (xy 353.260665 -280.623706)
			(xy 353.287273 -280.577617) (xy 353.320452 -280.536008) (xy 353.359462 -280.499808) (xy 353.403431 -280.469826)
			(xy 353.451377 -280.446732) (xy 353.50223 -280.431041) (xy 353.554853 -280.423104) (xy 353.581462 -280.422604)
			(xy 353.606408 -280.422992) (xy 353.655812 -280.429962) (xy 353.703756 -280.443771) (xy 353.749298 -280.464147)
			(xy 353.791544 -280.490691) (xy 353.829664 -280.52288) (xy 353.862909 -280.560083) (xy 353.877118 -280.580592)
			(xy 354.225606 -280.580592) (xy 354.239824 -280.560092) (xy 354.273076 -280.522902) (xy 354.311198 -280.490723)
			(xy 354.353443 -280.464186) (xy 354.398982 -280.443813) (xy 354.44692 -280.430003) (xy 354.496318 -280.423027)
			(xy 354.521262 -280.422604) (xy 354.547877 -280.423066) (xy 354.600514 -280.430995) (xy 354.651381 -280.44668)
			(xy 354.699342 -280.469772) (xy 354.743325 -280.499755) (xy 354.782347 -280.535959) (xy 354.815538 -280.577575)
			(xy 354.842155 -280.623672) (xy 354.861603 -280.673223) (xy 354.873449 -280.725118) (xy 354.877427 -280.7782)
			(xy 354.873449 -280.831282) (xy 354.861603 -280.883177) (xy 354.842155 -280.932728) (xy 354.815538 -280.978825)
			(xy 354.782347 -281.020441) (xy 354.743325 -281.056645) (xy 354.699342 -281.086628) (xy 354.651381 -281.10972)
			(xy 354.600514 -281.125405) (xy 354.547877 -281.133334) (xy 354.521262 -281.133804) (xy 354.496316 -281.133395)
			(xy 354.446914 -281.126428) (xy 354.398971 -281.112622) (xy 354.353429 -281.092249) (xy 354.311182 -281.065709)
			(xy 354.273062 -281.033523) (xy 354.239816 -280.996323) (xy 354.225606 -280.975816) (xy 353.877118 -280.975816)
			(xy 353.862887 -280.996306) (xy 353.829637 -281.033496) (xy 353.791517 -281.065676) (xy 353.749274 -281.092213)
			(xy 353.703738 -281.112588) (xy 353.655801 -281.126401) (xy 353.606405 -281.13338) (xy 353.581462 -281.133804)
			(xy 353.554853 -281.133296) (xy 353.50223 -281.125359) (xy 353.451377 -281.109668) (xy 353.403431 -281.086574)
			(xy 353.359462 -281.056592) (xy 353.320452 -281.020392) (xy 353.287273 -280.978783) (xy 353.260665 -280.932694)
			(xy 353.241224 -280.883154) (xy 353.229382 -280.83127) (xy 353.225405 -280.7782) (xy 352.998278 -280.7782)
			(xy 352.998278 -280.778204) (xy 352.997779 -280.804891) (xy 352.989824 -280.85767) (xy 352.974092 -280.908673)
			(xy 352.950934 -280.956762) (xy 352.920867 -281.000862) (xy 352.884563 -281.039989) (xy 352.842833 -281.073267)
			(xy 352.796609 -281.099954) (xy 352.746924 -281.119454) (xy 352.694887 -281.131331) (xy 352.641662 -281.13532)
			(xy 352.588437 -281.131331) (xy 352.5364 -281.119454) (xy 352.486715 -281.099954) (xy 352.440491 -281.073267)
			(xy 352.398761 -281.039989) (xy 352.362457 -281.000862) (xy 352.33239 -280.956762) (xy 352.309232 -280.908673)
			(xy 352.2935 -280.85767) (xy 352.285545 -280.804891) (xy 352.285046 -280.778204) (xy 352.058478 -280.778204)
			(xy 352.058478 -280.778712) (xy 352.058089 -280.801914) (xy 352.052024 -280.847921) (xy 352.040051 -280.892754)
			(xy 352.031554 -280.914348) (xy 352.021902 -280.937462) (xy 352.194114 -281.23515) (xy 352.219006 -281.238452)
			(xy 352.244381 -281.242322) (xy 352.293763 -281.256321) (xy 352.340629 -281.277253) (xy 352.384011 -281.304685)
			(xy 352.423013 -281.338052) (xy 352.456831 -281.376664) (xy 352.484766 -281.419725) (xy 352.506241 -281.466344)
			(xy 352.520812 -281.51556) (xy 352.52818 -281.566356) (xy 352.528632 -281.59202) (xy 353.695 -281.59202)
			(xy 353.695499 -281.565333) (xy 353.703454 -281.512554) (xy 353.719186 -281.461551) (xy 353.742344 -281.413462)
			(xy 353.772411 -281.369362) (xy 353.808715 -281.330235) (xy 353.850445 -281.296957) (xy 353.896669 -281.27027)
			(xy 353.946354 -281.25077) (xy 353.998391 -281.238893) (xy 354.051616 -281.234904) (xy 354.104841 -281.238893)
			(xy 354.156878 -281.25077) (xy 354.206563 -281.27027) (xy 354.252787 -281.296957) (xy 354.294517 -281.330235)
			(xy 354.330821 -281.369362) (xy 354.360888 -281.413462) (xy 354.384046 -281.461551) (xy 354.399778 -281.512554)
			(xy 354.407733 -281.565333) (xy 354.408232 -281.59202) (xy 354.407856 -281.615359) (xy 354.40176 -281.661638)
			(xy 354.389661 -281.706721) (xy 354.381054 -281.728418) (xy 354.371402 -281.751786) (xy 354.54336 -282.048966)
			(xy 354.568252 -282.052268) (xy 354.593636 -282.056086) (xy 354.643019 -282.070092) (xy 354.689886 -282.091031)
			(xy 354.733268 -282.11847) (xy 354.772269 -282.151843) (xy 354.806086 -282.190461) (xy 354.834019 -282.233526)
			(xy 354.855492 -282.28015) (xy 354.870062 -282.32937) (xy 354.877427 -282.38017) (xy 354.877878 -282.405836)
			(xy 354.877379 -282.432523) (xy 354.869424 -282.485302) (xy 354.853692 -282.536305) (xy 354.830534 -282.584394)
			(xy 354.800467 -282.628494) (xy 354.764163 -282.667621) (xy 354.722433 -282.700899) (xy 354.676209 -282.727586)
			(xy 354.626524 -282.747086) (xy 354.574487 -282.758963) (xy 354.521262 -282.762952) (xy 354.468037 -282.758963)
			(xy 354.416 -282.747086) (xy 354.366315 -282.727586) (xy 354.320091 -282.700899) (xy 354.278361 -282.667621)
			(xy 354.242057 -282.628494) (xy 354.21199 -282.584394) (xy 354.188832 -282.536305) (xy 354.1731 -282.485302)
			(xy 354.165145 -282.432523) (xy 354.164646 -282.405836) (xy 354.16501 -282.382496) (xy 354.171111 -282.336218)
			(xy 354.183215 -282.291135) (xy 354.191824 -282.269438) (xy 354.201476 -282.24607) (xy 354.029518 -281.94889)
			(xy 354.004626 -281.945588) (xy 353.979245 -281.941751) (xy 353.929858 -281.927753) (xy 353.882989 -281.906821)
			(xy 353.839604 -281.879386) (xy 353.800599 -281.846015) (xy 353.766781 -281.807399) (xy 353.738847 -281.764333)
			(xy 353.717375 -281.717708) (xy 353.702809 -281.668487) (xy 353.695448 -281.617686) (xy 353.695 -281.59202)
			(xy 352.528632 -281.59202) (xy 352.528133 -281.618707) (xy 352.520178 -281.671486) (xy 352.504446 -281.722489)
			(xy 352.481288 -281.770578) (xy 352.451221 -281.814678) (xy 352.414917 -281.853805) (xy 352.373187 -281.887083)
			(xy 352.326963 -281.91377) (xy 352.277278 -281.93327) (xy 352.225241 -281.945147) (xy 352.172016 -281.949136)
			(xy 352.118791 -281.945147) (xy 352.066754 -281.93327) (xy 352.017069 -281.91377) (xy 351.970845 -281.887083)
			(xy 351.929115 -281.853805) (xy 351.892811 -281.814678) (xy 351.862744 -281.770578) (xy 351.839586 -281.722489)
			(xy 351.823854 -281.671486) (xy 351.815899 -281.618707) (xy 351.8154 -281.59202) (xy 351.815754 -281.56868)
			(xy 351.821859 -281.522401) (xy 351.833967 -281.477318) (xy 351.842578 -281.455622) (xy 351.85223 -281.432254)
			(xy 351.680526 -281.135074) (xy 351.655634 -281.131772) (xy 351.63021 -281.12798) (xy 351.580725 -281.114075)
			(xy 351.533749 -281.093208) (xy 351.490256 -281.065812) (xy 351.451149 -281.032454) (xy 351.417236 -280.993826)
			(xy 351.389222 -280.950729) (xy 351.367687 -280.904056) (xy 351.353077 -280.854774) (xy 351.345696 -280.803905)
			(xy 351.345246 -280.778204) (xy 349.239078 -280.778204) (xy 349.239078 -280.778712) (xy 349.238689 -280.801914)
			(xy 349.232624 -280.847921) (xy 349.220651 -280.892754) (xy 349.212154 -280.914348) (xy 349.202502 -280.937462)
			(xy 349.374714 -281.23515) (xy 349.399606 -281.238452) (xy 349.424981 -281.242322) (xy 349.474363 -281.256321)
			(xy 349.521229 -281.277253) (xy 349.564611 -281.304685) (xy 349.603613 -281.338052) (xy 349.637431 -281.376664)
			(xy 349.665366 -281.419725) (xy 349.686841 -281.466344) (xy 349.701412 -281.51556) (xy 349.70878 -281.566356)
			(xy 349.709232 -281.59202) (xy 349.708733 -281.618707) (xy 349.700778 -281.671486) (xy 349.685046 -281.722489)
			(xy 349.661888 -281.770578) (xy 349.631821 -281.814678) (xy 349.595517 -281.853805) (xy 349.553787 -281.887083)
			(xy 349.507563 -281.91377) (xy 349.457878 -281.93327) (xy 349.405841 -281.945147) (xy 349.352616 -281.949136)
			(xy 349.299391 -281.945147) (xy 349.247354 -281.93327) (xy 349.197669 -281.91377) (xy 349.151445 -281.887083)
			(xy 349.109715 -281.853805) (xy 349.073411 -281.814678) (xy 349.043344 -281.770578) (xy 349.020186 -281.722489)
			(xy 349.004454 -281.671486) (xy 348.996499 -281.618707) (xy 348.996 -281.59202) (xy 348.996354 -281.56868)
			(xy 349.002459 -281.522401) (xy 349.014567 -281.477318) (xy 349.023178 -281.455622) (xy 349.03283 -281.432254)
			(xy 348.861126 -281.135074) (xy 348.836234 -281.131772) (xy 348.81081 -281.12798) (xy 348.761325 -281.114075)
			(xy 348.714349 -281.093208) (xy 348.670856 -281.065812) (xy 348.631749 -281.032454) (xy 348.597836 -280.993826)
			(xy 348.569822 -280.950729) (xy 348.548287 -280.904056) (xy 348.533677 -280.854774) (xy 348.526296 -280.803905)
			(xy 348.525846 -280.778204) (xy 346.419678 -280.778204) (xy 346.419237 -280.803872) (xy 346.411889 -280.854679)
			(xy 346.39733 -280.903908) (xy 346.375863 -280.95054) (xy 346.34793 -280.993611) (xy 346.31411 -281.032232)
			(xy 346.2751 -281.065603) (xy 346.231709 -281.093036) (xy 346.184831 -281.113962) (xy 346.135438 -281.127949)
			(xy 346.110052 -281.131772) (xy 346.08516 -281.135074) (xy 345.913202 -281.432254) (xy 345.922854 -281.455622)
			(xy 345.93142 -281.477333) (xy 345.943508 -281.522414) (xy 345.949629 -281.568684) (xy 345.950032 -281.592)
			(xy 347.116897 -281.592) (xy 347.120875 -281.538924) (xy 347.132719 -281.487034) (xy 347.152164 -281.437489)
			(xy 347.178777 -281.391395) (xy 347.211963 -281.349783) (xy 347.250981 -281.313582) (xy 347.294958 -281.2836)
			(xy 347.342912 -281.260509) (xy 347.393773 -281.244822) (xy 347.446404 -281.236892) (xy 347.473016 -281.23642)
			(xy 347.49796 -281.23688) (xy 347.547358 -281.243842) (xy 347.595299 -281.257641) (xy 347.640839 -281.278007)
			(xy 347.683086 -281.304538) (xy 347.721209 -281.336715) (xy 347.754459 -281.373905) (xy 347.768672 -281.394408)
			(xy 348.11716 -281.394408) (xy 348.131349 -281.373887) (xy 348.164605 -281.336696) (xy 348.202732 -281.304518)
			(xy 348.244982 -281.277984) (xy 348.290525 -281.257614) (xy 348.338469 -281.243809) (xy 348.38787 -281.236839)
			(xy 348.412816 -281.23642) (xy 348.439428 -281.236878) (xy 348.492057 -281.244813) (xy 348.542916 -281.260503)
			(xy 348.590869 -281.283598) (xy 348.634843 -281.313581) (xy 348.673859 -281.349783) (xy 348.707042 -281.391396)
			(xy 348.733654 -281.43749) (xy 348.753098 -281.487035) (xy 348.764941 -281.538925) (xy 348.768919 -281.592)
			(xy 348.764941 -281.645075) (xy 348.753098 -281.696965) (xy 348.733654 -281.74651) (xy 348.707042 -281.792604)
			(xy 348.673859 -281.834217) (xy 348.634843 -281.870419) (xy 348.590869 -281.900402) (xy 348.542916 -281.923497)
			(xy 348.492057 -281.939187) (xy 348.439428 -281.947122) (xy 348.412816 -281.94762) (xy 348.387869 -281.947239)
			(xy 348.338466 -281.940266) (xy 348.290523 -281.926455) (xy 348.244981 -281.906077) (xy 348.202735 -281.879533)
			(xy 348.164615 -281.847343) (xy 348.131369 -281.810141) (xy 348.11716 -281.789632) (xy 347.768672 -281.789632)
			(xy 347.754476 -281.810147) (xy 347.721219 -281.847336) (xy 347.683093 -281.879513) (xy 347.640844 -281.906048)
			(xy 347.595302 -281.926418) (xy 347.547361 -281.940226) (xy 347.497961 -281.947199) (xy 347.473016 -281.94762)
			(xy 347.446404 -281.947108) (xy 347.393773 -281.939178) (xy 347.342912 -281.923491) (xy 347.294958 -281.9004)
			(xy 347.250981 -281.870418) (xy 347.211963 -281.834217) (xy 347.178777 -281.792605) (xy 347.152164 -281.746511)
			(xy 347.132719 -281.696966) (xy 347.120875 -281.645076) (xy 347.116897 -281.592) (xy 345.950032 -281.592)
			(xy 345.950032 -281.59202) (xy 345.949533 -281.618707) (xy 345.941578 -281.671486) (xy 345.925846 -281.722489)
			(xy 345.902688 -281.770578) (xy 345.872621 -281.814678) (xy 345.836317 -281.853805) (xy 345.794587 -281.887083)
			(xy 345.748363 -281.91377) (xy 345.698678 -281.93327) (xy 345.646641 -281.945147) (xy 345.593416 -281.949136)
			(xy 345.540191 -281.945147) (xy 345.488154 -281.93327) (xy 345.438469 -281.91377) (xy 345.392245 -281.887083)
			(xy 345.350515 -281.853805) (xy 345.314211 -281.814678) (xy 345.284144 -281.770578) (xy 345.260986 -281.722489)
			(xy 345.245254 -281.671486) (xy 345.237299 -281.618707) (xy 345.2368 -281.59202) (xy 344.070432 -281.59202)
			(xy 344.070041 -281.617722) (xy 344.062645 -281.668592) (xy 344.048023 -281.717874) (xy 344.026478 -281.764546)
			(xy 343.998457 -281.807642) (xy 343.96454 -281.846269) (xy 343.925429 -281.879628) (xy 343.881935 -281.907027)
			(xy 343.834958 -281.927899) (xy 343.785471 -281.941811) (xy 343.760044 -281.945588) (xy 343.735152 -281.94889)
			(xy 343.563448 -282.24607) (xy 343.5731 -282.269438) (xy 343.581673 -282.291146) (xy 343.593758 -282.336228)
			(xy 343.599876 -282.382499) (xy 343.600278 -282.405836) (xy 343.826846 -282.405836) (xy 343.827345 -282.379149)
			(xy 343.8353 -282.32637) (xy 343.851032 -282.275367) (xy 343.87419 -282.227278) (xy 343.904257 -282.183178)
			(xy 343.940561 -282.144051) (xy 343.982291 -282.110773) (xy 344.028515 -282.084086) (xy 344.0782 -282.064586)
			(xy 344.130237 -282.052709) (xy 344.183462 -282.04872) (xy 344.236687 -282.052709) (xy 344.288724 -282.064586)
			(xy 344.338409 -282.084086) (xy 344.384633 -282.110773) (xy 344.426363 -282.144051) (xy 344.462667 -282.183178)
			(xy 344.492734 -282.227278) (xy 344.515892 -282.275367) (xy 344.531624 -282.32637) (xy 344.539579 -282.379149)
			(xy 344.540077 -282.4058) (xy 344.767237 -282.4058) (xy 344.771214 -282.352735) (xy 344.783054 -282.300856)
			(xy 344.802494 -282.25132) (xy 344.829099 -282.205235) (xy 344.862275 -282.163629) (xy 344.901282 -282.127433)
			(xy 344.945247 -282.097454) (xy 344.993189 -282.074361) (xy 345.044037 -282.058672) (xy 345.096655 -282.050736)
			(xy 345.123262 -282.050236) (xy 345.148207 -282.050654) (xy 345.197608 -282.057622) (xy 345.24555 -282.071428)
			(xy 345.291091 -282.091801) (xy 345.333337 -282.118339) (xy 345.371458 -282.150522) (xy 345.404707 -282.187719)
			(xy 345.418918 -282.208224) (xy 345.767406 -282.208224) (xy 345.781634 -282.187732) (xy 345.814883 -282.15054)
			(xy 345.853004 -282.118359) (xy 345.895247 -282.091821) (xy 345.940784 -282.071447) (xy 345.988721 -282.057635)
			(xy 346.038118 -282.050659) (xy 346.063062 -282.050236) (xy 346.08968 -282.050634) (xy 346.142321 -282.058563)
			(xy 346.193193 -282.07425) (xy 346.241158 -282.097344) (xy 346.285145 -282.12733) (xy 346.324171 -282.163537)
			(xy 346.357365 -282.205156) (xy 346.383984 -282.251258) (xy 346.403434 -282.300813) (xy 346.415281 -282.352714)
			(xy 346.41926 -282.4058) (xy 346.415281 -282.458886) (xy 346.403434 -282.510787) (xy 346.383984 -282.560342)
			(xy 346.357365 -282.606444) (xy 346.324171 -282.648063) (xy 346.285145 -282.68427) (xy 346.241158 -282.714256)
			(xy 346.193193 -282.73735) (xy 346.142321 -282.753037) (xy 346.08968 -282.760966) (xy 346.063062 -282.761436)
			(xy 346.038117 -282.761012) (xy 345.988716 -282.754046) (xy 345.940774 -282.740242) (xy 345.895232 -282.719871)
			(xy 345.852986 -282.693334) (xy 345.814864 -282.66115) (xy 345.781617 -282.623954) (xy 345.767406 -282.603448)
			(xy 345.418918 -282.603448) (xy 345.404665 -282.623923) (xy 345.371421 -282.661116) (xy 345.333306 -282.693299)
			(xy 345.291067 -282.71984) (xy 345.245533 -282.740217) (xy 345.197599 -282.754031) (xy 345.148205 -282.761011)
			(xy 345.123262 -282.761436) (xy 345.096655 -282.760864) (xy 345.044037 -282.752928) (xy 344.993189 -282.737239)
			(xy 344.945247 -282.714146) (xy 344.901282 -282.684167) (xy 344.862275 -282.647971) (xy 344.829099 -282.606365)
			(xy 344.802494 -282.56028) (xy 344.783054 -282.510744) (xy 344.771214 -282.458865) (xy 344.767237 -282.4058)
			(xy 344.540077 -282.4058) (xy 344.540078 -282.405836) (xy 344.540078 -282.406344) (xy 344.539667 -282.429545)
			(xy 344.533612 -282.475551) (xy 344.521647 -282.520386) (xy 344.513154 -282.54198) (xy 344.503502 -282.565094)
			(xy 344.675714 -282.863036) (xy 344.700606 -282.866338) (xy 344.725979 -282.870221) (xy 344.77536 -282.88422)
			(xy 344.822224 -282.90515) (xy 344.865606 -282.932582) (xy 344.904608 -282.965947) (xy 344.938426 -283.004557)
			(xy 344.966361 -283.047616) (xy 344.987837 -283.094234) (xy 345.00241 -283.143448) (xy 345.009779 -283.194243)
			(xy 345.010232 -283.219906) (xy 347.1164 -283.219906) (xy 347.116869 -283.194239) (xy 347.124216 -283.143434)
			(xy 347.138771 -283.094207) (xy 347.160236 -283.047576) (xy 347.188166 -283.004506) (xy 347.221983 -282.965885)
			(xy 347.260989 -282.932513) (xy 347.304377 -282.90508) (xy 347.351251 -282.884152) (xy 347.400642 -282.870162)
			(xy 347.426026 -282.866338) (xy 347.450918 -282.863036) (xy 347.623384 -282.564586) (xy 347.611618 -282.539792)
			(xy 347.594969 -282.487502) (xy 347.586549 -282.433275) (xy 347.586046 -282.405836) (xy 347.586545 -282.379149)
			(xy 347.5945 -282.32637) (xy 347.610232 -282.275367) (xy 347.63339 -282.227278) (xy 347.663457 -282.183178)
			(xy 347.699761 -282.144051) (xy 347.741491 -282.110773) (xy 347.787715 -282.084086) (xy 347.8374 -282.064586)
			(xy 347.889437 -282.052709) (xy 347.942662 -282.04872) (xy 347.995887 -282.052709) (xy 348.047924 -282.064586)
			(xy 348.097609 -282.084086) (xy 348.143833 -282.110773) (xy 348.185563 -282.144051) (xy 348.221867 -282.183178)
			(xy 348.251934 -282.227278) (xy 348.275092 -282.275367) (xy 348.290824 -282.32637) (xy 348.298779 -282.379149)
			(xy 348.299278 -282.405836) (xy 349.465646 -282.405836) (xy 349.466103 -282.380168) (xy 349.473446 -282.32936)
			(xy 349.488001 -282.280131) (xy 349.509465 -282.233498) (xy 349.537395 -282.190425) (xy 349.571215 -282.151804)
			(xy 349.610223 -282.118432) (xy 349.653615 -282.091) (xy 349.700492 -282.070075) (xy 349.749886 -282.056089)
			(xy 349.775272 -282.052268) (xy 349.800164 -282.048966) (xy 349.972376 -281.751278) (xy 349.962724 -281.728164)
			(xy 349.954224 -281.706571) (xy 349.942244 -281.661739) (xy 349.936189 -281.61573) (xy 349.9358 -281.592528)
			(xy 349.9358 -281.59202) (xy 349.936299 -281.565333) (xy 349.944254 -281.512554) (xy 349.959986 -281.461551)
			(xy 349.983144 -281.413462) (xy 350.013211 -281.369362) (xy 350.049515 -281.330235) (xy 350.091245 -281.296957)
			(xy 350.137469 -281.27027) (xy 350.187154 -281.25077) (xy 350.239191 -281.238893) (xy 350.292416 -281.234904)
			(xy 350.345641 -281.238893) (xy 350.397678 -281.25077) (xy 350.447363 -281.27027) (xy 350.493587 -281.296957)
			(xy 350.535317 -281.330235) (xy 350.571621 -281.369362) (xy 350.601688 -281.413462) (xy 350.624846 -281.461551)
			(xy 350.640578 -281.512554) (xy 350.648533 -281.565333) (xy 350.649032 -281.59202) (xy 350.648641 -281.617722)
			(xy 350.641245 -281.668592) (xy 350.626623 -281.717874) (xy 350.605078 -281.764546) (xy 350.577057 -281.807642)
			(xy 350.54314 -281.846269) (xy 350.504029 -281.879628) (xy 350.460535 -281.907027) (xy 350.413558 -281.927899)
			(xy 350.364071 -281.941811) (xy 350.338644 -281.945588) (xy 350.313752 -281.94889) (xy 350.142048 -282.24607)
			(xy 350.1517 -282.269438) (xy 350.160273 -282.291146) (xy 350.172358 -282.336228) (xy 350.178476 -282.382499)
			(xy 350.178877 -282.4058) (xy 351.345837 -282.4058) (xy 351.349814 -282.352735) (xy 351.361654 -282.300856)
			(xy 351.381094 -282.25132) (xy 351.407699 -282.205235) (xy 351.440875 -282.163629) (xy 351.479882 -282.127433)
			(xy 351.523847 -282.097454) (xy 351.571789 -282.074361) (xy 351.622637 -282.058672) (xy 351.675255 -282.050736)
			(xy 351.701862 -282.050236) (xy 351.726807 -282.050654) (xy 351.776208 -282.057622) (xy 351.82415 -282.071428)
			(xy 351.869691 -282.091801) (xy 351.911937 -282.118339) (xy 351.950058 -282.150522) (xy 351.983307 -282.187719)
			(xy 351.997518 -282.208224) (xy 352.346006 -282.208224) (xy 352.360234 -282.187732) (xy 352.393483 -282.15054)
			(xy 352.431604 -282.118359) (xy 352.473847 -282.091821) (xy 352.519384 -282.071447) (xy 352.567321 -282.057635)
			(xy 352.616718 -282.050659) (xy 352.641662 -282.050236) (xy 352.66828 -282.050634) (xy 352.720921 -282.058563)
			(xy 352.771793 -282.07425) (xy 352.819758 -282.097344) (xy 352.863745 -282.12733) (xy 352.902771 -282.163537)
			(xy 352.935965 -282.205156) (xy 352.962584 -282.251258) (xy 352.982034 -282.300813) (xy 352.993881 -282.352714)
			(xy 352.99786 -282.4058) (xy 352.993881 -282.458886) (xy 352.982034 -282.510787) (xy 352.962584 -282.560342)
			(xy 352.935965 -282.606444) (xy 352.902771 -282.648063) (xy 352.863745 -282.68427) (xy 352.819758 -282.714256)
			(xy 352.771793 -282.73735) (xy 352.720921 -282.753037) (xy 352.66828 -282.760966) (xy 352.641662 -282.761436)
			(xy 352.616717 -282.761012) (xy 352.567316 -282.754046) (xy 352.519374 -282.740242) (xy 352.473832 -282.719871)
			(xy 352.431586 -282.693334) (xy 352.393464 -282.66115) (xy 352.360217 -282.623954) (xy 352.346006 -282.603448)
			(xy 351.997518 -282.603448) (xy 351.983265 -282.623923) (xy 351.950021 -282.661116) (xy 351.911906 -282.693299)
			(xy 351.869667 -282.71984) (xy 351.824133 -282.740217) (xy 351.776199 -282.754031) (xy 351.726805 -282.761011)
			(xy 351.701862 -282.761436) (xy 351.675255 -282.760864) (xy 351.622637 -282.752928) (xy 351.571789 -282.737239)
			(xy 351.523847 -282.714146) (xy 351.479882 -282.684167) (xy 351.440875 -282.647971) (xy 351.407699 -282.606365)
			(xy 351.381094 -282.56028) (xy 351.361654 -282.510744) (xy 351.349814 -282.458865) (xy 351.345837 -282.4058)
			(xy 350.178877 -282.4058) (xy 350.178878 -282.405836) (xy 350.178379 -282.432523) (xy 350.170424 -282.485302)
			(xy 350.154692 -282.536305) (xy 350.131534 -282.584394) (xy 350.101467 -282.628494) (xy 350.065163 -282.667621)
			(xy 350.023433 -282.700899) (xy 349.977209 -282.727586) (xy 349.927524 -282.747086) (xy 349.875487 -282.758963)
			(xy 349.822262 -282.762952) (xy 349.769037 -282.758963) (xy 349.717 -282.747086) (xy 349.667315 -282.727586)
			(xy 349.621091 -282.700899) (xy 349.579361 -282.667621) (xy 349.543057 -282.628494) (xy 349.51299 -282.584394)
			(xy 349.489832 -282.536305) (xy 349.4741 -282.485302) (xy 349.466145 -282.432523) (xy 349.465646 -282.405836)
			(xy 348.299278 -282.405836) (xy 348.298737 -282.432711) (xy 348.290665 -282.485851) (xy 348.27471 -282.537178)
			(xy 348.251234 -282.58553) (xy 348.220767 -282.629811) (xy 348.184 -282.669018) (xy 348.141765 -282.702264)
			(xy 348.09502 -282.728795) (xy 348.044823 -282.748011) (xy 347.99231 -282.759476) (xy 347.965522 -282.76169)
			(xy 347.792802 -283.06014) (xy 347.802454 -283.083508) (xy 347.811016 -283.105221) (xy 347.823106 -283.1503)
			(xy 347.829228 -283.19657) (xy 347.829632 -283.2199) (xy 348.996483 -283.2199) (xy 349.000461 -283.166822)
			(xy 349.012305 -283.11493) (xy 349.031752 -283.065382) (xy 349.058366 -283.019287) (xy 349.091553 -282.977673)
			(xy 349.130572 -282.941471) (xy 349.174551 -282.911488) (xy 349.222507 -282.888396) (xy 349.27337 -282.872709)
			(xy 349.326003 -282.864778) (xy 349.352616 -282.864306) (xy 349.377588 -282.864683) (xy 349.427041 -282.871681)
			(xy 349.475029 -282.885524) (xy 349.520611 -282.905939) (xy 349.562892 -282.932525) (xy 349.601041 -282.964761)
			(xy 349.634309 -283.002013) (xy 349.648526 -283.022548) (xy 349.996506 -283.022548) (xy 350.010744 -283.002029)
			(xy 350.044003 -282.964773) (xy 350.082147 -282.932536) (xy 350.124425 -282.905952) (xy 350.170006 -282.885543)
			(xy 350.217994 -282.871711) (xy 350.267445 -282.864727) (xy 350.292416 -282.864306) (xy 350.319027 -282.864792)
			(xy 350.371654 -282.872727) (xy 350.422511 -282.888416) (xy 350.470462 -282.91151) (xy 350.514435 -282.941492)
			(xy 350.553448 -282.977693) (xy 350.586631 -283.019304) (xy 350.613241 -283.065396) (xy 350.632685 -283.114939)
			(xy 350.644527 -283.166827) (xy 350.648505 -283.2199) (xy 350.648505 -283.219906) (xy 352.7552 -283.219906)
			(xy 352.755669 -283.194239) (xy 352.763016 -283.143434) (xy 352.777571 -283.094207) (xy 352.799036 -283.047576)
			(xy 352.826966 -283.004506) (xy 352.860783 -282.965885) (xy 352.899789 -282.932513) (xy 352.943177 -282.90508)
			(xy 352.990051 -282.884152) (xy 353.039442 -282.870162) (xy 353.064826 -282.866338) (xy 353.089718 -282.863036)
			(xy 353.262184 -282.564586) (xy 353.250418 -282.539792) (xy 353.233769 -282.487502) (xy 353.225349 -282.433275)
			(xy 353.224846 -282.405836) (xy 353.225345 -282.379149) (xy 353.2333 -282.32637) (xy 353.249032 -282.275367)
			(xy 353.27219 -282.227278) (xy 353.302257 -282.183178) (xy 353.338561 -282.144051) (xy 353.380291 -282.110773)
			(xy 353.426515 -282.084086) (xy 353.4762 -282.064586) (xy 353.528237 -282.052709) (xy 353.581462 -282.04872)
			(xy 353.634687 -282.052709) (xy 353.686724 -282.064586) (xy 353.736409 -282.084086) (xy 353.782633 -282.110773)
			(xy 353.824363 -282.144051) (xy 353.860667 -282.183178) (xy 353.890734 -282.227278) (xy 353.913892 -282.275367)
			(xy 353.929624 -282.32637) (xy 353.937579 -282.379149) (xy 353.938078 -282.405836) (xy 353.937537 -282.432711)
			(xy 353.929465 -282.485851) (xy 353.91351 -282.537178) (xy 353.890034 -282.58553) (xy 353.859567 -282.629811)
			(xy 353.8228 -282.669018) (xy 353.780565 -282.702264) (xy 353.73382 -282.728795) (xy 353.683623 -282.748011)
			(xy 353.63111 -282.759476) (xy 353.604322 -282.76169) (xy 353.431602 -283.06014) (xy 353.441254 -283.083508)
			(xy 353.449816 -283.105221) (xy 353.461906 -283.1503) (xy 353.468028 -283.19657) (xy 353.468432 -283.219906)
			(xy 353.467933 -283.246593) (xy 353.459978 -283.299372) (xy 353.444246 -283.350375) (xy 353.421088 -283.398464)
			(xy 353.391021 -283.442564) (xy 353.354717 -283.481691) (xy 353.312987 -283.514969) (xy 353.266763 -283.541656)
			(xy 353.217078 -283.561156) (xy 353.165041 -283.573033) (xy 353.111816 -283.577022) (xy 353.058591 -283.573033)
			(xy 353.006554 -283.561156) (xy 352.956869 -283.541656) (xy 352.910645 -283.514969) (xy 352.868915 -283.481691)
			(xy 352.832611 -283.442564) (xy 352.802544 -283.398464) (xy 352.779386 -283.350375) (xy 352.763654 -283.299372)
			(xy 352.755699 -283.246593) (xy 352.7552 -283.219906) (xy 350.648505 -283.219906) (xy 350.644527 -283.272973)
			(xy 350.632685 -283.324861) (xy 350.613241 -283.374404) (xy 350.586631 -283.420496) (xy 350.553448 -283.462107)
			(xy 350.514435 -283.498308) (xy 350.470462 -283.52829) (xy 350.422511 -283.551384) (xy 350.371654 -283.567073)
			(xy 350.319027 -283.575008) (xy 350.292416 -283.575506) (xy 350.267445 -283.575099) (xy 350.217994 -283.568106)
			(xy 350.170007 -283.554268) (xy 350.124425 -283.533858) (xy 350.082144 -283.507276) (xy 350.043994 -283.475045)
			(xy 350.010724 -283.437797) (xy 349.996506 -283.417264) (xy 349.648526 -283.417264) (xy 349.634272 -283.437771)
			(xy 349.601015 -283.475026) (xy 349.562873 -283.507264) (xy 349.520598 -283.533849) (xy 349.47502 -283.55426)
			(xy 349.427035 -283.568096) (xy 349.377586 -283.575083) (xy 349.352616 -283.575506) (xy 349.326003 -283.575022)
			(xy 349.27337 -283.567091) (xy 349.222507 -283.551404) (xy 349.174551 -283.528312) (xy 349.130572 -283.498329)
			(xy 349.091553 -283.462127) (xy 349.058366 -283.420513) (xy 349.031752 -283.374418) (xy 349.012305 -283.32487)
			(xy 349.000461 -283.272978) (xy 348.996483 -283.2199) (xy 347.829632 -283.2199) (xy 347.829632 -283.219906)
			(xy 347.829133 -283.246593) (xy 347.821178 -283.299372) (xy 347.805446 -283.350375) (xy 347.782288 -283.398464)
			(xy 347.752221 -283.442564) (xy 347.715917 -283.481691) (xy 347.674187 -283.514969) (xy 347.627963 -283.541656)
			(xy 347.578278 -283.561156) (xy 347.526241 -283.573033) (xy 347.473016 -283.577022) (xy 347.419791 -283.573033)
			(xy 347.367754 -283.561156) (xy 347.318069 -283.541656) (xy 347.271845 -283.514969) (xy 347.230115 -283.481691)
			(xy 347.193811 -283.442564) (xy 347.163744 -283.398464) (xy 347.140586 -283.350375) (xy 347.124854 -283.299372)
			(xy 347.116899 -283.246593) (xy 347.1164 -283.219906) (xy 345.010232 -283.219906) (xy 345.009733 -283.246593)
			(xy 345.001778 -283.299372) (xy 344.986046 -283.350375) (xy 344.962888 -283.398464) (xy 344.932821 -283.442564)
			(xy 344.896517 -283.481691) (xy 344.854787 -283.514969) (xy 344.808563 -283.541656) (xy 344.758878 -283.561156)
			(xy 344.706841 -283.573033) (xy 344.653616 -283.577022) (xy 344.600391 -283.573033) (xy 344.548354 -283.561156)
			(xy 344.498669 -283.541656) (xy 344.452445 -283.514969) (xy 344.410715 -283.481691) (xy 344.374411 -283.442564)
			(xy 344.344344 -283.398464) (xy 344.321186 -283.350375) (xy 344.305454 -283.299372) (xy 344.297499 -283.246593)
			(xy 344.297 -283.219906) (xy 344.29735 -283.196566) (xy 344.303457 -283.150287) (xy 344.315566 -283.105204)
			(xy 344.324178 -283.083508) (xy 344.33383 -283.06014) (xy 344.162126 -282.762706) (xy 344.137234 -282.759404)
			(xy 344.111798 -282.755678) (xy 344.062308 -282.741769) (xy 344.015328 -282.720897) (xy 343.971833 -282.693494)
			(xy 343.932723 -282.660129) (xy 343.898811 -282.621493) (xy 343.870799 -282.578388) (xy 343.849268 -282.531706)
			(xy 343.834665 -282.482416) (xy 343.827291 -282.43154) (xy 343.826846 -282.405836) (xy 343.600278 -282.405836)
			(xy 343.599779 -282.432523) (xy 343.591824 -282.485302) (xy 343.576092 -282.536305) (xy 343.552934 -282.584394)
			(xy 343.522867 -282.628494) (xy 343.486563 -282.667621) (xy 343.444833 -282.700899) (xy 343.398609 -282.727586)
			(xy 343.348924 -282.747086) (xy 343.296887 -282.758963) (xy 343.243662 -282.762952) (xy 343.190437 -282.758963)
			(xy 343.1384 -282.747086) (xy 343.088715 -282.727586) (xy 343.042491 -282.700899) (xy 343.000761 -282.667621)
			(xy 342.964457 -282.628494) (xy 342.93439 -282.584394) (xy 342.911232 -282.536305) (xy 342.8955 -282.485302)
			(xy 342.887545 -282.432523) (xy 342.887046 -282.405836) (xy 341.720932 -282.405836) (xy 341.720433 -282.432523)
			(xy 341.712478 -282.485302) (xy 341.696746 -282.536305) (xy 341.673588 -282.584394) (xy 341.643521 -282.628494)
			(xy 341.607217 -282.667621) (xy 341.565487 -282.700899) (xy 341.519263 -282.727586) (xy 341.469578 -282.747086)
			(xy 341.417541 -282.758963) (xy 341.364316 -282.762952) (xy 341.311091 -282.758963) (xy 341.259054 -282.747086)
			(xy 341.209369 -282.727586) (xy 341.163145 -282.700899) (xy 341.121415 -282.667621) (xy 341.085111 -282.628494)
			(xy 341.055044 -282.584394) (xy 341.031886 -282.536305) (xy 341.016154 -282.485302) (xy 341.008199 -282.432523)
			(xy 341.0077 -282.405836) (xy 339.841332 -282.405836) (xy 339.840839 -282.431513) (xy 339.833482 -282.482337)
			(xy 339.818909 -282.53158) (xy 339.797424 -282.578223) (xy 339.769469 -282.621301) (xy 339.735624 -282.659924)
			(xy 339.696589 -282.693293) (xy 339.65317 -282.720716) (xy 339.606267 -282.741627) (xy 339.556849 -282.755594)
			(xy 339.531452 -282.759404) (xy 339.50656 -282.762706) (xy 339.334602 -283.060394) (xy 339.344254 -283.083508)
			(xy 339.352772 -283.105185) (xy 339.364777 -283.150184) (xy 339.370815 -283.196365) (xy 339.371178 -283.219652)
			(xy 339.371178 -283.2199) (xy 340.538107 -283.2199) (xy 340.542084 -283.166831) (xy 340.553926 -283.114947)
			(xy 340.573367 -283.065407) (xy 340.599974 -283.019318) (xy 340.633153 -282.977709) (xy 340.672163 -282.941509)
			(xy 340.716132 -282.911528) (xy 340.764078 -282.888433) (xy 340.81493 -282.872743) (xy 340.867553 -282.864806)
			(xy 340.894162 -282.864306) (xy 340.919133 -282.864725) (xy 340.968583 -282.871715) (xy 341.016571 -282.88555)
			(xy 341.062153 -282.905958) (xy 341.104434 -282.932539) (xy 341.142584 -282.964769) (xy 341.175854 -283.002016)
			(xy 341.190072 -283.022548) (xy 341.538052 -283.022548) (xy 341.55226 -283.002007) (xy 341.585525 -282.964752)
			(xy 341.623673 -282.932517) (xy 341.665957 -282.905935) (xy 341.711543 -282.88553) (xy 341.759535 -282.871702)
			(xy 341.80899 -282.864724) (xy 341.833962 -282.864306) (xy 341.860577 -282.864764) (xy 341.913214 -282.872693)
			(xy 341.964082 -282.888378) (xy 342.012043 -282.911471) (xy 342.056026 -282.941454) (xy 342.095049 -282.977657)
			(xy 342.128239 -283.019273) (xy 342.154856 -283.065372) (xy 342.174305 -283.114922) (xy 342.186151 -283.166818)
			(xy 342.190129 -283.2199) (xy 342.186151 -283.272982) (xy 342.174305 -283.324878) (xy 342.154856 -283.374428)
			(xy 342.128239 -283.420527) (xy 342.095049 -283.462143) (xy 342.056026 -283.498346) (xy 342.012043 -283.528329)
			(xy 341.964082 -283.551422) (xy 341.913214 -283.567107) (xy 341.860577 -283.575036) (xy 341.833962 -283.575506)
			(xy 341.808992 -283.575064) (xy 341.759543 -283.568077) (xy 341.711556 -283.554245) (xy 341.665974 -283.533841)
			(xy 341.623693 -283.507265) (xy 341.585542 -283.475038) (xy 341.552271 -283.437795) (xy 341.538052 -283.417264)
			(xy 341.190072 -283.417264) (xy 341.175852 -283.437796) (xy 341.142589 -283.475051) (xy 341.104442 -283.507286)
			(xy 341.062161 -283.533869) (xy 341.016577 -283.554276) (xy 340.968587 -283.568106) (xy 340.919134 -283.575087)
			(xy 340.894162 -283.575506) (xy 340.867553 -283.574994) (xy 340.81493 -283.567057) (xy 340.764078 -283.551367)
			(xy 340.716132 -283.528272) (xy 340.672163 -283.498291) (xy 340.633153 -283.462091) (xy 340.599974 -283.420482)
			(xy 340.573367 -283.374393) (xy 340.553926 -283.324853) (xy 340.542084 -283.272969) (xy 340.538107 -283.2199)
			(xy 339.371178 -283.2199) (xy 339.371178 -283.219906) (xy 339.370679 -283.246593) (xy 339.362724 -283.299372)
			(xy 339.346992 -283.350375) (xy 339.323834 -283.398464) (xy 339.293767 -283.442564) (xy 339.257463 -283.481691)
			(xy 339.215733 -283.514969) (xy 339.169509 -283.541656) (xy 339.119824 -283.561156) (xy 339.067787 -283.573033)
			(xy 339.014562 -283.577022) (xy 338.961337 -283.573033) (xy 338.9093 -283.561156) (xy 338.859615 -283.541656)
			(xy 338.813391 -283.514969) (xy 338.771661 -283.481691) (xy 338.735357 -283.442564) (xy 338.70529 -283.398464)
			(xy 338.682132 -283.350375) (xy 338.6664 -283.299372) (xy 338.658445 -283.246593) (xy 338.657946 -283.219906)
			(xy 336.551778 -283.219906) (xy 336.551279 -283.246593) (xy 336.543324 -283.299372) (xy 336.527592 -283.350375)
			(xy 336.504434 -283.398464) (xy 336.474367 -283.442564) (xy 336.438063 -283.481691) (xy 336.396333 -283.514969)
			(xy 336.350109 -283.541656) (xy 336.300424 -283.561156) (xy 336.248387 -283.573033) (xy 336.195162 -283.577022)
			(xy 336.141937 -283.573033) (xy 336.0899 -283.561156) (xy 336.040215 -283.541656) (xy 335.993991 -283.514969)
			(xy 335.952261 -283.481691) (xy 335.915957 -283.442564) (xy 335.88589 -283.398464) (xy 335.862732 -283.350375)
			(xy 335.847 -283.299372) (xy 335.839045 -283.246593) (xy 335.838546 -283.219906) (xy 335.8389 -283.196566)
			(xy 335.845006 -283.150287) (xy 335.857113 -283.105205) (xy 335.865724 -283.083508) (xy 335.875376 -283.06014)
			(xy 335.703164 -282.762706) (xy 335.678526 -282.759404) (xy 335.653134 -282.755564) (xy 335.603716 -282.741597)
			(xy 335.556812 -282.720688) (xy 335.513392 -282.693268) (xy 335.474354 -282.659904) (xy 335.440504 -282.621286)
			(xy 335.412543 -282.578212) (xy 335.391049 -282.531573) (xy 335.376466 -282.482334) (xy 335.369096 -282.431513)
			(xy 335.368646 -282.405836) (xy 335.142332 -282.405836) (xy 335.141833 -282.432523) (xy 335.133878 -282.485302)
			(xy 335.118146 -282.536305) (xy 335.094988 -282.584394) (xy 335.064921 -282.628494) (xy 335.028617 -282.667621)
			(xy 334.986887 -282.700899) (xy 334.940663 -282.727586) (xy 334.890978 -282.747086) (xy 334.838941 -282.758963)
			(xy 334.785716 -282.762952) (xy 334.732491 -282.758963) (xy 334.680454 -282.747086) (xy 334.630769 -282.727586)
			(xy 334.584545 -282.700899) (xy 334.542815 -282.667621) (xy 334.506511 -282.628494) (xy 334.476444 -282.584394)
			(xy 334.453286 -282.536305) (xy 334.437554 -282.485302) (xy 334.429599 -282.432523) (xy 334.4291 -282.405836)
			(xy 106.93781 -282.405836) (xy 106.937311 -282.432523) (xy 106.929356 -282.485302) (xy 106.913624 -282.536305)
			(xy 106.890466 -282.584394) (xy 106.860399 -282.628494) (xy 106.824095 -282.667621) (xy 106.782365 -282.700899)
			(xy 106.736141 -282.727586) (xy 106.686456 -282.747086) (xy 106.634419 -282.758963) (xy 106.581194 -282.762952)
			(xy 106.527969 -282.758963) (xy 106.475932 -282.747086) (xy 106.426247 -282.727586) (xy 106.380023 -282.700899)
			(xy 106.338293 -282.667621) (xy 106.301989 -282.628494) (xy 106.271922 -282.584394) (xy 106.248764 -282.536305)
			(xy 106.233032 -282.485302) (xy 106.225077 -282.432523) (xy 106.224578 -282.405836) (xy 106.224939 -282.382496)
			(xy 106.231042 -282.336217) (xy 106.243146 -282.291135) (xy 106.251756 -282.269438) (xy 106.261408 -282.24607)
			(xy 106.08945 -281.94889) (xy 106.064558 -281.945588) (xy 106.039168 -281.941804) (xy 105.989781 -281.927797)
			(xy 105.942912 -281.906857) (xy 105.899528 -281.879414) (xy 105.860525 -281.846038) (xy 105.826708 -281.807415)
			(xy 105.798776 -281.764345) (xy 105.777306 -281.717716) (xy 105.76274 -281.668491) (xy 105.75538 -281.617687)
			(xy 105.754932 -281.59202) (xy 104.588564 -281.59202) (xy 104.588065 -281.618707) (xy 104.58011 -281.671486)
			(xy 104.564378 -281.722489) (xy 104.54122 -281.770578) (xy 104.511153 -281.814678) (xy 104.474849 -281.853805)
			(xy 104.433119 -281.887083) (xy 104.386895 -281.91377) (xy 104.33721 -281.93327) (xy 104.285173 -281.945147)
			(xy 104.231948 -281.949136) (xy 104.178723 -281.945147) (xy 104.126686 -281.93327) (xy 104.077001 -281.91377)
			(xy 104.030777 -281.887083) (xy 103.989047 -281.853805) (xy 103.952743 -281.814678) (xy 103.922676 -281.770578)
			(xy 103.899518 -281.722489) (xy 103.883786 -281.671486) (xy 103.875831 -281.618707) (xy 103.875332 -281.59202)
			(xy 103.875692 -281.56868) (xy 103.881795 -281.522401) (xy 103.8939 -281.477319) (xy 103.90251 -281.455622)
			(xy 103.912162 -281.432254) (xy 103.740458 -281.135074) (xy 103.715566 -281.131772) (xy 103.690146 -281.127955)
			(xy 103.640661 -281.114054) (xy 103.593685 -281.093191) (xy 103.550192 -281.065798) (xy 103.511084 -281.032443)
			(xy 103.47717 -280.993818) (xy 103.449156 -280.950723) (xy 103.42762 -280.904052) (xy 103.41301 -280.854772)
			(xy 103.405628 -280.803904) (xy 103.405178 -280.778204) (xy 101.29901 -280.778204) (xy 101.29901 -280.778712)
			(xy 101.298626 -280.801914) (xy 101.29256 -280.847921) (xy 101.280585 -280.892755) (xy 101.272086 -280.914348)
			(xy 101.262434 -280.937462) (xy 101.434646 -281.23515) (xy 101.459538 -281.238452) (xy 101.484917 -281.242297)
			(xy 101.534299 -281.2563) (xy 101.581165 -281.277236) (xy 101.624546 -281.304672) (xy 101.663548 -281.338042)
			(xy 101.697365 -281.376656) (xy 101.725299 -281.419719) (xy 101.746773 -281.46634) (xy 101.761345 -281.515558)
			(xy 101.768712 -281.566355) (xy 101.769164 -281.59202) (xy 101.768665 -281.618707) (xy 101.76071 -281.671486)
			(xy 101.744978 -281.722489) (xy 101.72182 -281.770578) (xy 101.691753 -281.814678) (xy 101.655449 -281.853805)
			(xy 101.613719 -281.887083) (xy 101.567495 -281.91377) (xy 101.51781 -281.93327) (xy 101.465773 -281.945147)
			(xy 101.412548 -281.949136) (xy 101.359323 -281.945147) (xy 101.307286 -281.93327) (xy 101.257601 -281.91377)
			(xy 101.211377 -281.887083) (xy 101.169647 -281.853805) (xy 101.133343 -281.814678) (xy 101.103276 -281.770578)
			(xy 101.080118 -281.722489) (xy 101.064386 -281.671486) (xy 101.056431 -281.618707) (xy 101.055932 -281.59202)
			(xy 101.056292 -281.56868) (xy 101.062395 -281.522401) (xy 101.0745 -281.477319) (xy 101.08311 -281.455622)
			(xy 101.092762 -281.432254) (xy 100.921058 -281.135074) (xy 100.896166 -281.131772) (xy 100.870746 -281.127955)
			(xy 100.821261 -281.114054) (xy 100.774285 -281.093191) (xy 100.730792 -281.065798) (xy 100.691684 -281.032443)
			(xy 100.65777 -280.993818) (xy 100.629756 -280.950723) (xy 100.60822 -280.904052) (xy 100.59361 -280.854772)
			(xy 100.586228 -280.803904) (xy 100.585778 -280.778204) (xy 98.47961 -280.778204) (xy 98.479228 -280.803875)
			(xy 98.471878 -280.854687) (xy 98.457316 -280.903921) (xy 98.435844 -280.950556) (xy 98.407905 -280.99363)
			(xy 98.374077 -281.032252) (xy 98.33506 -281.065622) (xy 98.29166 -281.093052) (xy 98.244774 -281.113973)
			(xy 98.195373 -281.127953) (xy 98.169984 -281.131772) (xy 98.145092 -281.135074) (xy 97.973134 -281.432254)
			(xy 97.982786 -281.455622) (xy 97.991354 -281.477332) (xy 98.003441 -281.522413) (xy 98.009561 -281.568684)
			(xy 98.009964 -281.592) (xy 99.176797 -281.592) (xy 99.180775 -281.538921) (xy 99.19262 -281.487028)
			(xy 99.212068 -281.43748) (xy 99.238684 -281.391385) (xy 99.271874 -281.349772) (xy 99.310895 -281.31357)
			(xy 99.354876 -281.28359) (xy 99.402835 -281.2605) (xy 99.4537 -281.244816) (xy 99.506334 -281.236889)
			(xy 99.532948 -281.23642) (xy 99.557892 -281.236855) (xy 99.607292 -281.243822) (xy 99.655233 -281.257625)
			(xy 99.700774 -281.277995) (xy 99.74302 -281.30453) (xy 99.781142 -281.336711) (xy 99.814392 -281.373904)
			(xy 99.828604 -281.394408) (xy 100.177092 -281.394408) (xy 100.191324 -281.373919) (xy 100.224573 -281.336727)
			(xy 100.262693 -281.304547) (xy 100.304935 -281.278009) (xy 100.350472 -281.257634) (xy 100.398408 -281.243822)
			(xy 100.447805 -281.236844) (xy 100.472748 -281.23642) (xy 100.499358 -281.236881) (xy 100.551984 -281.244819)
			(xy 100.602839 -281.260512) (xy 100.650787 -281.283608) (xy 100.694758 -281.313592) (xy 100.733769 -281.349795)
			(xy 100.766949 -281.391406) (xy 100.793558 -281.437498) (xy 100.813 -281.487041) (xy 100.824842 -281.538928)
			(xy 100.828819 -281.592) (xy 100.824842 -281.645072) (xy 100.813 -281.696959) (xy 100.793558 -281.746502)
			(xy 100.766949 -281.792594) (xy 100.733769 -281.834205) (xy 100.694758 -281.870408) (xy 100.650787 -281.900392)
			(xy 100.602839 -281.923488) (xy 100.551984 -281.939181) (xy 100.499358 -281.947119) (xy 100.472748 -281.94762)
			(xy 100.447802 -281.947214) (xy 100.3984 -281.940246) (xy 100.350457 -281.926439) (xy 100.304915 -281.906065)
			(xy 100.262669 -281.879525) (xy 100.224548 -281.847339) (xy 100.191302 -281.810139) (xy 100.177092 -281.789632)
			(xy 99.828604 -281.789632) (xy 99.814387 -281.810132) (xy 99.781134 -281.847321) (xy 99.743011 -281.8795)
			(xy 99.700766 -281.906036) (xy 99.655228 -281.926409) (xy 99.60729 -281.94022) (xy 99.557892 -281.947197)
			(xy 99.532948 -281.94762) (xy 99.506334 -281.947111) (xy 99.4537 -281.939184) (xy 99.402835 -281.9235)
			(xy 99.354876 -281.90041) (xy 99.310895 -281.87043) (xy 99.271874 -281.834228) (xy 99.238684 -281.792615)
			(xy 99.212068 -281.74652) (xy 99.19262 -281.696972) (xy 99.180775 -281.645079) (xy 99.176797 -281.592)
			(xy 98.009964 -281.592) (xy 98.009964 -281.59202) (xy 98.009465 -281.618707) (xy 98.00151 -281.671486)
			(xy 97.985778 -281.722489) (xy 97.96262 -281.770578) (xy 97.932553 -281.814678) (xy 97.896249 -281.853805)
			(xy 97.854519 -281.887083) (xy 97.808295 -281.91377) (xy 97.75861 -281.93327) (xy 97.706573 -281.945147)
			(xy 97.653348 -281.949136) (xy 97.600123 -281.945147) (xy 97.548086 -281.93327) (xy 97.498401 -281.91377)
			(xy 97.452177 -281.887083) (xy 97.410447 -281.853805) (xy 97.374143 -281.814678) (xy 97.344076 -281.770578)
			(xy 97.320918 -281.722489) (xy 97.305186 -281.671486) (xy 97.297231 -281.618707) (xy 97.296732 -281.59202)
			(xy 96.130364 -281.59202) (xy 96.129945 -281.617721) (xy 96.12255 -281.668588) (xy 96.107929 -281.717868)
			(xy 96.086387 -281.764538) (xy 96.058369 -281.807633) (xy 96.024455 -281.84626) (xy 95.985348 -281.879619)
			(xy 95.941858 -281.907019) (xy 95.894885 -281.927893) (xy 95.845402 -281.941809) (xy 95.819976 -281.945588)
			(xy 95.795084 -281.94889) (xy 95.62338 -282.24607) (xy 95.633032 -282.269438) (xy 95.641608 -282.291146)
			(xy 95.653691 -282.336228) (xy 95.659809 -282.382499) (xy 95.66021 -282.405836) (xy 95.886778 -282.405836)
			(xy 95.887277 -282.379149) (xy 95.895232 -282.32637) (xy 95.910964 -282.275367) (xy 95.934122 -282.227278)
			(xy 95.964189 -282.183178) (xy 96.000493 -282.144051) (xy 96.042223 -282.110773) (xy 96.088447 -282.084086)
			(xy 96.138132 -282.064586) (xy 96.190169 -282.052709) (xy 96.243394 -282.04872) (xy 96.296619 -282.052709)
			(xy 96.348656 -282.064586) (xy 96.398341 -282.084086) (xy 96.444565 -282.110773) (xy 96.486295 -282.144051)
			(xy 96.522599 -282.183178) (xy 96.552666 -282.227278) (xy 96.575824 -282.275367) (xy 96.591556 -282.32637)
			(xy 96.599511 -282.379149) (xy 96.600009 -282.4058) (xy 96.827137 -282.4058) (xy 96.831114 -282.352732)
			(xy 96.842956 -282.30085) (xy 96.862398 -282.251312) (xy 96.889006 -282.205225) (xy 96.922186 -282.163618)
			(xy 96.961196 -282.127421) (xy 97.005165 -282.097443) (xy 97.053111 -282.074352) (xy 97.103964 -282.058666)
			(xy 97.156586 -282.050734) (xy 97.183194 -282.050236) (xy 97.20814 -282.050629) (xy 97.257542 -282.057602)
			(xy 97.305484 -282.071413) (xy 97.351025 -282.091789) (xy 97.393271 -282.118331) (xy 97.431392 -282.150518)
			(xy 97.464639 -282.187717) (xy 97.47885 -282.208224) (xy 97.827338 -282.208224) (xy 97.841546 -282.187717)
			(xy 97.874798 -282.150525) (xy 97.912922 -282.118345) (xy 97.955169 -282.091809) (xy 98.000709 -282.071437)
			(xy 98.04865 -282.057629) (xy 98.098049 -282.050657) (xy 98.122994 -282.050236) (xy 98.14961 -282.050636)
			(xy 98.202248 -282.058569) (xy 98.253115 -282.074259) (xy 98.301076 -282.097355) (xy 98.345059 -282.127341)
			(xy 98.384081 -282.163548) (xy 98.417271 -282.205166) (xy 98.443888 -282.251267) (xy 98.463336 -282.300819)
			(xy 98.475181 -282.352717) (xy 98.47916 -282.4058) (xy 98.475181 -282.458883) (xy 98.463336 -282.510781)
			(xy 98.443888 -282.560333) (xy 98.417271 -282.606434) (xy 98.384081 -282.648052) (xy 98.345059 -282.684259)
			(xy 98.301076 -282.714245) (xy 98.253115 -282.737341) (xy 98.202248 -282.753031) (xy 98.14961 -282.760964)
			(xy 98.122994 -282.761436) (xy 98.09805 -282.760988) (xy 98.04865 -282.754026) (xy 98.000708 -282.740227)
			(xy 97.955167 -282.71986) (xy 97.91292 -282.693326) (xy 97.874798 -282.661146) (xy 97.841549 -282.623952)
			(xy 97.827338 -282.603448) (xy 97.47885 -282.603448) (xy 97.464641 -282.623954) (xy 97.431389 -282.661147)
			(xy 97.393266 -282.693328) (xy 97.35102 -282.719865) (xy 97.305479 -282.740237) (xy 97.257539 -282.754044)
			(xy 97.208139 -282.761016) (xy 97.183194 -282.761436) (xy 97.156586 -282.760866) (xy 97.103964 -282.752934)
			(xy 97.053112 -282.737248) (xy 97.005165 -282.714157) (xy 96.961196 -282.684179) (xy 96.922186 -282.647982)
			(xy 96.889006 -282.606375) (xy 96.862398 -282.560288) (xy 96.842956 -282.51075) (xy 96.831114 -282.458868)
			(xy 96.827137 -282.4058) (xy 96.600009 -282.4058) (xy 96.60001 -282.405836) (xy 96.60001 -282.406344)
			(xy 96.599604 -282.429545) (xy 96.593547 -282.475552) (xy 96.581581 -282.520386) (xy 96.573086 -282.54198)
			(xy 96.563434 -282.565094) (xy 96.735646 -282.863036) (xy 96.760538 -282.866338) (xy 96.785915 -282.870196)
			(xy 96.835296 -282.884199) (xy 96.882161 -282.905133) (xy 96.925541 -282.932568) (xy 96.964543 -282.965936)
			(xy 96.99836 -283.00455) (xy 97.026294 -283.04761) (xy 97.04777 -283.09423) (xy 97.062342 -283.143446)
			(xy 97.069711 -283.194242) (xy 97.070164 -283.219906) (xy 99.176332 -283.219906) (xy 99.176774 -283.194238)
			(xy 99.184121 -283.14343) (xy 99.198678 -283.094201) (xy 99.220145 -283.047569) (xy 99.248078 -283.004497)
			(xy 99.281898 -282.965876) (xy 99.320908 -282.932505) (xy 99.3643 -282.905072) (xy 99.411178 -282.884147)
			(xy 99.460572 -282.87016) (xy 99.485958 -282.866338) (xy 99.51085 -282.863036) (xy 99.683316 -282.564586)
			(xy 99.671546 -282.539795) (xy 99.654899 -282.487503) (xy 99.646481 -282.433275) (xy 99.645978 -282.405836)
			(xy 99.646477 -282.379149) (xy 99.654432 -282.32637) (xy 99.670164 -282.275367) (xy 99.693322 -282.227278)
			(xy 99.723389 -282.183178) (xy 99.759693 -282.144051) (xy 99.801423 -282.110773) (xy 99.847647 -282.084086)
			(xy 99.897332 -282.064586) (xy 99.949369 -282.052709) (xy 100.002594 -282.04872) (xy 100.055819 -282.052709)
			(xy 100.107856 -282.064586) (xy 100.157541 -282.084086) (xy 100.203765 -282.110773) (xy 100.245495 -282.144051)
			(xy 100.281799 -282.183178) (xy 100.311866 -282.227278) (xy 100.335024 -282.275367) (xy 100.350756 -282.32637)
			(xy 100.358711 -282.379149) (xy 100.35921 -282.405836) (xy 101.525578 -282.405836) (xy 101.526008 -282.380167)
			(xy 101.533352 -282.329356) (xy 101.547907 -282.280125) (xy 101.569374 -282.23349) (xy 101.597307 -282.190417)
			(xy 101.63113 -282.151795) (xy 101.670143 -282.118423) (xy 101.713538 -282.090993) (xy 101.760419 -282.07007)
			(xy 101.809817 -282.056088) (xy 101.835204 -282.052268) (xy 101.860096 -282.048966) (xy 102.032308 -281.751278)
			(xy 102.022656 -281.728164) (xy 102.014157 -281.706571) (xy 102.002177 -281.661739) (xy 101.996121 -281.61573)
			(xy 101.995732 -281.592528) (xy 101.995732 -281.59202) (xy 101.996231 -281.565333) (xy 102.004186 -281.512554)
			(xy 102.019918 -281.461551) (xy 102.043076 -281.413462) (xy 102.073143 -281.369362) (xy 102.109447 -281.330235)
			(xy 102.151177 -281.296957) (xy 102.197401 -281.27027) (xy 102.247086 -281.25077) (xy 102.299123 -281.238893)
			(xy 102.352348 -281.234904) (xy 102.405573 -281.238893) (xy 102.45761 -281.25077) (xy 102.507295 -281.27027)
			(xy 102.553519 -281.296957) (xy 102.595249 -281.330235) (xy 102.631553 -281.369362) (xy 102.66162 -281.413462)
			(xy 102.684778 -281.461551) (xy 102.70051 -281.512554) (xy 102.708465 -281.565333) (xy 102.708964 -281.59202)
			(xy 102.708545 -281.617721) (xy 102.70115 -281.668588) (xy 102.686529 -281.717868) (xy 102.664987 -281.764538)
			(xy 102.636969 -281.807633) (xy 102.603055 -281.84626) (xy 102.563948 -281.879619) (xy 102.520458 -281.907019)
			(xy 102.473485 -281.927893) (xy 102.424002 -281.941809) (xy 102.398576 -281.945588) (xy 102.373684 -281.94889)
			(xy 102.20198 -282.24607) (xy 102.211632 -282.269438) (xy 102.220208 -282.291146) (xy 102.232291 -282.336228)
			(xy 102.238409 -282.382499) (xy 102.238809 -282.4058) (xy 103.405737 -282.4058) (xy 103.409714 -282.352732)
			(xy 103.421556 -282.30085) (xy 103.440998 -282.251312) (xy 103.467606 -282.205225) (xy 103.500786 -282.163618)
			(xy 103.539796 -282.127421) (xy 103.583765 -282.097443) (xy 103.631711 -282.074352) (xy 103.682564 -282.058666)
			(xy 103.735186 -282.050734) (xy 103.761794 -282.050236) (xy 103.78674 -282.050629) (xy 103.836142 -282.057602)
			(xy 103.884084 -282.071413) (xy 103.929625 -282.091789) (xy 103.971871 -282.118331) (xy 104.009992 -282.150518)
			(xy 104.043239 -282.187717) (xy 104.05745 -282.208224) (xy 104.405938 -282.208224) (xy 104.420146 -282.187717)
			(xy 104.453398 -282.150525) (xy 104.491522 -282.118345) (xy 104.533769 -282.091809) (xy 104.579309 -282.071437)
			(xy 104.62725 -282.057629) (xy 104.676649 -282.050657) (xy 104.701594 -282.050236) (xy 104.72821 -282.050636)
			(xy 104.780848 -282.058569) (xy 104.831715 -282.074259) (xy 104.879676 -282.097355) (xy 104.923659 -282.127341)
			(xy 104.962681 -282.163548) (xy 104.995871 -282.205166) (xy 105.022488 -282.251267) (xy 105.041936 -282.300819)
			(xy 105.053781 -282.352717) (xy 105.05776 -282.4058) (xy 105.053781 -282.458883) (xy 105.041936 -282.510781)
			(xy 105.022488 -282.560333) (xy 104.995871 -282.606434) (xy 104.962681 -282.648052) (xy 104.923659 -282.684259)
			(xy 104.879676 -282.714245) (xy 104.831715 -282.737341) (xy 104.780848 -282.753031) (xy 104.72821 -282.760964)
			(xy 104.701594 -282.761436) (xy 104.67665 -282.760988) (xy 104.62725 -282.754026) (xy 104.579308 -282.740227)
			(xy 104.533767 -282.71986) (xy 104.49152 -282.693326) (xy 104.453398 -282.661146) (xy 104.420149 -282.623952)
			(xy 104.405938 -282.603448) (xy 104.05745 -282.603448) (xy 104.043241 -282.623954) (xy 104.009989 -282.661147)
			(xy 103.971866 -282.693328) (xy 103.92962 -282.719865) (xy 103.884079 -282.740237) (xy 103.836139 -282.754044)
			(xy 103.786739 -282.761016) (xy 103.761794 -282.761436) (xy 103.735186 -282.760866) (xy 103.682564 -282.752934)
			(xy 103.631712 -282.737248) (xy 103.583765 -282.714157) (xy 103.539796 -282.684179) (xy 103.500786 -282.647982)
			(xy 103.467606 -282.606375) (xy 103.440998 -282.560288) (xy 103.421556 -282.51075) (xy 103.409714 -282.458868)
			(xy 103.405737 -282.4058) (xy 102.238809 -282.4058) (xy 102.23881 -282.405836) (xy 102.238311 -282.432523)
			(xy 102.230356 -282.485302) (xy 102.214624 -282.536305) (xy 102.191466 -282.584394) (xy 102.161399 -282.628494)
			(xy 102.125095 -282.667621) (xy 102.083365 -282.700899) (xy 102.037141 -282.727586) (xy 101.987456 -282.747086)
			(xy 101.935419 -282.758963) (xy 101.882194 -282.762952) (xy 101.828969 -282.758963) (xy 101.776932 -282.747086)
			(xy 101.727247 -282.727586) (xy 101.681023 -282.700899) (xy 101.639293 -282.667621) (xy 101.602989 -282.628494)
			(xy 101.572922 -282.584394) (xy 101.549764 -282.536305) (xy 101.534032 -282.485302) (xy 101.526077 -282.432523)
			(xy 101.525578 -282.405836) (xy 100.35921 -282.405836) (xy 100.358732 -282.432714) (xy 100.350659 -282.48586)
			(xy 100.3347 -282.537192) (xy 100.311218 -282.585548) (xy 100.280744 -282.629832) (xy 100.243969 -282.66904)
			(xy 100.201726 -282.702285) (xy 100.154972 -282.728813) (xy 100.104766 -282.748023) (xy 100.052245 -282.75948)
			(xy 100.025454 -282.76169) (xy 99.852734 -283.06014) (xy 99.862386 -283.083508) (xy 99.87095 -283.10522)
			(xy 99.883038 -283.1503) (xy 99.88916 -283.19657) (xy 99.889564 -283.2199) (xy 101.056383 -283.2199)
			(xy 101.060361 -283.166819) (xy 101.072207 -283.114924) (xy 101.091656 -283.065374) (xy 101.118273 -283.019277)
			(xy 101.151463 -282.977662) (xy 101.190486 -282.941459) (xy 101.234469 -282.911478) (xy 101.28243 -282.888387)
			(xy 101.333297 -282.872702) (xy 101.385933 -282.864775) (xy 101.412548 -282.864306) (xy 101.437519 -282.864735)
			(xy 101.486969 -282.871724) (xy 101.534956 -282.885557) (xy 101.580538 -282.905964) (xy 101.622819 -282.932542)
			(xy 101.660969 -282.964771) (xy 101.694239 -283.002016) (xy 101.708458 -283.022548) (xy 102.056438 -283.022548)
			(xy 102.070655 -283.002014) (xy 102.103918 -282.964759) (xy 102.142065 -282.932523) (xy 102.184347 -282.90594)
			(xy 102.229932 -282.885534) (xy 102.277923 -282.871705) (xy 102.327376 -282.864725) (xy 102.352348 -282.864306)
			(xy 102.378957 -282.864795) (xy 102.431581 -282.872733) (xy 102.482434 -282.888425) (xy 102.53038 -282.91152)
			(xy 102.574349 -282.941503) (xy 102.613359 -282.977704) (xy 102.646538 -283.019314) (xy 102.673145 -283.065404)
			(xy 102.692586 -283.114945) (xy 102.704428 -283.16683) (xy 102.708405 -283.2199) (xy 102.708405 -283.219906)
			(xy 104.815132 -283.219906) (xy 104.815574 -283.194238) (xy 104.822921 -283.14343) (xy 104.837478 -283.094201)
			(xy 104.858945 -283.047569) (xy 104.886878 -283.004497) (xy 104.920698 -282.965876) (xy 104.959708 -282.932505)
			(xy 105.0031 -282.905072) (xy 105.049978 -282.884147) (xy 105.099372 -282.87016) (xy 105.124758 -282.866338)
			(xy 105.14965 -282.863036) (xy 105.322116 -282.564586) (xy 105.310346 -282.539795) (xy 105.293699 -282.487503)
			(xy 105.285281 -282.433275) (xy 105.284778 -282.405836) (xy 105.285277 -282.379149) (xy 105.293232 -282.32637)
			(xy 105.308964 -282.275367) (xy 105.332122 -282.227278) (xy 105.362189 -282.183178) (xy 105.398493 -282.144051)
			(xy 105.440223 -282.110773) (xy 105.486447 -282.084086) (xy 105.536132 -282.064586) (xy 105.588169 -282.052709)
			(xy 105.641394 -282.04872) (xy 105.694619 -282.052709) (xy 105.746656 -282.064586) (xy 105.796341 -282.084086)
			(xy 105.842565 -282.110773) (xy 105.884295 -282.144051) (xy 105.920599 -282.183178) (xy 105.950666 -282.227278)
			(xy 105.973824 -282.275367) (xy 105.989556 -282.32637) (xy 105.997511 -282.379149) (xy 105.99801 -282.405836)
			(xy 105.997532 -282.432714) (xy 105.989459 -282.48586) (xy 105.9735 -282.537192) (xy 105.950018 -282.585548)
			(xy 105.919544 -282.629832) (xy 105.882769 -282.66904) (xy 105.840526 -282.702285) (xy 105.793772 -282.728813)
			(xy 105.743566 -282.748023) (xy 105.691045 -282.75948) (xy 105.664254 -282.76169) (xy 105.491534 -283.06014)
			(xy 105.501186 -283.083508) (xy 105.50975 -283.10522) (xy 105.521838 -283.1503) (xy 105.52796 -283.19657)
			(xy 105.528364 -283.219906) (xy 105.527865 -283.246593) (xy 105.51991 -283.299372) (xy 105.504178 -283.350375)
			(xy 105.48102 -283.398464) (xy 105.450953 -283.442564) (xy 105.414649 -283.481691) (xy 105.372919 -283.514969)
			(xy 105.326695 -283.541656) (xy 105.27701 -283.561156) (xy 105.224973 -283.573033) (xy 105.171748 -283.577022)
			(xy 105.118523 -283.573033) (xy 105.066486 -283.561156) (xy 105.016801 -283.541656) (xy 104.970577 -283.514969)
			(xy 104.928847 -283.481691) (xy 104.892543 -283.442564) (xy 104.862476 -283.398464) (xy 104.839318 -283.350375)
			(xy 104.823586 -283.299372) (xy 104.815631 -283.246593) (xy 104.815132 -283.219906) (xy 102.708405 -283.219906)
			(xy 102.704428 -283.27297) (xy 102.692586 -283.324855) (xy 102.673145 -283.374396) (xy 102.646538 -283.420486)
			(xy 102.613359 -283.462096) (xy 102.574349 -283.498297) (xy 102.53038 -283.52828) (xy 102.482434 -283.551375)
			(xy 102.431581 -283.567067) (xy 102.378957 -283.575005) (xy 102.352348 -283.575506) (xy 102.327378 -283.575075)
			(xy 102.277928 -283.568086) (xy 102.229941 -283.554252) (xy 102.184359 -283.533846) (xy 102.142078 -283.507268)
			(xy 102.103927 -283.47504) (xy 102.070657 -283.437795) (xy 102.056438 -283.417264) (xy 101.708458 -283.417264)
			(xy 101.694247 -283.437803) (xy 101.660983 -283.475057) (xy 101.622834 -283.507292) (xy 101.580551 -283.533874)
			(xy 101.534966 -283.55428) (xy 101.486974 -283.568108) (xy 101.43752 -283.575088) (xy 101.412548 -283.575506)
			(xy 101.385933 -283.575025) (xy 101.333297 -283.567098) (xy 101.28243 -283.551413) (xy 101.234469 -283.528322)
			(xy 101.190486 -283.498341) (xy 101.151463 -283.462138) (xy 101.118273 -283.420523) (xy 101.091656 -283.374426)
			(xy 101.072207 -283.324876) (xy 101.060361 -283.272981) (xy 101.056383 -283.2199) (xy 99.889564 -283.2199)
			(xy 99.889564 -283.219906) (xy 99.889065 -283.246593) (xy 99.88111 -283.299372) (xy 99.865378 -283.350375)
			(xy 99.84222 -283.398464) (xy 99.812153 -283.442564) (xy 99.775849 -283.481691) (xy 99.734119 -283.514969)
			(xy 99.687895 -283.541656) (xy 99.63821 -283.561156) (xy 99.586173 -283.573033) (xy 99.532948 -283.577022)
			(xy 99.479723 -283.573033) (xy 99.427686 -283.561156) (xy 99.378001 -283.541656) (xy 99.331777 -283.514969)
			(xy 99.290047 -283.481691) (xy 99.253743 -283.442564) (xy 99.223676 -283.398464) (xy 99.200518 -283.350375)
			(xy 99.184786 -283.299372) (xy 99.176831 -283.246593) (xy 99.176332 -283.219906) (xy 97.070164 -283.219906)
			(xy 97.069665 -283.246593) (xy 97.06171 -283.299372) (xy 97.045978 -283.350375) (xy 97.02282 -283.398464)
			(xy 96.992753 -283.442564) (xy 96.956449 -283.481691) (xy 96.914719 -283.514969) (xy 96.868495 -283.541656)
			(xy 96.81881 -283.561156) (xy 96.766773 -283.573033) (xy 96.713548 -283.577022) (xy 96.660323 -283.573033)
			(xy 96.608286 -283.561156) (xy 96.558601 -283.541656) (xy 96.512377 -283.514969) (xy 96.470647 -283.481691)
			(xy 96.434343 -283.442564) (xy 96.404276 -283.398464) (xy 96.381118 -283.350375) (xy 96.365386 -283.299372)
			(xy 96.357431 -283.246593) (xy 96.356932 -283.219906) (xy 96.357287 -283.196566) (xy 96.363393 -283.150287)
			(xy 96.3755 -283.105205) (xy 96.38411 -283.083508) (xy 96.393762 -283.06014) (xy 96.222058 -282.762706)
			(xy 96.197166 -282.759404) (xy 96.171734 -282.755652) (xy 96.122244 -282.741748) (xy 96.075264 -282.72088)
			(xy 96.031768 -282.693481) (xy 95.992658 -282.660119) (xy 95.958745 -282.621485) (xy 95.930733 -282.578382)
			(xy 95.909201 -282.531702) (xy 95.894597 -282.482414) (xy 95.887223 -282.431539) (xy 95.886778 -282.405836)
			(xy 95.66021 -282.405836) (xy 95.659711 -282.432523) (xy 95.651756 -282.485302) (xy 95.636024 -282.536305)
			(xy 95.612866 -282.584394) (xy 95.582799 -282.628494) (xy 95.546495 -282.667621) (xy 95.504765 -282.700899)
			(xy 95.458541 -282.727586) (xy 95.408856 -282.747086) (xy 95.356819 -282.758963) (xy 95.303594 -282.762952)
			(xy 95.250369 -282.758963) (xy 95.198332 -282.747086) (xy 95.148647 -282.727586) (xy 95.102423 -282.700899)
			(xy 95.060693 -282.667621) (xy 95.024389 -282.628494) (xy 94.994322 -282.584394) (xy 94.971164 -282.536305)
			(xy 94.955432 -282.485302) (xy 94.947477 -282.432523) (xy 94.946978 -282.405836) (xy 93.780864 -282.405836)
			(xy 93.780365 -282.432523) (xy 93.77241 -282.485302) (xy 93.756678 -282.536305) (xy 93.73352 -282.584394)
			(xy 93.703453 -282.628494) (xy 93.667149 -282.667621) (xy 93.625419 -282.700899) (xy 93.579195 -282.727586)
			(xy 93.52951 -282.747086) (xy 93.477473 -282.758963) (xy 93.424248 -282.762952) (xy 93.371023 -282.758963)
			(xy 93.318986 -282.747086) (xy 93.269301 -282.727586) (xy 93.223077 -282.700899) (xy 93.181347 -282.667621)
			(xy 93.145043 -282.628494) (xy 93.114976 -282.584394) (xy 93.091818 -282.536305) (xy 93.076086 -282.485302)
			(xy 93.068131 -282.432523) (xy 93.067632 -282.405836) (xy 91.901264 -282.405836) (xy 91.90083 -282.431516)
			(xy 91.893471 -282.482345) (xy 91.878895 -282.531592) (xy 91.857404 -282.578239) (xy 91.829444 -282.62132)
			(xy 91.795591 -282.659944) (xy 91.756548 -282.693311) (xy 91.713121 -282.720732) (xy 91.66621 -282.741638)
			(xy 91.616784 -282.755598) (xy 91.591384 -282.759404) (xy 91.566492 -282.762706) (xy 91.394534 -283.060394)
			(xy 91.404186 -283.083508) (xy 91.412706 -283.105184) (xy 91.42471 -283.150184) (xy 91.430747 -283.196365)
			(xy 91.43111 -283.219652) (xy 91.43111 -283.2199) (xy 92.598007 -283.2199) (xy 92.601985 -283.166828)
			(xy 92.613827 -283.114941) (xy 92.633271 -283.065399) (xy 92.659881 -283.019308) (xy 92.693064 -282.977698)
			(xy 92.732077 -282.941498) (xy 92.77605 -282.911517) (xy 92.824001 -282.888425) (xy 92.874857 -282.872737)
			(xy 92.927483 -282.864804) (xy 92.954094 -282.864306) (xy 92.979066 -282.8647) (xy 93.028517 -282.871695)
			(xy 93.076505 -282.885535) (xy 93.122087 -282.905947) (xy 93.164368 -282.932531) (xy 93.202518 -282.964764)
			(xy 93.235786 -283.002014) (xy 93.250004 -283.022548) (xy 93.597984 -283.022548) (xy 93.612236 -283.002039)
			(xy 93.645493 -282.964783) (xy 93.683634 -282.932546) (xy 93.72591 -282.90596) (xy 93.771489 -282.885549)
			(xy 93.819475 -282.871715) (xy 93.868924 -282.864728) (xy 93.893894 -282.864306) (xy 93.920508 -282.864766)
			(xy 93.973141 -282.872699) (xy 94.024004 -282.888387) (xy 94.071961 -282.911481) (xy 94.11594 -282.941465)
			(xy 94.154959 -282.977669) (xy 94.188146 -283.019283) (xy 94.21476 -283.06538) (xy 94.234207 -283.114928)
			(xy 94.246051 -283.166821) (xy 94.250029 -283.2199) (xy 94.246051 -283.272979) (xy 94.234207 -283.324872)
			(xy 94.21476 -283.37442) (xy 94.188146 -283.420517) (xy 94.154959 -283.462131) (xy 94.11594 -283.498335)
			(xy 94.071961 -283.528319) (xy 94.024004 -283.551413) (xy 93.973141 -283.567101) (xy 93.920508 -283.575034)
			(xy 93.893894 -283.575506) (xy 93.868922 -283.575116) (xy 93.819471 -283.568119) (xy 93.771483 -283.554279)
			(xy 93.725901 -283.533866) (xy 93.68362 -283.507281) (xy 93.645471 -283.475048) (xy 93.612202 -283.437798)
			(xy 93.597984 -283.417264) (xy 93.250004 -283.417264) (xy 93.235764 -283.437781) (xy 93.202504 -283.475036)
			(xy 93.164361 -283.507273) (xy 93.122083 -283.533857) (xy 93.076502 -283.554267) (xy 93.028515 -283.5681)
			(xy 92.979065 -283.575084) (xy 92.954094 -283.575506) (xy 92.927483 -283.574996) (xy 92.874857 -283.567063)
			(xy 92.824001 -283.551375) (xy 92.77605 -283.528283) (xy 92.732077 -283.498302) (xy 92.693064 -283.462102)
			(xy 92.659881 -283.420492) (xy 92.633271 -283.374401) (xy 92.613827 -283.324859) (xy 92.601985 -283.272972)
			(xy 92.598007 -283.2199) (xy 91.43111 -283.2199) (xy 91.43111 -283.219906) (xy 91.430611 -283.246593)
			(xy 91.422656 -283.299372) (xy 91.406924 -283.350375) (xy 91.383766 -283.398464) (xy 91.353699 -283.442564)
			(xy 91.317395 -283.481691) (xy 91.275665 -283.514969) (xy 91.229441 -283.541656) (xy 91.179756 -283.561156)
			(xy 91.127719 -283.573033) (xy 91.074494 -283.577022) (xy 91.021269 -283.573033) (xy 90.969232 -283.561156)
			(xy 90.919547 -283.541656) (xy 90.873323 -283.514969) (xy 90.831593 -283.481691) (xy 90.795289 -283.442564)
			(xy 90.765222 -283.398464) (xy 90.742064 -283.350375) (xy 90.726332 -283.299372) (xy 90.718377 -283.246593)
			(xy 90.717878 -283.219906) (xy 88.61171 -283.219906) (xy 88.611211 -283.246593) (xy 88.603256 -283.299372)
			(xy 88.587524 -283.350375) (xy 88.564366 -283.398464) (xy 88.534299 -283.442564) (xy 88.497995 -283.481691)
			(xy 88.456265 -283.514969) (xy 88.410041 -283.541656) (xy 88.360356 -283.561156) (xy 88.308319 -283.573033)
			(xy 88.255094 -283.577022) (xy 88.201869 -283.573033) (xy 88.149832 -283.561156) (xy 88.100147 -283.541656)
			(xy 88.053923 -283.514969) (xy 88.012193 -283.481691) (xy 87.975889 -283.442564) (xy 87.945822 -283.398464)
			(xy 87.922664 -283.350375) (xy 87.906932 -283.299372) (xy 87.898977 -283.246593) (xy 87.898478 -283.219906)
			(xy 87.89883 -283.196566) (xy 87.904936 -283.150287) (xy 87.917044 -283.105204) (xy 87.925656 -283.083508)
			(xy 87.935308 -283.06014) (xy 87.763096 -282.762706) (xy 87.738458 -282.759404) (xy 87.71307 -282.755538)
			(xy 87.663652 -282.741577) (xy 87.616748 -282.720671) (xy 87.573328 -282.693254) (xy 87.534289 -282.659893)
			(xy 87.500439 -282.621278) (xy 87.472477 -282.578206) (xy 87.450982 -282.53157) (xy 87.436398 -282.482332)
			(xy 87.429028 -282.431512) (xy 87.428578 -282.405836) (xy 87.202264 -282.405836) (xy 87.201765 -282.432523)
			(xy 87.19381 -282.485302) (xy 87.178078 -282.536305) (xy 87.15492 -282.584394) (xy 87.124853 -282.628494)
			(xy 87.088549 -282.667621) (xy 87.046819 -282.700899) (xy 87.000595 -282.727586) (xy 86.95091 -282.747086)
			(xy 86.898873 -282.758963) (xy 86.845648 -282.762952) (xy 86.792423 -282.758963) (xy 86.740386 -282.747086)
			(xy 86.690701 -282.727586) (xy 86.644477 -282.700899) (xy 86.602747 -282.667621) (xy 86.566443 -282.628494)
			(xy 86.536376 -282.584394) (xy 86.513218 -282.536305) (xy 86.497486 -282.485302) (xy 86.489531 -282.432523)
			(xy 86.489032 -282.405836) (xy 2.509012 -282.405836) (xy 2.509012 -284.033722) (xy 86.489032 -284.033722)
			(xy 86.489531 -284.007035) (xy 86.497486 -283.954256) (xy 86.513218 -283.903253) (xy 86.536376 -283.855164)
			(xy 86.566443 -283.811064) (xy 86.602747 -283.771937) (xy 86.644477 -283.738659) (xy 86.690701 -283.711972)
			(xy 86.740386 -283.692472) (xy 86.792423 -283.680595) (xy 86.845648 -283.676606) (xy 86.898873 -283.680595)
			(xy 86.95091 -283.692472) (xy 87.000595 -283.711972) (xy 87.046819 -283.738659) (xy 87.088549 -283.771937)
			(xy 87.124853 -283.811064) (xy 87.15492 -283.855164) (xy 87.178078 -283.903253) (xy 87.19381 -283.954256)
			(xy 87.201765 -284.007035) (xy 87.202264 -284.033722) (xy 334.4291 -284.033722) (xy 334.429599 -284.007035)
			(xy 334.437554 -283.954256) (xy 334.453286 -283.903253) (xy 334.476444 -283.855164) (xy 334.506511 -283.811064)
			(xy 334.542815 -283.771937) (xy 334.584545 -283.738659) (xy 334.630769 -283.711972) (xy 334.680454 -283.692472)
			(xy 334.732491 -283.680595) (xy 334.785716 -283.676606) (xy 334.838941 -283.680595) (xy 334.890978 -283.692472)
			(xy 334.940663 -283.711972) (xy 334.986887 -283.738659) (xy 335.028617 -283.771937) (xy 335.064921 -283.811064)
			(xy 335.094988 -283.855164) (xy 335.118146 -283.903253) (xy 335.133878 -283.954256) (xy 335.141833 -284.007035)
			(xy 335.142332 -284.033722) (xy 335.141957 -284.057061) (xy 335.13586 -284.10334) (xy 335.123761 -284.148423)
			(xy 335.115154 -284.17012) (xy 335.105502 -284.193488) (xy 335.27746 -284.490668) (xy 335.302352 -284.49397)
			(xy 335.327736 -284.497786) (xy 335.37712 -284.511792) (xy 335.423986 -284.532731) (xy 335.467368 -284.56017)
			(xy 335.50637 -284.593544) (xy 335.540187 -284.632162) (xy 335.56812 -284.675227) (xy 335.589593 -284.721852)
			(xy 335.604162 -284.771072) (xy 335.611527 -284.821872) (xy 335.611978 -284.847538) (xy 335.611479 -284.874225)
			(xy 335.603524 -284.927004) (xy 335.587792 -284.978007) (xy 335.564634 -285.026096) (xy 335.534567 -285.070196)
			(xy 335.498263 -285.109323) (xy 335.456533 -285.142601) (xy 335.410309 -285.169288) (xy 335.360624 -285.188788)
			(xy 335.308587 -285.200665) (xy 335.255362 -285.204654) (xy 335.202137 -285.200665) (xy 335.1501 -285.188788)
			(xy 335.100415 -285.169288) (xy 335.054191 -285.142601) (xy 335.012461 -285.109323) (xy 334.976157 -285.070196)
			(xy 334.94609 -285.026096) (xy 334.922932 -284.978007) (xy 334.9072 -284.927004) (xy 334.899245 -284.874225)
			(xy 334.898746 -284.847538) (xy 334.89911 -284.824198) (xy 334.905212 -284.77792) (xy 334.917315 -284.732837)
			(xy 334.925924 -284.71114) (xy 334.935576 -284.687772) (xy 334.763618 -284.390592) (xy 334.738726 -284.38729)
			(xy 334.713345 -284.383451) (xy 334.663959 -284.369453) (xy 334.617089 -284.348521) (xy 334.573704 -284.321086)
			(xy 334.5347 -284.287716) (xy 334.500882 -284.2491) (xy 334.472948 -284.206034) (xy 334.451476 -284.15941)
			(xy 334.436909 -284.110189) (xy 334.429548 -284.059388) (xy 334.4291 -284.033722) (xy 87.202264 -284.033722)
			(xy 87.201886 -284.057061) (xy 87.19579 -284.103339) (xy 87.183692 -284.148423) (xy 87.175086 -284.17012)
			(xy 87.165434 -284.193488) (xy 87.337392 -284.490668) (xy 87.362284 -284.49397) (xy 87.387659 -284.49784)
			(xy 87.437042 -284.511837) (xy 87.48391 -284.532767) (xy 87.527293 -284.560199) (xy 87.566296 -284.593566)
			(xy 87.600114 -284.632178) (xy 87.628049 -284.67524) (xy 87.649523 -284.72186) (xy 87.664094 -284.771077)
			(xy 87.671459 -284.821874) (xy 87.67191 -284.847538) (xy 87.671411 -284.874225) (xy 87.663456 -284.927004)
			(xy 87.647724 -284.978007) (xy 87.624566 -285.026096) (xy 87.594499 -285.070196) (xy 87.558195 -285.109323)
			(xy 87.516465 -285.142601) (xy 87.470241 -285.169288) (xy 87.420556 -285.188788) (xy 87.368519 -285.200665)
			(xy 87.315294 -285.204654) (xy 87.262069 -285.200665) (xy 87.210032 -285.188788) (xy 87.160347 -285.169288)
			(xy 87.114123 -285.142601) (xy 87.072393 -285.109323) (xy 87.036089 -285.070196) (xy 87.006022 -285.026096)
			(xy 86.982864 -284.978007) (xy 86.967132 -284.927004) (xy 86.959177 -284.874225) (xy 86.958678 -284.847538)
			(xy 86.95904 -284.824198) (xy 86.965142 -284.777919) (xy 86.977246 -284.732837) (xy 86.985856 -284.71114)
			(xy 86.995508 -284.687772) (xy 86.82355 -284.390592) (xy 86.798658 -284.38729) (xy 86.773268 -284.383504)
			(xy 86.723882 -284.369497) (xy 86.677013 -284.348557) (xy 86.633629 -284.321115) (xy 86.594626 -284.287738)
			(xy 86.560809 -284.249116) (xy 86.532877 -284.206046) (xy 86.511406 -284.159418) (xy 86.49684 -284.110193)
			(xy 86.48948 -284.059389) (xy 86.489032 -284.033722) (xy 2.509012 -284.033722) (xy 2.509012 -284.8475)
			(xy 85.079639 -284.8475) (xy 85.083616 -284.794433) (xy 85.095458 -284.74255) (xy 85.1149 -284.693013)
			(xy 85.141508 -284.646926) (xy 85.174687 -284.605319) (xy 85.213697 -284.569123) (xy 85.257666 -284.539145)
			(xy 85.305612 -284.516054) (xy 85.356464 -284.500368) (xy 85.409086 -284.492436) (xy 85.435694 -284.491938)
			(xy 85.460664 -284.492362) (xy 85.510113 -284.499356) (xy 85.558099 -284.513192) (xy 85.60368 -284.5336)
			(xy 85.645961 -284.560179) (xy 85.684112 -284.592406) (xy 85.717384 -284.62965) (xy 85.731604 -284.65018)
			(xy 86.079584 -284.65018) (xy 86.093814 -284.629656) (xy 86.127077 -284.592403) (xy 86.165223 -284.560169)
			(xy 86.207503 -284.533587) (xy 86.253085 -284.513178) (xy 86.301072 -284.499346) (xy 86.350523 -284.49236)
			(xy 86.375494 -284.491938) (xy 86.40211 -284.492334) (xy 86.454748 -284.500267) (xy 86.505616 -284.515957)
			(xy 86.553577 -284.539053) (xy 86.59756 -284.56904) (xy 86.636583 -284.605247) (xy 86.669773 -284.646865)
			(xy 86.69639 -284.692966) (xy 86.715838 -284.742518) (xy 86.727683 -284.794416) (xy 86.731662 -284.8475)
			(xy 86.727683 -284.900584) (xy 86.715838 -284.952482) (xy 86.69639 -285.002034) (xy 86.669773 -285.048135)
			(xy 86.636583 -285.089753) (xy 86.59756 -285.12596) (xy 86.553577 -285.155947) (xy 86.505616 -285.179043)
			(xy 86.454748 -285.194733) (xy 86.40211 -285.202666) (xy 86.375494 -285.203138) (xy 86.350523 -285.202734)
			(xy 86.301073 -285.195738) (xy 86.253086 -285.181899) (xy 86.207504 -285.161488) (xy 86.165224 -285.134906)
			(xy 86.127073 -285.102675) (xy 86.093803 -285.065428) (xy 86.079584 -285.044896) (xy 85.731604 -285.044896)
			(xy 85.717374 -285.06542) (xy 85.684112 -285.102674) (xy 85.645966 -285.134909) (xy 85.603686 -285.161492)
			(xy 85.558104 -285.1819) (xy 85.510116 -285.195732) (xy 85.460665 -285.202717) (xy 85.435694 -285.203138)
			(xy 85.409086 -285.202564) (xy 85.356464 -285.194632) (xy 85.305612 -285.178946) (xy 85.257666 -285.155855)
			(xy 85.213697 -285.125877) (xy 85.174687 -285.089681) (xy 85.141508 -285.048074) (xy 85.1149 -285.001987)
			(xy 85.095458 -284.95245) (xy 85.083616 -284.900567) (xy 85.079639 -284.8475) (xy 2.509012 -284.8475)
			(xy 2.509012 -285.661354) (xy 87.428578 -285.661354) (xy 87.429024 -285.635685) (xy 87.436366 -285.584876)
			(xy 87.450919 -285.535644) (xy 87.472384 -285.48901) (xy 87.500315 -285.445936) (xy 87.534136 -285.407314)
			(xy 87.573147 -285.373942) (xy 87.616541 -285.346511) (xy 87.663421 -285.325588) (xy 87.712817 -285.311606)
			(xy 87.738204 -285.307786) (xy 87.763096 -285.304484) (xy 87.935054 -285.006796) (xy 87.925402 -284.983682)
			(xy 87.916911 -284.962086) (xy 87.904927 -284.917255) (xy 87.898868 -284.871248) (xy 87.898478 -284.848046)
			(xy 87.898478 -284.847538) (xy 87.898977 -284.820851) (xy 87.906932 -284.768072) (xy 87.922664 -284.717069)
			(xy 87.945822 -284.66898) (xy 87.975889 -284.62488) (xy 88.012193 -284.585753) (xy 88.053923 -284.552475)
			(xy 88.100147 -284.525788) (xy 88.149832 -284.506288) (xy 88.201869 -284.494411) (xy 88.255094 -284.490422)
			(xy 88.308319 -284.494411) (xy 88.360356 -284.506288) (xy 88.410041 -284.525788) (xy 88.456265 -284.552475)
			(xy 88.497995 -284.585753) (xy 88.534299 -284.62488) (xy 88.564366 -284.66898) (xy 88.587524 -284.717069)
			(xy 88.603256 -284.768072) (xy 88.611211 -284.820851) (xy 88.61171 -284.847538) (xy 88.611267 -284.873207)
			(xy 88.603926 -284.924017) (xy 88.589373 -284.973249) (xy 88.567909 -285.019884) (xy 88.539977 -285.062959)
			(xy 88.506156 -285.101581) (xy 88.467144 -285.134952) (xy 88.423749 -285.162383) (xy 88.376868 -285.183306)
			(xy 88.327471 -285.197287) (xy 88.302084 -285.201106) (xy 88.277192 -285.204408) (xy 88.105234 -285.502096)
			(xy 88.114886 -285.52521) (xy 88.123374 -285.546807) (xy 88.135359 -285.591637) (xy 88.14142 -285.637644)
			(xy 88.14181 -285.660846) (xy 88.14181 -285.661354) (xy 89.335356 -285.661354) (xy 89.335864 -285.635467)
			(xy 89.343963 -285.584329) (xy 89.359962 -285.535089) (xy 89.383468 -285.488957) (xy 89.4139 -285.44707)
			(xy 89.45051 -285.41046) (xy 89.492397 -285.380028) (xy 89.538529 -285.356522) (xy 89.587769 -285.340523)
			(xy 89.638907 -285.332424) (xy 89.690681 -285.332424) (xy 89.741819 -285.340523) (xy 89.791059 -285.356522)
			(xy 89.837191 -285.380028) (xy 89.879078 -285.41046) (xy 89.915688 -285.44707) (xy 89.94612 -285.488957)
			(xy 89.969626 -285.535089) (xy 89.985625 -285.584329) (xy 89.993724 -285.635467) (xy 89.994232 -285.661354)
			(xy 90.275156 -285.661354) (xy 90.27559 -285.636007) (xy 90.28337 -285.585913) (xy 90.298725 -285.537599)
			(xy 90.321292 -285.492204) (xy 90.35054 -285.450798) (xy 90.385779 -285.414354) (xy 90.426181 -285.383733)
			(xy 90.470793 -285.359656) (xy 90.518564 -285.342688) (xy 90.54338 -285.337504) (xy 90.56624 -285.333186)
			(xy 90.771218 -284.978348) (xy 90.763344 -284.956504) (xy 90.754767 -284.930085) (xy 90.745569 -284.87531)
			(xy 90.745056 -284.847538) (xy 90.745564 -284.821651) (xy 90.753663 -284.770513) (xy 90.769662 -284.721273)
			(xy 90.793168 -284.675141) (xy 90.8236 -284.633254) (xy 90.86021 -284.596644) (xy 90.902097 -284.566212)
			(xy 90.948229 -284.542706) (xy 90.997469 -284.526707) (xy 91.048607 -284.518608) (xy 91.100381 -284.518608)
			(xy 91.151519 -284.526707) (xy 91.200759 -284.542706) (xy 91.246891 -284.566212) (xy 91.288778 -284.596644)
			(xy 91.325388 -284.633254) (xy 91.35582 -284.675141) (xy 91.379326 -284.721273) (xy 91.395325 -284.770513)
			(xy 91.403424 -284.821651) (xy 91.403932 -284.847538) (xy 91.403458 -284.872872) (xy 91.395701 -284.922944)
			(xy 91.380375 -284.971239) (xy 91.357841 -285.016622) (xy 91.32863 -285.058022) (xy 91.29343 -285.094467)
			(xy 91.253068 -285.125098) (xy 91.208495 -285.149194) (xy 91.160761 -285.166187) (xy 91.135962 -285.171388)
			(xy 91.113102 -285.175706) (xy 90.908124 -285.530544) (xy 90.915998 -285.552642) (xy 90.924622 -285.57899)
			(xy 90.933948 -285.633636) (xy 90.93454 -285.661354) (xy 91.214956 -285.661354) (xy 91.215464 -285.635447)
			(xy 91.22357 -285.58427) (xy 91.239582 -285.534991) (xy 91.263105 -285.488824) (xy 91.293561 -285.446905)
			(xy 91.330199 -285.410267) (xy 91.372118 -285.379811) (xy 91.418285 -285.356288) (xy 91.467564 -285.340276)
			(xy 91.518741 -285.33217) (xy 91.570555 -285.33217) (xy 91.621732 -285.340276) (xy 91.671011 -285.356288)
			(xy 91.717178 -285.379811) (xy 91.759097 -285.410267) (xy 91.795735 -285.446905) (xy 91.826191 -285.488824)
			(xy 91.849714 -285.534991) (xy 91.865726 -285.58427) (xy 91.873832 -285.635447) (xy 91.87434 -285.661354)
			(xy 92.154756 -285.661354) (xy 92.155232 -285.63602) (xy 92.16299 -285.585949) (xy 92.178317 -285.537654)
			(xy 92.20085 -285.492273) (xy 92.230061 -285.450872) (xy 92.265261 -285.414427) (xy 92.305622 -285.383796)
			(xy 92.350194 -285.3597) (xy 92.397927 -285.342705) (xy 92.422726 -285.337504) (xy 92.445586 -285.333186)
			(xy 92.650818 -284.97784) (xy 92.643198 -284.955996) (xy 92.634574 -284.929714) (xy 92.625259 -284.875193)
			(xy 92.624656 -284.847538) (xy 92.625164 -284.821631) (xy 92.63327 -284.770454) (xy 92.649282 -284.721175)
			(xy 92.672805 -284.675008) (xy 92.703261 -284.633089) (xy 92.739899 -284.596451) (xy 92.781818 -284.565995)
			(xy 92.827985 -284.542472) (xy 92.877264 -284.52646) (xy 92.928441 -284.518354) (xy 92.980255 -284.518354)
			(xy 93.031432 -284.52646) (xy 93.080711 -284.542472) (xy 93.126878 -284.565995) (xy 93.168797 -284.596451)
			(xy 93.205435 -284.633089) (xy 93.235891 -284.675008) (xy 93.259414 -284.721175) (xy 93.275426 -284.770454)
			(xy 93.283532 -284.821631) (xy 93.28404 -284.847538) (xy 93.283648 -284.872916) (xy 93.275873 -284.923072)
			(xy 93.260496 -284.971442) (xy 93.237881 -285.016882) (xy 93.208565 -285.058314) (xy 93.17324 -285.09476)
			(xy 93.132743 -285.125356) (xy 93.088033 -285.149379) (xy 93.040166 -285.166259) (xy 93.015308 -285.171388)
			(xy 92.992448 -285.175706) (xy 92.78747 -285.530544) (xy 92.795344 -285.552642) (xy 92.803916 -285.578997)
			(xy 92.813107 -285.633645) (xy 92.813632 -285.661354) (xy 93.094556 -285.661354) (xy 93.095064 -285.635467)
			(xy 93.103163 -285.584329) (xy 93.119162 -285.535089) (xy 93.142668 -285.488957) (xy 93.1731 -285.44707)
			(xy 93.20971 -285.41046) (xy 93.251597 -285.380028) (xy 93.297729 -285.356522) (xy 93.346969 -285.340523)
			(xy 93.398107 -285.332424) (xy 93.449881 -285.332424) (xy 93.501019 -285.340523) (xy 93.550259 -285.356522)
			(xy 93.596391 -285.380028) (xy 93.638278 -285.41046) (xy 93.674888 -285.44707) (xy 93.70532 -285.488957)
			(xy 93.728826 -285.535089) (xy 93.744825 -285.584329) (xy 93.752924 -285.635467) (xy 93.753432 -285.661354)
			(xy 94.034356 -285.661354) (xy 94.034832 -285.63602) (xy 94.04259 -285.585949) (xy 94.057917 -285.537654)
			(xy 94.08045 -285.492273) (xy 94.109661 -285.450872) (xy 94.144861 -285.414427) (xy 94.185222 -285.383796)
			(xy 94.229794 -285.3597) (xy 94.277527 -285.342705) (xy 94.302326 -285.337504) (xy 94.325186 -285.333186)
			(xy 94.530418 -284.97784) (xy 94.522798 -284.955996) (xy 94.514174 -284.929714) (xy 94.504859 -284.875193)
			(xy 94.504256 -284.847538) (xy 94.504764 -284.821631) (xy 94.51287 -284.770454) (xy 94.528882 -284.721175)
			(xy 94.552405 -284.675008) (xy 94.582861 -284.633089) (xy 94.619499 -284.596451) (xy 94.661418 -284.565995)
			(xy 94.707585 -284.542472) (xy 94.756864 -284.52646) (xy 94.808041 -284.518354) (xy 94.859855 -284.518354)
			(xy 94.911032 -284.52646) (xy 94.960311 -284.542472) (xy 95.006478 -284.565995) (xy 95.048397 -284.596451)
			(xy 95.085035 -284.633089) (xy 95.115491 -284.675008) (xy 95.139014 -284.721175) (xy 95.155026 -284.770454)
			(xy 95.163132 -284.821631) (xy 95.16364 -284.847538) (xy 95.163248 -284.872916) (xy 95.155473 -284.923072)
			(xy 95.140096 -284.971442) (xy 95.117481 -285.016882) (xy 95.088165 -285.058314) (xy 95.05284 -285.09476)
			(xy 95.012343 -285.125356) (xy 94.967633 -285.149379) (xy 94.919766 -285.166259) (xy 94.894908 -285.171388)
			(xy 94.872048 -285.175706) (xy 94.66707 -285.530544) (xy 94.674944 -285.552642) (xy 94.683516 -285.578997)
			(xy 94.692707 -285.633645) (xy 94.693232 -285.661354) (xy 94.974156 -285.661354) (xy 94.974664 -285.635467)
			(xy 94.982763 -285.584329) (xy 94.998762 -285.535089) (xy 95.022268 -285.488957) (xy 95.0527 -285.44707)
			(xy 95.08931 -285.41046) (xy 95.131197 -285.380028) (xy 95.177329 -285.356522) (xy 95.226569 -285.340523)
			(xy 95.277707 -285.332424) (xy 95.329481 -285.332424) (xy 95.380619 -285.340523) (xy 95.429859 -285.356522)
			(xy 95.475991 -285.380028) (xy 95.517878 -285.41046) (xy 95.554488 -285.44707) (xy 95.58492 -285.488957)
			(xy 95.608426 -285.535089) (xy 95.624425 -285.584329) (xy 95.632524 -285.635467) (xy 95.633032 -285.661354)
			(xy 95.913956 -285.661354) (xy 95.914432 -285.63602) (xy 95.92219 -285.585949) (xy 95.937517 -285.537654)
			(xy 95.96005 -285.492273) (xy 95.989261 -285.450872) (xy 96.024461 -285.414427) (xy 96.064822 -285.383796)
			(xy 96.109394 -285.3597) (xy 96.157127 -285.342705) (xy 96.181926 -285.337504) (xy 96.204786 -285.333186)
			(xy 96.410018 -284.97784) (xy 96.402398 -284.955996) (xy 96.393774 -284.929714) (xy 96.384459 -284.875193)
			(xy 96.383856 -284.847538) (xy 96.384364 -284.821631) (xy 96.39247 -284.770454) (xy 96.408482 -284.721175)
			(xy 96.432005 -284.675008) (xy 96.462461 -284.633089) (xy 96.499099 -284.596451) (xy 96.541018 -284.565995)
			(xy 96.587185 -284.542472) (xy 96.636464 -284.52646) (xy 96.687641 -284.518354) (xy 96.739455 -284.518354)
			(xy 96.790632 -284.52646) (xy 96.839911 -284.542472) (xy 96.886078 -284.565995) (xy 96.927997 -284.596451)
			(xy 96.964635 -284.633089) (xy 96.995091 -284.675008) (xy 97.018614 -284.721175) (xy 97.034626 -284.770454)
			(xy 97.042732 -284.821631) (xy 97.04324 -284.847538) (xy 97.042848 -284.872916) (xy 97.035073 -284.923072)
			(xy 97.019696 -284.971442) (xy 96.997081 -285.016882) (xy 96.967765 -285.058314) (xy 96.93244 -285.09476)
			(xy 96.891943 -285.125356) (xy 96.847233 -285.149379) (xy 96.799366 -285.166259) (xy 96.774508 -285.171388)
			(xy 96.751648 -285.175706) (xy 96.54667 -285.530544) (xy 96.554544 -285.552642) (xy 96.563116 -285.578997)
			(xy 96.572307 -285.633645) (xy 96.572832 -285.661354) (xy 96.853756 -285.661354) (xy 96.854264 -285.635467)
			(xy 96.862363 -285.584329) (xy 96.878362 -285.535089) (xy 96.901868 -285.488957) (xy 96.9323 -285.44707)
			(xy 96.96891 -285.41046) (xy 97.010797 -285.380028) (xy 97.056929 -285.356522) (xy 97.106169 -285.340523)
			(xy 97.157307 -285.332424) (xy 97.209081 -285.332424) (xy 97.260219 -285.340523) (xy 97.309459 -285.356522)
			(xy 97.355591 -285.380028) (xy 97.397478 -285.41046) (xy 97.434088 -285.44707) (xy 97.46452 -285.488957)
			(xy 97.488026 -285.535089) (xy 97.504025 -285.584329) (xy 97.512124 -285.635467) (xy 97.512632 -285.661354)
			(xy 97.793556 -285.661354) (xy 97.794032 -285.63602) (xy 97.80179 -285.585949) (xy 97.817117 -285.537654)
			(xy 97.83965 -285.492273) (xy 97.868861 -285.450872) (xy 97.904061 -285.414427) (xy 97.944422 -285.383796)
			(xy 97.988994 -285.3597) (xy 98.036727 -285.342705) (xy 98.061526 -285.337504) (xy 98.084386 -285.333186)
			(xy 98.289618 -284.97784) (xy 98.281998 -284.955996) (xy 98.273374 -284.929714) (xy 98.264059 -284.875193)
			(xy 98.263456 -284.847538) (xy 98.263964 -284.821631) (xy 98.27207 -284.770454) (xy 98.288082 -284.721175)
			(xy 98.311605 -284.675008) (xy 98.342061 -284.633089) (xy 98.378699 -284.596451) (xy 98.420618 -284.565995)
			(xy 98.466785 -284.542472) (xy 98.516064 -284.52646) (xy 98.567241 -284.518354) (xy 98.619055 -284.518354)
			(xy 98.670232 -284.52646) (xy 98.719511 -284.542472) (xy 98.765678 -284.565995) (xy 98.807597 -284.596451)
			(xy 98.844235 -284.633089) (xy 98.874691 -284.675008) (xy 98.898214 -284.721175) (xy 98.914226 -284.770454)
			(xy 98.922332 -284.821631) (xy 98.92284 -284.847538) (xy 98.922448 -284.872916) (xy 98.914673 -284.923072)
			(xy 98.899296 -284.971442) (xy 98.876681 -285.016882) (xy 98.847365 -285.058314) (xy 98.81204 -285.09476)
			(xy 98.771543 -285.125356) (xy 98.726833 -285.149379) (xy 98.678966 -285.166259) (xy 98.654108 -285.171388)
			(xy 98.631248 -285.175706) (xy 98.42627 -285.530544) (xy 98.434144 -285.552642) (xy 98.442716 -285.578997)
			(xy 98.451907 -285.633645) (xy 98.452432 -285.661354) (xy 98.733356 -285.661354) (xy 98.733864 -285.635467)
			(xy 98.741963 -285.584329) (xy 98.757962 -285.535089) (xy 98.781468 -285.488957) (xy 98.8119 -285.44707)
			(xy 98.84851 -285.41046) (xy 98.890397 -285.380028) (xy 98.936529 -285.356522) (xy 98.985769 -285.340523)
			(xy 99.036907 -285.332424) (xy 99.088681 -285.332424) (xy 99.139819 -285.340523) (xy 99.189059 -285.356522)
			(xy 99.235191 -285.380028) (xy 99.277078 -285.41046) (xy 99.313688 -285.44707) (xy 99.34412 -285.488957)
			(xy 99.367626 -285.535089) (xy 99.383625 -285.584329) (xy 99.391724 -285.635467) (xy 99.392232 -285.661354)
			(xy 99.673156 -285.661354) (xy 99.673632 -285.63602) (xy 99.68139 -285.585949) (xy 99.696717 -285.537654)
			(xy 99.71925 -285.492273) (xy 99.748461 -285.450872) (xy 99.783661 -285.414427) (xy 99.824022 -285.383796)
			(xy 99.868594 -285.3597) (xy 99.916327 -285.342705) (xy 99.941126 -285.337504) (xy 99.963986 -285.333186)
			(xy 100.169218 -284.97784) (xy 100.161598 -284.955996) (xy 100.152974 -284.929714) (xy 100.143659 -284.875193)
			(xy 100.143056 -284.847538) (xy 100.143564 -284.821631) (xy 100.15167 -284.770454) (xy 100.167682 -284.721175)
			(xy 100.191205 -284.675008) (xy 100.221661 -284.633089) (xy 100.258299 -284.596451) (xy 100.300218 -284.565995)
			(xy 100.346385 -284.542472) (xy 100.395664 -284.52646) (xy 100.446841 -284.518354) (xy 100.498655 -284.518354)
			(xy 100.549832 -284.52646) (xy 100.599111 -284.542472) (xy 100.645278 -284.565995) (xy 100.687197 -284.596451)
			(xy 100.723835 -284.633089) (xy 100.754291 -284.675008) (xy 100.777814 -284.721175) (xy 100.793826 -284.770454)
			(xy 100.801932 -284.821631) (xy 100.80244 -284.847538) (xy 100.802048 -284.872916) (xy 100.794273 -284.923072)
			(xy 100.778896 -284.971442) (xy 100.756281 -285.016882) (xy 100.726965 -285.058314) (xy 100.69164 -285.09476)
			(xy 100.651143 -285.125356) (xy 100.606433 -285.149379) (xy 100.558566 -285.166259) (xy 100.533708 -285.171388)
			(xy 100.510848 -285.175706) (xy 100.30587 -285.530544) (xy 100.313744 -285.552642) (xy 100.322316 -285.578997)
			(xy 100.331507 -285.633645) (xy 100.332032 -285.661354) (xy 100.612956 -285.661354) (xy 100.613464 -285.635467)
			(xy 100.621563 -285.584329) (xy 100.637562 -285.535089) (xy 100.661068 -285.488957) (xy 100.6915 -285.44707)
			(xy 100.72811 -285.41046) (xy 100.769997 -285.380028) (xy 100.816129 -285.356522) (xy 100.865369 -285.340523)
			(xy 100.916507 -285.332424) (xy 100.968281 -285.332424) (xy 101.019419 -285.340523) (xy 101.068659 -285.356522)
			(xy 101.114791 -285.380028) (xy 101.156678 -285.41046) (xy 101.193288 -285.44707) (xy 101.22372 -285.488957)
			(xy 101.247226 -285.535089) (xy 101.263225 -285.584329) (xy 101.271324 -285.635467) (xy 101.271832 -285.661354)
			(xy 101.552756 -285.661354) (xy 101.553232 -285.63602) (xy 101.56099 -285.585949) (xy 101.576317 -285.537654)
			(xy 101.59885 -285.492273) (xy 101.628061 -285.450872) (xy 101.663261 -285.414427) (xy 101.703622 -285.383796)
			(xy 101.748194 -285.3597) (xy 101.795927 -285.342705) (xy 101.820726 -285.337504) (xy 101.843586 -285.333186)
			(xy 102.048818 -284.97784) (xy 102.041198 -284.955996) (xy 102.032574 -284.929714) (xy 102.023259 -284.875193)
			(xy 102.022656 -284.847538) (xy 102.023164 -284.821631) (xy 102.03127 -284.770454) (xy 102.047282 -284.721175)
			(xy 102.070805 -284.675008) (xy 102.101261 -284.633089) (xy 102.137899 -284.596451) (xy 102.179818 -284.565995)
			(xy 102.225985 -284.542472) (xy 102.275264 -284.52646) (xy 102.326441 -284.518354) (xy 102.378255 -284.518354)
			(xy 102.429432 -284.52646) (xy 102.478711 -284.542472) (xy 102.524878 -284.565995) (xy 102.566797 -284.596451)
			(xy 102.603435 -284.633089) (xy 102.633891 -284.675008) (xy 102.657414 -284.721175) (xy 102.673426 -284.770454)
			(xy 102.681532 -284.821631) (xy 102.68204 -284.847538) (xy 102.681648 -284.872916) (xy 102.673873 -284.923072)
			(xy 102.658496 -284.971442) (xy 102.635881 -285.016882) (xy 102.606565 -285.058314) (xy 102.57124 -285.09476)
			(xy 102.530743 -285.125356) (xy 102.486033 -285.149379) (xy 102.438166 -285.166259) (xy 102.413308 -285.171388)
			(xy 102.390448 -285.175706) (xy 102.18547 -285.530544) (xy 102.193344 -285.552642) (xy 102.201916 -285.578997)
			(xy 102.211107 -285.633645) (xy 102.211632 -285.661354) (xy 102.492556 -285.661354) (xy 102.493064 -285.635467)
			(xy 102.501163 -285.584329) (xy 102.517162 -285.535089) (xy 102.540668 -285.488957) (xy 102.5711 -285.44707)
			(xy 102.60771 -285.41046) (xy 102.649597 -285.380028) (xy 102.695729 -285.356522) (xy 102.744969 -285.340523)
			(xy 102.796107 -285.332424) (xy 102.847881 -285.332424) (xy 102.899019 -285.340523) (xy 102.948259 -285.356522)
			(xy 102.994391 -285.380028) (xy 103.036278 -285.41046) (xy 103.072888 -285.44707) (xy 103.10332 -285.488957)
			(xy 103.126826 -285.535089) (xy 103.142825 -285.584329) (xy 103.150924 -285.635467) (xy 103.151432 -285.661354)
			(xy 103.432356 -285.661354) (xy 103.432832 -285.63602) (xy 103.44059 -285.585949) (xy 103.455917 -285.537654)
			(xy 103.47845 -285.492273) (xy 103.507661 -285.450872) (xy 103.542861 -285.414427) (xy 103.583222 -285.383796)
			(xy 103.627794 -285.3597) (xy 103.675527 -285.342705) (xy 103.700326 -285.337504) (xy 103.723186 -285.333186)
			(xy 103.928418 -284.97784) (xy 103.920798 -284.955996) (xy 103.912174 -284.929714) (xy 103.902859 -284.875193)
			(xy 103.902256 -284.847538) (xy 103.902764 -284.821631) (xy 103.91087 -284.770454) (xy 103.926882 -284.721175)
			(xy 103.950405 -284.675008) (xy 103.980861 -284.633089) (xy 104.017499 -284.596451) (xy 104.059418 -284.565995)
			(xy 104.105585 -284.542472) (xy 104.154864 -284.52646) (xy 104.206041 -284.518354) (xy 104.257855 -284.518354)
			(xy 104.309032 -284.52646) (xy 104.358311 -284.542472) (xy 104.404478 -284.565995) (xy 104.446397 -284.596451)
			(xy 104.483035 -284.633089) (xy 104.513491 -284.675008) (xy 104.537014 -284.721175) (xy 104.553026 -284.770454)
			(xy 104.561132 -284.821631) (xy 104.56164 -284.847538) (xy 118.939056 -284.847538) (xy 118.939564 -284.821631)
			(xy 118.94767 -284.770454) (xy 118.963682 -284.721175) (xy 118.987205 -284.675008) (xy 119.017661 -284.633089)
			(xy 119.054299 -284.596451) (xy 119.096218 -284.565995) (xy 119.142385 -284.542472) (xy 119.191664 -284.52646)
			(xy 119.242841 -284.518354) (xy 119.294655 -284.518354) (xy 119.345832 -284.52646) (xy 119.395111 -284.542472)
			(xy 119.441278 -284.565995) (xy 119.483197 -284.596451) (xy 119.519835 -284.633089) (xy 119.550291 -284.675008)
			(xy 119.573814 -284.721175) (xy 119.589826 -284.770454) (xy 119.597932 -284.821631) (xy 119.59844 -284.847538)
			(xy 120.818656 -284.847538) (xy 120.819164 -284.821631) (xy 120.82727 -284.770454) (xy 120.843282 -284.721175)
			(xy 120.866805 -284.675008) (xy 120.897261 -284.633089) (xy 120.933899 -284.596451) (xy 120.975818 -284.565995)
			(xy 121.021985 -284.542472) (xy 121.071264 -284.52646) (xy 121.122441 -284.518354) (xy 121.174255 -284.518354)
			(xy 121.225432 -284.52646) (xy 121.274711 -284.542472) (xy 121.320878 -284.565995) (xy 121.362797 -284.596451)
			(xy 121.399435 -284.633089) (xy 121.429891 -284.675008) (xy 121.453414 -284.721175) (xy 121.469426 -284.770454)
			(xy 121.477532 -284.821631) (xy 121.47804 -284.847538) (xy 122.698256 -284.847538) (xy 122.698764 -284.821631)
			(xy 122.70687 -284.770454) (xy 122.722882 -284.721175) (xy 122.746405 -284.675008) (xy 122.776861 -284.633089)
			(xy 122.813499 -284.596451) (xy 122.855418 -284.565995) (xy 122.901585 -284.542472) (xy 122.950864 -284.52646)
			(xy 123.002041 -284.518354) (xy 123.053855 -284.518354) (xy 123.105032 -284.52646) (xy 123.154311 -284.542472)
			(xy 123.200478 -284.565995) (xy 123.242397 -284.596451) (xy 123.279035 -284.633089) (xy 123.309491 -284.675008)
			(xy 123.333014 -284.721175) (xy 123.349026 -284.770454) (xy 123.357132 -284.821631) (xy 123.35764 -284.847538)
			(xy 124.577856 -284.847538) (xy 124.578364 -284.821631) (xy 124.58647 -284.770454) (xy 124.602482 -284.721175)
			(xy 124.626005 -284.675008) (xy 124.656461 -284.633089) (xy 124.693099 -284.596451) (xy 124.735018 -284.565995)
			(xy 124.781185 -284.542472) (xy 124.830464 -284.52646) (xy 124.881641 -284.518354) (xy 124.933455 -284.518354)
			(xy 124.984632 -284.52646) (xy 125.033911 -284.542472) (xy 125.080078 -284.565995) (xy 125.121997 -284.596451)
			(xy 125.158635 -284.633089) (xy 125.189091 -284.675008) (xy 125.212614 -284.721175) (xy 125.228626 -284.770454)
			(xy 125.236732 -284.821631) (xy 125.23724 -284.847538) (xy 126.457456 -284.847538) (xy 126.457964 -284.821631)
			(xy 126.46607 -284.770454) (xy 126.482082 -284.721175) (xy 126.505605 -284.675008) (xy 126.536061 -284.633089)
			(xy 126.572699 -284.596451) (xy 126.614618 -284.565995) (xy 126.660785 -284.542472) (xy 126.710064 -284.52646)
			(xy 126.761241 -284.518354) (xy 126.813055 -284.518354) (xy 126.864232 -284.52646) (xy 126.913511 -284.542472)
			(xy 126.959678 -284.565995) (xy 127.001597 -284.596451) (xy 127.038235 -284.633089) (xy 127.068691 -284.675008)
			(xy 127.092214 -284.721175) (xy 127.108226 -284.770454) (xy 127.116332 -284.821631) (xy 127.11684 -284.847538)
			(xy 128.337056 -284.847538) (xy 128.337564 -284.821631) (xy 128.34567 -284.770454) (xy 128.361682 -284.721175)
			(xy 128.385205 -284.675008) (xy 128.415661 -284.633089) (xy 128.452299 -284.596451) (xy 128.494218 -284.565995)
			(xy 128.540385 -284.542472) (xy 128.589664 -284.52646) (xy 128.640841 -284.518354) (xy 128.692655 -284.518354)
			(xy 128.743832 -284.52646) (xy 128.793111 -284.542472) (xy 128.839278 -284.565995) (xy 128.881197 -284.596451)
			(xy 128.917835 -284.633089) (xy 128.948291 -284.675008) (xy 128.971814 -284.721175) (xy 128.987826 -284.770454)
			(xy 128.995932 -284.821631) (xy 128.99644 -284.847538) (xy 130.216656 -284.847538) (xy 130.217164 -284.821631)
			(xy 130.22527 -284.770454) (xy 130.241282 -284.721175) (xy 130.264805 -284.675008) (xy 130.295261 -284.633089)
			(xy 130.331899 -284.596451) (xy 130.373818 -284.565995) (xy 130.419985 -284.542472) (xy 130.469264 -284.52646)
			(xy 130.520441 -284.518354) (xy 130.572255 -284.518354) (xy 130.623432 -284.52646) (xy 130.672711 -284.542472)
			(xy 130.718878 -284.565995) (xy 130.760797 -284.596451) (xy 130.797435 -284.633089) (xy 130.827891 -284.675008)
			(xy 130.851414 -284.721175) (xy 130.867426 -284.770454) (xy 130.875532 -284.821631) (xy 130.87604 -284.847538)
			(xy 132.096256 -284.847538) (xy 132.096764 -284.821631) (xy 132.10487 -284.770454) (xy 132.120882 -284.721175)
			(xy 132.144405 -284.675008) (xy 132.174861 -284.633089) (xy 132.211499 -284.596451) (xy 132.253418 -284.565995)
			(xy 132.299585 -284.542472) (xy 132.348864 -284.52646) (xy 132.400041 -284.518354) (xy 132.451855 -284.518354)
			(xy 132.503032 -284.52646) (xy 132.552311 -284.542472) (xy 132.598478 -284.565995) (xy 132.640397 -284.596451)
			(xy 132.677035 -284.633089) (xy 132.707491 -284.675008) (xy 132.731014 -284.721175) (xy 132.747026 -284.770454)
			(xy 132.755132 -284.821631) (xy 132.755639 -284.8475) (xy 333.019739 -284.8475) (xy 333.023716 -284.794436)
			(xy 333.035556 -284.742556) (xy 333.054996 -284.693021) (xy 333.081601 -284.646936) (xy 333.114777 -284.605331)
			(xy 333.153783 -284.569134) (xy 333.197748 -284.539155) (xy 333.24569 -284.516063) (xy 333.296537 -284.500374)
			(xy 333.349155 -284.492438) (xy 333.375762 -284.491938) (xy 333.400732 -284.492387) (xy 333.450179 -284.499376)
			(xy 333.498165 -284.513208) (xy 333.543746 -284.533612) (xy 333.586027 -284.560187) (xy 333.624179 -284.592411)
			(xy 333.657451 -284.629651) (xy 333.671672 -284.65018) (xy 334.019652 -284.65018) (xy 334.033839 -284.629624)
			(xy 334.067109 -284.592373) (xy 334.105263 -284.56014) (xy 334.14755 -284.533562) (xy 334.193138 -284.513159)
			(xy 334.241133 -284.499333) (xy 334.290589 -284.492356) (xy 334.315562 -284.491938) (xy 334.34218 -284.492332)
			(xy 334.394822 -284.500261) (xy 334.445693 -284.515948) (xy 334.493659 -284.539042) (xy 334.537646 -284.569028)
			(xy 334.576673 -284.605235) (xy 334.609866 -284.646855) (xy 334.636486 -284.692958) (xy 334.655936 -284.742513)
			(xy 334.667783 -284.794413) (xy 334.671762 -284.8475) (xy 334.667783 -284.900587) (xy 334.655936 -284.952487)
			(xy 334.636486 -285.002042) (xy 334.609866 -285.048145) (xy 334.576673 -285.089765) (xy 334.537646 -285.125972)
			(xy 334.493659 -285.155958) (xy 334.445693 -285.179052) (xy 334.394822 -285.194739) (xy 334.34218 -285.202668)
			(xy 334.315562 -285.203138) (xy 334.290593 -285.202682) (xy 334.241145 -285.195695) (xy 334.193159 -285.181865)
			(xy 334.147578 -285.161463) (xy 334.105296 -285.134889) (xy 334.067145 -285.102665) (xy 334.033872 -285.065425)
			(xy 334.019652 -285.044896) (xy 333.671672 -285.044896) (xy 333.657462 -285.065435) (xy 333.624197 -285.102688)
			(xy 333.586047 -285.134922) (xy 333.543764 -285.161504) (xy 333.498179 -285.181909) (xy 333.450188 -285.195738)
			(xy 333.400734 -285.202719) (xy 333.375762 -285.203138) (xy 333.349155 -285.202562) (xy 333.296537 -285.194626)
			(xy 333.24569 -285.178937) (xy 333.197748 -285.155845) (xy 333.153783 -285.125866) (xy 333.114777 -285.089669)
			(xy 333.081601 -285.048064) (xy 333.054996 -285.001979) (xy 333.035556 -284.952444) (xy 333.023716 -284.900564)
			(xy 333.019739 -284.8475) (xy 132.755639 -284.8475) (xy 132.75564 -284.847538) (xy 132.755034 -284.875255)
			(xy 132.745719 -284.929901) (xy 132.737098 -284.95625) (xy 132.729224 -284.978348) (xy 132.934202 -285.333186)
			(xy 132.957062 -285.337504) (xy 132.981868 -285.342683) (xy 133.02961 -285.359669) (xy 133.07419 -285.383762)
			(xy 133.114558 -285.414393) (xy 133.149763 -285.450841) (xy 133.178975 -285.492247) (xy 133.201506 -285.537636)
			(xy 133.216825 -285.585939) (xy 133.224572 -285.636017) (xy 133.225032 -285.661354) (xy 133.224524 -285.687241)
			(xy 133.216425 -285.738379) (xy 133.200426 -285.787619) (xy 133.17692 -285.833751) (xy 133.146488 -285.875638)
			(xy 133.109878 -285.912248) (xy 133.067991 -285.94268) (xy 133.021859 -285.966186) (xy 132.972619 -285.982185)
			(xy 132.921481 -285.990284) (xy 132.869707 -285.990284) (xy 132.818569 -285.982185) (xy 132.769329 -285.966186)
			(xy 132.723197 -285.94268) (xy 132.68131 -285.912248) (xy 132.6447 -285.875638) (xy 132.614268 -285.833751)
			(xy 132.590762 -285.787619) (xy 132.574763 -285.738379) (xy 132.566664 -285.687241) (xy 132.566156 -285.661354)
			(xy 132.566701 -285.633647) (xy 132.575886 -285.579) (xy 132.584444 -285.552642) (xy 132.592318 -285.530544)
			(xy 132.38734 -285.175706) (xy 132.36448 -285.171388) (xy 132.33966 -285.166215) (xy 132.29188 -285.149263)
			(xy 132.247259 -285.125194) (xy 132.206851 -285.094575) (xy 132.171609 -285.058129) (xy 132.142365 -285.016715)
			(xy 132.119809 -284.971312) (xy 132.104472 -284.922989) (xy 132.096717 -284.872887) (xy 132.096256 -284.847538)
			(xy 130.87604 -284.847538) (xy 130.875434 -284.875255) (xy 130.866119 -284.929901) (xy 130.857498 -284.95625)
			(xy 130.849624 -284.978348) (xy 131.054602 -285.333186) (xy 131.077462 -285.337504) (xy 131.102268 -285.342683)
			(xy 131.15001 -285.359669) (xy 131.19459 -285.383762) (xy 131.234958 -285.414393) (xy 131.270163 -285.450841)
			(xy 131.299375 -285.492247) (xy 131.321906 -285.537636) (xy 131.337225 -285.585939) (xy 131.344972 -285.636017)
			(xy 131.345432 -285.661354) (xy 131.344924 -285.687241) (xy 131.336825 -285.738379) (xy 131.320826 -285.787619)
			(xy 131.29732 -285.833751) (xy 131.266888 -285.875638) (xy 131.230278 -285.912248) (xy 131.188391 -285.94268)
			(xy 131.142259 -285.966186) (xy 131.093019 -285.982185) (xy 131.041881 -285.990284) (xy 130.990107 -285.990284)
			(xy 130.938969 -285.982185) (xy 130.889729 -285.966186) (xy 130.843597 -285.94268) (xy 130.80171 -285.912248)
			(xy 130.7651 -285.875638) (xy 130.734668 -285.833751) (xy 130.711162 -285.787619) (xy 130.695163 -285.738379)
			(xy 130.687064 -285.687241) (xy 130.686556 -285.661354) (xy 130.687101 -285.633647) (xy 130.696286 -285.579)
			(xy 130.704844 -285.552642) (xy 130.712718 -285.530544) (xy 130.50774 -285.175706) (xy 130.48488 -285.171388)
			(xy 130.46006 -285.166215) (xy 130.41228 -285.149263) (xy 130.367659 -285.125194) (xy 130.327251 -285.094575)
			(xy 130.292009 -285.058129) (xy 130.262765 -285.016715) (xy 130.240209 -284.971312) (xy 130.224872 -284.922989)
			(xy 130.217117 -284.872887) (xy 130.216656 -284.847538) (xy 128.99644 -284.847538) (xy 128.995834 -284.875255)
			(xy 128.986519 -284.929901) (xy 128.977898 -284.95625) (xy 128.970024 -284.978348) (xy 129.175002 -285.333186)
			(xy 129.197862 -285.337504) (xy 129.222668 -285.342683) (xy 129.27041 -285.359669) (xy 129.31499 -285.383762)
			(xy 129.355358 -285.414393) (xy 129.390563 -285.450841) (xy 129.419775 -285.492247) (xy 129.442306 -285.537636)
			(xy 129.457625 -285.585939) (xy 129.465372 -285.636017) (xy 129.465832 -285.661354) (xy 129.465324 -285.687241)
			(xy 129.457225 -285.738379) (xy 129.441226 -285.787619) (xy 129.41772 -285.833751) (xy 129.387288 -285.875638)
			(xy 129.350678 -285.912248) (xy 129.308791 -285.94268) (xy 129.262659 -285.966186) (xy 129.213419 -285.982185)
			(xy 129.162281 -285.990284) (xy 129.110507 -285.990284) (xy 129.059369 -285.982185) (xy 129.010129 -285.966186)
			(xy 128.963997 -285.94268) (xy 128.92211 -285.912248) (xy 128.8855 -285.875638) (xy 128.855068 -285.833751)
			(xy 128.831562 -285.787619) (xy 128.815563 -285.738379) (xy 128.807464 -285.687241) (xy 128.806956 -285.661354)
			(xy 128.807501 -285.633647) (xy 128.816686 -285.579) (xy 128.825244 -285.552642) (xy 128.833118 -285.530544)
			(xy 128.62814 -285.175706) (xy 128.60528 -285.171388) (xy 128.58046 -285.166215) (xy 128.53268 -285.149263)
			(xy 128.488059 -285.125194) (xy 128.447651 -285.094575) (xy 128.412409 -285.058129) (xy 128.383165 -285.016715)
			(xy 128.360609 -284.971312) (xy 128.345272 -284.922989) (xy 128.337517 -284.872887) (xy 128.337056 -284.847538)
			(xy 127.11684 -284.847538) (xy 127.116234 -284.875255) (xy 127.106919 -284.929901) (xy 127.098298 -284.95625)
			(xy 127.090424 -284.978348) (xy 127.295402 -285.333186) (xy 127.318262 -285.337504) (xy 127.343068 -285.342683)
			(xy 127.39081 -285.359669) (xy 127.43539 -285.383762) (xy 127.475758 -285.414393) (xy 127.510963 -285.450841)
			(xy 127.540175 -285.492247) (xy 127.562706 -285.537636) (xy 127.578025 -285.585939) (xy 127.585772 -285.636017)
			(xy 127.586232 -285.661354) (xy 127.585724 -285.687241) (xy 127.577625 -285.738379) (xy 127.561626 -285.787619)
			(xy 127.53812 -285.833751) (xy 127.507688 -285.875638) (xy 127.471078 -285.912248) (xy 127.429191 -285.94268)
			(xy 127.383059 -285.966186) (xy 127.333819 -285.982185) (xy 127.282681 -285.990284) (xy 127.230907 -285.990284)
			(xy 127.179769 -285.982185) (xy 127.130529 -285.966186) (xy 127.084397 -285.94268) (xy 127.04251 -285.912248)
			(xy 127.0059 -285.875638) (xy 126.975468 -285.833751) (xy 126.951962 -285.787619) (xy 126.935963 -285.738379)
			(xy 126.927864 -285.687241) (xy 126.927356 -285.661354) (xy 126.927901 -285.633647) (xy 126.937086 -285.579)
			(xy 126.945644 -285.552642) (xy 126.953518 -285.530544) (xy 126.74854 -285.175706) (xy 126.72568 -285.171388)
			(xy 126.70086 -285.166215) (xy 126.65308 -285.149263) (xy 126.608459 -285.125194) (xy 126.568051 -285.094575)
			(xy 126.532809 -285.058129) (xy 126.503565 -285.016715) (xy 126.481009 -284.971312) (xy 126.465672 -284.922989)
			(xy 126.457917 -284.872887) (xy 126.457456 -284.847538) (xy 125.23724 -284.847538) (xy 125.236634 -284.875255)
			(xy 125.227319 -284.929901) (xy 125.218698 -284.95625) (xy 125.210824 -284.978348) (xy 125.415802 -285.333186)
			(xy 125.438662 -285.337504) (xy 125.463468 -285.342683) (xy 125.51121 -285.359669) (xy 125.55579 -285.383762)
			(xy 125.596158 -285.414393) (xy 125.631363 -285.450841) (xy 125.660575 -285.492247) (xy 125.683106 -285.537636)
			(xy 125.698425 -285.585939) (xy 125.706172 -285.636017) (xy 125.706632 -285.661354) (xy 125.706124 -285.687241)
			(xy 125.698025 -285.738379) (xy 125.682026 -285.787619) (xy 125.65852 -285.833751) (xy 125.628088 -285.875638)
			(xy 125.591478 -285.912248) (xy 125.549591 -285.94268) (xy 125.503459 -285.966186) (xy 125.454219 -285.982185)
			(xy 125.403081 -285.990284) (xy 125.351307 -285.990284) (xy 125.300169 -285.982185) (xy 125.250929 -285.966186)
			(xy 125.204797 -285.94268) (xy 125.16291 -285.912248) (xy 125.1263 -285.875638) (xy 125.095868 -285.833751)
			(xy 125.072362 -285.787619) (xy 125.056363 -285.738379) (xy 125.048264 -285.687241) (xy 125.047756 -285.661354)
			(xy 125.048301 -285.633647) (xy 125.057486 -285.579) (xy 125.066044 -285.552642) (xy 125.073918 -285.530544)
			(xy 124.86894 -285.175706) (xy 124.84608 -285.171388) (xy 124.82126 -285.166215) (xy 124.77348 -285.149263)
			(xy 124.728859 -285.125194) (xy 124.688451 -285.094575) (xy 124.653209 -285.058129) (xy 124.623965 -285.016715)
			(xy 124.601409 -284.971312) (xy 124.586072 -284.922989) (xy 124.578317 -284.872887) (xy 124.577856 -284.847538)
			(xy 123.35764 -284.847538) (xy 123.357034 -284.875255) (xy 123.347719 -284.929901) (xy 123.339098 -284.95625)
			(xy 123.331224 -284.978348) (xy 123.536202 -285.333186) (xy 123.559062 -285.337504) (xy 123.583868 -285.342683)
			(xy 123.63161 -285.359669) (xy 123.67619 -285.383762) (xy 123.716558 -285.414393) (xy 123.751763 -285.450841)
			(xy 123.780975 -285.492247) (xy 123.803506 -285.537636) (xy 123.818825 -285.585939) (xy 123.826572 -285.636017)
			(xy 123.827032 -285.661354) (xy 123.826524 -285.687241) (xy 123.818425 -285.738379) (xy 123.802426 -285.787619)
			(xy 123.77892 -285.833751) (xy 123.748488 -285.875638) (xy 123.711878 -285.912248) (xy 123.669991 -285.94268)
			(xy 123.623859 -285.966186) (xy 123.574619 -285.982185) (xy 123.523481 -285.990284) (xy 123.471707 -285.990284)
			(xy 123.420569 -285.982185) (xy 123.371329 -285.966186) (xy 123.325197 -285.94268) (xy 123.28331 -285.912248)
			(xy 123.2467 -285.875638) (xy 123.216268 -285.833751) (xy 123.192762 -285.787619) (xy 123.176763 -285.738379)
			(xy 123.168664 -285.687241) (xy 123.168156 -285.661354) (xy 123.168701 -285.633647) (xy 123.177886 -285.579)
			(xy 123.186444 -285.552642) (xy 123.194318 -285.530544) (xy 122.98934 -285.175706) (xy 122.96648 -285.171388)
			(xy 122.94166 -285.166215) (xy 122.89388 -285.149263) (xy 122.849259 -285.125194) (xy 122.808851 -285.094575)
			(xy 122.773609 -285.058129) (xy 122.744365 -285.016715) (xy 122.721809 -284.971312) (xy 122.706472 -284.922989)
			(xy 122.698717 -284.872887) (xy 122.698256 -284.847538) (xy 121.47804 -284.847538) (xy 121.477434 -284.875255)
			(xy 121.468119 -284.929901) (xy 121.459498 -284.95625) (xy 121.451624 -284.978348) (xy 121.656602 -285.333186)
			(xy 121.679462 -285.337504) (xy 121.704268 -285.342683) (xy 121.75201 -285.359669) (xy 121.79659 -285.383762)
			(xy 121.836958 -285.414393) (xy 121.872163 -285.450841) (xy 121.901375 -285.492247) (xy 121.923906 -285.537636)
			(xy 121.939225 -285.585939) (xy 121.946972 -285.636017) (xy 121.947432 -285.661354) (xy 121.946924 -285.687241)
			(xy 121.938825 -285.738379) (xy 121.922826 -285.787619) (xy 121.89932 -285.833751) (xy 121.868888 -285.875638)
			(xy 121.832278 -285.912248) (xy 121.790391 -285.94268) (xy 121.744259 -285.966186) (xy 121.695019 -285.982185)
			(xy 121.643881 -285.990284) (xy 121.592107 -285.990284) (xy 121.540969 -285.982185) (xy 121.491729 -285.966186)
			(xy 121.445597 -285.94268) (xy 121.40371 -285.912248) (xy 121.3671 -285.875638) (xy 121.336668 -285.833751)
			(xy 121.313162 -285.787619) (xy 121.297163 -285.738379) (xy 121.289064 -285.687241) (xy 121.288556 -285.661354)
			(xy 121.289101 -285.633647) (xy 121.298286 -285.579) (xy 121.306844 -285.552642) (xy 121.314718 -285.530544)
			(xy 121.10974 -285.175706) (xy 121.08688 -285.171388) (xy 121.06206 -285.166215) (xy 121.01428 -285.149263)
			(xy 120.969659 -285.125194) (xy 120.929251 -285.094575) (xy 120.894009 -285.058129) (xy 120.864765 -285.016715)
			(xy 120.842209 -284.971312) (xy 120.826872 -284.922989) (xy 120.819117 -284.872887) (xy 120.818656 -284.847538)
			(xy 119.59844 -284.847538) (xy 119.597834 -284.875255) (xy 119.588519 -284.929901) (xy 119.579898 -284.95625)
			(xy 119.572024 -284.978348) (xy 119.777002 -285.333186) (xy 119.799862 -285.337504) (xy 119.824668 -285.342683)
			(xy 119.87241 -285.359669) (xy 119.91699 -285.383762) (xy 119.957358 -285.414393) (xy 119.992563 -285.450841)
			(xy 120.021775 -285.492247) (xy 120.044306 -285.537636) (xy 120.059625 -285.585939) (xy 120.067372 -285.636017)
			(xy 120.067832 -285.661354) (xy 120.067324 -285.687241) (xy 120.059225 -285.738379) (xy 120.043226 -285.787619)
			(xy 120.01972 -285.833751) (xy 119.989288 -285.875638) (xy 119.952678 -285.912248) (xy 119.910791 -285.94268)
			(xy 119.864659 -285.966186) (xy 119.815419 -285.982185) (xy 119.764281 -285.990284) (xy 119.712507 -285.990284)
			(xy 119.661369 -285.982185) (xy 119.612129 -285.966186) (xy 119.565997 -285.94268) (xy 119.52411 -285.912248)
			(xy 119.4875 -285.875638) (xy 119.457068 -285.833751) (xy 119.433562 -285.787619) (xy 119.417563 -285.738379)
			(xy 119.409464 -285.687241) (xy 119.408956 -285.661354) (xy 119.409501 -285.633647) (xy 119.418686 -285.579)
			(xy 119.427244 -285.552642) (xy 119.435118 -285.530544) (xy 119.23014 -285.175706) (xy 119.20728 -285.171388)
			(xy 119.18246 -285.166215) (xy 119.13468 -285.149263) (xy 119.090059 -285.125194) (xy 119.049651 -285.094575)
			(xy 119.014409 -285.058129) (xy 118.985165 -285.016715) (xy 118.962609 -284.971312) (xy 118.947272 -284.922989)
			(xy 118.939517 -284.872887) (xy 118.939056 -284.847538) (xy 104.56164 -284.847538) (xy 104.561248 -284.872916)
			(xy 104.553473 -284.923072) (xy 104.538096 -284.971442) (xy 104.515481 -285.016882) (xy 104.486165 -285.058314)
			(xy 104.45084 -285.09476) (xy 104.410343 -285.125356) (xy 104.365633 -285.149379) (xy 104.317766 -285.166259)
			(xy 104.292908 -285.171388) (xy 104.270048 -285.175706) (xy 104.06507 -285.530544) (xy 104.072944 -285.552642)
			(xy 104.081516 -285.578997) (xy 104.090707 -285.633645) (xy 104.091232 -285.661354) (xy 104.090724 -285.687241)
			(xy 104.082625 -285.738379) (xy 104.066626 -285.787619) (xy 104.04312 -285.833751) (xy 104.012688 -285.875638)
			(xy 103.976078 -285.912248) (xy 103.934191 -285.94268) (xy 103.888059 -285.966186) (xy 103.838819 -285.982185)
			(xy 103.787681 -285.990284) (xy 103.735907 -285.990284) (xy 103.684769 -285.982185) (xy 103.635529 -285.966186)
			(xy 103.589397 -285.94268) (xy 103.54751 -285.912248) (xy 103.5109 -285.875638) (xy 103.480468 -285.833751)
			(xy 103.456962 -285.787619) (xy 103.440963 -285.738379) (xy 103.432864 -285.687241) (xy 103.432356 -285.661354)
			(xy 103.151432 -285.661354) (xy 103.151432 -285.661862) (xy 103.150853 -285.689379) (xy 103.141659 -285.74364)
			(xy 103.133144 -285.769812) (xy 103.125524 -285.79191) (xy 103.330756 -286.147256) (xy 103.353616 -286.151574)
			(xy 103.378427 -286.156786) (xy 103.426204 -286.173734) (xy 103.470823 -286.197799) (xy 103.51123 -286.228413)
			(xy 103.546472 -286.264855) (xy 103.575717 -286.306263) (xy 103.598276 -286.351662) (xy 103.613617 -286.399979)
			(xy 103.621377 -286.450077) (xy 103.62184 -286.475424) (xy 119.878856 -286.475424) (xy 119.879354 -286.450079)
			(xy 119.887123 -286.399987) (xy 119.902468 -286.351675) (xy 119.925026 -286.306281) (xy 119.954266 -286.264873)
			(xy 119.989499 -286.228429) (xy 120.029894 -286.197807) (xy 120.0745 -286.173728) (xy 120.122266 -286.156759)
			(xy 120.14708 -286.151574) (xy 120.16994 -286.147256) (xy 120.374918 -285.792164) (xy 120.367044 -285.77032)
			(xy 120.358471 -285.743899) (xy 120.34927 -285.689126) (xy 120.348756 -285.661354) (xy 120.349264 -285.635467)
			(xy 120.357363 -285.584329) (xy 120.373362 -285.535089) (xy 120.396868 -285.488957) (xy 120.4273 -285.44707)
			(xy 120.46391 -285.41046) (xy 120.505797 -285.380028) (xy 120.551929 -285.356522) (xy 120.601169 -285.340523)
			(xy 120.652307 -285.332424) (xy 120.704081 -285.332424) (xy 120.755219 -285.340523) (xy 120.804459 -285.356522)
			(xy 120.850591 -285.380028) (xy 120.892478 -285.41046) (xy 120.929088 -285.44707) (xy 120.95952 -285.488957)
			(xy 120.983026 -285.535089) (xy 120.999025 -285.584329) (xy 121.007124 -285.635467) (xy 121.007632 -285.661354)
			(xy 121.007172 -285.686689) (xy 120.999413 -285.736761) (xy 120.984085 -285.785057) (xy 120.961549 -285.830439)
			(xy 120.932336 -285.87184) (xy 120.897134 -285.908285) (xy 120.856771 -285.938915) (xy 120.812197 -285.963011)
			(xy 120.764462 -285.980004) (xy 120.739662 -285.985204) (xy 120.716802 -285.989522) (xy 120.511824 -286.344614)
			(xy 120.519698 -286.366458) (xy 120.528349 -286.392865) (xy 120.537666 -286.447642) (xy 120.53824 -286.475424)
			(xy 121.758456 -286.475424) (xy 121.758954 -286.450079) (xy 121.766723 -286.399987) (xy 121.782068 -286.351675)
			(xy 121.804626 -286.306281) (xy 121.833866 -286.264873) (xy 121.869099 -286.228429) (xy 121.909494 -286.197807)
			(xy 121.9541 -286.173728) (xy 122.001866 -286.156759) (xy 122.02668 -286.151574) (xy 122.04954 -286.147256)
			(xy 122.254518 -285.792164) (xy 122.246644 -285.77032) (xy 122.238071 -285.743899) (xy 122.22887 -285.689126)
			(xy 122.228356 -285.661354) (xy 122.228864 -285.635467) (xy 122.236963 -285.584329) (xy 122.252962 -285.535089)
			(xy 122.276468 -285.488957) (xy 122.3069 -285.44707) (xy 122.34351 -285.41046) (xy 122.385397 -285.380028)
			(xy 122.431529 -285.356522) (xy 122.480769 -285.340523) (xy 122.531907 -285.332424) (xy 122.583681 -285.332424)
			(xy 122.634819 -285.340523) (xy 122.684059 -285.356522) (xy 122.730191 -285.380028) (xy 122.772078 -285.41046)
			(xy 122.808688 -285.44707) (xy 122.83912 -285.488957) (xy 122.862626 -285.535089) (xy 122.878625 -285.584329)
			(xy 122.886724 -285.635467) (xy 122.887232 -285.661354) (xy 122.886772 -285.686689) (xy 122.879013 -285.736761)
			(xy 122.863685 -285.785057) (xy 122.841149 -285.830439) (xy 122.811936 -285.87184) (xy 122.776734 -285.908285)
			(xy 122.736371 -285.938915) (xy 122.691797 -285.963011) (xy 122.644062 -285.980004) (xy 122.619262 -285.985204)
			(xy 122.596402 -285.989522) (xy 122.391424 -286.344614) (xy 122.399298 -286.366458) (xy 122.407949 -286.392865)
			(xy 122.417266 -286.447642) (xy 122.41784 -286.475424) (xy 123.638056 -286.475424) (xy 123.638554 -286.450079)
			(xy 123.646323 -286.399987) (xy 123.661668 -286.351675) (xy 123.684226 -286.306281) (xy 123.713466 -286.264873)
			(xy 123.748699 -286.228429) (xy 123.789094 -286.197807) (xy 123.8337 -286.173728) (xy 123.881466 -286.156759)
			(xy 123.90628 -286.151574) (xy 123.92914 -286.147256) (xy 124.134118 -285.792164) (xy 124.126244 -285.77032)
			(xy 124.117671 -285.743899) (xy 124.10847 -285.689126) (xy 124.107956 -285.661354) (xy 124.108464 -285.635467)
			(xy 124.116563 -285.584329) (xy 124.132562 -285.535089) (xy 124.156068 -285.488957) (xy 124.1865 -285.44707)
			(xy 124.22311 -285.41046) (xy 124.264997 -285.380028) (xy 124.311129 -285.356522) (xy 124.360369 -285.340523)
			(xy 124.411507 -285.332424) (xy 124.463281 -285.332424) (xy 124.514419 -285.340523) (xy 124.563659 -285.356522)
			(xy 124.609791 -285.380028) (xy 124.651678 -285.41046) (xy 124.688288 -285.44707) (xy 124.71872 -285.488957)
			(xy 124.742226 -285.535089) (xy 124.758225 -285.584329) (xy 124.766324 -285.635467) (xy 124.766832 -285.661354)
			(xy 124.766372 -285.686689) (xy 124.758613 -285.736761) (xy 124.743285 -285.785057) (xy 124.720749 -285.830439)
			(xy 124.691536 -285.87184) (xy 124.656334 -285.908285) (xy 124.615971 -285.938915) (xy 124.571397 -285.963011)
			(xy 124.523662 -285.980004) (xy 124.498862 -285.985204) (xy 124.476002 -285.989522) (xy 124.271024 -286.344614)
			(xy 124.278898 -286.366458) (xy 124.287549 -286.392865) (xy 124.296866 -286.447642) (xy 124.29744 -286.475424)
			(xy 125.517656 -286.475424) (xy 125.518154 -286.450079) (xy 125.525923 -286.399987) (xy 125.541268 -286.351675)
			(xy 125.563826 -286.306281) (xy 125.593066 -286.264873) (xy 125.628299 -286.228429) (xy 125.668694 -286.197807)
			(xy 125.7133 -286.173728) (xy 125.761066 -286.156759) (xy 125.78588 -286.151574) (xy 125.80874 -286.147256)
			(xy 126.013718 -285.792164) (xy 126.005844 -285.77032) (xy 125.997271 -285.743899) (xy 125.98807 -285.689126)
			(xy 125.987556 -285.661354) (xy 125.988064 -285.635467) (xy 125.996163 -285.584329) (xy 126.012162 -285.535089)
			(xy 126.035668 -285.488957) (xy 126.0661 -285.44707) (xy 126.10271 -285.41046) (xy 126.144597 -285.380028)
			(xy 126.190729 -285.356522) (xy 126.239969 -285.340523) (xy 126.291107 -285.332424) (xy 126.342881 -285.332424)
			(xy 126.394019 -285.340523) (xy 126.443259 -285.356522) (xy 126.489391 -285.380028) (xy 126.531278 -285.41046)
			(xy 126.567888 -285.44707) (xy 126.59832 -285.488957) (xy 126.621826 -285.535089) (xy 126.637825 -285.584329)
			(xy 126.645924 -285.635467) (xy 126.646432 -285.661354) (xy 126.645972 -285.686689) (xy 126.638213 -285.736761)
			(xy 126.622885 -285.785057) (xy 126.600349 -285.830439) (xy 126.571136 -285.87184) (xy 126.535934 -285.908285)
			(xy 126.495571 -285.938915) (xy 126.450997 -285.963011) (xy 126.403262 -285.980004) (xy 126.378462 -285.985204)
			(xy 126.355602 -285.989522) (xy 126.150624 -286.344614) (xy 126.158498 -286.366458) (xy 126.167149 -286.392865)
			(xy 126.176466 -286.447642) (xy 126.17704 -286.475424) (xy 127.397256 -286.475424) (xy 127.397754 -286.450079)
			(xy 127.405523 -286.399987) (xy 127.420868 -286.351675) (xy 127.443426 -286.306281) (xy 127.472666 -286.264873)
			(xy 127.507899 -286.228429) (xy 127.548294 -286.197807) (xy 127.5929 -286.173728) (xy 127.640666 -286.156759)
			(xy 127.66548 -286.151574) (xy 127.68834 -286.147256) (xy 127.893318 -285.792164) (xy 127.885444 -285.77032)
			(xy 127.876871 -285.743899) (xy 127.86767 -285.689126) (xy 127.867156 -285.661354) (xy 127.867664 -285.635467)
			(xy 127.875763 -285.584329) (xy 127.891762 -285.535089) (xy 127.915268 -285.488957) (xy 127.9457 -285.44707)
			(xy 127.98231 -285.41046) (xy 128.024197 -285.380028) (xy 128.070329 -285.356522) (xy 128.119569 -285.340523)
			(xy 128.170707 -285.332424) (xy 128.222481 -285.332424) (xy 128.273619 -285.340523) (xy 128.322859 -285.356522)
			(xy 128.368991 -285.380028) (xy 128.410878 -285.41046) (xy 128.447488 -285.44707) (xy 128.47792 -285.488957)
			(xy 128.501426 -285.535089) (xy 128.517425 -285.584329) (xy 128.525524 -285.635467) (xy 128.526032 -285.661354)
			(xy 128.525572 -285.686689) (xy 128.517813 -285.736761) (xy 128.502485 -285.785057) (xy 128.479949 -285.830439)
			(xy 128.450736 -285.87184) (xy 128.415534 -285.908285) (xy 128.375171 -285.938915) (xy 128.330597 -285.963011)
			(xy 128.282862 -285.980004) (xy 128.258062 -285.985204) (xy 128.235202 -285.989522) (xy 128.030224 -286.344614)
			(xy 128.038098 -286.366458) (xy 128.046749 -286.392865) (xy 128.056066 -286.447642) (xy 128.05664 -286.475424)
			(xy 129.276856 -286.475424) (xy 129.277354 -286.450079) (xy 129.285123 -286.399987) (xy 129.300468 -286.351675)
			(xy 129.323026 -286.306281) (xy 129.352266 -286.264873) (xy 129.387499 -286.228429) (xy 129.427894 -286.197807)
			(xy 129.4725 -286.173728) (xy 129.520266 -286.156759) (xy 129.54508 -286.151574) (xy 129.56794 -286.147256)
			(xy 129.772918 -285.792164) (xy 129.765044 -285.77032) (xy 129.756471 -285.743899) (xy 129.74727 -285.689126)
			(xy 129.746756 -285.661354) (xy 129.747264 -285.635467) (xy 129.755363 -285.584329) (xy 129.771362 -285.535089)
			(xy 129.794868 -285.488957) (xy 129.8253 -285.44707) (xy 129.86191 -285.41046) (xy 129.903797 -285.380028)
			(xy 129.949929 -285.356522) (xy 129.999169 -285.340523) (xy 130.050307 -285.332424) (xy 130.102081 -285.332424)
			(xy 130.153219 -285.340523) (xy 130.202459 -285.356522) (xy 130.248591 -285.380028) (xy 130.290478 -285.41046)
			(xy 130.327088 -285.44707) (xy 130.35752 -285.488957) (xy 130.381026 -285.535089) (xy 130.397025 -285.584329)
			(xy 130.405124 -285.635467) (xy 130.405632 -285.661354) (xy 130.405172 -285.686689) (xy 130.397413 -285.736761)
			(xy 130.382085 -285.785057) (xy 130.359549 -285.830439) (xy 130.330336 -285.87184) (xy 130.295134 -285.908285)
			(xy 130.254771 -285.938915) (xy 130.210197 -285.963011) (xy 130.162462 -285.980004) (xy 130.137662 -285.985204)
			(xy 130.114802 -285.989522) (xy 129.909824 -286.344614) (xy 129.917698 -286.366458) (xy 129.926349 -286.392865)
			(xy 129.935666 -286.447642) (xy 129.93624 -286.475424) (xy 131.156456 -286.475424) (xy 131.156954 -286.450079)
			(xy 131.164723 -286.399987) (xy 131.180068 -286.351675) (xy 131.202626 -286.306281) (xy 131.231866 -286.264873)
			(xy 131.267099 -286.228429) (xy 131.307494 -286.197807) (xy 131.3521 -286.173728) (xy 131.399866 -286.156759)
			(xy 131.42468 -286.151574) (xy 131.44754 -286.147256) (xy 131.652518 -285.792164) (xy 131.644644 -285.77032)
			(xy 131.636071 -285.743899) (xy 131.62687 -285.689126) (xy 131.626356 -285.661354) (xy 131.626864 -285.635467)
			(xy 131.634963 -285.584329) (xy 131.650962 -285.535089) (xy 131.674468 -285.488957) (xy 131.7049 -285.44707)
			(xy 131.74151 -285.41046) (xy 131.783397 -285.380028) (xy 131.829529 -285.356522) (xy 131.878769 -285.340523)
			(xy 131.929907 -285.332424) (xy 131.981681 -285.332424) (xy 132.032819 -285.340523) (xy 132.082059 -285.356522)
			(xy 132.128191 -285.380028) (xy 132.170078 -285.41046) (xy 132.206688 -285.44707) (xy 132.23712 -285.488957)
			(xy 132.260626 -285.535089) (xy 132.276625 -285.584329) (xy 132.284724 -285.635467) (xy 132.285232 -285.661354)
			(xy 132.284772 -285.686689) (xy 132.277013 -285.736761) (xy 132.261685 -285.785057) (xy 132.239149 -285.830439)
			(xy 132.209936 -285.87184) (xy 132.174734 -285.908285) (xy 132.134371 -285.938915) (xy 132.089797 -285.963011)
			(xy 132.042062 -285.980004) (xy 132.017262 -285.985204) (xy 131.994402 -285.989522) (xy 131.789424 -286.344614)
			(xy 131.797298 -286.366458) (xy 131.805949 -286.392865) (xy 131.815266 -286.447642) (xy 131.81584 -286.475424)
			(xy 133.036056 -286.475424) (xy 133.036554 -286.450079) (xy 133.044323 -286.399987) (xy 133.059668 -286.351675)
			(xy 133.082226 -286.306281) (xy 133.111466 -286.264873) (xy 133.146699 -286.228429) (xy 133.187094 -286.197807)
			(xy 133.2317 -286.173728) (xy 133.279466 -286.156759) (xy 133.30428 -286.151574) (xy 133.32714 -286.147256)
			(xy 133.532118 -285.792164) (xy 133.524244 -285.77032) (xy 133.515671 -285.743899) (xy 133.50647 -285.689126)
			(xy 133.505956 -285.661354) (xy 133.506464 -285.635467) (xy 133.514563 -285.584329) (xy 133.530562 -285.535089)
			(xy 133.554068 -285.488957) (xy 133.5845 -285.44707) (xy 133.62111 -285.41046) (xy 133.662997 -285.380028)
			(xy 133.709129 -285.356522) (xy 133.758369 -285.340523) (xy 133.809507 -285.332424) (xy 133.861281 -285.332424)
			(xy 133.912419 -285.340523) (xy 133.961659 -285.356522) (xy 134.007791 -285.380028) (xy 134.049678 -285.41046)
			(xy 134.086288 -285.44707) (xy 134.11672 -285.488957) (xy 134.140226 -285.535089) (xy 134.156225 -285.584329)
			(xy 134.164324 -285.635467) (xy 134.164832 -285.661354) (xy 335.368646 -285.661354) (xy 335.36912 -285.635686)
			(xy 335.376461 -285.584879) (xy 335.391012 -285.53565) (xy 335.412475 -285.489017) (xy 335.440403 -285.445945)
			(xy 335.474221 -285.407323) (xy 335.513228 -285.373951) (xy 335.556618 -285.346519) (xy 335.603494 -285.325594)
			(xy 335.652887 -285.311608) (xy 335.678272 -285.307786) (xy 335.703164 -285.304484) (xy 335.875122 -285.006796)
			(xy 335.86547 -284.983682) (xy 335.856977 -284.962086) (xy 335.844995 -284.917255) (xy 335.838936 -284.871248)
			(xy 335.838546 -284.848046) (xy 335.838546 -284.847538) (xy 335.839045 -284.820851) (xy 335.847 -284.768072)
			(xy 335.862732 -284.717069) (xy 335.88589 -284.66898) (xy 335.915957 -284.62488) (xy 335.952261 -284.585753)
			(xy 335.993991 -284.552475) (xy 336.040215 -284.525788) (xy 336.0899 -284.506288) (xy 336.141937 -284.494411)
			(xy 336.195162 -284.490422) (xy 336.248387 -284.494411) (xy 336.300424 -284.506288) (xy 336.350109 -284.525788)
			(xy 336.396333 -284.552475) (xy 336.438063 -284.585753) (xy 336.474367 -284.62488) (xy 336.504434 -284.66898)
			(xy 336.527592 -284.717069) (xy 336.543324 -284.768072) (xy 336.551279 -284.820851) (xy 336.551778 -284.847538)
			(xy 336.551276 -284.873204) (xy 336.543937 -284.924009) (xy 336.529387 -284.973236) (xy 336.507928 -285.019868)
			(xy 336.480003 -285.06294) (xy 336.446188 -285.101561) (xy 336.407185 -285.134934) (xy 336.363798 -285.162367)
			(xy 336.316925 -285.183294) (xy 336.267536 -285.197283) (xy 336.242152 -285.201106) (xy 336.21726 -285.204408)
			(xy 336.045302 -285.502096) (xy 336.054954 -285.52521) (xy 336.063445 -285.546806) (xy 336.075428 -285.591637)
			(xy 336.081488 -285.637644) (xy 336.081878 -285.660846) (xy 336.081878 -285.661354) (xy 337.275424 -285.661354)
			(xy 337.275932 -285.635467) (xy 337.284031 -285.584329) (xy 337.30003 -285.535089) (xy 337.323536 -285.488957)
			(xy 337.353968 -285.44707) (xy 337.390578 -285.41046) (xy 337.432465 -285.380028) (xy 337.478597 -285.356522)
			(xy 337.527837 -285.340523) (xy 337.578975 -285.332424) (xy 337.630749 -285.332424) (xy 337.681887 -285.340523)
			(xy 337.731127 -285.356522) (xy 337.777259 -285.380028) (xy 337.819146 -285.41046) (xy 337.855756 -285.44707)
			(xy 337.886188 -285.488957) (xy 337.909694 -285.535089) (xy 337.925693 -285.584329) (xy 337.933792 -285.635467)
			(xy 337.9343 -285.661354) (xy 338.215224 -285.661354) (xy 338.215684 -285.636008) (xy 338.223463 -285.585916)
			(xy 338.238816 -285.537605) (xy 338.26138 -285.492212) (xy 338.290625 -285.450806) (xy 338.325861 -285.414363)
			(xy 338.366259 -285.383741) (xy 338.410867 -285.359661) (xy 338.458634 -285.34269) (xy 338.483448 -285.337504)
			(xy 338.506308 -285.333186) (xy 338.711286 -284.978348) (xy 338.703412 -284.956504) (xy 338.694834 -284.930085)
			(xy 338.685636 -284.87531) (xy 338.685124 -284.847538) (xy 338.685632 -284.821651) (xy 338.693731 -284.770513)
			(xy 338.70973 -284.721273) (xy 338.733236 -284.675141) (xy 338.763668 -284.633254) (xy 338.800278 -284.596644)
			(xy 338.842165 -284.566212) (xy 338.888297 -284.542706) (xy 338.937537 -284.526707) (xy 338.988675 -284.518608)
			(xy 339.040449 -284.518608) (xy 339.091587 -284.526707) (xy 339.140827 -284.542706) (xy 339.186959 -284.566212)
			(xy 339.228846 -284.596644) (xy 339.265456 -284.633254) (xy 339.295888 -284.675141) (xy 339.319394 -284.721273)
			(xy 339.335393 -284.770513) (xy 339.343492 -284.821651) (xy 339.344 -284.847538) (xy 339.343552 -284.872874)
			(xy 339.335794 -284.922948) (xy 339.320466 -284.971245) (xy 339.29793 -285.016629) (xy 339.268716 -285.058031)
			(xy 339.233511 -285.094476) (xy 339.193146 -285.125106) (xy 339.148569 -285.149199) (xy 339.100831 -285.16619)
			(xy 339.07603 -285.171388) (xy 339.05317 -285.175706) (xy 338.848192 -285.530544) (xy 338.856066 -285.552642)
			(xy 338.86469 -285.578991) (xy 338.874015 -285.633637) (xy 338.874608 -285.661354) (xy 339.155024 -285.661354)
			(xy 339.155532 -285.635447) (xy 339.163638 -285.58427) (xy 339.17965 -285.534991) (xy 339.203173 -285.488824)
			(xy 339.233629 -285.446905) (xy 339.270267 -285.410267) (xy 339.312186 -285.379811) (xy 339.358353 -285.356288)
			(xy 339.407632 -285.340276) (xy 339.458809 -285.33217) (xy 339.510623 -285.33217) (xy 339.5618 -285.340276)
			(xy 339.611079 -285.356288) (xy 339.657246 -285.379811) (xy 339.699165 -285.410267) (xy 339.735803 -285.446905)
			(xy 339.766259 -285.488824) (xy 339.789782 -285.534991) (xy 339.805794 -285.58427) (xy 339.8139 -285.635447)
			(xy 339.814408 -285.661354) (xy 340.094824 -285.661354) (xy 340.095245 -285.636017) (xy 340.103005 -285.585941)
			(xy 340.118335 -285.537642) (xy 340.140875 -285.492257) (xy 340.170092 -285.450854) (xy 340.2053 -285.41441)
			(xy 340.24567 -285.383781) (xy 340.29025 -285.359689) (xy 340.337992 -285.342701) (xy 340.362794 -285.337504)
			(xy 340.385654 -285.333186) (xy 340.590886 -284.97784) (xy 340.583266 -284.955996) (xy 340.574644 -284.929713)
			(xy 340.565327 -284.875193) (xy 340.564724 -284.847538) (xy 340.565232 -284.821631) (xy 340.573338 -284.770454)
			(xy 340.58935 -284.721175) (xy 340.612873 -284.675008) (xy 340.643329 -284.633089) (xy 340.679967 -284.596451)
			(xy 340.721886 -284.565995) (xy 340.768053 -284.542472) (xy 340.817332 -284.52646) (xy 340.868509 -284.518354)
			(xy 340.920323 -284.518354) (xy 340.9715 -284.52646) (xy 341.020779 -284.542472) (xy 341.066946 -284.565995)
			(xy 341.108865 -284.596451) (xy 341.145503 -284.633089) (xy 341.175959 -284.675008) (xy 341.199482 -284.721175)
			(xy 341.215494 -284.770454) (xy 341.2236 -284.821631) (xy 341.224108 -284.847538) (xy 341.223661 -284.872913)
			(xy 341.215887 -284.923064) (xy 341.200514 -284.97143) (xy 341.177905 -285.016866) (xy 341.148596 -285.058297)
			(xy 341.113279 -285.094742) (xy 341.072791 -285.125341) (xy 341.028089 -285.149367) (xy 340.980231 -285.166254)
			(xy 340.955376 -285.171388) (xy 340.932516 -285.175706) (xy 340.727538 -285.530544) (xy 340.735412 -285.552642)
			(xy 340.743983 -285.578997) (xy 340.753175 -285.633645) (xy 340.7537 -285.661354) (xy 341.034624 -285.661354)
			(xy 341.035132 -285.635467) (xy 341.043231 -285.584329) (xy 341.05923 -285.535089) (xy 341.082736 -285.488957)
			(xy 341.113168 -285.44707) (xy 341.149778 -285.41046) (xy 341.191665 -285.380028) (xy 341.237797 -285.356522)
			(xy 341.287037 -285.340523) (xy 341.338175 -285.332424) (xy 341.389949 -285.332424) (xy 341.441087 -285.340523)
			(xy 341.490327 -285.356522) (xy 341.536459 -285.380028) (xy 341.578346 -285.41046) (xy 341.614956 -285.44707)
			(xy 341.645388 -285.488957) (xy 341.668894 -285.535089) (xy 341.684893 -285.584329) (xy 341.692992 -285.635467)
			(xy 341.6935 -285.661354) (xy 341.974424 -285.661354) (xy 341.974845 -285.636017) (xy 341.982605 -285.585941)
			(xy 341.997935 -285.537642) (xy 342.020475 -285.492257) (xy 342.049692 -285.450854) (xy 342.0849 -285.41441)
			(xy 342.12527 -285.383781) (xy 342.16985 -285.359689) (xy 342.217592 -285.342701) (xy 342.242394 -285.337504)
			(xy 342.265254 -285.333186) (xy 342.470486 -284.97784) (xy 342.462866 -284.955996) (xy 342.454244 -284.929713)
			(xy 342.444927 -284.875193) (xy 342.444324 -284.847538) (xy 342.444832 -284.821631) (xy 342.452938 -284.770454)
			(xy 342.46895 -284.721175) (xy 342.492473 -284.675008) (xy 342.522929 -284.633089) (xy 342.559567 -284.596451)
			(xy 342.601486 -284.565995) (xy 342.647653 -284.542472) (xy 342.696932 -284.52646) (xy 342.748109 -284.518354)
			(xy 342.799923 -284.518354) (xy 342.8511 -284.52646) (xy 342.900379 -284.542472) (xy 342.946546 -284.565995)
			(xy 342.988465 -284.596451) (xy 343.025103 -284.633089) (xy 343.055559 -284.675008) (xy 343.079082 -284.721175)
			(xy 343.095094 -284.770454) (xy 343.1032 -284.821631) (xy 343.103708 -284.847538) (xy 343.103261 -284.872913)
			(xy 343.095487 -284.923064) (xy 343.080114 -284.97143) (xy 343.057505 -285.016866) (xy 343.028196 -285.058297)
			(xy 342.992879 -285.094742) (xy 342.952391 -285.125341) (xy 342.907689 -285.149367) (xy 342.859831 -285.166254)
			(xy 342.834976 -285.171388) (xy 342.812116 -285.175706) (xy 342.607138 -285.530544) (xy 342.615012 -285.552642)
			(xy 342.623583 -285.578997) (xy 342.632775 -285.633645) (xy 342.6333 -285.661354) (xy 342.914224 -285.661354)
			(xy 342.914732 -285.635467) (xy 342.922831 -285.584329) (xy 342.93883 -285.535089) (xy 342.962336 -285.488957)
			(xy 342.992768 -285.44707) (xy 343.029378 -285.41046) (xy 343.071265 -285.380028) (xy 343.117397 -285.356522)
			(xy 343.166637 -285.340523) (xy 343.217775 -285.332424) (xy 343.269549 -285.332424) (xy 343.320687 -285.340523)
			(xy 343.369927 -285.356522) (xy 343.416059 -285.380028) (xy 343.457946 -285.41046) (xy 343.494556 -285.44707)
			(xy 343.524988 -285.488957) (xy 343.548494 -285.535089) (xy 343.564493 -285.584329) (xy 343.572592 -285.635467)
			(xy 343.5731 -285.661354) (xy 343.854024 -285.661354) (xy 343.854445 -285.636017) (xy 343.862205 -285.585941)
			(xy 343.877535 -285.537642) (xy 343.900075 -285.492257) (xy 343.929292 -285.450854) (xy 343.9645 -285.41441)
			(xy 344.00487 -285.383781) (xy 344.04945 -285.359689) (xy 344.097192 -285.342701) (xy 344.121994 -285.337504)
			(xy 344.144854 -285.333186) (xy 344.350086 -284.97784) (xy 344.342466 -284.955996) (xy 344.333844 -284.929713)
			(xy 344.324527 -284.875193) (xy 344.323924 -284.847538) (xy 344.324432 -284.821631) (xy 344.332538 -284.770454)
			(xy 344.34855 -284.721175) (xy 344.372073 -284.675008) (xy 344.402529 -284.633089) (xy 344.439167 -284.596451)
			(xy 344.481086 -284.565995) (xy 344.527253 -284.542472) (xy 344.576532 -284.52646) (xy 344.627709 -284.518354)
			(xy 344.679523 -284.518354) (xy 344.7307 -284.52646) (xy 344.779979 -284.542472) (xy 344.826146 -284.565995)
			(xy 344.868065 -284.596451) (xy 344.904703 -284.633089) (xy 344.935159 -284.675008) (xy 344.958682 -284.721175)
			(xy 344.974694 -284.770454) (xy 344.9828 -284.821631) (xy 344.983308 -284.847538) (xy 344.982861 -284.872913)
			(xy 344.975087 -284.923064) (xy 344.959714 -284.97143) (xy 344.937105 -285.016866) (xy 344.907796 -285.058297)
			(xy 344.872479 -285.094742) (xy 344.831991 -285.125341) (xy 344.787289 -285.149367) (xy 344.739431 -285.166254)
			(xy 344.714576 -285.171388) (xy 344.691716 -285.175706) (xy 344.486738 -285.530544) (xy 344.494612 -285.552642)
			(xy 344.503183 -285.578997) (xy 344.512375 -285.633645) (xy 344.5129 -285.661354) (xy 344.793824 -285.661354)
			(xy 344.794332 -285.635467) (xy 344.802431 -285.584329) (xy 344.81843 -285.535089) (xy 344.841936 -285.488957)
			(xy 344.872368 -285.44707) (xy 344.908978 -285.41046) (xy 344.950865 -285.380028) (xy 344.996997 -285.356522)
			(xy 345.046237 -285.340523) (xy 345.097375 -285.332424) (xy 345.149149 -285.332424) (xy 345.200287 -285.340523)
			(xy 345.249527 -285.356522) (xy 345.295659 -285.380028) (xy 345.337546 -285.41046) (xy 345.374156 -285.44707)
			(xy 345.404588 -285.488957) (xy 345.428094 -285.535089) (xy 345.444093 -285.584329) (xy 345.452192 -285.635467)
			(xy 345.4527 -285.661354) (xy 345.733624 -285.661354) (xy 345.734045 -285.636017) (xy 345.741805 -285.585941)
			(xy 345.757135 -285.537642) (xy 345.779675 -285.492257) (xy 345.808892 -285.450854) (xy 345.8441 -285.41441)
			(xy 345.88447 -285.383781) (xy 345.92905 -285.359689) (xy 345.976792 -285.342701) (xy 346.001594 -285.337504)
			(xy 346.024454 -285.333186) (xy 346.229686 -284.97784) (xy 346.222066 -284.955996) (xy 346.213444 -284.929713)
			(xy 346.204127 -284.875193) (xy 346.203524 -284.847538) (xy 346.204032 -284.821631) (xy 346.212138 -284.770454)
			(xy 346.22815 -284.721175) (xy 346.251673 -284.675008) (xy 346.282129 -284.633089) (xy 346.318767 -284.596451)
			(xy 346.360686 -284.565995) (xy 346.406853 -284.542472) (xy 346.456132 -284.52646) (xy 346.507309 -284.518354)
			(xy 346.559123 -284.518354) (xy 346.6103 -284.52646) (xy 346.659579 -284.542472) (xy 346.705746 -284.565995)
			(xy 346.747665 -284.596451) (xy 346.784303 -284.633089) (xy 346.814759 -284.675008) (xy 346.838282 -284.721175)
			(xy 346.854294 -284.770454) (xy 346.8624 -284.821631) (xy 346.862908 -284.847538) (xy 346.862461 -284.872913)
			(xy 346.854687 -284.923064) (xy 346.839314 -284.97143) (xy 346.816705 -285.016866) (xy 346.787396 -285.058297)
			(xy 346.752079 -285.094742) (xy 346.711591 -285.125341) (xy 346.666889 -285.149367) (xy 346.619031 -285.166254)
			(xy 346.594176 -285.171388) (xy 346.571316 -285.175706) (xy 346.366338 -285.530544) (xy 346.374212 -285.552642)
			(xy 346.382783 -285.578997) (xy 346.391975 -285.633645) (xy 346.3925 -285.661354) (xy 346.673424 -285.661354)
			(xy 346.673932 -285.635467) (xy 346.682031 -285.584329) (xy 346.69803 -285.535089) (xy 346.721536 -285.488957)
			(xy 346.751968 -285.44707) (xy 346.788578 -285.41046) (xy 346.830465 -285.380028) (xy 346.876597 -285.356522)
			(xy 346.925837 -285.340523) (xy 346.976975 -285.332424) (xy 347.028749 -285.332424) (xy 347.079887 -285.340523)
			(xy 347.129127 -285.356522) (xy 347.175259 -285.380028) (xy 347.217146 -285.41046) (xy 347.253756 -285.44707)
			(xy 347.284188 -285.488957) (xy 347.307694 -285.535089) (xy 347.323693 -285.584329) (xy 347.331792 -285.635467)
			(xy 347.3323 -285.661354) (xy 347.613224 -285.661354) (xy 347.613645 -285.636017) (xy 347.621405 -285.585941)
			(xy 347.636735 -285.537642) (xy 347.659275 -285.492257) (xy 347.688492 -285.450854) (xy 347.7237 -285.41441)
			(xy 347.76407 -285.383781) (xy 347.80865 -285.359689) (xy 347.856392 -285.342701) (xy 347.881194 -285.337504)
			(xy 347.904054 -285.333186) (xy 348.109286 -284.97784) (xy 348.101666 -284.955996) (xy 348.093044 -284.929713)
			(xy 348.083727 -284.875193) (xy 348.083124 -284.847538) (xy 348.083632 -284.821631) (xy 348.091738 -284.770454)
			(xy 348.10775 -284.721175) (xy 348.131273 -284.675008) (xy 348.161729 -284.633089) (xy 348.198367 -284.596451)
			(xy 348.240286 -284.565995) (xy 348.286453 -284.542472) (xy 348.335732 -284.52646) (xy 348.386909 -284.518354)
			(xy 348.438723 -284.518354) (xy 348.4899 -284.52646) (xy 348.539179 -284.542472) (xy 348.585346 -284.565995)
			(xy 348.627265 -284.596451) (xy 348.663903 -284.633089) (xy 348.694359 -284.675008) (xy 348.717882 -284.721175)
			(xy 348.733894 -284.770454) (xy 348.742 -284.821631) (xy 348.742508 -284.847538) (xy 348.742061 -284.872913)
			(xy 348.734287 -284.923064) (xy 348.718914 -284.97143) (xy 348.696305 -285.016866) (xy 348.666996 -285.058297)
			(xy 348.631679 -285.094742) (xy 348.591191 -285.125341) (xy 348.546489 -285.149367) (xy 348.498631 -285.166254)
			(xy 348.473776 -285.171388) (xy 348.450916 -285.175706) (xy 348.245938 -285.530544) (xy 348.253812 -285.552642)
			(xy 348.262383 -285.578997) (xy 348.271575 -285.633645) (xy 348.2721 -285.661354) (xy 348.553024 -285.661354)
			(xy 348.553532 -285.635467) (xy 348.561631 -285.584329) (xy 348.57763 -285.535089) (xy 348.601136 -285.488957)
			(xy 348.631568 -285.44707) (xy 348.668178 -285.41046) (xy 348.710065 -285.380028) (xy 348.756197 -285.356522)
			(xy 348.805437 -285.340523) (xy 348.856575 -285.332424) (xy 348.908349 -285.332424) (xy 348.959487 -285.340523)
			(xy 349.008727 -285.356522) (xy 349.054859 -285.380028) (xy 349.096746 -285.41046) (xy 349.133356 -285.44707)
			(xy 349.163788 -285.488957) (xy 349.187294 -285.535089) (xy 349.203293 -285.584329) (xy 349.211392 -285.635467)
			(xy 349.2119 -285.661354) (xy 349.492824 -285.661354) (xy 349.493245 -285.636017) (xy 349.501005 -285.585941)
			(xy 349.516335 -285.537642) (xy 349.538875 -285.492257) (xy 349.568092 -285.450854) (xy 349.6033 -285.41441)
			(xy 349.64367 -285.383781) (xy 349.68825 -285.359689) (xy 349.735992 -285.342701) (xy 349.760794 -285.337504)
			(xy 349.783654 -285.333186) (xy 349.988886 -284.97784) (xy 349.981266 -284.955996) (xy 349.972644 -284.929713)
			(xy 349.963327 -284.875193) (xy 349.962724 -284.847538) (xy 349.963232 -284.821631) (xy 349.971338 -284.770454)
			(xy 349.98735 -284.721175) (xy 350.010873 -284.675008) (xy 350.041329 -284.633089) (xy 350.077967 -284.596451)
			(xy 350.119886 -284.565995) (xy 350.166053 -284.542472) (xy 350.215332 -284.52646) (xy 350.266509 -284.518354)
			(xy 350.318323 -284.518354) (xy 350.3695 -284.52646) (xy 350.418779 -284.542472) (xy 350.464946 -284.565995)
			(xy 350.506865 -284.596451) (xy 350.543503 -284.633089) (xy 350.573959 -284.675008) (xy 350.597482 -284.721175)
			(xy 350.613494 -284.770454) (xy 350.6216 -284.821631) (xy 350.622108 -284.847538) (xy 350.621661 -284.872913)
			(xy 350.613887 -284.923064) (xy 350.598514 -284.97143) (xy 350.575905 -285.016866) (xy 350.546596 -285.058297)
			(xy 350.511279 -285.094742) (xy 350.470791 -285.125341) (xy 350.426089 -285.149367) (xy 350.378231 -285.166254)
			(xy 350.353376 -285.171388) (xy 350.330516 -285.175706) (xy 350.125538 -285.530544) (xy 350.133412 -285.552642)
			(xy 350.141983 -285.578997) (xy 350.151175 -285.633645) (xy 350.1517 -285.661354) (xy 350.432624 -285.661354)
			(xy 350.433132 -285.635467) (xy 350.441231 -285.584329) (xy 350.45723 -285.535089) (xy 350.480736 -285.488957)
			(xy 350.511168 -285.44707) (xy 350.547778 -285.41046) (xy 350.589665 -285.380028) (xy 350.635797 -285.356522)
			(xy 350.685037 -285.340523) (xy 350.736175 -285.332424) (xy 350.787949 -285.332424) (xy 350.839087 -285.340523)
			(xy 350.888327 -285.356522) (xy 350.934459 -285.380028) (xy 350.976346 -285.41046) (xy 351.012956 -285.44707)
			(xy 351.043388 -285.488957) (xy 351.066894 -285.535089) (xy 351.082893 -285.584329) (xy 351.090992 -285.635467)
			(xy 351.0915 -285.661354) (xy 351.372424 -285.661354) (xy 351.372845 -285.636017) (xy 351.380605 -285.585941)
			(xy 351.395935 -285.537642) (xy 351.418475 -285.492257) (xy 351.447692 -285.450854) (xy 351.4829 -285.41441)
			(xy 351.52327 -285.383781) (xy 351.56785 -285.359689) (xy 351.615592 -285.342701) (xy 351.640394 -285.337504)
			(xy 351.663254 -285.333186) (xy 351.868486 -284.97784) (xy 351.860866 -284.955996) (xy 351.852244 -284.929713)
			(xy 351.842927 -284.875193) (xy 351.842324 -284.847538) (xy 351.842832 -284.821631) (xy 351.850938 -284.770454)
			(xy 351.86695 -284.721175) (xy 351.890473 -284.675008) (xy 351.920929 -284.633089) (xy 351.957567 -284.596451)
			(xy 351.999486 -284.565995) (xy 352.045653 -284.542472) (xy 352.094932 -284.52646) (xy 352.146109 -284.518354)
			(xy 352.197923 -284.518354) (xy 352.2491 -284.52646) (xy 352.298379 -284.542472) (xy 352.344546 -284.565995)
			(xy 352.386465 -284.596451) (xy 352.423103 -284.633089) (xy 352.453559 -284.675008) (xy 352.477082 -284.721175)
			(xy 352.493094 -284.770454) (xy 352.5012 -284.821631) (xy 352.501708 -284.847538) (xy 366.879124 -284.847538)
			(xy 366.879632 -284.821631) (xy 366.887738 -284.770454) (xy 366.90375 -284.721175) (xy 366.927273 -284.675008)
			(xy 366.957729 -284.633089) (xy 366.994367 -284.596451) (xy 367.036286 -284.565995) (xy 367.082453 -284.542472)
			(xy 367.131732 -284.52646) (xy 367.182909 -284.518354) (xy 367.234723 -284.518354) (xy 367.2859 -284.52646)
			(xy 367.335179 -284.542472) (xy 367.381346 -284.565995) (xy 367.423265 -284.596451) (xy 367.459903 -284.633089)
			(xy 367.490359 -284.675008) (xy 367.513882 -284.721175) (xy 367.529894 -284.770454) (xy 367.538 -284.821631)
			(xy 367.538508 -284.847538) (xy 368.758724 -284.847538) (xy 368.759232 -284.821631) (xy 368.767338 -284.770454)
			(xy 368.78335 -284.721175) (xy 368.806873 -284.675008) (xy 368.837329 -284.633089) (xy 368.873967 -284.596451)
			(xy 368.915886 -284.565995) (xy 368.962053 -284.542472) (xy 369.011332 -284.52646) (xy 369.062509 -284.518354)
			(xy 369.114323 -284.518354) (xy 369.1655 -284.52646) (xy 369.214779 -284.542472) (xy 369.260946 -284.565995)
			(xy 369.302865 -284.596451) (xy 369.339503 -284.633089) (xy 369.369959 -284.675008) (xy 369.393482 -284.721175)
			(xy 369.409494 -284.770454) (xy 369.4176 -284.821631) (xy 369.418108 -284.847538) (xy 370.638324 -284.847538)
			(xy 370.638832 -284.821631) (xy 370.646938 -284.770454) (xy 370.66295 -284.721175) (xy 370.686473 -284.675008)
			(xy 370.716929 -284.633089) (xy 370.753567 -284.596451) (xy 370.795486 -284.565995) (xy 370.841653 -284.542472)
			(xy 370.890932 -284.52646) (xy 370.942109 -284.518354) (xy 370.993923 -284.518354) (xy 371.0451 -284.52646)
			(xy 371.094379 -284.542472) (xy 371.140546 -284.565995) (xy 371.182465 -284.596451) (xy 371.219103 -284.633089)
			(xy 371.249559 -284.675008) (xy 371.273082 -284.721175) (xy 371.289094 -284.770454) (xy 371.2972 -284.821631)
			(xy 371.297708 -284.847538) (xy 372.517924 -284.847538) (xy 372.518432 -284.821631) (xy 372.526538 -284.770454)
			(xy 372.54255 -284.721175) (xy 372.566073 -284.675008) (xy 372.596529 -284.633089) (xy 372.633167 -284.596451)
			(xy 372.675086 -284.565995) (xy 372.721253 -284.542472) (xy 372.770532 -284.52646) (xy 372.821709 -284.518354)
			(xy 372.873523 -284.518354) (xy 372.9247 -284.52646) (xy 372.973979 -284.542472) (xy 373.020146 -284.565995)
			(xy 373.062065 -284.596451) (xy 373.098703 -284.633089) (xy 373.129159 -284.675008) (xy 373.152682 -284.721175)
			(xy 373.168694 -284.770454) (xy 373.1768 -284.821631) (xy 373.177308 -284.847538) (xy 374.397524 -284.847538)
			(xy 374.398032 -284.821631) (xy 374.406138 -284.770454) (xy 374.42215 -284.721175) (xy 374.445673 -284.675008)
			(xy 374.476129 -284.633089) (xy 374.512767 -284.596451) (xy 374.554686 -284.565995) (xy 374.600853 -284.542472)
			(xy 374.650132 -284.52646) (xy 374.701309 -284.518354) (xy 374.753123 -284.518354) (xy 374.8043 -284.52646)
			(xy 374.853579 -284.542472) (xy 374.899746 -284.565995) (xy 374.941665 -284.596451) (xy 374.978303 -284.633089)
			(xy 375.008759 -284.675008) (xy 375.032282 -284.721175) (xy 375.048294 -284.770454) (xy 375.0564 -284.821631)
			(xy 375.056908 -284.847538) (xy 376.277124 -284.847538) (xy 376.277632 -284.821631) (xy 376.285738 -284.770454)
			(xy 376.30175 -284.721175) (xy 376.325273 -284.675008) (xy 376.355729 -284.633089) (xy 376.392367 -284.596451)
			(xy 376.434286 -284.565995) (xy 376.480453 -284.542472) (xy 376.529732 -284.52646) (xy 376.580909 -284.518354)
			(xy 376.632723 -284.518354) (xy 376.6839 -284.52646) (xy 376.733179 -284.542472) (xy 376.779346 -284.565995)
			(xy 376.821265 -284.596451) (xy 376.857903 -284.633089) (xy 376.888359 -284.675008) (xy 376.911882 -284.721175)
			(xy 376.927894 -284.770454) (xy 376.936 -284.821631) (xy 376.936508 -284.847538) (xy 378.156724 -284.847538)
			(xy 378.157232 -284.821631) (xy 378.165338 -284.770454) (xy 378.18135 -284.721175) (xy 378.204873 -284.675008)
			(xy 378.235329 -284.633089) (xy 378.271967 -284.596451) (xy 378.313886 -284.565995) (xy 378.360053 -284.542472)
			(xy 378.409332 -284.52646) (xy 378.460509 -284.518354) (xy 378.512323 -284.518354) (xy 378.5635 -284.52646)
			(xy 378.612779 -284.542472) (xy 378.658946 -284.565995) (xy 378.700865 -284.596451) (xy 378.737503 -284.633089)
			(xy 378.767959 -284.675008) (xy 378.791482 -284.721175) (xy 378.807494 -284.770454) (xy 378.8156 -284.821631)
			(xy 378.816108 -284.847538) (xy 380.036324 -284.847538) (xy 380.036832 -284.821631) (xy 380.044938 -284.770454)
			(xy 380.06095 -284.721175) (xy 380.084473 -284.675008) (xy 380.114929 -284.633089) (xy 380.151567 -284.596451)
			(xy 380.193486 -284.565995) (xy 380.239653 -284.542472) (xy 380.288932 -284.52646) (xy 380.340109 -284.518354)
			(xy 380.391923 -284.518354) (xy 380.4431 -284.52646) (xy 380.492379 -284.542472) (xy 380.538546 -284.565995)
			(xy 380.580465 -284.596451) (xy 380.617103 -284.633089) (xy 380.647559 -284.675008) (xy 380.671082 -284.721175)
			(xy 380.687094 -284.770454) (xy 380.6952 -284.821631) (xy 380.695708 -284.847538) (xy 380.695098 -284.875255)
			(xy 380.685785 -284.929901) (xy 380.677166 -284.95625) (xy 380.669292 -284.978348) (xy 380.87427 -285.333186)
			(xy 380.89713 -285.337504) (xy 380.921947 -285.342634) (xy 380.969689 -285.35963) (xy 381.014267 -285.383731)
			(xy 381.054634 -285.414369) (xy 381.089836 -285.450823) (xy 381.119046 -285.492235) (xy 381.141576 -285.537628)
			(xy 381.156894 -285.585934) (xy 381.16464 -285.636016) (xy 381.1651 -285.661354) (xy 381.164592 -285.687241)
			(xy 381.156493 -285.738379) (xy 381.140494 -285.787619) (xy 381.116988 -285.833751) (xy 381.086556 -285.875638)
			(xy 381.049946 -285.912248) (xy 381.008059 -285.94268) (xy 380.961927 -285.966186) (xy 380.912687 -285.982185)
			(xy 380.861549 -285.990284) (xy 380.809775 -285.990284) (xy 380.758637 -285.982185) (xy 380.709397 -285.966186)
			(xy 380.663265 -285.94268) (xy 380.621378 -285.912248) (xy 380.584768 -285.875638) (xy 380.554336 -285.833751)
			(xy 380.53083 -285.787619) (xy 380.514831 -285.738379) (xy 380.506732 -285.687241) (xy 380.506224 -285.661354)
			(xy 380.506766 -285.633646) (xy 380.515953 -285.579) (xy 380.524512 -285.552642) (xy 380.532386 -285.530544)
			(xy 380.327408 -285.175706) (xy 380.304548 -285.171388) (xy 380.279723 -285.166238) (xy 380.231943 -285.149282)
			(xy 380.187323 -285.125209) (xy 380.146916 -285.094586) (xy 380.111675 -285.058137) (xy 380.082431 -285.016721)
			(xy 380.059876 -284.971315) (xy 380.044539 -284.922991) (xy 380.036785 -284.872888) (xy 380.036324 -284.847538)
			(xy 378.816108 -284.847538) (xy 378.815498 -284.875255) (xy 378.806185 -284.929901) (xy 378.797566 -284.95625)
			(xy 378.789692 -284.978348) (xy 378.99467 -285.333186) (xy 379.01753 -285.337504) (xy 379.042347 -285.342634)
			(xy 379.090089 -285.35963) (xy 379.134667 -285.383731) (xy 379.175034 -285.414369) (xy 379.210236 -285.450823)
			(xy 379.239446 -285.492235) (xy 379.261976 -285.537628) (xy 379.277294 -285.585934) (xy 379.28504 -285.636016)
			(xy 379.2855 -285.661354) (xy 379.284992 -285.687241) (xy 379.276893 -285.738379) (xy 379.260894 -285.787619)
			(xy 379.237388 -285.833751) (xy 379.206956 -285.875638) (xy 379.170346 -285.912248) (xy 379.128459 -285.94268)
			(xy 379.082327 -285.966186) (xy 379.033087 -285.982185) (xy 378.981949 -285.990284) (xy 378.930175 -285.990284)
			(xy 378.879037 -285.982185) (xy 378.829797 -285.966186) (xy 378.783665 -285.94268) (xy 378.741778 -285.912248)
			(xy 378.705168 -285.875638) (xy 378.674736 -285.833751) (xy 378.65123 -285.787619) (xy 378.635231 -285.738379)
			(xy 378.627132 -285.687241) (xy 378.626624 -285.661354) (xy 378.627166 -285.633646) (xy 378.636353 -285.579)
			(xy 378.644912 -285.552642) (xy 378.652786 -285.530544) (xy 378.447808 -285.175706) (xy 378.424948 -285.171388)
			(xy 378.400123 -285.166238) (xy 378.352343 -285.149282) (xy 378.307723 -285.125209) (xy 378.267316 -285.094586)
			(xy 378.232075 -285.058137) (xy 378.202831 -285.016721) (xy 378.180276 -284.971315) (xy 378.164939 -284.922991)
			(xy 378.157185 -284.872888) (xy 378.156724 -284.847538) (xy 376.936508 -284.847538) (xy 376.935898 -284.875255)
			(xy 376.926585 -284.929901) (xy 376.917966 -284.95625) (xy 376.910092 -284.978348) (xy 377.11507 -285.333186)
			(xy 377.13793 -285.337504) (xy 377.162747 -285.342634) (xy 377.210489 -285.35963) (xy 377.255067 -285.383731)
			(xy 377.295434 -285.414369) (xy 377.330636 -285.450823) (xy 377.359846 -285.492235) (xy 377.382376 -285.537628)
			(xy 377.397694 -285.585934) (xy 377.40544 -285.636016) (xy 377.4059 -285.661354) (xy 377.405392 -285.687241)
			(xy 377.397293 -285.738379) (xy 377.381294 -285.787619) (xy 377.357788 -285.833751) (xy 377.327356 -285.875638)
			(xy 377.290746 -285.912248) (xy 377.248859 -285.94268) (xy 377.202727 -285.966186) (xy 377.153487 -285.982185)
			(xy 377.102349 -285.990284) (xy 377.050575 -285.990284) (xy 376.999437 -285.982185) (xy 376.950197 -285.966186)
			(xy 376.904065 -285.94268) (xy 376.862178 -285.912248) (xy 376.825568 -285.875638) (xy 376.795136 -285.833751)
			(xy 376.77163 -285.787619) (xy 376.755631 -285.738379) (xy 376.747532 -285.687241) (xy 376.747024 -285.661354)
			(xy 376.747566 -285.633646) (xy 376.756753 -285.579) (xy 376.765312 -285.552642) (xy 376.773186 -285.530544)
			(xy 376.568208 -285.175706) (xy 376.545348 -285.171388) (xy 376.520523 -285.166238) (xy 376.472743 -285.149282)
			(xy 376.428123 -285.125209) (xy 376.387716 -285.094586) (xy 376.352475 -285.058137) (xy 376.323231 -285.016721)
			(xy 376.300676 -284.971315) (xy 376.285339 -284.922991) (xy 376.277585 -284.872888) (xy 376.277124 -284.847538)
			(xy 375.056908 -284.847538) (xy 375.056298 -284.875255) (xy 375.046985 -284.929901) (xy 375.038366 -284.95625)
			(xy 375.030492 -284.978348) (xy 375.23547 -285.333186) (xy 375.25833 -285.337504) (xy 375.283147 -285.342634)
			(xy 375.330889 -285.35963) (xy 375.375467 -285.383731) (xy 375.415834 -285.414369) (xy 375.451036 -285.450823)
			(xy 375.480246 -285.492235) (xy 375.502776 -285.537628) (xy 375.518094 -285.585934) (xy 375.52584 -285.636016)
			(xy 375.5263 -285.661354) (xy 375.525792 -285.687241) (xy 375.517693 -285.738379) (xy 375.501694 -285.787619)
			(xy 375.478188 -285.833751) (xy 375.447756 -285.875638) (xy 375.411146 -285.912248) (xy 375.369259 -285.94268)
			(xy 375.323127 -285.966186) (xy 375.273887 -285.982185) (xy 375.222749 -285.990284) (xy 375.170975 -285.990284)
			(xy 375.119837 -285.982185) (xy 375.070597 -285.966186) (xy 375.024465 -285.94268) (xy 374.982578 -285.912248)
			(xy 374.945968 -285.875638) (xy 374.915536 -285.833751) (xy 374.89203 -285.787619) (xy 374.876031 -285.738379)
			(xy 374.867932 -285.687241) (xy 374.867424 -285.661354) (xy 374.867966 -285.633646) (xy 374.877153 -285.579)
			(xy 374.885712 -285.552642) (xy 374.893586 -285.530544) (xy 374.688608 -285.175706) (xy 374.665748 -285.171388)
			(xy 374.640923 -285.166238) (xy 374.593143 -285.149282) (xy 374.548523 -285.125209) (xy 374.508116 -285.094586)
			(xy 374.472875 -285.058137) (xy 374.443631 -285.016721) (xy 374.421076 -284.971315) (xy 374.405739 -284.922991)
			(xy 374.397985 -284.872888) (xy 374.397524 -284.847538) (xy 373.177308 -284.847538) (xy 373.176698 -284.875255)
			(xy 373.167385 -284.929901) (xy 373.158766 -284.95625) (xy 373.150892 -284.978348) (xy 373.35587 -285.333186)
			(xy 373.37873 -285.337504) (xy 373.403547 -285.342634) (xy 373.451289 -285.35963) (xy 373.495867 -285.383731)
			(xy 373.536234 -285.414369) (xy 373.571436 -285.450823) (xy 373.600646 -285.492235) (xy 373.623176 -285.537628)
			(xy 373.638494 -285.585934) (xy 373.64624 -285.636016) (xy 373.6467 -285.661354) (xy 373.646192 -285.687241)
			(xy 373.638093 -285.738379) (xy 373.622094 -285.787619) (xy 373.598588 -285.833751) (xy 373.568156 -285.875638)
			(xy 373.531546 -285.912248) (xy 373.489659 -285.94268) (xy 373.443527 -285.966186) (xy 373.394287 -285.982185)
			(xy 373.343149 -285.990284) (xy 373.291375 -285.990284) (xy 373.240237 -285.982185) (xy 373.190997 -285.966186)
			(xy 373.144865 -285.94268) (xy 373.102978 -285.912248) (xy 373.066368 -285.875638) (xy 373.035936 -285.833751)
			(xy 373.01243 -285.787619) (xy 372.996431 -285.738379) (xy 372.988332 -285.687241) (xy 372.987824 -285.661354)
			(xy 372.988366 -285.633646) (xy 372.997553 -285.579) (xy 373.006112 -285.552642) (xy 373.013986 -285.530544)
			(xy 372.809008 -285.175706) (xy 372.786148 -285.171388) (xy 372.761323 -285.166238) (xy 372.713543 -285.149282)
			(xy 372.668923 -285.125209) (xy 372.628516 -285.094586) (xy 372.593275 -285.058137) (xy 372.564031 -285.016721)
			(xy 372.541476 -284.971315) (xy 372.526139 -284.922991) (xy 372.518385 -284.872888) (xy 372.517924 -284.847538)
			(xy 371.297708 -284.847538) (xy 371.297098 -284.875255) (xy 371.287785 -284.929901) (xy 371.279166 -284.95625)
			(xy 371.271292 -284.978348) (xy 371.47627 -285.333186) (xy 371.49913 -285.337504) (xy 371.523947 -285.342634)
			(xy 371.571689 -285.35963) (xy 371.616267 -285.383731) (xy 371.656634 -285.414369) (xy 371.691836 -285.450823)
			(xy 371.721046 -285.492235) (xy 371.743576 -285.537628) (xy 371.758894 -285.585934) (xy 371.76664 -285.636016)
			(xy 371.7671 -285.661354) (xy 371.766592 -285.687241) (xy 371.758493 -285.738379) (xy 371.742494 -285.787619)
			(xy 371.718988 -285.833751) (xy 371.688556 -285.875638) (xy 371.651946 -285.912248) (xy 371.610059 -285.94268)
			(xy 371.563927 -285.966186) (xy 371.514687 -285.982185) (xy 371.463549 -285.990284) (xy 371.411775 -285.990284)
			(xy 371.360637 -285.982185) (xy 371.311397 -285.966186) (xy 371.265265 -285.94268) (xy 371.223378 -285.912248)
			(xy 371.186768 -285.875638) (xy 371.156336 -285.833751) (xy 371.13283 -285.787619) (xy 371.116831 -285.738379)
			(xy 371.108732 -285.687241) (xy 371.108224 -285.661354) (xy 371.108766 -285.633646) (xy 371.117953 -285.579)
			(xy 371.126512 -285.552642) (xy 371.134386 -285.530544) (xy 370.929408 -285.175706) (xy 370.906548 -285.171388)
			(xy 370.881723 -285.166238) (xy 370.833943 -285.149282) (xy 370.789323 -285.125209) (xy 370.748916 -285.094586)
			(xy 370.713675 -285.058137) (xy 370.684431 -285.016721) (xy 370.661876 -284.971315) (xy 370.646539 -284.922991)
			(xy 370.638785 -284.872888) (xy 370.638324 -284.847538) (xy 369.418108 -284.847538) (xy 369.417498 -284.875255)
			(xy 369.408185 -284.929901) (xy 369.399566 -284.95625) (xy 369.391692 -284.978348) (xy 369.59667 -285.333186)
			(xy 369.61953 -285.337504) (xy 369.644347 -285.342634) (xy 369.692089 -285.35963) (xy 369.736667 -285.383731)
			(xy 369.777034 -285.414369) (xy 369.812236 -285.450823) (xy 369.841446 -285.492235) (xy 369.863976 -285.537628)
			(xy 369.879294 -285.585934) (xy 369.88704 -285.636016) (xy 369.8875 -285.661354) (xy 369.886992 -285.687241)
			(xy 369.878893 -285.738379) (xy 369.862894 -285.787619) (xy 369.839388 -285.833751) (xy 369.808956 -285.875638)
			(xy 369.772346 -285.912248) (xy 369.730459 -285.94268) (xy 369.684327 -285.966186) (xy 369.635087 -285.982185)
			(xy 369.583949 -285.990284) (xy 369.532175 -285.990284) (xy 369.481037 -285.982185) (xy 369.431797 -285.966186)
			(xy 369.385665 -285.94268) (xy 369.343778 -285.912248) (xy 369.307168 -285.875638) (xy 369.276736 -285.833751)
			(xy 369.25323 -285.787619) (xy 369.237231 -285.738379) (xy 369.229132 -285.687241) (xy 369.228624 -285.661354)
			(xy 369.229166 -285.633646) (xy 369.238353 -285.579) (xy 369.246912 -285.552642) (xy 369.254786 -285.530544)
			(xy 369.049808 -285.175706) (xy 369.026948 -285.171388) (xy 369.002123 -285.166238) (xy 368.954343 -285.149282)
			(xy 368.909723 -285.125209) (xy 368.869316 -285.094586) (xy 368.834075 -285.058137) (xy 368.804831 -285.016721)
			(xy 368.782276 -284.971315) (xy 368.766939 -284.922991) (xy 368.759185 -284.872888) (xy 368.758724 -284.847538)
			(xy 367.538508 -284.847538) (xy 367.537898 -284.875255) (xy 367.528585 -284.929901) (xy 367.519966 -284.95625)
			(xy 367.512092 -284.978348) (xy 367.71707 -285.333186) (xy 367.73993 -285.337504) (xy 367.764747 -285.342634)
			(xy 367.812489 -285.35963) (xy 367.857067 -285.383731) (xy 367.897434 -285.414369) (xy 367.932636 -285.450823)
			(xy 367.961846 -285.492235) (xy 367.984376 -285.537628) (xy 367.999694 -285.585934) (xy 368.00744 -285.636016)
			(xy 368.0079 -285.661354) (xy 368.007392 -285.687241) (xy 367.999293 -285.738379) (xy 367.983294 -285.787619)
			(xy 367.959788 -285.833751) (xy 367.929356 -285.875638) (xy 367.892746 -285.912248) (xy 367.850859 -285.94268)
			(xy 367.804727 -285.966186) (xy 367.755487 -285.982185) (xy 367.704349 -285.990284) (xy 367.652575 -285.990284)
			(xy 367.601437 -285.982185) (xy 367.552197 -285.966186) (xy 367.506065 -285.94268) (xy 367.464178 -285.912248)
			(xy 367.427568 -285.875638) (xy 367.397136 -285.833751) (xy 367.37363 -285.787619) (xy 367.357631 -285.738379)
			(xy 367.349532 -285.687241) (xy 367.349024 -285.661354) (xy 367.349566 -285.633646) (xy 367.358753 -285.579)
			(xy 367.367312 -285.552642) (xy 367.375186 -285.530544) (xy 367.170208 -285.175706) (xy 367.147348 -285.171388)
			(xy 367.122523 -285.166238) (xy 367.074743 -285.149282) (xy 367.030123 -285.125209) (xy 366.989716 -285.094586)
			(xy 366.954475 -285.058137) (xy 366.925231 -285.016721) (xy 366.902676 -284.971315) (xy 366.887339 -284.922991)
			(xy 366.879585 -284.872888) (xy 366.879124 -284.847538) (xy 352.501708 -284.847538) (xy 352.501261 -284.872913)
			(xy 352.493487 -284.923064) (xy 352.478114 -284.97143) (xy 352.455505 -285.016866) (xy 352.426196 -285.058297)
			(xy 352.390879 -285.094742) (xy 352.350391 -285.125341) (xy 352.305689 -285.149367) (xy 352.257831 -285.166254)
			(xy 352.232976 -285.171388) (xy 352.210116 -285.175706) (xy 352.005138 -285.530544) (xy 352.013012 -285.552642)
			(xy 352.021583 -285.578997) (xy 352.030775 -285.633645) (xy 352.0313 -285.661354) (xy 352.030792 -285.687241)
			(xy 352.022693 -285.738379) (xy 352.006694 -285.787619) (xy 351.983188 -285.833751) (xy 351.952756 -285.875638)
			(xy 351.916146 -285.912248) (xy 351.874259 -285.94268) (xy 351.828127 -285.966186) (xy 351.778887 -285.982185)
			(xy 351.727749 -285.990284) (xy 351.675975 -285.990284) (xy 351.624837 -285.982185) (xy 351.575597 -285.966186)
			(xy 351.529465 -285.94268) (xy 351.487578 -285.912248) (xy 351.450968 -285.875638) (xy 351.420536 -285.833751)
			(xy 351.39703 -285.787619) (xy 351.381031 -285.738379) (xy 351.372932 -285.687241) (xy 351.372424 -285.661354)
			(xy 351.0915 -285.661354) (xy 351.0915 -285.661862) (xy 351.090923 -285.689379) (xy 351.081728 -285.74364)
			(xy 351.073212 -285.769812) (xy 351.065592 -285.79191) (xy 351.270824 -286.147256) (xy 351.293684 -286.151574)
			(xy 351.318506 -286.156737) (xy 351.366283 -286.173695) (xy 351.410901 -286.197768) (xy 351.451306 -286.22839)
			(xy 351.486546 -286.264837) (xy 351.515789 -286.30625) (xy 351.538346 -286.351653) (xy 351.553685 -286.399975)
			(xy 351.561445 -286.450075) (xy 351.561908 -286.475424) (xy 367.818924 -286.475424) (xy 367.819448 -286.45008)
			(xy 367.827216 -286.399991) (xy 367.842559 -286.351681) (xy 367.865115 -286.306288) (xy 367.894351 -286.264882)
			(xy 367.92958 -286.228438) (xy 367.969972 -286.197814) (xy 368.014574 -286.173733) (xy 368.062336 -286.156761)
			(xy 368.087148 -286.151574) (xy 368.110008 -286.147256) (xy 368.314986 -285.792164) (xy 368.307112 -285.77032)
			(xy 368.298538 -285.7439) (xy 368.289338 -285.689126) (xy 368.288824 -285.661354) (xy 368.289332 -285.635467)
			(xy 368.297431 -285.584329) (xy 368.31343 -285.535089) (xy 368.336936 -285.488957) (xy 368.367368 -285.44707)
			(xy 368.403978 -285.41046) (xy 368.445865 -285.380028) (xy 368.491997 -285.356522) (xy 368.541237 -285.340523)
			(xy 368.592375 -285.332424) (xy 368.644149 -285.332424) (xy 368.695287 -285.340523) (xy 368.744527 -285.356522)
			(xy 368.790659 -285.380028) (xy 368.832546 -285.41046) (xy 368.869156 -285.44707) (xy 368.899588 -285.488957)
			(xy 368.923094 -285.535089) (xy 368.939093 -285.584329) (xy 368.947192 -285.635467) (xy 368.9477 -285.661354)
			(xy 368.947266 -285.68669) (xy 368.939506 -285.736765) (xy 368.924176 -285.785062) (xy 368.901638 -285.830446)
			(xy 368.872422 -285.871848) (xy 368.837216 -285.908293) (xy 368.796849 -285.938922) (xy 368.752271 -285.963016)
			(xy 368.704531 -285.980006) (xy 368.67973 -285.985204) (xy 368.65687 -285.989522) (xy 368.451892 -286.344614)
			(xy 368.459766 -286.366458) (xy 368.468419 -286.392864) (xy 368.477734 -286.447642) (xy 368.478308 -286.475424)
			(xy 369.698524 -286.475424) (xy 369.699048 -286.45008) (xy 369.706816 -286.399991) (xy 369.722159 -286.351681)
			(xy 369.744715 -286.306288) (xy 369.773951 -286.264882) (xy 369.80918 -286.228438) (xy 369.849572 -286.197814)
			(xy 369.894174 -286.173733) (xy 369.941936 -286.156761) (xy 369.966748 -286.151574) (xy 369.989608 -286.147256)
			(xy 370.194586 -285.792164) (xy 370.186712 -285.77032) (xy 370.178138 -285.7439) (xy 370.168938 -285.689126)
			(xy 370.168424 -285.661354) (xy 370.168932 -285.635467) (xy 370.177031 -285.584329) (xy 370.19303 -285.535089)
			(xy 370.216536 -285.488957) (xy 370.246968 -285.44707) (xy 370.283578 -285.41046) (xy 370.325465 -285.380028)
			(xy 370.371597 -285.356522) (xy 370.420837 -285.340523) (xy 370.471975 -285.332424) (xy 370.523749 -285.332424)
			(xy 370.574887 -285.340523) (xy 370.624127 -285.356522) (xy 370.670259 -285.380028) (xy 370.712146 -285.41046)
			(xy 370.748756 -285.44707) (xy 370.779188 -285.488957) (xy 370.802694 -285.535089) (xy 370.818693 -285.584329)
			(xy 370.826792 -285.635467) (xy 370.8273 -285.661354) (xy 370.826866 -285.68669) (xy 370.819106 -285.736765)
			(xy 370.803776 -285.785062) (xy 370.781238 -285.830446) (xy 370.752022 -285.871848) (xy 370.716816 -285.908293)
			(xy 370.676449 -285.938922) (xy 370.631871 -285.963016) (xy 370.584131 -285.980006) (xy 370.55933 -285.985204)
			(xy 370.53647 -285.989522) (xy 370.331492 -286.344614) (xy 370.339366 -286.366458) (xy 370.348019 -286.392864)
			(xy 370.357334 -286.447642) (xy 370.357908 -286.475424) (xy 371.578124 -286.475424) (xy 371.578648 -286.45008)
			(xy 371.586416 -286.399991) (xy 371.601759 -286.351681) (xy 371.624315 -286.306288) (xy 371.653551 -286.264882)
			(xy 371.68878 -286.228438) (xy 371.729172 -286.197814) (xy 371.773774 -286.173733) (xy 371.821536 -286.156761)
			(xy 371.846348 -286.151574) (xy 371.869208 -286.147256) (xy 372.074186 -285.792164) (xy 372.066312 -285.77032)
			(xy 372.057738 -285.7439) (xy 372.048538 -285.689126) (xy 372.048024 -285.661354) (xy 372.048532 -285.635467)
			(xy 372.056631 -285.584329) (xy 372.07263 -285.535089) (xy 372.096136 -285.488957) (xy 372.126568 -285.44707)
			(xy 372.163178 -285.41046) (xy 372.205065 -285.380028) (xy 372.251197 -285.356522) (xy 372.300437 -285.340523)
			(xy 372.351575 -285.332424) (xy 372.403349 -285.332424) (xy 372.454487 -285.340523) (xy 372.503727 -285.356522)
			(xy 372.549859 -285.380028) (xy 372.591746 -285.41046) (xy 372.628356 -285.44707) (xy 372.658788 -285.488957)
			(xy 372.682294 -285.535089) (xy 372.698293 -285.584329) (xy 372.706392 -285.635467) (xy 372.7069 -285.661354)
			(xy 372.706466 -285.68669) (xy 372.698706 -285.736765) (xy 372.683376 -285.785062) (xy 372.660838 -285.830446)
			(xy 372.631622 -285.871848) (xy 372.596416 -285.908293) (xy 372.556049 -285.938922) (xy 372.511471 -285.963016)
			(xy 372.463731 -285.980006) (xy 372.43893 -285.985204) (xy 372.41607 -285.989522) (xy 372.211092 -286.344614)
			(xy 372.218966 -286.366458) (xy 372.227619 -286.392864) (xy 372.236934 -286.447642) (xy 372.237508 -286.475424)
			(xy 373.457724 -286.475424) (xy 373.458248 -286.45008) (xy 373.466016 -286.399991) (xy 373.481359 -286.351681)
			(xy 373.503915 -286.306288) (xy 373.533151 -286.264882) (xy 373.56838 -286.228438) (xy 373.608772 -286.197814)
			(xy 373.653374 -286.173733) (xy 373.701136 -286.156761) (xy 373.725948 -286.151574) (xy 373.748808 -286.147256)
			(xy 373.953786 -285.792164) (xy 373.945912 -285.77032) (xy 373.937338 -285.7439) (xy 373.928138 -285.689126)
			(xy 373.927624 -285.661354) (xy 373.928132 -285.635467) (xy 373.936231 -285.584329) (xy 373.95223 -285.535089)
			(xy 373.975736 -285.488957) (xy 374.006168 -285.44707) (xy 374.042778 -285.41046) (xy 374.084665 -285.380028)
			(xy 374.130797 -285.356522) (xy 374.180037 -285.340523) (xy 374.231175 -285.332424) (xy 374.282949 -285.332424)
			(xy 374.334087 -285.340523) (xy 374.383327 -285.356522) (xy 374.429459 -285.380028) (xy 374.471346 -285.41046)
			(xy 374.507956 -285.44707) (xy 374.538388 -285.488957) (xy 374.561894 -285.535089) (xy 374.577893 -285.584329)
			(xy 374.585992 -285.635467) (xy 374.5865 -285.661354) (xy 374.586066 -285.68669) (xy 374.578306 -285.736765)
			(xy 374.562976 -285.785062) (xy 374.540438 -285.830446) (xy 374.511222 -285.871848) (xy 374.476016 -285.908293)
			(xy 374.435649 -285.938922) (xy 374.391071 -285.963016) (xy 374.343331 -285.980006) (xy 374.31853 -285.985204)
			(xy 374.29567 -285.989522) (xy 374.090692 -286.344614) (xy 374.098566 -286.366458) (xy 374.107219 -286.392864)
			(xy 374.116534 -286.447642) (xy 374.117108 -286.475424) (xy 375.337324 -286.475424) (xy 375.337848 -286.45008)
			(xy 375.345616 -286.399991) (xy 375.360959 -286.351681) (xy 375.383515 -286.306288) (xy 375.412751 -286.264882)
			(xy 375.44798 -286.228438) (xy 375.488372 -286.197814) (xy 375.532974 -286.173733) (xy 375.580736 -286.156761)
			(xy 375.605548 -286.151574) (xy 375.628408 -286.147256) (xy 375.833386 -285.792164) (xy 375.825512 -285.77032)
			(xy 375.816938 -285.7439) (xy 375.807738 -285.689126) (xy 375.807224 -285.661354) (xy 375.807732 -285.635467)
			(xy 375.815831 -285.584329) (xy 375.83183 -285.535089) (xy 375.855336 -285.488957) (xy 375.885768 -285.44707)
			(xy 375.922378 -285.41046) (xy 375.964265 -285.380028) (xy 376.010397 -285.356522) (xy 376.059637 -285.340523)
			(xy 376.110775 -285.332424) (xy 376.162549 -285.332424) (xy 376.213687 -285.340523) (xy 376.262927 -285.356522)
			(xy 376.309059 -285.380028) (xy 376.350946 -285.41046) (xy 376.387556 -285.44707) (xy 376.417988 -285.488957)
			(xy 376.441494 -285.535089) (xy 376.457493 -285.584329) (xy 376.465592 -285.635467) (xy 376.4661 -285.661354)
			(xy 376.465666 -285.68669) (xy 376.457906 -285.736765) (xy 376.442576 -285.785062) (xy 376.420038 -285.830446)
			(xy 376.390822 -285.871848) (xy 376.355616 -285.908293) (xy 376.315249 -285.938922) (xy 376.270671 -285.963016)
			(xy 376.222931 -285.980006) (xy 376.19813 -285.985204) (xy 376.17527 -285.989522) (xy 375.970292 -286.344614)
			(xy 375.978166 -286.366458) (xy 375.986819 -286.392864) (xy 375.996134 -286.447642) (xy 375.996708 -286.475424)
			(xy 377.216924 -286.475424) (xy 377.217448 -286.45008) (xy 377.225216 -286.399991) (xy 377.240559 -286.351681)
			(xy 377.263115 -286.306288) (xy 377.292351 -286.264882) (xy 377.32758 -286.228438) (xy 377.367972 -286.197814)
			(xy 377.412574 -286.173733) (xy 377.460336 -286.156761) (xy 377.485148 -286.151574) (xy 377.508008 -286.147256)
			(xy 377.712986 -285.792164) (xy 377.705112 -285.77032) (xy 377.696538 -285.7439) (xy 377.687338 -285.689126)
			(xy 377.686824 -285.661354) (xy 377.687332 -285.635467) (xy 377.695431 -285.584329) (xy 377.71143 -285.535089)
			(xy 377.734936 -285.488957) (xy 377.765368 -285.44707) (xy 377.801978 -285.41046) (xy 377.843865 -285.380028)
			(xy 377.889997 -285.356522) (xy 377.939237 -285.340523) (xy 377.990375 -285.332424) (xy 378.042149 -285.332424)
			(xy 378.093287 -285.340523) (xy 378.142527 -285.356522) (xy 378.188659 -285.380028) (xy 378.230546 -285.41046)
			(xy 378.267156 -285.44707) (xy 378.297588 -285.488957) (xy 378.321094 -285.535089) (xy 378.337093 -285.584329)
			(xy 378.345192 -285.635467) (xy 378.3457 -285.661354) (xy 378.345266 -285.68669) (xy 378.337506 -285.736765)
			(xy 378.322176 -285.785062) (xy 378.299638 -285.830446) (xy 378.270422 -285.871848) (xy 378.235216 -285.908293)
			(xy 378.194849 -285.938922) (xy 378.150271 -285.963016) (xy 378.102531 -285.980006) (xy 378.07773 -285.985204)
			(xy 378.05487 -285.989522) (xy 377.849892 -286.344614) (xy 377.857766 -286.366458) (xy 377.866419 -286.392864)
			(xy 377.875734 -286.447642) (xy 377.876308 -286.475424) (xy 379.096524 -286.475424) (xy 379.097048 -286.45008)
			(xy 379.104816 -286.399991) (xy 379.120159 -286.351681) (xy 379.142715 -286.306288) (xy 379.171951 -286.264882)
			(xy 379.20718 -286.228438) (xy 379.247572 -286.197814) (xy 379.292174 -286.173733) (xy 379.339936 -286.156761)
			(xy 379.364748 -286.151574) (xy 379.387608 -286.147256) (xy 379.592586 -285.792164) (xy 379.584712 -285.77032)
			(xy 379.576138 -285.7439) (xy 379.566938 -285.689126) (xy 379.566424 -285.661354) (xy 379.566932 -285.635467)
			(xy 379.575031 -285.584329) (xy 379.59103 -285.535089) (xy 379.614536 -285.488957) (xy 379.644968 -285.44707)
			(xy 379.681578 -285.41046) (xy 379.723465 -285.380028) (xy 379.769597 -285.356522) (xy 379.818837 -285.340523)
			(xy 379.869975 -285.332424) (xy 379.921749 -285.332424) (xy 379.972887 -285.340523) (xy 380.022127 -285.356522)
			(xy 380.068259 -285.380028) (xy 380.110146 -285.41046) (xy 380.146756 -285.44707) (xy 380.177188 -285.488957)
			(xy 380.200694 -285.535089) (xy 380.216693 -285.584329) (xy 380.224792 -285.635467) (xy 380.2253 -285.661354)
			(xy 380.224866 -285.68669) (xy 380.217106 -285.736765) (xy 380.201776 -285.785062) (xy 380.179238 -285.830446)
			(xy 380.150022 -285.871848) (xy 380.114816 -285.908293) (xy 380.074449 -285.938922) (xy 380.029871 -285.963016)
			(xy 379.982131 -285.980006) (xy 379.95733 -285.985204) (xy 379.93447 -285.989522) (xy 379.729492 -286.344614)
			(xy 379.737366 -286.366458) (xy 379.746019 -286.392864) (xy 379.755334 -286.447642) (xy 379.755908 -286.475424)
			(xy 380.976124 -286.475424) (xy 380.976648 -286.45008) (xy 380.984416 -286.399991) (xy 380.999759 -286.351681)
			(xy 381.022315 -286.306288) (xy 381.051551 -286.264882) (xy 381.08678 -286.228438) (xy 381.127172 -286.197814)
			(xy 381.171774 -286.173733) (xy 381.219536 -286.156761) (xy 381.244348 -286.151574) (xy 381.267208 -286.147256)
			(xy 381.472186 -285.792164) (xy 381.464312 -285.77032) (xy 381.455738 -285.7439) (xy 381.446538 -285.689126)
			(xy 381.446024 -285.661354) (xy 381.446532 -285.635467) (xy 381.454631 -285.584329) (xy 381.47063 -285.535089)
			(xy 381.494136 -285.488957) (xy 381.524568 -285.44707) (xy 381.561178 -285.41046) (xy 381.603065 -285.380028)
			(xy 381.649197 -285.356522) (xy 381.698437 -285.340523) (xy 381.749575 -285.332424) (xy 381.801349 -285.332424)
			(xy 381.852487 -285.340523) (xy 381.901727 -285.356522) (xy 381.947859 -285.380028) (xy 381.989746 -285.41046)
			(xy 382.026356 -285.44707) (xy 382.056788 -285.488957) (xy 382.080294 -285.535089) (xy 382.096293 -285.584329)
			(xy 382.104392 -285.635467) (xy 382.1049 -285.661354) (xy 382.104466 -285.68669) (xy 382.096706 -285.736765)
			(xy 382.081376 -285.785062) (xy 382.058838 -285.830446) (xy 382.029622 -285.871848) (xy 381.994416 -285.908293)
			(xy 381.954049 -285.938922) (xy 381.909471 -285.963016) (xy 381.861731 -285.980006) (xy 381.83693 -285.985204)
			(xy 381.81407 -285.989522) (xy 381.609092 -286.344614) (xy 381.616966 -286.366458) (xy 381.625619 -286.392864)
			(xy 381.634934 -286.447642) (xy 381.635508 -286.475424) (xy 381.635 -286.501331) (xy 381.626894 -286.552508)
			(xy 381.610882 -286.601787) (xy 381.587359 -286.647954) (xy 381.556903 -286.689873) (xy 381.520265 -286.726511)
			(xy 381.478346 -286.756967) (xy 381.432179 -286.78049) (xy 381.3829 -286.796502) (xy 381.331723 -286.804608)
			(xy 381.279909 -286.804608) (xy 381.228732 -286.796502) (xy 381.179453 -286.78049) (xy 381.133286 -286.756967)
			(xy 381.091367 -286.726511) (xy 381.054729 -286.689873) (xy 381.024273 -286.647954) (xy 381.00075 -286.601787)
			(xy 380.984738 -286.552508) (xy 380.976632 -286.501331) (xy 380.976124 -286.475424) (xy 379.755908 -286.475424)
			(xy 379.7554 -286.501331) (xy 379.747294 -286.552508) (xy 379.731282 -286.601787) (xy 379.707759 -286.647954)
			(xy 379.677303 -286.689873) (xy 379.640665 -286.726511) (xy 379.598746 -286.756967) (xy 379.552579 -286.78049)
			(xy 379.5033 -286.796502) (xy 379.452123 -286.804608) (xy 379.400309 -286.804608) (xy 379.349132 -286.796502)
			(xy 379.299853 -286.78049) (xy 379.253686 -286.756967) (xy 379.211767 -286.726511) (xy 379.175129 -286.689873)
			(xy 379.144673 -286.647954) (xy 379.12115 -286.601787) (xy 379.105138 -286.552508) (xy 379.097032 -286.501331)
			(xy 379.096524 -286.475424) (xy 377.876308 -286.475424) (xy 377.8758 -286.501331) (xy 377.867694 -286.552508)
			(xy 377.851682 -286.601787) (xy 377.828159 -286.647954) (xy 377.797703 -286.689873) (xy 377.761065 -286.726511)
			(xy 377.719146 -286.756967) (xy 377.672979 -286.78049) (xy 377.6237 -286.796502) (xy 377.572523 -286.804608)
			(xy 377.520709 -286.804608) (xy 377.469532 -286.796502) (xy 377.420253 -286.78049) (xy 377.374086 -286.756967)
			(xy 377.332167 -286.726511) (xy 377.295529 -286.689873) (xy 377.265073 -286.647954) (xy 377.24155 -286.601787)
			(xy 377.225538 -286.552508) (xy 377.217432 -286.501331) (xy 377.216924 -286.475424) (xy 375.996708 -286.475424)
			(xy 375.9962 -286.501331) (xy 375.988094 -286.552508) (xy 375.972082 -286.601787) (xy 375.948559 -286.647954)
			(xy 375.918103 -286.689873) (xy 375.881465 -286.726511) (xy 375.839546 -286.756967) (xy 375.793379 -286.78049)
			(xy 375.7441 -286.796502) (xy 375.692923 -286.804608) (xy 375.641109 -286.804608) (xy 375.589932 -286.796502)
			(xy 375.540653 -286.78049) (xy 375.494486 -286.756967) (xy 375.452567 -286.726511) (xy 375.415929 -286.689873)
			(xy 375.385473 -286.647954) (xy 375.36195 -286.601787) (xy 375.345938 -286.552508) (xy 375.337832 -286.501331)
			(xy 375.337324 -286.475424) (xy 374.117108 -286.475424) (xy 374.1166 -286.501331) (xy 374.108494 -286.552508)
			(xy 374.092482 -286.601787) (xy 374.068959 -286.647954) (xy 374.038503 -286.689873) (xy 374.001865 -286.726511)
			(xy 373.959946 -286.756967) (xy 373.913779 -286.78049) (xy 373.8645 -286.796502) (xy 373.813323 -286.804608)
			(xy 373.761509 -286.804608) (xy 373.710332 -286.796502) (xy 373.661053 -286.78049) (xy 373.614886 -286.756967)
			(xy 373.572967 -286.726511) (xy 373.536329 -286.689873) (xy 373.505873 -286.647954) (xy 373.48235 -286.601787)
			(xy 373.466338 -286.552508) (xy 373.458232 -286.501331) (xy 373.457724 -286.475424) (xy 372.237508 -286.475424)
			(xy 372.237 -286.501331) (xy 372.228894 -286.552508) (xy 372.212882 -286.601787) (xy 372.189359 -286.647954)
			(xy 372.158903 -286.689873) (xy 372.122265 -286.726511) (xy 372.080346 -286.756967) (xy 372.034179 -286.78049)
			(xy 371.9849 -286.796502) (xy 371.933723 -286.804608) (xy 371.881909 -286.804608) (xy 371.830732 -286.796502)
			(xy 371.781453 -286.78049) (xy 371.735286 -286.756967) (xy 371.693367 -286.726511) (xy 371.656729 -286.689873)
			(xy 371.626273 -286.647954) (xy 371.60275 -286.601787) (xy 371.586738 -286.552508) (xy 371.578632 -286.501331)
			(xy 371.578124 -286.475424) (xy 370.357908 -286.475424) (xy 370.3574 -286.501331) (xy 370.349294 -286.552508)
			(xy 370.333282 -286.601787) (xy 370.309759 -286.647954) (xy 370.279303 -286.689873) (xy 370.242665 -286.726511)
			(xy 370.200746 -286.756967) (xy 370.154579 -286.78049) (xy 370.1053 -286.796502) (xy 370.054123 -286.804608)
			(xy 370.002309 -286.804608) (xy 369.951132 -286.796502) (xy 369.901853 -286.78049) (xy 369.855686 -286.756967)
			(xy 369.813767 -286.726511) (xy 369.777129 -286.689873) (xy 369.746673 -286.647954) (xy 369.72315 -286.601787)
			(xy 369.707138 -286.552508) (xy 369.699032 -286.501331) (xy 369.698524 -286.475424) (xy 368.478308 -286.475424)
			(xy 368.4778 -286.501331) (xy 368.469694 -286.552508) (xy 368.453682 -286.601787) (xy 368.430159 -286.647954)
			(xy 368.399703 -286.689873) (xy 368.363065 -286.726511) (xy 368.321146 -286.756967) (xy 368.274979 -286.78049)
			(xy 368.2257 -286.796502) (xy 368.174523 -286.804608) (xy 368.122709 -286.804608) (xy 368.071532 -286.796502)
			(xy 368.022253 -286.78049) (xy 367.976086 -286.756967) (xy 367.934167 -286.726511) (xy 367.897529 -286.689873)
			(xy 367.867073 -286.647954) (xy 367.84355 -286.601787) (xy 367.827538 -286.552508) (xy 367.819432 -286.501331)
			(xy 367.818924 -286.475424) (xy 351.561908 -286.475424) (xy 351.5614 -286.501331) (xy 351.553294 -286.552508)
			(xy 351.537282 -286.601787) (xy 351.513759 -286.647954) (xy 351.483303 -286.689873) (xy 351.446665 -286.726511)
			(xy 351.404746 -286.756967) (xy 351.358579 -286.78049) (xy 351.3093 -286.796502) (xy 351.258123 -286.804608)
			(xy 351.206309 -286.804608) (xy 351.155132 -286.796502) (xy 351.105853 -286.78049) (xy 351.059686 -286.756967)
			(xy 351.017767 -286.726511) (xy 350.981129 -286.689873) (xy 350.950673 -286.647954) (xy 350.92715 -286.601787)
			(xy 350.911138 -286.552508) (xy 350.903032 -286.501331) (xy 350.902524 -286.475424) (xy 350.903123 -286.447707)
			(xy 350.912443 -286.39306) (xy 350.921066 -286.366712) (xy 350.92894 -286.344614) (xy 350.723962 -285.989522)
			(xy 350.700848 -285.985204) (xy 350.676027 -285.980039) (xy 350.628247 -285.963084) (xy 350.583628 -285.939012)
			(xy 350.543222 -285.908392) (xy 350.507981 -285.871945) (xy 350.478737 -285.830531) (xy 350.45618 -285.785127)
			(xy 350.440843 -285.736804) (xy 350.433086 -285.686703) (xy 350.432624 -285.661354) (xy 350.1517 -285.661354)
			(xy 350.151192 -285.687241) (xy 350.143093 -285.738379) (xy 350.127094 -285.787619) (xy 350.103588 -285.833751)
			(xy 350.073156 -285.875638) (xy 350.036546 -285.912248) (xy 349.994659 -285.94268) (xy 349.948527 -285.966186)
			(xy 349.899287 -285.982185) (xy 349.848149 -285.990284) (xy 349.796375 -285.990284) (xy 349.745237 -285.982185)
			(xy 349.695997 -285.966186) (xy 349.649865 -285.94268) (xy 349.607978 -285.912248) (xy 349.571368 -285.875638)
			(xy 349.540936 -285.833751) (xy 349.51743 -285.787619) (xy 349.501431 -285.738379) (xy 349.493332 -285.687241)
			(xy 349.492824 -285.661354) (xy 349.2119 -285.661354) (xy 349.2119 -285.661862) (xy 349.211323 -285.689379)
			(xy 349.202128 -285.74364) (xy 349.193612 -285.769812) (xy 349.185992 -285.79191) (xy 349.391224 -286.147256)
			(xy 349.414084 -286.151574) (xy 349.438906 -286.156737) (xy 349.486683 -286.173695) (xy 349.531301 -286.197768)
			(xy 349.571706 -286.22839) (xy 349.606946 -286.264837) (xy 349.636189 -286.30625) (xy 349.658746 -286.351653)
			(xy 349.674085 -286.399975) (xy 349.681845 -286.450075) (xy 349.682308 -286.475424) (xy 349.6818 -286.501331)
			(xy 349.673694 -286.552508) (xy 349.657682 -286.601787) (xy 349.634159 -286.647954) (xy 349.603703 -286.689873)
			(xy 349.567065 -286.726511) (xy 349.525146 -286.756967) (xy 349.478979 -286.78049) (xy 349.4297 -286.796502)
			(xy 349.378523 -286.804608) (xy 349.326709 -286.804608) (xy 349.275532 -286.796502) (xy 349.226253 -286.78049)
			(xy 349.180086 -286.756967) (xy 349.138167 -286.726511) (xy 349.101529 -286.689873) (xy 349.071073 -286.647954)
			(xy 349.04755 -286.601787) (xy 349.031538 -286.552508) (xy 349.023432 -286.501331) (xy 349.022924 -286.475424)
			(xy 349.023523 -286.447707) (xy 349.032843 -286.39306) (xy 349.041466 -286.366712) (xy 349.04934 -286.344614)
			(xy 348.844362 -285.989522) (xy 348.821248 -285.985204) (xy 348.796427 -285.980039) (xy 348.748647 -285.963084)
			(xy 348.704028 -285.939012) (xy 348.663622 -285.908392) (xy 348.628381 -285.871945) (xy 348.599137 -285.830531)
			(xy 348.57658 -285.785127) (xy 348.561243 -285.736804) (xy 348.553486 -285.686703) (xy 348.553024 -285.661354)
			(xy 348.2721 -285.661354) (xy 348.271592 -285.687241) (xy 348.263493 -285.738379) (xy 348.247494 -285.787619)
			(xy 348.223988 -285.833751) (xy 348.193556 -285.875638) (xy 348.156946 -285.912248) (xy 348.115059 -285.94268)
			(xy 348.068927 -285.966186) (xy 348.019687 -285.982185) (xy 347.968549 -285.990284) (xy 347.916775 -285.990284)
			(xy 347.865637 -285.982185) (xy 347.816397 -285.966186) (xy 347.770265 -285.94268) (xy 347.728378 -285.912248)
			(xy 347.691768 -285.875638) (xy 347.661336 -285.833751) (xy 347.63783 -285.787619) (xy 347.621831 -285.738379)
			(xy 347.613732 -285.687241) (xy 347.613224 -285.661354) (xy 347.3323 -285.661354) (xy 347.3323 -285.661862)
			(xy 347.331723 -285.689379) (xy 347.322528 -285.74364) (xy 347.314012 -285.769812) (xy 347.306392 -285.79191)
			(xy 347.511624 -286.147256) (xy 347.534484 -286.151574) (xy 347.559306 -286.156737) (xy 347.607083 -286.173695)
			(xy 347.651701 -286.197768) (xy 347.692106 -286.22839) (xy 347.727346 -286.264837) (xy 347.756589 -286.30625)
			(xy 347.779146 -286.351653) (xy 347.794485 -286.399975) (xy 347.802245 -286.450075) (xy 347.802708 -286.475424)
			(xy 347.8022 -286.501331) (xy 347.794094 -286.552508) (xy 347.778082 -286.601787) (xy 347.754559 -286.647954)
			(xy 347.724103 -286.689873) (xy 347.687465 -286.726511) (xy 347.645546 -286.756967) (xy 347.599379 -286.78049)
			(xy 347.5501 -286.796502) (xy 347.498923 -286.804608) (xy 347.447109 -286.804608) (xy 347.395932 -286.796502)
			(xy 347.346653 -286.78049) (xy 347.300486 -286.756967) (xy 347.258567 -286.726511) (xy 347.221929 -286.689873)
			(xy 347.191473 -286.647954) (xy 347.16795 -286.601787) (xy 347.151938 -286.552508) (xy 347.143832 -286.501331)
			(xy 347.143324 -286.475424) (xy 347.143923 -286.447707) (xy 347.153243 -286.39306) (xy 347.161866 -286.366712)
			(xy 347.16974 -286.344614) (xy 346.964762 -285.989522) (xy 346.941648 -285.985204) (xy 346.916827 -285.980039)
			(xy 346.869047 -285.963084) (xy 346.824428 -285.939012) (xy 346.784022 -285.908392) (xy 346.748781 -285.871945)
			(xy 346.719537 -285.830531) (xy 346.69698 -285.785127) (xy 346.681643 -285.736804) (xy 346.673886 -285.686703)
			(xy 346.673424 -285.661354) (xy 346.3925 -285.661354) (xy 346.391992 -285.687241) (xy 346.383893 -285.738379)
			(xy 346.367894 -285.787619) (xy 346.344388 -285.833751) (xy 346.313956 -285.875638) (xy 346.277346 -285.912248)
			(xy 346.235459 -285.94268) (xy 346.189327 -285.966186) (xy 346.140087 -285.982185) (xy 346.088949 -285.990284)
			(xy 346.037175 -285.990284) (xy 345.986037 -285.982185) (xy 345.936797 -285.966186) (xy 345.890665 -285.94268)
			(xy 345.848778 -285.912248) (xy 345.812168 -285.875638) (xy 345.781736 -285.833751) (xy 345.75823 -285.787619)
			(xy 345.742231 -285.738379) (xy 345.734132 -285.687241) (xy 345.733624 -285.661354) (xy 345.4527 -285.661354)
			(xy 345.4527 -285.661862) (xy 345.452123 -285.689379) (xy 345.442928 -285.74364) (xy 345.434412 -285.769812)
			(xy 345.426792 -285.79191) (xy 345.632024 -286.147256) (xy 345.654884 -286.151574) (xy 345.679706 -286.156737)
			(xy 345.727483 -286.173695) (xy 345.772101 -286.197768) (xy 345.812506 -286.22839) (xy 345.847746 -286.264837)
			(xy 345.876989 -286.30625) (xy 345.899546 -286.351653) (xy 345.914885 -286.399975) (xy 345.922645 -286.450075)
			(xy 345.923108 -286.475424) (xy 345.9226 -286.501331) (xy 345.914494 -286.552508) (xy 345.898482 -286.601787)
			(xy 345.874959 -286.647954) (xy 345.844503 -286.689873) (xy 345.807865 -286.726511) (xy 345.765946 -286.756967)
			(xy 345.719779 -286.78049) (xy 345.6705 -286.796502) (xy 345.619323 -286.804608) (xy 345.567509 -286.804608)
			(xy 345.516332 -286.796502) (xy 345.467053 -286.78049) (xy 345.420886 -286.756967) (xy 345.378967 -286.726511)
			(xy 345.342329 -286.689873) (xy 345.311873 -286.647954) (xy 345.28835 -286.601787) (xy 345.272338 -286.552508)
			(xy 345.264232 -286.501331) (xy 345.263724 -286.475424) (xy 345.264323 -286.447707) (xy 345.273643 -286.39306)
			(xy 345.282266 -286.366712) (xy 345.29014 -286.344614) (xy 345.085162 -285.989522) (xy 345.062048 -285.985204)
			(xy 345.037227 -285.980039) (xy 344.989447 -285.963084) (xy 344.944828 -285.939012) (xy 344.904422 -285.908392)
			(xy 344.869181 -285.871945) (xy 344.839937 -285.830531) (xy 344.81738 -285.785127) (xy 344.802043 -285.736804)
			(xy 344.794286 -285.686703) (xy 344.793824 -285.661354) (xy 344.5129 -285.661354) (xy 344.512392 -285.687241)
			(xy 344.504293 -285.738379) (xy 344.488294 -285.787619) (xy 344.464788 -285.833751) (xy 344.434356 -285.875638)
			(xy 344.397746 -285.912248) (xy 344.355859 -285.94268) (xy 344.309727 -285.966186) (xy 344.260487 -285.982185)
			(xy 344.209349 -285.990284) (xy 344.157575 -285.990284) (xy 344.106437 -285.982185) (xy 344.057197 -285.966186)
			(xy 344.011065 -285.94268) (xy 343.969178 -285.912248) (xy 343.932568 -285.875638) (xy 343.902136 -285.833751)
			(xy 343.87863 -285.787619) (xy 343.862631 -285.738379) (xy 343.854532 -285.687241) (xy 343.854024 -285.661354)
			(xy 343.5731 -285.661354) (xy 343.5731 -285.661862) (xy 343.572523 -285.689379) (xy 343.563328 -285.74364)
			(xy 343.554812 -285.769812) (xy 343.547192 -285.79191) (xy 343.752424 -286.147256) (xy 343.775284 -286.151574)
			(xy 343.800106 -286.156737) (xy 343.847883 -286.173695) (xy 343.892501 -286.197768) (xy 343.932906 -286.22839)
			(xy 343.968146 -286.264837) (xy 343.997389 -286.30625) (xy 344.019946 -286.351653) (xy 344.035285 -286.399975)
			(xy 344.043045 -286.450075) (xy 344.043508 -286.475424) (xy 344.043 -286.501331) (xy 344.034894 -286.552508)
			(xy 344.018882 -286.601787) (xy 343.995359 -286.647954) (xy 343.964903 -286.689873) (xy 343.928265 -286.726511)
			(xy 343.886346 -286.756967) (xy 343.840179 -286.78049) (xy 343.7909 -286.796502) (xy 343.739723 -286.804608)
			(xy 343.687909 -286.804608) (xy 343.636732 -286.796502) (xy 343.587453 -286.78049) (xy 343.541286 -286.756967)
			(xy 343.499367 -286.726511) (xy 343.462729 -286.689873) (xy 343.432273 -286.647954) (xy 343.40875 -286.601787)
			(xy 343.392738 -286.552508) (xy 343.384632 -286.501331) (xy 343.384124 -286.475424) (xy 343.384723 -286.447707)
			(xy 343.394043 -286.39306) (xy 343.402666 -286.366712) (xy 343.41054 -286.344614) (xy 343.205562 -285.989522)
			(xy 343.182448 -285.985204) (xy 343.157627 -285.980039) (xy 343.109847 -285.963084) (xy 343.065228 -285.939012)
			(xy 343.024822 -285.908392) (xy 342.989581 -285.871945) (xy 342.960337 -285.830531) (xy 342.93778 -285.785127)
			(xy 342.922443 -285.736804) (xy 342.914686 -285.686703) (xy 342.914224 -285.661354) (xy 342.6333 -285.661354)
			(xy 342.632792 -285.687241) (xy 342.624693 -285.738379) (xy 342.608694 -285.787619) (xy 342.585188 -285.833751)
			(xy 342.554756 -285.875638) (xy 342.518146 -285.912248) (xy 342.476259 -285.94268) (xy 342.430127 -285.966186)
			(xy 342.380887 -285.982185) (xy 342.329749 -285.990284) (xy 342.277975 -285.990284) (xy 342.226837 -285.982185)
			(xy 342.177597 -285.966186) (xy 342.131465 -285.94268) (xy 342.089578 -285.912248) (xy 342.052968 -285.875638)
			(xy 342.022536 -285.833751) (xy 341.99903 -285.787619) (xy 341.983031 -285.738379) (xy 341.974932 -285.687241)
			(xy 341.974424 -285.661354) (xy 341.6935 -285.661354) (xy 341.6935 -285.661862) (xy 341.692923 -285.689379)
			(xy 341.683728 -285.74364) (xy 341.675212 -285.769812) (xy 341.667592 -285.79191) (xy 341.872824 -286.147256)
			(xy 341.895684 -286.151574) (xy 341.920506 -286.156737) (xy 341.968283 -286.173695) (xy 342.012901 -286.197768)
			(xy 342.053306 -286.22839) (xy 342.088546 -286.264837) (xy 342.117789 -286.30625) (xy 342.140346 -286.351653)
			(xy 342.155685 -286.399975) (xy 342.163445 -286.450075) (xy 342.163908 -286.475424) (xy 342.1634 -286.501331)
			(xy 342.155294 -286.552508) (xy 342.139282 -286.601787) (xy 342.115759 -286.647954) (xy 342.085303 -286.689873)
			(xy 342.048665 -286.726511) (xy 342.006746 -286.756967) (xy 341.960579 -286.78049) (xy 341.9113 -286.796502)
			(xy 341.860123 -286.804608) (xy 341.808309 -286.804608) (xy 341.757132 -286.796502) (xy 341.707853 -286.78049)
			(xy 341.661686 -286.756967) (xy 341.619767 -286.726511) (xy 341.583129 -286.689873) (xy 341.552673 -286.647954)
			(xy 341.52915 -286.601787) (xy 341.513138 -286.552508) (xy 341.505032 -286.501331) (xy 341.504524 -286.475424)
			(xy 341.505123 -286.447707) (xy 341.514443 -286.39306) (xy 341.523066 -286.366712) (xy 341.53094 -286.344614)
			(xy 341.325962 -285.989522) (xy 341.302848 -285.985204) (xy 341.278027 -285.980039) (xy 341.230247 -285.963084)
			(xy 341.185628 -285.939012) (xy 341.145222 -285.908392) (xy 341.109981 -285.871945) (xy 341.080737 -285.830531)
			(xy 341.05818 -285.785127) (xy 341.042843 -285.736804) (xy 341.035086 -285.686703) (xy 341.034624 -285.661354)
			(xy 340.7537 -285.661354) (xy 340.753192 -285.687241) (xy 340.745093 -285.738379) (xy 340.729094 -285.787619)
			(xy 340.705588 -285.833751) (xy 340.675156 -285.875638) (xy 340.638546 -285.912248) (xy 340.596659 -285.94268)
			(xy 340.550527 -285.966186) (xy 340.501287 -285.982185) (xy 340.450149 -285.990284) (xy 340.398375 -285.990284)
			(xy 340.347237 -285.982185) (xy 340.297997 -285.966186) (xy 340.251865 -285.94268) (xy 340.209978 -285.912248)
			(xy 340.173368 -285.875638) (xy 340.142936 -285.833751) (xy 340.11943 -285.787619) (xy 340.103431 -285.738379)
			(xy 340.095332 -285.687241) (xy 340.094824 -285.661354) (xy 339.814408 -285.661354) (xy 339.813802 -285.689071)
			(xy 339.804487 -285.743717) (xy 339.795866 -285.770066) (xy 339.787992 -285.792164) (xy 339.993224 -286.147256)
			(xy 340.016084 -286.151574) (xy 340.040906 -286.156737) (xy 340.088683 -286.173695) (xy 340.133301 -286.197768)
			(xy 340.173706 -286.22839) (xy 340.208946 -286.264837) (xy 340.238189 -286.30625) (xy 340.260746 -286.351653)
			(xy 340.276085 -286.399975) (xy 340.283845 -286.450075) (xy 340.284308 -286.475424) (xy 340.2838 -286.501331)
			(xy 340.275694 -286.552508) (xy 340.259682 -286.601787) (xy 340.236159 -286.647954) (xy 340.205703 -286.689873)
			(xy 340.169065 -286.726511) (xy 340.127146 -286.756967) (xy 340.080979 -286.78049) (xy 340.0317 -286.796502)
			(xy 339.980523 -286.804608) (xy 339.928709 -286.804608) (xy 339.877532 -286.796502) (xy 339.828253 -286.78049)
			(xy 339.782086 -286.756967) (xy 339.740167 -286.726511) (xy 339.703529 -286.689873) (xy 339.673073 -286.647954)
			(xy 339.64955 -286.601787) (xy 339.633538 -286.552508) (xy 339.625432 -286.501331) (xy 339.624924 -286.475424)
			(xy 339.625523 -286.447707) (xy 339.634843 -286.39306) (xy 339.643466 -286.366712) (xy 339.65134 -286.344614)
			(xy 339.446108 -285.989522) (xy 339.423248 -285.985204) (xy 339.398427 -285.980039) (xy 339.350647 -285.963084)
			(xy 339.306028 -285.939012) (xy 339.265622 -285.908392) (xy 339.230381 -285.871945) (xy 339.201137 -285.830531)
			(xy 339.17858 -285.785127) (xy 339.163243 -285.736804) (xy 339.155486 -285.686703) (xy 339.155024 -285.661354)
			(xy 338.874608 -285.661354) (xy 338.8741 -285.687261) (xy 338.865994 -285.738438) (xy 338.849982 -285.787717)
			(xy 338.826459 -285.833884) (xy 338.796003 -285.875803) (xy 338.759365 -285.912441) (xy 338.717446 -285.942897)
			(xy 338.671279 -285.96642) (xy 338.622 -285.982432) (xy 338.570823 -285.990538) (xy 338.519009 -285.990538)
			(xy 338.467832 -285.982432) (xy 338.418553 -285.96642) (xy 338.372386 -285.942897) (xy 338.330467 -285.912441)
			(xy 338.293829 -285.875803) (xy 338.263373 -285.833884) (xy 338.23985 -285.787717) (xy 338.223838 -285.738438)
			(xy 338.215732 -285.687261) (xy 338.215224 -285.661354) (xy 337.9343 -285.661354) (xy 337.933759 -285.689062)
			(xy 337.924571 -285.743708) (xy 337.916012 -285.770066) (xy 337.908138 -285.792164) (xy 338.11337 -286.147256)
			(xy 338.13623 -286.151574) (xy 338.16104 -286.156732) (xy 338.20878 -286.173726) (xy 338.253357 -286.197824)
			(xy 338.293722 -286.228459) (xy 338.328925 -286.264909) (xy 338.358136 -286.306317) (xy 338.380667 -286.351707)
			(xy 338.395988 -286.400009) (xy 338.403738 -286.450087) (xy 338.4042 -286.475424) (xy 338.403692 -286.501311)
			(xy 338.395593 -286.552449) (xy 338.379594 -286.601689) (xy 338.356088 -286.647821) (xy 338.325656 -286.689708)
			(xy 338.289046 -286.726318) (xy 338.247159 -286.75675) (xy 338.201027 -286.780256) (xy 338.151787 -286.796255)
			(xy 338.100649 -286.804354) (xy 338.048875 -286.804354) (xy 337.997737 -286.796255) (xy 337.948497 -286.780256)
			(xy 337.902365 -286.75675) (xy 337.860478 -286.726318) (xy 337.823868 -286.689708) (xy 337.793436 -286.647821)
			(xy 337.76993 -286.601689) (xy 337.753931 -286.552449) (xy 337.745832 -286.501311) (xy 337.745324 -286.475424)
			(xy 337.745858 -286.447716) (xy 337.75505 -286.393069) (xy 337.763612 -286.366712) (xy 337.771486 -286.344614)
			(xy 337.566254 -285.989522) (xy 337.543394 -285.985204) (xy 337.518583 -285.980049) (xy 337.470842 -285.963057)
			(xy 337.426263 -285.93896) (xy 337.385896 -285.908325) (xy 337.350693 -285.871874) (xy 337.321482 -285.830466)
			(xy 337.298951 -285.785075) (xy 337.283632 -285.736771) (xy 337.275885 -285.686692) (xy 337.275424 -285.661354)
			(xy 336.081878 -285.661354) (xy 336.081379 -285.688041) (xy 336.073424 -285.74082) (xy 336.057692 -285.791823)
			(xy 336.034534 -285.839912) (xy 336.004467 -285.884012) (xy 335.968163 -285.923139) (xy 335.926433 -285.956417)
			(xy 335.880209 -285.983104) (xy 335.830524 -286.002604) (xy 335.778487 -286.014481) (xy 335.725262 -286.01847)
			(xy 335.672037 -286.014481) (xy 335.62 -286.002604) (xy 335.570315 -285.983104) (xy 335.524091 -285.956417)
			(xy 335.482361 -285.923139) (xy 335.446057 -285.884012) (xy 335.41599 -285.839912) (xy 335.392832 -285.791823)
			(xy 335.3771 -285.74082) (xy 335.369145 -285.688041) (xy 335.368646 -285.661354) (xy 134.164832 -285.661354)
			(xy 134.164372 -285.686689) (xy 134.156613 -285.736761) (xy 134.141285 -285.785057) (xy 134.118749 -285.830439)
			(xy 134.089536 -285.87184) (xy 134.054334 -285.908285) (xy 134.013971 -285.938915) (xy 133.969397 -285.963011)
			(xy 133.921662 -285.980004) (xy 133.896862 -285.985204) (xy 133.874002 -285.989522) (xy 133.669024 -286.344614)
			(xy 133.676898 -286.366458) (xy 133.685549 -286.392865) (xy 133.694866 -286.447642) (xy 133.69544 -286.475424)
			(xy 333.958946 -286.475424) (xy 333.959445 -286.448737) (xy 333.9674 -286.395958) (xy 333.983132 -286.344955)
			(xy 334.00629 -286.296866) (xy 334.036357 -286.252766) (xy 334.072661 -286.213639) (xy 334.114391 -286.180361)
			(xy 334.160615 -286.153674) (xy 334.2103 -286.134174) (xy 334.262337 -286.122297) (xy 334.315562 -286.118308)
			(xy 334.368787 -286.122297) (xy 334.420824 -286.134174) (xy 334.470509 -286.153674) (xy 334.516733 -286.180361)
			(xy 334.558463 -286.213639) (xy 334.594767 -286.252766) (xy 334.624834 -286.296866) (xy 334.647992 -286.344955)
			(xy 334.663724 -286.395958) (xy 334.671679 -286.448737) (xy 334.672178 -286.4754) (xy 334.899325 -286.4754)
			(xy 334.903302 -286.422333) (xy 334.915143 -286.370452) (xy 334.934583 -286.320915) (xy 334.961189 -286.274828)
			(xy 334.994367 -286.233221) (xy 335.033374 -286.197023) (xy 335.077341 -286.167043) (xy 335.125284 -286.14395)
			(xy 335.176134 -286.12826) (xy 335.228754 -286.120324) (xy 335.255362 -286.119824) (xy 335.280307 -286.120247)
			(xy 335.329707 -286.127215) (xy 335.377649 -286.141021) (xy 335.42319 -286.161392) (xy 335.465436 -286.18793)
			(xy 335.503557 -286.220112) (xy 335.536806 -286.257307) (xy 335.551018 -286.277812) (xy 335.899506 -286.277812)
			(xy 335.91373 -286.257317) (xy 335.946981 -286.220126) (xy 335.985102 -286.187945) (xy 336.027345 -286.161408)
			(xy 336.072883 -286.141034) (xy 336.120821 -286.127223) (xy 336.170218 -286.120247) (xy 336.195162 -286.119824)
			(xy 336.221779 -286.120246) (xy 336.274418 -286.128175) (xy 336.325288 -286.143861) (xy 336.373252 -286.166955)
			(xy 336.417237 -286.196939) (xy 336.456262 -286.233145) (xy 336.489455 -286.274763) (xy 336.516073 -286.320864)
			(xy 336.535523 -286.370417) (xy 336.547369 -286.422315) (xy 336.551348 -286.4754) (xy 336.547369 -286.528485)
			(xy 336.535523 -286.580383) (xy 336.516073 -286.629936) (xy 336.489455 -286.676037) (xy 336.456262 -286.717655)
			(xy 336.417237 -286.753861) (xy 336.373252 -286.783845) (xy 336.325288 -286.806939) (xy 336.274418 -286.822625)
			(xy 336.221779 -286.830554) (xy 336.195162 -286.831024) (xy 336.170217 -286.830606) (xy 336.120815 -286.823639)
			(xy 336.072873 -286.809835) (xy 336.027331 -286.789463) (xy 335.985085 -286.762924) (xy 335.946963 -286.73074)
			(xy 335.913716 -286.693542) (xy 335.899506 -286.673036) (xy 335.551018 -286.673036) (xy 335.536761 -286.693508)
			(xy 335.503518 -286.730702) (xy 335.465404 -286.762886) (xy 335.423165 -286.789427) (xy 335.377632 -286.809804)
			(xy 335.329699 -286.823619) (xy 335.280304 -286.830599) (xy 335.255362 -286.831024) (xy 335.228754 -286.830476)
			(xy 335.176134 -286.82254) (xy 335.125284 -286.80685) (xy 335.077341 -286.783757) (xy 335.033374 -286.753777)
			(xy 334.994367 -286.717579) (xy 334.961189 -286.675972) (xy 334.934583 -286.629885) (xy 334.915143 -286.580348)
			(xy 334.903302 -286.528467) (xy 334.899325 -286.4754) (xy 334.672178 -286.4754) (xy 334.672178 -286.475424)
			(xy 334.672178 -286.475932) (xy 334.671795 -286.499134) (xy 334.665728 -286.545141) (xy 334.653752 -286.589975)
			(xy 334.645254 -286.611568) (xy 334.635602 -286.634682) (xy 334.80756 -286.93237) (xy 334.832452 -286.935672)
			(xy 334.857836 -286.939486) (xy 334.90722 -286.953493) (xy 334.954087 -286.974432) (xy 334.997469 -287.001871)
			(xy 335.036471 -287.035244) (xy 335.070287 -287.073863) (xy 335.098221 -287.116929) (xy 335.119693 -287.163553)
			(xy 335.134263 -287.212774) (xy 335.141628 -287.263574) (xy 335.142078 -287.28924) (xy 335.141579 -287.315927)
			(xy 335.133624 -287.368706) (xy 335.117892 -287.419709) (xy 335.094734 -287.467798) (xy 335.064667 -287.511898)
			(xy 335.028363 -287.551025) (xy 334.986633 -287.584303) (xy 334.940409 -287.61099) (xy 334.890724 -287.63049)
			(xy 334.838687 -287.642367) (xy 334.785462 -287.646356) (xy 334.732237 -287.642367) (xy 334.6802 -287.63049)
			(xy 334.630515 -287.61099) (xy 334.584291 -287.584303) (xy 334.542561 -287.551025) (xy 334.506257 -287.511898)
			(xy 334.47619 -287.467798) (xy 334.453032 -287.419709) (xy 334.4373 -287.368706) (xy 334.429345 -287.315927)
			(xy 334.428846 -287.28924) (xy 334.428846 -287.288732) (xy 334.429247 -287.26553) (xy 334.435307 -287.219524)
			(xy 334.447275 -287.17469) (xy 334.45577 -287.153096) (xy 334.465422 -287.129982) (xy 334.293464 -286.832294)
			(xy 334.268572 -286.828992) (xy 334.243184 -286.825193) (xy 334.193798 -286.811189) (xy 334.146929 -286.79025)
			(xy 334.103545 -286.76281) (xy 334.064542 -286.729435) (xy 334.030725 -286.690814) (xy 334.002792 -286.647745)
			(xy 333.981321 -286.601118) (xy 333.966755 -286.551894) (xy 333.959394 -286.501091) (xy 333.958946 -286.475424)
			(xy 133.69544 -286.475424) (xy 133.694932 -286.501331) (xy 133.686826 -286.552508) (xy 133.670814 -286.601787)
			(xy 133.647291 -286.647954) (xy 133.616835 -286.689873) (xy 133.580197 -286.726511) (xy 133.538278 -286.756967)
			(xy 133.492111 -286.78049) (xy 133.442832 -286.796502) (xy 133.391655 -286.804608) (xy 133.339841 -286.804608)
			(xy 133.288664 -286.796502) (xy 133.239385 -286.78049) (xy 133.193218 -286.756967) (xy 133.151299 -286.726511)
			(xy 133.114661 -286.689873) (xy 133.084205 -286.647954) (xy 133.060682 -286.601787) (xy 133.04467 -286.552508)
			(xy 133.036564 -286.501331) (xy 133.036056 -286.475424) (xy 131.81584 -286.475424) (xy 131.815332 -286.501331)
			(xy 131.807226 -286.552508) (xy 131.791214 -286.601787) (xy 131.767691 -286.647954) (xy 131.737235 -286.689873)
			(xy 131.700597 -286.726511) (xy 131.658678 -286.756967) (xy 131.612511 -286.78049) (xy 131.563232 -286.796502)
			(xy 131.512055 -286.804608) (xy 131.460241 -286.804608) (xy 131.409064 -286.796502) (xy 131.359785 -286.78049)
			(xy 131.313618 -286.756967) (xy 131.271699 -286.726511) (xy 131.235061 -286.689873) (xy 131.204605 -286.647954)
			(xy 131.181082 -286.601787) (xy 131.16507 -286.552508) (xy 131.156964 -286.501331) (xy 131.156456 -286.475424)
			(xy 129.93624 -286.475424) (xy 129.935732 -286.501331) (xy 129.927626 -286.552508) (xy 129.911614 -286.601787)
			(xy 129.888091 -286.647954) (xy 129.857635 -286.689873) (xy 129.820997 -286.726511) (xy 129.779078 -286.756967)
			(xy 129.732911 -286.78049) (xy 129.683632 -286.796502) (xy 129.632455 -286.804608) (xy 129.580641 -286.804608)
			(xy 129.529464 -286.796502) (xy 129.480185 -286.78049) (xy 129.434018 -286.756967) (xy 129.392099 -286.726511)
			(xy 129.355461 -286.689873) (xy 129.325005 -286.647954) (xy 129.301482 -286.601787) (xy 129.28547 -286.552508)
			(xy 129.277364 -286.501331) (xy 129.276856 -286.475424) (xy 128.05664 -286.475424) (xy 128.056132 -286.501331)
			(xy 128.048026 -286.552508) (xy 128.032014 -286.601787) (xy 128.008491 -286.647954) (xy 127.978035 -286.689873)
			(xy 127.941397 -286.726511) (xy 127.899478 -286.756967) (xy 127.853311 -286.78049) (xy 127.804032 -286.796502)
			(xy 127.752855 -286.804608) (xy 127.701041 -286.804608) (xy 127.649864 -286.796502) (xy 127.600585 -286.78049)
			(xy 127.554418 -286.756967) (xy 127.512499 -286.726511) (xy 127.475861 -286.689873) (xy 127.445405 -286.647954)
			(xy 127.421882 -286.601787) (xy 127.40587 -286.552508) (xy 127.397764 -286.501331) (xy 127.397256 -286.475424)
			(xy 126.17704 -286.475424) (xy 126.176532 -286.501331) (xy 126.168426 -286.552508) (xy 126.152414 -286.601787)
			(xy 126.128891 -286.647954) (xy 126.098435 -286.689873) (xy 126.061797 -286.726511) (xy 126.019878 -286.756967)
			(xy 125.973711 -286.78049) (xy 125.924432 -286.796502) (xy 125.873255 -286.804608) (xy 125.821441 -286.804608)
			(xy 125.770264 -286.796502) (xy 125.720985 -286.78049) (xy 125.674818 -286.756967) (xy 125.632899 -286.726511)
			(xy 125.596261 -286.689873) (xy 125.565805 -286.647954) (xy 125.542282 -286.601787) (xy 125.52627 -286.552508)
			(xy 125.518164 -286.501331) (xy 125.517656 -286.475424) (xy 124.29744 -286.475424) (xy 124.296932 -286.501331)
			(xy 124.288826 -286.552508) (xy 124.272814 -286.601787) (xy 124.249291 -286.647954) (xy 124.218835 -286.689873)
			(xy 124.182197 -286.726511) (xy 124.140278 -286.756967) (xy 124.094111 -286.78049) (xy 124.044832 -286.796502)
			(xy 123.993655 -286.804608) (xy 123.941841 -286.804608) (xy 123.890664 -286.796502) (xy 123.841385 -286.78049)
			(xy 123.795218 -286.756967) (xy 123.753299 -286.726511) (xy 123.716661 -286.689873) (xy 123.686205 -286.647954)
			(xy 123.662682 -286.601787) (xy 123.64667 -286.552508) (xy 123.638564 -286.501331) (xy 123.638056 -286.475424)
			(xy 122.41784 -286.475424) (xy 122.417332 -286.501331) (xy 122.409226 -286.552508) (xy 122.393214 -286.601787)
			(xy 122.369691 -286.647954) (xy 122.339235 -286.689873) (xy 122.302597 -286.726511) (xy 122.260678 -286.756967)
			(xy 122.214511 -286.78049) (xy 122.165232 -286.796502) (xy 122.114055 -286.804608) (xy 122.062241 -286.804608)
			(xy 122.011064 -286.796502) (xy 121.961785 -286.78049) (xy 121.915618 -286.756967) (xy 121.873699 -286.726511)
			(xy 121.837061 -286.689873) (xy 121.806605 -286.647954) (xy 121.783082 -286.601787) (xy 121.76707 -286.552508)
			(xy 121.758964 -286.501331) (xy 121.758456 -286.475424) (xy 120.53824 -286.475424) (xy 120.537732 -286.501331)
			(xy 120.529626 -286.552508) (xy 120.513614 -286.601787) (xy 120.490091 -286.647954) (xy 120.459635 -286.689873)
			(xy 120.422997 -286.726511) (xy 120.381078 -286.756967) (xy 120.334911 -286.78049) (xy 120.285632 -286.796502)
			(xy 120.234455 -286.804608) (xy 120.182641 -286.804608) (xy 120.131464 -286.796502) (xy 120.082185 -286.78049)
			(xy 120.036018 -286.756967) (xy 119.994099 -286.726511) (xy 119.957461 -286.689873) (xy 119.927005 -286.647954)
			(xy 119.903482 -286.601787) (xy 119.88747 -286.552508) (xy 119.879364 -286.501331) (xy 119.878856 -286.475424)
			(xy 103.62184 -286.475424) (xy 103.621332 -286.501331) (xy 103.613226 -286.552508) (xy 103.597214 -286.601787)
			(xy 103.573691 -286.647954) (xy 103.543235 -286.689873) (xy 103.506597 -286.726511) (xy 103.464678 -286.756967)
			(xy 103.418511 -286.78049) (xy 103.369232 -286.796502) (xy 103.318055 -286.804608) (xy 103.266241 -286.804608)
			(xy 103.215064 -286.796502) (xy 103.165785 -286.78049) (xy 103.119618 -286.756967) (xy 103.077699 -286.726511)
			(xy 103.041061 -286.689873) (xy 103.010605 -286.647954) (xy 102.987082 -286.601787) (xy 102.97107 -286.552508)
			(xy 102.962964 -286.501331) (xy 102.962456 -286.475424) (xy 102.963053 -286.447707) (xy 102.972374 -286.39306)
			(xy 102.980998 -286.366712) (xy 102.988872 -286.344614) (xy 102.783894 -285.989522) (xy 102.76078 -285.985204)
			(xy 102.735964 -285.980016) (xy 102.688184 -285.963065) (xy 102.643565 -285.938998) (xy 102.603157 -285.908381)
			(xy 102.567916 -285.871936) (xy 102.538671 -285.830525) (xy 102.516113 -285.785123) (xy 102.500775 -285.736802)
			(xy 102.493018 -285.686702) (xy 102.492556 -285.661354) (xy 102.211632 -285.661354) (xy 102.211124 -285.687241)
			(xy 102.203025 -285.738379) (xy 102.187026 -285.787619) (xy 102.16352 -285.833751) (xy 102.133088 -285.875638)
			(xy 102.096478 -285.912248) (xy 102.054591 -285.94268) (xy 102.008459 -285.966186) (xy 101.959219 -285.982185)
			(xy 101.908081 -285.990284) (xy 101.856307 -285.990284) (xy 101.805169 -285.982185) (xy 101.755929 -285.966186)
			(xy 101.709797 -285.94268) (xy 101.66791 -285.912248) (xy 101.6313 -285.875638) (xy 101.600868 -285.833751)
			(xy 101.577362 -285.787619) (xy 101.561363 -285.738379) (xy 101.553264 -285.687241) (xy 101.552756 -285.661354)
			(xy 101.271832 -285.661354) (xy 101.271832 -285.661862) (xy 101.271253 -285.689379) (xy 101.262059 -285.74364)
			(xy 101.253544 -285.769812) (xy 101.245924 -285.79191) (xy 101.451156 -286.147256) (xy 101.474016 -286.151574)
			(xy 101.498827 -286.156786) (xy 101.546604 -286.173734) (xy 101.591223 -286.197799) (xy 101.63163 -286.228413)
			(xy 101.666872 -286.264855) (xy 101.696117 -286.306263) (xy 101.718676 -286.351662) (xy 101.734017 -286.399979)
			(xy 101.741777 -286.450077) (xy 101.74224 -286.475424) (xy 101.741732 -286.501331) (xy 101.733626 -286.552508)
			(xy 101.717614 -286.601787) (xy 101.694091 -286.647954) (xy 101.663635 -286.689873) (xy 101.626997 -286.726511)
			(xy 101.585078 -286.756967) (xy 101.538911 -286.78049) (xy 101.489632 -286.796502) (xy 101.438455 -286.804608)
			(xy 101.386641 -286.804608) (xy 101.335464 -286.796502) (xy 101.286185 -286.78049) (xy 101.240018 -286.756967)
			(xy 101.198099 -286.726511) (xy 101.161461 -286.689873) (xy 101.131005 -286.647954) (xy 101.107482 -286.601787)
			(xy 101.09147 -286.552508) (xy 101.083364 -286.501331) (xy 101.082856 -286.475424) (xy 101.083453 -286.447707)
			(xy 101.092774 -286.39306) (xy 101.101398 -286.366712) (xy 101.109272 -286.344614) (xy 100.904294 -285.989522)
			(xy 100.88118 -285.985204) (xy 100.856364 -285.980016) (xy 100.808584 -285.963065) (xy 100.763965 -285.938998)
			(xy 100.723557 -285.908381) (xy 100.688316 -285.871936) (xy 100.659071 -285.830525) (xy 100.636513 -285.785123)
			(xy 100.621175 -285.736802) (xy 100.613418 -285.686702) (xy 100.612956 -285.661354) (xy 100.332032 -285.661354)
			(xy 100.331524 -285.687241) (xy 100.323425 -285.738379) (xy 100.307426 -285.787619) (xy 100.28392 -285.833751)
			(xy 100.253488 -285.875638) (xy 100.216878 -285.912248) (xy 100.174991 -285.94268) (xy 100.128859 -285.966186)
			(xy 100.079619 -285.982185) (xy 100.028481 -285.990284) (xy 99.976707 -285.990284) (xy 99.925569 -285.982185)
			(xy 99.876329 -285.966186) (xy 99.830197 -285.94268) (xy 99.78831 -285.912248) (xy 99.7517 -285.875638)
			(xy 99.721268 -285.833751) (xy 99.697762 -285.787619) (xy 99.681763 -285.738379) (xy 99.673664 -285.687241)
			(xy 99.673156 -285.661354) (xy 99.392232 -285.661354) (xy 99.392232 -285.661862) (xy 99.391653 -285.689379)
			(xy 99.382459 -285.74364) (xy 99.373944 -285.769812) (xy 99.366324 -285.79191) (xy 99.571556 -286.147256)
			(xy 99.594416 -286.151574) (xy 99.619227 -286.156786) (xy 99.667004 -286.173734) (xy 99.711623 -286.197799)
			(xy 99.75203 -286.228413) (xy 99.787272 -286.264855) (xy 99.816517 -286.306263) (xy 99.839076 -286.351662)
			(xy 99.854417 -286.399979) (xy 99.862177 -286.450077) (xy 99.86264 -286.475424) (xy 99.862132 -286.501331)
			(xy 99.854026 -286.552508) (xy 99.838014 -286.601787) (xy 99.814491 -286.647954) (xy 99.784035 -286.689873)
			(xy 99.747397 -286.726511) (xy 99.705478 -286.756967) (xy 99.659311 -286.78049) (xy 99.610032 -286.796502)
			(xy 99.558855 -286.804608) (xy 99.507041 -286.804608) (xy 99.455864 -286.796502) (xy 99.406585 -286.78049)
			(xy 99.360418 -286.756967) (xy 99.318499 -286.726511) (xy 99.281861 -286.689873) (xy 99.251405 -286.647954)
			(xy 99.227882 -286.601787) (xy 99.21187 -286.552508) (xy 99.203764 -286.501331) (xy 99.203256 -286.475424)
			(xy 99.203853 -286.447707) (xy 99.213174 -286.39306) (xy 99.221798 -286.366712) (xy 99.229672 -286.344614)
			(xy 99.024694 -285.989522) (xy 99.00158 -285.985204) (xy 98.976764 -285.980016) (xy 98.928984 -285.963065)
			(xy 98.884365 -285.938998) (xy 98.843957 -285.908381) (xy 98.808716 -285.871936) (xy 98.779471 -285.830525)
			(xy 98.756913 -285.785123) (xy 98.741575 -285.736802) (xy 98.733818 -285.686702) (xy 98.733356 -285.661354)
			(xy 98.452432 -285.661354) (xy 98.451924 -285.687241) (xy 98.443825 -285.738379) (xy 98.427826 -285.787619)
			(xy 98.40432 -285.833751) (xy 98.373888 -285.875638) (xy 98.337278 -285.912248) (xy 98.295391 -285.94268)
			(xy 98.249259 -285.966186) (xy 98.200019 -285.982185) (xy 98.148881 -285.990284) (xy 98.097107 -285.990284)
			(xy 98.045969 -285.982185) (xy 97.996729 -285.966186) (xy 97.950597 -285.94268) (xy 97.90871 -285.912248)
			(xy 97.8721 -285.875638) (xy 97.841668 -285.833751) (xy 97.818162 -285.787619) (xy 97.802163 -285.738379)
			(xy 97.794064 -285.687241) (xy 97.793556 -285.661354) (xy 97.512632 -285.661354) (xy 97.512632 -285.661862)
			(xy 97.512053 -285.689379) (xy 97.502859 -285.74364) (xy 97.494344 -285.769812) (xy 97.486724 -285.79191)
			(xy 97.691956 -286.147256) (xy 97.714816 -286.151574) (xy 97.739627 -286.156786) (xy 97.787404 -286.173734)
			(xy 97.832023 -286.197799) (xy 97.87243 -286.228413) (xy 97.907672 -286.264855) (xy 97.936917 -286.306263)
			(xy 97.959476 -286.351662) (xy 97.974817 -286.399979) (xy 97.982577 -286.450077) (xy 97.98304 -286.475424)
			(xy 97.982532 -286.501331) (xy 97.974426 -286.552508) (xy 97.958414 -286.601787) (xy 97.934891 -286.647954)
			(xy 97.904435 -286.689873) (xy 97.867797 -286.726511) (xy 97.825878 -286.756967) (xy 97.779711 -286.78049)
			(xy 97.730432 -286.796502) (xy 97.679255 -286.804608) (xy 97.627441 -286.804608) (xy 97.576264 -286.796502)
			(xy 97.526985 -286.78049) (xy 97.480818 -286.756967) (xy 97.438899 -286.726511) (xy 97.402261 -286.689873)
			(xy 97.371805 -286.647954) (xy 97.348282 -286.601787) (xy 97.33227 -286.552508) (xy 97.324164 -286.501331)
			(xy 97.323656 -286.475424) (xy 97.324253 -286.447707) (xy 97.333574 -286.39306) (xy 97.342198 -286.366712)
			(xy 97.350072 -286.344614) (xy 97.145094 -285.989522) (xy 97.12198 -285.985204) (xy 97.097164 -285.980016)
			(xy 97.049384 -285.963065) (xy 97.004765 -285.938998) (xy 96.964357 -285.908381) (xy 96.929116 -285.871936)
			(xy 96.899871 -285.830525) (xy 96.877313 -285.785123) (xy 96.861975 -285.736802) (xy 96.854218 -285.686702)
			(xy 96.853756 -285.661354) (xy 96.572832 -285.661354) (xy 96.572324 -285.687241) (xy 96.564225 -285.738379)
			(xy 96.548226 -285.787619) (xy 96.52472 -285.833751) (xy 96.494288 -285.875638) (xy 96.457678 -285.912248)
			(xy 96.415791 -285.94268) (xy 96.369659 -285.966186) (xy 96.320419 -285.982185) (xy 96.269281 -285.990284)
			(xy 96.217507 -285.990284) (xy 96.166369 -285.982185) (xy 96.117129 -285.966186) (xy 96.070997 -285.94268)
			(xy 96.02911 -285.912248) (xy 95.9925 -285.875638) (xy 95.962068 -285.833751) (xy 95.938562 -285.787619)
			(xy 95.922563 -285.738379) (xy 95.914464 -285.687241) (xy 95.913956 -285.661354) (xy 95.633032 -285.661354)
			(xy 95.633032 -285.661862) (xy 95.632453 -285.689379) (xy 95.623259 -285.74364) (xy 95.614744 -285.769812)
			(xy 95.607124 -285.79191) (xy 95.812356 -286.147256) (xy 95.835216 -286.151574) (xy 95.860027 -286.156786)
			(xy 95.907804 -286.173734) (xy 95.952423 -286.197799) (xy 95.99283 -286.228413) (xy 96.028072 -286.264855)
			(xy 96.057317 -286.306263) (xy 96.079876 -286.351662) (xy 96.095217 -286.399979) (xy 96.102977 -286.450077)
			(xy 96.10344 -286.475424) (xy 96.102932 -286.501331) (xy 96.094826 -286.552508) (xy 96.078814 -286.601787)
			(xy 96.055291 -286.647954) (xy 96.024835 -286.689873) (xy 95.988197 -286.726511) (xy 95.946278 -286.756967)
			(xy 95.900111 -286.78049) (xy 95.850832 -286.796502) (xy 95.799655 -286.804608) (xy 95.747841 -286.804608)
			(xy 95.696664 -286.796502) (xy 95.647385 -286.78049) (xy 95.601218 -286.756967) (xy 95.559299 -286.726511)
			(xy 95.522661 -286.689873) (xy 95.492205 -286.647954) (xy 95.468682 -286.601787) (xy 95.45267 -286.552508)
			(xy 95.444564 -286.501331) (xy 95.444056 -286.475424) (xy 95.444653 -286.447707) (xy 95.453974 -286.39306)
			(xy 95.462598 -286.366712) (xy 95.470472 -286.344614) (xy 95.265494 -285.989522) (xy 95.24238 -285.985204)
			(xy 95.217564 -285.980016) (xy 95.169784 -285.963065) (xy 95.125165 -285.938998) (xy 95.084757 -285.908381)
			(xy 95.049516 -285.871936) (xy 95.020271 -285.830525) (xy 94.997713 -285.785123) (xy 94.982375 -285.736802)
			(xy 94.974618 -285.686702) (xy 94.974156 -285.661354) (xy 94.693232 -285.661354) (xy 94.692724 -285.687241)
			(xy 94.684625 -285.738379) (xy 94.668626 -285.787619) (xy 94.64512 -285.833751) (xy 94.614688 -285.875638)
			(xy 94.578078 -285.912248) (xy 94.536191 -285.94268) (xy 94.490059 -285.966186) (xy 94.440819 -285.982185)
			(xy 94.389681 -285.990284) (xy 94.337907 -285.990284) (xy 94.286769 -285.982185) (xy 94.237529 -285.966186)
			(xy 94.191397 -285.94268) (xy 94.14951 -285.912248) (xy 94.1129 -285.875638) (xy 94.082468 -285.833751)
			(xy 94.058962 -285.787619) (xy 94.042963 -285.738379) (xy 94.034864 -285.687241) (xy 94.034356 -285.661354)
			(xy 93.753432 -285.661354) (xy 93.753432 -285.661862) (xy 93.752853 -285.689379) (xy 93.743659 -285.74364)
			(xy 93.735144 -285.769812) (xy 93.727524 -285.79191) (xy 93.932756 -286.147256) (xy 93.955616 -286.151574)
			(xy 93.980427 -286.156786) (xy 94.028204 -286.173734) (xy 94.072823 -286.197799) (xy 94.11323 -286.228413)
			(xy 94.148472 -286.264855) (xy 94.177717 -286.306263) (xy 94.200276 -286.351662) (xy 94.215617 -286.399979)
			(xy 94.223377 -286.450077) (xy 94.22384 -286.475424) (xy 94.223332 -286.501331) (xy 94.215226 -286.552508)
			(xy 94.199214 -286.601787) (xy 94.175691 -286.647954) (xy 94.145235 -286.689873) (xy 94.108597 -286.726511)
			(xy 94.066678 -286.756967) (xy 94.020511 -286.78049) (xy 93.971232 -286.796502) (xy 93.920055 -286.804608)
			(xy 93.868241 -286.804608) (xy 93.817064 -286.796502) (xy 93.767785 -286.78049) (xy 93.721618 -286.756967)
			(xy 93.679699 -286.726511) (xy 93.643061 -286.689873) (xy 93.612605 -286.647954) (xy 93.589082 -286.601787)
			(xy 93.57307 -286.552508) (xy 93.564964 -286.501331) (xy 93.564456 -286.475424) (xy 93.565053 -286.447707)
			(xy 93.574374 -286.39306) (xy 93.582998 -286.366712) (xy 93.590872 -286.344614) (xy 93.385894 -285.989522)
			(xy 93.36278 -285.985204) (xy 93.337964 -285.980016) (xy 93.290184 -285.963065) (xy 93.245565 -285.938998)
			(xy 93.205157 -285.908381) (xy 93.169916 -285.871936) (xy 93.140671 -285.830525) (xy 93.118113 -285.785123)
			(xy 93.102775 -285.736802) (xy 93.095018 -285.686702) (xy 93.094556 -285.661354) (xy 92.813632 -285.661354)
			(xy 92.813124 -285.687241) (xy 92.805025 -285.738379) (xy 92.789026 -285.787619) (xy 92.76552 -285.833751)
			(xy 92.735088 -285.875638) (xy 92.698478 -285.912248) (xy 92.656591 -285.94268) (xy 92.610459 -285.966186)
			(xy 92.561219 -285.982185) (xy 92.510081 -285.990284) (xy 92.458307 -285.990284) (xy 92.407169 -285.982185)
			(xy 92.357929 -285.966186) (xy 92.311797 -285.94268) (xy 92.26991 -285.912248) (xy 92.2333 -285.875638)
			(xy 92.202868 -285.833751) (xy 92.179362 -285.787619) (xy 92.163363 -285.738379) (xy 92.155264 -285.687241)
			(xy 92.154756 -285.661354) (xy 91.87434 -285.661354) (xy 91.873738 -285.689071) (xy 91.86442 -285.743718)
			(xy 91.855798 -285.770066) (xy 91.847924 -285.792164) (xy 92.053156 -286.147256) (xy 92.076016 -286.151574)
			(xy 92.100827 -286.156786) (xy 92.148604 -286.173734) (xy 92.193223 -286.197799) (xy 92.23363 -286.228413)
			(xy 92.268872 -286.264855) (xy 92.298117 -286.306263) (xy 92.320676 -286.351662) (xy 92.336017 -286.399979)
			(xy 92.343777 -286.450077) (xy 92.34424 -286.475424) (xy 92.343732 -286.501331) (xy 92.335626 -286.552508)
			(xy 92.319614 -286.601787) (xy 92.296091 -286.647954) (xy 92.265635 -286.689873) (xy 92.228997 -286.726511)
			(xy 92.187078 -286.756967) (xy 92.140911 -286.78049) (xy 92.091632 -286.796502) (xy 92.040455 -286.804608)
			(xy 91.988641 -286.804608) (xy 91.937464 -286.796502) (xy 91.888185 -286.78049) (xy 91.842018 -286.756967)
			(xy 91.800099 -286.726511) (xy 91.763461 -286.689873) (xy 91.733005 -286.647954) (xy 91.709482 -286.601787)
			(xy 91.69347 -286.552508) (xy 91.685364 -286.501331) (xy 91.684856 -286.475424) (xy 91.685453 -286.447707)
			(xy 91.694774 -286.39306) (xy 91.703398 -286.366712) (xy 91.711272 -286.344614) (xy 91.50604 -285.989522)
			(xy 91.48318 -285.985204) (xy 91.458364 -285.980016) (xy 91.410584 -285.963065) (xy 91.365965 -285.938998)
			(xy 91.325557 -285.908381) (xy 91.290316 -285.871936) (xy 91.261071 -285.830525) (xy 91.238513 -285.785123)
			(xy 91.223175 -285.736802) (xy 91.215418 -285.686702) (xy 91.214956 -285.661354) (xy 90.93454 -285.661354)
			(xy 90.934032 -285.687261) (xy 90.925926 -285.738438) (xy 90.909914 -285.787717) (xy 90.886391 -285.833884)
			(xy 90.855935 -285.875803) (xy 90.819297 -285.912441) (xy 90.777378 -285.942897) (xy 90.731211 -285.96642)
			(xy 90.681932 -285.982432) (xy 90.630755 -285.990538) (xy 90.578941 -285.990538) (xy 90.527764 -285.982432)
			(xy 90.478485 -285.96642) (xy 90.432318 -285.942897) (xy 90.390399 -285.912441) (xy 90.353761 -285.875803)
			(xy 90.323305 -285.833884) (xy 90.299782 -285.787717) (xy 90.28377 -285.738438) (xy 90.275664 -285.687261)
			(xy 90.275156 -285.661354) (xy 89.994232 -285.661354) (xy 89.993689 -285.689062) (xy 89.984503 -285.743708)
			(xy 89.975944 -285.770066) (xy 89.96807 -285.792164) (xy 90.173302 -286.147256) (xy 90.196162 -286.151574)
			(xy 90.220961 -286.156781) (xy 90.268701 -286.173765) (xy 90.31328 -286.197855) (xy 90.353647 -286.228483)
			(xy 90.388851 -286.264927) (xy 90.418064 -286.30633) (xy 90.440597 -286.351715) (xy 90.455919 -286.400014)
			(xy 90.46367 -286.450088) (xy 90.464132 -286.475424) (xy 90.463624 -286.501311) (xy 90.455525 -286.552449)
			(xy 90.439526 -286.601689) (xy 90.41602 -286.647821) (xy 90.385588 -286.689708) (xy 90.348978 -286.726318)
			(xy 90.307091 -286.75675) (xy 90.260959 -286.780256) (xy 90.211719 -286.796255) (xy 90.160581 -286.804354)
			(xy 90.108807 -286.804354) (xy 90.057669 -286.796255) (xy 90.008429 -286.780256) (xy 89.962297 -286.75675)
			(xy 89.92041 -286.726318) (xy 89.8838 -286.689708) (xy 89.853368 -286.647821) (xy 89.829862 -286.601689)
			(xy 89.813863 -286.552449) (xy 89.805764 -286.501311) (xy 89.805256 -286.475424) (xy 89.805793 -286.447716)
			(xy 89.814983 -286.393069) (xy 89.823544 -286.366712) (xy 89.831418 -286.344614) (xy 89.626186 -285.989522)
			(xy 89.603326 -285.985204) (xy 89.57852 -285.980026) (xy 89.530779 -285.963039) (xy 89.486199 -285.938946)
			(xy 89.445832 -285.908314) (xy 89.410627 -285.871866) (xy 89.381416 -285.83046) (xy 89.358884 -285.785071)
			(xy 89.343564 -285.736769) (xy 89.335817 -285.686691) (xy 89.335356 -285.661354) (xy 88.14181 -285.661354)
			(xy 88.141311 -285.688041) (xy 88.133356 -285.74082) (xy 88.117624 -285.791823) (xy 88.094466 -285.839912)
			(xy 88.064399 -285.884012) (xy 88.028095 -285.923139) (xy 87.986365 -285.956417) (xy 87.940141 -285.983104)
			(xy 87.890456 -286.002604) (xy 87.838419 -286.014481) (xy 87.785194 -286.01847) (xy 87.731969 -286.014481)
			(xy 87.679932 -286.002604) (xy 87.630247 -285.983104) (xy 87.584023 -285.956417) (xy 87.542293 -285.923139)
			(xy 87.505989 -285.884012) (xy 87.475922 -285.839912) (xy 87.452764 -285.791823) (xy 87.437032 -285.74082)
			(xy 87.429077 -285.688041) (xy 87.428578 -285.661354) (xy 2.509012 -285.661354) (xy 2.509012 -286.475424)
			(xy 86.018878 -286.475424) (xy 86.019377 -286.448737) (xy 86.027332 -286.395958) (xy 86.043064 -286.344955)
			(xy 86.066222 -286.296866) (xy 86.096289 -286.252766) (xy 86.132593 -286.213639) (xy 86.174323 -286.180361)
			(xy 86.220547 -286.153674) (xy 86.270232 -286.134174) (xy 86.322269 -286.122297) (xy 86.375494 -286.118308)
			(xy 86.428719 -286.122297) (xy 86.480756 -286.134174) (xy 86.530441 -286.153674) (xy 86.576665 -286.180361)
			(xy 86.618395 -286.213639) (xy 86.654699 -286.252766) (xy 86.684766 -286.296866) (xy 86.707924 -286.344955)
			(xy 86.723656 -286.395958) (xy 86.731611 -286.448737) (xy 86.73211 -286.4754) (xy 86.959225 -286.4754)
			(xy 86.963202 -286.42233) (xy 86.975045 -286.370446) (xy 86.994487 -286.320907) (xy 87.021096 -286.274818)
			(xy 87.054277 -286.23321) (xy 87.093288 -286.197012) (xy 87.137259 -286.167032) (xy 87.185207 -286.143941)
			(xy 87.236061 -286.128254) (xy 87.288685 -286.120322) (xy 87.315294 -286.119824) (xy 87.34024 -286.120223)
			(xy 87.389641 -286.127195) (xy 87.437583 -286.141005) (xy 87.483124 -286.161381) (xy 87.52537 -286.187922)
			(xy 87.563491 -286.220107) (xy 87.596739 -286.257306) (xy 87.61095 -286.277812) (xy 87.959438 -286.277812)
			(xy 87.973642 -286.257302) (xy 88.006896 -286.220111) (xy 88.04502 -286.187932) (xy 88.087267 -286.161396)
			(xy 88.132808 -286.141025) (xy 88.180749 -286.127217) (xy 88.230149 -286.120245) (xy 88.255094 -286.119824)
			(xy 88.281709 -286.120248) (xy 88.334345 -286.128181) (xy 88.385211 -286.14387) (xy 88.43317 -286.166965)
			(xy 88.477152 -286.196951) (xy 88.516173 -286.233156) (xy 88.549362 -286.274773) (xy 88.575977 -286.320872)
			(xy 88.595425 -286.370423) (xy 88.60727 -286.422318) (xy 88.611248 -286.4754) (xy 88.60727 -286.528482)
			(xy 88.595425 -286.580377) (xy 88.575977 -286.629928) (xy 88.549362 -286.676027) (xy 88.516173 -286.717644)
			(xy 88.477152 -286.753849) (xy 88.43317 -286.783835) (xy 88.385211 -286.80693) (xy 88.334345 -286.822619)
			(xy 88.281709 -286.830552) (xy 88.255094 -286.831024) (xy 88.23015 -286.830581) (xy 88.180749 -286.823619)
			(xy 88.132807 -286.809819) (xy 88.087265 -286.789451) (xy 88.045019 -286.762916) (xy 88.006897 -286.730736)
			(xy 87.973649 -286.693541) (xy 87.959438 -286.673036) (xy 87.61095 -286.673036) (xy 87.596737 -286.69354)
			(xy 87.563487 -286.730733) (xy 87.525364 -286.762914) (xy 87.483119 -286.789452) (xy 87.437579 -286.809824)
			(xy 87.389638 -286.823632) (xy 87.340239 -286.830604) (xy 87.315294 -286.831024) (xy 87.288685 -286.830478)
			(xy 87.236061 -286.822546) (xy 87.185207 -286.806859) (xy 87.137259 -286.783768) (xy 87.093288 -286.753788)
			(xy 87.054277 -286.71759) (xy 87.021096 -286.675982) (xy 86.994487 -286.629893) (xy 86.975045 -286.580354)
			(xy 86.963202 -286.52847) (xy 86.959225 -286.4754) (xy 86.73211 -286.4754) (xy 86.73211 -286.475424)
			(xy 86.73211 -286.475932) (xy 86.731732 -286.499134) (xy 86.725664 -286.545142) (xy 86.713686 -286.589975)
			(xy 86.705186 -286.611568) (xy 86.695534 -286.634682) (xy 86.867492 -286.93237) (xy 86.892384 -286.935672)
			(xy 86.91776 -286.93954) (xy 86.967143 -286.953537) (xy 87.01401 -286.974468) (xy 87.057393 -287.0019)
			(xy 87.096397 -287.035267) (xy 87.130215 -287.073879) (xy 87.15815 -287.116941) (xy 87.179624 -287.163561)
			(xy 87.194194 -287.212778) (xy 87.201559 -287.263576) (xy 87.20201 -287.28924) (xy 87.201511 -287.315927)
			(xy 87.193556 -287.368706) (xy 87.177824 -287.419709) (xy 87.154666 -287.467798) (xy 87.124599 -287.511898)
			(xy 87.088295 -287.551025) (xy 87.046565 -287.584303) (xy 87.000341 -287.61099) (xy 86.950656 -287.63049)
			(xy 86.898619 -287.642367) (xy 86.845394 -287.646356) (xy 86.792169 -287.642367) (xy 86.740132 -287.63049)
			(xy 86.690447 -287.61099) (xy 86.644223 -287.584303) (xy 86.602493 -287.551025) (xy 86.566189 -287.511898)
			(xy 86.536122 -287.467798) (xy 86.512964 -287.419709) (xy 86.497232 -287.368706) (xy 86.489277 -287.315927)
			(xy 86.488778 -287.28924) (xy 86.488778 -287.288732) (xy 86.489177 -287.26553) (xy 86.495237 -287.219524)
			(xy 86.507206 -287.17469) (xy 86.515702 -287.153096) (xy 86.525354 -287.129982) (xy 86.353396 -286.832294)
			(xy 86.328504 -286.828992) (xy 86.303121 -286.825168) (xy 86.253735 -286.811168) (xy 86.206865 -286.790233)
			(xy 86.163481 -286.762796) (xy 86.124477 -286.729424) (xy 86.090659 -286.690806) (xy 86.062726 -286.647739)
			(xy 86.041254 -286.601114) (xy 86.026687 -286.551892) (xy 86.019326 -286.50109) (xy 86.018878 -286.475424)
			(xy 2.509012 -286.475424) (xy 2.509012 -288.917126) (xy 88.395556 -288.917126) (xy 88.396056 -288.891781)
			(xy 88.403825 -288.84169) (xy 88.419169 -288.793377) (xy 88.441727 -288.747983) (xy 88.470967 -288.706576)
			(xy 88.506199 -288.670131) (xy 88.546595 -288.639509) (xy 88.591201 -288.61543) (xy 88.638966 -288.598461)
			(xy 88.66378 -288.593276) (xy 88.68664 -288.588958) (xy 88.891618 -288.233866) (xy 88.883744 -288.212022)
			(xy 88.875171 -288.185601) (xy 88.86597 -288.130828) (xy 88.865456 -288.103056) (xy 88.865964 -288.077169)
			(xy 88.874063 -288.026031) (xy 88.890062 -287.976791) (xy 88.913568 -287.930659) (xy 88.944 -287.888772)
			(xy 88.98061 -287.852162) (xy 89.022497 -287.82173) (xy 89.068629 -287.798224) (xy 89.117869 -287.782225)
			(xy 89.169007 -287.774126) (xy 89.220781 -287.774126) (xy 89.271919 -287.782225) (xy 89.321159 -287.798224)
			(xy 89.367291 -287.82173) (xy 89.409178 -287.852162) (xy 89.445788 -287.888772) (xy 89.47622 -287.930659)
			(xy 89.499726 -287.976791) (xy 89.515725 -288.026031) (xy 89.523824 -288.077169) (xy 89.524332 -288.103056)
			(xy 89.523874 -288.128391) (xy 89.516115 -288.178463) (xy 89.500786 -288.226759) (xy 89.47825 -288.272141)
			(xy 89.449037 -288.313542) (xy 89.413835 -288.349987) (xy 89.373471 -288.380617) (xy 89.328897 -288.404713)
			(xy 89.281162 -288.421706) (xy 89.256362 -288.426906) (xy 89.233502 -288.431224) (xy 89.028524 -288.786316)
			(xy 89.036398 -288.80816) (xy 89.045049 -288.834567) (xy 89.054366 -288.889344) (xy 89.05494 -288.917126)
			(xy 90.275156 -288.917126) (xy 90.275656 -288.891781) (xy 90.283425 -288.84169) (xy 90.298769 -288.793377)
			(xy 90.321327 -288.747983) (xy 90.350567 -288.706576) (xy 90.385799 -288.670131) (xy 90.426195 -288.639509)
			(xy 90.470801 -288.61543) (xy 90.518566 -288.598461) (xy 90.54338 -288.593276) (xy 90.56624 -288.588958)
			(xy 90.771218 -288.233866) (xy 90.763344 -288.212022) (xy 90.754771 -288.185601) (xy 90.74557 -288.130828)
			(xy 90.745056 -288.103056) (xy 90.745564 -288.077169) (xy 90.753663 -288.026031) (xy 90.769662 -287.976791)
			(xy 90.793168 -287.930659) (xy 90.8236 -287.888772) (xy 90.86021 -287.852162) (xy 90.902097 -287.82173)
			(xy 90.948229 -287.798224) (xy 90.997469 -287.782225) (xy 91.048607 -287.774126) (xy 91.100381 -287.774126)
			(xy 91.151519 -287.782225) (xy 91.200759 -287.798224) (xy 91.246891 -287.82173) (xy 91.288778 -287.852162)
			(xy 91.325388 -287.888772) (xy 91.35582 -287.930659) (xy 91.379326 -287.976791) (xy 91.395325 -288.026031)
			(xy 91.403424 -288.077169) (xy 91.403932 -288.103056) (xy 91.403474 -288.128391) (xy 91.395715 -288.178463)
			(xy 91.380386 -288.226759) (xy 91.35785 -288.272141) (xy 91.328637 -288.313542) (xy 91.293435 -288.349987)
			(xy 91.253071 -288.380617) (xy 91.208497 -288.404713) (xy 91.160762 -288.421706) (xy 91.135962 -288.426906)
			(xy 91.113102 -288.431224) (xy 90.908124 -288.786316) (xy 90.915998 -288.80816) (xy 90.924649 -288.834567)
			(xy 90.933966 -288.889344) (xy 90.93454 -288.917126) (xy 91.214956 -288.917126) (xy 91.215464 -288.891219)
			(xy 91.22357 -288.840042) (xy 91.239582 -288.790763) (xy 91.263105 -288.744596) (xy 91.293561 -288.702677)
			(xy 91.330199 -288.666039) (xy 91.372118 -288.635583) (xy 91.418285 -288.61206) (xy 91.467564 -288.596048)
			(xy 91.518741 -288.587942) (xy 91.570555 -288.587942) (xy 91.621732 -288.596048) (xy 91.671011 -288.61206)
			(xy 91.717178 -288.635583) (xy 91.759097 -288.666039) (xy 91.795735 -288.702677) (xy 91.826191 -288.744596)
			(xy 91.849714 -288.790763) (xy 91.865726 -288.840042) (xy 91.873832 -288.891219) (xy 91.87434 -288.917126)
			(xy 92.154756 -288.917126) (xy 92.155256 -288.891781) (xy 92.163025 -288.84169) (xy 92.178369 -288.793377)
			(xy 92.200927 -288.747983) (xy 92.230167 -288.706576) (xy 92.265399 -288.670131) (xy 92.305795 -288.639509)
			(xy 92.350401 -288.61543) (xy 92.398166 -288.598461) (xy 92.42298 -288.593276) (xy 92.44584 -288.588958)
			(xy 92.651072 -288.233866) (xy 92.643198 -288.211768) (xy 92.634576 -288.185419) (xy 92.625249 -288.130773)
			(xy 92.624656 -288.103056) (xy 92.625164 -288.077149) (xy 92.63327 -288.025972) (xy 92.649282 -287.976693)
			(xy 92.672805 -287.930526) (xy 92.703261 -287.888607) (xy 92.739899 -287.851969) (xy 92.781818 -287.821513)
			(xy 92.827985 -287.79799) (xy 92.877264 -287.781978) (xy 92.928441 -287.773872) (xy 92.980255 -287.773872)
			(xy 93.031432 -287.781978) (xy 93.080711 -287.79799) (xy 93.126878 -287.821513) (xy 93.168797 -287.851969)
			(xy 93.205435 -287.888607) (xy 93.235891 -287.930526) (xy 93.259414 -287.976693) (xy 93.275426 -288.025972)
			(xy 93.283532 -288.077149) (xy 93.28404 -288.103056) (xy 93.283618 -288.128404) (xy 93.275836 -288.178499)
			(xy 93.26048 -288.226813) (xy 93.237912 -288.272208) (xy 93.208662 -288.313614) (xy 93.173421 -288.350057)
			(xy 93.133018 -288.380678) (xy 93.088405 -288.404755) (xy 93.040632 -288.421722) (xy 93.015816 -288.426906)
			(xy 92.992956 -288.431224) (xy 92.787724 -288.786316) (xy 92.795598 -288.808414) (xy 92.80424 -288.834757)
			(xy 92.813554 -288.889407) (xy 92.81414 -288.917126) (xy 93.094556 -288.917126) (xy 93.095064 -288.891219)
			(xy 93.10317 -288.840042) (xy 93.119182 -288.790763) (xy 93.142705 -288.744596) (xy 93.173161 -288.702677)
			(xy 93.209799 -288.666039) (xy 93.251718 -288.635583) (xy 93.297885 -288.61206) (xy 93.347164 -288.596048)
			(xy 93.398341 -288.587942) (xy 93.450155 -288.587942) (xy 93.501332 -288.596048) (xy 93.550611 -288.61206)
			(xy 93.596778 -288.635583) (xy 93.638697 -288.666039) (xy 93.675335 -288.702677) (xy 93.705791 -288.744596)
			(xy 93.729314 -288.790763) (xy 93.745326 -288.840042) (xy 93.753432 -288.891219) (xy 93.75394 -288.917126)
			(xy 94.034356 -288.917126) (xy 94.034856 -288.891781) (xy 94.042625 -288.84169) (xy 94.057969 -288.793377)
			(xy 94.080527 -288.747983) (xy 94.109767 -288.706576) (xy 94.144999 -288.670131) (xy 94.185395 -288.639509)
			(xy 94.230001 -288.61543) (xy 94.277766 -288.598461) (xy 94.30258 -288.593276) (xy 94.32544 -288.588958)
			(xy 94.530672 -288.233866) (xy 94.522798 -288.211768) (xy 94.514176 -288.185419) (xy 94.504849 -288.130773)
			(xy 94.504256 -288.103056) (xy 94.504764 -288.077149) (xy 94.51287 -288.025972) (xy 94.528882 -287.976693)
			(xy 94.552405 -287.930526) (xy 94.582861 -287.888607) (xy 94.619499 -287.851969) (xy 94.661418 -287.821513)
			(xy 94.707585 -287.79799) (xy 94.756864 -287.781978) (xy 94.808041 -287.773872) (xy 94.859855 -287.773872)
			(xy 94.911032 -287.781978) (xy 94.960311 -287.79799) (xy 95.006478 -287.821513) (xy 95.048397 -287.851969)
			(xy 95.085035 -287.888607) (xy 95.115491 -287.930526) (xy 95.139014 -287.976693) (xy 95.155026 -288.025972)
			(xy 95.163132 -288.077149) (xy 95.16364 -288.103056) (xy 95.163218 -288.128404) (xy 95.155436 -288.178499)
			(xy 95.14008 -288.226813) (xy 95.117512 -288.272208) (xy 95.088262 -288.313614) (xy 95.053021 -288.350057)
			(xy 95.012618 -288.380678) (xy 94.968005 -288.404755) (xy 94.920232 -288.421722) (xy 94.895416 -288.426906)
			(xy 94.872556 -288.431224) (xy 94.667324 -288.786316) (xy 94.675198 -288.808414) (xy 94.68384 -288.834757)
			(xy 94.693154 -288.889407) (xy 94.69374 -288.917126) (xy 94.974156 -288.917126) (xy 94.974664 -288.891219)
			(xy 94.98277 -288.840042) (xy 94.998782 -288.790763) (xy 95.022305 -288.744596) (xy 95.052761 -288.702677)
			(xy 95.089399 -288.666039) (xy 95.131318 -288.635583) (xy 95.177485 -288.61206) (xy 95.226764 -288.596048)
			(xy 95.277941 -288.587942) (xy 95.329755 -288.587942) (xy 95.380932 -288.596048) (xy 95.430211 -288.61206)
			(xy 95.476378 -288.635583) (xy 95.518297 -288.666039) (xy 95.554935 -288.702677) (xy 95.585391 -288.744596)
			(xy 95.608914 -288.790763) (xy 95.624926 -288.840042) (xy 95.633032 -288.891219) (xy 95.63354 -288.917126)
			(xy 95.913956 -288.917126) (xy 95.914456 -288.891781) (xy 95.922225 -288.84169) (xy 95.937569 -288.793377)
			(xy 95.960127 -288.747983) (xy 95.989367 -288.706576) (xy 96.024599 -288.670131) (xy 96.064995 -288.639509)
			(xy 96.109601 -288.61543) (xy 96.157366 -288.598461) (xy 96.18218 -288.593276) (xy 96.20504 -288.588958)
			(xy 96.410272 -288.233866) (xy 96.402398 -288.211768) (xy 96.393776 -288.185419) (xy 96.384449 -288.130773)
			(xy 96.383856 -288.103056) (xy 96.384364 -288.077149) (xy 96.39247 -288.025972) (xy 96.408482 -287.976693)
			(xy 96.432005 -287.930526) (xy 96.462461 -287.888607) (xy 96.499099 -287.851969) (xy 96.541018 -287.821513)
			(xy 96.587185 -287.79799) (xy 96.636464 -287.781978) (xy 96.687641 -287.773872) (xy 96.739455 -287.773872)
			(xy 96.790632 -287.781978) (xy 96.839911 -287.79799) (xy 96.886078 -287.821513) (xy 96.927997 -287.851969)
			(xy 96.964635 -287.888607) (xy 96.995091 -287.930526) (xy 97.018614 -287.976693) (xy 97.034626 -288.025972)
			(xy 97.042732 -288.077149) (xy 97.04324 -288.103056) (xy 97.042818 -288.128404) (xy 97.035036 -288.178499)
			(xy 97.01968 -288.226813) (xy 96.997112 -288.272208) (xy 96.967862 -288.313614) (xy 96.932621 -288.350057)
			(xy 96.892218 -288.380678) (xy 96.847605 -288.404755) (xy 96.799832 -288.421722) (xy 96.775016 -288.426906)
			(xy 96.752156 -288.431224) (xy 96.546924 -288.786316) (xy 96.554798 -288.808414) (xy 96.56344 -288.834757)
			(xy 96.572754 -288.889407) (xy 96.57334 -288.917126) (xy 96.853756 -288.917126) (xy 96.854264 -288.891219)
			(xy 96.86237 -288.840042) (xy 96.878382 -288.790763) (xy 96.901905 -288.744596) (xy 96.932361 -288.702677)
			(xy 96.968999 -288.666039) (xy 97.010918 -288.635583) (xy 97.057085 -288.61206) (xy 97.106364 -288.596048)
			(xy 97.157541 -288.587942) (xy 97.209355 -288.587942) (xy 97.260532 -288.596048) (xy 97.309811 -288.61206)
			(xy 97.355978 -288.635583) (xy 97.397897 -288.666039) (xy 97.434535 -288.702677) (xy 97.464991 -288.744596)
			(xy 97.488514 -288.790763) (xy 97.504526 -288.840042) (xy 97.512632 -288.891219) (xy 97.51314 -288.917126)
			(xy 97.793556 -288.917126) (xy 97.794056 -288.891781) (xy 97.801825 -288.84169) (xy 97.817169 -288.793377)
			(xy 97.839727 -288.747983) (xy 97.868967 -288.706576) (xy 97.904199 -288.670131) (xy 97.944595 -288.639509)
			(xy 97.989201 -288.61543) (xy 98.036966 -288.598461) (xy 98.06178 -288.593276) (xy 98.08464 -288.588958)
			(xy 98.289872 -288.233866) (xy 98.281998 -288.211768) (xy 98.273376 -288.185419) (xy 98.264049 -288.130773)
			(xy 98.263456 -288.103056) (xy 98.263964 -288.077149) (xy 98.27207 -288.025972) (xy 98.288082 -287.976693)
			(xy 98.311605 -287.930526) (xy 98.342061 -287.888607) (xy 98.378699 -287.851969) (xy 98.420618 -287.821513)
			(xy 98.466785 -287.79799) (xy 98.516064 -287.781978) (xy 98.567241 -287.773872) (xy 98.619055 -287.773872)
			(xy 98.670232 -287.781978) (xy 98.719511 -287.79799) (xy 98.765678 -287.821513) (xy 98.807597 -287.851969)
			(xy 98.844235 -287.888607) (xy 98.874691 -287.930526) (xy 98.898214 -287.976693) (xy 98.914226 -288.025972)
			(xy 98.922332 -288.077149) (xy 98.92284 -288.103056) (xy 98.922418 -288.128404) (xy 98.914636 -288.178499)
			(xy 98.89928 -288.226813) (xy 98.876712 -288.272208) (xy 98.847462 -288.313614) (xy 98.812221 -288.350057)
			(xy 98.771818 -288.380678) (xy 98.727205 -288.404755) (xy 98.679432 -288.421722) (xy 98.654616 -288.426906)
			(xy 98.631756 -288.431224) (xy 98.426524 -288.786316) (xy 98.434398 -288.808414) (xy 98.44304 -288.834757)
			(xy 98.452354 -288.889407) (xy 98.45294 -288.917126) (xy 98.733356 -288.917126) (xy 98.733864 -288.891219)
			(xy 98.74197 -288.840042) (xy 98.757982 -288.790763) (xy 98.781505 -288.744596) (xy 98.811961 -288.702677)
			(xy 98.848599 -288.666039) (xy 98.890518 -288.635583) (xy 98.936685 -288.61206) (xy 98.985964 -288.596048)
			(xy 99.037141 -288.587942) (xy 99.088955 -288.587942) (xy 99.140132 -288.596048) (xy 99.189411 -288.61206)
			(xy 99.235578 -288.635583) (xy 99.277497 -288.666039) (xy 99.314135 -288.702677) (xy 99.344591 -288.744596)
			(xy 99.368114 -288.790763) (xy 99.384126 -288.840042) (xy 99.392232 -288.891219) (xy 99.39274 -288.917126)
			(xy 99.673156 -288.917126) (xy 99.673656 -288.891781) (xy 99.681425 -288.84169) (xy 99.696769 -288.793377)
			(xy 99.719327 -288.747983) (xy 99.748567 -288.706576) (xy 99.783799 -288.670131) (xy 99.824195 -288.639509)
			(xy 99.868801 -288.61543) (xy 99.916566 -288.598461) (xy 99.94138 -288.593276) (xy 99.96424 -288.588958)
			(xy 100.169472 -288.233866) (xy 100.161598 -288.211768) (xy 100.152976 -288.185419) (xy 100.143649 -288.130773)
			(xy 100.143056 -288.103056) (xy 100.143564 -288.077149) (xy 100.15167 -288.025972) (xy 100.167682 -287.976693)
			(xy 100.191205 -287.930526) (xy 100.221661 -287.888607) (xy 100.258299 -287.851969) (xy 100.300218 -287.821513)
			(xy 100.346385 -287.79799) (xy 100.395664 -287.781978) (xy 100.446841 -287.773872) (xy 100.498655 -287.773872)
			(xy 100.549832 -287.781978) (xy 100.599111 -287.79799) (xy 100.645278 -287.821513) (xy 100.687197 -287.851969)
			(xy 100.723835 -287.888607) (xy 100.754291 -287.930526) (xy 100.777814 -287.976693) (xy 100.793826 -288.025972)
			(xy 100.801932 -288.077149) (xy 100.80244 -288.103056) (xy 100.802018 -288.128404) (xy 100.794236 -288.178499)
			(xy 100.77888 -288.226813) (xy 100.756312 -288.272208) (xy 100.727062 -288.313614) (xy 100.691821 -288.350057)
			(xy 100.651418 -288.380678) (xy 100.606805 -288.404755) (xy 100.559032 -288.421722) (xy 100.534216 -288.426906)
			(xy 100.511356 -288.431224) (xy 100.306124 -288.786316) (xy 100.313998 -288.808414) (xy 100.32264 -288.834757)
			(xy 100.331954 -288.889407) (xy 100.33254 -288.917126) (xy 100.612956 -288.917126) (xy 100.613464 -288.891219)
			(xy 100.62157 -288.840042) (xy 100.637582 -288.790763) (xy 100.661105 -288.744596) (xy 100.691561 -288.702677)
			(xy 100.728199 -288.666039) (xy 100.770118 -288.635583) (xy 100.816285 -288.61206) (xy 100.865564 -288.596048)
			(xy 100.916741 -288.587942) (xy 100.968555 -288.587942) (xy 101.019732 -288.596048) (xy 101.069011 -288.61206)
			(xy 101.115178 -288.635583) (xy 101.157097 -288.666039) (xy 101.193735 -288.702677) (xy 101.224191 -288.744596)
			(xy 101.247714 -288.790763) (xy 101.263726 -288.840042) (xy 101.271832 -288.891219) (xy 101.27234 -288.917126)
			(xy 101.552756 -288.917126) (xy 101.553256 -288.891781) (xy 101.561025 -288.84169) (xy 101.576369 -288.793377)
			(xy 101.598927 -288.747983) (xy 101.628167 -288.706576) (xy 101.663399 -288.670131) (xy 101.703795 -288.639509)
			(xy 101.748401 -288.61543) (xy 101.796166 -288.598461) (xy 101.82098 -288.593276) (xy 101.84384 -288.588958)
			(xy 102.049072 -288.233866) (xy 102.041198 -288.211768) (xy 102.032576 -288.185419) (xy 102.023249 -288.130773)
			(xy 102.022656 -288.103056) (xy 102.023164 -288.077149) (xy 102.03127 -288.025972) (xy 102.047282 -287.976693)
			(xy 102.070805 -287.930526) (xy 102.101261 -287.888607) (xy 102.137899 -287.851969) (xy 102.179818 -287.821513)
			(xy 102.225985 -287.79799) (xy 102.275264 -287.781978) (xy 102.326441 -287.773872) (xy 102.378255 -287.773872)
			(xy 102.429432 -287.781978) (xy 102.478711 -287.79799) (xy 102.524878 -287.821513) (xy 102.566797 -287.851969)
			(xy 102.603435 -287.888607) (xy 102.633891 -287.930526) (xy 102.657414 -287.976693) (xy 102.673426 -288.025972)
			(xy 102.681532 -288.077149) (xy 102.68204 -288.103056) (xy 102.681618 -288.128404) (xy 102.673836 -288.178499)
			(xy 102.65848 -288.226813) (xy 102.635912 -288.272208) (xy 102.606662 -288.313614) (xy 102.571421 -288.350057)
			(xy 102.531018 -288.380678) (xy 102.486405 -288.404755) (xy 102.438632 -288.421722) (xy 102.413816 -288.426906)
			(xy 102.390956 -288.431224) (xy 102.185724 -288.786316) (xy 102.193598 -288.808414) (xy 102.20224 -288.834757)
			(xy 102.211554 -288.889407) (xy 102.21214 -288.917126) (xy 102.492556 -288.917126) (xy 102.493064 -288.891219)
			(xy 102.50117 -288.840042) (xy 102.517182 -288.790763) (xy 102.540705 -288.744596) (xy 102.571161 -288.702677)
			(xy 102.607799 -288.666039) (xy 102.649718 -288.635583) (xy 102.695885 -288.61206) (xy 102.745164 -288.596048)
			(xy 102.796341 -288.587942) (xy 102.848155 -288.587942) (xy 102.899332 -288.596048) (xy 102.948611 -288.61206)
			(xy 102.994778 -288.635583) (xy 103.036697 -288.666039) (xy 103.073335 -288.702677) (xy 103.103791 -288.744596)
			(xy 103.127314 -288.790763) (xy 103.143326 -288.840042) (xy 103.151432 -288.891219) (xy 103.15194 -288.917126)
			(xy 103.432356 -288.917126) (xy 103.432856 -288.891781) (xy 103.440625 -288.84169) (xy 103.455969 -288.793377)
			(xy 103.478527 -288.747983) (xy 103.507767 -288.706576) (xy 103.542999 -288.670131) (xy 103.583395 -288.639509)
			(xy 103.628001 -288.61543) (xy 103.675766 -288.598461) (xy 103.70058 -288.593276) (xy 103.72344 -288.588958)
			(xy 103.928672 -288.233866) (xy 103.920798 -288.211768) (xy 103.912176 -288.185419) (xy 103.902849 -288.130773)
			(xy 103.902256 -288.103056) (xy 103.902764 -288.077149) (xy 103.91087 -288.025972) (xy 103.926882 -287.976693)
			(xy 103.950405 -287.930526) (xy 103.980861 -287.888607) (xy 104.017499 -287.851969) (xy 104.059418 -287.821513)
			(xy 104.105585 -287.79799) (xy 104.154864 -287.781978) (xy 104.206041 -287.773872) (xy 104.257855 -287.773872)
			(xy 104.309032 -287.781978) (xy 104.358311 -287.79799) (xy 104.404478 -287.821513) (xy 104.446397 -287.851969)
			(xy 104.483035 -287.888607) (xy 104.513491 -287.930526) (xy 104.537014 -287.976693) (xy 104.553026 -288.025972)
			(xy 104.561132 -288.077149) (xy 104.56164 -288.103056) (xy 120.818656 -288.103056) (xy 120.819164 -288.077149)
			(xy 120.82727 -288.025972) (xy 120.843282 -287.976693) (xy 120.866805 -287.930526) (xy 120.897261 -287.888607)
			(xy 120.933899 -287.851969) (xy 120.975818 -287.821513) (xy 121.021985 -287.79799) (xy 121.071264 -287.781978)
			(xy 121.122441 -287.773872) (xy 121.174255 -287.773872) (xy 121.225432 -287.781978) (xy 121.274711 -287.79799)
			(xy 121.320878 -287.821513) (xy 121.362797 -287.851969) (xy 121.399435 -287.888607) (xy 121.429891 -287.930526)
			(xy 121.453414 -287.976693) (xy 121.469426 -288.025972) (xy 121.477532 -288.077149) (xy 121.47804 -288.103056)
			(xy 122.698256 -288.103056) (xy 122.698764 -288.077149) (xy 122.70687 -288.025972) (xy 122.722882 -287.976693)
			(xy 122.746405 -287.930526) (xy 122.776861 -287.888607) (xy 122.813499 -287.851969) (xy 122.855418 -287.821513)
			(xy 122.901585 -287.79799) (xy 122.950864 -287.781978) (xy 123.002041 -287.773872) (xy 123.053855 -287.773872)
			(xy 123.105032 -287.781978) (xy 123.154311 -287.79799) (xy 123.200478 -287.821513) (xy 123.242397 -287.851969)
			(xy 123.279035 -287.888607) (xy 123.309491 -287.930526) (xy 123.333014 -287.976693) (xy 123.349026 -288.025972)
			(xy 123.357132 -288.077149) (xy 123.35764 -288.103056) (xy 124.577856 -288.103056) (xy 124.578364 -288.077149)
			(xy 124.58647 -288.025972) (xy 124.602482 -287.976693) (xy 124.626005 -287.930526) (xy 124.656461 -287.888607)
			(xy 124.693099 -287.851969) (xy 124.735018 -287.821513) (xy 124.781185 -287.79799) (xy 124.830464 -287.781978)
			(xy 124.881641 -287.773872) (xy 124.933455 -287.773872) (xy 124.984632 -287.781978) (xy 125.033911 -287.79799)
			(xy 125.080078 -287.821513) (xy 125.121997 -287.851969) (xy 125.158635 -287.888607) (xy 125.189091 -287.930526)
			(xy 125.212614 -287.976693) (xy 125.228626 -288.025972) (xy 125.236732 -288.077149) (xy 125.23724 -288.103056)
			(xy 126.457456 -288.103056) (xy 126.457964 -288.077149) (xy 126.46607 -288.025972) (xy 126.482082 -287.976693)
			(xy 126.505605 -287.930526) (xy 126.536061 -287.888607) (xy 126.572699 -287.851969) (xy 126.614618 -287.821513)
			(xy 126.660785 -287.79799) (xy 126.710064 -287.781978) (xy 126.761241 -287.773872) (xy 126.813055 -287.773872)
			(xy 126.864232 -287.781978) (xy 126.913511 -287.79799) (xy 126.959678 -287.821513) (xy 127.001597 -287.851969)
			(xy 127.038235 -287.888607) (xy 127.068691 -287.930526) (xy 127.092214 -287.976693) (xy 127.108226 -288.025972)
			(xy 127.116332 -288.077149) (xy 127.11684 -288.103056) (xy 128.337056 -288.103056) (xy 128.337564 -288.077149)
			(xy 128.34567 -288.025972) (xy 128.361682 -287.976693) (xy 128.385205 -287.930526) (xy 128.415661 -287.888607)
			(xy 128.452299 -287.851969) (xy 128.494218 -287.821513) (xy 128.540385 -287.79799) (xy 128.589664 -287.781978)
			(xy 128.640841 -287.773872) (xy 128.692655 -287.773872) (xy 128.743832 -287.781978) (xy 128.793111 -287.79799)
			(xy 128.839278 -287.821513) (xy 128.881197 -287.851969) (xy 128.917835 -287.888607) (xy 128.948291 -287.930526)
			(xy 128.971814 -287.976693) (xy 128.987826 -288.025972) (xy 128.995932 -288.077149) (xy 128.99644 -288.103056)
			(xy 130.216656 -288.103056) (xy 130.217164 -288.077149) (xy 130.22527 -288.025972) (xy 130.241282 -287.976693)
			(xy 130.264805 -287.930526) (xy 130.295261 -287.888607) (xy 130.331899 -287.851969) (xy 130.373818 -287.821513)
			(xy 130.419985 -287.79799) (xy 130.469264 -287.781978) (xy 130.520441 -287.773872) (xy 130.572255 -287.773872)
			(xy 130.623432 -287.781978) (xy 130.672711 -287.79799) (xy 130.718878 -287.821513) (xy 130.760797 -287.851969)
			(xy 130.797435 -287.888607) (xy 130.827891 -287.930526) (xy 130.851414 -287.976693) (xy 130.867426 -288.025972)
			(xy 130.875532 -288.077149) (xy 130.87604 -288.103056) (xy 132.096256 -288.103056) (xy 132.096764 -288.077149)
			(xy 132.10487 -288.025972) (xy 132.120882 -287.976693) (xy 132.144405 -287.930526) (xy 132.174861 -287.888607)
			(xy 132.211499 -287.851969) (xy 132.253418 -287.821513) (xy 132.299585 -287.79799) (xy 132.348864 -287.781978)
			(xy 132.400041 -287.773872) (xy 132.451855 -287.773872) (xy 132.503032 -287.781978) (xy 132.552311 -287.79799)
			(xy 132.598478 -287.821513) (xy 132.640397 -287.851969) (xy 132.677035 -287.888607) (xy 132.707491 -287.930526)
			(xy 132.731014 -287.976693) (xy 132.747026 -288.025972) (xy 132.755132 -288.077149) (xy 132.75564 -288.103056)
			(xy 134.915656 -288.103056) (xy 134.916164 -288.077149) (xy 134.92427 -288.025972) (xy 134.940282 -287.976693)
			(xy 134.963805 -287.930526) (xy 134.994261 -287.888607) (xy 135.030899 -287.851969) (xy 135.072818 -287.821513)
			(xy 135.118985 -287.79799) (xy 135.168264 -287.781978) (xy 135.219441 -287.773872) (xy 135.271255 -287.773872)
			(xy 135.322432 -287.781978) (xy 135.371711 -287.79799) (xy 135.417878 -287.821513) (xy 135.459797 -287.851969)
			(xy 135.496435 -287.888607) (xy 135.526891 -287.930526) (xy 135.550414 -287.976693) (xy 135.566426 -288.025972)
			(xy 135.574532 -288.077149) (xy 135.57504 -288.103056) (xy 135.574438 -288.130773) (xy 135.56512 -288.18542)
			(xy 135.556498 -288.211768) (xy 135.548624 -288.233866) (xy 135.753856 -288.588958) (xy 135.776716 -288.593276)
			(xy 135.801527 -288.598486) (xy 135.849305 -288.615434) (xy 135.893924 -288.6395) (xy 135.934331 -288.670114)
			(xy 135.969573 -288.706556) (xy 135.998818 -288.747964) (xy 136.021377 -288.793363) (xy 136.036717 -288.841681)
			(xy 136.044477 -288.891779) (xy 136.04494 -288.917126) (xy 336.335624 -288.917126) (xy 336.336149 -288.891782)
			(xy 336.343918 -288.841693) (xy 336.359261 -288.793383) (xy 336.381816 -288.74799) (xy 336.411052 -288.706584)
			(xy 336.446281 -288.67014) (xy 336.486672 -288.639516) (xy 336.531274 -288.615435) (xy 336.579036 -288.598463)
			(xy 336.603848 -288.593276) (xy 336.626708 -288.588958) (xy 336.831686 -288.233866) (xy 336.823812 -288.212022)
			(xy 336.815238 -288.185602) (xy 336.806038 -288.130828) (xy 336.805524 -288.103056) (xy 336.806032 -288.077169)
			(xy 336.814131 -288.026031) (xy 336.83013 -287.976791) (xy 336.853636 -287.930659) (xy 336.884068 -287.888772)
			(xy 336.920678 -287.852162) (xy 336.962565 -287.82173) (xy 337.008697 -287.798224) (xy 337.057937 -287.782225)
			(xy 337.109075 -287.774126) (xy 337.160849 -287.774126) (xy 337.211987 -287.782225) (xy 337.261227 -287.798224)
			(xy 337.307359 -287.82173) (xy 337.349246 -287.852162) (xy 337.385856 -287.888772) (xy 337.416288 -287.930659)
			(xy 337.439794 -287.976791) (xy 337.455793 -288.026031) (xy 337.463892 -288.077169) (xy 337.4644 -288.103056)
			(xy 337.463968 -288.128392) (xy 337.456207 -288.178467) (xy 337.440877 -288.226765) (xy 337.418339 -288.272149)
			(xy 337.389123 -288.31355) (xy 337.353916 -288.349995) (xy 337.313549 -288.380624) (xy 337.268971 -288.404718)
			(xy 337.221232 -288.421708) (xy 337.19643 -288.426906) (xy 337.17357 -288.431224) (xy 336.968592 -288.786316)
			(xy 336.976466 -288.80816) (xy 336.985119 -288.834566) (xy 336.994435 -288.889344) (xy 336.995008 -288.917126)
			(xy 338.215224 -288.917126) (xy 338.215749 -288.891782) (xy 338.223518 -288.841693) (xy 338.238861 -288.793383)
			(xy 338.261416 -288.74799) (xy 338.290652 -288.706584) (xy 338.325881 -288.67014) (xy 338.366272 -288.639516)
			(xy 338.410874 -288.615435) (xy 338.458636 -288.598463) (xy 338.483448 -288.593276) (xy 338.506308 -288.588958)
			(xy 338.711286 -288.233866) (xy 338.703412 -288.212022) (xy 338.694838 -288.185602) (xy 338.685638 -288.130828)
			(xy 338.685124 -288.103056) (xy 338.685632 -288.077169) (xy 338.693731 -288.026031) (xy 338.70973 -287.976791)
			(xy 338.733236 -287.930659) (xy 338.763668 -287.888772) (xy 338.800278 -287.852162) (xy 338.842165 -287.82173)
			(xy 338.888297 -287.798224) (xy 338.937537 -287.782225) (xy 338.988675 -287.774126) (xy 339.040449 -287.774126)
			(xy 339.091587 -287.782225) (xy 339.140827 -287.798224) (xy 339.186959 -287.82173) (xy 339.228846 -287.852162)
			(xy 339.265456 -287.888772) (xy 339.295888 -287.930659) (xy 339.319394 -287.976791) (xy 339.335393 -288.026031)
			(xy 339.343492 -288.077169) (xy 339.344 -288.103056) (xy 339.343568 -288.128392) (xy 339.335807 -288.178467)
			(xy 339.320477 -288.226765) (xy 339.297939 -288.272149) (xy 339.268723 -288.31355) (xy 339.233516 -288.349995)
			(xy 339.193149 -288.380624) (xy 339.148571 -288.404718) (xy 339.100832 -288.421708) (xy 339.07603 -288.426906)
			(xy 339.05317 -288.431224) (xy 338.848192 -288.786316) (xy 338.856066 -288.80816) (xy 338.864719 -288.834566)
			(xy 338.874035 -288.889344) (xy 338.874608 -288.917126) (xy 339.155024 -288.917126) (xy 339.155532 -288.891219)
			(xy 339.163638 -288.840042) (xy 339.17965 -288.790763) (xy 339.203173 -288.744596) (xy 339.233629 -288.702677)
			(xy 339.270267 -288.666039) (xy 339.312186 -288.635583) (xy 339.358353 -288.61206) (xy 339.407632 -288.596048)
			(xy 339.458809 -288.587942) (xy 339.510623 -288.587942) (xy 339.5618 -288.596048) (xy 339.611079 -288.61206)
			(xy 339.657246 -288.635583) (xy 339.699165 -288.666039) (xy 339.735803 -288.702677) (xy 339.766259 -288.744596)
			(xy 339.789782 -288.790763) (xy 339.805794 -288.840042) (xy 339.8139 -288.891219) (xy 339.814408 -288.917126)
			(xy 340.094824 -288.917126) (xy 340.095349 -288.891782) (xy 340.103118 -288.841693) (xy 340.118461 -288.793383)
			(xy 340.141016 -288.74799) (xy 340.170252 -288.706584) (xy 340.205481 -288.67014) (xy 340.245872 -288.639516)
			(xy 340.290474 -288.615435) (xy 340.338236 -288.598463) (xy 340.363048 -288.593276) (xy 340.385908 -288.588958)
			(xy 340.59114 -288.233866) (xy 340.583266 -288.211768) (xy 340.574642 -288.185419) (xy 340.565317 -288.130773)
			(xy 340.564724 -288.103056) (xy 340.565232 -288.077149) (xy 340.573338 -288.025972) (xy 340.58935 -287.976693)
			(xy 340.612873 -287.930526) (xy 340.643329 -287.888607) (xy 340.679967 -287.851969) (xy 340.721886 -287.821513)
			(xy 340.768053 -287.79799) (xy 340.817332 -287.781978) (xy 340.868509 -287.773872) (xy 340.920323 -287.773872)
			(xy 340.9715 -287.781978) (xy 341.020779 -287.79799) (xy 341.066946 -287.821513) (xy 341.108865 -287.851969)
			(xy 341.145503 -287.888607) (xy 341.175959 -287.930526) (xy 341.199482 -287.976693) (xy 341.215494 -288.025972)
			(xy 341.2236 -288.077149) (xy 341.224108 -288.103056) (xy 341.223631 -288.128401) (xy 341.215851 -288.178491)
			(xy 341.200499 -288.2268) (xy 341.177936 -288.272192) (xy 341.148694 -288.313597) (xy 341.11346 -288.35004)
			(xy 341.073065 -288.380663) (xy 341.028461 -288.404744) (xy 340.980697 -288.421718) (xy 340.955884 -288.426906)
			(xy 340.933024 -288.431224) (xy 340.727792 -288.786316) (xy 340.735666 -288.808414) (xy 340.744307 -288.834758)
			(xy 340.753621 -288.889407) (xy 340.754208 -288.917126) (xy 341.034624 -288.917126) (xy 341.035132 -288.891219)
			(xy 341.043238 -288.840042) (xy 341.05925 -288.790763) (xy 341.082773 -288.744596) (xy 341.113229 -288.702677)
			(xy 341.149867 -288.666039) (xy 341.191786 -288.635583) (xy 341.237953 -288.61206) (xy 341.287232 -288.596048)
			(xy 341.338409 -288.587942) (xy 341.390223 -288.587942) (xy 341.4414 -288.596048) (xy 341.490679 -288.61206)
			(xy 341.536846 -288.635583) (xy 341.578765 -288.666039) (xy 341.615403 -288.702677) (xy 341.645859 -288.744596)
			(xy 341.669382 -288.790763) (xy 341.685394 -288.840042) (xy 341.6935 -288.891219) (xy 341.694008 -288.917126)
			(xy 341.974424 -288.917126) (xy 341.974949 -288.891782) (xy 341.982718 -288.841693) (xy 341.998061 -288.793383)
			(xy 342.020616 -288.74799) (xy 342.049852 -288.706584) (xy 342.085081 -288.67014) (xy 342.125472 -288.639516)
			(xy 342.170074 -288.615435) (xy 342.217836 -288.598463) (xy 342.242648 -288.593276) (xy 342.265508 -288.588958)
			(xy 342.47074 -288.233866) (xy 342.462866 -288.211768) (xy 342.454242 -288.185419) (xy 342.444917 -288.130773)
			(xy 342.444324 -288.103056) (xy 342.444832 -288.077149) (xy 342.452938 -288.025972) (xy 342.46895 -287.976693)
			(xy 342.492473 -287.930526) (xy 342.522929 -287.888607) (xy 342.559567 -287.851969) (xy 342.601486 -287.821513)
			(xy 342.647653 -287.79799) (xy 342.696932 -287.781978) (xy 342.748109 -287.773872) (xy 342.799923 -287.773872)
			(xy 342.8511 -287.781978) (xy 342.900379 -287.79799) (xy 342.946546 -287.821513) (xy 342.988465 -287.851969)
			(xy 343.025103 -287.888607) (xy 343.055559 -287.930526) (xy 343.079082 -287.976693) (xy 343.095094 -288.025972)
			(xy 343.1032 -288.077149) (xy 343.103708 -288.103056) (xy 343.103231 -288.128401) (xy 343.095451 -288.178491)
			(xy 343.080099 -288.2268) (xy 343.057536 -288.272192) (xy 343.028294 -288.313597) (xy 342.99306 -288.35004)
			(xy 342.952665 -288.380663) (xy 342.908061 -288.404744) (xy 342.860297 -288.421718) (xy 342.835484 -288.426906)
			(xy 342.812624 -288.431224) (xy 342.607392 -288.786316) (xy 342.615266 -288.808414) (xy 342.623907 -288.834758)
			(xy 342.633221 -288.889407) (xy 342.633808 -288.917126) (xy 342.914224 -288.917126) (xy 342.914732 -288.891219)
			(xy 342.922838 -288.840042) (xy 342.93885 -288.790763) (xy 342.962373 -288.744596) (xy 342.992829 -288.702677)
			(xy 343.029467 -288.666039) (xy 343.071386 -288.635583) (xy 343.117553 -288.61206) (xy 343.166832 -288.596048)
			(xy 343.218009 -288.587942) (xy 343.269823 -288.587942) (xy 343.321 -288.596048) (xy 343.370279 -288.61206)
			(xy 343.416446 -288.635583) (xy 343.458365 -288.666039) (xy 343.495003 -288.702677) (xy 343.525459 -288.744596)
			(xy 343.548982 -288.790763) (xy 343.564994 -288.840042) (xy 343.5731 -288.891219) (xy 343.573608 -288.917126)
			(xy 343.854024 -288.917126) (xy 343.854549 -288.891782) (xy 343.862318 -288.841693) (xy 343.877661 -288.793383)
			(xy 343.900216 -288.74799) (xy 343.929452 -288.706584) (xy 343.964681 -288.67014) (xy 344.005072 -288.639516)
			(xy 344.049674 -288.615435) (xy 344.097436 -288.598463) (xy 344.122248 -288.593276) (xy 344.145108 -288.588958)
			(xy 344.35034 -288.233866) (xy 344.342466 -288.211768) (xy 344.333842 -288.185419) (xy 344.324517 -288.130773)
			(xy 344.323924 -288.103056) (xy 344.324432 -288.077149) (xy 344.332538 -288.025972) (xy 344.34855 -287.976693)
			(xy 344.372073 -287.930526) (xy 344.402529 -287.888607) (xy 344.439167 -287.851969) (xy 344.481086 -287.821513)
			(xy 344.527253 -287.79799) (xy 344.576532 -287.781978) (xy 344.627709 -287.773872) (xy 344.679523 -287.773872)
			(xy 344.7307 -287.781978) (xy 344.779979 -287.79799) (xy 344.826146 -287.821513) (xy 344.868065 -287.851969)
			(xy 344.904703 -287.888607) (xy 344.935159 -287.930526) (xy 344.958682 -287.976693) (xy 344.974694 -288.025972)
			(xy 344.9828 -288.077149) (xy 344.983308 -288.103056) (xy 344.982831 -288.128401) (xy 344.975051 -288.178491)
			(xy 344.959699 -288.2268) (xy 344.937136 -288.272192) (xy 344.907894 -288.313597) (xy 344.87266 -288.35004)
			(xy 344.832265 -288.380663) (xy 344.787661 -288.404744) (xy 344.739897 -288.421718) (xy 344.715084 -288.426906)
			(xy 344.692224 -288.431224) (xy 344.486992 -288.786316) (xy 344.494866 -288.808414) (xy 344.503507 -288.834758)
			(xy 344.512821 -288.889407) (xy 344.513408 -288.917126) (xy 344.793824 -288.917126) (xy 344.794332 -288.891219)
			(xy 344.802438 -288.840042) (xy 344.81845 -288.790763) (xy 344.841973 -288.744596) (xy 344.872429 -288.702677)
			(xy 344.909067 -288.666039) (xy 344.950986 -288.635583) (xy 344.997153 -288.61206) (xy 345.046432 -288.596048)
			(xy 345.097609 -288.587942) (xy 345.149423 -288.587942) (xy 345.2006 -288.596048) (xy 345.249879 -288.61206)
			(xy 345.296046 -288.635583) (xy 345.337965 -288.666039) (xy 345.374603 -288.702677) (xy 345.405059 -288.744596)
			(xy 345.428582 -288.790763) (xy 345.444594 -288.840042) (xy 345.4527 -288.891219) (xy 345.453208 -288.917126)
			(xy 345.733624 -288.917126) (xy 345.734149 -288.891782) (xy 345.741918 -288.841693) (xy 345.757261 -288.793383)
			(xy 345.779816 -288.74799) (xy 345.809052 -288.706584) (xy 345.844281 -288.67014) (xy 345.884672 -288.639516)
			(xy 345.929274 -288.615435) (xy 345.977036 -288.598463) (xy 346.001848 -288.593276) (xy 346.024708 -288.588958)
			(xy 346.22994 -288.233866) (xy 346.222066 -288.211768) (xy 346.213442 -288.185419) (xy 346.204117 -288.130773)
			(xy 346.203524 -288.103056) (xy 346.204032 -288.077149) (xy 346.212138 -288.025972) (xy 346.22815 -287.976693)
			(xy 346.251673 -287.930526) (xy 346.282129 -287.888607) (xy 346.318767 -287.851969) (xy 346.360686 -287.821513)
			(xy 346.406853 -287.79799) (xy 346.456132 -287.781978) (xy 346.507309 -287.773872) (xy 346.559123 -287.773872)
			(xy 346.6103 -287.781978) (xy 346.659579 -287.79799) (xy 346.705746 -287.821513) (xy 346.747665 -287.851969)
			(xy 346.784303 -287.888607) (xy 346.814759 -287.930526) (xy 346.838282 -287.976693) (xy 346.854294 -288.025972)
			(xy 346.8624 -288.077149) (xy 346.862908 -288.103056) (xy 346.862431 -288.128401) (xy 346.854651 -288.178491)
			(xy 346.839299 -288.2268) (xy 346.816736 -288.272192) (xy 346.787494 -288.313597) (xy 346.75226 -288.35004)
			(xy 346.711865 -288.380663) (xy 346.667261 -288.404744) (xy 346.619497 -288.421718) (xy 346.594684 -288.426906)
			(xy 346.571824 -288.431224) (xy 346.366592 -288.786316) (xy 346.374466 -288.808414) (xy 346.383107 -288.834758)
			(xy 346.392421 -288.889407) (xy 346.393008 -288.917126) (xy 346.673424 -288.917126) (xy 346.673932 -288.891219)
			(xy 346.682038 -288.840042) (xy 346.69805 -288.790763) (xy 346.721573 -288.744596) (xy 346.752029 -288.702677)
			(xy 346.788667 -288.666039) (xy 346.830586 -288.635583) (xy 346.876753 -288.61206) (xy 346.926032 -288.596048)
			(xy 346.977209 -288.587942) (xy 347.029023 -288.587942) (xy 347.0802 -288.596048) (xy 347.129479 -288.61206)
			(xy 347.175646 -288.635583) (xy 347.217565 -288.666039) (xy 347.254203 -288.702677) (xy 347.284659 -288.744596)
			(xy 347.308182 -288.790763) (xy 347.324194 -288.840042) (xy 347.3323 -288.891219) (xy 347.332808 -288.917126)
			(xy 347.613224 -288.917126) (xy 347.613749 -288.891782) (xy 347.621518 -288.841693) (xy 347.636861 -288.793383)
			(xy 347.659416 -288.74799) (xy 347.688652 -288.706584) (xy 347.723881 -288.67014) (xy 347.764272 -288.639516)
			(xy 347.808874 -288.615435) (xy 347.856636 -288.598463) (xy 347.881448 -288.593276) (xy 347.904308 -288.588958)
			(xy 348.10954 -288.233866) (xy 348.101666 -288.211768) (xy 348.093042 -288.185419) (xy 348.083717 -288.130773)
			(xy 348.083124 -288.103056) (xy 348.083632 -288.077149) (xy 348.091738 -288.025972) (xy 348.10775 -287.976693)
			(xy 348.131273 -287.930526) (xy 348.161729 -287.888607) (xy 348.198367 -287.851969) (xy 348.240286 -287.821513)
			(xy 348.286453 -287.79799) (xy 348.335732 -287.781978) (xy 348.386909 -287.773872) (xy 348.438723 -287.773872)
			(xy 348.4899 -287.781978) (xy 348.539179 -287.79799) (xy 348.585346 -287.821513) (xy 348.627265 -287.851969)
			(xy 348.663903 -287.888607) (xy 348.694359 -287.930526) (xy 348.717882 -287.976693) (xy 348.733894 -288.025972)
			(xy 348.742 -288.077149) (xy 348.742508 -288.103056) (xy 348.742031 -288.128401) (xy 348.734251 -288.178491)
			(xy 348.718899 -288.2268) (xy 348.696336 -288.272192) (xy 348.667094 -288.313597) (xy 348.63186 -288.35004)
			(xy 348.591465 -288.380663) (xy 348.546861 -288.404744) (xy 348.499097 -288.421718) (xy 348.474284 -288.426906)
			(xy 348.451424 -288.431224) (xy 348.246192 -288.786316) (xy 348.254066 -288.808414) (xy 348.262707 -288.834758)
			(xy 348.272021 -288.889407) (xy 348.272608 -288.917126) (xy 348.553024 -288.917126) (xy 348.553532 -288.891219)
			(xy 348.561638 -288.840042) (xy 348.57765 -288.790763) (xy 348.601173 -288.744596) (xy 348.631629 -288.702677)
			(xy 348.668267 -288.666039) (xy 348.710186 -288.635583) (xy 348.756353 -288.61206) (xy 348.805632 -288.596048)
			(xy 348.856809 -288.587942) (xy 348.908623 -288.587942) (xy 348.9598 -288.596048) (xy 349.009079 -288.61206)
			(xy 349.055246 -288.635583) (xy 349.097165 -288.666039) (xy 349.133803 -288.702677) (xy 349.164259 -288.744596)
			(xy 349.187782 -288.790763) (xy 349.203794 -288.840042) (xy 349.2119 -288.891219) (xy 349.212408 -288.917126)
			(xy 349.492824 -288.917126) (xy 349.493349 -288.891782) (xy 349.501118 -288.841693) (xy 349.516461 -288.793383)
			(xy 349.539016 -288.74799) (xy 349.568252 -288.706584) (xy 349.603481 -288.67014) (xy 349.643872 -288.639516)
			(xy 349.688474 -288.615435) (xy 349.736236 -288.598463) (xy 349.761048 -288.593276) (xy 349.783908 -288.588958)
			(xy 349.98914 -288.233866) (xy 349.981266 -288.211768) (xy 349.972642 -288.185419) (xy 349.963317 -288.130773)
			(xy 349.962724 -288.103056) (xy 349.963232 -288.077149) (xy 349.971338 -288.025972) (xy 349.98735 -287.976693)
			(xy 350.010873 -287.930526) (xy 350.041329 -287.888607) (xy 350.077967 -287.851969) (xy 350.119886 -287.821513)
			(xy 350.166053 -287.79799) (xy 350.215332 -287.781978) (xy 350.266509 -287.773872) (xy 350.318323 -287.773872)
			(xy 350.3695 -287.781978) (xy 350.418779 -287.79799) (xy 350.464946 -287.821513) (xy 350.506865 -287.851969)
			(xy 350.543503 -287.888607) (xy 350.573959 -287.930526) (xy 350.597482 -287.976693) (xy 350.613494 -288.025972)
			(xy 350.6216 -288.077149) (xy 350.622108 -288.103056) (xy 350.621631 -288.128401) (xy 350.613851 -288.178491)
			(xy 350.598499 -288.2268) (xy 350.575936 -288.272192) (xy 350.546694 -288.313597) (xy 350.51146 -288.35004)
			(xy 350.471065 -288.380663) (xy 350.426461 -288.404744) (xy 350.378697 -288.421718) (xy 350.353884 -288.426906)
			(xy 350.331024 -288.431224) (xy 350.125792 -288.786316) (xy 350.133666 -288.808414) (xy 350.142307 -288.834758)
			(xy 350.151621 -288.889407) (xy 350.152208 -288.917126) (xy 350.432624 -288.917126) (xy 350.433132 -288.891219)
			(xy 350.441238 -288.840042) (xy 350.45725 -288.790763) (xy 350.480773 -288.744596) (xy 350.511229 -288.702677)
			(xy 350.547867 -288.666039) (xy 350.589786 -288.635583) (xy 350.635953 -288.61206) (xy 350.685232 -288.596048)
			(xy 350.736409 -288.587942) (xy 350.788223 -288.587942) (xy 350.8394 -288.596048) (xy 350.888679 -288.61206)
			(xy 350.934846 -288.635583) (xy 350.976765 -288.666039) (xy 351.013403 -288.702677) (xy 351.043859 -288.744596)
			(xy 351.067382 -288.790763) (xy 351.083394 -288.840042) (xy 351.0915 -288.891219) (xy 351.092008 -288.917126)
			(xy 351.372424 -288.917126) (xy 351.372949 -288.891782) (xy 351.380718 -288.841693) (xy 351.396061 -288.793383)
			(xy 351.418616 -288.74799) (xy 351.447852 -288.706584) (xy 351.483081 -288.67014) (xy 351.523472 -288.639516)
			(xy 351.568074 -288.615435) (xy 351.615836 -288.598463) (xy 351.640648 -288.593276) (xy 351.663508 -288.588958)
			(xy 351.86874 -288.233866) (xy 351.860866 -288.211768) (xy 351.852242 -288.185419) (xy 351.842917 -288.130773)
			(xy 351.842324 -288.103056) (xy 351.842832 -288.077149) (xy 351.850938 -288.025972) (xy 351.86695 -287.976693)
			(xy 351.890473 -287.930526) (xy 351.920929 -287.888607) (xy 351.957567 -287.851969) (xy 351.999486 -287.821513)
			(xy 352.045653 -287.79799) (xy 352.094932 -287.781978) (xy 352.146109 -287.773872) (xy 352.197923 -287.773872)
			(xy 352.2491 -287.781978) (xy 352.298379 -287.79799) (xy 352.344546 -287.821513) (xy 352.386465 -287.851969)
			(xy 352.423103 -287.888607) (xy 352.453559 -287.930526) (xy 352.477082 -287.976693) (xy 352.493094 -288.025972)
			(xy 352.5012 -288.077149) (xy 352.501708 -288.103056) (xy 368.758724 -288.103056) (xy 368.759232 -288.077149)
			(xy 368.767338 -288.025972) (xy 368.78335 -287.976693) (xy 368.806873 -287.930526) (xy 368.837329 -287.888607)
			(xy 368.873967 -287.851969) (xy 368.915886 -287.821513) (xy 368.962053 -287.79799) (xy 369.011332 -287.781978)
			(xy 369.062509 -287.773872) (xy 369.114323 -287.773872) (xy 369.1655 -287.781978) (xy 369.214779 -287.79799)
			(xy 369.260946 -287.821513) (xy 369.302865 -287.851969) (xy 369.339503 -287.888607) (xy 369.369959 -287.930526)
			(xy 369.393482 -287.976693) (xy 369.409494 -288.025972) (xy 369.4176 -288.077149) (xy 369.418108 -288.103056)
			(xy 370.638324 -288.103056) (xy 370.638832 -288.077149) (xy 370.646938 -288.025972) (xy 370.66295 -287.976693)
			(xy 370.686473 -287.930526) (xy 370.716929 -287.888607) (xy 370.753567 -287.851969) (xy 370.795486 -287.821513)
			(xy 370.841653 -287.79799) (xy 370.890932 -287.781978) (xy 370.942109 -287.773872) (xy 370.993923 -287.773872)
			(xy 371.0451 -287.781978) (xy 371.094379 -287.79799) (xy 371.140546 -287.821513) (xy 371.182465 -287.851969)
			(xy 371.219103 -287.888607) (xy 371.249559 -287.930526) (xy 371.273082 -287.976693) (xy 371.289094 -288.025972)
			(xy 371.2972 -288.077149) (xy 371.297708 -288.103056) (xy 372.517924 -288.103056) (xy 372.518432 -288.077149)
			(xy 372.526538 -288.025972) (xy 372.54255 -287.976693) (xy 372.566073 -287.930526) (xy 372.596529 -287.888607)
			(xy 372.633167 -287.851969) (xy 372.675086 -287.821513) (xy 372.721253 -287.79799) (xy 372.770532 -287.781978)
			(xy 372.821709 -287.773872) (xy 372.873523 -287.773872) (xy 372.9247 -287.781978) (xy 372.973979 -287.79799)
			(xy 373.020146 -287.821513) (xy 373.062065 -287.851969) (xy 373.098703 -287.888607) (xy 373.129159 -287.930526)
			(xy 373.152682 -287.976693) (xy 373.168694 -288.025972) (xy 373.1768 -288.077149) (xy 373.177308 -288.103056)
			(xy 374.397524 -288.103056) (xy 374.398032 -288.077149) (xy 374.406138 -288.025972) (xy 374.42215 -287.976693)
			(xy 374.445673 -287.930526) (xy 374.476129 -287.888607) (xy 374.512767 -287.851969) (xy 374.554686 -287.821513)
			(xy 374.600853 -287.79799) (xy 374.650132 -287.781978) (xy 374.701309 -287.773872) (xy 374.753123 -287.773872)
			(xy 374.8043 -287.781978) (xy 374.853579 -287.79799) (xy 374.899746 -287.821513) (xy 374.941665 -287.851969)
			(xy 374.978303 -287.888607) (xy 375.008759 -287.930526) (xy 375.032282 -287.976693) (xy 375.048294 -288.025972)
			(xy 375.0564 -288.077149) (xy 375.056908 -288.103056) (xy 376.277124 -288.103056) (xy 376.277632 -288.077149)
			(xy 376.285738 -288.025972) (xy 376.30175 -287.976693) (xy 376.325273 -287.930526) (xy 376.355729 -287.888607)
			(xy 376.392367 -287.851969) (xy 376.434286 -287.821513) (xy 376.480453 -287.79799) (xy 376.529732 -287.781978)
			(xy 376.580909 -287.773872) (xy 376.632723 -287.773872) (xy 376.6839 -287.781978) (xy 376.733179 -287.79799)
			(xy 376.779346 -287.821513) (xy 376.821265 -287.851969) (xy 376.857903 -287.888607) (xy 376.888359 -287.930526)
			(xy 376.911882 -287.976693) (xy 376.927894 -288.025972) (xy 376.936 -288.077149) (xy 376.936508 -288.103056)
			(xy 378.156724 -288.103056) (xy 378.157232 -288.077149) (xy 378.165338 -288.025972) (xy 378.18135 -287.976693)
			(xy 378.204873 -287.930526) (xy 378.235329 -287.888607) (xy 378.271967 -287.851969) (xy 378.313886 -287.821513)
			(xy 378.360053 -287.79799) (xy 378.409332 -287.781978) (xy 378.460509 -287.773872) (xy 378.512323 -287.773872)
			(xy 378.5635 -287.781978) (xy 378.612779 -287.79799) (xy 378.658946 -287.821513) (xy 378.700865 -287.851969)
			(xy 378.737503 -287.888607) (xy 378.767959 -287.930526) (xy 378.791482 -287.976693) (xy 378.807494 -288.025972)
			(xy 378.8156 -288.077149) (xy 378.816108 -288.103056) (xy 380.036324 -288.103056) (xy 380.036832 -288.077149)
			(xy 380.044938 -288.025972) (xy 380.06095 -287.976693) (xy 380.084473 -287.930526) (xy 380.114929 -287.888607)
			(xy 380.151567 -287.851969) (xy 380.193486 -287.821513) (xy 380.239653 -287.79799) (xy 380.288932 -287.781978)
			(xy 380.340109 -287.773872) (xy 380.391923 -287.773872) (xy 380.4431 -287.781978) (xy 380.492379 -287.79799)
			(xy 380.538546 -287.821513) (xy 380.580465 -287.851969) (xy 380.617103 -287.888607) (xy 380.647559 -287.930526)
			(xy 380.671082 -287.976693) (xy 380.687094 -288.025972) (xy 380.6952 -288.077149) (xy 380.695708 -288.103056)
			(xy 382.855724 -288.103056) (xy 382.856232 -288.077149) (xy 382.864338 -288.025972) (xy 382.88035 -287.976693)
			(xy 382.903873 -287.930526) (xy 382.934329 -287.888607) (xy 382.970967 -287.851969) (xy 383.012886 -287.821513)
			(xy 383.059053 -287.79799) (xy 383.108332 -287.781978) (xy 383.159509 -287.773872) (xy 383.211323 -287.773872)
			(xy 383.2625 -287.781978) (xy 383.311779 -287.79799) (xy 383.357946 -287.821513) (xy 383.399865 -287.851969)
			(xy 383.436503 -287.888607) (xy 383.466959 -287.930526) (xy 383.490482 -287.976693) (xy 383.506494 -288.025972)
			(xy 383.5146 -288.077149) (xy 383.515108 -288.103056) (xy 383.514503 -288.130773) (xy 383.505187 -288.185419)
			(xy 383.496566 -288.211768) (xy 383.488692 -288.233866) (xy 383.693924 -288.588958) (xy 383.716784 -288.593276)
			(xy 383.741606 -288.598437) (xy 383.789384 -288.615395) (xy 383.834001 -288.639469) (xy 383.874406 -288.67009)
			(xy 383.909646 -288.706538) (xy 383.93889 -288.747952) (xy 383.961447 -288.793355) (xy 383.976786 -288.841676)
			(xy 383.984545 -288.891777) (xy 383.985008 -288.917126) (xy 383.9845 -288.943033) (xy 383.976394 -288.99421)
			(xy 383.960382 -289.043489) (xy 383.936859 -289.089656) (xy 383.906403 -289.131575) (xy 383.869765 -289.168213)
			(xy 383.827846 -289.198669) (xy 383.781679 -289.222192) (xy 383.7324 -289.238204) (xy 383.681223 -289.24631)
			(xy 383.629409 -289.24631) (xy 383.578232 -289.238204) (xy 383.528953 -289.222192) (xy 383.482786 -289.198669)
			(xy 383.440867 -289.168213) (xy 383.404229 -289.131575) (xy 383.373773 -289.089656) (xy 383.35025 -289.043489)
			(xy 383.334238 -288.99421) (xy 383.326132 -288.943033) (xy 383.325624 -288.917126) (xy 383.326223 -288.889409)
			(xy 383.335543 -288.834762) (xy 383.344166 -288.808414) (xy 383.35204 -288.786316) (xy 383.146808 -288.431224)
			(xy 383.123948 -288.426906) (xy 383.099127 -288.421739) (xy 383.051348 -288.404784) (xy 383.006729 -288.380713)
			(xy 382.966322 -288.350092) (xy 382.931082 -288.313646) (xy 382.901838 -288.272232) (xy 382.879281 -288.226828)
			(xy 382.863943 -288.178506) (xy 382.856186 -288.128405) (xy 382.855724 -288.103056) (xy 380.695708 -288.103056)
			(xy 380.695103 -288.130773) (xy 380.685787 -288.185419) (xy 380.677166 -288.211768) (xy 380.669546 -288.233866)
			(xy 380.874524 -288.588958) (xy 380.897384 -288.593276) (xy 380.922206 -288.598437) (xy 380.969984 -288.615395)
			(xy 381.014601 -288.639469) (xy 381.055006 -288.67009) (xy 381.090246 -288.706538) (xy 381.11949 -288.747952)
			(xy 381.142047 -288.793355) (xy 381.157386 -288.841676) (xy 381.165145 -288.891777) (xy 381.165608 -288.917126)
			(xy 381.1651 -288.943033) (xy 381.156994 -288.99421) (xy 381.140982 -289.043489) (xy 381.117459 -289.089656)
			(xy 381.087003 -289.131575) (xy 381.050365 -289.168213) (xy 381.008446 -289.198669) (xy 380.962279 -289.222192)
			(xy 380.913 -289.238204) (xy 380.861823 -289.24631) (xy 380.810009 -289.24631) (xy 380.758832 -289.238204)
			(xy 380.709553 -289.222192) (xy 380.663386 -289.198669) (xy 380.621467 -289.168213) (xy 380.584829 -289.131575)
			(xy 380.554373 -289.089656) (xy 380.53085 -289.043489) (xy 380.514838 -288.99421) (xy 380.506732 -288.943033)
			(xy 380.506224 -288.917126) (xy 380.506823 -288.889409) (xy 380.516143 -288.834762) (xy 380.524766 -288.808414)
			(xy 380.53264 -288.786316) (xy 380.327662 -288.431224) (xy 380.304802 -288.426906) (xy 380.279961 -288.421779)
			(xy 380.232152 -288.40484) (xy 380.187502 -288.380778) (xy 380.147063 -288.350162) (xy 380.111791 -288.313713)
			(xy 380.082517 -288.272293) (xy 380.059933 -288.226877) (xy 380.044571 -288.178538) (xy 380.036794 -288.128417)
			(xy 380.036324 -288.103056) (xy 378.816108 -288.103056) (xy 378.815503 -288.130773) (xy 378.806187 -288.185419)
			(xy 378.797566 -288.211768) (xy 378.789946 -288.233866) (xy 378.994924 -288.588958) (xy 379.017784 -288.593276)
			(xy 379.042606 -288.598437) (xy 379.090384 -288.615395) (xy 379.135001 -288.639469) (xy 379.175406 -288.67009)
			(xy 379.210646 -288.706538) (xy 379.23989 -288.747952) (xy 379.262447 -288.793355) (xy 379.277786 -288.841676)
			(xy 379.285545 -288.891777) (xy 379.286008 -288.917126) (xy 379.2855 -288.943033) (xy 379.277394 -288.99421)
			(xy 379.261382 -289.043489) (xy 379.237859 -289.089656) (xy 379.207403 -289.131575) (xy 379.170765 -289.168213)
			(xy 379.128846 -289.198669) (xy 379.082679 -289.222192) (xy 379.0334 -289.238204) (xy 378.982223 -289.24631)
			(xy 378.930409 -289.24631) (xy 378.879232 -289.238204) (xy 378.829953 -289.222192) (xy 378.783786 -289.198669)
			(xy 378.741867 -289.168213) (xy 378.705229 -289.131575) (xy 378.674773 -289.089656) (xy 378.65125 -289.043489)
			(xy 378.635238 -288.99421) (xy 378.627132 -288.943033) (xy 378.626624 -288.917126) (xy 378.627223 -288.889409)
			(xy 378.636543 -288.834762) (xy 378.645166 -288.808414) (xy 378.65304 -288.786316) (xy 378.448062 -288.431224)
			(xy 378.425202 -288.426906) (xy 378.400361 -288.421779) (xy 378.352552 -288.40484) (xy 378.307902 -288.380778)
			(xy 378.267463 -288.350162) (xy 378.232191 -288.313713) (xy 378.202917 -288.272293) (xy 378.180333 -288.226877)
			(xy 378.164971 -288.178538) (xy 378.157194 -288.128417) (xy 378.156724 -288.103056) (xy 376.936508 -288.103056)
			(xy 376.935903 -288.130773) (xy 376.926587 -288.185419) (xy 376.917966 -288.211768) (xy 376.910346 -288.233866)
			(xy 377.115324 -288.588958) (xy 377.138184 -288.593276) (xy 377.163006 -288.598437) (xy 377.210784 -288.615395)
			(xy 377.255401 -288.639469) (xy 377.295806 -288.67009) (xy 377.331046 -288.706538) (xy 377.36029 -288.747952)
			(xy 377.382847 -288.793355) (xy 377.398186 -288.841676) (xy 377.405945 -288.891777) (xy 377.406408 -288.917126)
			(xy 377.4059 -288.943033) (xy 377.397794 -288.99421) (xy 377.381782 -289.043489) (xy 377.358259 -289.089656)
			(xy 377.327803 -289.131575) (xy 377.291165 -289.168213) (xy 377.249246 -289.198669) (xy 377.203079 -289.222192)
			(xy 377.1538 -289.238204) (xy 377.102623 -289.24631) (xy 377.050809 -289.24631) (xy 376.999632 -289.238204)
			(xy 376.950353 -289.222192) (xy 376.904186 -289.198669) (xy 376.862267 -289.168213) (xy 376.825629 -289.131575)
			(xy 376.795173 -289.089656) (xy 376.77165 -289.043489) (xy 376.755638 -288.99421) (xy 376.747532 -288.943033)
			(xy 376.747024 -288.917126) (xy 376.747623 -288.889409) (xy 376.756943 -288.834762) (xy 376.765566 -288.808414)
			(xy 376.77344 -288.786316) (xy 376.568462 -288.431224) (xy 376.545602 -288.426906) (xy 376.520761 -288.421779)
			(xy 376.472952 -288.40484) (xy 376.428302 -288.380778) (xy 376.387863 -288.350162) (xy 376.352591 -288.313713)
			(xy 376.323317 -288.272293) (xy 376.300733 -288.226877) (xy 376.285371 -288.178538) (xy 376.277594 -288.128417)
			(xy 376.277124 -288.103056) (xy 375.056908 -288.103056) (xy 375.056303 -288.130773) (xy 375.046987 -288.185419)
			(xy 375.038366 -288.211768) (xy 375.030746 -288.233866) (xy 375.235724 -288.588958) (xy 375.258584 -288.593276)
			(xy 375.283406 -288.598437) (xy 375.331184 -288.615395) (xy 375.375801 -288.639469) (xy 375.416206 -288.67009)
			(xy 375.451446 -288.706538) (xy 375.48069 -288.747952) (xy 375.503247 -288.793355) (xy 375.518586 -288.841676)
			(xy 375.526345 -288.891777) (xy 375.526808 -288.917126) (xy 375.5263 -288.943033) (xy 375.518194 -288.99421)
			(xy 375.502182 -289.043489) (xy 375.478659 -289.089656) (xy 375.448203 -289.131575) (xy 375.411565 -289.168213)
			(xy 375.369646 -289.198669) (xy 375.323479 -289.222192) (xy 375.2742 -289.238204) (xy 375.223023 -289.24631)
			(xy 375.171209 -289.24631) (xy 375.120032 -289.238204) (xy 375.070753 -289.222192) (xy 375.024586 -289.198669)
			(xy 374.982667 -289.168213) (xy 374.946029 -289.131575) (xy 374.915573 -289.089656) (xy 374.89205 -289.043489)
			(xy 374.876038 -288.99421) (xy 374.867932 -288.943033) (xy 374.867424 -288.917126) (xy 374.868023 -288.889409)
			(xy 374.877343 -288.834762) (xy 374.885966 -288.808414) (xy 374.89384 -288.786316) (xy 374.688862 -288.431224)
			(xy 374.666002 -288.426906) (xy 374.641161 -288.421779) (xy 374.593352 -288.40484) (xy 374.548702 -288.380778)
			(xy 374.508263 -288.350162) (xy 374.472991 -288.313713) (xy 374.443717 -288.272293) (xy 374.421133 -288.226877)
			(xy 374.405771 -288.178538) (xy 374.397994 -288.128417) (xy 374.397524 -288.103056) (xy 373.177308 -288.103056)
			(xy 373.176703 -288.130773) (xy 373.167387 -288.185419) (xy 373.158766 -288.211768) (xy 373.151146 -288.233866)
			(xy 373.356124 -288.588958) (xy 373.378984 -288.593276) (xy 373.403806 -288.598437) (xy 373.451584 -288.615395)
			(xy 373.496201 -288.639469) (xy 373.536606 -288.67009) (xy 373.571846 -288.706538) (xy 373.60109 -288.747952)
			(xy 373.623647 -288.793355) (xy 373.638986 -288.841676) (xy 373.646745 -288.891777) (xy 373.647208 -288.917126)
			(xy 373.6467 -288.943033) (xy 373.638594 -288.99421) (xy 373.622582 -289.043489) (xy 373.599059 -289.089656)
			(xy 373.568603 -289.131575) (xy 373.531965 -289.168213) (xy 373.490046 -289.198669) (xy 373.443879 -289.222192)
			(xy 373.3946 -289.238204) (xy 373.343423 -289.24631) (xy 373.291609 -289.24631) (xy 373.240432 -289.238204)
			(xy 373.191153 -289.222192) (xy 373.144986 -289.198669) (xy 373.103067 -289.168213) (xy 373.066429 -289.131575)
			(xy 373.035973 -289.089656) (xy 373.01245 -289.043489) (xy 372.996438 -288.99421) (xy 372.988332 -288.943033)
			(xy 372.987824 -288.917126) (xy 372.988423 -288.889409) (xy 372.997743 -288.834762) (xy 373.006366 -288.808414)
			(xy 373.01424 -288.786316) (xy 372.809262 -288.431224) (xy 372.786402 -288.426906) (xy 372.761561 -288.421779)
			(xy 372.713752 -288.40484) (xy 372.669102 -288.380778) (xy 372.628663 -288.350162) (xy 372.593391 -288.313713)
			(xy 372.564117 -288.272293) (xy 372.541533 -288.226877) (xy 372.526171 -288.178538) (xy 372.518394 -288.128417)
			(xy 372.517924 -288.103056) (xy 371.297708 -288.103056) (xy 371.297103 -288.130773) (xy 371.287787 -288.185419)
			(xy 371.279166 -288.211768) (xy 371.271546 -288.233866) (xy 371.476524 -288.588958) (xy 371.499384 -288.593276)
			(xy 371.524206 -288.598437) (xy 371.571984 -288.615395) (xy 371.616601 -288.639469) (xy 371.657006 -288.67009)
			(xy 371.692246 -288.706538) (xy 371.72149 -288.747952) (xy 371.744047 -288.793355) (xy 371.759386 -288.841676)
			(xy 371.767145 -288.891777) (xy 371.767608 -288.917126) (xy 371.7671 -288.943033) (xy 371.758994 -288.99421)
			(xy 371.742982 -289.043489) (xy 371.719459 -289.089656) (xy 371.689003 -289.131575) (xy 371.652365 -289.168213)
			(xy 371.610446 -289.198669) (xy 371.564279 -289.222192) (xy 371.515 -289.238204) (xy 371.463823 -289.24631)
			(xy 371.412009 -289.24631) (xy 371.360832 -289.238204) (xy 371.311553 -289.222192) (xy 371.265386 -289.198669)
			(xy 371.223467 -289.168213) (xy 371.186829 -289.131575) (xy 371.156373 -289.089656) (xy 371.13285 -289.043489)
			(xy 371.116838 -288.99421) (xy 371.108732 -288.943033) (xy 371.108224 -288.917126) (xy 371.108823 -288.889409)
			(xy 371.118143 -288.834762) (xy 371.126766 -288.808414) (xy 371.13464 -288.786316) (xy 370.929662 -288.431224)
			(xy 370.906802 -288.426906) (xy 370.881961 -288.421779) (xy 370.834152 -288.40484) (xy 370.789502 -288.380778)
			(xy 370.749063 -288.350162) (xy 370.713791 -288.313713) (xy 370.684517 -288.272293) (xy 370.661933 -288.226877)
			(xy 370.646571 -288.178538) (xy 370.638794 -288.128417) (xy 370.638324 -288.103056) (xy 369.418108 -288.103056)
			(xy 369.417503 -288.130773) (xy 369.408187 -288.185419) (xy 369.399566 -288.211768) (xy 369.391692 -288.233866)
			(xy 369.596924 -288.588958) (xy 369.619784 -288.593276) (xy 369.644606 -288.598437) (xy 369.692384 -288.615395)
			(xy 369.737001 -288.639469) (xy 369.777406 -288.67009) (xy 369.812646 -288.706538) (xy 369.84189 -288.747952)
			(xy 369.864447 -288.793355) (xy 369.879786 -288.841676) (xy 369.887545 -288.891777) (xy 369.888008 -288.917126)
			(xy 369.8875 -288.943033) (xy 369.879394 -288.99421) (xy 369.863382 -289.043489) (xy 369.839859 -289.089656)
			(xy 369.809403 -289.131575) (xy 369.772765 -289.168213) (xy 369.730846 -289.198669) (xy 369.684679 -289.222192)
			(xy 369.6354 -289.238204) (xy 369.584223 -289.24631) (xy 369.532409 -289.24631) (xy 369.481232 -289.238204)
			(xy 369.431953 -289.222192) (xy 369.385786 -289.198669) (xy 369.343867 -289.168213) (xy 369.307229 -289.131575)
			(xy 369.276773 -289.089656) (xy 369.25325 -289.043489) (xy 369.237238 -288.99421) (xy 369.229132 -288.943033)
			(xy 369.228624 -288.917126) (xy 369.229223 -288.889409) (xy 369.238543 -288.834762) (xy 369.247166 -288.808414)
			(xy 369.25504 -288.786316) (xy 369.049808 -288.431224) (xy 369.026948 -288.426906) (xy 369.002127 -288.421739)
			(xy 368.954348 -288.404784) (xy 368.909729 -288.380713) (xy 368.869322 -288.350092) (xy 368.834082 -288.313646)
			(xy 368.804838 -288.272232) (xy 368.782281 -288.226828) (xy 368.766943 -288.178506) (xy 368.759186 -288.128405)
			(xy 368.758724 -288.103056) (xy 352.501708 -288.103056) (xy 352.501231 -288.128401) (xy 352.493451 -288.178491)
			(xy 352.478099 -288.2268) (xy 352.455536 -288.272192) (xy 352.426294 -288.313597) (xy 352.39106 -288.35004)
			(xy 352.350665 -288.380663) (xy 352.306061 -288.404744) (xy 352.258297 -288.421718) (xy 352.233484 -288.426906)
			(xy 352.210624 -288.431224) (xy 352.005392 -288.786316) (xy 352.013266 -288.808414) (xy 352.021907 -288.834758)
			(xy 352.031221 -288.889407) (xy 352.031808 -288.917126) (xy 352.0313 -288.943033) (xy 352.023194 -288.99421)
			(xy 352.007182 -289.043489) (xy 351.983659 -289.089656) (xy 351.953203 -289.131575) (xy 351.916565 -289.168213)
			(xy 351.874646 -289.198669) (xy 351.828479 -289.222192) (xy 351.7792 -289.238204) (xy 351.728023 -289.24631)
			(xy 351.676209 -289.24631) (xy 351.625032 -289.238204) (xy 351.575753 -289.222192) (xy 351.529586 -289.198669)
			(xy 351.487667 -289.168213) (xy 351.451029 -289.131575) (xy 351.420573 -289.089656) (xy 351.39705 -289.043489)
			(xy 351.381038 -288.99421) (xy 351.372932 -288.943033) (xy 351.372424 -288.917126) (xy 351.092008 -288.917126)
			(xy 351.091589 -288.940067) (xy 351.08516 -288.985498) (xy 351.072513 -289.029604) (xy 351.06356 -289.05073)
			(xy 351.053654 -289.073336) (xy 351.267522 -289.478466) (xy 351.291652 -289.483038) (xy 351.316573 -289.488138)
			(xy 351.364584 -289.504939) (xy 351.409443 -289.528919) (xy 351.450084 -289.559507) (xy 351.485541 -289.595978)
			(xy 351.514973 -289.637465) (xy 351.537679 -289.682981) (xy 351.553121 -289.731446) (xy 351.560931 -289.781709)
			(xy 351.5614 -289.807142) (xy 367.818924 -289.807142) (xy 367.819411 -289.781712) (xy 367.827244 -289.73146)
			(xy 367.842699 -289.683005) (xy 367.86541 -289.637498) (xy 367.894839 -289.596018) (xy 367.930287 -289.559547)
			(xy 367.970914 -289.528951) (xy 368.015757 -289.504956) (xy 368.063753 -289.48813) (xy 368.088672 -289.483038)
			(xy 368.112802 -289.478466) (xy 368.327178 -289.073082) (xy 368.317272 -289.050476) (xy 368.308309 -289.029398)
			(xy 368.295664 -288.985377) (xy 368.289249 -288.940026) (xy 368.288824 -288.917126) (xy 368.289332 -288.891219)
			(xy 368.297438 -288.840042) (xy 368.31345 -288.790763) (xy 368.336973 -288.744596) (xy 368.367429 -288.702677)
			(xy 368.404067 -288.666039) (xy 368.445986 -288.635583) (xy 368.492153 -288.61206) (xy 368.541432 -288.596048)
			(xy 368.592609 -288.587942) (xy 368.644423 -288.587942) (xy 368.6956 -288.596048) (xy 368.744879 -288.61206)
			(xy 368.791046 -288.635583) (xy 368.832965 -288.666039) (xy 368.869603 -288.702677) (xy 368.900059 -288.744596)
			(xy 368.923582 -288.790763) (xy 368.939594 -288.840042) (xy 368.9477 -288.891219) (xy 368.948208 -288.917126)
			(xy 368.947753 -288.942575) (xy 368.939949 -288.992871) (xy 368.924499 -289.041367) (xy 368.901771 -289.086909)
			(xy 368.872307 -289.128411) (xy 368.836809 -289.164887) (xy 368.796121 -289.195466) (xy 368.751213 -289.21942)
			(xy 368.703153 -289.23618) (xy 368.678206 -289.24123) (xy 368.654076 -289.245802) (xy 368.4397 -289.651186)
			(xy 368.449606 -289.673792) (xy 368.458528 -289.694877) (xy 368.471078 -289.738907) (xy 368.47741 -289.78425)
			(xy 368.4778 -289.807142) (xy 369.698524 -289.807142) (xy 369.699011 -289.781712) (xy 369.706844 -289.73146)
			(xy 369.722299 -289.683005) (xy 369.74501 -289.637498) (xy 369.774439 -289.596018) (xy 369.809887 -289.559547)
			(xy 369.850514 -289.528951) (xy 369.895357 -289.504956) (xy 369.943353 -289.48813) (xy 369.968272 -289.483038)
			(xy 369.992402 -289.478466) (xy 370.206778 -289.073082) (xy 370.196872 -289.050476) (xy 370.187909 -289.029398)
			(xy 370.175264 -288.985377) (xy 370.168849 -288.940026) (xy 370.168424 -288.917126) (xy 370.168932 -288.891219)
			(xy 370.177038 -288.840042) (xy 370.19305 -288.790763) (xy 370.216573 -288.744596) (xy 370.247029 -288.702677)
			(xy 370.283667 -288.666039) (xy 370.325586 -288.635583) (xy 370.371753 -288.61206) (xy 370.421032 -288.596048)
			(xy 370.472209 -288.587942) (xy 370.524023 -288.587942) (xy 370.5752 -288.596048) (xy 370.624479 -288.61206)
			(xy 370.670646 -288.635583) (xy 370.712565 -288.666039) (xy 370.749203 -288.702677) (xy 370.779659 -288.744596)
			(xy 370.803182 -288.790763) (xy 370.819194 -288.840042) (xy 370.8273 -288.891219) (xy 370.827808 -288.917126)
			(xy 370.827353 -288.942575) (xy 370.819549 -288.992871) (xy 370.804099 -289.041367) (xy 370.781371 -289.086909)
			(xy 370.751907 -289.128411) (xy 370.716409 -289.164887) (xy 370.675721 -289.195466) (xy 370.630813 -289.21942)
			(xy 370.582753 -289.23618) (xy 370.557806 -289.24123) (xy 370.533676 -289.245802) (xy 370.3193 -289.651186)
			(xy 370.329206 -289.673792) (xy 370.338128 -289.694877) (xy 370.350678 -289.738907) (xy 370.35701 -289.78425)
			(xy 370.3574 -289.807142) (xy 371.578124 -289.807142) (xy 371.578611 -289.781712) (xy 371.586444 -289.73146)
			(xy 371.601899 -289.683005) (xy 371.62461 -289.637498) (xy 371.654039 -289.596018) (xy 371.689487 -289.559547)
			(xy 371.730114 -289.528951) (xy 371.774957 -289.504956) (xy 371.822953 -289.48813) (xy 371.847872 -289.483038)
			(xy 371.872002 -289.478466) (xy 372.086378 -289.073082) (xy 372.076472 -289.050476) (xy 372.067509 -289.029398)
			(xy 372.054864 -288.985377) (xy 372.048449 -288.940026) (xy 372.048024 -288.917126) (xy 372.048532 -288.891219)
			(xy 372.056638 -288.840042) (xy 372.07265 -288.790763) (xy 372.096173 -288.744596) (xy 372.126629 -288.702677)
			(xy 372.163267 -288.666039) (xy 372.205186 -288.635583) (xy 372.251353 -288.61206) (xy 372.300632 -288.596048)
			(xy 372.351809 -288.587942) (xy 372.403623 -288.587942) (xy 372.4548 -288.596048) (xy 372.504079 -288.61206)
			(xy 372.550246 -288.635583) (xy 372.592165 -288.666039) (xy 372.628803 -288.702677) (xy 372.659259 -288.744596)
			(xy 372.682782 -288.790763) (xy 372.698794 -288.840042) (xy 372.7069 -288.891219) (xy 372.707408 -288.917126)
			(xy 372.706953 -288.942575) (xy 372.699149 -288.992871) (xy 372.683699 -289.041367) (xy 372.660971 -289.086909)
			(xy 372.631507 -289.128411) (xy 372.596009 -289.164887) (xy 372.555321 -289.195466) (xy 372.510413 -289.21942)
			(xy 372.462353 -289.23618) (xy 372.437406 -289.24123) (xy 372.413276 -289.245802) (xy 372.1989 -289.651186)
			(xy 372.208806 -289.673792) (xy 372.217728 -289.694877) (xy 372.230278 -289.738907) (xy 372.23661 -289.78425)
			(xy 372.237 -289.807142) (xy 373.457724 -289.807142) (xy 373.458211 -289.781712) (xy 373.466044 -289.73146)
			(xy 373.481499 -289.683005) (xy 373.50421 -289.637498) (xy 373.533639 -289.596018) (xy 373.569087 -289.559547)
			(xy 373.609714 -289.528951) (xy 373.654557 -289.504956) (xy 373.702553 -289.48813) (xy 373.727472 -289.483038)
			(xy 373.751602 -289.478466) (xy 373.965978 -289.073082) (xy 373.956072 -289.050476) (xy 373.947109 -289.029398)
			(xy 373.934464 -288.985377) (xy 373.928049 -288.940026) (xy 373.927624 -288.917126) (xy 373.928132 -288.891219)
			(xy 373.936238 -288.840042) (xy 373.95225 -288.790763) (xy 373.975773 -288.744596) (xy 374.006229 -288.702677)
			(xy 374.042867 -288.666039) (xy 374.084786 -288.635583) (xy 374.130953 -288.61206) (xy 374.180232 -288.596048)
			(xy 374.231409 -288.587942) (xy 374.283223 -288.587942) (xy 374.3344 -288.596048) (xy 374.383679 -288.61206)
			(xy 374.429846 -288.635583) (xy 374.471765 -288.666039) (xy 374.508403 -288.702677) (xy 374.538859 -288.744596)
			(xy 374.562382 -288.790763) (xy 374.578394 -288.840042) (xy 374.5865 -288.891219) (xy 374.587008 -288.917126)
			(xy 374.586553 -288.942575) (xy 374.578749 -288.992871) (xy 374.563299 -289.041367) (xy 374.540571 -289.086909)
			(xy 374.511107 -289.128411) (xy 374.475609 -289.164887) (xy 374.434921 -289.195466) (xy 374.390013 -289.21942)
			(xy 374.341953 -289.23618) (xy 374.317006 -289.24123) (xy 374.292876 -289.245802) (xy 374.0785 -289.651186)
			(xy 374.088406 -289.673792) (xy 374.097328 -289.694877) (xy 374.109878 -289.738907) (xy 374.11621 -289.78425)
			(xy 374.1166 -289.807142) (xy 375.337324 -289.807142) (xy 375.337811 -289.781712) (xy 375.345644 -289.73146)
			(xy 375.361099 -289.683005) (xy 375.38381 -289.637498) (xy 375.413239 -289.596018) (xy 375.448687 -289.559547)
			(xy 375.489314 -289.528951) (xy 375.534157 -289.504956) (xy 375.582153 -289.48813) (xy 375.607072 -289.483038)
			(xy 375.631202 -289.478466) (xy 375.845578 -289.073082) (xy 375.835672 -289.050476) (xy 375.826709 -289.029398)
			(xy 375.814064 -288.985377) (xy 375.807649 -288.940026) (xy 375.807224 -288.917126) (xy 375.807732 -288.891219)
			(xy 375.815838 -288.840042) (xy 375.83185 -288.790763) (xy 375.855373 -288.744596) (xy 375.885829 -288.702677)
			(xy 375.922467 -288.666039) (xy 375.964386 -288.635583) (xy 376.010553 -288.61206) (xy 376.059832 -288.596048)
			(xy 376.111009 -288.587942) (xy 376.162823 -288.587942) (xy 376.214 -288.596048) (xy 376.263279 -288.61206)
			(xy 376.309446 -288.635583) (xy 376.351365 -288.666039) (xy 376.388003 -288.702677) (xy 376.418459 -288.744596)
			(xy 376.441982 -288.790763) (xy 376.457994 -288.840042) (xy 376.4661 -288.891219) (xy 376.466608 -288.917126)
			(xy 376.466153 -288.942575) (xy 376.458349 -288.992871) (xy 376.442899 -289.041367) (xy 376.420171 -289.086909)
			(xy 376.390707 -289.128411) (xy 376.355209 -289.164887) (xy 376.314521 -289.195466) (xy 376.269613 -289.21942)
			(xy 376.221553 -289.23618) (xy 376.196606 -289.24123) (xy 376.172476 -289.245802) (xy 375.9581 -289.651186)
			(xy 375.968006 -289.673792) (xy 375.976928 -289.694877) (xy 375.989478 -289.738907) (xy 375.99581 -289.78425)
			(xy 375.9962 -289.807142) (xy 377.216924 -289.807142) (xy 377.217411 -289.781712) (xy 377.225244 -289.73146)
			(xy 377.240699 -289.683005) (xy 377.26341 -289.637498) (xy 377.292839 -289.596018) (xy 377.328287 -289.559547)
			(xy 377.368914 -289.528951) (xy 377.413757 -289.504956) (xy 377.461753 -289.48813) (xy 377.486672 -289.483038)
			(xy 377.510802 -289.478466) (xy 377.725178 -289.073082) (xy 377.715272 -289.050476) (xy 377.706309 -289.029398)
			(xy 377.693664 -288.985377) (xy 377.687249 -288.940026) (xy 377.686824 -288.917126) (xy 377.687332 -288.891219)
			(xy 377.695438 -288.840042) (xy 377.71145 -288.790763) (xy 377.734973 -288.744596) (xy 377.765429 -288.702677)
			(xy 377.802067 -288.666039) (xy 377.843986 -288.635583) (xy 377.890153 -288.61206) (xy 377.939432 -288.596048)
			(xy 377.990609 -288.587942) (xy 378.042423 -288.587942) (xy 378.0936 -288.596048) (xy 378.142879 -288.61206)
			(xy 378.189046 -288.635583) (xy 378.230965 -288.666039) (xy 378.267603 -288.702677) (xy 378.298059 -288.744596)
			(xy 378.321582 -288.790763) (xy 378.337594 -288.840042) (xy 378.3457 -288.891219) (xy 378.346208 -288.917126)
			(xy 378.345753 -288.942575) (xy 378.337949 -288.992871) (xy 378.322499 -289.041367) (xy 378.299771 -289.086909)
			(xy 378.270307 -289.128411) (xy 378.234809 -289.164887) (xy 378.194121 -289.195466) (xy 378.149213 -289.21942)
			(xy 378.101153 -289.23618) (xy 378.076206 -289.24123) (xy 378.052076 -289.245802) (xy 377.8377 -289.651186)
			(xy 377.847606 -289.673792) (xy 377.856528 -289.694877) (xy 377.869078 -289.738907) (xy 377.87541 -289.78425)
			(xy 377.8758 -289.807142) (xy 379.096524 -289.807142) (xy 379.097011 -289.781712) (xy 379.104844 -289.73146)
			(xy 379.120299 -289.683005) (xy 379.14301 -289.637498) (xy 379.172439 -289.596018) (xy 379.207887 -289.559547)
			(xy 379.248514 -289.528951) (xy 379.293357 -289.504956) (xy 379.341353 -289.48813) (xy 379.366272 -289.483038)
			(xy 379.390402 -289.478466) (xy 379.604778 -289.073082) (xy 379.594872 -289.050476) (xy 379.585909 -289.029398)
			(xy 379.573264 -288.985377) (xy 379.566849 -288.940026) (xy 379.566424 -288.917126) (xy 379.566932 -288.891219)
			(xy 379.575038 -288.840042) (xy 379.59105 -288.790763) (xy 379.614573 -288.744596) (xy 379.645029 -288.702677)
			(xy 379.681667 -288.666039) (xy 379.723586 -288.635583) (xy 379.769753 -288.61206) (xy 379.819032 -288.596048)
			(xy 379.870209 -288.587942) (xy 379.922023 -288.587942) (xy 379.9732 -288.596048) (xy 380.022479 -288.61206)
			(xy 380.068646 -288.635583) (xy 380.110565 -288.666039) (xy 380.147203 -288.702677) (xy 380.177659 -288.744596)
			(xy 380.201182 -288.790763) (xy 380.217194 -288.840042) (xy 380.2253 -288.891219) (xy 380.225808 -288.917126)
			(xy 380.225353 -288.942575) (xy 380.217549 -288.992871) (xy 380.202099 -289.041367) (xy 380.179371 -289.086909)
			(xy 380.149907 -289.128411) (xy 380.114409 -289.164887) (xy 380.073721 -289.195466) (xy 380.028813 -289.21942)
			(xy 379.980753 -289.23618) (xy 379.955806 -289.24123) (xy 379.931676 -289.245802) (xy 379.7173 -289.651186)
			(xy 379.727206 -289.673792) (xy 379.736128 -289.694877) (xy 379.748678 -289.738907) (xy 379.75501 -289.78425)
			(xy 379.7554 -289.807142) (xy 380.976124 -289.807142) (xy 380.976611 -289.781712) (xy 380.984444 -289.73146)
			(xy 380.999899 -289.683005) (xy 381.02261 -289.637498) (xy 381.052039 -289.596018) (xy 381.087487 -289.559547)
			(xy 381.128114 -289.528951) (xy 381.172957 -289.504956) (xy 381.220953 -289.48813) (xy 381.245872 -289.483038)
			(xy 381.270002 -289.478466) (xy 381.484378 -289.073082) (xy 381.474472 -289.050476) (xy 381.465509 -289.029398)
			(xy 381.452864 -288.985377) (xy 381.446449 -288.940026) (xy 381.446024 -288.917126) (xy 381.446532 -288.891219)
			(xy 381.454638 -288.840042) (xy 381.47065 -288.790763) (xy 381.494173 -288.744596) (xy 381.524629 -288.702677)
			(xy 381.561267 -288.666039) (xy 381.603186 -288.635583) (xy 381.649353 -288.61206) (xy 381.698632 -288.596048)
			(xy 381.749809 -288.587942) (xy 381.801623 -288.587942) (xy 381.8528 -288.596048) (xy 381.902079 -288.61206)
			(xy 381.948246 -288.635583) (xy 381.990165 -288.666039) (xy 382.026803 -288.702677) (xy 382.057259 -288.744596)
			(xy 382.080782 -288.790763) (xy 382.096794 -288.840042) (xy 382.1049 -288.891219) (xy 382.105408 -288.917126)
			(xy 382.104953 -288.942575) (xy 382.097149 -288.992871) (xy 382.081699 -289.041367) (xy 382.058971 -289.086909)
			(xy 382.029507 -289.128411) (xy 381.994009 -289.164887) (xy 381.953321 -289.195466) (xy 381.908413 -289.21942)
			(xy 381.860353 -289.23618) (xy 381.835406 -289.24123) (xy 381.811276 -289.245802) (xy 381.5969 -289.651186)
			(xy 381.606806 -289.673792) (xy 381.615728 -289.694877) (xy 381.628278 -289.738907) (xy 381.63461 -289.78425)
			(xy 381.635 -289.807142) (xy 381.634492 -289.833029) (xy 381.626393 -289.884167) (xy 381.610394 -289.933407)
			(xy 381.586888 -289.979539) (xy 381.556456 -290.021426) (xy 381.519846 -290.058036) (xy 381.477959 -290.088468)
			(xy 381.431827 -290.111974) (xy 381.382587 -290.127973) (xy 381.331449 -290.136072) (xy 381.279675 -290.136072)
			(xy 381.228537 -290.127973) (xy 381.179297 -290.111974) (xy 381.133165 -290.088468) (xy 381.091278 -290.058036)
			(xy 381.054668 -290.021426) (xy 381.024236 -289.979539) (xy 381.00073 -289.933407) (xy 380.984731 -289.884167)
			(xy 380.976632 -289.833029) (xy 380.976124 -289.807142) (xy 379.7554 -289.807142) (xy 379.754892 -289.833029)
			(xy 379.746793 -289.884167) (xy 379.730794 -289.933407) (xy 379.707288 -289.979539) (xy 379.676856 -290.021426)
			(xy 379.640246 -290.058036) (xy 379.598359 -290.088468) (xy 379.552227 -290.111974) (xy 379.502987 -290.127973)
			(xy 379.451849 -290.136072) (xy 379.400075 -290.136072) (xy 379.348937 -290.127973) (xy 379.299697 -290.111974)
			(xy 379.253565 -290.088468) (xy 379.211678 -290.058036) (xy 379.175068 -290.021426) (xy 379.144636 -289.979539)
			(xy 379.12113 -289.933407) (xy 379.105131 -289.884167) (xy 379.097032 -289.833029) (xy 379.096524 -289.807142)
			(xy 377.8758 -289.807142) (xy 377.875292 -289.833029) (xy 377.867193 -289.884167) (xy 377.851194 -289.933407)
			(xy 377.827688 -289.979539) (xy 377.797256 -290.021426) (xy 377.760646 -290.058036) (xy 377.718759 -290.088468)
			(xy 377.672627 -290.111974) (xy 377.623387 -290.127973) (xy 377.572249 -290.136072) (xy 377.520475 -290.136072)
			(xy 377.469337 -290.127973) (xy 377.420097 -290.111974) (xy 377.373965 -290.088468) (xy 377.332078 -290.058036)
			(xy 377.295468 -290.021426) (xy 377.265036 -289.979539) (xy 377.24153 -289.933407) (xy 377.225531 -289.884167)
			(xy 377.217432 -289.833029) (xy 377.216924 -289.807142) (xy 375.9962 -289.807142) (xy 375.995692 -289.833029)
			(xy 375.987593 -289.884167) (xy 375.971594 -289.933407) (xy 375.948088 -289.979539) (xy 375.917656 -290.021426)
			(xy 375.881046 -290.058036) (xy 375.839159 -290.088468) (xy 375.793027 -290.111974) (xy 375.743787 -290.127973)
			(xy 375.692649 -290.136072) (xy 375.640875 -290.136072) (xy 375.589737 -290.127973) (xy 375.540497 -290.111974)
			(xy 375.494365 -290.088468) (xy 375.452478 -290.058036) (xy 375.415868 -290.021426) (xy 375.385436 -289.979539)
			(xy 375.36193 -289.933407) (xy 375.345931 -289.884167) (xy 375.337832 -289.833029) (xy 375.337324 -289.807142)
			(xy 374.1166 -289.807142) (xy 374.116092 -289.833029) (xy 374.107993 -289.884167) (xy 374.091994 -289.933407)
			(xy 374.068488 -289.979539) (xy 374.038056 -290.021426) (xy 374.001446 -290.058036) (xy 373.959559 -290.088468)
			(xy 373.913427 -290.111974) (xy 373.864187 -290.127973) (xy 373.813049 -290.136072) (xy 373.761275 -290.136072)
			(xy 373.710137 -290.127973) (xy 373.660897 -290.111974) (xy 373.614765 -290.088468) (xy 373.572878 -290.058036)
			(xy 373.536268 -290.021426) (xy 373.505836 -289.979539) (xy 373.48233 -289.933407) (xy 373.466331 -289.884167)
			(xy 373.458232 -289.833029) (xy 373.457724 -289.807142) (xy 372.237 -289.807142) (xy 372.236492 -289.833029)
			(xy 372.228393 -289.884167) (xy 372.212394 -289.933407) (xy 372.188888 -289.979539) (xy 372.158456 -290.021426)
			(xy 372.121846 -290.058036) (xy 372.079959 -290.088468) (xy 372.033827 -290.111974) (xy 371.984587 -290.127973)
			(xy 371.933449 -290.136072) (xy 371.881675 -290.136072) (xy 371.830537 -290.127973) (xy 371.781297 -290.111974)
			(xy 371.735165 -290.088468) (xy 371.693278 -290.058036) (xy 371.656668 -290.021426) (xy 371.626236 -289.979539)
			(xy 371.60273 -289.933407) (xy 371.586731 -289.884167) (xy 371.578632 -289.833029) (xy 371.578124 -289.807142)
			(xy 370.3574 -289.807142) (xy 370.356892 -289.833029) (xy 370.348793 -289.884167) (xy 370.332794 -289.933407)
			(xy 370.309288 -289.979539) (xy 370.278856 -290.021426) (xy 370.242246 -290.058036) (xy 370.200359 -290.088468)
			(xy 370.154227 -290.111974) (xy 370.104987 -290.127973) (xy 370.053849 -290.136072) (xy 370.002075 -290.136072)
			(xy 369.950937 -290.127973) (xy 369.901697 -290.111974) (xy 369.855565 -290.088468) (xy 369.813678 -290.058036)
			(xy 369.777068 -290.021426) (xy 369.746636 -289.979539) (xy 369.72313 -289.933407) (xy 369.707131 -289.884167)
			(xy 369.699032 -289.833029) (xy 369.698524 -289.807142) (xy 368.4778 -289.807142) (xy 368.477292 -289.833029)
			(xy 368.469193 -289.884167) (xy 368.453194 -289.933407) (xy 368.429688 -289.979539) (xy 368.399256 -290.021426)
			(xy 368.362646 -290.058036) (xy 368.320759 -290.088468) (xy 368.274627 -290.111974) (xy 368.225387 -290.127973)
			(xy 368.174249 -290.136072) (xy 368.122475 -290.136072) (xy 368.071337 -290.127973) (xy 368.022097 -290.111974)
			(xy 367.975965 -290.088468) (xy 367.934078 -290.058036) (xy 367.897468 -290.021426) (xy 367.867036 -289.979539)
			(xy 367.84353 -289.933407) (xy 367.827531 -289.884167) (xy 367.819432 -289.833029) (xy 367.818924 -289.807142)
			(xy 351.5614 -289.807142) (xy 351.560892 -289.833029) (xy 351.552793 -289.884167) (xy 351.536794 -289.933407)
			(xy 351.513288 -289.979539) (xy 351.482856 -290.021426) (xy 351.446246 -290.058036) (xy 351.404359 -290.088468)
			(xy 351.358227 -290.111974) (xy 351.308987 -290.127973) (xy 351.257849 -290.136072) (xy 351.206075 -290.136072)
			(xy 351.154937 -290.127973) (xy 351.105697 -290.111974) (xy 351.059565 -290.088468) (xy 351.017678 -290.058036)
			(xy 350.981068 -290.021426) (xy 350.950636 -289.979539) (xy 350.92713 -289.933407) (xy 350.911131 -289.884167)
			(xy 350.903032 -289.833029) (xy 350.902524 -289.807142) (xy 350.902524 -289.806634) (xy 350.902922 -289.783785)
			(xy 350.909275 -289.738531) (xy 350.921824 -289.694589) (xy 350.930718 -289.673538) (xy 350.940624 -289.650932)
			(xy 350.726756 -289.245802) (xy 350.702626 -289.24123) (xy 350.677682 -289.236182) (xy 350.629639 -289.219398)
			(xy 350.584746 -289.195428) (xy 350.544072 -289.164843) (xy 350.508582 -289.128369) (xy 350.479121 -289.086873)
			(xy 350.456389 -289.041341) (xy 350.440925 -288.992857) (xy 350.433099 -288.942571) (xy 350.432624 -288.917126)
			(xy 350.152208 -288.917126) (xy 350.1517 -288.943033) (xy 350.143594 -288.99421) (xy 350.127582 -289.043489)
			(xy 350.104059 -289.089656) (xy 350.073603 -289.131575) (xy 350.036965 -289.168213) (xy 349.995046 -289.198669)
			(xy 349.948879 -289.222192) (xy 349.8996 -289.238204) (xy 349.848423 -289.24631) (xy 349.796609 -289.24631)
			(xy 349.745432 -289.238204) (xy 349.696153 -289.222192) (xy 349.649986 -289.198669) (xy 349.608067 -289.168213)
			(xy 349.571429 -289.131575) (xy 349.540973 -289.089656) (xy 349.51745 -289.043489) (xy 349.501438 -288.99421)
			(xy 349.493332 -288.943033) (xy 349.492824 -288.917126) (xy 349.212408 -288.917126) (xy 349.211989 -288.940067)
			(xy 349.20556 -288.985498) (xy 349.192913 -289.029604) (xy 349.18396 -289.05073) (xy 349.174054 -289.073336)
			(xy 349.387922 -289.478466) (xy 349.412052 -289.483038) (xy 349.436973 -289.488138) (xy 349.484984 -289.504939)
			(xy 349.529843 -289.528919) (xy 349.570484 -289.559507) (xy 349.605941 -289.595978) (xy 349.635373 -289.637465)
			(xy 349.658079 -289.682981) (xy 349.673521 -289.731446) (xy 349.681331 -289.781709) (xy 349.6818 -289.807142)
			(xy 349.681292 -289.833029) (xy 349.673193 -289.884167) (xy 349.657194 -289.933407) (xy 349.633688 -289.979539)
			(xy 349.603256 -290.021426) (xy 349.566646 -290.058036) (xy 349.524759 -290.088468) (xy 349.478627 -290.111974)
			(xy 349.429387 -290.127973) (xy 349.378249 -290.136072) (xy 349.326475 -290.136072) (xy 349.275337 -290.127973)
			(xy 349.226097 -290.111974) (xy 349.179965 -290.088468) (xy 349.138078 -290.058036) (xy 349.101468 -290.021426)
			(xy 349.071036 -289.979539) (xy 349.04753 -289.933407) (xy 349.031531 -289.884167) (xy 349.023432 -289.833029)
			(xy 349.022924 -289.807142) (xy 349.022924 -289.806634) (xy 349.023322 -289.783785) (xy 349.029675 -289.738531)
			(xy 349.042224 -289.694589) (xy 349.051118 -289.673538) (xy 349.061024 -289.650932) (xy 348.847156 -289.245802)
			(xy 348.823026 -289.24123) (xy 348.798082 -289.236182) (xy 348.750039 -289.219398) (xy 348.705146 -289.195428)
			(xy 348.664472 -289.164843) (xy 348.628982 -289.128369) (xy 348.599521 -289.086873) (xy 348.576789 -289.041341)
			(xy 348.561325 -288.992857) (xy 348.553499 -288.942571) (xy 348.553024 -288.917126) (xy 348.272608 -288.917126)
			(xy 348.2721 -288.943033) (xy 348.263994 -288.99421) (xy 348.247982 -289.043489) (xy 348.224459 -289.089656)
			(xy 348.194003 -289.131575) (xy 348.157365 -289.168213) (xy 348.115446 -289.198669) (xy 348.069279 -289.222192)
			(xy 348.02 -289.238204) (xy 347.968823 -289.24631) (xy 347.917009 -289.24631) (xy 347.865832 -289.238204)
			(xy 347.816553 -289.222192) (xy 347.770386 -289.198669) (xy 347.728467 -289.168213) (xy 347.691829 -289.131575)
			(xy 347.661373 -289.089656) (xy 347.63785 -289.043489) (xy 347.621838 -288.99421) (xy 347.613732 -288.943033)
			(xy 347.613224 -288.917126) (xy 347.332808 -288.917126) (xy 347.332389 -288.940067) (xy 347.32596 -288.985498)
			(xy 347.313313 -289.029604) (xy 347.30436 -289.05073) (xy 347.294454 -289.073336) (xy 347.508322 -289.478466)
			(xy 347.532452 -289.483038) (xy 347.557373 -289.488138) (xy 347.605384 -289.504939) (xy 347.650243 -289.528919)
			(xy 347.690884 -289.559507) (xy 347.726341 -289.595978) (xy 347.755773 -289.637465) (xy 347.778479 -289.682981)
			(xy 347.793921 -289.731446) (xy 347.801731 -289.781709) (xy 347.8022 -289.807142) (xy 347.801692 -289.833029)
			(xy 347.793593 -289.884167) (xy 347.777594 -289.933407) (xy 347.754088 -289.979539) (xy 347.723656 -290.021426)
			(xy 347.687046 -290.058036) (xy 347.645159 -290.088468) (xy 347.599027 -290.111974) (xy 347.549787 -290.127973)
			(xy 347.498649 -290.136072) (xy 347.446875 -290.136072) (xy 347.395737 -290.127973) (xy 347.346497 -290.111974)
			(xy 347.300365 -290.088468) (xy 347.258478 -290.058036) (xy 347.221868 -290.021426) (xy 347.191436 -289.979539)
			(xy 347.16793 -289.933407) (xy 347.151931 -289.884167) (xy 347.143832 -289.833029) (xy 347.143324 -289.807142)
			(xy 347.143324 -289.806634) (xy 347.143722 -289.783785) (xy 347.150075 -289.738531) (xy 347.162624 -289.694589)
			(xy 347.171518 -289.673538) (xy 347.181424 -289.650932) (xy 346.967556 -289.245802) (xy 346.943426 -289.24123)
			(xy 346.918482 -289.236182) (xy 346.870439 -289.219398) (xy 346.825546 -289.195428) (xy 346.784872 -289.164843)
			(xy 346.749382 -289.128369) (xy 346.719921 -289.086873) (xy 346.697189 -289.041341) (xy 346.681725 -288.992857)
			(xy 346.673899 -288.942571) (xy 346.673424 -288.917126) (xy 346.393008 -288.917126) (xy 346.3925 -288.943033)
			(xy 346.384394 -288.99421) (xy 346.368382 -289.043489) (xy 346.344859 -289.089656) (xy 346.314403 -289.131575)
			(xy 346.277765 -289.168213) (xy 346.235846 -289.198669) (xy 346.189679 -289.222192) (xy 346.1404 -289.238204)
			(xy 346.089223 -289.24631) (xy 346.037409 -289.24631) (xy 345.986232 -289.238204) (xy 345.936953 -289.222192)
			(xy 345.890786 -289.198669) (xy 345.848867 -289.168213) (xy 345.812229 -289.131575) (xy 345.781773 -289.089656)
			(xy 345.75825 -289.043489) (xy 345.742238 -288.99421) (xy 345.734132 -288.943033) (xy 345.733624 -288.917126)
			(xy 345.453208 -288.917126) (xy 345.452789 -288.940067) (xy 345.44636 -288.985498) (xy 345.433713 -289.029604)
			(xy 345.42476 -289.05073) (xy 345.414854 -289.073336) (xy 345.628722 -289.478466) (xy 345.652852 -289.483038)
			(xy 345.677773 -289.488138) (xy 345.725784 -289.504939) (xy 345.770643 -289.528919) (xy 345.811284 -289.559507)
			(xy 345.846741 -289.595978) (xy 345.876173 -289.637465) (xy 345.898879 -289.682981) (xy 345.914321 -289.731446)
			(xy 345.922131 -289.781709) (xy 345.9226 -289.807142) (xy 345.922092 -289.833029) (xy 345.913993 -289.884167)
			(xy 345.897994 -289.933407) (xy 345.874488 -289.979539) (xy 345.844056 -290.021426) (xy 345.807446 -290.058036)
			(xy 345.765559 -290.088468) (xy 345.719427 -290.111974) (xy 345.670187 -290.127973) (xy 345.619049 -290.136072)
			(xy 345.567275 -290.136072) (xy 345.516137 -290.127973) (xy 345.466897 -290.111974) (xy 345.420765 -290.088468)
			(xy 345.378878 -290.058036) (xy 345.342268 -290.021426) (xy 345.311836 -289.979539) (xy 345.28833 -289.933407)
			(xy 345.272331 -289.884167) (xy 345.264232 -289.833029) (xy 345.263724 -289.807142) (xy 345.263724 -289.806634)
			(xy 345.264122 -289.783785) (xy 345.270475 -289.738531) (xy 345.283024 -289.694589) (xy 345.291918 -289.673538)
			(xy 345.301824 -289.650932) (xy 345.087956 -289.245802) (xy 345.063826 -289.24123) (xy 345.038882 -289.236182)
			(xy 344.990839 -289.219398) (xy 344.945946 -289.195428) (xy 344.905272 -289.164843) (xy 344.869782 -289.128369)
			(xy 344.840321 -289.086873) (xy 344.817589 -289.041341) (xy 344.802125 -288.992857) (xy 344.794299 -288.942571)
			(xy 344.793824 -288.917126) (xy 344.513408 -288.917126) (xy 344.5129 -288.943033) (xy 344.504794 -288.99421)
			(xy 344.488782 -289.043489) (xy 344.465259 -289.089656) (xy 344.434803 -289.131575) (xy 344.398165 -289.168213)
			(xy 344.356246 -289.198669) (xy 344.310079 -289.222192) (xy 344.2608 -289.238204) (xy 344.209623 -289.24631)
			(xy 344.157809 -289.24631) (xy 344.106632 -289.238204) (xy 344.057353 -289.222192) (xy 344.011186 -289.198669)
			(xy 343.969267 -289.168213) (xy 343.932629 -289.131575) (xy 343.902173 -289.089656) (xy 343.87865 -289.043489)
			(xy 343.862638 -288.99421) (xy 343.854532 -288.943033) (xy 343.854024 -288.917126) (xy 343.573608 -288.917126)
			(xy 343.573189 -288.940067) (xy 343.56676 -288.985498) (xy 343.554113 -289.029604) (xy 343.54516 -289.05073)
			(xy 343.535254 -289.073336) (xy 343.749122 -289.478466) (xy 343.773252 -289.483038) (xy 343.798173 -289.488138)
			(xy 343.846184 -289.504939) (xy 343.891043 -289.528919) (xy 343.931684 -289.559507) (xy 343.967141 -289.595978)
			(xy 343.996573 -289.637465) (xy 344.019279 -289.682981) (xy 344.034721 -289.731446) (xy 344.042531 -289.781709)
			(xy 344.043 -289.807142) (xy 344.042492 -289.833029) (xy 344.034393 -289.884167) (xy 344.018394 -289.933407)
			(xy 343.994888 -289.979539) (xy 343.964456 -290.021426) (xy 343.927846 -290.058036) (xy 343.885959 -290.088468)
			(xy 343.839827 -290.111974) (xy 343.790587 -290.127973) (xy 343.739449 -290.136072) (xy 343.687675 -290.136072)
			(xy 343.636537 -290.127973) (xy 343.587297 -290.111974) (xy 343.541165 -290.088468) (xy 343.499278 -290.058036)
			(xy 343.462668 -290.021426) (xy 343.432236 -289.979539) (xy 343.40873 -289.933407) (xy 343.392731 -289.884167)
			(xy 343.384632 -289.833029) (xy 343.384124 -289.807142) (xy 343.384124 -289.806634) (xy 343.384522 -289.783785)
			(xy 343.390875 -289.738531) (xy 343.403424 -289.694589) (xy 343.412318 -289.673538) (xy 343.422224 -289.650932)
			(xy 343.208356 -289.245802) (xy 343.184226 -289.24123) (xy 343.159282 -289.236182) (xy 343.111239 -289.219398)
			(xy 343.066346 -289.195428) (xy 343.025672 -289.164843) (xy 342.990182 -289.128369) (xy 342.960721 -289.086873)
			(xy 342.937989 -289.041341) (xy 342.922525 -288.992857) (xy 342.914699 -288.942571) (xy 342.914224 -288.917126)
			(xy 342.633808 -288.917126) (xy 342.6333 -288.943033) (xy 342.625194 -288.99421) (xy 342.609182 -289.043489)
			(xy 342.585659 -289.089656) (xy 342.555203 -289.131575) (xy 342.518565 -289.168213) (xy 342.476646 -289.198669)
			(xy 342.430479 -289.222192) (xy 342.3812 -289.238204) (xy 342.330023 -289.24631) (xy 342.278209 -289.24631)
			(xy 342.227032 -289.238204) (xy 342.177753 -289.222192) (xy 342.131586 -289.198669) (xy 342.089667 -289.168213)
			(xy 342.053029 -289.131575) (xy 342.022573 -289.089656) (xy 341.99905 -289.043489) (xy 341.983038 -288.99421)
			(xy 341.974932 -288.943033) (xy 341.974424 -288.917126) (xy 341.694008 -288.917126) (xy 341.693589 -288.940067)
			(xy 341.68716 -288.985498) (xy 341.674513 -289.029604) (xy 341.66556 -289.05073) (xy 341.655654 -289.073336)
			(xy 341.869522 -289.478466) (xy 341.893652 -289.483038) (xy 341.918573 -289.488138) (xy 341.966584 -289.504939)
			(xy 342.011443 -289.528919) (xy 342.052084 -289.559507) (xy 342.087541 -289.595978) (xy 342.116973 -289.637465)
			(xy 342.139679 -289.682981) (xy 342.155121 -289.731446) (xy 342.162931 -289.781709) (xy 342.1634 -289.807142)
			(xy 342.162892 -289.833029) (xy 342.154793 -289.884167) (xy 342.138794 -289.933407) (xy 342.115288 -289.979539)
			(xy 342.084856 -290.021426) (xy 342.048246 -290.058036) (xy 342.006359 -290.088468) (xy 341.960227 -290.111974)
			(xy 341.910987 -290.127973) (xy 341.859849 -290.136072) (xy 341.808075 -290.136072) (xy 341.756937 -290.127973)
			(xy 341.707697 -290.111974) (xy 341.661565 -290.088468) (xy 341.619678 -290.058036) (xy 341.583068 -290.021426)
			(xy 341.552636 -289.979539) (xy 341.52913 -289.933407) (xy 341.513131 -289.884167) (xy 341.505032 -289.833029)
			(xy 341.504524 -289.807142) (xy 341.504524 -289.806634) (xy 341.504922 -289.783785) (xy 341.511275 -289.738531)
			(xy 341.523824 -289.694589) (xy 341.532718 -289.673538) (xy 341.542624 -289.650932) (xy 341.328756 -289.245802)
			(xy 341.304626 -289.24123) (xy 341.279682 -289.236182) (xy 341.231639 -289.219398) (xy 341.186746 -289.195428)
			(xy 341.146072 -289.164843) (xy 341.110582 -289.128369) (xy 341.081121 -289.086873) (xy 341.058389 -289.041341)
			(xy 341.042925 -288.992857) (xy 341.035099 -288.942571) (xy 341.034624 -288.917126) (xy 340.754208 -288.917126)
			(xy 340.7537 -288.943033) (xy 340.745594 -288.99421) (xy 340.729582 -289.043489) (xy 340.706059 -289.089656)
			(xy 340.675603 -289.131575) (xy 340.638965 -289.168213) (xy 340.597046 -289.198669) (xy 340.550879 -289.222192)
			(xy 340.5016 -289.238204) (xy 340.450423 -289.24631) (xy 340.398609 -289.24631) (xy 340.347432 -289.238204)
			(xy 340.298153 -289.222192) (xy 340.251986 -289.198669) (xy 340.210067 -289.168213) (xy 340.173429 -289.131575)
			(xy 340.142973 -289.089656) (xy 340.11945 -289.043489) (xy 340.103438 -288.99421) (xy 340.095332 -288.943033)
			(xy 340.094824 -288.917126) (xy 339.814408 -288.917126) (xy 339.813989 -288.940067) (xy 339.80756 -288.985498)
			(xy 339.794913 -289.029604) (xy 339.78596 -289.05073) (xy 339.776054 -289.073336) (xy 339.989922 -289.478466)
			(xy 340.014052 -289.483038) (xy 340.038973 -289.488138) (xy 340.086984 -289.504939) (xy 340.131843 -289.528919)
			(xy 340.172484 -289.559507) (xy 340.207941 -289.595978) (xy 340.237373 -289.637465) (xy 340.260079 -289.682981)
			(xy 340.275521 -289.731446) (xy 340.283331 -289.781709) (xy 340.2838 -289.807142) (xy 340.283292 -289.833029)
			(xy 340.275193 -289.884167) (xy 340.259194 -289.933407) (xy 340.235688 -289.979539) (xy 340.205256 -290.021426)
			(xy 340.168646 -290.058036) (xy 340.126759 -290.088468) (xy 340.080627 -290.111974) (xy 340.031387 -290.127973)
			(xy 339.980249 -290.136072) (xy 339.928475 -290.136072) (xy 339.877337 -290.127973) (xy 339.828097 -290.111974)
			(xy 339.781965 -290.088468) (xy 339.740078 -290.058036) (xy 339.703468 -290.021426) (xy 339.673036 -289.979539)
			(xy 339.64953 -289.933407) (xy 339.633531 -289.884167) (xy 339.625432 -289.833029) (xy 339.624924 -289.807142)
			(xy 339.624924 -289.806634) (xy 339.625322 -289.783785) (xy 339.631675 -289.738531) (xy 339.644224 -289.694589)
			(xy 339.653118 -289.673538) (xy 339.663024 -289.650932) (xy 339.449156 -289.245802) (xy 339.425026 -289.24123)
			(xy 339.400082 -289.236182) (xy 339.352039 -289.219398) (xy 339.307146 -289.195428) (xy 339.266472 -289.164843)
			(xy 339.230982 -289.128369) (xy 339.201521 -289.086873) (xy 339.178789 -289.041341) (xy 339.163325 -288.992857)
			(xy 339.155499 -288.942571) (xy 339.155024 -288.917126) (xy 338.874608 -288.917126) (xy 338.8741 -288.943033)
			(xy 338.865994 -288.99421) (xy 338.849982 -289.043489) (xy 338.826459 -289.089656) (xy 338.796003 -289.131575)
			(xy 338.759365 -289.168213) (xy 338.717446 -289.198669) (xy 338.671279 -289.222192) (xy 338.622 -289.238204)
			(xy 338.570823 -289.24631) (xy 338.519009 -289.24631) (xy 338.467832 -289.238204) (xy 338.418553 -289.222192)
			(xy 338.372386 -289.198669) (xy 338.330467 -289.168213) (xy 338.293829 -289.131575) (xy 338.263373 -289.089656)
			(xy 338.23985 -289.043489) (xy 338.223838 -288.99421) (xy 338.215732 -288.943033) (xy 338.215224 -288.917126)
			(xy 336.995008 -288.917126) (xy 336.9945 -288.943033) (xy 336.986394 -288.99421) (xy 336.970382 -289.043489)
			(xy 336.946859 -289.089656) (xy 336.916403 -289.131575) (xy 336.879765 -289.168213) (xy 336.837846 -289.198669)
			(xy 336.791679 -289.222192) (xy 336.7424 -289.238204) (xy 336.691223 -289.24631) (xy 336.639409 -289.24631)
			(xy 336.588232 -289.238204) (xy 336.538953 -289.222192) (xy 336.492786 -289.198669) (xy 336.450867 -289.168213)
			(xy 336.414229 -289.131575) (xy 336.383773 -289.089656) (xy 336.36025 -289.043489) (xy 336.344238 -288.99421)
			(xy 336.336132 -288.943033) (xy 336.335624 -288.917126) (xy 136.04494 -288.917126) (xy 136.044432 -288.943033)
			(xy 136.036326 -288.99421) (xy 136.020314 -289.043489) (xy 135.996791 -289.089656) (xy 135.966335 -289.131575)
			(xy 135.929697 -289.168213) (xy 135.887778 -289.198669) (xy 135.841611 -289.222192) (xy 135.792332 -289.238204)
			(xy 135.741155 -289.24631) (xy 135.689341 -289.24631) (xy 135.638164 -289.238204) (xy 135.588885 -289.222192)
			(xy 135.542718 -289.198669) (xy 135.500799 -289.168213) (xy 135.464161 -289.131575) (xy 135.433705 -289.089656)
			(xy 135.410182 -289.043489) (xy 135.39417 -288.99421) (xy 135.386064 -288.943033) (xy 135.385556 -288.917126)
			(xy 135.386153 -288.889409) (xy 135.395474 -288.834762) (xy 135.404098 -288.808414) (xy 135.411972 -288.786316)
			(xy 135.20674 -288.431224) (xy 135.18388 -288.426906) (xy 135.159064 -288.421716) (xy 135.111285 -288.404766)
			(xy 135.066665 -288.380698) (xy 135.026258 -288.350081) (xy 134.991016 -288.313637) (xy 134.961772 -288.272226)
			(xy 134.939214 -288.226825) (xy 134.923875 -288.178504) (xy 134.916118 -288.128404) (xy 134.915656 -288.103056)
			(xy 132.75564 -288.103056) (xy 132.755038 -288.130773) (xy 132.74572 -288.18542) (xy 132.737098 -288.211768)
			(xy 132.729478 -288.233866) (xy 132.934456 -288.588958) (xy 132.957316 -288.593276) (xy 132.982127 -288.598486)
			(xy 133.029905 -288.615434) (xy 133.074524 -288.6395) (xy 133.114931 -288.670114) (xy 133.150173 -288.706556)
			(xy 133.179418 -288.747964) (xy 133.201977 -288.793363) (xy 133.217317 -288.841681) (xy 133.225077 -288.891779)
			(xy 133.22554 -288.917126) (xy 133.225032 -288.943033) (xy 133.216926 -288.99421) (xy 133.200914 -289.043489)
			(xy 133.177391 -289.089656) (xy 133.146935 -289.131575) (xy 133.110297 -289.168213) (xy 133.068378 -289.198669)
			(xy 133.022211 -289.222192) (xy 132.972932 -289.238204) (xy 132.921755 -289.24631) (xy 132.869941 -289.24631)
			(xy 132.818764 -289.238204) (xy 132.769485 -289.222192) (xy 132.723318 -289.198669) (xy 132.681399 -289.168213)
			(xy 132.644761 -289.131575) (xy 132.614305 -289.089656) (xy 132.590782 -289.043489) (xy 132.57477 -288.99421)
			(xy 132.566664 -288.943033) (xy 132.566156 -288.917126) (xy 132.566753 -288.889409) (xy 132.576074 -288.834762)
			(xy 132.584698 -288.808414) (xy 132.592572 -288.786316) (xy 132.387594 -288.431224) (xy 132.364734 -288.426906)
			(xy 132.339899 -288.421756) (xy 132.292089 -288.404821) (xy 132.247438 -288.380764) (xy 132.206999 -288.350151)
			(xy 132.171726 -288.313705) (xy 132.142451 -288.272287) (xy 132.119866 -288.226873) (xy 132.104504 -288.178536)
			(xy 132.096726 -288.128416) (xy 132.096256 -288.103056) (xy 130.87604 -288.103056) (xy 130.875438 -288.130773)
			(xy 130.86612 -288.18542) (xy 130.857498 -288.211768) (xy 130.849878 -288.233866) (xy 131.054856 -288.588958)
			(xy 131.077716 -288.593276) (xy 131.102527 -288.598486) (xy 131.150305 -288.615434) (xy 131.194924 -288.6395)
			(xy 131.235331 -288.670114) (xy 131.270573 -288.706556) (xy 131.299818 -288.747964) (xy 131.322377 -288.793363)
			(xy 131.337717 -288.841681) (xy 131.345477 -288.891779) (xy 131.34594 -288.917126) (xy 131.345432 -288.943033)
			(xy 131.337326 -288.99421) (xy 131.321314 -289.043489) (xy 131.297791 -289.089656) (xy 131.267335 -289.131575)
			(xy 131.230697 -289.168213) (xy 131.188778 -289.198669) (xy 131.142611 -289.222192) (xy 131.093332 -289.238204)
			(xy 131.042155 -289.24631) (xy 130.990341 -289.24631) (xy 130.939164 -289.238204) (xy 130.889885 -289.222192)
			(xy 130.843718 -289.198669) (xy 130.801799 -289.168213) (xy 130.765161 -289.131575) (xy 130.734705 -289.089656)
			(xy 130.711182 -289.043489) (xy 130.69517 -288.99421) (xy 130.687064 -288.943033) (xy 130.686556 -288.917126)
			(xy 130.687153 -288.889409) (xy 130.696474 -288.834762) (xy 130.705098 -288.808414) (xy 130.712972 -288.786316)
			(xy 130.507994 -288.431224) (xy 130.485134 -288.426906) (xy 130.460299 -288.421756) (xy 130.412489 -288.404821)
			(xy 130.367838 -288.380764) (xy 130.327399 -288.350151) (xy 130.292126 -288.313705) (xy 130.262851 -288.272287)
			(xy 130.240266 -288.226873) (xy 130.224904 -288.178536) (xy 130.217126 -288.128416) (xy 130.216656 -288.103056)
			(xy 128.99644 -288.103056) (xy 128.995838 -288.130773) (xy 128.98652 -288.18542) (xy 128.977898 -288.211768)
			(xy 128.970278 -288.233866) (xy 129.175256 -288.588958) (xy 129.198116 -288.593276) (xy 129.222927 -288.598486)
			(xy 129.270705 -288.615434) (xy 129.315324 -288.6395) (xy 129.355731 -288.670114) (xy 129.390973 -288.706556)
			(xy 129.420218 -288.747964) (xy 129.442777 -288.793363) (xy 129.458117 -288.841681) (xy 129.465877 -288.891779)
			(xy 129.46634 -288.917126) (xy 129.465832 -288.943033) (xy 129.457726 -288.99421) (xy 129.441714 -289.043489)
			(xy 129.418191 -289.089656) (xy 129.387735 -289.131575) (xy 129.351097 -289.168213) (xy 129.309178 -289.198669)
			(xy 129.263011 -289.222192) (xy 129.213732 -289.238204) (xy 129.162555 -289.24631) (xy 129.110741 -289.24631)
			(xy 129.059564 -289.238204) (xy 129.010285 -289.222192) (xy 128.964118 -289.198669) (xy 128.922199 -289.168213)
			(xy 128.885561 -289.131575) (xy 128.855105 -289.089656) (xy 128.831582 -289.043489) (xy 128.81557 -288.99421)
			(xy 128.807464 -288.943033) (xy 128.806956 -288.917126) (xy 128.807553 -288.889409) (xy 128.816874 -288.834762)
			(xy 128.825498 -288.808414) (xy 128.833372 -288.786316) (xy 128.628394 -288.431224) (xy 128.605534 -288.426906)
			(xy 128.580699 -288.421756) (xy 128.532889 -288.404821) (xy 128.488238 -288.380764) (xy 128.447799 -288.350151)
			(xy 128.412526 -288.313705) (xy 128.383251 -288.272287) (xy 128.360666 -288.226873) (xy 128.345304 -288.178536)
			(xy 128.337526 -288.128416) (xy 128.337056 -288.103056) (xy 127.11684 -288.103056) (xy 127.116238 -288.130773)
			(xy 127.10692 -288.18542) (xy 127.098298 -288.211768) (xy 127.090678 -288.233866) (xy 127.295656 -288.588958)
			(xy 127.318516 -288.593276) (xy 127.343327 -288.598486) (xy 127.391105 -288.615434) (xy 127.435724 -288.6395)
			(xy 127.476131 -288.670114) (xy 127.511373 -288.706556) (xy 127.540618 -288.747964) (xy 127.563177 -288.793363)
			(xy 127.578517 -288.841681) (xy 127.586277 -288.891779) (xy 127.58674 -288.917126) (xy 127.586232 -288.943033)
			(xy 127.578126 -288.99421) (xy 127.562114 -289.043489) (xy 127.538591 -289.089656) (xy 127.508135 -289.131575)
			(xy 127.471497 -289.168213) (xy 127.429578 -289.198669) (xy 127.383411 -289.222192) (xy 127.334132 -289.238204)
			(xy 127.282955 -289.24631) (xy 127.231141 -289.24631) (xy 127.179964 -289.238204) (xy 127.130685 -289.222192)
			(xy 127.084518 -289.198669) (xy 127.042599 -289.168213) (xy 127.005961 -289.131575) (xy 126.975505 -289.089656)
			(xy 126.951982 -289.043489) (xy 126.93597 -288.99421) (xy 126.927864 -288.943033) (xy 126.927356 -288.917126)
			(xy 126.927953 -288.889409) (xy 126.937274 -288.834762) (xy 126.945898 -288.808414) (xy 126.953772 -288.786316)
			(xy 126.748794 -288.431224) (xy 126.725934 -288.426906) (xy 126.701099 -288.421756) (xy 126.653289 -288.404821)
			(xy 126.608638 -288.380764) (xy 126.568199 -288.350151) (xy 126.532926 -288.313705) (xy 126.503651 -288.272287)
			(xy 126.481066 -288.226873) (xy 126.465704 -288.178536) (xy 126.457926 -288.128416) (xy 126.457456 -288.103056)
			(xy 125.23724 -288.103056) (xy 125.236638 -288.130773) (xy 125.22732 -288.18542) (xy 125.218698 -288.211768)
			(xy 125.211078 -288.233866) (xy 125.416056 -288.588958) (xy 125.438916 -288.593276) (xy 125.463727 -288.598486)
			(xy 125.511505 -288.615434) (xy 125.556124 -288.6395) (xy 125.596531 -288.670114) (xy 125.631773 -288.706556)
			(xy 125.661018 -288.747964) (xy 125.683577 -288.793363) (xy 125.698917 -288.841681) (xy 125.706677 -288.891779)
			(xy 125.70714 -288.917126) (xy 125.706632 -288.943033) (xy 125.698526 -288.99421) (xy 125.682514 -289.043489)
			(xy 125.658991 -289.089656) (xy 125.628535 -289.131575) (xy 125.591897 -289.168213) (xy 125.549978 -289.198669)
			(xy 125.503811 -289.222192) (xy 125.454532 -289.238204) (xy 125.403355 -289.24631) (xy 125.351541 -289.24631)
			(xy 125.300364 -289.238204) (xy 125.251085 -289.222192) (xy 125.204918 -289.198669) (xy 125.162999 -289.168213)
			(xy 125.126361 -289.131575) (xy 125.095905 -289.089656) (xy 125.072382 -289.043489) (xy 125.05637 -288.99421)
			(xy 125.048264 -288.943033) (xy 125.047756 -288.917126) (xy 125.048353 -288.889409) (xy 125.057674 -288.834762)
			(xy 125.066298 -288.808414) (xy 125.074172 -288.786316) (xy 124.869194 -288.431224) (xy 124.846334 -288.426906)
			(xy 124.821499 -288.421756) (xy 124.773689 -288.404821) (xy 124.729038 -288.380764) (xy 124.688599 -288.350151)
			(xy 124.653326 -288.313705) (xy 124.624051 -288.272287) (xy 124.601466 -288.226873) (xy 124.586104 -288.178536)
			(xy 124.578326 -288.128416) (xy 124.577856 -288.103056) (xy 123.35764 -288.103056) (xy 123.357038 -288.130773)
			(xy 123.34772 -288.18542) (xy 123.339098 -288.211768) (xy 123.331478 -288.233866) (xy 123.536456 -288.588958)
			(xy 123.559316 -288.593276) (xy 123.584127 -288.598486) (xy 123.631905 -288.615434) (xy 123.676524 -288.6395)
			(xy 123.716931 -288.670114) (xy 123.752173 -288.706556) (xy 123.781418 -288.747964) (xy 123.803977 -288.793363)
			(xy 123.819317 -288.841681) (xy 123.827077 -288.891779) (xy 123.82754 -288.917126) (xy 123.827032 -288.943033)
			(xy 123.818926 -288.99421) (xy 123.802914 -289.043489) (xy 123.779391 -289.089656) (xy 123.748935 -289.131575)
			(xy 123.712297 -289.168213) (xy 123.670378 -289.198669) (xy 123.624211 -289.222192) (xy 123.574932 -289.238204)
			(xy 123.523755 -289.24631) (xy 123.471941 -289.24631) (xy 123.420764 -289.238204) (xy 123.371485 -289.222192)
			(xy 123.325318 -289.198669) (xy 123.283399 -289.168213) (xy 123.246761 -289.131575) (xy 123.216305 -289.089656)
			(xy 123.192782 -289.043489) (xy 123.17677 -288.99421) (xy 123.168664 -288.943033) (xy 123.168156 -288.917126)
			(xy 123.168753 -288.889409) (xy 123.178074 -288.834762) (xy 123.186698 -288.808414) (xy 123.194572 -288.786316)
			(xy 122.989594 -288.431224) (xy 122.966734 -288.426906) (xy 122.941899 -288.421756) (xy 122.894089 -288.404821)
			(xy 122.849438 -288.380764) (xy 122.808999 -288.350151) (xy 122.773726 -288.313705) (xy 122.744451 -288.272287)
			(xy 122.721866 -288.226873) (xy 122.706504 -288.178536) (xy 122.698726 -288.128416) (xy 122.698256 -288.103056)
			(xy 121.47804 -288.103056) (xy 121.477438 -288.130773) (xy 121.46812 -288.18542) (xy 121.459498 -288.211768)
			(xy 121.451624 -288.233866) (xy 121.656856 -288.588958) (xy 121.679716 -288.593276) (xy 121.704527 -288.598486)
			(xy 121.752305 -288.615434) (xy 121.796924 -288.6395) (xy 121.837331 -288.670114) (xy 121.872573 -288.706556)
			(xy 121.901818 -288.747964) (xy 121.924377 -288.793363) (xy 121.939717 -288.841681) (xy 121.947477 -288.891779)
			(xy 121.94794 -288.917126) (xy 121.947432 -288.943033) (xy 121.939326 -288.99421) (xy 121.923314 -289.043489)
			(xy 121.899791 -289.089656) (xy 121.869335 -289.131575) (xy 121.832697 -289.168213) (xy 121.790778 -289.198669)
			(xy 121.744611 -289.222192) (xy 121.695332 -289.238204) (xy 121.644155 -289.24631) (xy 121.592341 -289.24631)
			(xy 121.541164 -289.238204) (xy 121.491885 -289.222192) (xy 121.445718 -289.198669) (xy 121.403799 -289.168213)
			(xy 121.367161 -289.131575) (xy 121.336705 -289.089656) (xy 121.313182 -289.043489) (xy 121.29717 -288.99421)
			(xy 121.289064 -288.943033) (xy 121.288556 -288.917126) (xy 121.289153 -288.889409) (xy 121.298474 -288.834762)
			(xy 121.307098 -288.808414) (xy 121.314972 -288.786316) (xy 121.10974 -288.431224) (xy 121.08688 -288.426906)
			(xy 121.062064 -288.421716) (xy 121.014285 -288.404766) (xy 120.969665 -288.380698) (xy 120.929258 -288.350081)
			(xy 120.894016 -288.313637) (xy 120.864772 -288.272226) (xy 120.842214 -288.226825) (xy 120.826875 -288.178504)
			(xy 120.819118 -288.128404) (xy 120.818656 -288.103056) (xy 104.56164 -288.103056) (xy 104.561218 -288.128404)
			(xy 104.553436 -288.178499) (xy 104.53808 -288.226813) (xy 104.515512 -288.272208) (xy 104.486262 -288.313614)
			(xy 104.451021 -288.350057) (xy 104.410618 -288.380678) (xy 104.366005 -288.404755) (xy 104.318232 -288.421722)
			(xy 104.293416 -288.426906) (xy 104.270556 -288.431224) (xy 104.065324 -288.786316) (xy 104.073198 -288.808414)
			(xy 104.08184 -288.834757) (xy 104.091154 -288.889407) (xy 104.09174 -288.917126) (xy 104.091232 -288.943033)
			(xy 104.083126 -288.99421) (xy 104.067114 -289.043489) (xy 104.043591 -289.089656) (xy 104.013135 -289.131575)
			(xy 103.976497 -289.168213) (xy 103.934578 -289.198669) (xy 103.888411 -289.222192) (xy 103.839132 -289.238204)
			(xy 103.787955 -289.24631) (xy 103.736141 -289.24631) (xy 103.684964 -289.238204) (xy 103.635685 -289.222192)
			(xy 103.589518 -289.198669) (xy 103.547599 -289.168213) (xy 103.510961 -289.131575) (xy 103.480505 -289.089656)
			(xy 103.456982 -289.043489) (xy 103.44097 -288.99421) (xy 103.432864 -288.943033) (xy 103.432356 -288.917126)
			(xy 103.15194 -288.917126) (xy 103.151518 -288.940067) (xy 103.14509 -288.985498) (xy 103.132444 -289.029604)
			(xy 103.123492 -289.05073) (xy 103.113586 -289.073336) (xy 103.327454 -289.478466) (xy 103.351584 -289.483038)
			(xy 103.37651 -289.488115) (xy 103.424521 -289.50492) (xy 103.469379 -289.528904) (xy 103.510019 -289.559496)
			(xy 103.545476 -289.59597) (xy 103.574906 -289.637459) (xy 103.597612 -289.682977) (xy 103.613053 -289.731444)
			(xy 103.620863 -289.781708) (xy 103.621332 -289.807142) (xy 119.878856 -289.807142) (xy 119.879399 -289.781715)
			(xy 119.887229 -289.731468) (xy 119.90268 -289.683018) (xy 119.925386 -289.637514) (xy 119.954808 -289.596036)
			(xy 119.990248 -289.559565) (xy 120.030867 -289.528967) (xy 120.075701 -289.504967) (xy 120.123688 -289.488134)
			(xy 120.148604 -289.483038) (xy 120.172734 -289.478466) (xy 120.38711 -289.073082) (xy 120.377204 -289.050476)
			(xy 120.368243 -289.029398) (xy 120.355596 -288.985377) (xy 120.349182 -288.940026) (xy 120.348756 -288.917126)
			(xy 120.349264 -288.891219) (xy 120.35737 -288.840042) (xy 120.373382 -288.790763) (xy 120.396905 -288.744596)
			(xy 120.427361 -288.702677) (xy 120.463999 -288.666039) (xy 120.505918 -288.635583) (xy 120.552085 -288.61206)
			(xy 120.601364 -288.596048) (xy 120.652541 -288.587942) (xy 120.704355 -288.587942) (xy 120.755532 -288.596048)
			(xy 120.804811 -288.61206) (xy 120.850978 -288.635583) (xy 120.892897 -288.666039) (xy 120.929535 -288.702677)
			(xy 120.959991 -288.744596) (xy 120.983514 -288.790763) (xy 120.999526 -288.840042) (xy 121.007632 -288.891219)
			(xy 121.00814 -288.917126) (xy 121.007659 -288.942574) (xy 120.999856 -288.992867) (xy 120.984408 -289.041361)
			(xy 120.961683 -289.086901) (xy 120.932222 -289.128403) (xy 120.896727 -289.164878) (xy 120.856043 -289.195458)
			(xy 120.811139 -289.219415) (xy 120.763084 -289.236178) (xy 120.738138 -289.24123) (xy 120.714008 -289.245802)
			(xy 120.499632 -289.651186) (xy 120.509538 -289.673792) (xy 120.518456 -289.694878) (xy 120.531008 -289.738907)
			(xy 120.537342 -289.78425) (xy 120.537732 -289.807142) (xy 121.758456 -289.807142) (xy 121.758999 -289.781715)
			(xy 121.766829 -289.731468) (xy 121.78228 -289.683018) (xy 121.804986 -289.637514) (xy 121.834408 -289.596036)
			(xy 121.869848 -289.559565) (xy 121.910467 -289.528967) (xy 121.955301 -289.504967) (xy 122.003288 -289.488134)
			(xy 122.028204 -289.483038) (xy 122.052334 -289.478466) (xy 122.26671 -289.073082) (xy 122.256804 -289.050476)
			(xy 122.247843 -289.029398) (xy 122.235196 -288.985377) (xy 122.228782 -288.940026) (xy 122.228356 -288.917126)
			(xy 122.228864 -288.891219) (xy 122.23697 -288.840042) (xy 122.252982 -288.790763) (xy 122.276505 -288.744596)
			(xy 122.306961 -288.702677) (xy 122.343599 -288.666039) (xy 122.385518 -288.635583) (xy 122.431685 -288.61206)
			(xy 122.480964 -288.596048) (xy 122.532141 -288.587942) (xy 122.583955 -288.587942) (xy 122.635132 -288.596048)
			(xy 122.684411 -288.61206) (xy 122.730578 -288.635583) (xy 122.772497 -288.666039) (xy 122.809135 -288.702677)
			(xy 122.839591 -288.744596) (xy 122.863114 -288.790763) (xy 122.879126 -288.840042) (xy 122.887232 -288.891219)
			(xy 122.88774 -288.917126) (xy 122.887259 -288.942574) (xy 122.879456 -288.992867) (xy 122.864008 -289.041361)
			(xy 122.841283 -289.086901) (xy 122.811822 -289.128403) (xy 122.776327 -289.164878) (xy 122.735643 -289.195458)
			(xy 122.690739 -289.219415) (xy 122.642684 -289.236178) (xy 122.617738 -289.24123) (xy 122.593608 -289.245802)
			(xy 122.379232 -289.651186) (xy 122.389138 -289.673792) (xy 122.398056 -289.694878) (xy 122.410608 -289.738907)
			(xy 122.416942 -289.78425) (xy 122.417332 -289.807142) (xy 123.638056 -289.807142) (xy 123.638599 -289.781715)
			(xy 123.646429 -289.731468) (xy 123.66188 -289.683018) (xy 123.684586 -289.637514) (xy 123.714008 -289.596036)
			(xy 123.749448 -289.559565) (xy 123.790067 -289.528967) (xy 123.834901 -289.504967) (xy 123.882888 -289.488134)
			(xy 123.907804 -289.483038) (xy 123.931934 -289.478466) (xy 124.14631 -289.073082) (xy 124.136404 -289.050476)
			(xy 124.127443 -289.029398) (xy 124.114796 -288.985377) (xy 124.108382 -288.940026) (xy 124.107956 -288.917126)
			(xy 124.108464 -288.891219) (xy 124.11657 -288.840042) (xy 124.132582 -288.790763) (xy 124.156105 -288.744596)
			(xy 124.186561 -288.702677) (xy 124.223199 -288.666039) (xy 124.265118 -288.635583) (xy 124.311285 -288.61206)
			(xy 124.360564 -288.596048) (xy 124.411741 -288.587942) (xy 124.463555 -288.587942) (xy 124.514732 -288.596048)
			(xy 124.564011 -288.61206) (xy 124.610178 -288.635583) (xy 124.652097 -288.666039) (xy 124.688735 -288.702677)
			(xy 124.719191 -288.744596) (xy 124.742714 -288.790763) (xy 124.758726 -288.840042) (xy 124.766832 -288.891219)
			(xy 124.76734 -288.917126) (xy 124.766859 -288.942574) (xy 124.759056 -288.992867) (xy 124.743608 -289.041361)
			(xy 124.720883 -289.086901) (xy 124.691422 -289.128403) (xy 124.655927 -289.164878) (xy 124.615243 -289.195458)
			(xy 124.570339 -289.219415) (xy 124.522284 -289.236178) (xy 124.497338 -289.24123) (xy 124.473208 -289.245802)
			(xy 124.258832 -289.651186) (xy 124.268738 -289.673792) (xy 124.277656 -289.694878) (xy 124.290208 -289.738907)
			(xy 124.296542 -289.78425) (xy 124.296932 -289.807142) (xy 125.517656 -289.807142) (xy 125.518199 -289.781715)
			(xy 125.526029 -289.731468) (xy 125.54148 -289.683018) (xy 125.564186 -289.637514) (xy 125.593608 -289.596036)
			(xy 125.629048 -289.559565) (xy 125.669667 -289.528967) (xy 125.714501 -289.504967) (xy 125.762488 -289.488134)
			(xy 125.787404 -289.483038) (xy 125.811534 -289.478466) (xy 126.02591 -289.073082) (xy 126.016004 -289.050476)
			(xy 126.007043 -289.029398) (xy 125.994396 -288.985377) (xy 125.987982 -288.940026) (xy 125.987556 -288.917126)
			(xy 125.988064 -288.891219) (xy 125.99617 -288.840042) (xy 126.012182 -288.790763) (xy 126.035705 -288.744596)
			(xy 126.066161 -288.702677) (xy 126.102799 -288.666039) (xy 126.144718 -288.635583) (xy 126.190885 -288.61206)
			(xy 126.240164 -288.596048) (xy 126.291341 -288.587942) (xy 126.343155 -288.587942) (xy 126.394332 -288.596048)
			(xy 126.443611 -288.61206) (xy 126.489778 -288.635583) (xy 126.531697 -288.666039) (xy 126.568335 -288.702677)
			(xy 126.598791 -288.744596) (xy 126.622314 -288.790763) (xy 126.638326 -288.840042) (xy 126.646432 -288.891219)
			(xy 126.64694 -288.917126) (xy 126.646459 -288.942574) (xy 126.638656 -288.992867) (xy 126.623208 -289.041361)
			(xy 126.600483 -289.086901) (xy 126.571022 -289.128403) (xy 126.535527 -289.164878) (xy 126.494843 -289.195458)
			(xy 126.449939 -289.219415) (xy 126.401884 -289.236178) (xy 126.376938 -289.24123) (xy 126.352808 -289.245802)
			(xy 126.138432 -289.651186) (xy 126.148338 -289.673792) (xy 126.157256 -289.694878) (xy 126.169808 -289.738907)
			(xy 126.176142 -289.78425) (xy 126.176532 -289.807142) (xy 127.397256 -289.807142) (xy 127.397799 -289.781715)
			(xy 127.405629 -289.731468) (xy 127.42108 -289.683018) (xy 127.443786 -289.637514) (xy 127.473208 -289.596036)
			(xy 127.508648 -289.559565) (xy 127.549267 -289.528967) (xy 127.594101 -289.504967) (xy 127.642088 -289.488134)
			(xy 127.667004 -289.483038) (xy 127.691134 -289.478466) (xy 127.90551 -289.073082) (xy 127.895604 -289.050476)
			(xy 127.886643 -289.029398) (xy 127.873996 -288.985377) (xy 127.867582 -288.940026) (xy 127.867156 -288.917126)
			(xy 127.867664 -288.891219) (xy 127.87577 -288.840042) (xy 127.891782 -288.790763) (xy 127.915305 -288.744596)
			(xy 127.945761 -288.702677) (xy 127.982399 -288.666039) (xy 128.024318 -288.635583) (xy 128.070485 -288.61206)
			(xy 128.119764 -288.596048) (xy 128.170941 -288.587942) (xy 128.222755 -288.587942) (xy 128.273932 -288.596048)
			(xy 128.323211 -288.61206) (xy 128.369378 -288.635583) (xy 128.411297 -288.666039) (xy 128.447935 -288.702677)
			(xy 128.478391 -288.744596) (xy 128.501914 -288.790763) (xy 128.517926 -288.840042) (xy 128.526032 -288.891219)
			(xy 128.52654 -288.917126) (xy 128.526059 -288.942574) (xy 128.518256 -288.992867) (xy 128.502808 -289.041361)
			(xy 128.480083 -289.086901) (xy 128.450622 -289.128403) (xy 128.415127 -289.164878) (xy 128.374443 -289.195458)
			(xy 128.329539 -289.219415) (xy 128.281484 -289.236178) (xy 128.256538 -289.24123) (xy 128.232408 -289.245802)
			(xy 128.018032 -289.651186) (xy 128.027938 -289.673792) (xy 128.036856 -289.694878) (xy 128.049408 -289.738907)
			(xy 128.055742 -289.78425) (xy 128.056132 -289.807142) (xy 129.276856 -289.807142) (xy 129.277399 -289.781715)
			(xy 129.285229 -289.731468) (xy 129.30068 -289.683018) (xy 129.323386 -289.637514) (xy 129.352808 -289.596036)
			(xy 129.388248 -289.559565) (xy 129.428867 -289.528967) (xy 129.473701 -289.504967) (xy 129.521688 -289.488134)
			(xy 129.546604 -289.483038) (xy 129.570734 -289.478466) (xy 129.78511 -289.073082) (xy 129.775204 -289.050476)
			(xy 129.766243 -289.029398) (xy 129.753596 -288.985377) (xy 129.747182 -288.940026) (xy 129.746756 -288.917126)
			(xy 129.747264 -288.891219) (xy 129.75537 -288.840042) (xy 129.771382 -288.790763) (xy 129.794905 -288.744596)
			(xy 129.825361 -288.702677) (xy 129.861999 -288.666039) (xy 129.903918 -288.635583) (xy 129.950085 -288.61206)
			(xy 129.999364 -288.596048) (xy 130.050541 -288.587942) (xy 130.102355 -288.587942) (xy 130.153532 -288.596048)
			(xy 130.202811 -288.61206) (xy 130.248978 -288.635583) (xy 130.290897 -288.666039) (xy 130.327535 -288.702677)
			(xy 130.357991 -288.744596) (xy 130.381514 -288.790763) (xy 130.397526 -288.840042) (xy 130.405632 -288.891219)
			(xy 130.40614 -288.917126) (xy 130.405659 -288.942574) (xy 130.397856 -288.992867) (xy 130.382408 -289.041361)
			(xy 130.359683 -289.086901) (xy 130.330222 -289.128403) (xy 130.294727 -289.164878) (xy 130.254043 -289.195458)
			(xy 130.209139 -289.219415) (xy 130.161084 -289.236178) (xy 130.136138 -289.24123) (xy 130.112008 -289.245802)
			(xy 129.897632 -289.651186) (xy 129.907538 -289.673792) (xy 129.916456 -289.694878) (xy 129.929008 -289.738907)
			(xy 129.935342 -289.78425) (xy 129.935732 -289.807142) (xy 131.156456 -289.807142) (xy 131.156999 -289.781715)
			(xy 131.164829 -289.731468) (xy 131.18028 -289.683018) (xy 131.202986 -289.637514) (xy 131.232408 -289.596036)
			(xy 131.267848 -289.559565) (xy 131.308467 -289.528967) (xy 131.353301 -289.504967) (xy 131.401288 -289.488134)
			(xy 131.426204 -289.483038) (xy 131.450334 -289.478466) (xy 131.66471 -289.073082) (xy 131.654804 -289.050476)
			(xy 131.645843 -289.029398) (xy 131.633196 -288.985377) (xy 131.626782 -288.940026) (xy 131.626356 -288.917126)
			(xy 131.626864 -288.891219) (xy 131.63497 -288.840042) (xy 131.650982 -288.790763) (xy 131.674505 -288.744596)
			(xy 131.704961 -288.702677) (xy 131.741599 -288.666039) (xy 131.783518 -288.635583) (xy 131.829685 -288.61206)
			(xy 131.878964 -288.596048) (xy 131.930141 -288.587942) (xy 131.981955 -288.587942) (xy 132.033132 -288.596048)
			(xy 132.082411 -288.61206) (xy 132.128578 -288.635583) (xy 132.170497 -288.666039) (xy 132.207135 -288.702677)
			(xy 132.237591 -288.744596) (xy 132.261114 -288.790763) (xy 132.277126 -288.840042) (xy 132.285232 -288.891219)
			(xy 132.28574 -288.917126) (xy 132.285259 -288.942574) (xy 132.277456 -288.992867) (xy 132.262008 -289.041361)
			(xy 132.239283 -289.086901) (xy 132.209822 -289.128403) (xy 132.174327 -289.164878) (xy 132.133643 -289.195458)
			(xy 132.088739 -289.219415) (xy 132.040684 -289.236178) (xy 132.015738 -289.24123) (xy 131.991608 -289.245802)
			(xy 131.777232 -289.651186) (xy 131.787138 -289.673792) (xy 131.796056 -289.694878) (xy 131.808608 -289.738907)
			(xy 131.814942 -289.78425) (xy 131.815332 -289.807142) (xy 133.036056 -289.807142) (xy 133.036599 -289.781715)
			(xy 133.044429 -289.731468) (xy 133.05988 -289.683018) (xy 133.082586 -289.637514) (xy 133.112008 -289.596036)
			(xy 133.147448 -289.559565) (xy 133.188067 -289.528967) (xy 133.232901 -289.504967) (xy 133.280888 -289.488134)
			(xy 133.305804 -289.483038) (xy 133.329934 -289.478466) (xy 133.54431 -289.073082) (xy 133.534404 -289.050476)
			(xy 133.525443 -289.029398) (xy 133.512796 -288.985377) (xy 133.506382 -288.940026) (xy 133.505956 -288.917126)
			(xy 133.506464 -288.891219) (xy 133.51457 -288.840042) (xy 133.530582 -288.790763) (xy 133.554105 -288.744596)
			(xy 133.584561 -288.702677) (xy 133.621199 -288.666039) (xy 133.663118 -288.635583) (xy 133.709285 -288.61206)
			(xy 133.758564 -288.596048) (xy 133.809741 -288.587942) (xy 133.861555 -288.587942) (xy 133.912732 -288.596048)
			(xy 133.962011 -288.61206) (xy 134.008178 -288.635583) (xy 134.050097 -288.666039) (xy 134.086735 -288.702677)
			(xy 134.117191 -288.744596) (xy 134.140714 -288.790763) (xy 134.156726 -288.840042) (xy 134.164832 -288.891219)
			(xy 134.16534 -288.917126) (xy 134.164859 -288.942574) (xy 134.157056 -288.992867) (xy 134.141608 -289.041361)
			(xy 134.118883 -289.086901) (xy 134.089422 -289.128403) (xy 134.053927 -289.164878) (xy 134.013243 -289.195458)
			(xy 133.968339 -289.219415) (xy 133.920284 -289.236178) (xy 133.895338 -289.24123) (xy 133.871208 -289.245802)
			(xy 133.656832 -289.651186) (xy 133.666738 -289.673792) (xy 133.675656 -289.694878) (xy 133.688208 -289.738907)
			(xy 133.694542 -289.78425) (xy 133.694932 -289.807142) (xy 133.694424 -289.833029) (xy 133.686325 -289.884167)
			(xy 133.670326 -289.933407) (xy 133.64682 -289.979539) (xy 133.616388 -290.021426) (xy 133.579778 -290.058036)
			(xy 133.537891 -290.088468) (xy 133.491759 -290.111974) (xy 133.442519 -290.127973) (xy 133.391381 -290.136072)
			(xy 133.339607 -290.136072) (xy 133.288469 -290.127973) (xy 133.239229 -290.111974) (xy 133.193097 -290.088468)
			(xy 133.15121 -290.058036) (xy 133.1146 -290.021426) (xy 133.084168 -289.979539) (xy 133.060662 -289.933407)
			(xy 133.044663 -289.884167) (xy 133.036564 -289.833029) (xy 133.036056 -289.807142) (xy 131.815332 -289.807142)
			(xy 131.814824 -289.833029) (xy 131.806725 -289.884167) (xy 131.790726 -289.933407) (xy 131.76722 -289.979539)
			(xy 131.736788 -290.021426) (xy 131.700178 -290.058036) (xy 131.658291 -290.088468) (xy 131.612159 -290.111974)
			(xy 131.562919 -290.127973) (xy 131.511781 -290.136072) (xy 131.460007 -290.136072) (xy 131.408869 -290.127973)
			(xy 131.359629 -290.111974) (xy 131.313497 -290.088468) (xy 131.27161 -290.058036) (xy 131.235 -290.021426)
			(xy 131.204568 -289.979539) (xy 131.181062 -289.933407) (xy 131.165063 -289.884167) (xy 131.156964 -289.833029)
			(xy 131.156456 -289.807142) (xy 129.935732 -289.807142) (xy 129.935224 -289.833029) (xy 129.927125 -289.884167)
			(xy 129.911126 -289.933407) (xy 129.88762 -289.979539) (xy 129.857188 -290.021426) (xy 129.820578 -290.058036)
			(xy 129.778691 -290.088468) (xy 129.732559 -290.111974) (xy 129.683319 -290.127973) (xy 129.632181 -290.136072)
			(xy 129.580407 -290.136072) (xy 129.529269 -290.127973) (xy 129.480029 -290.111974) (xy 129.433897 -290.088468)
			(xy 129.39201 -290.058036) (xy 129.3554 -290.021426) (xy 129.324968 -289.979539) (xy 129.301462 -289.933407)
			(xy 129.285463 -289.884167) (xy 129.277364 -289.833029) (xy 129.276856 -289.807142) (xy 128.056132 -289.807142)
			(xy 128.055624 -289.833029) (xy 128.047525 -289.884167) (xy 128.031526 -289.933407) (xy 128.00802 -289.979539)
			(xy 127.977588 -290.021426) (xy 127.940978 -290.058036) (xy 127.899091 -290.088468) (xy 127.852959 -290.111974)
			(xy 127.803719 -290.127973) (xy 127.752581 -290.136072) (xy 127.700807 -290.136072) (xy 127.649669 -290.127973)
			(xy 127.600429 -290.111974) (xy 127.554297 -290.088468) (xy 127.51241 -290.058036) (xy 127.4758 -290.021426)
			(xy 127.445368 -289.979539) (xy 127.421862 -289.933407) (xy 127.405863 -289.884167) (xy 127.397764 -289.833029)
			(xy 127.397256 -289.807142) (xy 126.176532 -289.807142) (xy 126.176024 -289.833029) (xy 126.167925 -289.884167)
			(xy 126.151926 -289.933407) (xy 126.12842 -289.979539) (xy 126.097988 -290.021426) (xy 126.061378 -290.058036)
			(xy 126.019491 -290.088468) (xy 125.973359 -290.111974) (xy 125.924119 -290.127973) (xy 125.872981 -290.136072)
			(xy 125.821207 -290.136072) (xy 125.770069 -290.127973) (xy 125.720829 -290.111974) (xy 125.674697 -290.088468)
			(xy 125.63281 -290.058036) (xy 125.5962 -290.021426) (xy 125.565768 -289.979539) (xy 125.542262 -289.933407)
			(xy 125.526263 -289.884167) (xy 125.518164 -289.833029) (xy 125.517656 -289.807142) (xy 124.296932 -289.807142)
			(xy 124.296424 -289.833029) (xy 124.288325 -289.884167) (xy 124.272326 -289.933407) (xy 124.24882 -289.979539)
			(xy 124.218388 -290.021426) (xy 124.181778 -290.058036) (xy 124.139891 -290.088468) (xy 124.093759 -290.111974)
			(xy 124.044519 -290.127973) (xy 123.993381 -290.136072) (xy 123.941607 -290.136072) (xy 123.890469 -290.127973)
			(xy 123.841229 -290.111974) (xy 123.795097 -290.088468) (xy 123.75321 -290.058036) (xy 123.7166 -290.021426)
			(xy 123.686168 -289.979539) (xy 123.662662 -289.933407) (xy 123.646663 -289.884167) (xy 123.638564 -289.833029)
			(xy 123.638056 -289.807142) (xy 122.417332 -289.807142) (xy 122.416824 -289.833029) (xy 122.408725 -289.884167)
			(xy 122.392726 -289.933407) (xy 122.36922 -289.979539) (xy 122.338788 -290.021426) (xy 122.302178 -290.058036)
			(xy 122.260291 -290.088468) (xy 122.214159 -290.111974) (xy 122.164919 -290.127973) (xy 122.113781 -290.136072)
			(xy 122.062007 -290.136072) (xy 122.010869 -290.127973) (xy 121.961629 -290.111974) (xy 121.915497 -290.088468)
			(xy 121.87361 -290.058036) (xy 121.837 -290.021426) (xy 121.806568 -289.979539) (xy 121.783062 -289.933407)
			(xy 121.767063 -289.884167) (xy 121.758964 -289.833029) (xy 121.758456 -289.807142) (xy 120.537732 -289.807142)
			(xy 120.537224 -289.833029) (xy 120.529125 -289.884167) (xy 120.513126 -289.933407) (xy 120.48962 -289.979539)
			(xy 120.459188 -290.021426) (xy 120.422578 -290.058036) (xy 120.380691 -290.088468) (xy 120.334559 -290.111974)
			(xy 120.285319 -290.127973) (xy 120.234181 -290.136072) (xy 120.182407 -290.136072) (xy 120.131269 -290.127973)
			(xy 120.082029 -290.111974) (xy 120.035897 -290.088468) (xy 119.99401 -290.058036) (xy 119.9574 -290.021426)
			(xy 119.926968 -289.979539) (xy 119.903462 -289.933407) (xy 119.887463 -289.884167) (xy 119.879364 -289.833029)
			(xy 119.878856 -289.807142) (xy 103.621332 -289.807142) (xy 103.620824 -289.833029) (xy 103.612725 -289.884167)
			(xy 103.596726 -289.933407) (xy 103.57322 -289.979539) (xy 103.542788 -290.021426) (xy 103.506178 -290.058036)
			(xy 103.464291 -290.088468) (xy 103.418159 -290.111974) (xy 103.368919 -290.127973) (xy 103.317781 -290.136072)
			(xy 103.266007 -290.136072) (xy 103.214869 -290.127973) (xy 103.165629 -290.111974) (xy 103.119497 -290.088468)
			(xy 103.07761 -290.058036) (xy 103.041 -290.021426) (xy 103.010568 -289.979539) (xy 102.987062 -289.933407)
			(xy 102.971063 -289.884167) (xy 102.962964 -289.833029) (xy 102.962456 -289.807142) (xy 102.962456 -289.806634)
			(xy 102.962859 -289.783785) (xy 102.969212 -289.738531) (xy 102.981758 -289.694589) (xy 102.99065 -289.673538)
			(xy 103.000556 -289.650932) (xy 102.786688 -289.245802) (xy 102.762558 -289.24123) (xy 102.737619 -289.236158)
			(xy 102.689576 -289.219379) (xy 102.644683 -289.195414) (xy 102.604007 -289.164832) (xy 102.568517 -289.12836)
			(xy 102.539055 -289.086867) (xy 102.516322 -289.041337) (xy 102.500858 -288.992854) (xy 102.493031 -288.942571)
			(xy 102.492556 -288.917126) (xy 102.21214 -288.917126) (xy 102.211632 -288.943033) (xy 102.203526 -288.99421)
			(xy 102.187514 -289.043489) (xy 102.163991 -289.089656) (xy 102.133535 -289.131575) (xy 102.096897 -289.168213)
			(xy 102.054978 -289.198669) (xy 102.008811 -289.222192) (xy 101.959532 -289.238204) (xy 101.908355 -289.24631)
			(xy 101.856541 -289.24631) (xy 101.805364 -289.238204) (xy 101.756085 -289.222192) (xy 101.709918 -289.198669)
			(xy 101.667999 -289.168213) (xy 101.631361 -289.131575) (xy 101.600905 -289.089656) (xy 101.577382 -289.043489)
			(xy 101.56137 -288.99421) (xy 101.553264 -288.943033) (xy 101.552756 -288.917126) (xy 101.27234 -288.917126)
			(xy 101.271918 -288.940067) (xy 101.26549 -288.985498) (xy 101.252844 -289.029604) (xy 101.243892 -289.05073)
			(xy 101.233986 -289.073336) (xy 101.447854 -289.478466) (xy 101.471984 -289.483038) (xy 101.49691 -289.488115)
			(xy 101.544921 -289.50492) (xy 101.589779 -289.528904) (xy 101.630419 -289.559496) (xy 101.665876 -289.59597)
			(xy 101.695306 -289.637459) (xy 101.718012 -289.682977) (xy 101.733453 -289.731444) (xy 101.741263 -289.781708)
			(xy 101.741732 -289.807142) (xy 101.741224 -289.833029) (xy 101.733125 -289.884167) (xy 101.717126 -289.933407)
			(xy 101.69362 -289.979539) (xy 101.663188 -290.021426) (xy 101.626578 -290.058036) (xy 101.584691 -290.088468)
			(xy 101.538559 -290.111974) (xy 101.489319 -290.127973) (xy 101.438181 -290.136072) (xy 101.386407 -290.136072)
			(xy 101.335269 -290.127973) (xy 101.286029 -290.111974) (xy 101.239897 -290.088468) (xy 101.19801 -290.058036)
			(xy 101.1614 -290.021426) (xy 101.130968 -289.979539) (xy 101.107462 -289.933407) (xy 101.091463 -289.884167)
			(xy 101.083364 -289.833029) (xy 101.082856 -289.807142) (xy 101.082856 -289.806634) (xy 101.083259 -289.783785)
			(xy 101.089612 -289.738531) (xy 101.102158 -289.694589) (xy 101.11105 -289.673538) (xy 101.120956 -289.650932)
			(xy 100.907088 -289.245802) (xy 100.882958 -289.24123) (xy 100.858019 -289.236158) (xy 100.809976 -289.219379)
			(xy 100.765083 -289.195414) (xy 100.724407 -289.164832) (xy 100.688917 -289.12836) (xy 100.659455 -289.086867)
			(xy 100.636722 -289.041337) (xy 100.621258 -288.992854) (xy 100.613431 -288.942571) (xy 100.612956 -288.917126)
			(xy 100.33254 -288.917126) (xy 100.332032 -288.943033) (xy 100.323926 -288.99421) (xy 100.307914 -289.043489)
			(xy 100.284391 -289.089656) (xy 100.253935 -289.131575) (xy 100.217297 -289.168213) (xy 100.175378 -289.198669)
			(xy 100.129211 -289.222192) (xy 100.079932 -289.238204) (xy 100.028755 -289.24631) (xy 99.976941 -289.24631)
			(xy 99.925764 -289.238204) (xy 99.876485 -289.222192) (xy 99.830318 -289.198669) (xy 99.788399 -289.168213)
			(xy 99.751761 -289.131575) (xy 99.721305 -289.089656) (xy 99.697782 -289.043489) (xy 99.68177 -288.99421)
			(xy 99.673664 -288.943033) (xy 99.673156 -288.917126) (xy 99.39274 -288.917126) (xy 99.392318 -288.940067)
			(xy 99.38589 -288.985498) (xy 99.373244 -289.029604) (xy 99.364292 -289.05073) (xy 99.354386 -289.073336)
			(xy 99.568254 -289.478466) (xy 99.592384 -289.483038) (xy 99.61731 -289.488115) (xy 99.665321 -289.50492)
			(xy 99.710179 -289.528904) (xy 99.750819 -289.559496) (xy 99.786276 -289.59597) (xy 99.815706 -289.637459)
			(xy 99.838412 -289.682977) (xy 99.853853 -289.731444) (xy 99.861663 -289.781708) (xy 99.862132 -289.807142)
			(xy 99.861624 -289.833029) (xy 99.853525 -289.884167) (xy 99.837526 -289.933407) (xy 99.81402 -289.979539)
			(xy 99.783588 -290.021426) (xy 99.746978 -290.058036) (xy 99.705091 -290.088468) (xy 99.658959 -290.111974)
			(xy 99.609719 -290.127973) (xy 99.558581 -290.136072) (xy 99.506807 -290.136072) (xy 99.455669 -290.127973)
			(xy 99.406429 -290.111974) (xy 99.360297 -290.088468) (xy 99.31841 -290.058036) (xy 99.2818 -290.021426)
			(xy 99.251368 -289.979539) (xy 99.227862 -289.933407) (xy 99.211863 -289.884167) (xy 99.203764 -289.833029)
			(xy 99.203256 -289.807142) (xy 99.203256 -289.806634) (xy 99.203659 -289.783785) (xy 99.210012 -289.738531)
			(xy 99.222558 -289.694589) (xy 99.23145 -289.673538) (xy 99.241356 -289.650932) (xy 99.027488 -289.245802)
			(xy 99.003358 -289.24123) (xy 98.978419 -289.236158) (xy 98.930376 -289.219379) (xy 98.885483 -289.195414)
			(xy 98.844807 -289.164832) (xy 98.809317 -289.12836) (xy 98.779855 -289.086867) (xy 98.757122 -289.041337)
			(xy 98.741658 -288.992854) (xy 98.733831 -288.942571) (xy 98.733356 -288.917126) (xy 98.45294 -288.917126)
			(xy 98.452432 -288.943033) (xy 98.444326 -288.99421) (xy 98.428314 -289.043489) (xy 98.404791 -289.089656)
			(xy 98.374335 -289.131575) (xy 98.337697 -289.168213) (xy 98.295778 -289.198669) (xy 98.249611 -289.222192)
			(xy 98.200332 -289.238204) (xy 98.149155 -289.24631) (xy 98.097341 -289.24631) (xy 98.046164 -289.238204)
			(xy 97.996885 -289.222192) (xy 97.950718 -289.198669) (xy 97.908799 -289.168213) (xy 97.872161 -289.131575)
			(xy 97.841705 -289.089656) (xy 97.818182 -289.043489) (xy 97.80217 -288.99421) (xy 97.794064 -288.943033)
			(xy 97.793556 -288.917126) (xy 97.51314 -288.917126) (xy 97.512718 -288.940067) (xy 97.50629 -288.985498)
			(xy 97.493644 -289.029604) (xy 97.484692 -289.05073) (xy 97.474786 -289.073336) (xy 97.688654 -289.478466)
			(xy 97.712784 -289.483038) (xy 97.73771 -289.488115) (xy 97.785721 -289.50492) (xy 97.830579 -289.528904)
			(xy 97.871219 -289.559496) (xy 97.906676 -289.59597) (xy 97.936106 -289.637459) (xy 97.958812 -289.682977)
			(xy 97.974253 -289.731444) (xy 97.982063 -289.781708) (xy 97.982532 -289.807142) (xy 97.982024 -289.833029)
			(xy 97.973925 -289.884167) (xy 97.957926 -289.933407) (xy 97.93442 -289.979539) (xy 97.903988 -290.021426)
			(xy 97.867378 -290.058036) (xy 97.825491 -290.088468) (xy 97.779359 -290.111974) (xy 97.730119 -290.127973)
			(xy 97.678981 -290.136072) (xy 97.627207 -290.136072) (xy 97.576069 -290.127973) (xy 97.526829 -290.111974)
			(xy 97.480697 -290.088468) (xy 97.43881 -290.058036) (xy 97.4022 -290.021426) (xy 97.371768 -289.979539)
			(xy 97.348262 -289.933407) (xy 97.332263 -289.884167) (xy 97.324164 -289.833029) (xy 97.323656 -289.807142)
			(xy 97.323656 -289.806634) (xy 97.324059 -289.783785) (xy 97.330412 -289.738531) (xy 97.342958 -289.694589)
			(xy 97.35185 -289.673538) (xy 97.361756 -289.650932) (xy 97.147888 -289.245802) (xy 97.123758 -289.24123)
			(xy 97.098819 -289.236158) (xy 97.050776 -289.219379) (xy 97.005883 -289.195414) (xy 96.965207 -289.164832)
			(xy 96.929717 -289.12836) (xy 96.900255 -289.086867) (xy 96.877522 -289.041337) (xy 96.862058 -288.992854)
			(xy 96.854231 -288.942571) (xy 96.853756 -288.917126) (xy 96.57334 -288.917126) (xy 96.572832 -288.943033)
			(xy 96.564726 -288.99421) (xy 96.548714 -289.043489) (xy 96.525191 -289.089656) (xy 96.494735 -289.131575)
			(xy 96.458097 -289.168213) (xy 96.416178 -289.198669) (xy 96.370011 -289.222192) (xy 96.320732 -289.238204)
			(xy 96.269555 -289.24631) (xy 96.217741 -289.24631) (xy 96.166564 -289.238204) (xy 96.117285 -289.222192)
			(xy 96.071118 -289.198669) (xy 96.029199 -289.168213) (xy 95.992561 -289.131575) (xy 95.962105 -289.089656)
			(xy 95.938582 -289.043489) (xy 95.92257 -288.99421) (xy 95.914464 -288.943033) (xy 95.913956 -288.917126)
			(xy 95.63354 -288.917126) (xy 95.633118 -288.940067) (xy 95.62669 -288.985498) (xy 95.614044 -289.029604)
			(xy 95.605092 -289.05073) (xy 95.595186 -289.073336) (xy 95.809054 -289.478466) (xy 95.833184 -289.483038)
			(xy 95.85811 -289.488115) (xy 95.906121 -289.50492) (xy 95.950979 -289.528904) (xy 95.991619 -289.559496)
			(xy 96.027076 -289.59597) (xy 96.056506 -289.637459) (xy 96.079212 -289.682977) (xy 96.094653 -289.731444)
			(xy 96.102463 -289.781708) (xy 96.102932 -289.807142) (xy 96.102424 -289.833029) (xy 96.094325 -289.884167)
			(xy 96.078326 -289.933407) (xy 96.05482 -289.979539) (xy 96.024388 -290.021426) (xy 95.987778 -290.058036)
			(xy 95.945891 -290.088468) (xy 95.899759 -290.111974) (xy 95.850519 -290.127973) (xy 95.799381 -290.136072)
			(xy 95.747607 -290.136072) (xy 95.696469 -290.127973) (xy 95.647229 -290.111974) (xy 95.601097 -290.088468)
			(xy 95.55921 -290.058036) (xy 95.5226 -290.021426) (xy 95.492168 -289.979539) (xy 95.468662 -289.933407)
			(xy 95.452663 -289.884167) (xy 95.444564 -289.833029) (xy 95.444056 -289.807142) (xy 95.444056 -289.806634)
			(xy 95.444459 -289.783785) (xy 95.450812 -289.738531) (xy 95.463358 -289.694589) (xy 95.47225 -289.673538)
			(xy 95.482156 -289.650932) (xy 95.268288 -289.245802) (xy 95.244158 -289.24123) (xy 95.219219 -289.236158)
			(xy 95.171176 -289.219379) (xy 95.126283 -289.195414) (xy 95.085607 -289.164832) (xy 95.050117 -289.12836)
			(xy 95.020655 -289.086867) (xy 94.997922 -289.041337) (xy 94.982458 -288.992854) (xy 94.974631 -288.942571)
			(xy 94.974156 -288.917126) (xy 94.69374 -288.917126) (xy 94.693232 -288.943033) (xy 94.685126 -288.99421)
			(xy 94.669114 -289.043489) (xy 94.645591 -289.089656) (xy 94.615135 -289.131575) (xy 94.578497 -289.168213)
			(xy 94.536578 -289.198669) (xy 94.490411 -289.222192) (xy 94.441132 -289.238204) (xy 94.389955 -289.24631)
			(xy 94.338141 -289.24631) (xy 94.286964 -289.238204) (xy 94.237685 -289.222192) (xy 94.191518 -289.198669)
			(xy 94.149599 -289.168213) (xy 94.112961 -289.131575) (xy 94.082505 -289.089656) (xy 94.058982 -289.043489)
			(xy 94.04297 -288.99421) (xy 94.034864 -288.943033) (xy 94.034356 -288.917126) (xy 93.75394 -288.917126)
			(xy 93.753518 -288.940067) (xy 93.74709 -288.985498) (xy 93.734444 -289.029604) (xy 93.725492 -289.05073)
			(xy 93.715586 -289.073336) (xy 93.929454 -289.478466) (xy 93.953584 -289.483038) (xy 93.97851 -289.488115)
			(xy 94.026521 -289.50492) (xy 94.071379 -289.528904) (xy 94.112019 -289.559496) (xy 94.147476 -289.59597)
			(xy 94.176906 -289.637459) (xy 94.199612 -289.682977) (xy 94.215053 -289.731444) (xy 94.222863 -289.781708)
			(xy 94.223332 -289.807142) (xy 94.222824 -289.833029) (xy 94.214725 -289.884167) (xy 94.198726 -289.933407)
			(xy 94.17522 -289.979539) (xy 94.144788 -290.021426) (xy 94.108178 -290.058036) (xy 94.066291 -290.088468)
			(xy 94.020159 -290.111974) (xy 93.970919 -290.127973) (xy 93.919781 -290.136072) (xy 93.868007 -290.136072)
			(xy 93.816869 -290.127973) (xy 93.767629 -290.111974) (xy 93.721497 -290.088468) (xy 93.67961 -290.058036)
			(xy 93.643 -290.021426) (xy 93.612568 -289.979539) (xy 93.589062 -289.933407) (xy 93.573063 -289.884167)
			(xy 93.564964 -289.833029) (xy 93.564456 -289.807142) (xy 93.564456 -289.806634) (xy 93.564859 -289.783785)
			(xy 93.571212 -289.738531) (xy 93.583758 -289.694589) (xy 93.59265 -289.673538) (xy 93.602556 -289.650932)
			(xy 93.388688 -289.245802) (xy 93.364558 -289.24123) (xy 93.339619 -289.236158) (xy 93.291576 -289.219379)
			(xy 93.246683 -289.195414) (xy 93.206007 -289.164832) (xy 93.170517 -289.12836) (xy 93.141055 -289.086867)
			(xy 93.118322 -289.041337) (xy 93.102858 -288.992854) (xy 93.095031 -288.942571) (xy 93.094556 -288.917126)
			(xy 92.81414 -288.917126) (xy 92.813632 -288.943033) (xy 92.805526 -288.99421) (xy 92.789514 -289.043489)
			(xy 92.765991 -289.089656) (xy 92.735535 -289.131575) (xy 92.698897 -289.168213) (xy 92.656978 -289.198669)
			(xy 92.610811 -289.222192) (xy 92.561532 -289.238204) (xy 92.510355 -289.24631) (xy 92.458541 -289.24631)
			(xy 92.407364 -289.238204) (xy 92.358085 -289.222192) (xy 92.311918 -289.198669) (xy 92.269999 -289.168213)
			(xy 92.233361 -289.131575) (xy 92.202905 -289.089656) (xy 92.179382 -289.043489) (xy 92.16337 -288.99421)
			(xy 92.155264 -288.943033) (xy 92.154756 -288.917126) (xy 91.87434 -288.917126) (xy 91.873918 -288.940067)
			(xy 91.86749 -288.985498) (xy 91.854844 -289.029604) (xy 91.845892 -289.05073) (xy 91.835986 -289.073336)
			(xy 92.049854 -289.478466) (xy 92.073984 -289.483038) (xy 92.09891 -289.488115) (xy 92.146921 -289.50492)
			(xy 92.191779 -289.528904) (xy 92.232419 -289.559496) (xy 92.267876 -289.59597) (xy 92.297306 -289.637459)
			(xy 92.320012 -289.682977) (xy 92.335453 -289.731444) (xy 92.343263 -289.781708) (xy 92.343732 -289.807142)
			(xy 92.343224 -289.833029) (xy 92.335125 -289.884167) (xy 92.319126 -289.933407) (xy 92.29562 -289.979539)
			(xy 92.265188 -290.021426) (xy 92.228578 -290.058036) (xy 92.186691 -290.088468) (xy 92.140559 -290.111974)
			(xy 92.091319 -290.127973) (xy 92.040181 -290.136072) (xy 91.988407 -290.136072) (xy 91.937269 -290.127973)
			(xy 91.888029 -290.111974) (xy 91.841897 -290.088468) (xy 91.80001 -290.058036) (xy 91.7634 -290.021426)
			(xy 91.732968 -289.979539) (xy 91.709462 -289.933407) (xy 91.693463 -289.884167) (xy 91.685364 -289.833029)
			(xy 91.684856 -289.807142) (xy 91.684856 -289.806634) (xy 91.685259 -289.783785) (xy 91.691612 -289.738531)
			(xy 91.704158 -289.694589) (xy 91.71305 -289.673538) (xy 91.722956 -289.650932) (xy 91.509088 -289.245802)
			(xy 91.484958 -289.24123) (xy 91.460019 -289.236158) (xy 91.411976 -289.219379) (xy 91.367083 -289.195414)
			(xy 91.326407 -289.164832) (xy 91.290917 -289.12836) (xy 91.261455 -289.086867) (xy 91.238722 -289.041337)
			(xy 91.223258 -288.992854) (xy 91.215431 -288.942571) (xy 91.214956 -288.917126) (xy 90.93454 -288.917126)
			(xy 90.934032 -288.943033) (xy 90.925926 -288.99421) (xy 90.909914 -289.043489) (xy 90.886391 -289.089656)
			(xy 90.855935 -289.131575) (xy 90.819297 -289.168213) (xy 90.777378 -289.198669) (xy 90.731211 -289.222192)
			(xy 90.681932 -289.238204) (xy 90.630755 -289.24631) (xy 90.578941 -289.24631) (xy 90.527764 -289.238204)
			(xy 90.478485 -289.222192) (xy 90.432318 -289.198669) (xy 90.390399 -289.168213) (xy 90.353761 -289.131575)
			(xy 90.323305 -289.089656) (xy 90.299782 -289.043489) (xy 90.28377 -288.99421) (xy 90.275664 -288.943033)
			(xy 90.275156 -288.917126) (xy 89.05494 -288.917126) (xy 89.054432 -288.943033) (xy 89.046326 -288.99421)
			(xy 89.030314 -289.043489) (xy 89.006791 -289.089656) (xy 88.976335 -289.131575) (xy 88.939697 -289.168213)
			(xy 88.897778 -289.198669) (xy 88.851611 -289.222192) (xy 88.802332 -289.238204) (xy 88.751155 -289.24631)
			(xy 88.699341 -289.24631) (xy 88.648164 -289.238204) (xy 88.598885 -289.222192) (xy 88.552718 -289.198669)
			(xy 88.510799 -289.168213) (xy 88.474161 -289.131575) (xy 88.443705 -289.089656) (xy 88.420182 -289.043489)
			(xy 88.40417 -288.99421) (xy 88.396064 -288.943033) (xy 88.395556 -288.917126) (xy 2.509012 -288.917126)
			(xy 2.509012 -297.515026) (xy 88.21548 -297.515026) (xy 88.219461 -297.382006) (xy 88.23139 -297.249461)
			(xy 88.251225 -297.117868) (xy 88.278894 -296.987696) (xy 88.314298 -296.859411) (xy 88.357311 -296.733474)
			(xy 88.407778 -296.610335) (xy 88.465519 -296.490434) (xy 88.530328 -296.374201) (xy 88.601972 -296.262051)
			(xy 88.680194 -296.154387) (xy 88.764715 -296.051594) (xy 88.855233 -295.954039) (xy 88.951422 -295.862073)
			(xy 89.05294 -295.776023) (xy 89.159421 -295.696199) (xy 89.270486 -295.622886) (xy 89.385737 -295.556346)
			(xy 89.504761 -295.496817) (xy 89.627132 -295.444513) (xy 89.752411 -295.399621) (xy 89.880152 -295.362302)
			(xy 90.009895 -295.332689) (xy 90.141177 -295.310888) (xy 90.273528 -295.296978) (xy 90.406474 -295.291007)
			(xy 90.539539 -295.292998) (xy 90.672247 -295.302943) (xy 90.804123 -295.320807) (xy 90.934694 -295.346525)
			(xy 91.063494 -295.380006) (xy 91.19006 -295.42113) (xy 91.313941 -295.46975) (xy 91.434692 -295.525691)
			(xy 91.551882 -295.588753) (xy 91.665091 -295.658711) (xy 91.773913 -295.735315) (xy 91.877959 -295.818289)
			(xy 91.976857 -295.907337) (xy 92.070252 -296.00214) (xy 92.15781 -296.102358) (xy 92.239219 -296.207634)
			(xy 92.314185 -296.31759) (xy 92.382442 -296.431832) (xy 92.443744 -296.549952) (xy 92.497873 -296.671527)
			(xy 92.544634 -296.796121) (xy 92.58386 -296.923289) (xy 92.61541 -297.052575) (xy 92.639173 -297.183516)
			(xy 92.655062 -297.315644) (xy 92.66302 -297.448486) (xy 92.663518 -297.515026) (xy 131.195582 -297.515026)
			(xy 131.199563 -297.382006) (xy 131.211492 -297.249461) (xy 131.231327 -297.117868) (xy 131.258996 -296.987696)
			(xy 131.2944 -296.859411) (xy 131.337413 -296.733474) (xy 131.38788 -296.610335) (xy 131.445621 -296.490434)
			(xy 131.51043 -296.374201) (xy 131.582074 -296.262051) (xy 131.660296 -296.154387) (xy 131.744817 -296.051594)
			(xy 131.835335 -295.954039) (xy 131.931524 -295.862073) (xy 132.033042 -295.776023) (xy 132.139523 -295.696199)
			(xy 132.250588 -295.622886) (xy 132.365839 -295.556346) (xy 132.484863 -295.496817) (xy 132.607234 -295.444513)
			(xy 132.732513 -295.399621) (xy 132.860254 -295.362302) (xy 132.989997 -295.332689) (xy 133.121279 -295.310888)
			(xy 133.25363 -295.296978) (xy 133.386576 -295.291007) (xy 133.519641 -295.292998) (xy 133.652349 -295.302943)
			(xy 133.784225 -295.320807) (xy 133.914796 -295.346525) (xy 134.043596 -295.380006) (xy 134.170162 -295.42113)
			(xy 134.294043 -295.46975) (xy 134.414794 -295.525691) (xy 134.531984 -295.588753) (xy 134.645193 -295.658711)
			(xy 134.754015 -295.735315) (xy 134.858061 -295.818289) (xy 134.956959 -295.907337) (xy 135.050354 -296.00214)
			(xy 135.137912 -296.102358) (xy 135.219321 -296.207634) (xy 135.294287 -296.31759) (xy 135.362544 -296.431832)
			(xy 135.423846 -296.549952) (xy 135.477975 -296.671527) (xy 135.524736 -296.796121) (xy 135.563962 -296.923289)
			(xy 135.595512 -297.052575) (xy 135.619275 -297.183516) (xy 135.635164 -297.315644) (xy 135.643122 -297.448486)
			(xy 135.64362 -297.515026) (xy 336.155548 -297.515026) (xy 336.159529 -297.382006) (xy 336.171458 -297.249461)
			(xy 336.191293 -297.117868) (xy 336.218962 -296.987696) (xy 336.254366 -296.859411) (xy 336.297379 -296.733474)
			(xy 336.347846 -296.610335) (xy 336.405587 -296.490434) (xy 336.470396 -296.374201) (xy 336.54204 -296.262051)
			(xy 336.620262 -296.154387) (xy 336.704783 -296.051594) (xy 336.795301 -295.954039) (xy 336.89149 -295.862073)
			(xy 336.993008 -295.776023) (xy 337.099489 -295.696199) (xy 337.210554 -295.622886) (xy 337.325805 -295.556346)
			(xy 337.444829 -295.496817) (xy 337.5672 -295.444513) (xy 337.692479 -295.399621) (xy 337.82022 -295.362302)
			(xy 337.949963 -295.332689) (xy 338.081245 -295.310888) (xy 338.213596 -295.296978) (xy 338.346542 -295.291007)
			(xy 338.479607 -295.292998) (xy 338.612315 -295.302943) (xy 338.744191 -295.320807) (xy 338.874762 -295.346525)
			(xy 339.003562 -295.380006) (xy 339.130128 -295.42113) (xy 339.254009 -295.46975) (xy 339.37476 -295.525691)
			(xy 339.49195 -295.588753) (xy 339.605159 -295.658711) (xy 339.713981 -295.735315) (xy 339.818027 -295.818289)
			(xy 339.916925 -295.907337) (xy 340.01032 -296.00214) (xy 340.097878 -296.102358) (xy 340.179287 -296.207634)
			(xy 340.254253 -296.31759) (xy 340.32251 -296.431832) (xy 340.383812 -296.549952) (xy 340.437941 -296.671527)
			(xy 340.484702 -296.796121) (xy 340.523928 -296.923289) (xy 340.555478 -297.052575) (xy 340.579241 -297.183516)
			(xy 340.59513 -297.315644) (xy 340.603088 -297.448486) (xy 340.603586 -297.515026) (xy 379.13565 -297.515026)
			(xy 379.139631 -297.382006) (xy 379.15156 -297.249461) (xy 379.171395 -297.117868) (xy 379.199064 -296.987696)
			(xy 379.234468 -296.859411) (xy 379.277481 -296.733474) (xy 379.327948 -296.610335) (xy 379.385689 -296.490434)
			(xy 379.450498 -296.374201) (xy 379.522142 -296.262051) (xy 379.600364 -296.154387) (xy 379.684885 -296.051594)
			(xy 379.775403 -295.954039) (xy 379.871592 -295.862073) (xy 379.97311 -295.776023) (xy 380.079591 -295.696199)
			(xy 380.190656 -295.622886) (xy 380.305907 -295.556346) (xy 380.424931 -295.496817) (xy 380.547302 -295.444513)
			(xy 380.672581 -295.399621) (xy 380.800322 -295.362302) (xy 380.930065 -295.332689) (xy 381.061347 -295.310888)
			(xy 381.193698 -295.296978) (xy 381.326644 -295.291007) (xy 381.459709 -295.292998) (xy 381.592417 -295.302943)
			(xy 381.724293 -295.320807) (xy 381.854864 -295.346525) (xy 381.983664 -295.380006) (xy 382.11023 -295.42113)
			(xy 382.234111 -295.46975) (xy 382.354862 -295.525691) (xy 382.472052 -295.588753) (xy 382.585261 -295.658711)
			(xy 382.694083 -295.735315) (xy 382.798129 -295.818289) (xy 382.897027 -295.907337) (xy 382.990422 -296.00214)
			(xy 383.07798 -296.102358) (xy 383.159389 -296.207634) (xy 383.234355 -296.31759) (xy 383.302612 -296.431832)
			(xy 383.363914 -296.549952) (xy 383.418043 -296.671527) (xy 383.464804 -296.796121) (xy 383.50403 -296.923289)
			(xy 383.53558 -297.052575) (xy 383.559343 -297.183516) (xy 383.575232 -297.315644) (xy 383.58319 -297.448486)
			(xy 383.583688 -297.515026) (xy 383.58319 -297.581566) (xy 383.575232 -297.714408) (xy 383.559343 -297.846536)
			(xy 383.53558 -297.977477) (xy 383.50403 -298.106763) (xy 383.464804 -298.233931) (xy 383.418043 -298.358525)
			(xy 383.363914 -298.4801) (xy 383.302612 -298.59822) (xy 383.234355 -298.712462) (xy 383.159389 -298.822418)
			(xy 383.07798 -298.927694) (xy 382.990422 -299.027912) (xy 382.897027 -299.122715) (xy 382.798129 -299.211763)
			(xy 382.694083 -299.294737) (xy 382.585261 -299.371341) (xy 382.472052 -299.441299) (xy 382.354862 -299.504361)
			(xy 382.234111 -299.560302) (xy 382.11023 -299.608922) (xy 381.983664 -299.650046) (xy 381.854864 -299.683527)
			(xy 381.724293 -299.709245) (xy 381.592417 -299.727109) (xy 381.459709 -299.737054) (xy 381.326644 -299.739045)
			(xy 381.193698 -299.733074) (xy 381.061347 -299.719164) (xy 380.930065 -299.697363) (xy 380.800322 -299.66775)
			(xy 380.672581 -299.630431) (xy 380.547302 -299.585539) (xy 380.424931 -299.533235) (xy 380.305907 -299.473706)
			(xy 380.190656 -299.407166) (xy 380.079591 -299.333853) (xy 379.97311 -299.254029) (xy 379.871592 -299.167979)
			(xy 379.775403 -299.076013) (xy 379.684885 -298.978458) (xy 379.600364 -298.875665) (xy 379.522142 -298.768001)
			(xy 379.450498 -298.655851) (xy 379.385689 -298.539618) (xy 379.327948 -298.419717) (xy 379.277481 -298.296578)
			(xy 379.234468 -298.170641) (xy 379.199064 -298.042356) (xy 379.171395 -297.912184) (xy 379.15156 -297.780591)
			(xy 379.139631 -297.648046) (xy 379.13565 -297.515026) (xy 340.603586 -297.515026) (xy 340.603088 -297.581566)
			(xy 340.59513 -297.714408) (xy 340.579241 -297.846536) (xy 340.555478 -297.977477) (xy 340.523928 -298.106763)
			(xy 340.484702 -298.233931) (xy 340.437941 -298.358525) (xy 340.383812 -298.4801) (xy 340.32251 -298.59822)
			(xy 340.254253 -298.712462) (xy 340.179287 -298.822418) (xy 340.097878 -298.927694) (xy 340.01032 -299.027912)
			(xy 339.916925 -299.122715) (xy 339.818027 -299.211763) (xy 339.713981 -299.294737) (xy 339.605159 -299.371341)
			(xy 339.49195 -299.441299) (xy 339.37476 -299.504361) (xy 339.254009 -299.560302) (xy 339.130128 -299.608922)
			(xy 339.003562 -299.650046) (xy 338.874762 -299.683527) (xy 338.744191 -299.709245) (xy 338.612315 -299.727109)
			(xy 338.479607 -299.737054) (xy 338.346542 -299.739045) (xy 338.213596 -299.733074) (xy 338.081245 -299.719164)
			(xy 337.949963 -299.697363) (xy 337.82022 -299.66775) (xy 337.692479 -299.630431) (xy 337.5672 -299.585539)
			(xy 337.444829 -299.533235) (xy 337.325805 -299.473706) (xy 337.210554 -299.407166) (xy 337.099489 -299.333853)
			(xy 336.993008 -299.254029) (xy 336.89149 -299.167979) (xy 336.795301 -299.076013) (xy 336.704783 -298.978458)
			(xy 336.620262 -298.875665) (xy 336.54204 -298.768001) (xy 336.470396 -298.655851) (xy 336.405587 -298.539618)
			(xy 336.347846 -298.419717) (xy 336.297379 -298.296578) (xy 336.254366 -298.170641) (xy 336.218962 -298.042356)
			(xy 336.191293 -297.912184) (xy 336.171458 -297.780591) (xy 336.159529 -297.648046) (xy 336.155548 -297.515026)
			(xy 135.64362 -297.515026) (xy 135.643122 -297.581566) (xy 135.635164 -297.714408) (xy 135.619275 -297.846536)
			(xy 135.595512 -297.977477) (xy 135.563962 -298.106763) (xy 135.524736 -298.233931) (xy 135.477975 -298.358525)
			(xy 135.423846 -298.4801) (xy 135.362544 -298.59822) (xy 135.294287 -298.712462) (xy 135.219321 -298.822418)
			(xy 135.137912 -298.927694) (xy 135.050354 -299.027912) (xy 134.956959 -299.122715) (xy 134.858061 -299.211763)
			(xy 134.754015 -299.294737) (xy 134.645193 -299.371341) (xy 134.531984 -299.441299) (xy 134.414794 -299.504361)
			(xy 134.294043 -299.560302) (xy 134.170162 -299.608922) (xy 134.043596 -299.650046) (xy 133.914796 -299.683527)
			(xy 133.784225 -299.709245) (xy 133.652349 -299.727109) (xy 133.519641 -299.737054) (xy 133.386576 -299.739045)
			(xy 133.25363 -299.733074) (xy 133.121279 -299.719164) (xy 132.989997 -299.697363) (xy 132.860254 -299.66775)
			(xy 132.732513 -299.630431) (xy 132.607234 -299.585539) (xy 132.484863 -299.533235) (xy 132.365839 -299.473706)
			(xy 132.250588 -299.407166) (xy 132.139523 -299.333853) (xy 132.033042 -299.254029) (xy 131.931524 -299.167979)
			(xy 131.835335 -299.076013) (xy 131.744817 -298.978458) (xy 131.660296 -298.875665) (xy 131.582074 -298.768001)
			(xy 131.51043 -298.655851) (xy 131.445621 -298.539618) (xy 131.38788 -298.419717) (xy 131.337413 -298.296578)
			(xy 131.2944 -298.170641) (xy 131.258996 -298.042356) (xy 131.231327 -297.912184) (xy 131.211492 -297.780591)
			(xy 131.199563 -297.648046) (xy 131.195582 -297.515026) (xy 92.663518 -297.515026) (xy 92.66302 -297.581566)
			(xy 92.655062 -297.714408) (xy 92.639173 -297.846536) (xy 92.61541 -297.977477) (xy 92.58386 -298.106763)
			(xy 92.544634 -298.233931) (xy 92.497873 -298.358525) (xy 92.443744 -298.4801) (xy 92.382442 -298.59822)
			(xy 92.314185 -298.712462) (xy 92.239219 -298.822418) (xy 92.15781 -298.927694) (xy 92.070252 -299.027912)
			(xy 91.976857 -299.122715) (xy 91.877959 -299.211763) (xy 91.773913 -299.294737) (xy 91.665091 -299.371341)
			(xy 91.551882 -299.441299) (xy 91.434692 -299.504361) (xy 91.313941 -299.560302) (xy 91.19006 -299.608922)
			(xy 91.063494 -299.650046) (xy 90.934694 -299.683527) (xy 90.804123 -299.709245) (xy 90.672247 -299.727109)
			(xy 90.539539 -299.737054) (xy 90.406474 -299.739045) (xy 90.273528 -299.733074) (xy 90.141177 -299.719164)
			(xy 90.009895 -299.697363) (xy 89.880152 -299.66775) (xy 89.752411 -299.630431) (xy 89.627132 -299.585539)
			(xy 89.504761 -299.533235) (xy 89.385737 -299.473706) (xy 89.270486 -299.407166) (xy 89.159421 -299.333853)
			(xy 89.05294 -299.254029) (xy 88.951422 -299.167979) (xy 88.855233 -299.076013) (xy 88.764715 -298.978458)
			(xy 88.680194 -298.875665) (xy 88.601972 -298.768001) (xy 88.530328 -298.655851) (xy 88.465519 -298.539618)
			(xy 88.407778 -298.419717) (xy 88.357311 -298.296578) (xy 88.314298 -298.170641) (xy 88.278894 -298.042356)
			(xy 88.251225 -297.912184) (xy 88.23139 -297.780591) (xy 88.219461 -297.648046) (xy 88.21548 -297.515026)
			(xy 2.509012 -297.515026) (xy 2.509012 -360.76382) (xy 4.226823 -360.76382) (xy 4.230819 -360.553934)
			(xy 4.242804 -360.344352) (xy 4.262758 -360.135378) (xy 4.290654 -359.927316) (xy 4.326451 -359.720466)
			(xy 4.370096 -359.515129) (xy 4.421528 -359.311603) (xy 4.48067 -359.110182) (xy 4.547438 -358.911159)
			(xy 4.621734 -358.714822) (xy 4.703452 -358.521456) (xy 4.792471 -358.331341) (xy 4.888664 -358.144753)
			(xy 4.991891 -357.961962) (xy 5.102002 -357.783234) (xy 5.218837 -357.608827) (xy 5.342227 -357.438995)
			(xy 5.471994 -357.273983) (xy 5.607948 -357.114032) (xy 5.749894 -356.959372) (xy 5.897624 -356.810228)
			(xy 6.050926 -356.666817) (xy 6.209576 -356.529346) (xy 6.373345 -356.398014) (xy 6.541995 -356.273013)
			(xy 6.715281 -356.154522) (xy 6.892953 -356.042715) (xy 7.074753 -355.937753) (xy 7.260417 -355.839788)
			(xy 7.449675 -355.748963) (xy 7.642255 -355.665409) (xy 7.837876 -355.589246) (xy 8.036254 -355.520587)
			(xy 8.237103 -355.45953) (xy 8.44013 -355.406163) (xy 8.645043 -355.360565) (xy 8.851542 -355.3228)
			(xy 9.059329 -355.292925) (xy 9.268104 -355.270982) (xy 9.477562 -355.257003) (xy 9.687401 -355.251008)
			(xy 9.897315 -355.253007) (xy 10.107002 -355.262995) (xy 10.316156 -355.28096) (xy 10.524474 -355.306874)
			(xy 10.731655 -355.340699) (xy 10.937399 -355.382388) (xy 11.141405 -355.43188) (xy 11.34338 -355.489102)
			(xy 11.54303 -355.553972) (xy 11.740065 -355.626396) (xy 11.934201 -355.706269) (xy 12.125154 -355.793475)
			(xy 12.31265 -355.887887) (xy 12.496415 -355.989369) (xy 12.676183 -356.097773) (xy 12.851694 -356.212943)
			(xy 13.022693 -356.334711) (xy 13.188933 -356.4629) (xy 13.350172 -356.597326) (xy 13.506176 -356.737793)
			(xy 13.656719 -356.884097) (xy 13.801583 -357.036026) (xy 13.940558 -357.19336) (xy 14.073443 -357.355871)
			(xy 14.200044 -357.523324) (xy 14.320179 -357.695474) (xy 14.433673 -357.872074) (xy 14.540361 -358.052866)
			(xy 14.640088 -358.237589) (xy 14.732711 -358.425975) (xy 14.818095 -358.61775) (xy 14.896116 -358.812637)
			(xy 14.966661 -359.010353) (xy 15.029628 -359.210611) (xy 15.084925 -359.413121) (xy 15.132472 -359.61759)
			(xy 15.1722 -359.823721) (xy 15.204052 -360.031214) (xy 15.227982 -360.23977) (xy 15.243954 -360.449086)
			(xy 15.251946 -360.658858) (xy 15.252446 -360.76382) (xy 15.251946 -360.868782) (xy 15.243954 -361.078554)
			(xy 15.239789 -361.133136) (xy 121.446286 -361.133136) (xy 121.450375 -361.077254) (xy 121.462558 -361.022564)
			(xy 121.482574 -360.97023) (xy 121.509997 -360.921368) (xy 121.544242 -360.87702) (xy 121.584578 -360.83813)
			(xy 121.630148 -360.805528) (xy 121.679979 -360.779909) (xy 121.733009 -360.761817) (xy 121.788107 -360.75164)
			(xy 121.844101 -360.749594) (xy 121.899796 -360.755722) (xy 121.930771 -360.76382) (xy 211.161635 -360.76382)
			(xy 211.16566 -360.621628) (xy 211.177723 -360.479892) (xy 211.197786 -360.339066) (xy 211.225784 -360.1996)
			(xy 211.261628 -360.061941) (xy 211.305202 -359.926531) (xy 211.356367 -359.793803) (xy 211.41496 -359.664182)
			(xy 211.480791 -359.538084) (xy 211.553652 -359.415912) (xy 211.633307 -359.298058) (xy 211.719503 -359.184899)
			(xy 211.811962 -359.076797) (xy 211.91039 -358.9741) (xy 212.014469 -358.877136) (xy 212.123868 -358.786216)
			(xy 212.238236 -358.70163) (xy 212.357205 -358.62365) (xy 212.480396 -358.552526) (xy 212.607413 -358.488485)
			(xy 212.73785 -358.431733) (xy 212.871289 -358.382451) (xy 213.007302 -358.340797) (xy 213.145454 -358.306905)
			(xy 213.285303 -358.280884) (xy 213.426399 -358.262816) (xy 213.568291 -358.252759) (xy 213.710526 -358.250746)
			(xy 213.852646 -358.256783) (xy 213.994197 -358.270851) (xy 214.134726 -358.292905) (xy 214.273781 -358.322874)
			(xy 214.410919 -358.360662) (xy 214.545699 -358.406148) (xy 214.67769 -358.459186) (xy 214.806469 -358.519607)
			(xy 214.931623 -358.587216) (xy 215.052751 -358.661798) (xy 215.169467 -358.743114) (xy 215.281395 -358.830902)
			(xy 215.388177 -358.924882) (xy 215.489471 -359.024752) (xy 215.584952 -359.130194) (xy 215.674316 -359.240868)
			(xy 215.757274 -359.356421) (xy 215.833563 -359.476482) (xy 215.902937 -359.600667) (xy 215.965174 -359.728578)
			(xy 216.020075 -359.859805) (xy 216.067463 -359.993928) (xy 216.107188 -360.130517) (xy 216.139121 -360.269135)
			(xy 216.163162 -360.409337) (xy 216.179231 -360.550675) (xy 216.187279 -360.692696) (xy 216.187782 -360.76382)
			(xy 255.611635 -360.76382) (xy 255.61566 -360.621628) (xy 255.627723 -360.479892) (xy 255.647786 -360.339066)
			(xy 255.675784 -360.1996) (xy 255.711628 -360.061941) (xy 255.755202 -359.926531) (xy 255.806367 -359.793803)
			(xy 255.86496 -359.664182) (xy 255.930791 -359.538084) (xy 256.003652 -359.415912) (xy 256.083307 -359.298058)
			(xy 256.169503 -359.184899) (xy 256.261962 -359.076797) (xy 256.36039 -358.9741) (xy 256.464469 -358.877136)
			(xy 256.573868 -358.786216) (xy 256.688236 -358.70163) (xy 256.807205 -358.62365) (xy 256.930396 -358.552526)
			(xy 257.057413 -358.488485) (xy 257.18785 -358.431733) (xy 257.321289 -358.382451) (xy 257.457302 -358.340797)
			(xy 257.595454 -358.306905) (xy 257.735303 -358.280884) (xy 257.876399 -358.262816) (xy 258.018291 -358.252759)
			(xy 258.160526 -358.250746) (xy 258.302646 -358.256783) (xy 258.444197 -358.270851) (xy 258.584726 -358.292905)
			(xy 258.723781 -358.322874) (xy 258.860919 -358.360662) (xy 258.995699 -358.406148) (xy 259.12769 -358.459186)
			(xy 259.256469 -358.519607) (xy 259.381623 -358.587216) (xy 259.502751 -358.661798) (xy 259.619467 -358.743114)
			(xy 259.731395 -358.830902) (xy 259.838177 -358.924882) (xy 259.939471 -359.024752) (xy 260.034952 -359.130194)
			(xy 260.124316 -359.240868) (xy 260.207274 -359.356421) (xy 260.283563 -359.476482) (xy 260.352937 -359.600667)
			(xy 260.415174 -359.728578) (xy 260.470075 -359.859805) (xy 260.517463 -359.993928) (xy 260.557188 -360.130517)
			(xy 260.589121 -360.269135) (xy 260.613162 -360.409337) (xy 260.629231 -360.550675) (xy 260.637279 -360.692696)
			(xy 260.637782 -360.76382) (xy 260.637279 -360.834944) (xy 260.629231 -360.976965) (xy 260.613162 -361.118303)
			(xy 260.610619 -361.133136) (xy 369.3861 -361.133136) (xy 369.390189 -361.077254) (xy 369.402372 -361.022564)
			(xy 369.422388 -360.97023) (xy 369.449811 -360.921368) (xy 369.484056 -360.87702) (xy 369.524392 -360.83813)
			(xy 369.569962 -360.805528) (xy 369.619793 -360.779909) (xy 369.672823 -360.761817) (xy 369.727921 -360.75164)
			(xy 369.783915 -360.749594) (xy 369.83961 -360.755722) (xy 369.870585 -360.76382) (xy 456.565771 -360.76382)
			(xy 456.569767 -360.553934) (xy 456.581752 -360.344352) (xy 456.601706 -360.135378) (xy 456.629602 -359.927316)
			(xy 456.665399 -359.720466) (xy 456.709044 -359.515129) (xy 456.760476 -359.311603) (xy 456.819618 -359.110182)
			(xy 456.886386 -358.911159) (xy 456.960682 -358.714822) (xy 457.0424 -358.521456) (xy 457.131419 -358.331341)
			(xy 457.227612 -358.144753) (xy 457.330839 -357.961962) (xy 457.44095 -357.783234) (xy 457.557785 -357.608827)
			(xy 457.681175 -357.438995) (xy 457.810942 -357.273983) (xy 457.946896 -357.114032) (xy 458.088842 -356.959372)
			(xy 458.236572 -356.810228) (xy 458.389874 -356.666817) (xy 458.548524 -356.529346) (xy 458.712293 -356.398014)
			(xy 458.880943 -356.273013) (xy 459.054229 -356.154522) (xy 459.231901 -356.042715) (xy 459.413701 -355.937753)
			(xy 459.599365 -355.839788) (xy 459.788623 -355.748963) (xy 459.981203 -355.665409) (xy 460.176824 -355.589246)
			(xy 460.375202 -355.520587) (xy 460.576051 -355.45953) (xy 460.779078 -355.406163) (xy 460.983991 -355.360565)
			(xy 461.19049 -355.3228) (xy 461.398277 -355.292925) (xy 461.607052 -355.270982) (xy 461.81651 -355.257003)
			(xy 462.026349 -355.251008) (xy 462.236263 -355.253007) (xy 462.44595 -355.262995) (xy 462.655104 -355.28096)
			(xy 462.863422 -355.306874) (xy 463.070603 -355.340699) (xy 463.276347 -355.382388) (xy 463.480353 -355.43188)
			(xy 463.682328 -355.489102) (xy 463.881978 -355.553972) (xy 464.079013 -355.626396) (xy 464.273149 -355.706269)
			(xy 464.464102 -355.793475) (xy 464.651598 -355.887887) (xy 464.835363 -355.989369) (xy 465.015131 -356.097773)
			(xy 465.190642 -356.212943) (xy 465.361641 -356.334711) (xy 465.527881 -356.4629) (xy 465.68912 -356.597326)
			(xy 465.845124 -356.737793) (xy 465.995667 -356.884097) (xy 466.140531 -357.036026) (xy 466.279506 -357.19336)
			(xy 466.412391 -357.355871) (xy 466.538992 -357.523324) (xy 466.659127 -357.695474) (xy 466.772621 -357.872074)
			(xy 466.879309 -358.052866) (xy 466.979036 -358.237589) (xy 467.071659 -358.425975) (xy 467.157043 -358.61775)
			(xy 467.235064 -358.812637) (xy 467.305609 -359.010353) (xy 467.368576 -359.210611) (xy 467.423873 -359.413121)
			(xy 467.47142 -359.61759) (xy 467.511148 -359.823721) (xy 467.543 -360.031214) (xy 467.56693 -360.23977)
			(xy 467.582902 -360.449086) (xy 467.590894 -360.658858) (xy 467.591394 -360.76382) (xy 467.590894 -360.868782)
			(xy 467.582902 -361.078554) (xy 467.56693 -361.28787) (xy 467.543 -361.496426) (xy 467.511148 -361.703919)
			(xy 467.47142 -361.91005) (xy 467.423873 -362.114519) (xy 467.368576 -362.317029) (xy 467.305609 -362.517287)
			(xy 467.235064 -362.715003) (xy 467.157043 -362.90989) (xy 467.071659 -363.101665) (xy 466.979036 -363.290051)
			(xy 466.879309 -363.474774) (xy 466.772621 -363.655566) (xy 466.659127 -363.832166) (xy 466.538992 -364.004316)
			(xy 466.412391 -364.171769) (xy 466.279506 -364.33428) (xy 466.140531 -364.491614) (xy 465.995667 -364.643543)
			(xy 465.845124 -364.789847) (xy 465.68912 -364.930314) (xy 465.527881 -365.06474) (xy 465.361641 -365.192929)
			(xy 465.190642 -365.314697) (xy 465.015131 -365.429867) (xy 464.835363 -365.538271) (xy 464.651598 -365.639753)
			(xy 464.464102 -365.734165) (xy 464.273149 -365.821371) (xy 464.079013 -365.901244) (xy 463.881978 -365.973668)
			(xy 463.682328 -366.038538) (xy 463.480353 -366.09576) (xy 463.276347 -366.145252) (xy 463.070603 -366.186941)
			(xy 462.863422 -366.220766) (xy 462.655104 -366.24668) (xy 462.44595 -366.264645) (xy 462.236263 -366.274633)
			(xy 462.026349 -366.276632) (xy 461.81651 -366.270637) (xy 461.607052 -366.256658) (xy 461.398277 -366.234715)
			(xy 461.19049 -366.20484) (xy 460.983991 -366.167075) (xy 460.779078 -366.121477) (xy 460.576051 -366.06811)
			(xy 460.375202 -366.007053) (xy 460.176824 -365.938394) (xy 459.981203 -365.862231) (xy 459.788623 -365.778677)
			(xy 459.599365 -365.687852) (xy 459.413701 -365.589887) (xy 459.231901 -365.484925) (xy 459.054229 -365.373118)
			(xy 458.880943 -365.254627) (xy 458.712293 -365.129626) (xy 458.548524 -364.998294) (xy 458.389874 -364.860823)
			(xy 458.236572 -364.717412) (xy 458.088842 -364.568268) (xy 457.946896 -364.413608) (xy 457.810942 -364.253657)
			(xy 457.681175 -364.088645) (xy 457.557785 -363.918813) (xy 457.44095 -363.744406) (xy 457.330839 -363.565678)
			(xy 457.227612 -363.382887) (xy 457.131419 -363.196299) (xy 457.0424 -363.006184) (xy 456.960682 -362.812818)
			(xy 456.886386 -362.616481) (xy 456.819618 -362.417458) (xy 456.760476 -362.216037) (xy 456.709044 -362.012511)
			(xy 456.665399 -361.807174) (xy 456.629602 -361.600324) (xy 456.601706 -361.392262) (xy 456.581752 -361.183288)
			(xy 456.569767 -360.973706) (xy 456.565771 -360.76382) (xy 369.870585 -360.76382) (xy 369.893819 -360.769894)
			(xy 369.945387 -360.791808) (xy 369.993215 -360.820997) (xy 370.036283 -360.856838) (xy 370.073673 -360.898568)
			(xy 370.104589 -360.945298) (xy 370.128372 -360.996031) (xy 370.144514 -361.049687) (xy 370.152673 -361.105121)
			(xy 370.153184 -361.133136) (xy 370.152673 -361.161151) (xy 370.144514 -361.216585) (xy 370.128372 -361.270241)
			(xy 370.104589 -361.320974) (xy 370.073673 -361.367704) (xy 370.036283 -361.409434) (xy 369.993215 -361.445275)
			(xy 369.945387 -361.474464) (xy 369.893819 -361.496378) (xy 369.83961 -361.51055) (xy 369.783915 -361.516678)
			(xy 369.727921 -361.514632) (xy 369.672823 -361.504455) (xy 369.619793 -361.486363) (xy 369.569962 -361.460744)
			(xy 369.524392 -361.428142) (xy 369.484056 -361.389252) (xy 369.449811 -361.344904) (xy 369.422388 -361.296042)
			(xy 369.402372 -361.243708) (xy 369.390189 -361.189018) (xy 369.3861 -361.133136) (xy 260.610619 -361.133136)
			(xy 260.589121 -361.258505) (xy 260.557188 -361.397123) (xy 260.517463 -361.533712) (xy 260.470075 -361.667835)
			(xy 260.415174 -361.799062) (xy 260.352937 -361.926973) (xy 260.283563 -362.051158) (xy 260.207274 -362.171219)
			(xy 260.124316 -362.286772) (xy 260.034952 -362.397446) (xy 259.939471 -362.502888) (xy 259.838177 -362.602758)
			(xy 259.731395 -362.696738) (xy 259.619467 -362.784526) (xy 259.502751 -362.865842) (xy 259.381623 -362.940424)
			(xy 259.256469 -363.008033) (xy 259.12769 -363.068454) (xy 258.995699 -363.121492) (xy 258.860919 -363.166978)
			(xy 258.723781 -363.204766) (xy 258.584726 -363.234735) (xy 258.444197 -363.256789) (xy 258.302646 -363.270857)
			(xy 258.160526 -363.276894) (xy 258.018291 -363.274881) (xy 257.876399 -363.264824) (xy 257.735303 -363.246756)
			(xy 257.595454 -363.220735) (xy 257.457302 -363.186843) (xy 257.321289 -363.145189) (xy 257.18785 -363.095907)
			(xy 257.057413 -363.039155) (xy 256.930396 -362.975114) (xy 256.807205 -362.90399) (xy 256.688236 -362.82601)
			(xy 256.573868 -362.741424) (xy 256.464469 -362.650504) (xy 256.36039 -362.55354) (xy 256.261962 -362.450843)
			(xy 256.169503 -362.342741) (xy 256.083307 -362.229582) (xy 256.003652 -362.111728) (xy 255.930791 -361.989556)
			(xy 255.86496 -361.863458) (xy 255.806367 -361.733837) (xy 255.755202 -361.601109) (xy 255.711628 -361.465699)
			(xy 255.675784 -361.32804) (xy 255.647786 -361.188574) (xy 255.627723 -361.047748) (xy 255.61566 -360.906012)
			(xy 255.611635 -360.76382) (xy 216.187782 -360.76382) (xy 216.187279 -360.834944) (xy 216.179231 -360.976965)
			(xy 216.163162 -361.118303) (xy 216.139121 -361.258505) (xy 216.107188 -361.397123) (xy 216.067463 -361.533712)
			(xy 216.020075 -361.667835) (xy 215.965174 -361.799062) (xy 215.902937 -361.926973) (xy 215.833563 -362.051158)
			(xy 215.757274 -362.171219) (xy 215.674316 -362.286772) (xy 215.584952 -362.397446) (xy 215.489471 -362.502888)
			(xy 215.388177 -362.602758) (xy 215.281395 -362.696738) (xy 215.169467 -362.784526) (xy 215.052751 -362.865842)
			(xy 214.931623 -362.940424) (xy 214.806469 -363.008033) (xy 214.67769 -363.068454) (xy 214.545699 -363.121492)
			(xy 214.410919 -363.166978) (xy 214.273781 -363.204766) (xy 214.134726 -363.234735) (xy 213.994197 -363.256789)
			(xy 213.852646 -363.270857) (xy 213.710526 -363.276894) (xy 213.568291 -363.274881) (xy 213.426399 -363.264824)
			(xy 213.285303 -363.246756) (xy 213.145454 -363.220735) (xy 213.007302 -363.186843) (xy 212.871289 -363.145189)
			(xy 212.73785 -363.095907) (xy 212.607413 -363.039155) (xy 212.480396 -362.975114) (xy 212.357205 -362.90399)
			(xy 212.238236 -362.82601) (xy 212.123868 -362.741424) (xy 212.014469 -362.650504) (xy 211.91039 -362.55354)
			(xy 211.811962 -362.450843) (xy 211.719503 -362.342741) (xy 211.633307 -362.229582) (xy 211.553652 -362.111728)
			(xy 211.480791 -361.989556) (xy 211.41496 -361.863458) (xy 211.356367 -361.733837) (xy 211.305202 -361.601109)
			(xy 211.261628 -361.465699) (xy 211.225784 -361.32804) (xy 211.197786 -361.188574) (xy 211.177723 -361.047748)
			(xy 211.16566 -360.906012) (xy 211.161635 -360.76382) (xy 121.930771 -360.76382) (xy 121.954005 -360.769894)
			(xy 122.005573 -360.791808) (xy 122.053401 -360.820997) (xy 122.096469 -360.856838) (xy 122.133859 -360.898568)
			(xy 122.164775 -360.945298) (xy 122.188558 -360.996031) (xy 122.2047 -361.049687) (xy 122.212859 -361.105121)
			(xy 122.21337 -361.133136) (xy 122.212859 -361.161151) (xy 122.2047 -361.216585) (xy 122.188558 -361.270241)
			(xy 122.164775 -361.320974) (xy 122.133859 -361.367704) (xy 122.096469 -361.409434) (xy 122.053401 -361.445275)
			(xy 122.005573 -361.474464) (xy 121.954005 -361.496378) (xy 121.899796 -361.51055) (xy 121.844101 -361.516678)
			(xy 121.788107 -361.514632) (xy 121.733009 -361.504455) (xy 121.679979 -361.486363) (xy 121.630148 -361.460744)
			(xy 121.584578 -361.428142) (xy 121.544242 -361.389252) (xy 121.509997 -361.344904) (xy 121.482574 -361.296042)
			(xy 121.462558 -361.243708) (xy 121.450375 -361.189018) (xy 121.446286 -361.133136) (xy 15.239789 -361.133136)
			(xy 15.227982 -361.28787) (xy 15.204052 -361.496426) (xy 15.1722 -361.703919) (xy 15.132472 -361.91005)
			(xy 15.084925 -362.114519) (xy 15.029628 -362.317029) (xy 14.966661 -362.517287) (xy 14.896116 -362.715003)
			(xy 14.818095 -362.90989) (xy 14.732711 -363.101665) (xy 14.640088 -363.290051) (xy 14.540361 -363.474774)
			(xy 14.433673 -363.655566) (xy 14.320179 -363.832166) (xy 14.200044 -364.004316) (xy 14.073443 -364.171769)
			(xy 13.940558 -364.33428) (xy 13.801583 -364.491614) (xy 13.656719 -364.643543) (xy 13.506176 -364.789847)
			(xy 13.350172 -364.930314) (xy 13.188933 -365.06474) (xy 13.022693 -365.192929) (xy 12.851694 -365.314697)
			(xy 12.676183 -365.429867) (xy 12.496415 -365.538271) (xy 12.31265 -365.639753) (xy 12.125154 -365.734165)
			(xy 11.934201 -365.821371) (xy 11.740065 -365.901244) (xy 11.54303 -365.973668) (xy 11.34338 -366.038538)
			(xy 11.141405 -366.09576) (xy 10.937399 -366.145252) (xy 10.731655 -366.186941) (xy 10.524474 -366.220766)
			(xy 10.316156 -366.24668) (xy 10.107002 -366.264645) (xy 9.897315 -366.274633) (xy 9.687401 -366.276632)
			(xy 9.477562 -366.270637) (xy 9.268104 -366.256658) (xy 9.059329 -366.234715) (xy 8.851542 -366.20484)
			(xy 8.645043 -366.167075) (xy 8.44013 -366.121477) (xy 8.237103 -366.06811) (xy 8.036254 -366.007053)
			(xy 7.837876 -365.938394) (xy 7.642255 -365.862231) (xy 7.449675 -365.778677) (xy 7.260417 -365.687852)
			(xy 7.074753 -365.589887) (xy 6.892953 -365.484925) (xy 6.715281 -365.373118) (xy 6.541995 -365.254627)
			(xy 6.373345 -365.129626) (xy 6.209576 -364.998294) (xy 6.050926 -364.860823) (xy 5.897624 -364.717412)
			(xy 5.749894 -364.568268) (xy 5.607948 -364.413608) (xy 5.471994 -364.253657) (xy 5.342227 -364.088645)
			(xy 5.218837 -363.918813) (xy 5.102002 -363.744406) (xy 4.991891 -363.565678) (xy 4.888664 -363.382887)
			(xy 4.792471 -363.196299) (xy 4.703452 -363.006184) (xy 4.621734 -362.812818) (xy 4.547438 -362.616481)
			(xy 4.48067 -362.417458) (xy 4.421528 -362.216037) (xy 4.370096 -362.012511) (xy 4.326451 -361.807174)
			(xy 4.290654 -361.600324) (xy 4.262758 -361.392262) (xy 4.242804 -361.183288) (xy 4.230819 -360.973706)
			(xy 4.226823 -360.76382) (xy 2.509012 -360.76382) (xy 2.509012 -383.932484) (xy 8.539215 -383.932484)
			(xy 8.539215 -383.803344) (xy 8.547165 -383.674449) (xy 8.563035 -383.546289) (xy 8.586764 -383.419348)
			(xy 8.618263 -383.294109) (xy 8.657412 -383.171046) (xy 8.704063 -383.050627) (xy 8.758038 -382.933308)
			(xy 8.819133 -382.819534) (xy 8.887116 -382.709737) (xy 8.96173 -382.604334) (xy 9.042691 -382.503724)
			(xy 9.129691 -382.408289) (xy 9.222402 -382.31839) (xy 9.320472 -382.234369) (xy 9.423527 -382.156545)
			(xy 9.531178 -382.085213) (xy 9.643017 -382.020643) (xy 9.758618 -381.963081) (xy 9.877543 -381.912744)
			(xy 9.999342 -381.869824) (xy 10.123552 -381.834483) (xy 10.249701 -381.806856) (xy 10.377313 -381.787047)
			(xy 10.505902 -381.775131) (xy 10.63498 -381.771155) (xy 10.764058 -381.775131) (xy 10.892647 -381.787047)
			(xy 11.020259 -381.806856) (xy 11.146408 -381.834483) (xy 11.270618 -381.869824) (xy 11.392417 -381.912744)
			(xy 11.511342 -381.963081) (xy 11.626943 -382.020643) (xy 11.738782 -382.085213) (xy 11.846433 -382.156545)
			(xy 11.949488 -382.234369) (xy 12.047558 -382.31839) (xy 12.140269 -382.408289) (xy 12.227269 -382.503724)
			(xy 12.30823 -382.604334) (xy 12.382844 -382.709737) (xy 12.450827 -382.819534) (xy 12.505341 -382.921052)
			(xy 19.016679 -382.921052) (xy 19.016679 -382.866548) (xy 19.024437 -382.812598) (xy 19.039793 -382.760301)
			(xy 19.062436 -382.710722) (xy 19.091904 -382.664871) (xy 19.127599 -382.62368) (xy 19.168792 -382.587989)
			(xy 19.214645 -382.558523) (xy 19.264226 -382.535884) (xy 19.316523 -382.520531) (xy 19.370474 -382.512778)
			(xy 19.397726 -382.512316) (xy 20.261326 -382.512316) (xy 20.288578 -382.512756) (xy 20.342526 -382.520516)
			(xy 20.394821 -382.535874) (xy 20.444398 -382.558518) (xy 20.490248 -382.587987) (xy 20.531438 -382.623681)
			(xy 20.567129 -382.664873) (xy 20.596594 -382.710725) (xy 20.619235 -382.760303) (xy 20.63459 -382.812599)
			(xy 20.642346 -382.866548) (xy 20.642346 -382.921052) (xy 20.636681 -382.960459) (xy 22.291788 -382.960459)
			(xy 22.291788 -382.905921) (xy 22.29955 -382.851938) (xy 22.314915 -382.79961) (xy 22.337571 -382.75)
			(xy 22.367056 -382.70412) (xy 22.40277 -382.662903) (xy 22.443987 -382.627188) (xy 22.489867 -382.597702)
			(xy 22.539476 -382.575046) (xy 22.591804 -382.559681) (xy 22.645787 -382.551919) (xy 22.673056 -382.551432)
			(xy 23.536656 -382.551432) (xy 23.563927 -382.551887) (xy 23.617915 -382.559649) (xy 23.670249 -382.575015)
			(xy 23.719863 -382.597673) (xy 23.765748 -382.62716) (xy 23.806969 -382.662878) (xy 23.842687 -382.704099)
			(xy 23.872175 -382.749983) (xy 23.894834 -382.799597) (xy 23.9102 -382.851931) (xy 23.917962 -382.905919)
			(xy 23.917962 -382.960461) (xy 23.9102 -383.014449) (xy 23.894834 -383.066783) (xy 23.872175 -383.116397)
			(xy 23.842687 -383.162281) (xy 23.806969 -383.203502) (xy 23.765748 -383.23922) (xy 23.719863 -383.268707)
			(xy 23.670249 -383.291365) (xy 23.617915 -383.306731) (xy 23.563927 -383.314493) (xy 23.536656 -383.314956)
			(xy 22.673056 -383.314956) (xy 22.645787 -383.314461) (xy 22.591804 -383.306699) (xy 22.539476 -383.291334)
			(xy 22.489867 -383.268678) (xy 22.443987 -383.239192) (xy 22.40277 -383.203477) (xy 22.367056 -383.16226)
			(xy 22.337571 -383.11638) (xy 22.314915 -383.06677) (xy 22.29955 -383.014442) (xy 22.291788 -382.960459)
			(xy 20.636681 -382.960459) (xy 20.63459 -382.975001) (xy 20.619235 -383.027297) (xy 20.596594 -383.076875)
			(xy 20.567129 -383.122727) (xy 20.531438 -383.163919) (xy 20.490248 -383.199613) (xy 20.444398 -383.229082)
			(xy 20.394821 -383.251726) (xy 20.342526 -383.267084) (xy 20.288578 -383.274844) (xy 20.261326 -383.275332)
			(xy 19.397726 -383.275332) (xy 19.370474 -383.274822) (xy 19.316523 -383.267069) (xy 19.264226 -383.251716)
			(xy 19.214645 -383.229077) (xy 19.168792 -383.199611) (xy 19.127599 -383.16392) (xy 19.091904 -383.122729)
			(xy 19.062436 -383.076878) (xy 19.039793 -383.027299) (xy 19.024437 -382.975002) (xy 19.016679 -382.921052)
			(xy 12.505341 -382.921052) (xy 12.511922 -382.933308) (xy 12.565897 -383.050627) (xy 12.612548 -383.171046)
			(xy 12.651697 -383.294109) (xy 12.683196 -383.419348) (xy 12.706925 -383.546289) (xy 12.722795 -383.674449)
			(xy 12.730745 -383.803344) (xy 12.731242 -383.867914) (xy 12.730745 -383.932484) (xy 12.722795 -384.061379)
			(xy 12.706925 -384.189539) (xy 12.683196 -384.31648) (xy 12.651697 -384.441719) (xy 12.612548 -384.564782)
			(xy 12.565897 -384.685201) (xy 12.511922 -384.80252) (xy 12.450827 -384.916294) (xy 12.382844 -385.026091)
			(xy 12.30823 -385.131494) (xy 12.227269 -385.232104) (xy 12.140269 -385.327539) (xy 12.047558 -385.417438)
			(xy 11.949488 -385.501459) (xy 11.846433 -385.579283) (xy 11.738782 -385.650615) (xy 11.626943 -385.715185)
			(xy 11.511342 -385.772747) (xy 11.483943 -385.784344) (xy 19.460972 -385.784344) (xy 19.460972 -384.920744)
			(xy 19.461458 -384.893493) (xy 19.469214 -384.839545) (xy 19.484569 -384.78725) (xy 19.507211 -384.737673)
			(xy 19.536677 -384.691823) (xy 19.572368 -384.650632) (xy 19.613559 -384.614941) (xy 19.659409 -384.585475)
			(xy 19.708986 -384.562833) (xy 19.761281 -384.547478) (xy 19.815229 -384.539722) (xy 19.869731 -384.539722)
			(xy 19.923679 -384.547478) (xy 19.975974 -384.562833) (xy 20.025551 -384.585475) (xy 20.071401 -384.614941)
			(xy 20.112592 -384.650632) (xy 20.148283 -384.691823) (xy 20.177749 -384.737673) (xy 20.200391 -384.78725)
			(xy 20.215746 -384.839545) (xy 20.223502 -384.893493) (xy 20.223988 -384.920744) (xy 20.223988 -385.784344)
			(xy 20.22353 -385.809998) (xy 22.731984 -385.809998) (xy 22.731984 -384.946398) (xy 22.73247 -384.919147)
			(xy 22.740226 -384.865199) (xy 22.755581 -384.812904) (xy 22.778223 -384.763327) (xy 22.807689 -384.717477)
			(xy 22.84338 -384.676286) (xy 22.884571 -384.640595) (xy 22.930421 -384.611129) (xy 22.979998 -384.588487)
			(xy 23.032293 -384.573132) (xy 23.086241 -384.565376) (xy 23.140743 -384.565376) (xy 23.194691 -384.573132)
			(xy 23.246986 -384.588487) (xy 23.296563 -384.611129) (xy 23.342413 -384.640595) (xy 23.383604 -384.676286)
			(xy 23.419295 -384.717477) (xy 23.448761 -384.763327) (xy 23.471403 -384.812904) (xy 23.486758 -384.865199)
			(xy 23.494514 -384.919147) (xy 23.495 -384.946398) (xy 23.495 -385.440249) (xy 36.585674 -385.440249)
			(xy 36.585674 -385.385751) (xy 36.593429 -385.331807) (xy 36.608782 -385.279515) (xy 36.63142 -385.229941)
			(xy 36.660882 -385.184092) (xy 36.696569 -385.142903) (xy 36.737753 -385.107211) (xy 36.783598 -385.077743)
			(xy 36.83317 -385.055099) (xy 36.88546 -385.039739) (xy 36.939403 -385.031977) (xy 36.966652 -385.031488)
			(xy 37.830252 -385.031488) (xy 37.857507 -385.031956) (xy 37.911462 -385.039707) (xy 37.963765 -385.055059)
			(xy 38.013351 -385.077699) (xy 38.05921 -385.107165) (xy 38.100408 -385.142858) (xy 38.136106 -385.184052)
			(xy 38.165578 -385.229907) (xy 38.188224 -385.27949) (xy 38.203582 -385.331791) (xy 38.211341 -385.385745)
			(xy 38.211341 -385.440255) (xy 38.203582 -385.494209) (xy 38.188224 -385.54651) (xy 38.165578 -385.596093)
			(xy 38.16123 -385.602858) (xy 41.455211 -385.602858) (xy 41.455211 -385.548342) (xy 41.46297 -385.494381)
			(xy 41.47833 -385.442074) (xy 41.500978 -385.392486) (xy 41.530453 -385.346625) (xy 41.566155 -385.305427)
			(xy 41.607357 -385.269729) (xy 41.653221 -385.240259) (xy 41.702812 -385.217616) (xy 41.755121 -385.202261)
			(xy 41.809082 -385.194508) (xy 41.83634 -385.194048) (xy 42.69994 -385.194048) (xy 42.727186 -385.194625)
			(xy 42.781123 -385.202385) (xy 42.833407 -385.217742) (xy 42.882974 -385.240383) (xy 42.928814 -385.269847)
			(xy 42.969994 -385.305534) (xy 43.005677 -385.346718) (xy 43.035136 -385.392562) (xy 43.057772 -385.44213)
			(xy 43.073123 -385.494416) (xy 43.080878 -385.548354) (xy 43.080878 -385.602846) (xy 43.073123 -385.656784)
			(xy 43.057772 -385.70907) (xy 43.035136 -385.758638) (xy 43.005677 -385.804482) (xy 42.969994 -385.845666)
			(xy 42.928814 -385.881353) (xy 42.882974 -385.910817) (xy 42.833407 -385.933458) (xy 42.781123 -385.948815)
			(xy 42.727186 -385.956575) (xy 42.69994 -385.957064) (xy 41.83634 -385.957064) (xy 41.809082 -385.956692)
			(xy 41.755121 -385.948939) (xy 41.702812 -385.933584) (xy 41.653221 -385.910941) (xy 41.607357 -385.881471)
			(xy 41.566155 -385.845773) (xy 41.530453 -385.804575) (xy 41.500978 -385.758714) (xy 41.47833 -385.709126)
			(xy 41.46297 -385.656819) (xy 41.455211 -385.602858) (xy 38.16123 -385.602858) (xy 38.136106 -385.641948)
			(xy 38.100408 -385.683142) (xy 38.05921 -385.718835) (xy 38.013351 -385.748301) (xy 37.963765 -385.770941)
			(xy 37.911462 -385.786293) (xy 37.857507 -385.794044) (xy 37.830252 -385.794504) (xy 36.966652 -385.794504)
			(xy 36.939403 -385.794023) (xy 36.88546 -385.786261) (xy 36.83317 -385.770901) (xy 36.783598 -385.748257)
			(xy 36.737753 -385.718789) (xy 36.696569 -385.683097) (xy 36.660882 -385.641908) (xy 36.63142 -385.596059)
			(xy 36.608782 -385.546485) (xy 36.593429 -385.494193) (xy 36.585674 -385.440249) (xy 23.495 -385.440249)
			(xy 23.495 -385.809998) (xy 23.494514 -385.837249) (xy 23.486758 -385.891197) (xy 23.471403 -385.943492)
			(xy 23.448761 -385.993069) (xy 23.419295 -386.038919) (xy 23.383604 -386.08011) (xy 23.342413 -386.115801)
			(xy 23.296563 -386.145267) (xy 23.246986 -386.167909) (xy 23.194691 -386.183264) (xy 23.140743 -386.19102)
			(xy 23.086241 -386.19102) (xy 23.032293 -386.183264) (xy 22.979998 -386.167909) (xy 22.930421 -386.145267)
			(xy 22.884571 -386.115801) (xy 22.84338 -386.08011) (xy 22.807689 -386.038919) (xy 22.778223 -385.993069)
			(xy 22.755581 -385.943492) (xy 22.740226 -385.891197) (xy 22.73247 -385.837249) (xy 22.731984 -385.809998)
			(xy 20.22353 -385.809998) (xy 20.223502 -385.811595) (xy 20.215746 -385.865543) (xy 20.200391 -385.917838)
			(xy 20.177749 -385.967415) (xy 20.148283 -386.013265) (xy 20.112592 -386.054456) (xy 20.071401 -386.090147)
			(xy 20.025551 -386.119613) (xy 19.975974 -386.142255) (xy 19.923679 -386.15761) (xy 19.869731 -386.165366)
			(xy 19.815229 -386.165366) (xy 19.761281 -386.15761) (xy 19.708986 -386.142255) (xy 19.659409 -386.119613)
			(xy 19.613559 -386.090147) (xy 19.572368 -386.054456) (xy 19.536677 -386.013265) (xy 19.507211 -385.967415)
			(xy 19.484569 -385.917838) (xy 19.469214 -385.865543) (xy 19.461458 -385.811595) (xy 19.460972 -385.784344)
			(xy 11.483943 -385.784344) (xy 11.392417 -385.823084) (xy 11.270618 -385.866004) (xy 11.146408 -385.901345)
			(xy 11.020259 -385.928972) (xy 10.892647 -385.948781) (xy 10.764058 -385.960697) (xy 10.63498 -385.964674)
			(xy 10.505902 -385.960697) (xy 10.377313 -385.948781) (xy 10.249701 -385.928972) (xy 10.123552 -385.901345)
			(xy 9.999342 -385.866004) (xy 9.877543 -385.823084) (xy 9.758618 -385.772747) (xy 9.643017 -385.715185)
			(xy 9.531178 -385.650615) (xy 9.423527 -385.579283) (xy 9.320472 -385.501459) (xy 9.222402 -385.417438)
			(xy 9.129691 -385.327539) (xy 9.042691 -385.232104) (xy 8.96173 -385.131494) (xy 8.887116 -385.026091)
			(xy 8.819133 -384.916294) (xy 8.758038 -384.80252) (xy 8.704063 -384.685201) (xy 8.657412 -384.564782)
			(xy 8.618263 -384.441719) (xy 8.586764 -384.31648) (xy 8.563035 -384.189539) (xy 8.547165 -384.061379)
			(xy 8.539215 -383.932484) (xy 2.509012 -383.932484) (xy 2.509012 -389.402275) (xy 286.566098 -389.402275)
			(xy 286.566098 -389.317529) (xy 286.574154 -389.233168) (xy 286.590192 -389.149954) (xy 286.614067 -389.068641)
			(xy 286.645564 -388.989966) (xy 286.684397 -388.914642) (xy 286.730213 -388.843349) (xy 286.7826 -388.776735)
			(xy 286.84108 -388.715402) (xy 286.905127 -388.659906) (xy 286.974158 -388.610748) (xy 287.04755 -388.568376)
			(xy 287.124637 -388.533171) (xy 287.204721 -388.505454) (xy 287.287078 -388.485474) (xy 287.370961 -388.473414)
			(xy 287.45561 -388.469382) (xy 287.540259 -388.473414) (xy 287.624142 -388.485474) (xy 287.706499 -388.505454)
			(xy 287.786583 -388.533171) (xy 287.86367 -388.568376) (xy 287.937062 -388.610748) (xy 288.006093 -388.659906)
			(xy 288.07014 -388.715402) (xy 288.12862 -388.776735) (xy 288.181007 -388.843349) (xy 288.226823 -388.914642)
			(xy 288.265656 -388.989966) (xy 288.297153 -389.068641) (xy 288.321028 -389.149954) (xy 288.337066 -389.233168)
			(xy 288.345122 -389.317529) (xy 288.345626 -389.359902) (xy 288.345122 -389.402275) (xy 297.615098 -389.402275)
			(xy 297.615098 -389.317529) (xy 297.623154 -389.233168) (xy 297.639192 -389.149954) (xy 297.663067 -389.068641)
			(xy 297.694564 -388.989966) (xy 297.733397 -388.914642) (xy 297.779213 -388.843349) (xy 297.8316 -388.776735)
			(xy 297.89008 -388.715402) (xy 297.954127 -388.659906) (xy 298.023158 -388.610748) (xy 298.09655 -388.568376)
			(xy 298.173637 -388.533171) (xy 298.253721 -388.505454) (xy 298.336078 -388.485474) (xy 298.419961 -388.473414)
			(xy 298.50461 -388.469382) (xy 298.589259 -388.473414) (xy 298.673142 -388.485474) (xy 298.755499 -388.505454)
			(xy 298.835583 -388.533171) (xy 298.91267 -388.568376) (xy 298.986062 -388.610748) (xy 299.055093 -388.659906)
			(xy 299.11914 -388.715402) (xy 299.17762 -388.776735) (xy 299.230007 -388.843349) (xy 299.275823 -388.914642)
			(xy 299.314656 -388.989966) (xy 299.346153 -389.068641) (xy 299.370028 -389.149954) (xy 299.386066 -389.233168)
			(xy 299.394122 -389.317529) (xy 299.394626 -389.359902) (xy 299.394122 -389.402275) (xy 299.386066 -389.486636)
			(xy 299.370028 -389.56985) (xy 299.346153 -389.651163) (xy 299.314656 -389.729838) (xy 299.275823 -389.805162)
			(xy 299.230007 -389.876455) (xy 299.17762 -389.943069) (xy 299.11914 -390.004402) (xy 299.055093 -390.059898)
			(xy 298.986062 -390.109056) (xy 298.91267 -390.151428) (xy 298.835583 -390.186633) (xy 298.755499 -390.21435)
			(xy 298.673142 -390.23433) (xy 298.589259 -390.24639) (xy 298.50461 -390.250423) (xy 298.419961 -390.24639)
			(xy 298.336078 -390.23433) (xy 298.253721 -390.21435) (xy 298.173637 -390.186633) (xy 298.09655 -390.151428)
			(xy 298.023158 -390.109056) (xy 297.954127 -390.059898) (xy 297.89008 -390.004402) (xy 297.8316 -389.943069)
			(xy 297.779213 -389.876455) (xy 297.733397 -389.805162) (xy 297.694564 -389.729838) (xy 297.663067 -389.651163)
			(xy 297.639192 -389.56985) (xy 297.623154 -389.486636) (xy 297.615098 -389.402275) (xy 288.345122 -389.402275)
			(xy 288.337066 -389.486636) (xy 288.321028 -389.56985) (xy 288.297153 -389.651163) (xy 288.265656 -389.729838)
			(xy 288.226823 -389.805162) (xy 288.181007 -389.876455) (xy 288.12862 -389.943069) (xy 288.07014 -390.004402)
			(xy 288.006093 -390.059898) (xy 287.937062 -390.109056) (xy 287.86367 -390.151428) (xy 287.786583 -390.186633)
			(xy 287.706499 -390.21435) (xy 287.624142 -390.23433) (xy 287.540259 -390.24639) (xy 287.45561 -390.250423)
			(xy 287.370961 -390.24639) (xy 287.287078 -390.23433) (xy 287.204721 -390.21435) (xy 287.124637 -390.186633)
			(xy 287.04755 -390.151428) (xy 286.974158 -390.109056) (xy 286.905127 -390.059898) (xy 286.84108 -390.004402)
			(xy 286.7826 -389.943069) (xy 286.730213 -389.876455) (xy 286.684397 -389.805162) (xy 286.645564 -389.729838)
			(xy 286.614067 -389.651163) (xy 286.590192 -389.56985) (xy 286.574154 -389.486636) (xy 286.566098 -389.402275)
			(xy 2.509012 -389.402275) (xy 2.509012 -390.74852) (xy 289.828732 -390.74852) (xy 289.829157 -390.717787)
			(xy 289.836564 -390.656768) (xy 289.851272 -390.597088) (xy 289.873068 -390.539615) (xy 289.901633 -390.485189)
			(xy 289.93655 -390.434604) (xy 289.97731 -390.388596) (xy 290.023319 -390.347837) (xy 290.073907 -390.312922)
			(xy 290.128334 -390.28436) (xy 290.185807 -390.262566) (xy 290.245488 -390.24786) (xy 290.306507 -390.240455)
			(xy 290.33724 -390.240012) (xy 290.369283 -390.240508) (xy 290.432859 -390.248584) (xy 290.494917 -390.264579)
			(xy 290.554476 -390.288239) (xy 290.610594 -390.31919) (xy 290.662381 -390.356941) (xy 290.709019 -390.400896)
			(xy 290.749768 -390.450359) (xy 290.783985 -390.504546) (xy 290.811128 -390.562601) (xy 290.830767 -390.623604)
			(xy 290.842591 -390.686591) (xy 290.844986 -390.718548) (xy 290.846452 -390.733661) (xy 290.857061 -390.762093)
			(xy 290.875562 -390.786147) (xy 290.900318 -390.803698) (xy 290.929141 -390.813192) (xy 290.9443 -390.814052)
			(xy 290.977155 -390.815239) (xy 291.042167 -390.825028) (xy 291.105376 -390.843112) (xy 291.165728 -390.86919)
			(xy 291.222216 -390.902827) (xy 291.2739 -390.943462) (xy 291.319917 -390.990417) (xy 291.359501 -391.04291)
			(xy 291.391992 -391.100065) (xy 291.416847 -391.160931) (xy 291.433653 -391.224491) (xy 291.442129 -391.289688)
			(xy 291.442648 -391.32256) (xy 291.442106 -391.353289) (xy 291.434703 -391.414298) (xy 291.42 -391.473971)
			(xy 291.398212 -391.531436) (xy 291.369656 -391.585856) (xy 291.334748 -391.636437) (xy 291.293998 -391.682441)
			(xy 291.248 -391.723199) (xy 291.197424 -391.758114) (xy 291.143009 -391.786679) (xy 291.085547 -391.808477)
			(xy 291.025877 -391.823189) (xy 290.964869 -391.830602) (xy 290.93414 -391.831068) (xy 290.902098 -391.830516)
			(xy 290.838523 -391.822449) (xy 290.776465 -391.806463) (xy 290.716905 -391.78281) (xy 290.660787 -391.751866)
			(xy 290.608999 -391.71412) (xy 290.56236 -391.670169) (xy 290.521609 -391.620711) (xy 290.487392 -391.566526)
			(xy 290.460249 -391.508474) (xy 290.440611 -391.447473) (xy 290.428788 -391.384488) (xy 290.426394 -391.352532)
			(xy 290.424962 -391.337414) (xy 290.414346 -391.308979) (xy 290.395837 -391.284924) (xy 290.371072 -391.267376)
			(xy 290.342242 -391.257886) (xy 290.32708 -391.257028) (xy 290.294229 -391.25578) (xy 290.229223 -391.24599)
			(xy 290.166019 -391.227907) (xy 290.105673 -391.201832) (xy 290.049188 -391.1682) (xy 289.997507 -391.127571)
			(xy 289.95149 -391.080623) (xy 289.911906 -391.028137) (xy 289.879413 -390.97099) (xy 289.854553 -390.910132)
			(xy 289.837741 -390.846579) (xy 289.829256 -390.78139) (xy 289.828732 -390.74852) (xy 2.509012 -390.74852)
			(xy 2.509012 -394.8085) (xy 243.179528 -394.8085) (xy 243.183558 -394.723892) (xy 243.195613 -394.640051)
			(xy 243.215583 -394.557735) (xy 243.243287 -394.47769) (xy 243.278475 -394.400641) (xy 243.320827 -394.327286)
			(xy 243.36996 -394.258289) (xy 243.42543 -394.194274) (xy 243.486733 -394.135823) (xy 243.553315 -394.083463)
			(xy 243.624573 -394.03767) (xy 243.699861 -393.998857) (xy 243.778498 -393.967377) (xy 243.859771 -393.943515)
			(xy 243.942944 -393.927486) (xy 244.027264 -393.919435) (xy 244.069616 -393.918948) (xy 244.11084 -393.919417)
			(xy 244.192933 -393.927053) (xy 244.273968 -393.94225) (xy 244.35325 -393.964876) (xy 244.430099 -393.994739)
			(xy 244.503857 -394.031582) (xy 244.573891 -394.075088) (xy 244.639601 -394.124886) (xy 244.670326 -394.152374)
			(xy 244.677558 -394.158461) (xy 244.695171 -394.165287) (xy 244.714061 -394.165287) (xy 244.731674 -394.158461)
			(xy 244.738906 -394.152374) (xy 244.769639 -394.124894) (xy 244.835341 -394.075085) (xy 244.905371 -394.03157)
			(xy 244.979128 -393.994723) (xy 245.055977 -393.964858) (xy 245.13526 -393.942233) (xy 245.216297 -393.927041)
			(xy 245.298392 -393.919413) (xy 245.339616 -393.918948) (xy 245.380184 -393.919416) (xy 245.460981 -393.926807)
			(xy 245.54077 -393.941524) (xy 245.618888 -393.963447) (xy 245.694684 -393.992392) (xy 245.767529 -394.02812)
			(xy 245.836818 -394.070333) (xy 245.901975 -394.118681) (xy 245.962458 -394.172761) (xy 246.017765 -394.232125)
			(xy 246.067436 -394.296278) (xy 246.111059 -394.364689) (xy 246.130064 -394.400532) (xy 246.157157 -394.401367)
			(xy 246.21073 -394.409598) (xy 246.262601 -394.42532) (xy 246.31173 -394.448214) (xy 246.357129 -394.477824)
			(xy 246.397887 -394.513553) (xy 246.433186 -394.554684) (xy 246.462317 -394.600391) (xy 246.484695 -394.649758)
			(xy 246.499871 -394.701791) (xy 246.507539 -394.755447) (xy 246.508016 -394.782548) (xy 246.507582 -394.8085)
			(xy 249.114543 -394.8085) (xy 249.118574 -394.723896) (xy 249.130628 -394.640058) (xy 249.150596 -394.557746)
			(xy 249.178298 -394.477704) (xy 249.213483 -394.400658) (xy 249.255833 -394.327305) (xy 249.304963 -394.25831)
			(xy 249.360429 -394.194298) (xy 249.421729 -394.135847) (xy 249.488307 -394.083488) (xy 249.55956 -394.037695)
			(xy 249.634844 -393.998882) (xy 249.713476 -393.967401) (xy 249.794745 -393.943537) (xy 249.877914 -393.927506)
			(xy 249.96223 -393.919453) (xy 250.00458 -393.918948) (xy 250.045803 -393.919439) (xy 250.127896 -393.927072)
			(xy 250.20893 -393.942266) (xy 250.288212 -393.964889) (xy 250.365061 -393.994749) (xy 250.438819 -394.031588)
			(xy 250.508854 -394.075092) (xy 250.574564 -394.124887) (xy 250.60529 -394.152374) (xy 250.612522 -394.158461)
			(xy 250.630135 -394.165287) (xy 250.649025 -394.165287) (xy 250.666638 -394.158461) (xy 250.67387 -394.152374)
			(xy 250.704576 -394.124863) (xy 250.770283 -394.075057) (xy 250.840317 -394.031545) (xy 250.914078 -393.994701)
			(xy 250.990931 -393.96484) (xy 251.070218 -393.942219) (xy 251.151257 -393.927032) (xy 251.233355 -393.91941)
			(xy 251.27458 -393.918948) (xy 251.315219 -393.919386) (xy 251.396157 -393.926808) (xy 251.47608 -393.941582)
			(xy 251.554323 -393.963585) (xy 251.630232 -393.992634) (xy 251.703174 -394.028487) (xy 251.772542 -394.070844)
			(xy 251.837756 -394.119353) (xy 251.898274 -394.173608) (xy 251.95359 -394.233158) (xy 252.003243 -394.297505)
			(xy 252.046819 -394.366114) (xy 252.06579 -394.402056) (xy 252.086364 -394.401548) (xy 252.113582 -394.401996)
			(xy 252.167464 -394.409739) (xy 252.219695 -394.425073) (xy 252.269213 -394.447684) (xy 252.315007 -394.477114)
			(xy 252.356147 -394.512762) (xy 252.391793 -394.553902) (xy 252.421221 -394.599698) (xy 252.443832 -394.649216)
			(xy 252.459163 -394.701448) (xy 252.466905 -394.75533) (xy 252.467364 -394.782548) (xy 252.466916 -394.8085)
			(xy 255.049428 -394.8085) (xy 255.053459 -394.723891) (xy 255.065514 -394.640048) (xy 255.085484 -394.55773)
			(xy 255.11319 -394.477684) (xy 255.148379 -394.400634) (xy 255.190732 -394.327277) (xy 255.239868 -394.258279)
			(xy 255.295339 -394.194265) (xy 255.356645 -394.135813) (xy 255.423229 -394.083453) (xy 255.494489 -394.03766)
			(xy 255.56978 -393.998849) (xy 255.648419 -393.96737) (xy 255.729694 -393.943509) (xy 255.812869 -393.927482)
			(xy 255.897191 -393.919434) (xy 255.939544 -393.918948) (xy 255.980768 -393.919399) (xy 256.062862 -393.927038)
			(xy 256.143897 -393.942237) (xy 256.223179 -393.964866) (xy 256.300029 -393.994731) (xy 256.373786 -394.031576)
			(xy 256.44382 -394.075085) (xy 256.509529 -394.124885) (xy 256.540254 -394.152374) (xy 256.547486 -394.158461)
			(xy 256.565099 -394.165287) (xy 256.583989 -394.165287) (xy 256.601602 -394.158461) (xy 256.608834 -394.152374)
			(xy 256.639555 -394.12488) (xy 256.70526 -394.075073) (xy 256.775292 -394.031559) (xy 256.849049 -393.994713)
			(xy 256.925901 -393.96485) (xy 257.005185 -393.942227) (xy 257.086223 -393.927037) (xy 257.168319 -393.919412)
			(xy 257.209544 -393.918948) (xy 257.250365 -393.919407) (xy 257.331665 -393.926876) (xy 257.411938 -393.941765)
			(xy 257.490509 -393.963948) (xy 257.566715 -393.993239) (xy 257.639917 -394.029392) (xy 257.709496 -394.072102)
			(xy 257.774868 -394.121009) (xy 257.835483 -394.175702) (xy 257.890829 -394.235721) (xy 257.940442 -394.300559)
			(xy 257.983902 -394.369672) (xy 258.002786 -394.405866) (xy 258.01873 -394.403337) (xy 258.050905 -394.400664)
			(xy 258.067048 -394.400532) (xy 258.094337 -394.400926) (xy 258.148358 -394.408699) (xy 258.200723 -394.424081)
			(xy 258.250366 -394.446758) (xy 258.296278 -394.476268) (xy 258.337522 -394.512012) (xy 258.37326 -394.553261)
			(xy 258.402765 -394.599176) (xy 258.425436 -394.648822) (xy 258.440811 -394.701189) (xy 258.448577 -394.755211)
			(xy 258.448577 -394.8085) (xy 260.984428 -394.8085) (xy 260.988458 -394.723893) (xy 261.000513 -394.640052)
			(xy 261.020483 -394.557736) (xy 261.048186 -394.477692) (xy 261.083374 -394.400643) (xy 261.125725 -394.327288)
			(xy 261.174858 -394.258291) (xy 261.230327 -394.194277) (xy 261.29163 -394.135826) (xy 261.358212 -394.083466)
			(xy 261.429469 -394.037672) (xy 261.504756 -393.99886) (xy 261.583392 -393.967379) (xy 261.664664 -393.943516)
			(xy 261.747837 -393.927487) (xy 261.832156 -393.919436) (xy 261.874508 -393.918948) (xy 261.915732 -393.919422)
			(xy 261.997825 -393.927057) (xy 262.078859 -393.942253) (xy 262.158141 -393.964879) (xy 262.234991 -393.994741)
			(xy 262.308749 -394.031583) (xy 262.378783 -394.075089) (xy 262.444493 -394.124886) (xy 262.475218 -394.152374)
			(xy 262.48245 -394.158461) (xy 262.500063 -394.165287) (xy 262.518953 -394.165287) (xy 262.536566 -394.158461)
			(xy 262.543798 -394.152374) (xy 262.574534 -394.124897) (xy 262.640236 -394.075089) (xy 262.710266 -394.031574)
			(xy 262.784021 -393.994725) (xy 262.86087 -393.96486) (xy 262.940153 -393.942234) (xy 263.021189 -393.927042)
			(xy 263.103284 -393.919413) (xy 263.144508 -393.918948) (xy 263.185239 -393.919443) (xy 263.26636 -393.9269)
			(xy 263.346458 -393.941743) (xy 263.424865 -393.963847) (xy 263.500922 -393.993026) (xy 263.573993 -394.029037)
			(xy 263.643465 -394.071577) (xy 263.708758 -394.120291) (xy 263.769323 -394.174771) (xy 263.824654 -394.234559)
			(xy 263.874287 -394.299155) (xy 263.917806 -394.368019) (xy 263.936734 -394.404088) (xy 263.947933 -394.402872)
			(xy 263.970427 -394.401601) (xy 263.981692 -394.401548) (xy 264.008912 -394.401914) (xy 264.062799 -394.409661)
			(xy 264.115035 -394.424998) (xy 264.164556 -394.447612) (xy 264.210355 -394.477045) (xy 264.251499 -394.512695)
			(xy 264.287151 -394.553838) (xy 264.316584 -394.599637) (xy 264.3392 -394.649158) (xy 264.354537 -394.701393)
			(xy 264.362285 -394.75528) (xy 264.362285 -394.8085) (xy 266.919443 -394.8085) (xy 266.923474 -394.723896)
			(xy 266.935527 -394.640059) (xy 266.955496 -394.557747) (xy 266.983198 -394.477706) (xy 267.018382 -394.40066)
			(xy 267.060731 -394.327308) (xy 267.109861 -394.258313) (xy 267.165326 -394.194301) (xy 267.226625 -394.13585)
			(xy 267.293203 -394.083491) (xy 267.364456 -394.037698) (xy 267.439739 -393.998885) (xy 267.51837 -393.967403)
			(xy 267.599638 -393.943538) (xy 267.682807 -393.927507) (xy 267.767122 -393.919453) (xy 267.809472 -393.918948)
			(xy 267.850695 -393.919444) (xy 267.932787 -393.927077) (xy 268.013822 -393.942269) (xy 268.093103 -393.964892)
			(xy 268.169953 -393.994751) (xy 268.243711 -394.03159) (xy 268.313746 -394.075093) (xy 268.379456 -394.124888)
			(xy 268.410182 -394.152374) (xy 268.417414 -394.158461) (xy 268.435027 -394.165287) (xy 268.453917 -394.165287)
			(xy 268.47153 -394.158461) (xy 268.478762 -394.152374) (xy 268.509471 -394.124866) (xy 268.575178 -394.07506)
			(xy 268.645212 -394.031548) (xy 268.718971 -393.994703) (xy 268.795824 -393.964842) (xy 268.87511 -393.942221)
			(xy 268.95615 -393.927033) (xy 269.038247 -393.91941) (xy 269.079472 -393.918948) (xy 269.120039 -393.919454)
			(xy 269.200835 -393.92684) (xy 269.280624 -393.941554) (xy 269.35874 -393.963472) (xy 269.434536 -393.992414)
			(xy 269.507381 -394.028138) (xy 269.576671 -394.070348) (xy 269.641828 -394.118693) (xy 269.702312 -394.17277)
			(xy 269.757619 -394.232131) (xy 269.807291 -394.296282) (xy 269.850914 -394.36469) (xy 269.86992 -394.400532)
			(xy 269.897015 -394.401316) (xy 269.95059 -394.409555) (xy 270.002462 -394.425283) (xy 270.051591 -394.448184)
			(xy 270.096989 -394.477799) (xy 270.137747 -394.513533) (xy 270.173045 -394.554669) (xy 270.202175 -394.60038)
			(xy 270.224552 -394.64975) (xy 270.239727 -394.701787) (xy 270.247395 -394.755446) (xy 270.247872 -394.782548)
			(xy 270.24739 -394.8085) (xy 272.854328 -394.8085) (xy 272.858359 -394.723891) (xy 272.870414 -394.640048)
			(xy 272.890384 -394.557731) (xy 272.918089 -394.477686) (xy 272.953277 -394.400636) (xy 272.995631 -394.32728)
			(xy 273.044766 -394.258282) (xy 273.100237 -394.194267) (xy 273.161542 -394.135816) (xy 273.228125 -394.083456)
			(xy 273.299385 -394.037663) (xy 273.374675 -393.998851) (xy 273.453313 -393.967372) (xy 273.534587 -393.943511)
			(xy 273.617762 -393.927483) (xy 273.702084 -393.919434) (xy 273.744436 -393.918948) (xy 273.78566 -393.919404)
			(xy 273.867754 -393.927042) (xy 273.948789 -393.942241) (xy 274.028071 -393.964869) (xy 274.10492 -393.994734)
			(xy 274.178678 -394.031578) (xy 274.248712 -394.075086) (xy 274.314421 -394.124886) (xy 274.345146 -394.152374)
			(xy 274.352378 -394.158461) (xy 274.369991 -394.165287) (xy 274.388881 -394.165287) (xy 274.406494 -394.158461)
			(xy 274.413726 -394.152374) (xy 274.44445 -394.124884) (xy 274.510154 -394.075076) (xy 274.580186 -394.031562)
			(xy 274.653943 -393.994716) (xy 274.730794 -393.964852) (xy 274.810078 -393.942228) (xy 274.891116 -393.927038)
			(xy 274.973211 -393.919412) (xy 275.014436 -393.918948) (xy 275.055004 -393.9194) (xy 275.135802 -393.926792)
			(xy 275.215592 -393.941511) (xy 275.293709 -393.963435) (xy 275.369506 -393.992382) (xy 275.442351 -394.028112)
			(xy 275.51164 -394.070326) (xy 275.576797 -394.118675) (xy 275.63728 -394.172757) (xy 275.692586 -394.232122)
			(xy 275.742257 -394.296277) (xy 275.785879 -394.364688) (xy 275.804884 -394.400532) (xy 275.831978 -394.401349)
			(xy 275.885551 -394.409583) (xy 275.937423 -394.425306) (xy 275.986552 -394.448204) (xy 276.031951 -394.477815)
			(xy 276.072709 -394.513546) (xy 276.108007 -394.554678) (xy 276.137138 -394.600387) (xy 276.159515 -394.649755)
			(xy 276.174691 -394.70179) (xy 276.182359 -394.755447) (xy 276.182836 -394.782548) (xy 276.182385 -394.808456)
			(xy 278.916892 -394.808456) (xy 278.917356 -394.766262) (xy 278.925335 -394.682252) (xy 278.941234 -394.599376)
			(xy 278.964912 -394.518378) (xy 278.996156 -394.439987) (xy 279.034684 -394.364908) (xy 279.08015 -394.293815)
			(xy 279.132146 -394.227349) (xy 279.190203 -394.166106) (xy 279.2538 -394.110638) (xy 279.322365 -394.061443)
			(xy 279.395282 -394.018964) (xy 279.471894 -393.983582) (xy 279.551513 -393.955615) (xy 279.633423 -393.935316)
			(xy 279.675082 -393.9286) (xy 279.689459 -393.925944) (xy 279.715949 -393.913606) (xy 279.737852 -393.894262)
			(xy 279.753368 -393.869499) (xy 279.761223 -393.841352) (xy 279.760772 -393.812133) (xy 279.75687 -393.798044)
			(xy 279.744165 -393.755179) (xy 279.726399 -393.667554) (xy 279.717507 -393.578589) (xy 279.716992 -393.533884)
			(xy 279.717496 -393.491536) (xy 279.725547 -393.407222) (xy 279.741576 -393.324056) (xy 279.765437 -393.242789)
			(xy 279.796916 -393.164159) (xy 279.835727 -393.088878) (xy 279.881517 -393.017626) (xy 279.933873 -392.95105)
			(xy 279.992321 -392.889752) (xy 280.056331 -392.834287) (xy 280.125323 -392.785158) (xy 280.198673 -392.742809)
			(xy 280.275716 -392.707625) (xy 280.355755 -392.679923) (xy 280.438064 -392.659955) (xy 280.521899 -392.647902)
			(xy 280.6065 -392.643872) (xy 280.691101 -392.647902) (xy 280.774936 -392.659955) (xy 280.857245 -392.679923)
			(xy 280.937284 -392.707625) (xy 281.014327 -392.742809) (xy 281.087677 -392.785158) (xy 281.156669 -392.834287)
			(xy 281.220679 -392.889752) (xy 281.279127 -392.95105) (xy 281.331483 -393.017626) (xy 281.377273 -393.088878)
			(xy 281.416084 -393.164159) (xy 281.447563 -393.242789) (xy 281.471424 -393.324056) (xy 281.487453 -393.407222)
			(xy 281.495504 -393.491536) (xy 281.496008 -393.533884) (xy 281.495487 -393.576077) (xy 281.487514 -393.660085)
			(xy 281.47162 -393.74296) (xy 281.461756 -393.776708) (xy 289.471608 -393.776708) (xy 289.471608 -393.776454)
			(xy 289.47211 -393.744493) (xy 289.480121 -393.681075) (xy 289.496018 -393.619161) (xy 289.51955 -393.559728)
			(xy 289.550344 -393.503713) (xy 289.587917 -393.451998) (xy 289.631674 -393.405401) (xy 289.680927 -393.364656)
			(xy 289.734898 -393.330405) (xy 289.792737 -393.303188) (xy 289.85353 -393.283435) (xy 289.91632 -393.271457)
			(xy 289.980116 -393.267444) (xy 290.043912 -393.271457) (xy 290.106702 -393.283435) (xy 290.167495 -393.303188)
			(xy 290.225334 -393.330405) (xy 290.279305 -393.364656) (xy 290.328558 -393.405401) (xy 290.372315 -393.451998)
			(xy 290.409888 -393.503713) (xy 290.440682 -393.559728) (xy 290.464214 -393.619161) (xy 290.480111 -393.681075)
			(xy 290.488122 -393.744493) (xy 290.488624 -393.776454) (xy 290.488624 -393.7765) (xy 291.470768 -393.7765)
			(xy 291.474784 -393.712663) (xy 291.48677 -393.649832) (xy 291.506536 -393.589) (xy 291.533771 -393.531124)
			(xy 291.568045 -393.477118) (xy 291.608817 -393.427834) (xy 291.655445 -393.384049) (xy 291.707193 -393.346453)
			(xy 291.763245 -393.315639) (xy 291.822717 -393.292094) (xy 291.884671 -393.276188) (xy 291.94813 -393.268172)
			(xy 291.980112 -393.267692) (xy 292.010658 -393.268138) (xy 292.071311 -393.275449) (xy 292.13065 -393.289975)
			(xy 292.187822 -393.311508) (xy 292.242001 -393.339737) (xy 292.292406 -393.374254) (xy 292.338312 -393.414564)
			(xy 292.379057 -393.460084) (xy 292.396926 -393.484862) (xy 292.405296 -393.496027) (xy 292.426903 -393.51367)
			(xy 292.452477 -393.52481) (xy 292.480111 -393.528618) (xy 292.507745 -393.52481) (xy 292.533319 -393.51367)
			(xy 292.554926 -393.496027) (xy 292.563296 -393.484862) (xy 292.582389 -393.458454) (xy 292.626241 -393.410247)
			(xy 292.675892 -393.368039) (xy 292.730528 -393.332518) (xy 292.789254 -393.304269) (xy 292.851108 -393.283754)
			(xy 292.915076 -393.271309) (xy 292.98011 -393.267138) (xy 293.045144 -393.271309) (xy 293.109112 -393.283754)
			(xy 293.170966 -393.304269) (xy 293.229692 -393.332518) (xy 293.284328 -393.368039) (xy 293.333979 -393.410247)
			(xy 293.377831 -393.458454) (xy 293.396924 -393.484862) (xy 293.405294 -393.496027) (xy 293.426901 -393.51367)
			(xy 293.452475 -393.52481) (xy 293.480109 -393.528618) (xy 293.507743 -393.52481) (xy 293.533317 -393.51367)
			(xy 293.554924 -393.496027) (xy 293.563294 -393.484862) (xy 293.582387 -393.458454) (xy 293.626239 -393.410247)
			(xy 293.67589 -393.368039) (xy 293.730526 -393.332518) (xy 293.789252 -393.304269) (xy 293.851106 -393.283754)
			(xy 293.915074 -393.271309) (xy 293.980108 -393.267138) (xy 294.045142 -393.271309) (xy 294.10911 -393.283754)
			(xy 294.170964 -393.304269) (xy 294.22969 -393.332518) (xy 294.284326 -393.368039) (xy 294.333977 -393.410247)
			(xy 294.377829 -393.458454) (xy 294.396922 -393.484862) (xy 294.405292 -393.496027) (xy 294.426899 -393.51367)
			(xy 294.452473 -393.52481) (xy 294.480107 -393.528618) (xy 294.507741 -393.52481) (xy 294.533315 -393.51367)
			(xy 294.554922 -393.496027) (xy 294.563292 -393.484862) (xy 294.582385 -393.458454) (xy 294.626237 -393.410247)
			(xy 294.675888 -393.368039) (xy 294.730524 -393.332518) (xy 294.78925 -393.304269) (xy 294.851104 -393.283754)
			(xy 294.915072 -393.271309) (xy 294.980106 -393.267138) (xy 295.04514 -393.271309) (xy 295.109108 -393.283754)
			(xy 295.170962 -393.304269) (xy 295.229688 -393.332518) (xy 295.284324 -393.368039) (xy 295.333975 -393.410247)
			(xy 295.377827 -393.458454) (xy 295.39692 -393.484862) (xy 295.40529 -393.496027) (xy 295.426897 -393.51367)
			(xy 295.452471 -393.52481) (xy 295.480105 -393.528618) (xy 295.507739 -393.52481) (xy 295.533313 -393.51367)
			(xy 295.55492 -393.496027) (xy 295.56329 -393.484862) (xy 295.582383 -393.458454) (xy 295.626235 -393.410247)
			(xy 295.675886 -393.368039) (xy 295.730522 -393.332518) (xy 295.789248 -393.304269) (xy 295.851102 -393.283754)
			(xy 295.91507 -393.271309) (xy 295.980104 -393.267138) (xy 296.045138 -393.271309) (xy 296.109106 -393.283754)
			(xy 296.17096 -393.304269) (xy 296.229686 -393.332518) (xy 296.284322 -393.368039) (xy 296.333973 -393.410247)
			(xy 296.377825 -393.458454) (xy 296.396918 -393.484862) (xy 296.405288 -393.496027) (xy 296.426895 -393.51367)
			(xy 296.452469 -393.52481) (xy 296.480103 -393.528618) (xy 296.507737 -393.52481) (xy 296.533311 -393.51367)
			(xy 296.554918 -393.496027) (xy 296.563288 -393.484862) (xy 296.581151 -393.46008) (xy 296.621903 -393.414568)
			(xy 296.667813 -393.374265) (xy 296.71822 -393.339752) (xy 296.772399 -393.311525) (xy 296.829568 -393.289992)
			(xy 296.888906 -393.275462) (xy 296.949557 -393.268144) (xy 296.980102 -393.267692) (xy 297.012076 -393.268286)
			(xy 297.07552 -393.276301) (xy 297.137459 -393.292204) (xy 297.196916 -393.315745) (xy 297.252954 -393.346553)
			(xy 297.304689 -393.384141) (xy 297.351305 -393.427916) (xy 297.392067 -393.477189) (xy 297.426332 -393.531182)
			(xy 297.45356 -393.589044) (xy 297.473321 -393.649863) (xy 297.485304 -393.712678) (xy 297.489319 -393.7765)
			(xy 297.485304 -393.840322) (xy 297.473321 -393.903137) (xy 297.45356 -393.963956) (xy 297.426332 -394.021818)
			(xy 297.392067 -394.075811) (xy 297.351305 -394.125084) (xy 297.304689 -394.168859) (xy 297.252954 -394.206447)
			(xy 297.196916 -394.237255) (xy 297.137459 -394.260796) (xy 297.07552 -394.276699) (xy 297.012076 -394.284714)
			(xy 296.980102 -394.285216) (xy 296.949556 -394.284756) (xy 296.888904 -394.277447) (xy 296.829565 -394.262922)
			(xy 296.772394 -394.241392) (xy 296.718215 -394.213165) (xy 296.667809 -394.178649) (xy 296.621903 -394.138341)
			(xy 296.581158 -394.092823) (xy 296.563288 -394.068046) (xy 296.554946 -394.056837) (xy 296.53336 -394.03911)
			(xy 296.507771 -394.027912) (xy 296.480103 -394.024083) (xy 296.452435 -394.027912) (xy 296.426846 -394.03911)
			(xy 296.40526 -394.056837) (xy 296.396918 -394.068046) (xy 296.377825 -394.094454) (xy 296.333973 -394.142661)
			(xy 296.284322 -394.184869) (xy 296.229686 -394.22039) (xy 296.17096 -394.248639) (xy 296.109106 -394.269154)
			(xy 296.045138 -394.281599) (xy 295.980104 -394.28577) (xy 295.91507 -394.281599) (xy 295.851102 -394.269154)
			(xy 295.789248 -394.248639) (xy 295.730522 -394.22039) (xy 295.675886 -394.184869) (xy 295.626235 -394.142661)
			(xy 295.582383 -394.094454) (xy 295.56329 -394.068046) (xy 295.554948 -394.056837) (xy 295.533362 -394.03911)
			(xy 295.507773 -394.027912) (xy 295.480105 -394.024083) (xy 295.452437 -394.027912) (xy 295.426848 -394.03911)
			(xy 295.405262 -394.056837) (xy 295.39692 -394.068046) (xy 295.377827 -394.094454) (xy 295.333975 -394.142661)
			(xy 295.284324 -394.184869) (xy 295.229688 -394.22039) (xy 295.170962 -394.248639) (xy 295.109108 -394.269154)
			(xy 295.04514 -394.281599) (xy 294.980106 -394.28577) (xy 294.915072 -394.281599) (xy 294.851104 -394.269154)
			(xy 294.78925 -394.248639) (xy 294.730524 -394.22039) (xy 294.675888 -394.184869) (xy 294.626237 -394.142661)
			(xy 294.582385 -394.094454) (xy 294.563292 -394.068046) (xy 294.55495 -394.056837) (xy 294.533364 -394.03911)
			(xy 294.507775 -394.027912) (xy 294.480107 -394.024083) (xy 294.452439 -394.027912) (xy 294.42685 -394.03911)
			(xy 294.405264 -394.056837) (xy 294.396922 -394.068046) (xy 294.377829 -394.094454) (xy 294.333977 -394.142661)
			(xy 294.284326 -394.184869) (xy 294.22969 -394.22039) (xy 294.170964 -394.248639) (xy 294.10911 -394.269154)
			(xy 294.045142 -394.281599) (xy 293.980108 -394.28577) (xy 293.915074 -394.281599) (xy 293.851106 -394.269154)
			(xy 293.789252 -394.248639) (xy 293.730526 -394.22039) (xy 293.67589 -394.184869) (xy 293.626239 -394.142661)
			(xy 293.582387 -394.094454) (xy 293.563294 -394.068046) (xy 293.554952 -394.056837) (xy 293.533366 -394.03911)
			(xy 293.507777 -394.027912) (xy 293.480109 -394.024083) (xy 293.452441 -394.027912) (xy 293.426852 -394.03911)
			(xy 293.405266 -394.056837) (xy 293.396924 -394.068046) (xy 293.377831 -394.094454) (xy 293.333979 -394.142661)
			(xy 293.284328 -394.184869) (xy 293.229692 -394.22039) (xy 293.170966 -394.248639) (xy 293.109112 -394.269154)
			(xy 293.045144 -394.281599) (xy 292.98011 -394.28577) (xy 292.915076 -394.281599) (xy 292.851108 -394.269154)
			(xy 292.789254 -394.248639) (xy 292.730528 -394.22039) (xy 292.675892 -394.184869) (xy 292.626241 -394.142661)
			(xy 292.582389 -394.094454) (xy 292.563296 -394.068046) (xy 292.554954 -394.056837) (xy 292.533368 -394.03911)
			(xy 292.507779 -394.027912) (xy 292.480111 -394.024083) (xy 292.452443 -394.027912) (xy 292.426854 -394.03911)
			(xy 292.405268 -394.056837) (xy 292.396926 -394.068046) (xy 292.379057 -394.092823) (xy 292.338306 -394.138335)
			(xy 292.292396 -394.178638) (xy 292.24199 -394.213151) (xy 292.187812 -394.241378) (xy 292.130644 -394.262913)
			(xy 292.071307 -394.277444) (xy 292.010657 -394.284763) (xy 291.980112 -394.285216) (xy 291.94813 -394.284828)
			(xy 291.884671 -394.276812) (xy 291.822717 -394.260906) (xy 291.763245 -394.237361) (xy 291.707193 -394.206547)
			(xy 291.655445 -394.168951) (xy 291.608817 -394.125166) (xy 291.568045 -394.075882) (xy 291.533771 -394.021876)
			(xy 291.506536 -393.964) (xy 291.48677 -393.903168) (xy 291.474784 -393.840337) (xy 291.470768 -393.7765)
			(xy 290.488624 -393.7765) (xy 290.488624 -393.776962) (xy 290.488202 -393.806564) (xy 290.481324 -393.865367)
			(xy 290.467658 -393.922971) (xy 290.447389 -393.978597) (xy 290.420792 -394.03149) (xy 290.388226 -394.080932)
			(xy 290.369498 -394.10386) (xy 290.389588 -394.127178) (xy 290.424612 -394.17779) (xy 290.453267 -394.232263)
			(xy 290.475133 -394.289797) (xy 290.48989 -394.349552) (xy 290.497321 -394.410651) (xy 290.497768 -394.441426)
			(xy 290.497768 -394.44168) (xy 290.497266 -394.473641) (xy 290.489255 -394.537059) (xy 290.473358 -394.598973)
			(xy 290.449826 -394.658406) (xy 290.419032 -394.714421) (xy 290.381459 -394.766136) (xy 290.337702 -394.812733)
			(xy 290.288449 -394.853478) (xy 290.234478 -394.887729) (xy 290.176639 -394.914946) (xy 290.115846 -394.934699)
			(xy 290.053056 -394.946677) (xy 289.98926 -394.950691) (xy 289.925464 -394.946677) (xy 289.862674 -394.934699)
			(xy 289.801881 -394.914946) (xy 289.744042 -394.887729) (xy 289.690071 -394.853478) (xy 289.640818 -394.812733)
			(xy 289.597061 -394.766136) (xy 289.559488 -394.714421) (xy 289.528694 -394.658406) (xy 289.505162 -394.598973)
			(xy 289.489265 -394.537059) (xy 289.481254 -394.473641) (xy 289.480752 -394.44168) (xy 289.480752 -394.441172)
			(xy 289.481141 -394.411569) (xy 289.488026 -394.352765) (xy 289.501699 -394.29516) (xy 289.521974 -394.239535)
			(xy 289.548577 -394.186643) (xy 289.581148 -394.137202) (xy 289.599878 -394.114274) (xy 289.579769 -394.090972)
			(xy 289.544745 -394.040357) (xy 289.516091 -393.985882) (xy 289.494228 -393.928344) (xy 289.479476 -393.868586)
			(xy 289.472051 -393.807484) (xy 289.471608 -393.776708) (xy 281.461756 -393.776708) (xy 281.447947 -393.823957)
			(xy 281.416708 -393.902348) (xy 281.378185 -393.977427) (xy 281.332723 -394.04852) (xy 281.280732 -394.114986)
			(xy 281.222678 -394.176229) (xy 281.159084 -394.231698) (xy 281.090523 -394.280894) (xy 281.017609 -394.323374)
			(xy 280.941 -394.358757) (xy 280.861383 -394.386724) (xy 280.779476 -394.407024) (xy 280.737818 -394.41374)
			(xy 280.72343 -394.416347) (xy 280.696933 -394.428691) (xy 280.675026 -394.448046) (xy 280.659511 -394.472819)
			(xy 280.651661 -394.500977) (xy 280.652122 -394.530204) (xy 280.65603 -394.544296) (xy 280.668744 -394.587158)
			(xy 280.686507 -394.674785) (xy 280.695395 -394.763751) (xy 280.695908 -394.808456) (xy 280.695404 -394.850804)
			(xy 280.687353 -394.935118) (xy 280.671324 -395.018284) (xy 280.647463 -395.099551) (xy 280.615984 -395.178181)
			(xy 280.577173 -395.253462) (xy 280.531383 -395.324714) (xy 280.479027 -395.39129) (xy 280.420579 -395.452588)
			(xy 280.356569 -395.508053) (xy 280.287577 -395.557182) (xy 280.214227 -395.599531) (xy 280.137184 -395.634715)
			(xy 280.057145 -395.662417) (xy 279.974836 -395.682385) (xy 279.891001 -395.694438) (xy 279.8064 -395.698469)
			(xy 279.721799 -395.694438) (xy 279.637964 -395.682385) (xy 279.555655 -395.662417) (xy 279.475616 -395.634715)
			(xy 279.398573 -395.599531) (xy 279.325223 -395.557182) (xy 279.256231 -395.508053) (xy 279.192221 -395.452588)
			(xy 279.133773 -395.39129) (xy 279.081417 -395.324714) (xy 279.035627 -395.253462) (xy 278.996816 -395.178181)
			(xy 278.965337 -395.099551) (xy 278.941476 -395.018284) (xy 278.925447 -394.935118) (xy 278.917396 -394.850804)
			(xy 278.916892 -394.808456) (xy 276.182385 -394.808456) (xy 276.182339 -394.81111) (xy 276.173854 -394.867601)
			(xy 276.157051 -394.922198) (xy 276.132304 -394.973684) (xy 276.100165 -395.02091) (xy 276.061351 -395.062822)
			(xy 276.016728 -395.098487) (xy 275.967291 -395.127109) (xy 275.914142 -395.148048) (xy 275.858468 -395.160839)
			(xy 275.83003 -395.163548) (xy 275.812369 -395.202766) (xy 275.770577 -395.277947) (xy 275.721724 -395.348744)
			(xy 275.666266 -395.414494) (xy 275.60472 -395.474584) (xy 275.537661 -395.528453) (xy 275.465716 -395.575598)
			(xy 275.389556 -395.615578) (xy 275.309893 -395.648021) (xy 275.22747 -395.672622) (xy 275.143058 -395.689153)
			(xy 275.057444 -395.697459) (xy 275.014436 -395.697964) (xy 274.973213 -395.69746) (xy 274.891121 -395.689828)
			(xy 274.810087 -395.674636) (xy 274.730806 -395.652015) (xy 274.653956 -395.622157) (xy 274.580198 -395.585319)
			(xy 274.510163 -395.541817) (xy 274.444452 -395.492024) (xy 274.413726 -395.464538) (xy 274.406494 -395.458451)
			(xy 274.388881 -395.451625) (xy 274.369991 -395.451625) (xy 274.352378 -395.458451) (xy 274.345146 -395.464538)
			(xy 274.314435 -395.492044) (xy 274.248729 -395.54185) (xy 274.178695 -395.585362) (xy 274.104936 -395.622207)
			(xy 274.028083 -395.652068) (xy 273.948797 -395.67469) (xy 273.867758 -395.689878) (xy 273.785661 -395.697501)
			(xy 273.744436 -395.697964) (xy 273.702084 -395.697566) (xy 273.617762 -395.689517) (xy 273.534587 -395.673489)
			(xy 273.453313 -395.649628) (xy 273.374675 -395.618149) (xy 273.299385 -395.579337) (xy 273.228125 -395.533544)
			(xy 273.161542 -395.481184) (xy 273.100237 -395.422733) (xy 273.044766 -395.358718) (xy 272.995631 -395.28972)
			(xy 272.953277 -395.216364) (xy 272.918089 -395.139314) (xy 272.890384 -395.059269) (xy 272.870414 -394.976952)
			(xy 272.858359 -394.893109) (xy 272.854328 -394.8085) (xy 270.24739 -394.8085) (xy 270.247342 -394.811109)
			(xy 270.238858 -394.867596) (xy 270.222057 -394.922191) (xy 270.197312 -394.973674) (xy 270.165177 -395.020899)
			(xy 270.126367 -395.062811) (xy 270.081748 -395.098476) (xy 270.032316 -395.127099) (xy 269.979172 -395.148042)
			(xy 269.923503 -395.160836) (xy 269.895066 -395.163548) (xy 269.877376 -395.202752) (xy 269.835586 -395.277933)
			(xy 269.786736 -395.348729) (xy 269.73128 -395.414479) (xy 269.669737 -395.474569) (xy 269.602681 -395.528439)
			(xy 269.530739 -395.575585) (xy 269.454582 -395.615566) (xy 269.374921 -395.648011) (xy 269.292501 -395.672615)
			(xy 269.208091 -395.689148) (xy 269.122479 -395.697457) (xy 269.079472 -395.697964) (xy 269.038248 -395.6975)
			(xy 268.956155 -395.689862) (xy 268.87512 -395.674665) (xy 268.795838 -395.652037) (xy 268.718989 -395.622174)
			(xy 268.645231 -395.585331) (xy 268.575197 -395.541824) (xy 268.509487 -395.492026) (xy 268.478762 -395.464538)
			(xy 268.47153 -395.458451) (xy 268.453917 -395.451625) (xy 268.435027 -395.451625) (xy 268.417414 -395.458451)
			(xy 268.410182 -395.464538) (xy 268.379456 -395.492026) (xy 268.313752 -395.541834) (xy 268.243721 -395.585348)
			(xy 268.169964 -395.622194) (xy 268.093113 -395.652058) (xy 268.013829 -395.674682) (xy 267.932792 -395.689873)
			(xy 267.850696 -395.6975) (xy 267.809472 -395.697964) (xy 267.767122 -395.697547) (xy 267.682807 -395.689493)
			(xy 267.599638 -395.673462) (xy 267.51837 -395.649597) (xy 267.439739 -395.618115) (xy 267.364456 -395.579302)
			(xy 267.293203 -395.533509) (xy 267.226625 -395.48115) (xy 267.165326 -395.422699) (xy 267.109861 -395.358687)
			(xy 267.060731 -395.289692) (xy 267.018382 -395.21634) (xy 266.983198 -395.139294) (xy 266.955496 -395.059253)
			(xy 266.935527 -394.976941) (xy 266.923474 -394.893104) (xy 266.919443 -394.8085) (xy 264.362285 -394.8085)
			(xy 264.362285 -394.80972) (xy 264.354537 -394.863607) (xy 264.3392 -394.915842) (xy 264.316584 -394.965363)
			(xy 264.287151 -395.011162) (xy 264.251499 -395.052305) (xy 264.210355 -395.087955) (xy 264.164556 -395.117388)
			(xy 264.115035 -395.140002) (xy 264.062799 -395.155339) (xy 264.008912 -395.163086) (xy 263.981692 -395.163548)
			(xy 263.960356 -395.16304) (xy 263.942674 -395.202274) (xy 263.9009 -395.277517) (xy 263.852055 -395.348375)
			(xy 263.796597 -395.414185) (xy 263.735042 -395.474332) (xy 263.667968 -395.528254) (xy 263.596 -395.575447)
			(xy 263.519811 -395.61547) (xy 263.440113 -395.647949) (xy 263.357652 -395.67258) (xy 263.273197 -395.689134)
			(xy 263.187539 -395.697455) (xy 263.144508 -395.697964) (xy 263.103285 -395.697477) (xy 263.021192 -395.689843)
			(xy 262.940158 -395.674649) (xy 262.860876 -395.652025) (xy 262.784027 -395.622164) (xy 262.710269 -395.585324)
			(xy 262.640234 -395.54182) (xy 262.574524 -395.492025) (xy 262.543798 -395.464538) (xy 262.536566 -395.458451)
			(xy 262.518953 -395.451625) (xy 262.500063 -395.451625) (xy 262.48245 -395.458451) (xy 262.475218 -395.464538)
			(xy 262.444477 -395.492009) (xy 262.378775 -395.541818) (xy 262.308747 -395.585333) (xy 262.234992 -395.622182)
			(xy 262.158144 -395.652048) (xy 262.078861 -395.674675) (xy 261.997826 -395.689868) (xy 261.915732 -395.697498)
			(xy 261.874508 -395.697964) (xy 261.832156 -395.697564) (xy 261.747837 -395.689513) (xy 261.664664 -395.673484)
			(xy 261.583392 -395.649621) (xy 261.504756 -395.61814) (xy 261.429469 -395.579328) (xy 261.358212 -395.533534)
			(xy 261.29163 -395.481174) (xy 261.230327 -395.422723) (xy 261.174858 -395.358709) (xy 261.125725 -395.289712)
			(xy 261.083374 -395.216357) (xy 261.048186 -395.139308) (xy 261.020483 -395.059264) (xy 261.000513 -394.976948)
			(xy 260.988458 -394.893107) (xy 260.984428 -394.8085) (xy 258.448577 -394.8085) (xy 258.448577 -394.809789)
			(xy 258.440811 -394.863811) (xy 258.425436 -394.916178) (xy 258.402765 -394.965824) (xy 258.37326 -395.011739)
			(xy 258.337522 -395.052988) (xy 258.296278 -395.088732) (xy 258.250366 -395.118242) (xy 258.200723 -395.140919)
			(xy 258.148358 -395.156301) (xy 258.094337 -395.164074) (xy 258.067048 -395.164564) (xy 258.056676 -395.164479)
			(xy 258.035964 -395.163337) (xy 258.025646 -395.162278) (xy 258.008 -395.201564) (xy 257.966267 -395.276906)
			(xy 257.917448 -395.347861) (xy 257.861999 -395.413765) (xy 257.80044 -395.474001) (xy 257.733346 -395.528004)
			(xy 257.661347 -395.575269) (xy 257.585116 -395.615354) (xy 257.505368 -395.647883) (xy 257.422848 -395.672551)
			(xy 257.338331 -395.689127) (xy 257.252608 -395.697456) (xy 257.209544 -395.697964) (xy 257.168321 -395.697455)
			(xy 257.08623 -395.689824) (xy 257.005196 -395.674633) (xy 256.925914 -395.652012) (xy 256.849065 -395.622155)
			(xy 256.775306 -395.585317) (xy 256.705271 -395.541816) (xy 256.63956 -395.492023) (xy 256.608834 -395.464538)
			(xy 256.601602 -395.458451) (xy 256.583989 -395.451625) (xy 256.565099 -395.451625) (xy 256.547486 -395.458451)
			(xy 256.540254 -395.464538) (xy 256.50954 -395.49204) (xy 256.443834 -395.541846) (xy 256.373801 -395.585359)
			(xy 256.300042 -395.622204) (xy 256.22319 -395.652066) (xy 256.143904 -395.674688) (xy 256.062865 -395.689877)
			(xy 255.980769 -395.697501) (xy 255.939544 -395.697964) (xy 255.897191 -395.697566) (xy 255.812869 -395.689518)
			(xy 255.729694 -395.673491) (xy 255.648419 -395.64963) (xy 255.56978 -395.618151) (xy 255.494489 -395.57934)
			(xy 255.423229 -395.533547) (xy 255.356645 -395.481187) (xy 255.295339 -395.422735) (xy 255.239868 -395.358721)
			(xy 255.190732 -395.289723) (xy 255.148379 -395.216366) (xy 255.11319 -395.139316) (xy 255.085484 -395.05927)
			(xy 255.065514 -394.976952) (xy 255.053459 -394.893109) (xy 255.049428 -394.8085) (xy 252.466916 -394.8085)
			(xy 252.466897 -394.809592) (xy 252.459254 -394.863136) (xy 252.444116 -394.915061) (xy 252.421785 -394.964324)
			(xy 252.392711 -395.009932) (xy 252.357479 -395.05097) (xy 252.316797 -395.086613) (xy 252.271483 -395.116143)
			(xy 252.222447 -395.138967) (xy 252.170677 -395.154627) (xy 252.117212 -395.162807) (xy 252.090174 -395.163548)
			(xy 252.072477 -395.202749) (xy 252.030688 -395.27793) (xy 251.981838 -395.348725) (xy 251.926383 -395.414475)
			(xy 251.864841 -395.474566) (xy 251.797785 -395.528436) (xy 251.725844 -395.575582) (xy 251.649687 -395.615564)
			(xy 251.570027 -395.648009) (xy 251.487608 -395.672613) (xy 251.403198 -395.689147) (xy 251.317587 -395.697457)
			(xy 251.27458 -395.697964) (xy 251.233356 -395.697495) (xy 251.151263 -395.689858) (xy 251.070228 -395.674661)
			(xy 250.990947 -395.652035) (xy 250.914097 -395.622172) (xy 250.840339 -395.58533) (xy 250.770305 -395.541823)
			(xy 250.704595 -395.492026) (xy 250.67387 -395.464538) (xy 250.666638 -395.458451) (xy 250.649025 -395.451625)
			(xy 250.630135 -395.451625) (xy 250.612522 -395.458451) (xy 250.60529 -395.464538) (xy 250.574561 -395.492023)
			(xy 250.508857 -395.54183) (xy 250.438827 -395.585344) (xy 250.36507 -395.622192) (xy 250.28822 -395.652056)
			(xy 250.208936 -395.67468) (xy 250.127899 -395.689872) (xy 250.045804 -395.697499) (xy 250.00458 -395.697964)
			(xy 249.96223 -395.697547) (xy 249.877914 -395.689494) (xy 249.794745 -395.673463) (xy 249.713476 -395.649599)
			(xy 249.634844 -395.618118) (xy 249.55956 -395.579305) (xy 249.488307 -395.533512) (xy 249.421729 -395.481153)
			(xy 249.360429 -395.422702) (xy 249.304963 -395.35869) (xy 249.255833 -395.289695) (xy 249.213483 -395.216342)
			(xy 249.178298 -395.139296) (xy 249.150596 -395.059254) (xy 249.130628 -394.976942) (xy 249.118574 -394.893104)
			(xy 249.114543 -394.8085) (xy 246.507582 -394.8085) (xy 246.507538 -394.811111) (xy 246.499052 -394.867604)
			(xy 246.482248 -394.922202) (xy 246.457499 -394.973689) (xy 246.425358 -395.020916) (xy 246.386542 -395.062829)
			(xy 246.341916 -395.098493) (xy 246.292476 -395.127114) (xy 246.239326 -395.148052) (xy 246.183649 -395.16084)
			(xy 246.15521 -395.163548) (xy 246.137565 -395.202774) (xy 246.095772 -395.277955) (xy 246.046918 -395.348752)
			(xy 245.991458 -395.414502) (xy 245.929911 -395.474592) (xy 245.86285 -395.528461) (xy 245.790904 -395.575605)
			(xy 245.714742 -395.615585) (xy 245.635078 -395.648026) (xy 245.552653 -395.672626) (xy 245.46824 -395.689156)
			(xy 245.382624 -395.69746) (xy 245.339616 -395.697964) (xy 245.298393 -395.697472) (xy 245.216301 -395.689839)
			(xy 245.135266 -395.674645) (xy 245.055985 -395.652022) (xy 244.979135 -395.622162) (xy 244.905377 -395.585323)
			(xy 244.835342 -395.541819) (xy 244.769632 -395.492024) (xy 244.738906 -395.464538) (xy 244.731674 -395.458451)
			(xy 244.714061 -395.451625) (xy 244.695171 -395.451625) (xy 244.677558 -395.458451) (xy 244.670326 -395.464538)
			(xy 244.639624 -395.492053) (xy 244.573916 -395.541859) (xy 244.503881 -395.58537) (xy 244.43012 -395.622214)
			(xy 244.353266 -395.652074) (xy 244.273979 -395.674694) (xy 244.192939 -395.68988) (xy 244.110841 -395.697502)
			(xy 244.069616 -395.697964) (xy 244.027264 -395.697565) (xy 243.942944 -395.689514) (xy 243.859771 -395.673485)
			(xy 243.778498 -395.649623) (xy 243.699861 -395.618143) (xy 243.624573 -395.57933) (xy 243.553315 -395.533537)
			(xy 243.486733 -395.481177) (xy 243.42543 -395.422726) (xy 243.36996 -395.358711) (xy 243.320827 -395.289714)
			(xy 243.278475 -395.216359) (xy 243.243287 -395.13931) (xy 243.215583 -395.059265) (xy 243.195613 -394.976949)
			(xy 243.183558 -394.893108) (xy 243.179528 -394.8085) (xy 2.509012 -394.8085) (xy 2.509012 -396.842996)
			(xy 18.90268 -396.842996) (xy 18.90268 -395.979396) (xy 18.903166 -395.952145) (xy 18.910922 -395.898197)
			(xy 18.926277 -395.845902) (xy 18.948919 -395.796325) (xy 18.978385 -395.750475) (xy 19.014076 -395.709284)
			(xy 19.055267 -395.673593) (xy 19.101117 -395.644127) (xy 19.150694 -395.621485) (xy 19.202989 -395.60613)
			(xy 19.256937 -395.598374) (xy 19.311439 -395.598374) (xy 19.365387 -395.60613) (xy 19.417682 -395.621485)
			(xy 19.467259 -395.644127) (xy 19.513109 -395.673593) (xy 19.5543 -395.709284) (xy 19.589991 -395.750475)
			(xy 19.601933 -395.769057) (xy 288.471858 -395.769057) (xy 288.471858 -395.705103) (xy 288.479873 -395.641653)
			(xy 288.495778 -395.579708) (xy 288.519321 -395.520246) (xy 288.550131 -395.464202) (xy 288.587723 -395.412462)
			(xy 288.631502 -395.365842) (xy 288.68078 -395.325076) (xy 288.734778 -395.290808) (xy 288.792645 -395.263577)
			(xy 288.853469 -395.243814) (xy 288.91629 -395.231831) (xy 288.980118 -395.227815) (xy 289.043946 -395.231831)
			(xy 289.106767 -395.243814) (xy 289.167591 -395.263577) (xy 289.225458 -395.290808) (xy 289.279456 -395.325076)
			(xy 289.328734 -395.365842) (xy 289.372513 -395.412462) (xy 289.410105 -395.464202) (xy 289.440915 -395.520246)
			(xy 289.464458 -395.579708) (xy 289.480363 -395.641653) (xy 289.488378 -395.705103) (xy 289.48888 -395.73708)
			(xy 289.488378 -395.769057) (xy 289.480363 -395.832507) (xy 289.464458 -395.894452) (xy 289.440915 -395.953914)
			(xy 289.410105 -396.009958) (xy 289.372513 -396.061698) (xy 289.328734 -396.108318) (xy 289.279456 -396.149084)
			(xy 289.225458 -396.183352) (xy 289.167591 -396.210583) (xy 289.106767 -396.230346) (xy 289.043946 -396.242329)
			(xy 288.980118 -396.246345) (xy 288.91629 -396.242329) (xy 288.853469 -396.230346) (xy 288.792645 -396.210583)
			(xy 288.734778 -396.183352) (xy 288.68078 -396.149084) (xy 288.631502 -396.108318) (xy 288.587723 -396.061698)
			(xy 288.550131 -396.009958) (xy 288.519321 -395.953914) (xy 288.495778 -395.894452) (xy 288.479873 -395.832507)
			(xy 288.471858 -395.769057) (xy 19.601933 -395.769057) (xy 19.619457 -395.796325) (xy 19.642099 -395.845902)
			(xy 19.657454 -395.898197) (xy 19.66521 -395.952145) (xy 19.665696 -395.979396) (xy 19.665696 -396.842996)
			(xy 19.66521 -396.870247) (xy 19.657454 -396.924195) (xy 19.642099 -396.97649) (xy 19.619457 -397.026067)
			(xy 19.589991 -397.071917) (xy 19.5543 -397.113108) (xy 19.513109 -397.148799) (xy 19.467259 -397.178265)
			(xy 19.417682 -397.200907) (xy 19.365387 -397.216262) (xy 19.311439 -397.224018) (xy 19.256937 -397.224018)
			(xy 19.202989 -397.216262) (xy 19.150694 -397.200907) (xy 19.101117 -397.178265) (xy 19.055267 -397.148799)
			(xy 19.014076 -397.113108) (xy 18.978385 -397.071917) (xy 18.948919 -397.026067) (xy 18.926277 -396.97649)
			(xy 18.910922 -396.924195) (xy 18.903166 -396.870247) (xy 18.90268 -396.842996) (xy 2.509012 -396.842996)
			(xy 2.509012 -397.606012) (xy 24.954992 -397.606012) (xy 24.954992 -396.742412) (xy 24.955478 -396.715161)
			(xy 24.963234 -396.661213) (xy 24.978589 -396.608918) (xy 25.001231 -396.559341) (xy 25.030697 -396.513491)
			(xy 25.066388 -396.4723) (xy 25.107579 -396.436609) (xy 25.153429 -396.407143) (xy 25.203006 -396.384501)
			(xy 25.255301 -396.369146) (xy 25.309249 -396.36139) (xy 25.363751 -396.36139) (xy 25.417699 -396.369146)
			(xy 25.469994 -396.384501) (xy 25.519571 -396.407143) (xy 25.565421 -396.436609) (xy 25.606612 -396.4723)
			(xy 25.642303 -396.513491) (xy 25.671769 -396.559341) (xy 25.694411 -396.608918) (xy 25.709766 -396.661213)
			(xy 25.717522 -396.715161) (xy 25.718008 -396.742412) (xy 25.718008 -397.606012) (xy 25.717522 -397.633263)
			(xy 25.709766 -397.687211) (xy 25.694411 -397.739506) (xy 25.671769 -397.789083) (xy 25.642303 -397.834933)
			(xy 25.606612 -397.876124) (xy 25.565421 -397.911815) (xy 25.519571 -397.941281) (xy 25.469994 -397.963923)
			(xy 25.417699 -397.979278) (xy 25.363751 -397.987034) (xy 25.309249 -397.987034) (xy 25.255301 -397.979278)
			(xy 25.203006 -397.963923) (xy 25.153429 -397.941281) (xy 25.107579 -397.911815) (xy 25.066388 -397.876124)
			(xy 25.030697 -397.834933) (xy 25.001231 -397.789083) (xy 24.978589 -397.739506) (xy 24.963234 -397.687211)
			(xy 24.955478 -397.633263) (xy 24.954992 -397.606012) (xy 2.509012 -397.606012) (xy 2.509012 -398.68657)
			(xy 36.781952 -398.68657) (xy 36.781952 -398.63203) (xy 36.789714 -398.578046) (xy 36.805081 -398.525717)
			(xy 36.827739 -398.476107) (xy 36.857227 -398.430227) (xy 36.892945 -398.389011) (xy 36.934165 -398.353298)
			(xy 36.980049 -398.323816) (xy 37.029662 -398.301164) (xy 37.081993 -398.285804) (xy 37.135978 -398.278048)
			(xy 37.163248 -398.277588) (xy 38.026848 -398.277588) (xy 38.054119 -398.277978) (xy 38.108104 -398.285746)
			(xy 38.160435 -398.301118) (xy 38.210045 -398.323779) (xy 38.255926 -398.353271) (xy 38.297144 -398.38899)
			(xy 38.332858 -398.430212) (xy 38.362344 -398.476097) (xy 38.384999 -398.52571) (xy 38.400364 -398.578043)
			(xy 38.408126 -398.632029) (xy 38.408126 -398.686571) (xy 38.400364 -398.740557) (xy 38.384999 -398.79289)
			(xy 38.38214 -398.799152) (xy 42.10455 -398.799152) (xy 42.10455 -398.744648) (xy 42.112306 -398.6907)
			(xy 42.12766 -398.638404) (xy 42.150301 -398.588826) (xy 42.179766 -398.542974) (xy 42.215456 -398.501781)
			(xy 42.256645 -398.466087) (xy 42.302494 -398.436618) (xy 42.35207 -398.413973) (xy 42.404365 -398.398614)
			(xy 42.458312 -398.390852) (xy 42.485564 -398.390364) (xy 43.349164 -398.390364) (xy 43.376417 -398.390881)
			(xy 43.430367 -398.398633) (xy 43.482666 -398.413985) (xy 43.532247 -398.436624) (xy 43.578101 -398.466088)
			(xy 43.619295 -398.50178) (xy 43.65499 -398.54297) (xy 43.684459 -398.588822) (xy 43.707103 -398.638401)
			(xy 43.722459 -398.690697) (xy 43.730217 -398.744648) (xy 43.730217 -398.799152) (xy 43.722459 -398.853103)
			(xy 43.707103 -398.9054) (xy 43.684459 -398.954978) (xy 43.65499 -399.00083) (xy 43.619295 -399.04202)
			(xy 43.578101 -399.077712) (xy 43.532247 -399.107176) (xy 43.482666 -399.129815) (xy 43.430367 -399.145167)
			(xy 43.376417 -399.152919) (xy 43.349164 -399.15338) (xy 42.485564 -399.15338) (xy 42.458312 -399.152948)
			(xy 42.404365 -399.145186) (xy 42.35207 -399.129827) (xy 42.302494 -399.107182) (xy 42.256645 -399.077713)
			(xy 42.215456 -399.042019) (xy 42.179766 -399.000826) (xy 42.150301 -398.954974) (xy 42.12766 -398.905396)
			(xy 42.112306 -398.8531) (xy 42.10455 -398.799152) (xy 38.38214 -398.799152) (xy 38.362344 -398.842503)
			(xy 38.332858 -398.888388) (xy 38.297144 -398.92961) (xy 38.255926 -398.965329) (xy 38.210045 -398.994821)
			(xy 38.160435 -399.017482) (xy 38.108104 -399.032854) (xy 38.054119 -399.040622) (xy 38.026848 -399.041112)
			(xy 37.163248 -399.041112) (xy 37.135978 -399.040552) (xy 37.081993 -399.032796) (xy 37.029662 -399.017436)
			(xy 36.980049 -398.994784) (xy 36.934165 -398.965302) (xy 36.892945 -398.929589) (xy 36.857227 -398.888373)
			(xy 36.827739 -398.842493) (xy 36.805081 -398.792883) (xy 36.789714 -398.740554) (xy 36.781952 -398.68657)
			(xy 2.509012 -398.68657) (xy 2.509012 -399.443249) (xy 18.470394 -399.443249) (xy 18.470394 -399.388751)
			(xy 18.47815 -399.334808) (xy 18.493503 -399.282518) (xy 18.516141 -399.232945) (xy 18.545603 -399.187098)
			(xy 18.58129 -399.14591) (xy 18.622475 -399.11022) (xy 18.66832 -399.080754) (xy 18.717892 -399.058112)
			(xy 18.770181 -399.042756) (xy 18.824123 -399.034996) (xy 18.851372 -399.034508) (xy 19.714972 -399.034508)
			(xy 19.742227 -399.034937) (xy 19.796184 -399.042691) (xy 19.848487 -399.058045) (xy 19.898073 -399.080687)
			(xy 19.943931 -399.110156) (xy 19.985129 -399.145851) (xy 20.020827 -399.187046) (xy 20.050299 -399.232903)
			(xy 20.072945 -399.282487) (xy 20.088303 -399.334789) (xy 20.096061 -399.388745) (xy 20.096061 -399.443255)
			(xy 20.088303 -399.497211) (xy 20.072945 -399.549513) (xy 20.050299 -399.599097) (xy 20.020828 -399.644954)
			(xy 19.985129 -399.686149) (xy 19.943931 -399.721844) (xy 19.898073 -399.751313) (xy 19.848487 -399.773955)
			(xy 19.796184 -399.789309) (xy 19.742227 -399.797063) (xy 19.714972 -399.797524) (xy 18.851372 -399.797524)
			(xy 18.824123 -399.797004) (xy 18.770181 -399.789244) (xy 18.717892 -399.773888) (xy 18.66832 -399.751246)
			(xy 18.622475 -399.72178) (xy 18.58129 -399.68609) (xy 18.545603 -399.644902) (xy 18.516141 -399.599055)
			(xy 18.493503 -399.549482) (xy 18.47815 -399.497192) (xy 18.470394 -399.443249) (xy 2.509012 -399.443249)
			(xy 2.509012 -400.459248) (xy 25.590794 -400.459248) (xy 25.590794 -400.404752) (xy 25.598549 -400.350811)
			(xy 25.613901 -400.298522) (xy 25.636538 -400.24895) (xy 25.665999 -400.203104) (xy 25.701684 -400.161916)
			(xy 25.742867 -400.126226) (xy 25.788709 -400.09676) (xy 25.838279 -400.074117) (xy 25.890566 -400.058759)
			(xy 25.944506 -400.050997) (xy 25.971754 -400.050508) (xy 26.835354 -400.050508) (xy 26.86261 -400.050936)
			(xy 26.916568 -400.058688) (xy 26.968874 -400.07404) (xy 27.018462 -400.096681) (xy 27.064323 -400.126149)
			(xy 27.105523 -400.161845) (xy 27.141223 -400.20304) (xy 27.170697 -400.248897) (xy 27.193343 -400.298483)
			(xy 27.208702 -400.350787) (xy 27.216461 -400.404744) (xy 27.216461 -400.459256) (xy 27.208702 -400.513213)
			(xy 27.193343 -400.565517) (xy 27.170697 -400.615103) (xy 27.141223 -400.66096) (xy 27.105523 -400.702155)
			(xy 27.064323 -400.737851) (xy 27.018462 -400.767319) (xy 26.968874 -400.78996) (xy 26.916568 -400.805312)
			(xy 26.86261 -400.813064) (xy 26.835354 -400.813524) (xy 25.971754 -400.813524) (xy 25.944506 -400.813003)
			(xy 25.890566 -400.805241) (xy 25.838279 -400.789883) (xy 25.788709 -400.76724) (xy 25.742867 -400.737774)
			(xy 25.701684 -400.702084) (xy 25.665999 -400.660896) (xy 25.636538 -400.61505) (xy 25.613901 -400.565478)
			(xy 25.598549 -400.513189) (xy 25.590794 -400.459248) (xy 2.509012 -400.459248) (xy 2.509012 -400.885453)
			(xy 47.598783 -400.885453) (xy 47.598783 -400.830947) (xy 47.606541 -400.776997) (xy 47.621898 -400.7247)
			(xy 47.644541 -400.675121) (xy 47.674011 -400.629269) (xy 47.709706 -400.588079) (xy 47.7509 -400.552388)
			(xy 47.796754 -400.522923) (xy 47.846336 -400.500284) (xy 47.898634 -400.484933) (xy 47.952585 -400.477181)
			(xy 47.979838 -400.47672) (xy 48.843438 -400.47672) (xy 48.870689 -400.477152) (xy 48.924637 -400.484914)
			(xy 48.976931 -400.500273) (xy 49.026507 -400.522918) (xy 49.072356 -400.552388) (xy 49.113545 -400.588082)
			(xy 49.149235 -400.629274) (xy 49.1787 -400.675126) (xy 49.20134 -400.724705) (xy 49.216694 -400.777)
			(xy 49.22445 -400.830948) (xy 49.22445 -400.885448) (xy 50.662106 -400.885448) (xy 50.662106 -400.830952)
			(xy 50.669862 -400.77701) (xy 50.685214 -400.724721) (xy 50.707852 -400.675149) (xy 50.737314 -400.629303)
			(xy 50.773001 -400.588116) (xy 50.814185 -400.552427) (xy 50.86003 -400.522963) (xy 50.9096 -400.500322)
			(xy 50.961888 -400.484966) (xy 51.01583 -400.477208) (xy 51.043078 -400.47672) (xy 51.906678 -400.47672)
			(xy 51.933934 -400.477125) (xy 51.987891 -400.48488) (xy 52.040196 -400.500236) (xy 52.089782 -400.522879)
			(xy 52.135642 -400.552348) (xy 52.17684 -400.588045) (xy 52.212539 -400.629241) (xy 52.242011 -400.675098)
			(xy 52.264657 -400.724684) (xy 52.280015 -400.776987) (xy 52.287773 -400.830944) (xy 52.287773 -400.885452)
			(xy 53.725283 -400.885452) (xy 53.725283 -400.830948) (xy 53.73304 -400.777) (xy 53.748396 -400.724704)
			(xy 53.771038 -400.675127) (xy 53.800506 -400.629276) (xy 53.836199 -400.588086) (xy 53.87739 -400.552395)
			(xy 53.923242 -400.52293) (xy 53.972821 -400.50029) (xy 54.025117 -400.484936) (xy 54.079066 -400.477182)
			(xy 54.106318 -400.47672) (xy 54.969918 -400.47672) (xy 54.99717 -400.477151) (xy 55.05112 -400.48491)
			(xy 55.103417 -400.500268) (xy 55.152995 -400.522912) (xy 55.198847 -400.552381) (xy 55.240038 -400.588075)
			(xy 55.27573 -400.629268) (xy 55.305197 -400.675121) (xy 55.327838 -400.7247) (xy 55.343194 -400.776997)
			(xy 55.35095 -400.830948) (xy 55.35095 -400.885447) (xy 56.788606 -400.885447) (xy 56.788606 -400.830953)
			(xy 56.796361 -400.777013) (xy 56.811713 -400.724725) (xy 56.834349 -400.675154) (xy 56.863809 -400.629309)
			(xy 56.899494 -400.588123) (xy 56.940676 -400.552435) (xy 56.986518 -400.522969) (xy 57.036086 -400.500327)
			(xy 57.088372 -400.48497) (xy 57.142311 -400.477209) (xy 57.169558 -400.47672) (xy 58.033158 -400.47672)
			(xy 58.060415 -400.477124) (xy 58.114374 -400.484877) (xy 58.166681 -400.50023) (xy 58.21627 -400.522872)
			(xy 58.262132 -400.552341) (xy 58.303333 -400.588037) (xy 58.339034 -400.629234) (xy 58.368508 -400.675093)
			(xy 58.391155 -400.724679) (xy 58.406514 -400.776985) (xy 58.414273 -400.830943) (xy 58.414273 -400.885449)
			(xy 59.851806 -400.885449) (xy 59.851806 -400.830951) (xy 59.859562 -400.777007) (xy 59.874916 -400.724717)
			(xy 59.897555 -400.675143) (xy 59.927019 -400.629296) (xy 59.962708 -400.588109) (xy 60.003895 -400.55242)
			(xy 60.049742 -400.522956) (xy 60.099315 -400.500317) (xy 60.151605 -400.484963) (xy 60.205549 -400.477206)
			(xy 60.232798 -400.47672) (xy 61.096398 -400.47672) (xy 61.123653 -400.477127) (xy 61.177608 -400.484884)
			(xy 61.22991 -400.500241) (xy 61.279494 -400.522885) (xy 61.325351 -400.552355) (xy 61.366547 -400.588052)
			(xy 61.402243 -400.629247) (xy 61.431714 -400.675104) (xy 61.454358 -400.724688) (xy 61.469715 -400.77699)
			(xy 61.477473 -400.830945) (xy 61.477473 -400.885453) (xy 62.914983 -400.885453) (xy 62.914983 -400.830947)
			(xy 62.922741 -400.776997) (xy 62.938098 -400.7247) (xy 62.960741 -400.675121) (xy 62.990211 -400.629269)
			(xy 63.025906 -400.588079) (xy 63.0671 -400.552388) (xy 63.112954 -400.522923) (xy 63.162536 -400.500284)
			(xy 63.214834 -400.484933) (xy 63.268785 -400.477181) (xy 63.296038 -400.47672) (xy 64.159638 -400.47672)
			(xy 64.186889 -400.477152) (xy 64.240837 -400.484914) (xy 64.293131 -400.500273) (xy 64.342707 -400.522918)
			(xy 64.388556 -400.552388) (xy 64.429745 -400.588082) (xy 64.465435 -400.629274) (xy 64.4949 -400.675126)
			(xy 64.51754 -400.724705) (xy 64.532894 -400.777) (xy 64.54065 -400.830948) (xy 64.54065 -400.885448)
			(xy 65.978306 -400.885448) (xy 65.978306 -400.830952) (xy 65.986062 -400.77701) (xy 66.001414 -400.724721)
			(xy 66.024052 -400.675149) (xy 66.053514 -400.629303) (xy 66.089201 -400.588116) (xy 66.130385 -400.552427)
			(xy 66.17623 -400.522963) (xy 66.2258 -400.500322) (xy 66.278088 -400.484966) (xy 66.33203 -400.477208)
			(xy 66.359278 -400.47672) (xy 67.222878 -400.47672) (xy 67.250134 -400.477125) (xy 67.304091 -400.48488)
			(xy 67.356396 -400.500236) (xy 67.405982 -400.522879) (xy 67.451842 -400.552348) (xy 67.49304 -400.588045)
			(xy 67.528739 -400.629241) (xy 67.558211 -400.675098) (xy 67.580857 -400.724684) (xy 67.596215 -400.776987)
			(xy 67.603973 -400.830944) (xy 67.603973 -400.885452) (xy 69.041483 -400.885452) (xy 69.041483 -400.830948)
			(xy 69.04924 -400.777) (xy 69.064596 -400.724704) (xy 69.087238 -400.675127) (xy 69.116706 -400.629276)
			(xy 69.152399 -400.588086) (xy 69.19359 -400.552395) (xy 69.239442 -400.52293) (xy 69.289021 -400.50029)
			(xy 69.341317 -400.484936) (xy 69.395266 -400.477182) (xy 69.422518 -400.47672) (xy 70.286118 -400.47672)
			(xy 70.31337 -400.477151) (xy 70.36732 -400.48491) (xy 70.419617 -400.500268) (xy 70.469195 -400.522912)
			(xy 70.515047 -400.552381) (xy 70.556238 -400.588075) (xy 70.59193 -400.629268) (xy 70.621397 -400.675121)
			(xy 70.644038 -400.7247) (xy 70.659394 -400.776997) (xy 70.66715 -400.830948) (xy 70.66715 -400.885447)
			(xy 72.104806 -400.885447) (xy 72.104806 -400.830953) (xy 72.112561 -400.777013) (xy 72.127913 -400.724725)
			(xy 72.150549 -400.675154) (xy 72.180009 -400.629309) (xy 72.215694 -400.588123) (xy 72.256876 -400.552435)
			(xy 72.302718 -400.522969) (xy 72.352286 -400.500327) (xy 72.404572 -400.48497) (xy 72.458511 -400.477209)
			(xy 72.485758 -400.47672) (xy 73.349358 -400.47672) (xy 73.376615 -400.477124) (xy 73.430574 -400.484877)
			(xy 73.482881 -400.50023) (xy 73.53247 -400.522872) (xy 73.578332 -400.552341) (xy 73.619533 -400.588037)
			(xy 73.655234 -400.629234) (xy 73.684708 -400.675093) (xy 73.707355 -400.724679) (xy 73.722714 -400.776985)
			(xy 73.730473 -400.830943) (xy 73.730473 -400.885449) (xy 75.168006 -400.885449) (xy 75.168006 -400.830951)
			(xy 75.175762 -400.777007) (xy 75.191116 -400.724717) (xy 75.213755 -400.675143) (xy 75.243219 -400.629296)
			(xy 75.278908 -400.588109) (xy 75.320095 -400.55242) (xy 75.365942 -400.522956) (xy 75.415515 -400.500317)
			(xy 75.467805 -400.484963) (xy 75.521749 -400.477206) (xy 75.548998 -400.47672) (xy 76.412598 -400.47672)
			(xy 76.439853 -400.477127) (xy 76.493808 -400.484884) (xy 76.54611 -400.500241) (xy 76.595694 -400.522885)
			(xy 76.641551 -400.552355) (xy 76.682747 -400.588052) (xy 76.718443 -400.629247) (xy 76.747914 -400.675104)
			(xy 76.770558 -400.724688) (xy 76.785915 -400.77699) (xy 76.793673 -400.830945) (xy 76.793673 -400.885453)
			(xy 78.231183 -400.885453) (xy 78.231183 -400.830947) (xy 78.238941 -400.776997) (xy 78.254298 -400.7247)
			(xy 78.276941 -400.675121) (xy 78.306411 -400.629269) (xy 78.342106 -400.588079) (xy 78.3833 -400.552388)
			(xy 78.429154 -400.522923) (xy 78.478736 -400.500284) (xy 78.531034 -400.484933) (xy 78.584985 -400.477181)
			(xy 78.612238 -400.47672) (xy 79.475838 -400.47672) (xy 79.503089 -400.477152) (xy 79.557037 -400.484914)
			(xy 79.609331 -400.500273) (xy 79.658907 -400.522918) (xy 79.704756 -400.552388) (xy 79.745945 -400.588082)
			(xy 79.781635 -400.629274) (xy 79.8111 -400.675126) (xy 79.83374 -400.724705) (xy 79.849094 -400.777)
			(xy 79.85685 -400.830948) (xy 79.85685 -400.885448) (xy 81.294506 -400.885448) (xy 81.294506 -400.830952)
			(xy 81.302262 -400.77701) (xy 81.317614 -400.724721) (xy 81.340252 -400.675149) (xy 81.369714 -400.629303)
			(xy 81.405401 -400.588116) (xy 81.446585 -400.552427) (xy 81.49243 -400.522963) (xy 81.542 -400.500322)
			(xy 81.594288 -400.484966) (xy 81.64823 -400.477208) (xy 81.675478 -400.47672) (xy 82.539078 -400.47672)
			(xy 82.566334 -400.477125) (xy 82.620291 -400.48488) (xy 82.672596 -400.500236) (xy 82.722182 -400.522879)
			(xy 82.768042 -400.552348) (xy 82.80924 -400.588045) (xy 82.844939 -400.629241) (xy 82.874411 -400.675098)
			(xy 82.897057 -400.724684) (xy 82.912415 -400.776987) (xy 82.920173 -400.830944) (xy 82.920173 -400.885452)
			(xy 84.357683 -400.885452) (xy 84.357683 -400.830948) (xy 84.36544 -400.777) (xy 84.380796 -400.724704)
			(xy 84.403438 -400.675127) (xy 84.432906 -400.629276) (xy 84.468599 -400.588086) (xy 84.50979 -400.552395)
			(xy 84.555642 -400.52293) (xy 84.605221 -400.50029) (xy 84.657517 -400.484936) (xy 84.711466 -400.477182)
			(xy 84.738718 -400.47672) (xy 85.602318 -400.47672) (xy 85.62957 -400.477151) (xy 85.68352 -400.48491)
			(xy 85.735817 -400.500268) (xy 85.785395 -400.522912) (xy 85.831247 -400.552381) (xy 85.872438 -400.588075)
			(xy 85.90813 -400.629268) (xy 85.937597 -400.675121) (xy 85.960238 -400.7247) (xy 85.975594 -400.776997)
			(xy 85.98335 -400.830948) (xy 85.98335 -400.885447) (xy 87.421006 -400.885447) (xy 87.421006 -400.830953)
			(xy 87.428761 -400.777013) (xy 87.444113 -400.724725) (xy 87.466749 -400.675154) (xy 87.496209 -400.629309)
			(xy 87.531894 -400.588123) (xy 87.573076 -400.552435) (xy 87.618918 -400.522969) (xy 87.668486 -400.500327)
			(xy 87.720772 -400.48497) (xy 87.774711 -400.477209) (xy 87.801958 -400.47672) (xy 88.665558 -400.47672)
			(xy 88.692815 -400.477124) (xy 88.746774 -400.484877) (xy 88.799081 -400.50023) (xy 88.84867 -400.522872)
			(xy 88.894532 -400.552341) (xy 88.935733 -400.588037) (xy 88.971434 -400.629234) (xy 89.000908 -400.675093)
			(xy 89.023555 -400.724679) (xy 89.038914 -400.776985) (xy 89.046673 -400.830943) (xy 89.046673 -400.885449)
			(xy 90.484206 -400.885449) (xy 90.484206 -400.830951) (xy 90.491962 -400.777007) (xy 90.507316 -400.724717)
			(xy 90.529955 -400.675143) (xy 90.559419 -400.629296) (xy 90.595108 -400.588109) (xy 90.636295 -400.55242)
			(xy 90.682142 -400.522956) (xy 90.731715 -400.500317) (xy 90.784005 -400.484963) (xy 90.837949 -400.477206)
			(xy 90.865198 -400.47672) (xy 91.728798 -400.47672) (xy 91.756053 -400.477127) (xy 91.810008 -400.484884)
			(xy 91.86231 -400.500241) (xy 91.911894 -400.522885) (xy 91.957751 -400.552355) (xy 91.998947 -400.588052)
			(xy 92.034643 -400.629247) (xy 92.064114 -400.675104) (xy 92.086758 -400.724688) (xy 92.102115 -400.77699)
			(xy 92.109873 -400.830945) (xy 92.109873 -400.885453) (xy 93.547383 -400.885453) (xy 93.547383 -400.830947)
			(xy 93.555141 -400.776997) (xy 93.570498 -400.7247) (xy 93.593141 -400.675121) (xy 93.622611 -400.629269)
			(xy 93.658306 -400.588079) (xy 93.6995 -400.552388) (xy 93.745354 -400.522923) (xy 93.794936 -400.500284)
			(xy 93.847234 -400.484933) (xy 93.901185 -400.477181) (xy 93.928438 -400.47672) (xy 94.792038 -400.47672)
			(xy 94.819289 -400.477152) (xy 94.873237 -400.484914) (xy 94.925531 -400.500273) (xy 94.975107 -400.522918)
			(xy 95.020956 -400.552388) (xy 95.062145 -400.588082) (xy 95.097835 -400.629274) (xy 95.1273 -400.675126)
			(xy 95.14994 -400.724705) (xy 95.165294 -400.777) (xy 95.17305 -400.830948) (xy 95.17305 -400.885447)
			(xy 119.774006 -400.885447) (xy 119.774006 -400.830953) (xy 119.781761 -400.777013) (xy 119.797112 -400.724726)
			(xy 119.819749 -400.675156) (xy 119.849208 -400.629311) (xy 119.884892 -400.588125) (xy 119.926074 -400.552436)
			(xy 119.971915 -400.522971) (xy 120.021483 -400.500329) (xy 120.073768 -400.484971) (xy 120.127707 -400.477209)
			(xy 120.154954 -400.47672) (xy 121.018554 -400.47672) (xy 121.045811 -400.477124) (xy 121.099771 -400.484876)
			(xy 121.152078 -400.500229) (xy 121.201668 -400.522871) (xy 121.24753 -400.55234) (xy 121.288731 -400.588036)
			(xy 121.324433 -400.629233) (xy 121.353907 -400.675092) (xy 121.376555 -400.724679) (xy 121.391914 -400.776984)
			(xy 121.399673 -400.830943) (xy 121.399673 -400.885449) (xy 122.837206 -400.885449) (xy 122.837206 -400.830951)
			(xy 122.844962 -400.777008) (xy 122.860316 -400.724717) (xy 122.882955 -400.675144) (xy 122.912418 -400.629298)
			(xy 122.948106 -400.588111) (xy 122.989293 -400.552422) (xy 123.035139 -400.522958) (xy 123.084712 -400.500318)
			(xy 123.137002 -400.484963) (xy 123.190945 -400.477207) (xy 123.218194 -400.47672) (xy 124.081794 -400.47672)
			(xy 124.109049 -400.477127) (xy 124.163005 -400.484883) (xy 124.215307 -400.50024) (xy 124.264892 -400.522884)
			(xy 124.310749 -400.552354) (xy 124.351946 -400.58805) (xy 124.387643 -400.629246) (xy 124.417113 -400.675103)
			(xy 124.439758 -400.724687) (xy 124.455115 -400.776989) (xy 124.462873 -400.830945) (xy 124.462873 -400.885452)
			(xy 125.900383 -400.885452) (xy 125.900383 -400.830948) (xy 125.908141 -400.776998) (xy 125.923497 -400.724701)
			(xy 125.946141 -400.675122) (xy 125.97561 -400.629271) (xy 126.011304 -400.58808) (xy 126.052498 -400.552389)
			(xy 126.098352 -400.522924) (xy 126.147933 -400.500285) (xy 126.200231 -400.484933) (xy 126.254182 -400.477181)
			(xy 126.281434 -400.47672) (xy 127.145034 -400.47672) (xy 127.172286 -400.477152) (xy 127.226234 -400.484913)
			(xy 127.278528 -400.500272) (xy 127.328105 -400.522917) (xy 127.373954 -400.552386) (xy 127.415143 -400.588081)
			(xy 127.450834 -400.629273) (xy 127.480299 -400.675125) (xy 127.50294 -400.724704) (xy 127.518294 -400.777)
			(xy 127.52605 -400.830948) (xy 127.52605 -400.885448) (xy 128.963706 -400.885448) (xy 128.963706 -400.830952)
			(xy 128.971461 -400.777011) (xy 128.986814 -400.724722) (xy 129.009452 -400.67515) (xy 129.038913 -400.629304)
			(xy 129.074599 -400.588118) (xy 129.115783 -400.552429) (xy 129.161627 -400.522964) (xy 129.211197 -400.500323)
			(xy 129.263485 -400.484967) (xy 129.317426 -400.477208) (xy 129.344674 -400.47672) (xy 130.208274 -400.47672)
			(xy 130.23553 -400.477125) (xy 130.289488 -400.48488) (xy 130.341793 -400.500235) (xy 130.39138 -400.522877)
			(xy 130.43724 -400.552347) (xy 130.478438 -400.588043) (xy 130.514138 -400.62924) (xy 130.54361 -400.675097)
			(xy 130.566256 -400.724683) (xy 130.581615 -400.776987) (xy 130.589373 -400.830944) (xy 130.589373 -400.885451)
			(xy 132.026883 -400.885451) (xy 132.026883 -400.830949) (xy 132.03464 -400.777) (xy 132.049996 -400.724705)
			(xy 132.072638 -400.675128) (xy 132.102105 -400.629277) (xy 132.137797 -400.588087) (xy 132.178989 -400.552396)
			(xy 132.22484 -400.522931) (xy 132.274418 -400.500291) (xy 132.326714 -400.484937) (xy 132.380662 -400.477182)
			(xy 132.407914 -400.47672) (xy 133.271514 -400.47672) (xy 133.298767 -400.477151) (xy 133.352717 -400.48491)
			(xy 133.405014 -400.500267) (xy 133.454593 -400.522911) (xy 133.500445 -400.552379) (xy 133.541636 -400.588074)
			(xy 133.577329 -400.629266) (xy 133.606796 -400.67512) (xy 133.629438 -400.724699) (xy 133.644793 -400.776997)
			(xy 133.65255 -400.830947) (xy 133.65255 -400.885447) (xy 135.090206 -400.885447) (xy 135.090206 -400.830953)
			(xy 135.097961 -400.777013) (xy 135.113312 -400.724726) (xy 135.135949 -400.675156) (xy 135.165408 -400.629311)
			(xy 135.201092 -400.588125) (xy 135.242274 -400.552436) (xy 135.288115 -400.522971) (xy 135.337683 -400.500329)
			(xy 135.389968 -400.484971) (xy 135.443907 -400.477209) (xy 135.471154 -400.47672) (xy 136.334754 -400.47672)
			(xy 136.362011 -400.477124) (xy 136.415971 -400.484876) (xy 136.468278 -400.500229) (xy 136.517868 -400.522871)
			(xy 136.56373 -400.55234) (xy 136.604931 -400.588036) (xy 136.640633 -400.629233) (xy 136.670107 -400.675092)
			(xy 136.692755 -400.724679) (xy 136.708114 -400.776984) (xy 136.715873 -400.830943) (xy 136.715873 -400.885449)
			(xy 138.153406 -400.885449) (xy 138.153406 -400.830951) (xy 138.161162 -400.777008) (xy 138.176516 -400.724717)
			(xy 138.199155 -400.675144) (xy 138.228618 -400.629298) (xy 138.264306 -400.588111) (xy 138.305493 -400.552422)
			(xy 138.351339 -400.522958) (xy 138.400912 -400.500318) (xy 138.453202 -400.484963) (xy 138.507145 -400.477207)
			(xy 138.534394 -400.47672) (xy 139.397994 -400.47672) (xy 139.425249 -400.477127) (xy 139.479205 -400.484883)
			(xy 139.531507 -400.50024) (xy 139.581092 -400.522884) (xy 139.626949 -400.552354) (xy 139.668146 -400.58805)
			(xy 139.703843 -400.629246) (xy 139.733313 -400.675103) (xy 139.755958 -400.724687) (xy 139.771315 -400.776989)
			(xy 139.779073 -400.830945) (xy 139.779073 -400.885452) (xy 141.216583 -400.885452) (xy 141.216583 -400.830948)
			(xy 141.224341 -400.776998) (xy 141.239697 -400.724701) (xy 141.262341 -400.675122) (xy 141.29181 -400.629271)
			(xy 141.327504 -400.58808) (xy 141.368698 -400.552389) (xy 141.414552 -400.522924) (xy 141.464133 -400.500285)
			(xy 141.516431 -400.484933) (xy 141.570382 -400.477181) (xy 141.597634 -400.47672) (xy 142.461234 -400.47672)
			(xy 142.488486 -400.477152) (xy 142.542434 -400.484913) (xy 142.594728 -400.500272) (xy 142.644305 -400.522917)
			(xy 142.690154 -400.552386) (xy 142.731343 -400.588081) (xy 142.767034 -400.629273) (xy 142.796499 -400.675125)
			(xy 142.81914 -400.724704) (xy 142.834494 -400.777) (xy 142.84225 -400.830948) (xy 142.84225 -400.885448)
			(xy 144.279906 -400.885448) (xy 144.279906 -400.830952) (xy 144.287661 -400.777011) (xy 144.303014 -400.724722)
			(xy 144.325652 -400.67515) (xy 144.355113 -400.629304) (xy 144.390799 -400.588118) (xy 144.431983 -400.552429)
			(xy 144.477827 -400.522964) (xy 144.527397 -400.500323) (xy 144.579685 -400.484967) (xy 144.633626 -400.477208)
			(xy 144.660874 -400.47672) (xy 145.524474 -400.47672) (xy 145.55173 -400.477125) (xy 145.605688 -400.48488)
			(xy 145.657993 -400.500235) (xy 145.70758 -400.522877) (xy 145.75344 -400.552347) (xy 145.794638 -400.588043)
			(xy 145.830338 -400.62924) (xy 145.85981 -400.675097) (xy 145.882456 -400.724683) (xy 145.897815 -400.776987)
			(xy 145.905573 -400.830944) (xy 145.905573 -400.885451) (xy 147.343083 -400.885451) (xy 147.343083 -400.830949)
			(xy 147.35084 -400.777) (xy 147.366196 -400.724705) (xy 147.388838 -400.675128) (xy 147.418305 -400.629277)
			(xy 147.453997 -400.588087) (xy 147.495189 -400.552396) (xy 147.54104 -400.522931) (xy 147.590618 -400.500291)
			(xy 147.642914 -400.484937) (xy 147.696862 -400.477182) (xy 147.724114 -400.47672) (xy 148.587714 -400.47672)
			(xy 148.614967 -400.477151) (xy 148.668917 -400.48491) (xy 148.721214 -400.500267) (xy 148.770793 -400.522911)
			(xy 148.816645 -400.552379) (xy 148.857836 -400.588074) (xy 148.893529 -400.629266) (xy 148.922996 -400.67512)
			(xy 148.945638 -400.724699) (xy 148.960993 -400.776997) (xy 148.96875 -400.830947) (xy 148.96875 -400.885447)
			(xy 150.406406 -400.885447) (xy 150.406406 -400.830953) (xy 150.414161 -400.777013) (xy 150.429512 -400.724726)
			(xy 150.452149 -400.675156) (xy 150.481608 -400.629311) (xy 150.517292 -400.588125) (xy 150.558474 -400.552436)
			(xy 150.604315 -400.522971) (xy 150.653883 -400.500329) (xy 150.706168 -400.484971) (xy 150.760107 -400.477209)
			(xy 150.787354 -400.47672) (xy 151.650954 -400.47672) (xy 151.678211 -400.477124) (xy 151.732171 -400.484876)
			(xy 151.784478 -400.500229) (xy 151.834068 -400.522871) (xy 151.87993 -400.55234) (xy 151.921131 -400.588036)
			(xy 151.956833 -400.629233) (xy 151.986307 -400.675092) (xy 152.008955 -400.724679) (xy 152.024314 -400.776984)
			(xy 152.032073 -400.830943) (xy 152.032073 -400.885449) (xy 153.469606 -400.885449) (xy 153.469606 -400.830951)
			(xy 153.477362 -400.777008) (xy 153.492716 -400.724717) (xy 153.515355 -400.675144) (xy 153.544818 -400.629298)
			(xy 153.580506 -400.588111) (xy 153.621693 -400.552422) (xy 153.667539 -400.522958) (xy 153.717112 -400.500318)
			(xy 153.769402 -400.484963) (xy 153.823345 -400.477207) (xy 153.850594 -400.47672) (xy 154.714194 -400.47672)
			(xy 154.741449 -400.477127) (xy 154.795405 -400.484883) (xy 154.847707 -400.50024) (xy 154.897292 -400.522884)
			(xy 154.943149 -400.552354) (xy 154.984346 -400.58805) (xy 155.020043 -400.629246) (xy 155.049513 -400.675103)
			(xy 155.072158 -400.724687) (xy 155.087515 -400.776989) (xy 155.095273 -400.830945) (xy 155.095273 -400.885452)
			(xy 156.532783 -400.885452) (xy 156.532783 -400.830948) (xy 156.540541 -400.776998) (xy 156.555897 -400.724701)
			(xy 156.578541 -400.675122) (xy 156.60801 -400.629271) (xy 156.643704 -400.58808) (xy 156.684898 -400.552389)
			(xy 156.730752 -400.522924) (xy 156.780333 -400.500285) (xy 156.832631 -400.484933) (xy 156.886582 -400.477181)
			(xy 156.913834 -400.47672) (xy 157.777434 -400.47672) (xy 157.804686 -400.477152) (xy 157.858634 -400.484913)
			(xy 157.910928 -400.500272) (xy 157.960505 -400.522917) (xy 158.006354 -400.552386) (xy 158.047543 -400.588081)
			(xy 158.083234 -400.629273) (xy 158.112699 -400.675125) (xy 158.13534 -400.724704) (xy 158.150694 -400.777)
			(xy 158.15845 -400.830948) (xy 158.15845 -400.885448) (xy 159.596106 -400.885448) (xy 159.596106 -400.830952)
			(xy 159.603861 -400.777011) (xy 159.619214 -400.724722) (xy 159.641852 -400.67515) (xy 159.671313 -400.629304)
			(xy 159.706999 -400.588118) (xy 159.748183 -400.552429) (xy 159.794027 -400.522964) (xy 159.843597 -400.500323)
			(xy 159.895885 -400.484967) (xy 159.949826 -400.477208) (xy 159.977074 -400.47672) (xy 160.840674 -400.47672)
			(xy 160.86793 -400.477125) (xy 160.921888 -400.48488) (xy 160.974193 -400.500235) (xy 161.02378 -400.522877)
			(xy 161.06964 -400.552347) (xy 161.110838 -400.588043) (xy 161.146538 -400.62924) (xy 161.17601 -400.675097)
			(xy 161.198656 -400.724683) (xy 161.214015 -400.776987) (xy 161.221773 -400.830944) (xy 161.221773 -400.885451)
			(xy 162.659283 -400.885451) (xy 162.659283 -400.830949) (xy 162.66704 -400.777) (xy 162.682396 -400.724705)
			(xy 162.705038 -400.675128) (xy 162.734505 -400.629277) (xy 162.770197 -400.588087) (xy 162.811389 -400.552396)
			(xy 162.85724 -400.522931) (xy 162.906818 -400.500291) (xy 162.959114 -400.484937) (xy 163.013062 -400.477182)
			(xy 163.040314 -400.47672) (xy 163.903914 -400.47672) (xy 163.931167 -400.477151) (xy 163.985117 -400.48491)
			(xy 164.037414 -400.500267) (xy 164.086993 -400.522911) (xy 164.132845 -400.552379) (xy 164.174036 -400.588074)
			(xy 164.209729 -400.629266) (xy 164.239196 -400.67512) (xy 164.261838 -400.724699) (xy 164.277193 -400.776997)
			(xy 164.28495 -400.830947) (xy 164.28495 -400.885447) (xy 165.722606 -400.885447) (xy 165.722606 -400.830953)
			(xy 165.730361 -400.777013) (xy 165.745712 -400.724726) (xy 165.768349 -400.675156) (xy 165.797808 -400.629311)
			(xy 165.833492 -400.588125) (xy 165.874674 -400.552436) (xy 165.920515 -400.522971) (xy 165.970083 -400.500329)
			(xy 166.022368 -400.484971) (xy 166.076307 -400.477209) (xy 166.103554 -400.47672) (xy 166.967154 -400.47672)
			(xy 166.994411 -400.477124) (xy 167.048371 -400.484876) (xy 167.100678 -400.500229) (xy 167.150268 -400.522871)
			(xy 167.19613 -400.55234) (xy 167.237331 -400.588036) (xy 167.273033 -400.629233) (xy 167.302507 -400.675092)
			(xy 167.325155 -400.724679) (xy 167.340514 -400.776984) (xy 167.348273 -400.830943) (xy 167.348273 -400.885457)
			(xy 167.340514 -400.939416) (xy 167.325155 -400.991721) (xy 167.302507 -401.041308) (xy 167.273033 -401.087167)
			(xy 167.237331 -401.128364) (xy 167.19613 -401.16406) (xy 167.150268 -401.193529) (xy 167.100678 -401.216171)
			(xy 167.048371 -401.231524) (xy 166.994411 -401.239276) (xy 166.967154 -401.239736) (xy 166.103554 -401.239736)
			(xy 166.076307 -401.239191) (xy 166.022368 -401.231429) (xy 165.970083 -401.216071) (xy 165.920515 -401.193429)
			(xy 165.874674 -401.163964) (xy 165.833492 -401.128275) (xy 165.797808 -401.087089) (xy 165.768349 -401.041244)
			(xy 165.745712 -400.991674) (xy 165.730361 -400.939387) (xy 165.722606 -400.885447) (xy 164.28495 -400.885447)
			(xy 164.28495 -400.885453) (xy 164.277193 -400.939403) (xy 164.261838 -400.991701) (xy 164.239196 -401.04128)
			(xy 164.209729 -401.087134) (xy 164.174036 -401.128326) (xy 164.132845 -401.164021) (xy 164.086993 -401.193489)
			(xy 164.037414 -401.216133) (xy 163.985117 -401.23149) (xy 163.931167 -401.239249) (xy 163.903914 -401.239736)
			(xy 163.040314 -401.239736) (xy 163.013062 -401.239218) (xy 162.959114 -401.231463) (xy 162.906818 -401.216109)
			(xy 162.85724 -401.193469) (xy 162.811389 -401.164004) (xy 162.770197 -401.128313) (xy 162.734505 -401.087123)
			(xy 162.705038 -401.041272) (xy 162.682396 -400.991695) (xy 162.66704 -400.9394) (xy 162.659283 -400.885451)
			(xy 161.221773 -400.885451) (xy 161.221773 -400.885456) (xy 161.214015 -400.939413) (xy 161.198656 -400.991717)
			(xy 161.17601 -401.041303) (xy 161.146538 -401.08716) (xy 161.110838 -401.128357) (xy 161.06964 -401.164053)
			(xy 161.02378 -401.193523) (xy 160.974193 -401.216165) (xy 160.921888 -401.23152) (xy 160.86793 -401.239275)
			(xy 160.840674 -401.239736) (xy 159.977074 -401.239736) (xy 159.949826 -401.239192) (xy 159.895885 -401.231433)
			(xy 159.843597 -401.216077) (xy 159.794027 -401.193436) (xy 159.748183 -401.163971) (xy 159.706999 -401.128282)
			(xy 159.671313 -401.087096) (xy 159.641852 -401.04125) (xy 159.619214 -400.991678) (xy 159.603861 -400.939389)
			(xy 159.596106 -400.885448) (xy 158.15845 -400.885448) (xy 158.15845 -400.885452) (xy 158.150694 -400.9394)
			(xy 158.13534 -400.991696) (xy 158.112699 -401.041275) (xy 158.083234 -401.087127) (xy 158.047543 -401.128319)
			(xy 158.006354 -401.164014) (xy 157.960505 -401.193483) (xy 157.910928 -401.216128) (xy 157.858634 -401.231487)
			(xy 157.804686 -401.239248) (xy 157.777434 -401.239736) (xy 156.913834 -401.239736) (xy 156.886582 -401.239219)
			(xy 156.832631 -401.231467) (xy 156.780333 -401.216115) (xy 156.730752 -401.193476) (xy 156.684898 -401.164011)
			(xy 156.643704 -401.12832) (xy 156.60801 -401.087129) (xy 156.578541 -401.041278) (xy 156.555897 -400.991699)
			(xy 156.540541 -400.939402) (xy 156.532783 -400.885452) (xy 155.095273 -400.885452) (xy 155.095273 -400.885455)
			(xy 155.087515 -400.939411) (xy 155.072158 -400.991713) (xy 155.049513 -401.041297) (xy 155.020043 -401.087154)
			(xy 154.984346 -401.12835) (xy 154.943149 -401.164046) (xy 154.897292 -401.193516) (xy 154.847707 -401.21616)
			(xy 154.795405 -401.231517) (xy 154.741449 -401.239273) (xy 154.714194 -401.239736) (xy 153.850594 -401.239736)
			(xy 153.823345 -401.239193) (xy 153.769402 -401.231437) (xy 153.717112 -401.216082) (xy 153.667539 -401.193442)
			(xy 153.621693 -401.163978) (xy 153.580506 -401.128289) (xy 153.544818 -401.087102) (xy 153.515355 -401.041256)
			(xy 153.492716 -400.991683) (xy 153.477362 -400.939392) (xy 153.469606 -400.885449) (xy 152.032073 -400.885449)
			(xy 152.032073 -400.885457) (xy 152.024314 -400.939416) (xy 152.008955 -400.991721) (xy 151.986307 -401.041308)
			(xy 151.956833 -401.087167) (xy 151.921131 -401.128364) (xy 151.87993 -401.16406) (xy 151.834068 -401.193529)
			(xy 151.784478 -401.216171) (xy 151.732171 -401.231524) (xy 151.678211 -401.239276) (xy 151.650954 -401.239736)
			(xy 150.787354 -401.239736) (xy 150.760107 -401.239191) (xy 150.706168 -401.231429) (xy 150.653883 -401.216071)
			(xy 150.604315 -401.193429) (xy 150.558474 -401.163964) (xy 150.517292 -401.128275) (xy 150.481608 -401.087089)
			(xy 150.452149 -401.041244) (xy 150.429512 -400.991674) (xy 150.414161 -400.939387) (xy 150.406406 -400.885447)
			(xy 148.96875 -400.885447) (xy 148.96875 -400.885453) (xy 148.960993 -400.939403) (xy 148.945638 -400.991701)
			(xy 148.922996 -401.04128) (xy 148.893529 -401.087134) (xy 148.857836 -401.128326) (xy 148.816645 -401.164021)
			(xy 148.770793 -401.193489) (xy 148.721214 -401.216133) (xy 148.668917 -401.23149) (xy 148.614967 -401.239249)
			(xy 148.587714 -401.239736) (xy 147.724114 -401.239736) (xy 147.696862 -401.239218) (xy 147.642914 -401.231463)
			(xy 147.590618 -401.216109) (xy 147.54104 -401.193469) (xy 147.495189 -401.164004) (xy 147.453997 -401.128313)
			(xy 147.418305 -401.087123) (xy 147.388838 -401.041272) (xy 147.366196 -400.991695) (xy 147.35084 -400.9394)
			(xy 147.343083 -400.885451) (xy 145.905573 -400.885451) (xy 145.905573 -400.885456) (xy 145.897815 -400.939413)
			(xy 145.882456 -400.991717) (xy 145.85981 -401.041303) (xy 145.830338 -401.08716) (xy 145.794638 -401.128357)
			(xy 145.75344 -401.164053) (xy 145.70758 -401.193523) (xy 145.657993 -401.216165) (xy 145.605688 -401.23152)
			(xy 145.55173 -401.239275) (xy 145.524474 -401.239736) (xy 144.660874 -401.239736) (xy 144.633626 -401.239192)
			(xy 144.579685 -401.231433) (xy 144.527397 -401.216077) (xy 144.477827 -401.193436) (xy 144.431983 -401.163971)
			(xy 144.390799 -401.128282) (xy 144.355113 -401.087096) (xy 144.325652 -401.04125) (xy 144.303014 -400.991678)
			(xy 144.287661 -400.939389) (xy 144.279906 -400.885448) (xy 142.84225 -400.885448) (xy 142.84225 -400.885452)
			(xy 142.834494 -400.9394) (xy 142.81914 -400.991696) (xy 142.796499 -401.041275) (xy 142.767034 -401.087127)
			(xy 142.731343 -401.128319) (xy 142.690154 -401.164014) (xy 142.644305 -401.193483) (xy 142.594728 -401.216128)
			(xy 142.542434 -401.231487) (xy 142.488486 -401.239248) (xy 142.461234 -401.239736) (xy 141.597634 -401.239736)
			(xy 141.570382 -401.239219) (xy 141.516431 -401.231467) (xy 141.464133 -401.216115) (xy 141.414552 -401.193476)
			(xy 141.368698 -401.164011) (xy 141.327504 -401.12832) (xy 141.29181 -401.087129) (xy 141.262341 -401.041278)
			(xy 141.239697 -400.991699) (xy 141.224341 -400.939402) (xy 141.216583 -400.885452) (xy 139.779073 -400.885452)
			(xy 139.779073 -400.885455) (xy 139.771315 -400.939411) (xy 139.755958 -400.991713) (xy 139.733313 -401.041297)
			(xy 139.703843 -401.087154) (xy 139.668146 -401.12835) (xy 139.626949 -401.164046) (xy 139.581092 -401.193516)
			(xy 139.531507 -401.21616) (xy 139.479205 -401.231517) (xy 139.425249 -401.239273) (xy 139.397994 -401.239736)
			(xy 138.534394 -401.239736) (xy 138.507145 -401.239193) (xy 138.453202 -401.231437) (xy 138.400912 -401.216082)
			(xy 138.351339 -401.193442) (xy 138.305493 -401.163978) (xy 138.264306 -401.128289) (xy 138.228618 -401.087102)
			(xy 138.199155 -401.041256) (xy 138.176516 -400.991683) (xy 138.161162 -400.939392) (xy 138.153406 -400.885449)
			(xy 136.715873 -400.885449) (xy 136.715873 -400.885457) (xy 136.708114 -400.939416) (xy 136.692755 -400.991721)
			(xy 136.670107 -401.041308) (xy 136.640633 -401.087167) (xy 136.604931 -401.128364) (xy 136.56373 -401.16406)
			(xy 136.517868 -401.193529) (xy 136.468278 -401.216171) (xy 136.415971 -401.231524) (xy 136.362011 -401.239276)
			(xy 136.334754 -401.239736) (xy 135.471154 -401.239736) (xy 135.443907 -401.239191) (xy 135.389968 -401.231429)
			(xy 135.337683 -401.216071) (xy 135.288115 -401.193429) (xy 135.242274 -401.163964) (xy 135.201092 -401.128275)
			(xy 135.165408 -401.087089) (xy 135.135949 -401.041244) (xy 135.113312 -400.991674) (xy 135.097961 -400.939387)
			(xy 135.090206 -400.885447) (xy 133.65255 -400.885447) (xy 133.65255 -400.885453) (xy 133.644793 -400.939403)
			(xy 133.629438 -400.991701) (xy 133.606796 -401.04128) (xy 133.577329 -401.087134) (xy 133.541636 -401.128326)
			(xy 133.500445 -401.164021) (xy 133.454593 -401.193489) (xy 133.405014 -401.216133) (xy 133.352717 -401.23149)
			(xy 133.298767 -401.239249) (xy 133.271514 -401.239736) (xy 132.407914 -401.239736) (xy 132.380662 -401.239218)
			(xy 132.326714 -401.231463) (xy 132.274418 -401.216109) (xy 132.22484 -401.193469) (xy 132.178989 -401.164004)
			(xy 132.137797 -401.128313) (xy 132.102105 -401.087123) (xy 132.072638 -401.041272) (xy 132.049996 -400.991695)
			(xy 132.03464 -400.9394) (xy 132.026883 -400.885451) (xy 130.589373 -400.885451) (xy 130.589373 -400.885456)
			(xy 130.581615 -400.939413) (xy 130.566256 -400.991717) (xy 130.54361 -401.041303) (xy 130.514138 -401.08716)
			(xy 130.478438 -401.128357) (xy 130.43724 -401.164053) (xy 130.39138 -401.193523) (xy 130.341793 -401.216165)
			(xy 130.289488 -401.23152) (xy 130.23553 -401.239275) (xy 130.208274 -401.239736) (xy 129.344674 -401.239736)
			(xy 129.317426 -401.239192) (xy 129.263485 -401.231433) (xy 129.211197 -401.216077) (xy 129.161627 -401.193436)
			(xy 129.115783 -401.163971) (xy 129.074599 -401.128282) (xy 129.038913 -401.087096) (xy 129.009452 -401.04125)
			(xy 128.986814 -400.991678) (xy 128.971461 -400.939389) (xy 128.963706 -400.885448) (xy 127.52605 -400.885448)
			(xy 127.52605 -400.885452) (xy 127.518294 -400.9394) (xy 127.50294 -400.991696) (xy 127.480299 -401.041275)
			(xy 127.450834 -401.087127) (xy 127.415143 -401.128319) (xy 127.373954 -401.164014) (xy 127.328105 -401.193483)
			(xy 127.278528 -401.216128) (xy 127.226234 -401.231487) (xy 127.172286 -401.239248) (xy 127.145034 -401.239736)
			(xy 126.281434 -401.239736) (xy 126.254182 -401.239219) (xy 126.200231 -401.231467) (xy 126.147933 -401.216115)
			(xy 126.098352 -401.193476) (xy 126.052498 -401.164011) (xy 126.011304 -401.12832) (xy 125.97561 -401.087129)
			(xy 125.946141 -401.041278) (xy 125.923497 -400.991699) (xy 125.908141 -400.939402) (xy 125.900383 -400.885452)
			(xy 124.462873 -400.885452) (xy 124.462873 -400.885455) (xy 124.455115 -400.939411) (xy 124.439758 -400.991713)
			(xy 124.417113 -401.041297) (xy 124.387643 -401.087154) (xy 124.351946 -401.12835) (xy 124.310749 -401.164046)
			(xy 124.264892 -401.193516) (xy 124.215307 -401.21616) (xy 124.163005 -401.231517) (xy 124.109049 -401.239273)
			(xy 124.081794 -401.239736) (xy 123.218194 -401.239736) (xy 123.190945 -401.239193) (xy 123.137002 -401.231437)
			(xy 123.084712 -401.216082) (xy 123.035139 -401.193442) (xy 122.989293 -401.163978) (xy 122.948106 -401.128289)
			(xy 122.912418 -401.087102) (xy 122.882955 -401.041256) (xy 122.860316 -400.991683) (xy 122.844962 -400.939392)
			(xy 122.837206 -400.885449) (xy 121.399673 -400.885449) (xy 121.399673 -400.885457) (xy 121.391914 -400.939416)
			(xy 121.376555 -400.991721) (xy 121.353907 -401.041308) (xy 121.324433 -401.087167) (xy 121.288731 -401.128364)
			(xy 121.24753 -401.16406) (xy 121.201668 -401.193529) (xy 121.152078 -401.216171) (xy 121.099771 -401.231524)
			(xy 121.045811 -401.239276) (xy 121.018554 -401.239736) (xy 120.154954 -401.239736) (xy 120.127707 -401.239191)
			(xy 120.073768 -401.231429) (xy 120.021483 -401.216071) (xy 119.971915 -401.193429) (xy 119.926074 -401.163964)
			(xy 119.884892 -401.128275) (xy 119.849208 -401.087089) (xy 119.819749 -401.041244) (xy 119.797112 -400.991674)
			(xy 119.781761 -400.939387) (xy 119.774006 -400.885447) (xy 95.17305 -400.885447) (xy 95.17305 -400.885452)
			(xy 95.165294 -400.9394) (xy 95.14994 -400.991695) (xy 95.1273 -401.041274) (xy 95.097835 -401.087126)
			(xy 95.062145 -401.128318) (xy 95.020956 -401.164012) (xy 94.975107 -401.193482) (xy 94.925531 -401.216127)
			(xy 94.873237 -401.231486) (xy 94.819289 -401.239248) (xy 94.792038 -401.239736) (xy 93.928438 -401.239736)
			(xy 93.901185 -401.239219) (xy 93.847234 -401.231467) (xy 93.794936 -401.216116) (xy 93.745354 -401.193477)
			(xy 93.6995 -401.164012) (xy 93.658306 -401.128321) (xy 93.622611 -401.087131) (xy 93.593141 -401.041279)
			(xy 93.570498 -400.9917) (xy 93.555141 -400.939403) (xy 93.547383 -400.885453) (xy 92.109873 -400.885453)
			(xy 92.109873 -400.885455) (xy 92.102115 -400.93941) (xy 92.086758 -400.991712) (xy 92.064114 -401.041296)
			(xy 92.034643 -401.087153) (xy 91.998947 -401.128348) (xy 91.957751 -401.164045) (xy 91.911894 -401.193515)
			(xy 91.86231 -401.216159) (xy 91.810008 -401.231516) (xy 91.756053 -401.239273) (xy 91.728798 -401.239736)
			(xy 90.865198 -401.239736) (xy 90.837949 -401.239194) (xy 90.784005 -401.231437) (xy 90.731715 -401.216083)
			(xy 90.682142 -401.193444) (xy 90.636295 -401.16398) (xy 90.595108 -401.128291) (xy 90.559419 -401.087104)
			(xy 90.529955 -401.041257) (xy 90.507316 -400.991683) (xy 90.491962 -400.939393) (xy 90.484206 -400.885449)
			(xy 89.046673 -400.885449) (xy 89.046673 -400.885457) (xy 89.038914 -400.939415) (xy 89.023555 -400.991721)
			(xy 89.000908 -401.041307) (xy 88.971434 -401.087166) (xy 88.935733 -401.128363) (xy 88.894532 -401.164059)
			(xy 88.84867 -401.193528) (xy 88.799081 -401.21617) (xy 88.746774 -401.231523) (xy 88.692815 -401.239276)
			(xy 88.665558 -401.239736) (xy 87.801958 -401.239736) (xy 87.774711 -401.239191) (xy 87.720772 -401.23143)
			(xy 87.668486 -401.216073) (xy 87.618918 -401.193431) (xy 87.573076 -401.163965) (xy 87.531894 -401.128277)
			(xy 87.496209 -401.087091) (xy 87.466749 -401.041246) (xy 87.444113 -400.991675) (xy 87.428761 -400.939387)
			(xy 87.421006 -400.885447) (xy 85.98335 -400.885447) (xy 85.98335 -400.885452) (xy 85.975594 -400.939403)
			(xy 85.960238 -400.9917) (xy 85.937597 -401.041279) (xy 85.90813 -401.087132) (xy 85.872438 -401.128325)
			(xy 85.831247 -401.164019) (xy 85.785395 -401.193488) (xy 85.735817 -401.216132) (xy 85.68352 -401.23149)
			(xy 85.62957 -401.239249) (xy 85.602318 -401.239736) (xy 84.738718 -401.239736) (xy 84.711466 -401.239218)
			(xy 84.657517 -401.231464) (xy 84.605221 -401.21611) (xy 84.555642 -401.19347) (xy 84.50979 -401.164005)
			(xy 84.468599 -401.128314) (xy 84.432906 -401.087124) (xy 84.403438 -401.041273) (xy 84.380796 -400.991696)
			(xy 84.36544 -400.9394) (xy 84.357683 -400.885452) (xy 82.920173 -400.885452) (xy 82.920173 -400.885456)
			(xy 82.912415 -400.939413) (xy 82.897057 -400.991716) (xy 82.874411 -401.041302) (xy 82.844939 -401.087159)
			(xy 82.80924 -401.128355) (xy 82.768042 -401.164052) (xy 82.722182 -401.193521) (xy 82.672596 -401.216164)
			(xy 82.620291 -401.23152) (xy 82.566334 -401.239275) (xy 82.539078 -401.239736) (xy 81.675478 -401.239736)
			(xy 81.64823 -401.239192) (xy 81.594288 -401.231434) (xy 81.542 -401.216078) (xy 81.49243 -401.193437)
			(xy 81.446585 -401.163973) (xy 81.405401 -401.128284) (xy 81.369714 -401.087097) (xy 81.340252 -401.041251)
			(xy 81.317614 -400.991679) (xy 81.302262 -400.93939) (xy 81.294506 -400.885448) (xy 79.85685 -400.885448)
			(xy 79.85685 -400.885452) (xy 79.849094 -400.9394) (xy 79.83374 -400.991695) (xy 79.8111 -401.041274)
			(xy 79.781635 -401.087126) (xy 79.745945 -401.128318) (xy 79.704756 -401.164012) (xy 79.658907 -401.193482)
			(xy 79.609331 -401.216127) (xy 79.557037 -401.231486) (xy 79.503089 -401.239248) (xy 79.475838 -401.239736)
			(xy 78.612238 -401.239736) (xy 78.584985 -401.239219) (xy 78.531034 -401.231467) (xy 78.478736 -401.216116)
			(xy 78.429154 -401.193477) (xy 78.3833 -401.164012) (xy 78.342106 -401.128321) (xy 78.306411 -401.087131)
			(xy 78.276941 -401.041279) (xy 78.254298 -400.9917) (xy 78.238941 -400.939403) (xy 78.231183 -400.885453)
			(xy 76.793673 -400.885453) (xy 76.793673 -400.885455) (xy 76.785915 -400.93941) (xy 76.770558 -400.991712)
			(xy 76.747914 -401.041296) (xy 76.718443 -401.087153) (xy 76.682747 -401.128348) (xy 76.641551 -401.164045)
			(xy 76.595694 -401.193515) (xy 76.54611 -401.216159) (xy 76.493808 -401.231516) (xy 76.439853 -401.239273)
			(xy 76.412598 -401.239736) (xy 75.548998 -401.239736) (xy 75.521749 -401.239194) (xy 75.467805 -401.231437)
			(xy 75.415515 -401.216083) (xy 75.365942 -401.193444) (xy 75.320095 -401.16398) (xy 75.278908 -401.128291)
			(xy 75.243219 -401.087104) (xy 75.213755 -401.041257) (xy 75.191116 -400.991683) (xy 75.175762 -400.939393)
			(xy 75.168006 -400.885449) (xy 73.730473 -400.885449) (xy 73.730473 -400.885457) (xy 73.722714 -400.939415)
			(xy 73.707355 -400.991721) (xy 73.684708 -401.041307) (xy 73.655234 -401.087166) (xy 73.619533 -401.128363)
			(xy 73.578332 -401.164059) (xy 73.53247 -401.193528) (xy 73.482881 -401.21617) (xy 73.430574 -401.231523)
			(xy 73.376615 -401.239276) (xy 73.349358 -401.239736) (xy 72.485758 -401.239736) (xy 72.458511 -401.239191)
			(xy 72.404572 -401.23143) (xy 72.352286 -401.216073) (xy 72.302718 -401.193431) (xy 72.256876 -401.163965)
			(xy 72.215694 -401.128277) (xy 72.180009 -401.087091) (xy 72.150549 -401.041246) (xy 72.127913 -400.991675)
			(xy 72.112561 -400.939387) (xy 72.104806 -400.885447) (xy 70.66715 -400.885447) (xy 70.66715 -400.885452)
			(xy 70.659394 -400.939403) (xy 70.644038 -400.9917) (xy 70.621397 -401.041279) (xy 70.59193 -401.087132)
			(xy 70.556238 -401.128325) (xy 70.515047 -401.164019) (xy 70.469195 -401.193488) (xy 70.419617 -401.216132)
			(xy 70.36732 -401.23149) (xy 70.31337 -401.239249) (xy 70.286118 -401.239736) (xy 69.422518 -401.239736)
			(xy 69.395266 -401.239218) (xy 69.341317 -401.231464) (xy 69.289021 -401.21611) (xy 69.239442 -401.19347)
			(xy 69.19359 -401.164005) (xy 69.152399 -401.128314) (xy 69.116706 -401.087124) (xy 69.087238 -401.041273)
			(xy 69.064596 -400.991696) (xy 69.04924 -400.9394) (xy 69.041483 -400.885452) (xy 67.603973 -400.885452)
			(xy 67.603973 -400.885456) (xy 67.596215 -400.939413) (xy 67.580857 -400.991716) (xy 67.558211 -401.041302)
			(xy 67.528739 -401.087159) (xy 67.49304 -401.128355) (xy 67.451842 -401.164052) (xy 67.405982 -401.193521)
			(xy 67.356396 -401.216164) (xy 67.304091 -401.23152) (xy 67.250134 -401.239275) (xy 67.222878 -401.239736)
			(xy 66.359278 -401.239736) (xy 66.33203 -401.239192) (xy 66.278088 -401.231434) (xy 66.2258 -401.216078)
			(xy 66.17623 -401.193437) (xy 66.130385 -401.163973) (xy 66.089201 -401.128284) (xy 66.053514 -401.087097)
			(xy 66.024052 -401.041251) (xy 66.001414 -400.991679) (xy 65.986062 -400.93939) (xy 65.978306 -400.885448)
			(xy 64.54065 -400.885448) (xy 64.54065 -400.885452) (xy 64.532894 -400.9394) (xy 64.51754 -400.991695)
			(xy 64.4949 -401.041274) (xy 64.465435 -401.087126) (xy 64.429745 -401.128318) (xy 64.388556 -401.164012)
			(xy 64.342707 -401.193482) (xy 64.293131 -401.216127) (xy 64.240837 -401.231486) (xy 64.186889 -401.239248)
			(xy 64.159638 -401.239736) (xy 63.296038 -401.239736) (xy 63.268785 -401.239219) (xy 63.214834 -401.231467)
			(xy 63.162536 -401.216116) (xy 63.112954 -401.193477) (xy 63.0671 -401.164012) (xy 63.025906 -401.128321)
			(xy 62.990211 -401.087131) (xy 62.960741 -401.041279) (xy 62.938098 -400.9917) (xy 62.922741 -400.939403)
			(xy 62.914983 -400.885453) (xy 61.477473 -400.885453) (xy 61.477473 -400.885455) (xy 61.469715 -400.93941)
			(xy 61.454358 -400.991712) (xy 61.431714 -401.041296) (xy 61.402243 -401.087153) (xy 61.366547 -401.128348)
			(xy 61.325351 -401.164045) (xy 61.279494 -401.193515) (xy 61.22991 -401.216159) (xy 61.177608 -401.231516)
			(xy 61.123653 -401.239273) (xy 61.096398 -401.239736) (xy 60.232798 -401.239736) (xy 60.205549 -401.239194)
			(xy 60.151605 -401.231437) (xy 60.099315 -401.216083) (xy 60.049742 -401.193444) (xy 60.003895 -401.16398)
			(xy 59.962708 -401.128291) (xy 59.927019 -401.087104) (xy 59.897555 -401.041257) (xy 59.874916 -400.991683)
			(xy 59.859562 -400.939393) (xy 59.851806 -400.885449) (xy 58.414273 -400.885449) (xy 58.414273 -400.885457)
			(xy 58.406514 -400.939415) (xy 58.391155 -400.991721) (xy 58.368508 -401.041307) (xy 58.339034 -401.087166)
			(xy 58.303333 -401.128363) (xy 58.262132 -401.164059) (xy 58.21627 -401.193528) (xy 58.166681 -401.21617)
			(xy 58.114374 -401.231523) (xy 58.060415 -401.239276) (xy 58.033158 -401.239736) (xy 57.169558 -401.239736)
			(xy 57.142311 -401.239191) (xy 57.088372 -401.23143) (xy 57.036086 -401.216073) (xy 56.986518 -401.193431)
			(xy 56.940676 -401.163965) (xy 56.899494 -401.128277) (xy 56.863809 -401.087091) (xy 56.834349 -401.041246)
			(xy 56.811713 -400.991675) (xy 56.796361 -400.939387) (xy 56.788606 -400.885447) (xy 55.35095 -400.885447)
			(xy 55.35095 -400.885452) (xy 55.343194 -400.939403) (xy 55.327838 -400.9917) (xy 55.305197 -401.041279)
			(xy 55.27573 -401.087132) (xy 55.240038 -401.128325) (xy 55.198847 -401.164019) (xy 55.152995 -401.193488)
			(xy 55.103417 -401.216132) (xy 55.05112 -401.23149) (xy 54.99717 -401.239249) (xy 54.969918 -401.239736)
			(xy 54.106318 -401.239736) (xy 54.079066 -401.239218) (xy 54.025117 -401.231464) (xy 53.972821 -401.21611)
			(xy 53.923242 -401.19347) (xy 53.87739 -401.164005) (xy 53.836199 -401.128314) (xy 53.800506 -401.087124)
			(xy 53.771038 -401.041273) (xy 53.748396 -400.991696) (xy 53.73304 -400.9394) (xy 53.725283 -400.885452)
			(xy 52.287773 -400.885452) (xy 52.287773 -400.885456) (xy 52.280015 -400.939413) (xy 52.264657 -400.991716)
			(xy 52.242011 -401.041302) (xy 52.212539 -401.087159) (xy 52.17684 -401.128355) (xy 52.135642 -401.164052)
			(xy 52.089782 -401.193521) (xy 52.040196 -401.216164) (xy 51.987891 -401.23152) (xy 51.933934 -401.239275)
			(xy 51.906678 -401.239736) (xy 51.043078 -401.239736) (xy 51.01583 -401.239192) (xy 50.961888 -401.231434)
			(xy 50.9096 -401.216078) (xy 50.86003 -401.193437) (xy 50.814185 -401.163973) (xy 50.773001 -401.128284)
			(xy 50.737314 -401.087097) (xy 50.707852 -401.041251) (xy 50.685214 -400.991679) (xy 50.669862 -400.93939)
			(xy 50.662106 -400.885448) (xy 49.22445 -400.885448) (xy 49.22445 -400.885452) (xy 49.216694 -400.9394)
			(xy 49.20134 -400.991695) (xy 49.1787 -401.041274) (xy 49.149235 -401.087126) (xy 49.113545 -401.128318)
			(xy 49.072356 -401.164012) (xy 49.026507 -401.193482) (xy 48.976931 -401.216127) (xy 48.924637 -401.231486)
			(xy 48.870689 -401.239248) (xy 48.843438 -401.239736) (xy 47.979838 -401.239736) (xy 47.952585 -401.239219)
			(xy 47.898634 -401.231467) (xy 47.846336 -401.216116) (xy 47.796754 -401.193477) (xy 47.7509 -401.164012)
			(xy 47.709706 -401.128321) (xy 47.674011 -401.087131) (xy 47.644541 -401.041279) (xy 47.621898 -400.9917)
			(xy 47.606541 -400.939403) (xy 47.598783 -400.885453) (xy 2.509012 -400.885453) (xy 2.509012 -402.656674)
			(xy 98.152872 -402.656674) (xy 98.152872 -402.602126) (xy 98.160635 -402.548133) (xy 98.176003 -402.495795)
			(xy 98.198664 -402.446176) (xy 98.228156 -402.400288) (xy 98.263878 -402.359064) (xy 98.305104 -402.323344)
			(xy 98.350994 -402.293855) (xy 98.400613 -402.271196) (xy 98.452953 -402.255831) (xy 98.506946 -402.24807)
			(xy 98.53422 -402.247608) (xy 99.39782 -402.247608) (xy 99.425086 -402.248156) (xy 99.479063 -402.255919)
			(xy 99.531387 -402.271285) (xy 99.58099 -402.293941) (xy 99.626865 -402.323425) (xy 99.668077 -402.359137)
			(xy 99.703787 -402.400351) (xy 99.733269 -402.446227) (xy 99.755922 -402.495832) (xy 99.771285 -402.548156)
			(xy 99.779046 -402.602134) (xy 99.779046 -402.656666) (xy 99.771285 -402.710644) (xy 99.755922 -402.762968)
			(xy 99.733269 -402.812573) (xy 99.703787 -402.858449) (xy 99.668077 -402.899663) (xy 99.626865 -402.935375)
			(xy 99.58099 -402.964859) (xy 99.531387 -402.987515) (xy 99.479063 -403.002881) (xy 99.425086 -403.010644)
			(xy 99.39782 -403.011132) (xy 98.53422 -403.011132) (xy 98.506946 -403.01073) (xy 98.452953 -403.002969)
			(xy 98.400613 -402.987604) (xy 98.350994 -402.964945) (xy 98.305104 -402.935456) (xy 98.263878 -402.899736)
			(xy 98.228156 -402.858512) (xy 98.198664 -402.812624) (xy 98.176003 -402.763005) (xy 98.160635 -402.710667)
			(xy 98.152872 -402.656674) (xy 2.509012 -402.656674) (xy 2.509012 -403.371812) (xy 2.5095 -403.425034)
			(xy 2.517117 -403.531207) (xy 2.532283 -403.636566) (xy 2.554922 -403.740575) (xy 2.584919 -403.842706)
			(xy 2.610452 -403.911156) (xy 47.598731 -403.911156) (xy 47.598731 -403.856644) (xy 47.606489 -403.802686)
			(xy 47.621848 -403.750382) (xy 47.644495 -403.700796) (xy 47.673969 -403.654938) (xy 47.709669 -403.613742)
			(xy 47.750868 -403.578046) (xy 47.796729 -403.548577) (xy 47.846317 -403.525935) (xy 47.898623 -403.510581)
			(xy 47.952582 -403.502828) (xy 47.979838 -403.502368) (xy 48.843438 -403.502368) (xy 48.870686 -403.502905)
			(xy 48.924626 -403.510665) (xy 48.976913 -403.526023) (xy 49.026482 -403.548665) (xy 49.072325 -403.57813)
			(xy 49.113508 -403.613819) (xy 49.149193 -403.655006) (xy 49.178654 -403.700851) (xy 49.201291 -403.750423)
			(xy 49.216643 -403.802711) (xy 49.224398 -403.856652) (xy 49.224398 -403.911148) (xy 49.224397 -403.911152)
			(xy 50.662054 -403.911152) (xy 50.662054 -403.856648) (xy 50.66981 -403.802699) (xy 50.685165 -403.750403)
			(xy 50.707806 -403.700824) (xy 50.737272 -403.654971) (xy 50.772964 -403.613779) (xy 50.814154 -403.578085)
			(xy 50.860004 -403.548617) (xy 50.909582 -403.525973) (xy 50.961877 -403.510615) (xy 51.015826 -403.502855)
			(xy 51.043078 -403.502368) (xy 51.906678 -403.502368) (xy 51.93393 -403.502878) (xy 51.98788 -403.510632)
			(xy 52.040177 -403.525985) (xy 52.089757 -403.548625) (xy 52.13561 -403.57809) (xy 52.176803 -403.613782)
			(xy 52.212497 -403.654972) (xy 52.241965 -403.700824) (xy 52.264607 -403.750402) (xy 52.279964 -403.802698)
			(xy 52.287721 -403.856648) (xy 52.287721 -403.911152) (xy 52.287721 -403.911155) (xy 53.725231 -403.911155)
			(xy 53.725231 -403.856645) (xy 53.732989 -403.802689) (xy 53.748347 -403.750386) (xy 53.770992 -403.700801)
			(xy 53.800464 -403.654945) (xy 53.836162 -403.613749) (xy 53.877359 -403.578053) (xy 53.923217 -403.548583)
			(xy 53.972803 -403.525941) (xy 54.025106 -403.510585) (xy 54.079063 -403.50283) (xy 54.106318 -403.502368)
			(xy 54.969918 -403.502368) (xy 54.997167 -403.502903) (xy 55.051109 -403.510662) (xy 55.103398 -403.526017)
			(xy 55.15297 -403.548658) (xy 55.198815 -403.578123) (xy 55.240001 -403.613812) (xy 55.275688 -403.654999)
			(xy 55.305151 -403.700846) (xy 55.327789 -403.750419) (xy 55.343142 -403.802709) (xy 55.350898 -403.856651)
			(xy 55.350898 -403.911149) (xy 55.350898 -403.911151) (xy 56.788554 -403.911151) (xy 56.788554 -403.856649)
			(xy 56.79631 -403.802702) (xy 56.811664 -403.750407) (xy 56.834303 -403.700829) (xy 56.863767 -403.654978)
			(xy 56.899457 -403.613786) (xy 56.940644 -403.578093) (xy 56.986492 -403.548623) (xy 57.036067 -403.525978)
			(xy 57.08836 -403.510619) (xy 57.142307 -403.502857) (xy 57.169558 -403.502368) (xy 58.033158 -403.502368)
			(xy 58.060411 -403.502876) (xy 58.114363 -403.510628) (xy 58.166663 -403.525979) (xy 58.216245 -403.548618)
			(xy 58.262101 -403.578083) (xy 58.303296 -403.613775) (xy 58.338992 -403.654966) (xy 58.368462 -403.700818)
			(xy 58.391106 -403.750398) (xy 58.406463 -403.802696) (xy 58.414221 -403.856647) (xy 58.414221 -403.911153)
			(xy 59.851754 -403.911153) (xy 59.851754 -403.856647) (xy 59.859511 -403.802696) (xy 59.874867 -403.750398)
			(xy 59.897509 -403.700818) (xy 59.926977 -403.654965) (xy 59.962671 -403.613772) (xy 60.003863 -403.578078)
			(xy 60.049716 -403.54861) (xy 60.099296 -403.525967) (xy 60.151594 -403.510611) (xy 60.205545 -403.502854)
			(xy 60.232798 -403.502368) (xy 61.096398 -403.502368) (xy 61.123649 -403.502879) (xy 61.177597 -403.510635)
			(xy 61.229892 -403.52599) (xy 61.279469 -403.548631) (xy 61.32532 -403.578097) (xy 61.36651 -403.613789)
			(xy 61.402201 -403.654979) (xy 61.431668 -403.700829) (xy 61.454309 -403.750406) (xy 61.469664 -403.802701)
			(xy 61.477421 -403.856649) (xy 61.477421 -403.911151) (xy 61.47742 -403.911156) (xy 62.914931 -403.911156)
			(xy 62.914931 -403.856644) (xy 62.922689 -403.802686) (xy 62.938048 -403.750382) (xy 62.960695 -403.700796)
			(xy 62.990169 -403.654938) (xy 63.025869 -403.613742) (xy 63.067068 -403.578046) (xy 63.112929 -403.548577)
			(xy 63.162517 -403.525935) (xy 63.214823 -403.510581) (xy 63.268782 -403.502828) (xy 63.296038 -403.502368)
			(xy 64.159638 -403.502368) (xy 64.186886 -403.502905) (xy 64.240826 -403.510665) (xy 64.293113 -403.526023)
			(xy 64.342682 -403.548665) (xy 64.388525 -403.57813) (xy 64.429708 -403.613819) (xy 64.465393 -403.655006)
			(xy 64.494854 -403.700851) (xy 64.517491 -403.750423) (xy 64.532843 -403.802711) (xy 64.540598 -403.856652)
			(xy 64.540598 -403.911148) (xy 64.540597 -403.911152) (xy 65.978254 -403.911152) (xy 65.978254 -403.856648)
			(xy 65.98601 -403.802699) (xy 66.001365 -403.750403) (xy 66.024006 -403.700824) (xy 66.053472 -403.654971)
			(xy 66.089164 -403.613779) (xy 66.130354 -403.578085) (xy 66.176204 -403.548617) (xy 66.225782 -403.525973)
			(xy 66.278077 -403.510615) (xy 66.332026 -403.502855) (xy 66.359278 -403.502368) (xy 67.222878 -403.502368)
			(xy 67.25013 -403.502878) (xy 67.30408 -403.510632) (xy 67.356377 -403.525985) (xy 67.405957 -403.548625)
			(xy 67.45181 -403.57809) (xy 67.493003 -403.613782) (xy 67.528697 -403.654972) (xy 67.558165 -403.700824)
			(xy 67.580807 -403.750402) (xy 67.596164 -403.802698) (xy 67.603921 -403.856648) (xy 67.603921 -403.911152)
			(xy 67.603921 -403.911155) (xy 69.041431 -403.911155) (xy 69.041431 -403.856645) (xy 69.049189 -403.802689)
			(xy 69.064547 -403.750386) (xy 69.087192 -403.700801) (xy 69.116664 -403.654945) (xy 69.152362 -403.613749)
			(xy 69.193559 -403.578053) (xy 69.239417 -403.548583) (xy 69.289003 -403.525941) (xy 69.341306 -403.510585)
			(xy 69.395263 -403.50283) (xy 69.422518 -403.502368) (xy 70.286118 -403.502368) (xy 70.313367 -403.502903)
			(xy 70.367309 -403.510662) (xy 70.419598 -403.526017) (xy 70.46917 -403.548658) (xy 70.515015 -403.578123)
			(xy 70.556201 -403.613812) (xy 70.591888 -403.654999) (xy 70.621351 -403.700846) (xy 70.643989 -403.750419)
			(xy 70.659342 -403.802709) (xy 70.667098 -403.856651) (xy 70.667098 -403.911149) (xy 70.667098 -403.911151)
			(xy 72.104754 -403.911151) (xy 72.104754 -403.856649) (xy 72.11251 -403.802702) (xy 72.127864 -403.750407)
			(xy 72.150503 -403.700829) (xy 72.179967 -403.654978) (xy 72.215657 -403.613786) (xy 72.256844 -403.578093)
			(xy 72.302692 -403.548623) (xy 72.352267 -403.525978) (xy 72.40456 -403.510619) (xy 72.458507 -403.502857)
			(xy 72.485758 -403.502368) (xy 73.349358 -403.502368) (xy 73.376611 -403.502876) (xy 73.430563 -403.510628)
			(xy 73.482863 -403.525979) (xy 73.532445 -403.548618) (xy 73.578301 -403.578083) (xy 73.619496 -403.613775)
			(xy 73.655192 -403.654966) (xy 73.684662 -403.700818) (xy 73.707306 -403.750398) (xy 73.722663 -403.802696)
			(xy 73.730421 -403.856647) (xy 73.730421 -403.911153) (xy 75.167954 -403.911153) (xy 75.167954 -403.856647)
			(xy 75.175711 -403.802696) (xy 75.191067 -403.750398) (xy 75.213709 -403.700818) (xy 75.243177 -403.654965)
			(xy 75.278871 -403.613772) (xy 75.320063 -403.578078) (xy 75.365916 -403.54861) (xy 75.415496 -403.525967)
			(xy 75.467794 -403.510611) (xy 75.521745 -403.502854) (xy 75.548998 -403.502368) (xy 76.412598 -403.502368)
			(xy 76.439849 -403.502879) (xy 76.493797 -403.510635) (xy 76.546092 -403.52599) (xy 76.595669 -403.548631)
			(xy 76.64152 -403.578097) (xy 76.68271 -403.613789) (xy 76.718401 -403.654979) (xy 76.747868 -403.700829)
			(xy 76.770509 -403.750406) (xy 76.785864 -403.802701) (xy 76.793621 -403.856649) (xy 76.793621 -403.911151)
			(xy 76.79362 -403.911156) (xy 78.231131 -403.911156) (xy 78.231131 -403.856644) (xy 78.238889 -403.802686)
			(xy 78.254248 -403.750382) (xy 78.276895 -403.700796) (xy 78.306369 -403.654938) (xy 78.342069 -403.613742)
			(xy 78.383268 -403.578046) (xy 78.429129 -403.548577) (xy 78.478717 -403.525935) (xy 78.531023 -403.510581)
			(xy 78.584982 -403.502828) (xy 78.612238 -403.502368) (xy 79.475838 -403.502368) (xy 79.503086 -403.502905)
			(xy 79.557026 -403.510665) (xy 79.609313 -403.526023) (xy 79.658882 -403.548665) (xy 79.704725 -403.57813)
			(xy 79.745908 -403.613819) (xy 79.781593 -403.655006) (xy 79.811054 -403.700851) (xy 79.833691 -403.750423)
			(xy 79.849043 -403.802711) (xy 79.856798 -403.856652) (xy 79.856798 -403.911148) (xy 79.856797 -403.911152)
			(xy 81.294454 -403.911152) (xy 81.294454 -403.856648) (xy 81.30221 -403.802699) (xy 81.317565 -403.750403)
			(xy 81.340206 -403.700824) (xy 81.369672 -403.654971) (xy 81.405364 -403.613779) (xy 81.446554 -403.578085)
			(xy 81.492404 -403.548617) (xy 81.541982 -403.525973) (xy 81.594277 -403.510615) (xy 81.648226 -403.502855)
			(xy 81.675478 -403.502368) (xy 82.539078 -403.502368) (xy 82.56633 -403.502878) (xy 82.62028 -403.510632)
			(xy 82.672577 -403.525985) (xy 82.722157 -403.548625) (xy 82.76801 -403.57809) (xy 82.809203 -403.613782)
			(xy 82.844897 -403.654972) (xy 82.874365 -403.700824) (xy 82.897007 -403.750402) (xy 82.912364 -403.802698)
			(xy 82.920121 -403.856648) (xy 82.920121 -403.911152) (xy 82.920121 -403.911155) (xy 84.357631 -403.911155)
			(xy 84.357631 -403.856645) (xy 84.365389 -403.802689) (xy 84.380747 -403.750386) (xy 84.403392 -403.700801)
			(xy 84.432864 -403.654945) (xy 84.468562 -403.613749) (xy 84.509759 -403.578053) (xy 84.555617 -403.548583)
			(xy 84.605203 -403.525941) (xy 84.657506 -403.510585) (xy 84.711463 -403.50283) (xy 84.738718 -403.502368)
			(xy 85.602318 -403.502368) (xy 85.629567 -403.502903) (xy 85.683509 -403.510662) (xy 85.735798 -403.526017)
			(xy 85.78537 -403.548658) (xy 85.831215 -403.578123) (xy 85.872401 -403.613812) (xy 85.908088 -403.654999)
			(xy 85.937551 -403.700846) (xy 85.960189 -403.750419) (xy 85.975542 -403.802709) (xy 85.983298 -403.856651)
			(xy 85.983298 -403.911149) (xy 85.983298 -403.911151) (xy 87.420954 -403.911151) (xy 87.420954 -403.856649)
			(xy 87.42871 -403.802702) (xy 87.444064 -403.750407) (xy 87.466703 -403.700829) (xy 87.496167 -403.654978)
			(xy 87.531857 -403.613786) (xy 87.573044 -403.578093) (xy 87.618892 -403.548623) (xy 87.668467 -403.525978)
			(xy 87.72076 -403.510619) (xy 87.774707 -403.502857) (xy 87.801958 -403.502368) (xy 88.665558 -403.502368)
			(xy 88.692811 -403.502876) (xy 88.746763 -403.510628) (xy 88.799063 -403.525979) (xy 88.848645 -403.548618)
			(xy 88.894501 -403.578083) (xy 88.935696 -403.613775) (xy 88.971392 -403.654966) (xy 89.000862 -403.700818)
			(xy 89.023506 -403.750398) (xy 89.038863 -403.802696) (xy 89.046621 -403.856647) (xy 89.046621 -403.911153)
			(xy 90.484154 -403.911153) (xy 90.484154 -403.856647) (xy 90.491911 -403.802696) (xy 90.507267 -403.750398)
			(xy 90.529909 -403.700818) (xy 90.559377 -403.654965) (xy 90.595071 -403.613772) (xy 90.636263 -403.578078)
			(xy 90.682116 -403.54861) (xy 90.731696 -403.525967) (xy 90.783994 -403.510611) (xy 90.837945 -403.502854)
			(xy 90.865198 -403.502368) (xy 91.728798 -403.502368) (xy 91.756049 -403.502879) (xy 91.809997 -403.510635)
			(xy 91.862292 -403.52599) (xy 91.911869 -403.548631) (xy 91.95772 -403.578097) (xy 91.99891 -403.613789)
			(xy 92.034601 -403.654979) (xy 92.064068 -403.700829) (xy 92.086709 -403.750406) (xy 92.102064 -403.802701)
			(xy 92.109821 -403.856649) (xy 92.109821 -403.911151) (xy 92.10982 -403.911156) (xy 93.547331 -403.911156)
			(xy 93.547331 -403.856644) (xy 93.555089 -403.802686) (xy 93.570448 -403.750382) (xy 93.593095 -403.700796)
			(xy 93.622569 -403.654938) (xy 93.658269 -403.613742) (xy 93.699468 -403.578046) (xy 93.745329 -403.548577)
			(xy 93.794917 -403.525935) (xy 93.847223 -403.510581) (xy 93.901182 -403.502828) (xy 93.928438 -403.502368)
			(xy 94.792038 -403.502368) (xy 94.819286 -403.502905) (xy 94.873226 -403.510665) (xy 94.925513 -403.526023)
			(xy 94.975082 -403.548665) (xy 95.020925 -403.57813) (xy 95.062108 -403.613819) (xy 95.097793 -403.655006)
			(xy 95.127254 -403.700851) (xy 95.149891 -403.750423) (xy 95.165243 -403.802711) (xy 95.172998 -403.856652)
			(xy 95.172998 -403.911148) (xy 95.172998 -403.911151) (xy 119.773954 -403.911151) (xy 119.773954 -403.856649)
			(xy 119.78171 -403.802702) (xy 119.797063 -403.750408) (xy 119.819702 -403.70083) (xy 119.849166 -403.654979)
			(xy 119.884855 -403.613788) (xy 119.926042 -403.578094) (xy 119.97189 -403.548625) (xy 120.021465 -403.525979)
			(xy 120.073757 -403.510619) (xy 120.127703 -403.502857) (xy 120.154954 -403.502368) (xy 121.018554 -403.502368)
			(xy 121.045807 -403.502876) (xy 121.09976 -403.510627) (xy 121.15206 -403.525978) (xy 121.201643 -403.548617)
			(xy 121.247499 -403.578082) (xy 121.288694 -403.613773) (xy 121.324391 -403.654964) (xy 121.353861 -403.700817)
			(xy 121.376506 -403.750397) (xy 121.391863 -403.802695) (xy 121.399621 -403.856647) (xy 121.399621 -403.911153)
			(xy 122.837154 -403.911153) (xy 122.837154 -403.856647) (xy 122.844911 -403.802697) (xy 122.860266 -403.750399)
			(xy 122.882909 -403.700819) (xy 122.912376 -403.654966) (xy 122.948069 -403.613774) (xy 122.989261 -403.57808)
			(xy 123.035114 -403.548611) (xy 123.084694 -403.525969) (xy 123.136991 -403.510612) (xy 123.190941 -403.502854)
			(xy 123.218194 -403.502368) (xy 124.081794 -403.502368) (xy 124.109045 -403.502879) (xy 124.162994 -403.510635)
			(xy 124.215289 -403.525989) (xy 124.264867 -403.54863) (xy 124.310718 -403.578096) (xy 124.351908 -403.613787)
			(xy 124.3876 -403.654978) (xy 124.417067 -403.700828) (xy 124.439709 -403.750406) (xy 124.455064 -403.802701)
			(xy 124.462821 -403.856649) (xy 124.462821 -403.911151) (xy 124.46282 -403.911156) (xy 125.900331 -403.911156)
			(xy 125.900331 -403.856644) (xy 125.908089 -403.802686) (xy 125.923448 -403.750383) (xy 125.946095 -403.700797)
			(xy 125.975568 -403.654939) (xy 126.011267 -403.613743) (xy 126.052467 -403.578047) (xy 126.098327 -403.548578)
			(xy 126.147914 -403.525936) (xy 126.20022 -403.510582) (xy 126.254178 -403.502829) (xy 126.281434 -403.502368)
			(xy 127.145034 -403.502368) (xy 127.172282 -403.502905) (xy 127.226223 -403.510664) (xy 127.27851 -403.526022)
			(xy 127.32808 -403.548663) (xy 127.373923 -403.578129) (xy 127.415106 -403.613818) (xy 127.450792 -403.655004)
			(xy 127.480253 -403.70085) (xy 127.50289 -403.750422) (xy 127.518243 -403.802711) (xy 127.525998 -403.856652)
			(xy 127.525998 -403.911148) (xy 127.525997 -403.911152) (xy 128.963654 -403.911152) (xy 128.963654 -403.856648)
			(xy 128.97141 -403.802699) (xy 128.986765 -403.750403) (xy 129.009406 -403.700825) (xy 129.038871 -403.654973)
			(xy 129.074562 -403.613781) (xy 129.115752 -403.578087) (xy 129.161602 -403.548618) (xy 129.211179 -403.525974)
			(xy 129.263474 -403.510616) (xy 129.317422 -403.502856) (xy 129.344674 -403.502368) (xy 130.208274 -403.502368)
			(xy 130.235526 -403.502878) (xy 130.289477 -403.510631) (xy 130.341774 -403.525984) (xy 130.391355 -403.548623)
			(xy 130.437208 -403.578089) (xy 130.478401 -403.61378) (xy 130.514096 -403.654971) (xy 130.543564 -403.700822)
			(xy 130.566207 -403.750401) (xy 130.581563 -403.802698) (xy 130.589321 -403.856648) (xy 130.589321 -403.911152)
			(xy 130.589321 -403.911155) (xy 132.026831 -403.911155) (xy 132.026831 -403.856645) (xy 132.034589 -403.802689)
			(xy 132.049946 -403.750387) (xy 132.072591 -403.700803) (xy 132.102063 -403.654946) (xy 132.13776 -403.61375)
			(xy 132.178957 -403.578054) (xy 132.224815 -403.548585) (xy 132.2744 -403.525942) (xy 132.326703 -403.510586)
			(xy 132.380659 -403.50283) (xy 132.407914 -403.502368) (xy 133.271514 -403.502368) (xy 133.298763 -403.502903)
			(xy 133.352706 -403.510661) (xy 133.404995 -403.526016) (xy 133.454568 -403.548657) (xy 133.500413 -403.578121)
			(xy 133.541599 -403.613811) (xy 133.577287 -403.654998) (xy 133.60675 -403.700845) (xy 133.629389 -403.750418)
			(xy 133.644742 -403.802708) (xy 133.652498 -403.856651) (xy 133.652498 -403.911149) (xy 133.652498 -403.911151)
			(xy 135.090154 -403.911151) (xy 135.090154 -403.856649) (xy 135.09791 -403.802702) (xy 135.113263 -403.750408)
			(xy 135.135902 -403.70083) (xy 135.165366 -403.654979) (xy 135.201055 -403.613788) (xy 135.242242 -403.578094)
			(xy 135.28809 -403.548625) (xy 135.337665 -403.525979) (xy 135.389957 -403.510619) (xy 135.443903 -403.502857)
			(xy 135.471154 -403.502368) (xy 136.334754 -403.502368) (xy 136.362007 -403.502876) (xy 136.41596 -403.510627)
			(xy 136.46826 -403.525978) (xy 136.517843 -403.548617) (xy 136.563699 -403.578082) (xy 136.604894 -403.613773)
			(xy 136.640591 -403.654964) (xy 136.670061 -403.700817) (xy 136.692706 -403.750397) (xy 136.708063 -403.802695)
			(xy 136.715821 -403.856647) (xy 136.715821 -403.911153) (xy 138.153354 -403.911153) (xy 138.153354 -403.856647)
			(xy 138.161111 -403.802697) (xy 138.176466 -403.750399) (xy 138.199109 -403.700819) (xy 138.228576 -403.654966)
			(xy 138.264269 -403.613774) (xy 138.305461 -403.57808) (xy 138.351314 -403.548611) (xy 138.400894 -403.525969)
			(xy 138.453191 -403.510612) (xy 138.507141 -403.502854) (xy 138.534394 -403.502368) (xy 139.397994 -403.502368)
			(xy 139.425245 -403.502879) (xy 139.479194 -403.510635) (xy 139.531489 -403.525989) (xy 139.581067 -403.54863)
			(xy 139.626918 -403.578096) (xy 139.668108 -403.613787) (xy 139.7038 -403.654978) (xy 139.733267 -403.700828)
			(xy 139.755909 -403.750406) (xy 139.771264 -403.802701) (xy 139.779021 -403.856649) (xy 139.779021 -403.911151)
			(xy 139.77902 -403.911156) (xy 141.216531 -403.911156) (xy 141.216531 -403.856644) (xy 141.224289 -403.802686)
			(xy 141.239648 -403.750383) (xy 141.262295 -403.700797) (xy 141.291768 -403.654939) (xy 141.327467 -403.613743)
			(xy 141.368667 -403.578047) (xy 141.414527 -403.548578) (xy 141.464114 -403.525936) (xy 141.51642 -403.510582)
			(xy 141.570378 -403.502829) (xy 141.597634 -403.502368) (xy 142.461234 -403.502368) (xy 142.488482 -403.502905)
			(xy 142.542423 -403.510664) (xy 142.59471 -403.526022) (xy 142.64428 -403.548663) (xy 142.690123 -403.578129)
			(xy 142.731306 -403.613818) (xy 142.766992 -403.655004) (xy 142.796453 -403.70085) (xy 142.81909 -403.750422)
			(xy 142.834443 -403.802711) (xy 142.842198 -403.856652) (xy 142.842198 -403.911148) (xy 142.842197 -403.911152)
			(xy 144.279854 -403.911152) (xy 144.279854 -403.856648) (xy 144.28761 -403.802699) (xy 144.302965 -403.750403)
			(xy 144.325606 -403.700825) (xy 144.355071 -403.654973) (xy 144.390762 -403.613781) (xy 144.431952 -403.578087)
			(xy 144.477802 -403.548618) (xy 144.527379 -403.525974) (xy 144.579674 -403.510616) (xy 144.633622 -403.502856)
			(xy 144.660874 -403.502368) (xy 145.524474 -403.502368) (xy 145.551726 -403.502878) (xy 145.605677 -403.510631)
			(xy 145.657974 -403.525984) (xy 145.707555 -403.548623) (xy 145.753408 -403.578089) (xy 145.794601 -403.61378)
			(xy 145.830296 -403.654971) (xy 145.859764 -403.700822) (xy 145.882407 -403.750401) (xy 145.897763 -403.802698)
			(xy 145.905521 -403.856648) (xy 145.905521 -403.911152) (xy 145.905521 -403.911155) (xy 147.343031 -403.911155)
			(xy 147.343031 -403.856645) (xy 147.350789 -403.802689) (xy 147.366146 -403.750387) (xy 147.388791 -403.700803)
			(xy 147.418263 -403.654946) (xy 147.45396 -403.61375) (xy 147.495157 -403.578054) (xy 147.541015 -403.548585)
			(xy 147.5906 -403.525942) (xy 147.642903 -403.510586) (xy 147.696859 -403.50283) (xy 147.724114 -403.502368)
			(xy 148.587714 -403.502368) (xy 148.614963 -403.502903) (xy 148.668906 -403.510661) (xy 148.721195 -403.526016)
			(xy 148.770768 -403.548657) (xy 148.816613 -403.578121) (xy 148.857799 -403.613811) (xy 148.893487 -403.654998)
			(xy 148.92295 -403.700845) (xy 148.945589 -403.750418) (xy 148.960942 -403.802708) (xy 148.968698 -403.856651)
			(xy 148.968698 -403.911149) (xy 148.968698 -403.911151) (xy 150.406354 -403.911151) (xy 150.406354 -403.856649)
			(xy 150.41411 -403.802702) (xy 150.429463 -403.750408) (xy 150.452102 -403.70083) (xy 150.481566 -403.654979)
			(xy 150.517255 -403.613788) (xy 150.558442 -403.578094) (xy 150.60429 -403.548625) (xy 150.653865 -403.525979)
			(xy 150.706157 -403.510619) (xy 150.760103 -403.502857) (xy 150.787354 -403.502368) (xy 151.650954 -403.502368)
			(xy 151.678207 -403.502876) (xy 151.73216 -403.510627) (xy 151.78446 -403.525978) (xy 151.834043 -403.548617)
			(xy 151.879899 -403.578082) (xy 151.921094 -403.613773) (xy 151.956791 -403.654964) (xy 151.986261 -403.700817)
			(xy 152.008906 -403.750397) (xy 152.024263 -403.802695) (xy 152.032021 -403.856647) (xy 152.032021 -403.911153)
			(xy 153.469554 -403.911153) (xy 153.469554 -403.856647) (xy 153.477311 -403.802697) (xy 153.492666 -403.750399)
			(xy 153.515309 -403.700819) (xy 153.544776 -403.654966) (xy 153.580469 -403.613774) (xy 153.621661 -403.57808)
			(xy 153.667514 -403.548611) (xy 153.717094 -403.525969) (xy 153.769391 -403.510612) (xy 153.823341 -403.502854)
			(xy 153.850594 -403.502368) (xy 154.714194 -403.502368) (xy 154.741445 -403.502879) (xy 154.795394 -403.510635)
			(xy 154.847689 -403.525989) (xy 154.897267 -403.54863) (xy 154.943118 -403.578096) (xy 154.984308 -403.613787)
			(xy 155.02 -403.654978) (xy 155.049467 -403.700828) (xy 155.072109 -403.750406) (xy 155.087464 -403.802701)
			(xy 155.095221 -403.856649) (xy 155.095221 -403.911151) (xy 155.09522 -403.911156) (xy 156.532731 -403.911156)
			(xy 156.532731 -403.856644) (xy 156.540489 -403.802686) (xy 156.555848 -403.750383) (xy 156.578495 -403.700797)
			(xy 156.607968 -403.654939) (xy 156.643667 -403.613743) (xy 156.684867 -403.578047) (xy 156.730727 -403.548578)
			(xy 156.780314 -403.525936) (xy 156.83262 -403.510582) (xy 156.886578 -403.502829) (xy 156.913834 -403.502368)
			(xy 157.777434 -403.502368) (xy 157.804682 -403.502905) (xy 157.858623 -403.510664) (xy 157.91091 -403.526022)
			(xy 157.96048 -403.548663) (xy 158.006323 -403.578129) (xy 158.047506 -403.613818) (xy 158.083192 -403.655004)
			(xy 158.112653 -403.70085) (xy 158.13529 -403.750422) (xy 158.150643 -403.802711) (xy 158.158398 -403.856652)
			(xy 158.158398 -403.911148) (xy 158.158397 -403.911152) (xy 159.596054 -403.911152) (xy 159.596054 -403.856648)
			(xy 159.60381 -403.802699) (xy 159.619165 -403.750403) (xy 159.641806 -403.700825) (xy 159.671271 -403.654973)
			(xy 159.706962 -403.613781) (xy 159.748152 -403.578087) (xy 159.794002 -403.548618) (xy 159.843579 -403.525974)
			(xy 159.895874 -403.510616) (xy 159.949822 -403.502856) (xy 159.977074 -403.502368) (xy 160.840674 -403.502368)
			(xy 160.867926 -403.502878) (xy 160.921877 -403.510631) (xy 160.974174 -403.525984) (xy 161.023755 -403.548623)
			(xy 161.069608 -403.578089) (xy 161.110801 -403.61378) (xy 161.146496 -403.654971) (xy 161.175964 -403.700822)
			(xy 161.198607 -403.750401) (xy 161.213963 -403.802698) (xy 161.221721 -403.856648) (xy 161.221721 -403.911152)
			(xy 161.221721 -403.911155) (xy 162.659231 -403.911155) (xy 162.659231 -403.856645) (xy 162.666989 -403.802689)
			(xy 162.682346 -403.750387) (xy 162.704991 -403.700803) (xy 162.734463 -403.654946) (xy 162.77016 -403.61375)
			(xy 162.811357 -403.578054) (xy 162.857215 -403.548585) (xy 162.9068 -403.525942) (xy 162.959103 -403.510586)
			(xy 163.013059 -403.50283) (xy 163.040314 -403.502368) (xy 163.903914 -403.502368) (xy 163.931163 -403.502903)
			(xy 163.985106 -403.510661) (xy 164.037395 -403.526016) (xy 164.086968 -403.548657) (xy 164.132813 -403.578121)
			(xy 164.173999 -403.613811) (xy 164.209687 -403.654998) (xy 164.23915 -403.700845) (xy 164.261789 -403.750418)
			(xy 164.277142 -403.802708) (xy 164.284898 -403.856651) (xy 164.284898 -403.911149) (xy 164.284898 -403.911151)
			(xy 165.722554 -403.911151) (xy 165.722554 -403.856649) (xy 165.73031 -403.802702) (xy 165.745663 -403.750408)
			(xy 165.768302 -403.70083) (xy 165.797766 -403.654979) (xy 165.833455 -403.613788) (xy 165.874642 -403.578094)
			(xy 165.92049 -403.548625) (xy 165.970065 -403.525979) (xy 166.022357 -403.510619) (xy 166.076303 -403.502857)
			(xy 166.103554 -403.502368) (xy 166.967154 -403.502368) (xy 166.994407 -403.502876) (xy 167.04836 -403.510627)
			(xy 167.10066 -403.525978) (xy 167.150243 -403.548617) (xy 167.196099 -403.578082) (xy 167.237294 -403.613773)
			(xy 167.272991 -403.654964) (xy 167.302461 -403.700817) (xy 167.325106 -403.750397) (xy 167.340463 -403.802695)
			(xy 167.348221 -403.856647) (xy 167.348221 -403.911153) (xy 167.340463 -403.965105) (xy 167.325106 -404.017403)
			(xy 167.302461 -404.066983) (xy 167.272991 -404.112836) (xy 167.237294 -404.154027) (xy 167.196099 -404.189718)
			(xy 167.150243 -404.219183) (xy 167.10066 -404.241822) (xy 167.04836 -404.257173) (xy 166.994407 -404.264924)
			(xy 166.967154 -404.265384) (xy 166.103554 -404.265384) (xy 166.076303 -404.264943) (xy 166.022357 -404.257181)
			(xy 165.970065 -404.241821) (xy 165.92049 -404.219175) (xy 165.874642 -404.189706) (xy 165.833455 -404.154012)
			(xy 165.797766 -404.112821) (xy 165.768302 -404.06697) (xy 165.745663 -404.017392) (xy 165.73031 -403.965098)
			(xy 165.722554 -403.911151) (xy 164.284898 -403.911151) (xy 164.277142 -403.965092) (xy 164.261789 -404.017382)
			(xy 164.23915 -404.066955) (xy 164.209687 -404.112802) (xy 164.173999 -404.153989) (xy 164.132813 -404.189679)
			(xy 164.086968 -404.219143) (xy 164.037395 -404.241784) (xy 163.985106 -404.257139) (xy 163.931163 -404.264897)
			(xy 163.903914 -404.265384) (xy 163.040314 -404.265384) (xy 163.013059 -404.26497) (xy 162.959103 -404.257214)
			(xy 162.9068 -404.241858) (xy 162.857215 -404.219215) (xy 162.811357 -404.189746) (xy 162.77016 -404.15405)
			(xy 162.734463 -404.112854) (xy 162.704991 -404.066997) (xy 162.682346 -404.017413) (xy 162.666989 -403.965111)
			(xy 162.659231 -403.911155) (xy 161.221721 -403.911155) (xy 161.213963 -403.965102) (xy 161.198607 -404.017399)
			(xy 161.175964 -404.066978) (xy 161.146496 -404.112829) (xy 161.110801 -404.15402) (xy 161.069608 -404.189711)
			(xy 161.023755 -404.219177) (xy 160.974174 -404.241816) (xy 160.921877 -404.257169) (xy 160.867926 -404.264922)
			(xy 160.840674 -404.265384) (xy 159.977074 -404.265384) (xy 159.949822 -404.264944) (xy 159.895874 -404.257184)
			(xy 159.843579 -404.241826) (xy 159.794002 -404.219182) (xy 159.748152 -404.189713) (xy 159.706962 -404.154019)
			(xy 159.671271 -404.112827) (xy 159.641806 -404.066975) (xy 159.619165 -404.017397) (xy 159.60381 -403.965101)
			(xy 159.596054 -403.911152) (xy 158.158397 -403.911152) (xy 158.150643 -403.965089) (xy 158.13529 -404.017378)
			(xy 158.112653 -404.06695) (xy 158.083192 -404.112796) (xy 158.047506 -404.153982) (xy 158.006323 -404.189671)
			(xy 157.96048 -404.219137) (xy 157.91091 -404.241778) (xy 157.858623 -404.257136) (xy 157.804682 -404.264895)
			(xy 157.777434 -404.265384) (xy 156.913834 -404.265384) (xy 156.886578 -404.264971) (xy 156.83262 -404.257218)
			(xy 156.780314 -404.241864) (xy 156.730727 -404.219222) (xy 156.684867 -404.189753) (xy 156.643667 -404.154057)
			(xy 156.607968 -404.112861) (xy 156.578495 -404.067003) (xy 156.555848 -404.017417) (xy 156.540489 -403.965114)
			(xy 156.532731 -403.911156) (xy 155.09522 -403.911156) (xy 155.087464 -403.965099) (xy 155.072109 -404.017394)
			(xy 155.049467 -404.066972) (xy 155.02 -404.112822) (xy 154.984308 -404.154013) (xy 154.943118 -404.189704)
			(xy 154.897267 -404.21917) (xy 154.847689 -404.241811) (xy 154.795394 -404.257165) (xy 154.741445 -404.264921)
			(xy 154.714194 -404.265384) (xy 153.850594 -404.265384) (xy 153.823341 -404.264946) (xy 153.769391 -404.257188)
			(xy 153.717094 -404.241831) (xy 153.667514 -404.219189) (xy 153.621661 -404.18972) (xy 153.580469 -404.154026)
			(xy 153.544776 -404.112834) (xy 153.515309 -404.066981) (xy 153.492666 -404.017401) (xy 153.477311 -403.965103)
			(xy 153.469554 -403.911153) (xy 152.032021 -403.911153) (xy 152.024263 -403.965105) (xy 152.008906 -404.017403)
			(xy 151.986261 -404.066983) (xy 151.956791 -404.112836) (xy 151.921094 -404.154027) (xy 151.879899 -404.189718)
			(xy 151.834043 -404.219183) (xy 151.78446 -404.241822) (xy 151.73216 -404.257173) (xy 151.678207 -404.264924)
			(xy 151.650954 -404.265384) (xy 150.787354 -404.265384) (xy 150.760103 -404.264943) (xy 150.706157 -404.257181)
			(xy 150.653865 -404.241821) (xy 150.60429 -404.219175) (xy 150.558442 -404.189706) (xy 150.517255 -404.154012)
			(xy 150.481566 -404.112821) (xy 150.452102 -404.06697) (xy 150.429463 -404.017392) (xy 150.41411 -403.965098)
			(xy 150.406354 -403.911151) (xy 148.968698 -403.911151) (xy 148.960942 -403.965092) (xy 148.945589 -404.017382)
			(xy 148.92295 -404.066955) (xy 148.893487 -404.112802) (xy 148.857799 -404.153989) (xy 148.816613 -404.189679)
			(xy 148.770768 -404.219143) (xy 148.721195 -404.241784) (xy 148.668906 -404.257139) (xy 148.614963 -404.264897)
			(xy 148.587714 -404.265384) (xy 147.724114 -404.265384) (xy 147.696859 -404.26497) (xy 147.642903 -404.257214)
			(xy 147.5906 -404.241858) (xy 147.541015 -404.219215) (xy 147.495157 -404.189746) (xy 147.45396 -404.15405)
			(xy 147.418263 -404.112854) (xy 147.388791 -404.066997) (xy 147.366146 -404.017413) (xy 147.350789 -403.965111)
			(xy 147.343031 -403.911155) (xy 145.905521 -403.911155) (xy 145.897763 -403.965102) (xy 145.882407 -404.017399)
			(xy 145.859764 -404.066978) (xy 145.830296 -404.112829) (xy 145.794601 -404.15402) (xy 145.753408 -404.189711)
			(xy 145.707555 -404.219177) (xy 145.657974 -404.241816) (xy 145.605677 -404.257169) (xy 145.551726 -404.264922)
			(xy 145.524474 -404.265384) (xy 144.660874 -404.265384) (xy 144.633622 -404.264944) (xy 144.579674 -404.257184)
			(xy 144.527379 -404.241826) (xy 144.477802 -404.219182) (xy 144.431952 -404.189713) (xy 144.390762 -404.154019)
			(xy 144.355071 -404.112827) (xy 144.325606 -404.066975) (xy 144.302965 -404.017397) (xy 144.28761 -403.965101)
			(xy 144.279854 -403.911152) (xy 142.842197 -403.911152) (xy 142.834443 -403.965089) (xy 142.81909 -404.017378)
			(xy 142.796453 -404.06695) (xy 142.766992 -404.112796) (xy 142.731306 -404.153982) (xy 142.690123 -404.189671)
			(xy 142.64428 -404.219137) (xy 142.59471 -404.241778) (xy 142.542423 -404.257136) (xy 142.488482 -404.264895)
			(xy 142.461234 -404.265384) (xy 141.597634 -404.265384) (xy 141.570378 -404.264971) (xy 141.51642 -404.257218)
			(xy 141.464114 -404.241864) (xy 141.414527 -404.219222) (xy 141.368667 -404.189753) (xy 141.327467 -404.154057)
			(xy 141.291768 -404.112861) (xy 141.262295 -404.067003) (xy 141.239648 -404.017417) (xy 141.224289 -403.965114)
			(xy 141.216531 -403.911156) (xy 139.77902 -403.911156) (xy 139.771264 -403.965099) (xy 139.755909 -404.017394)
			(xy 139.733267 -404.066972) (xy 139.7038 -404.112822) (xy 139.668108 -404.154013) (xy 139.626918 -404.189704)
			(xy 139.581067 -404.21917) (xy 139.531489 -404.241811) (xy 139.479194 -404.257165) (xy 139.425245 -404.264921)
			(xy 139.397994 -404.265384) (xy 138.534394 -404.265384) (xy 138.507141 -404.264946) (xy 138.453191 -404.257188)
			(xy 138.400894 -404.241831) (xy 138.351314 -404.219189) (xy 138.305461 -404.18972) (xy 138.264269 -404.154026)
			(xy 138.228576 -404.112834) (xy 138.199109 -404.066981) (xy 138.176466 -404.017401) (xy 138.161111 -403.965103)
			(xy 138.153354 -403.911153) (xy 136.715821 -403.911153) (xy 136.708063 -403.965105) (xy 136.692706 -404.017403)
			(xy 136.670061 -404.066983) (xy 136.640591 -404.112836) (xy 136.604894 -404.154027) (xy 136.563699 -404.189718)
			(xy 136.517843 -404.219183) (xy 136.46826 -404.241822) (xy 136.41596 -404.257173) (xy 136.362007 -404.264924)
			(xy 136.334754 -404.265384) (xy 135.471154 -404.265384) (xy 135.443903 -404.264943) (xy 135.389957 -404.257181)
			(xy 135.337665 -404.241821) (xy 135.28809 -404.219175) (xy 135.242242 -404.189706) (xy 135.201055 -404.154012)
			(xy 135.165366 -404.112821) (xy 135.135902 -404.06697) (xy 135.113263 -404.017392) (xy 135.09791 -403.965098)
			(xy 135.090154 -403.911151) (xy 133.652498 -403.911151) (xy 133.644742 -403.965092) (xy 133.629389 -404.017382)
			(xy 133.60675 -404.066955) (xy 133.577287 -404.112802) (xy 133.541599 -404.153989) (xy 133.500413 -404.189679)
			(xy 133.454568 -404.219143) (xy 133.404995 -404.241784) (xy 133.352706 -404.257139) (xy 133.298763 -404.264897)
			(xy 133.271514 -404.265384) (xy 132.407914 -404.265384) (xy 132.380659 -404.26497) (xy 132.326703 -404.257214)
			(xy 132.2744 -404.241858) (xy 132.224815 -404.219215) (xy 132.178957 -404.189746) (xy 132.13776 -404.15405)
			(xy 132.102063 -404.112854) (xy 132.072591 -404.066997) (xy 132.049946 -404.017413) (xy 132.034589 -403.965111)
			(xy 132.026831 -403.911155) (xy 130.589321 -403.911155) (xy 130.581563 -403.965102) (xy 130.566207 -404.017399)
			(xy 130.543564 -404.066978) (xy 130.514096 -404.112829) (xy 130.478401 -404.15402) (xy 130.437208 -404.189711)
			(xy 130.391355 -404.219177) (xy 130.341774 -404.241816) (xy 130.289477 -404.257169) (xy 130.235526 -404.264922)
			(xy 130.208274 -404.265384) (xy 129.344674 -404.265384) (xy 129.317422 -404.264944) (xy 129.263474 -404.257184)
			(xy 129.211179 -404.241826) (xy 129.161602 -404.219182) (xy 129.115752 -404.189713) (xy 129.074562 -404.154019)
			(xy 129.038871 -404.112827) (xy 129.009406 -404.066975) (xy 128.986765 -404.017397) (xy 128.97141 -403.965101)
			(xy 128.963654 -403.911152) (xy 127.525997 -403.911152) (xy 127.518243 -403.965089) (xy 127.50289 -404.017378)
			(xy 127.480253 -404.06695) (xy 127.450792 -404.112796) (xy 127.415106 -404.153982) (xy 127.373923 -404.189671)
			(xy 127.32808 -404.219137) (xy 127.27851 -404.241778) (xy 127.226223 -404.257136) (xy 127.172282 -404.264895)
			(xy 127.145034 -404.265384) (xy 126.281434 -404.265384) (xy 126.254178 -404.264971) (xy 126.20022 -404.257218)
			(xy 126.147914 -404.241864) (xy 126.098327 -404.219222) (xy 126.052467 -404.189753) (xy 126.011267 -404.154057)
			(xy 125.975568 -404.112861) (xy 125.946095 -404.067003) (xy 125.923448 -404.017417) (xy 125.908089 -403.965114)
			(xy 125.900331 -403.911156) (xy 124.46282 -403.911156) (xy 124.455064 -403.965099) (xy 124.439709 -404.017394)
			(xy 124.417067 -404.066972) (xy 124.3876 -404.112822) (xy 124.351908 -404.154013) (xy 124.310718 -404.189704)
			(xy 124.264867 -404.21917) (xy 124.215289 -404.241811) (xy 124.162994 -404.257165) (xy 124.109045 -404.264921)
			(xy 124.081794 -404.265384) (xy 123.218194 -404.265384) (xy 123.190941 -404.264946) (xy 123.136991 -404.257188)
			(xy 123.084694 -404.241831) (xy 123.035114 -404.219189) (xy 122.989261 -404.18972) (xy 122.948069 -404.154026)
			(xy 122.912376 -404.112834) (xy 122.882909 -404.066981) (xy 122.860266 -404.017401) (xy 122.844911 -403.965103)
			(xy 122.837154 -403.911153) (xy 121.399621 -403.911153) (xy 121.391863 -403.965105) (xy 121.376506 -404.017403)
			(xy 121.353861 -404.066983) (xy 121.324391 -404.112836) (xy 121.288694 -404.154027) (xy 121.247499 -404.189718)
			(xy 121.201643 -404.219183) (xy 121.15206 -404.241822) (xy 121.09976 -404.257173) (xy 121.045807 -404.264924)
			(xy 121.018554 -404.265384) (xy 120.154954 -404.265384) (xy 120.127703 -404.264943) (xy 120.073757 -404.257181)
			(xy 120.021465 -404.241821) (xy 119.97189 -404.219175) (xy 119.926042 -404.189706) (xy 119.884855 -404.154012)
			(xy 119.849166 -404.112821) (xy 119.819702 -404.06697) (xy 119.797063 -404.017392) (xy 119.78171 -403.965098)
			(xy 119.773954 -403.911151) (xy 95.172998 -403.911151) (xy 95.165243 -403.965089) (xy 95.149891 -404.017377)
			(xy 95.127254 -404.066949) (xy 95.097793 -404.112794) (xy 95.062108 -404.153981) (xy 95.020925 -404.18967)
			(xy 94.975082 -404.219135) (xy 94.925513 -404.241777) (xy 94.873226 -404.257135) (xy 94.819286 -404.264895)
			(xy 94.792038 -404.265384) (xy 93.928438 -404.265384) (xy 93.901182 -404.264972) (xy 93.847223 -404.257219)
			(xy 93.794917 -404.241865) (xy 93.745329 -404.219223) (xy 93.699468 -404.189754) (xy 93.658269 -404.154058)
			(xy 93.622569 -404.112862) (xy 93.593095 -404.067004) (xy 93.570448 -404.017418) (xy 93.555089 -403.965114)
			(xy 93.547331 -403.911156) (xy 92.10982 -403.911156) (xy 92.102064 -403.965099) (xy 92.086709 -404.017394)
			(xy 92.064068 -404.066971) (xy 92.034601 -404.112821) (xy 91.99891 -404.154011) (xy 91.95772 -404.189703)
			(xy 91.911869 -404.219169) (xy 91.862292 -404.24181) (xy 91.809997 -404.257165) (xy 91.756049 -404.264921)
			(xy 91.728798 -404.265384) (xy 90.865198 -404.265384) (xy 90.837945 -404.264946) (xy 90.783994 -404.257189)
			(xy 90.731696 -404.241833) (xy 90.682116 -404.21919) (xy 90.636263 -404.189722) (xy 90.595071 -404.154028)
			(xy 90.559377 -404.112835) (xy 90.529909 -404.066982) (xy 90.507267 -404.017402) (xy 90.491911 -403.965104)
			(xy 90.484154 -403.911153) (xy 89.046621 -403.911153) (xy 89.038863 -403.965104) (xy 89.023506 -404.017402)
			(xy 89.000862 -404.066982) (xy 88.971392 -404.112834) (xy 88.935696 -404.154025) (xy 88.894501 -404.189717)
			(xy 88.848645 -404.219182) (xy 88.799063 -404.241821) (xy 88.746763 -404.257172) (xy 88.692811 -404.264924)
			(xy 88.665558 -404.265384) (xy 87.801958 -404.265384) (xy 87.774707 -404.264943) (xy 87.72076 -404.257181)
			(xy 87.668467 -404.241822) (xy 87.618892 -404.219177) (xy 87.573044 -404.189707) (xy 87.531857 -404.154014)
			(xy 87.496167 -404.112822) (xy 87.466703 -404.066971) (xy 87.444064 -404.017393) (xy 87.42871 -403.965098)
			(xy 87.420954 -403.911151) (xy 85.983298 -403.911151) (xy 85.975542 -403.965091) (xy 85.960189 -404.017381)
			(xy 85.937551 -404.066954) (xy 85.908088 -404.112801) (xy 85.872401 -404.153988) (xy 85.831215 -404.189677)
			(xy 85.78537 -404.219142) (xy 85.735798 -404.241783) (xy 85.683509 -404.257138) (xy 85.629567 -404.264897)
			(xy 85.602318 -404.265384) (xy 84.738718 -404.265384) (xy 84.711463 -404.26497) (xy 84.657506 -404.257215)
			(xy 84.605203 -404.241859) (xy 84.555617 -404.219217) (xy 84.509759 -404.189747) (xy 84.468562 -404.154051)
			(xy 84.432864 -404.112855) (xy 84.403392 -404.066999) (xy 84.380747 -404.017414) (xy 84.365389 -403.965111)
			(xy 84.357631 -403.911155) (xy 82.920121 -403.911155) (xy 82.912364 -403.965102) (xy 82.897007 -404.017398)
			(xy 82.874365 -404.066976) (xy 82.844897 -404.112828) (xy 82.809203 -404.154018) (xy 82.76801 -404.18971)
			(xy 82.722157 -404.219175) (xy 82.672577 -404.241815) (xy 82.62028 -404.257168) (xy 82.56633 -404.264922)
			(xy 82.539078 -404.265384) (xy 81.675478 -404.265384) (xy 81.648226 -404.264945) (xy 81.594277 -404.257185)
			(xy 81.541982 -404.241827) (xy 81.492404 -404.219183) (xy 81.446554 -404.189715) (xy 81.405364 -404.154021)
			(xy 81.369672 -404.112829) (xy 81.340206 -404.066976) (xy 81.317565 -404.017397) (xy 81.30221 -403.965101)
			(xy 81.294454 -403.911152) (xy 79.856797 -403.911152) (xy 79.849043 -403.965089) (xy 79.833691 -404.017377)
			(xy 79.811054 -404.066949) (xy 79.781593 -404.112794) (xy 79.745908 -404.153981) (xy 79.704725 -404.18967)
			(xy 79.658882 -404.219135) (xy 79.609313 -404.241777) (xy 79.557026 -404.257135) (xy 79.503086 -404.264895)
			(xy 79.475838 -404.265384) (xy 78.612238 -404.265384) (xy 78.584982 -404.264972) (xy 78.531023 -404.257219)
			(xy 78.478717 -404.241865) (xy 78.429129 -404.219223) (xy 78.383268 -404.189754) (xy 78.342069 -404.154058)
			(xy 78.306369 -404.112862) (xy 78.276895 -404.067004) (xy 78.254248 -404.017418) (xy 78.238889 -403.965114)
			(xy 78.231131 -403.911156) (xy 76.79362 -403.911156) (xy 76.785864 -403.965099) (xy 76.770509 -404.017394)
			(xy 76.747868 -404.066971) (xy 76.718401 -404.112821) (xy 76.68271 -404.154011) (xy 76.64152 -404.189703)
			(xy 76.595669 -404.219169) (xy 76.546092 -404.24181) (xy 76.493797 -404.257165) (xy 76.439849 -404.264921)
			(xy 76.412598 -404.265384) (xy 75.548998 -404.265384) (xy 75.521745 -404.264946) (xy 75.467794 -404.257189)
			(xy 75.415496 -404.241833) (xy 75.365916 -404.21919) (xy 75.320063 -404.189722) (xy 75.278871 -404.154028)
			(xy 75.243177 -404.112835) (xy 75.213709 -404.066982) (xy 75.191067 -404.017402) (xy 75.175711 -403.965104)
			(xy 75.167954 -403.911153) (xy 73.730421 -403.911153) (xy 73.722663 -403.965104) (xy 73.707306 -404.017402)
			(xy 73.684662 -404.066982) (xy 73.655192 -404.112834) (xy 73.619496 -404.154025) (xy 73.578301 -404.189717)
			(xy 73.532445 -404.219182) (xy 73.482863 -404.241821) (xy 73.430563 -404.257172) (xy 73.376611 -404.264924)
			(xy 73.349358 -404.265384) (xy 72.485758 -404.265384) (xy 72.458507 -404.264943) (xy 72.40456 -404.257181)
			(xy 72.352267 -404.241822) (xy 72.302692 -404.219177) (xy 72.256844 -404.189707) (xy 72.215657 -404.154014)
			(xy 72.179967 -404.112822) (xy 72.150503 -404.066971) (xy 72.127864 -404.017393) (xy 72.11251 -403.965098)
			(xy 72.104754 -403.911151) (xy 70.667098 -403.911151) (xy 70.659342 -403.965091) (xy 70.643989 -404.017381)
			(xy 70.621351 -404.066954) (xy 70.591888 -404.112801) (xy 70.556201 -404.153988) (xy 70.515015 -404.189677)
			(xy 70.46917 -404.219142) (xy 70.419598 -404.241783) (xy 70.367309 -404.257138) (xy 70.313367 -404.264897)
			(xy 70.286118 -404.265384) (xy 69.422518 -404.265384) (xy 69.395263 -404.26497) (xy 69.341306 -404.257215)
			(xy 69.289003 -404.241859) (xy 69.239417 -404.219217) (xy 69.193559 -404.189747) (xy 69.152362 -404.154051)
			(xy 69.116664 -404.112855) (xy 69.087192 -404.066999) (xy 69.064547 -404.017414) (xy 69.049189 -403.965111)
			(xy 69.041431 -403.911155) (xy 67.603921 -403.911155) (xy 67.596164 -403.965102) (xy 67.580807 -404.017398)
			(xy 67.558165 -404.066976) (xy 67.528697 -404.112828) (xy 67.493003 -404.154018) (xy 67.45181 -404.18971)
			(xy 67.405957 -404.219175) (xy 67.356377 -404.241815) (xy 67.30408 -404.257168) (xy 67.25013 -404.264922)
			(xy 67.222878 -404.265384) (xy 66.359278 -404.265384) (xy 66.332026 -404.264945) (xy 66.278077 -404.257185)
			(xy 66.225782 -404.241827) (xy 66.176204 -404.219183) (xy 66.130354 -404.189715) (xy 66.089164 -404.154021)
			(xy 66.053472 -404.112829) (xy 66.024006 -404.066976) (xy 66.001365 -404.017397) (xy 65.98601 -403.965101)
			(xy 65.978254 -403.911152) (xy 64.540597 -403.911152) (xy 64.532843 -403.965089) (xy 64.517491 -404.017377)
			(xy 64.494854 -404.066949) (xy 64.465393 -404.112794) (xy 64.429708 -404.153981) (xy 64.388525 -404.18967)
			(xy 64.342682 -404.219135) (xy 64.293113 -404.241777) (xy 64.240826 -404.257135) (xy 64.186886 -404.264895)
			(xy 64.159638 -404.265384) (xy 63.296038 -404.265384) (xy 63.268782 -404.264972) (xy 63.214823 -404.257219)
			(xy 63.162517 -404.241865) (xy 63.112929 -404.219223) (xy 63.067068 -404.189754) (xy 63.025869 -404.154058)
			(xy 62.990169 -404.112862) (xy 62.960695 -404.067004) (xy 62.938048 -404.017418) (xy 62.922689 -403.965114)
			(xy 62.914931 -403.911156) (xy 61.47742 -403.911156) (xy 61.469664 -403.965099) (xy 61.454309 -404.017394)
			(xy 61.431668 -404.066971) (xy 61.402201 -404.112821) (xy 61.36651 -404.154011) (xy 61.32532 -404.189703)
			(xy 61.279469 -404.219169) (xy 61.229892 -404.24181) (xy 61.177597 -404.257165) (xy 61.123649 -404.264921)
			(xy 61.096398 -404.265384) (xy 60.232798 -404.265384) (xy 60.205545 -404.264946) (xy 60.151594 -404.257189)
			(xy 60.099296 -404.241833) (xy 60.049716 -404.21919) (xy 60.003863 -404.189722) (xy 59.962671 -404.154028)
			(xy 59.926977 -404.112835) (xy 59.897509 -404.066982) (xy 59.874867 -404.017402) (xy 59.859511 -403.965104)
			(xy 59.851754 -403.911153) (xy 58.414221 -403.911153) (xy 58.406463 -403.965104) (xy 58.391106 -404.017402)
			(xy 58.368462 -404.066982) (xy 58.338992 -404.112834) (xy 58.303296 -404.154025) (xy 58.262101 -404.189717)
			(xy 58.216245 -404.219182) (xy 58.166663 -404.241821) (xy 58.114363 -404.257172) (xy 58.060411 -404.264924)
			(xy 58.033158 -404.265384) (xy 57.169558 -404.265384) (xy 57.142307 -404.264943) (xy 57.08836 -404.257181)
			(xy 57.036067 -404.241822) (xy 56.986492 -404.219177) (xy 56.940644 -404.189707) (xy 56.899457 -404.154014)
			(xy 56.863767 -404.112822) (xy 56.834303 -404.066971) (xy 56.811664 -404.017393) (xy 56.79631 -403.965098)
			(xy 56.788554 -403.911151) (xy 55.350898 -403.911151) (xy 55.343142 -403.965091) (xy 55.327789 -404.017381)
			(xy 55.305151 -404.066954) (xy 55.275688 -404.112801) (xy 55.240001 -404.153988) (xy 55.198815 -404.189677)
			(xy 55.15297 -404.219142) (xy 55.103398 -404.241783) (xy 55.051109 -404.257138) (xy 54.997167 -404.264897)
			(xy 54.969918 -404.265384) (xy 54.106318 -404.265384) (xy 54.079063 -404.26497) (xy 54.025106 -404.257215)
			(xy 53.972803 -404.241859) (xy 53.923217 -404.219217) (xy 53.877359 -404.189747) (xy 53.836162 -404.154051)
			(xy 53.800464 -404.112855) (xy 53.770992 -404.066999) (xy 53.748347 -404.017414) (xy 53.732989 -403.965111)
			(xy 53.725231 -403.911155) (xy 52.287721 -403.911155) (xy 52.279964 -403.965102) (xy 52.264607 -404.017398)
			(xy 52.241965 -404.066976) (xy 52.212497 -404.112828) (xy 52.176803 -404.154018) (xy 52.13561 -404.18971)
			(xy 52.089757 -404.219175) (xy 52.040177 -404.241815) (xy 51.98788 -404.257168) (xy 51.93393 -404.264922)
			(xy 51.906678 -404.265384) (xy 51.043078 -404.265384) (xy 51.015826 -404.264945) (xy 50.961877 -404.257185)
			(xy 50.909582 -404.241827) (xy 50.860004 -404.219183) (xy 50.814154 -404.189715) (xy 50.772964 -404.154021)
			(xy 50.737272 -404.112829) (xy 50.707806 -404.066976) (xy 50.685165 -404.017397) (xy 50.66981 -403.965101)
			(xy 50.662054 -403.911152) (xy 49.224397 -403.911152) (xy 49.216643 -403.965089) (xy 49.201291 -404.017377)
			(xy 49.178654 -404.066949) (xy 49.149193 -404.112794) (xy 49.113508 -404.153981) (xy 49.072325 -404.18967)
			(xy 49.026482 -404.219135) (xy 48.976913 -404.241777) (xy 48.924626 -404.257135) (xy 48.870686 -404.264895)
			(xy 48.843438 -404.265384) (xy 47.979838 -404.265384) (xy 47.952582 -404.264972) (xy 47.898623 -404.257219)
			(xy 47.846317 -404.241865) (xy 47.796729 -404.219223) (xy 47.750868 -404.189754) (xy 47.709669 -404.154058)
			(xy 47.673969 -404.112862) (xy 47.644495 -404.067004) (xy 47.621848 -404.017418) (xy 47.606489 -403.965114)
			(xy 47.598731 -403.911156) (xy 2.610452 -403.911156) (xy 2.622121 -403.942439) (xy 2.666338 -404.039266)
			(xy 2.717346 -404.132693) (xy 2.774884 -404.222247) (xy 2.838661 -404.307471) (xy 2.908351 -404.387931)
			(xy 2.945638 -404.425912) (xy 3.748786 -405.22906) (xy 102.242112 -405.22906) (xy 102.242112 -404.36546)
			(xy 102.242598 -404.338209) (xy 102.250354 -404.284261) (xy 102.265709 -404.231966) (xy 102.288351 -404.182389)
			(xy 102.317817 -404.136539) (xy 102.353508 -404.095348) (xy 102.394699 -404.059657) (xy 102.440549 -404.030191)
			(xy 102.490126 -404.007549) (xy 102.542421 -403.992194) (xy 102.596369 -403.984438) (xy 102.650871 -403.984438)
			(xy 102.704819 -403.992194) (xy 102.757114 -404.007549) (xy 102.806691 -404.030191) (xy 102.852541 -404.059657)
			(xy 102.893732 -404.095348) (xy 102.929423 -404.136539) (xy 102.958889 -404.182389) (xy 102.981531 -404.231966)
			(xy 102.996886 -404.284261) (xy 103.004642 -404.338209) (xy 103.005128 -404.36546) (xy 103.005128 -405.22906)
			(xy 103.004642 -405.256311) (xy 102.996886 -405.310259) (xy 102.981531 -405.362554) (xy 102.958889 -405.412131)
			(xy 102.929423 -405.457981) (xy 102.893732 -405.499172) (xy 102.852541 -405.534863) (xy 102.806691 -405.564329)
			(xy 102.757114 -405.586971) (xy 102.704819 -405.602326) (xy 102.650871 -405.610082) (xy 102.596369 -405.610082)
			(xy 102.542421 -405.602326) (xy 102.490126 -405.586971) (xy 102.440549 -405.564329) (xy 102.394699 -405.534863)
			(xy 102.353508 -405.499172) (xy 102.317817 -405.457981) (xy 102.288351 -405.412131) (xy 102.265709 -405.362554)
			(xy 102.250354 -405.310259) (xy 102.242598 -405.256311) (xy 102.242112 -405.22906) (xy 3.748786 -405.22906)
			(xy 5.555234 -407.035508) (xy 15.978632 -407.035508) (xy 15.978632 -406.171908) (xy 15.979118 -406.144657)
			(xy 15.986874 -406.090709) (xy 16.002229 -406.038414) (xy 16.024871 -405.988837) (xy 16.054337 -405.942987)
			(xy 16.090028 -405.901796) (xy 16.131219 -405.866105) (xy 16.177069 -405.836639) (xy 16.226646 -405.813997)
			(xy 16.278941 -405.798642) (xy 16.332889 -405.790886) (xy 16.387391 -405.790886) (xy 16.441339 -405.798642)
			(xy 16.493634 -405.813997) (xy 16.543211 -405.836639) (xy 16.589061 -405.866105) (xy 16.630252 -405.901796)
			(xy 16.665943 -405.942987) (xy 16.695409 -405.988837) (xy 16.718051 -406.038414) (xy 16.733406 -406.090709)
			(xy 16.741162 -406.144657) (xy 16.741648 -406.171908) (xy 16.741648 -406.620726) (xy 184.561988 -406.620726)
			(xy 184.561988 -400.685254) (xy 184.562447 -400.660304) (xy 184.570259 -400.611019) (xy 184.585684 -400.563563)
			(xy 184.608342 -400.519104) (xy 184.637676 -400.478736) (xy 184.672962 -400.443454) (xy 184.713333 -400.414125)
			(xy 184.757795 -400.391471) (xy 184.805253 -400.376051) (xy 184.854538 -400.368244) (xy 184.879488 -400.367754)
			(xy 188.73343 -400.367754) (xy 188.758609 -400.368272) (xy 188.808334 -400.376233) (xy 188.856176 -400.39195)
			(xy 188.900934 -400.415029) (xy 188.941484 -400.444889) (xy 188.95949 -400.462496) (xy 189.16142 -400.667474)
			(xy 189.178411 -400.68542) (xy 189.207232 -400.725562) (xy 189.229493 -400.76968) (xy 189.244658 -400.816712)
			(xy 189.252363 -400.865524) (xy 189.25286 -400.890232) (xy 189.25286 -403.517354) (xy 189.46876 -403.517354)
			(xy 189.49371 -403.51783) (xy 189.542993 -403.525649) (xy 189.590451 -403.541071) (xy 189.634916 -403.563718)
			(xy 189.675298 -403.593032) (xy 189.693296 -403.610318) (xy 189.904624 -403.821646) (xy 189.921945 -403.839613)
			(xy 189.951264 -403.879997) (xy 189.973905 -403.92447) (xy 189.989312 -403.971937) (xy 189.997105 -404.021229)
			(xy 189.997588 -404.046182) (xy 189.997588 -404.34641) (xy 190.325756 -404.674832) (xy 190.350648 -404.671276)
			(xy 190.363288 -404.669701) (xy 190.38871 -404.668051) (xy 190.401448 -404.667974) (xy 190.4287 -404.668433)
			(xy 190.482647 -404.676196) (xy 190.534941 -404.691556) (xy 190.584518 -404.714201) (xy 190.630367 -404.743671)
			(xy 190.671556 -404.779365) (xy 190.707247 -404.820557) (xy 190.736713 -404.866409) (xy 190.759355 -404.915987)
			(xy 190.774711 -404.968282) (xy 190.782469 -405.02223) (xy 190.782956 -405.049482) (xy 190.782871 -405.06222)
			(xy 190.781219 -405.087641) (xy 190.779654 -405.100282) (xy 190.776098 -405.125174) (xy 191.001904 -405.35098)
			(xy 196.838316 -405.35098) (xy 197.83298 -404.356316) (xy 197.83298 -400.893788) (xy 197.833478 -400.868839)
			(xy 197.841291 -400.819556) (xy 197.856708 -400.772099) (xy 197.879349 -400.727633) (xy 197.908659 -400.68725)
			(xy 197.925944 -400.669252) (xy 198.116952 -400.478244) (xy 198.134911 -400.460913) (xy 198.175295 -400.431588)
			(xy 198.219769 -400.408941) (xy 198.267238 -400.393531) (xy 198.316534 -400.385737) (xy 198.341488 -400.38528)
			(xy 201.995532 -400.38528) (xy 202.020482 -400.385766) (xy 202.069765 -400.393582) (xy 202.117222 -400.409001)
			(xy 202.161688 -400.431645) (xy 202.20207 -400.460958) (xy 202.220068 -400.478244) (xy 202.418696 -400.676872)
			(xy 202.435977 -400.694876) (xy 202.465302 -400.73525) (xy 202.487952 -400.779713) (xy 202.503368 -400.827172)
			(xy 202.511171 -400.876458) (xy 202.51166 -400.901408) (xy 202.51166 -404.330916) (xy 202.604624 -404.42388)
			(xy 202.621913 -404.441876) (xy 202.651236 -404.482252) (xy 202.673884 -404.526718) (xy 202.689298 -404.574178)
			(xy 202.6971 -404.623466) (xy 202.697588 -404.648416) (xy 202.697588 -407.475436) (xy 204.291692 -409.06954)
			(xy 206.414116 -409.06954) (xy 208.310988 -407.172668) (xy 208.310988 -404.642828) (xy 208.311509 -404.61788)
			(xy 208.319316 -404.568598) (xy 208.334727 -404.521141) (xy 208.357363 -404.476674) (xy 208.386669 -404.436291)
			(xy 208.403952 -404.418292) (xy 208.50098 -404.321264) (xy 208.50098 -400.893788) (xy 208.501478 -400.868839)
			(xy 208.509291 -400.819556) (xy 208.524708 -400.772099) (xy 208.547349 -400.727633) (xy 208.576659 -400.68725)
			(xy 208.593944 -400.669252) (xy 208.784952 -400.478244) (xy 208.802911 -400.460913) (xy 208.843295 -400.431588)
			(xy 208.887769 -400.408941) (xy 208.935238 -400.393531) (xy 208.984534 -400.385737) (xy 209.009488 -400.38528)
			(xy 212.668612 -400.38528) (xy 212.693561 -400.385778) (xy 212.742844 -400.393591) (xy 212.790301 -400.409008)
			(xy 212.834767 -400.431649) (xy 212.87515 -400.460959) (xy 212.893148 -400.478244) (xy 213.084156 -400.669252)
			(xy 213.101487 -400.687211) (xy 213.130812 -400.727595) (xy 213.153459 -400.772069) (xy 213.168869 -400.819538)
			(xy 213.176663 -400.868834) (xy 213.17712 -400.893788) (xy 213.17712 -404.353776) (xy 213.261956 -404.438612)
			(xy 213.279249 -404.456605) (xy 213.308574 -404.496981) (xy 213.331222 -404.541447) (xy 213.346636 -404.588909)
			(xy 213.354434 -404.638197) (xy 213.35492 -404.663148) (xy 213.35492 -407.394156) (xy 214.926164 -408.9654)
			(xy 217.141044 -408.9654) (xy 218.978988 -407.127456) (xy 218.978988 -404.673308) (xy 218.979496 -404.648359)
			(xy 218.987307 -404.599077) (xy 219.00272 -404.55162) (xy 219.02536 -404.507153) (xy 219.054668 -404.46677)
			(xy 219.071952 -404.448772) (xy 219.16136 -404.359364) (xy 219.16136 -400.906488) (xy 219.161864 -400.881539)
			(xy 219.169676 -400.832257) (xy 219.185092 -400.7848) (xy 219.207732 -400.740334) (xy 219.23704 -400.699951)
			(xy 219.254324 -400.681952) (xy 219.458032 -400.478244) (xy 219.476 -400.460922) (xy 219.516381 -400.431596)
			(xy 219.560853 -400.408948) (xy 219.60832 -400.393535) (xy 219.657614 -400.385739) (xy 219.682568 -400.38528)
			(xy 223.323912 -400.38528) (xy 223.348861 -400.385778) (xy 223.398144 -400.393591) (xy 223.445601 -400.409008)
			(xy 223.490067 -400.431649) (xy 223.53045 -400.460959) (xy 223.548448 -400.478244) (xy 223.759776 -400.689572)
			(xy 223.777053 -400.707579) (xy 223.80638 -400.747952) (xy 223.82903 -400.792414) (xy 223.844447 -400.839873)
			(xy 223.852251 -400.889158) (xy 223.85274 -400.914108) (xy 223.85274 -404.348188) (xy 223.940624 -404.436072)
			(xy 223.957909 -404.454071) (xy 223.987233 -404.494447) (xy 224.009881 -404.538912) (xy 224.025297 -404.586371)
			(xy 224.0331 -404.635658) (xy 224.033588 -404.660608) (xy 224.033588 -407.272236) (xy 225.838512 -409.07716)
			(xy 227.803456 -409.07716) (xy 229.621588 -407.259028) (xy 229.621588 -404.678388) (xy 229.622084 -404.653439)
			(xy 229.629897 -404.604156) (xy 229.645314 -404.556698) (xy 229.667956 -404.512233) (xy 229.697267 -404.47185)
			(xy 229.714552 -404.453852) (xy 229.82682 -404.341584) (xy 229.82682 -400.901408) (xy 229.827348 -400.87646)
			(xy 229.835156 -400.82718) (xy 229.850567 -400.779723) (xy 229.873201 -400.735257) (xy 229.902503 -400.694872)
			(xy 229.919784 -400.676872) (xy 230.120952 -400.475704) (xy 230.138921 -400.458385) (xy 230.179304 -400.429065)
			(xy 230.223776 -400.406422) (xy 230.271243 -400.391015) (xy 230.320536 -400.383222) (xy 230.345488 -400.38274)
			(xy 233.996992 -400.38274) (xy 234.02194 -400.383262) (xy 234.071221 -400.391071) (xy 234.118678 -400.406483)
			(xy 234.163144 -400.429118) (xy 234.203528 -400.458422) (xy 234.221528 -400.475704) (xy 234.422696 -400.676872)
			(xy 234.439977 -400.694876) (xy 234.469302 -400.73525) (xy 234.491952 -400.779713) (xy 234.507368 -400.827172)
			(xy 234.515171 -400.876458) (xy 234.51566 -400.901408) (xy 234.51566 -404.346156) (xy 235.652564 -405.48306)
			(xy 237.746032 -405.48306) (xy 237.770981 -405.483551) (xy 237.820264 -405.491367) (xy 237.867721 -405.506785)
			(xy 237.912187 -405.529428) (xy 237.95257 -405.558739) (xy 237.970568 -405.576024) (xy 238.814356 -406.419812)
			(xy 238.968788 -406.419812) (xy 239.014 -406.3746) (xy 239.014 -397.839946) (xy 239.014705 -397.809318)
			(xy 239.02648 -397.749203) (xy 239.037368 -397.720566) (xy 239.093502 -397.582136) (xy 239.102124 -397.561821)
			(xy 239.124183 -397.523596) (xy 239.151323 -397.488796) (xy 239.166908 -397.47317) (xy 239.218978 -397.423132)
			(xy 239.692688 -396.949422) (xy 239.720237 -396.922524) (xy 239.780375 -396.87444) (xy 239.845524 -396.833399)
			(xy 239.914862 -396.799918) (xy 239.987515 -396.774419) (xy 240.062568 -396.757222) (xy 240.139075 -396.748545)
			(xy 240.177574 -396.748) (xy 274.117054 -396.748) (xy 274.147682 -396.748705) (xy 274.207797 -396.76048)
			(xy 274.236434 -396.771368) (xy 274.374864 -396.827502) (xy 274.395179 -396.836124) (xy 274.433404 -396.858183)
			(xy 274.468204 -396.885323) (xy 274.48383 -396.900908) (xy 274.533868 -396.952978) (xy 274.753578 -397.172688)
			(xy 274.777454 -397.19758) (xy 274.787032 -397.207432) (xy 274.810234 -397.222125) (xy 274.836515 -397.230094)
			(xy 274.86397 -397.230762) (xy 274.890608 -397.22408) (xy 274.914497 -397.210532) (xy 274.92452 -397.201136)
			(xy 275.284692 -396.840964) (xy 275.302681 -396.823665) (xy 275.343056 -396.794335) (xy 275.387522 -396.771682)
			(xy 275.434985 -396.756264) (xy 275.484276 -396.748462) (xy 275.509228 -396.748) (xy 280.83764 -396.748)
			(xy 280.86259 -396.748475) (xy 280.911874 -396.756293) (xy 280.959332 -396.771714) (xy 281.003797 -396.794361)
			(xy 281.044179 -396.823677) (xy 281.062176 -396.840964) (xy 281.593544 -397.372332) (xy 281.610864 -397.390302)
			(xy 281.640191 -397.430682) (xy 281.66284 -397.475154) (xy 281.678252 -397.522621) (xy 281.686049 -397.571915)
			(xy 281.686508 -397.596868) (xy 281.686508 -398.65534) (xy 457.185003 -398.65534) (xy 457.185003 -398.5262)
			(xy 457.192953 -398.397305) (xy 457.208823 -398.269145) (xy 457.232552 -398.142204) (xy 457.264051 -398.016965)
			(xy 457.3032 -397.893902) (xy 457.349851 -397.773483) (xy 457.403826 -397.656164) (xy 457.464921 -397.54239)
			(xy 457.532904 -397.432593) (xy 457.607518 -397.32719) (xy 457.688479 -397.22658) (xy 457.775479 -397.131145)
			(xy 457.86819 -397.041246) (xy 457.96626 -396.957225) (xy 458.069315 -396.879401) (xy 458.176966 -396.808069)
			(xy 458.288805 -396.743499) (xy 458.404406 -396.685937) (xy 458.523331 -396.6356) (xy 458.64513 -396.59268)
			(xy 458.76934 -396.557339) (xy 458.895489 -396.529712) (xy 459.023101 -396.509903) (xy 459.15169 -396.497987)
			(xy 459.280768 -396.494011) (xy 459.409846 -396.497987) (xy 459.538435 -396.509903) (xy 459.666047 -396.529712)
			(xy 459.792196 -396.557339) (xy 459.916406 -396.59268) (xy 460.038205 -396.6356) (xy 460.15713 -396.685937)
			(xy 460.272731 -396.743499) (xy 460.38457 -396.808069) (xy 460.492221 -396.879401) (xy 460.595276 -396.957225)
			(xy 460.693346 -397.041246) (xy 460.786057 -397.131145) (xy 460.873057 -397.22658) (xy 460.954018 -397.32719)
			(xy 461.028632 -397.432593) (xy 461.096615 -397.54239) (xy 461.15771 -397.656164) (xy 461.211685 -397.773483)
			(xy 461.258336 -397.893902) (xy 461.297485 -398.016965) (xy 461.328984 -398.142204) (xy 461.352713 -398.269145)
			(xy 461.368583 -398.397305) (xy 461.376533 -398.5262) (xy 461.37703 -398.59077) (xy 461.376533 -398.65534)
			(xy 461.368583 -398.784235) (xy 461.352713 -398.912395) (xy 461.328984 -399.039336) (xy 461.297485 -399.164575)
			(xy 461.258336 -399.287638) (xy 461.211685 -399.408057) (xy 461.15771 -399.525376) (xy 461.096615 -399.63915)
			(xy 461.028632 -399.748947) (xy 460.954018 -399.85435) (xy 460.873057 -399.95496) (xy 460.786057 -400.050395)
			(xy 460.693346 -400.140294) (xy 460.595276 -400.224315) (xy 460.492221 -400.302139) (xy 460.38457 -400.373471)
			(xy 460.272731 -400.438041) (xy 460.15713 -400.495603) (xy 460.038205 -400.54594) (xy 459.916406 -400.58886)
			(xy 459.792196 -400.624201) (xy 459.666047 -400.651828) (xy 459.538435 -400.671637) (xy 459.409846 -400.683553)
			(xy 459.280768 -400.68753) (xy 459.15169 -400.683553) (xy 459.023101 -400.671637) (xy 458.895489 -400.651828)
			(xy 458.76934 -400.624201) (xy 458.64513 -400.58886) (xy 458.523331 -400.54594) (xy 458.404406 -400.495603)
			(xy 458.288805 -400.438041) (xy 458.176966 -400.373471) (xy 458.069315 -400.302139) (xy 457.96626 -400.224315)
			(xy 457.86819 -400.140294) (xy 457.775479 -400.050395) (xy 457.688479 -399.95496) (xy 457.607518 -399.85435)
			(xy 457.532904 -399.748947) (xy 457.464921 -399.63915) (xy 457.403826 -399.525376) (xy 457.349851 -399.408057)
			(xy 457.3032 -399.287638) (xy 457.264051 -399.164575) (xy 457.232552 -399.039336) (xy 457.208823 -398.912395)
			(xy 457.192953 -398.784235) (xy 457.185003 -398.65534) (xy 281.686508 -398.65534) (xy 281.686508 -399.9835)
			(xy 289.606441 -399.9835) (xy 289.610455 -399.919698) (xy 289.622434 -399.856902) (xy 289.642189 -399.796103)
			(xy 289.669408 -399.73826) (xy 289.703662 -399.684283) (xy 289.744411 -399.635026) (xy 289.791013 -399.591264)
			(xy 289.842731 -399.553688) (xy 289.898752 -399.52289) (xy 289.958191 -399.499357) (xy 290.02011 -399.483458)
			(xy 290.083534 -399.475446) (xy 290.115498 -399.474944) (xy 290.115752 -399.474944) (xy 290.147498 -399.475464)
			(xy 290.210494 -399.483393) (xy 290.272014 -399.499096) (xy 290.331102 -399.52233) (xy 290.386842 -399.552733)
			(xy 290.438367 -399.589834) (xy 290.461954 -399.611088) (xy 290.469217 -399.617272) (xy 290.486967 -399.624223)
			(xy 290.506029 -399.624223) (xy 290.523779 -399.617272) (xy 290.531042 -399.611088) (xy 290.554631 -399.589832)
			(xy 290.60614 -399.5527) (xy 290.661874 -399.522276) (xy 290.720965 -399.499035) (xy 290.782492 -399.483338)
			(xy 290.845495 -399.475431) (xy 290.877244 -399.474944) (xy 290.877498 -399.474944) (xy 290.909457 -399.475521)
			(xy 290.972872 -399.483532) (xy 291.034783 -399.499427) (xy 291.094213 -399.522957) (xy 291.150226 -399.55375)
			(xy 291.201937 -399.591321) (xy 291.248532 -399.635076) (xy 291.289276 -399.684326) (xy 291.323525 -399.738295)
			(xy 291.350741 -399.79613) (xy 291.370493 -399.856921) (xy 291.38247 -399.919707) (xy 291.386484 -399.9835)
			(xy 292.146441 -399.9835) (xy 292.150455 -399.919698) (xy 292.162434 -399.856902) (xy 292.182189 -399.796103)
			(xy 292.209408 -399.73826) (xy 292.243662 -399.684283) (xy 292.284411 -399.635026) (xy 292.331013 -399.591264)
			(xy 292.382731 -399.553688) (xy 292.438752 -399.52289) (xy 292.498191 -399.499357) (xy 292.56011 -399.483458)
			(xy 292.623534 -399.475446) (xy 292.655498 -399.474944) (xy 292.655752 -399.474944) (xy 292.687498 -399.475464)
			(xy 292.750494 -399.483393) (xy 292.812014 -399.499096) (xy 292.871102 -399.52233) (xy 292.926842 -399.552733)
			(xy 292.978367 -399.589834) (xy 293.001954 -399.611088) (xy 293.009217 -399.617272) (xy 293.026967 -399.624223)
			(xy 293.046029 -399.624223) (xy 293.063779 -399.617272) (xy 293.071042 -399.611088) (xy 293.094631 -399.589832)
			(xy 293.14614 -399.5527) (xy 293.201874 -399.522276) (xy 293.260965 -399.499035) (xy 293.322492 -399.483338)
			(xy 293.385495 -399.475431) (xy 293.417244 -399.474944) (xy 293.417498 -399.474944) (xy 293.449457 -399.475521)
			(xy 293.512872 -399.483532) (xy 293.574783 -399.499427) (xy 293.634213 -399.522957) (xy 293.690226 -399.55375)
			(xy 293.741937 -399.591321) (xy 293.788532 -399.635076) (xy 293.829276 -399.684326) (xy 293.863525 -399.738295)
			(xy 293.890741 -399.79613) (xy 293.910493 -399.856921) (xy 293.92247 -399.919707) (xy 293.926484 -399.9835)
			(xy 294.53602 -399.9835) (xy 294.540035 -399.919693) (xy 294.552015 -399.856892) (xy 294.571773 -399.796089)
			(xy 294.598995 -399.738241) (xy 294.633253 -399.684261) (xy 294.674007 -399.635001) (xy 294.720613 -399.591237)
			(xy 294.772338 -399.55366) (xy 294.828364 -399.522862) (xy 294.887809 -399.499329) (xy 294.949734 -399.483433)
			(xy 295.013163 -399.475423) (xy 295.04513 -399.474944) (xy 295.045384 -399.474944) (xy 295.077131 -399.475444)
			(xy 295.140127 -399.483377) (xy 295.201647 -399.499084) (xy 295.260736 -399.522322) (xy 295.316476 -399.552728)
			(xy 295.368 -399.589832) (xy 295.391586 -399.611088) (xy 295.398849 -399.617272) (xy 295.416599 -399.624223)
			(xy 295.435661 -399.624223) (xy 295.453411 -399.617272) (xy 295.460674 -399.611088) (xy 295.48425 -399.589817)
			(xy 295.535761 -399.552686) (xy 295.591498 -399.522265) (xy 295.650592 -399.499026) (xy 295.712121 -399.483332)
			(xy 295.775126 -399.475429) (xy 295.806876 -399.474944) (xy 295.80713 -399.474944) (xy 295.839087 -399.475544)
			(xy 295.902496 -399.483558) (xy 295.964401 -399.499455) (xy 296.023825 -399.522986) (xy 296.079832 -399.553779)
			(xy 296.131538 -399.591348) (xy 296.178128 -399.635102) (xy 296.218866 -399.684349) (xy 296.253112 -399.738314)
			(xy 296.280324 -399.796145) (xy 296.300074 -399.856931) (xy 296.312049 -399.919712) (xy 296.316063 -399.9835)
			(xy 297.07602 -399.9835) (xy 297.080035 -399.919693) (xy 297.092015 -399.856892) (xy 297.111773 -399.796089)
			(xy 297.138995 -399.738241) (xy 297.173253 -399.684261) (xy 297.214007 -399.635001) (xy 297.260613 -399.591237)
			(xy 297.312338 -399.55366) (xy 297.368364 -399.522862) (xy 297.427809 -399.499329) (xy 297.489734 -399.483433)
			(xy 297.553163 -399.475423) (xy 297.58513 -399.474944) (xy 297.585384 -399.474944) (xy 297.617131 -399.475444)
			(xy 297.680127 -399.483377) (xy 297.741647 -399.499084) (xy 297.800736 -399.522322) (xy 297.856476 -399.552728)
			(xy 297.908 -399.589832) (xy 297.931586 -399.611088) (xy 297.938849 -399.617272) (xy 297.956599 -399.624223)
			(xy 297.975661 -399.624223) (xy 297.993411 -399.617272) (xy 298.000674 -399.611088) (xy 298.02425 -399.589817)
			(xy 298.075761 -399.552686) (xy 298.131498 -399.522265) (xy 298.190592 -399.499026) (xy 298.252121 -399.483332)
			(xy 298.315126 -399.475429) (xy 298.346876 -399.474944) (xy 298.34713 -399.474944) (xy 298.379087 -399.475544)
			(xy 298.442496 -399.483558) (xy 298.504401 -399.499455) (xy 298.563825 -399.522986) (xy 298.619832 -399.553779)
			(xy 298.671538 -399.591348) (xy 298.718128 -399.635102) (xy 298.758866 -399.684349) (xy 298.793112 -399.738314)
			(xy 298.820324 -399.796145) (xy 298.840074 -399.856931) (xy 298.852049 -399.919712) (xy 298.856063 -399.9835)
			(xy 298.852049 -400.047288) (xy 298.840074 -400.110069) (xy 298.820324 -400.170855) (xy 298.793112 -400.228686)
			(xy 298.758866 -400.282651) (xy 298.718128 -400.331898) (xy 298.671538 -400.375652) (xy 298.619832 -400.413221)
			(xy 298.563825 -400.444014) (xy 298.504401 -400.467545) (xy 298.442496 -400.483442) (xy 298.379087 -400.491456)
			(xy 298.34713 -400.49196) (xy 298.346876 -400.49196) (xy 298.315131 -400.491422) (xy 298.252136 -400.483497)
			(xy 298.190616 -400.467797) (xy 298.131527 -400.444566) (xy 298.075787 -400.414166) (xy 298.024261 -400.377069)
			(xy 298.000674 -400.355816) (xy 297.993411 -400.349632) (xy 297.975661 -400.342681) (xy 297.956599 -400.342681)
			(xy 297.938849 -400.349632) (xy 297.931586 -400.355816) (xy 297.908028 -400.377107) (xy 297.856512 -400.414235)
			(xy 297.800771 -400.444654) (xy 297.741674 -400.467889) (xy 297.680142 -400.483579) (xy 297.617135 -400.491478)
			(xy 297.585384 -400.49196) (xy 297.58513 -400.49196) (xy 297.553163 -400.491577) (xy 297.489734 -400.483567)
			(xy 297.427809 -400.467671) (xy 297.368364 -400.444138) (xy 297.312338 -400.41334) (xy 297.260613 -400.375763)
			(xy 297.214007 -400.331999) (xy 297.173253 -400.282739) (xy 297.138995 -400.228759) (xy 297.111773 -400.170911)
			(xy 297.092015 -400.110108) (xy 297.080035 -400.047307) (xy 297.07602 -399.9835) (xy 296.316063 -399.9835)
			(xy 296.312049 -400.047288) (xy 296.300074 -400.110069) (xy 296.280324 -400.170855) (xy 296.253112 -400.228686)
			(xy 296.218866 -400.282651) (xy 296.178128 -400.331898) (xy 296.131538 -400.375652) (xy 296.079832 -400.413221)
			(xy 296.023825 -400.444014) (xy 295.964401 -400.467545) (xy 295.902496 -400.483442) (xy 295.839087 -400.491456)
			(xy 295.80713 -400.49196) (xy 295.806876 -400.49196) (xy 295.775131 -400.491422) (xy 295.712136 -400.483497)
			(xy 295.650616 -400.467797) (xy 295.591527 -400.444566) (xy 295.535787 -400.414166) (xy 295.484261 -400.377069)
			(xy 295.460674 -400.355816) (xy 295.453411 -400.349632) (xy 295.435661 -400.342681) (xy 295.416599 -400.342681)
			(xy 295.398849 -400.349632) (xy 295.391586 -400.355816) (xy 295.368028 -400.377107) (xy 295.316512 -400.414235)
			(xy 295.260771 -400.444654) (xy 295.201674 -400.467889) (xy 295.140142 -400.483579) (xy 295.077135 -400.491478)
			(xy 295.045384 -400.49196) (xy 295.04513 -400.49196) (xy 295.013163 -400.491577) (xy 294.949734 -400.483567)
			(xy 294.887809 -400.467671) (xy 294.828364 -400.444138) (xy 294.772338 -400.41334) (xy 294.720613 -400.375763)
			(xy 294.674007 -400.331999) (xy 294.633253 -400.282739) (xy 294.598995 -400.228759) (xy 294.571773 -400.170911)
			(xy 294.552015 -400.110108) (xy 294.540035 -400.047307) (xy 294.53602 -399.9835) (xy 293.926484 -399.9835)
			(xy 293.92247 -400.047293) (xy 293.910493 -400.110079) (xy 293.890741 -400.17087) (xy 293.863525 -400.228705)
			(xy 293.829276 -400.282674) (xy 293.788532 -400.331924) (xy 293.741937 -400.375679) (xy 293.690226 -400.41325)
			(xy 293.634213 -400.444043) (xy 293.574783 -400.467573) (xy 293.512872 -400.483468) (xy 293.449457 -400.491479)
			(xy 293.417498 -400.49196) (xy 293.417244 -400.49196) (xy 293.385498 -400.491442) (xy 293.322502 -400.483512)
			(xy 293.260982 -400.467809) (xy 293.201894 -400.444575) (xy 293.146154 -400.414171) (xy 293.094629 -400.37707)
			(xy 293.071042 -400.355816) (xy 293.063779 -400.349632) (xy 293.046029 -400.342681) (xy 293.026967 -400.342681)
			(xy 293.009217 -400.349632) (xy 293.001954 -400.355816) (xy 292.978367 -400.377074) (xy 292.926858 -400.414206)
			(xy 292.871123 -400.44463) (xy 292.812032 -400.467871) (xy 292.750504 -400.483567) (xy 292.687501 -400.491474)
			(xy 292.655752 -400.49196) (xy 292.655498 -400.49196) (xy 292.623534 -400.491554) (xy 292.56011 -400.483542)
			(xy 292.498191 -400.467643) (xy 292.438752 -400.44411) (xy 292.382731 -400.413312) (xy 292.331013 -400.375736)
			(xy 292.284411 -400.331974) (xy 292.243662 -400.282717) (xy 292.209408 -400.22874) (xy 292.182189 -400.170897)
			(xy 292.162434 -400.110098) (xy 292.150455 -400.047302) (xy 292.146441 -399.9835) (xy 291.386484 -399.9835)
			(xy 291.38247 -400.047293) (xy 291.370493 -400.110079) (xy 291.350741 -400.17087) (xy 291.323525 -400.228705)
			(xy 291.289276 -400.282674) (xy 291.248532 -400.331924) (xy 291.201937 -400.375679) (xy 291.150226 -400.41325)
			(xy 291.094213 -400.444043) (xy 291.034783 -400.467573) (xy 290.972872 -400.483468) (xy 290.909457 -400.491479)
			(xy 290.877498 -400.49196) (xy 290.877244 -400.49196) (xy 290.845498 -400.491442) (xy 290.782502 -400.483512)
			(xy 290.720982 -400.467809) (xy 290.661894 -400.444575) (xy 290.606154 -400.414171) (xy 290.554629 -400.37707)
			(xy 290.531042 -400.355816) (xy 290.523779 -400.349632) (xy 290.506029 -400.342681) (xy 290.486967 -400.342681)
			(xy 290.469217 -400.349632) (xy 290.461954 -400.355816) (xy 290.438367 -400.377074) (xy 290.386858 -400.414206)
			(xy 290.331123 -400.44463) (xy 290.272032 -400.467871) (xy 290.210504 -400.483567) (xy 290.147501 -400.491474)
			(xy 290.115752 -400.49196) (xy 290.115498 -400.49196) (xy 290.083534 -400.491554) (xy 290.02011 -400.483542)
			(xy 289.958191 -400.467643) (xy 289.898752 -400.44411) (xy 289.842731 -400.413312) (xy 289.791013 -400.375736)
			(xy 289.744411 -400.331974) (xy 289.703662 -400.282717) (xy 289.669408 -400.22874) (xy 289.642189 -400.170897)
			(xy 289.622434 -400.110098) (xy 289.610455 -400.047302) (xy 289.606441 -399.9835) (xy 281.686508 -399.9835)
			(xy 281.686508 -400.885449) (xy 303.599106 -400.885449) (xy 303.599106 -400.830951) (xy 303.606862 -400.777009)
			(xy 303.622215 -400.724719) (xy 303.644854 -400.675146) (xy 303.674317 -400.6293) (xy 303.710004 -400.588113)
			(xy 303.75119 -400.552424) (xy 303.797036 -400.52296) (xy 303.846608 -400.500319) (xy 303.898897 -400.484964)
			(xy 303.952839 -400.477207) (xy 303.980088 -400.47672) (xy 304.843688 -400.47672) (xy 304.870943 -400.477126)
			(xy 304.9249 -400.484882) (xy 304.977203 -400.500238) (xy 305.026788 -400.522882) (xy 305.072646 -400.552352)
			(xy 305.113843 -400.588048) (xy 305.149541 -400.629244) (xy 305.179012 -400.675101) (xy 305.201657 -400.724686)
			(xy 305.217015 -400.776989) (xy 305.224773 -400.830945) (xy 305.224773 -400.885452) (xy 306.662283 -400.885452)
			(xy 306.662283 -400.830948) (xy 306.67004 -400.776998) (xy 306.685397 -400.724702) (xy 306.70804 -400.675124)
			(xy 306.737508 -400.629273) (xy 306.773202 -400.588082) (xy 306.814395 -400.552391) (xy 306.860248 -400.522926)
			(xy 306.909828 -400.500287) (xy 306.962126 -400.484935) (xy 307.016076 -400.477181) (xy 307.043328 -400.47672)
			(xy 307.906928 -400.47672) (xy 307.93418 -400.477152) (xy 307.988129 -400.484912) (xy 308.040424 -400.500271)
			(xy 308.090001 -400.522915) (xy 308.135851 -400.552384) (xy 308.177041 -400.588079) (xy 308.212732 -400.629271)
			(xy 308.242198 -400.675123) (xy 308.264839 -400.724702) (xy 308.280194 -400.776999) (xy 308.28795 -400.830948)
			(xy 308.28795 -400.885448) (xy 309.725606 -400.885448) (xy 309.725606 -400.830952) (xy 309.733361 -400.777011)
			(xy 309.748714 -400.724723) (xy 309.771351 -400.675152) (xy 309.800812 -400.629306) (xy 309.836497 -400.58812)
			(xy 309.877681 -400.552431) (xy 309.923524 -400.522966) (xy 309.973093 -400.500325) (xy 310.02538 -400.484968)
			(xy 310.07932 -400.477208) (xy 310.106568 -400.47672) (xy 310.970168 -400.47672) (xy 310.997424 -400.477125)
			(xy 311.051383 -400.484879) (xy 311.103688 -400.500233) (xy 311.153276 -400.522875) (xy 311.199137 -400.552345)
			(xy 311.240336 -400.588041) (xy 311.276036 -400.629238) (xy 311.305509 -400.675096) (xy 311.328156 -400.724682)
			(xy 311.343515 -400.776986) (xy 311.351273 -400.830944) (xy 311.351273 -400.885451) (xy 312.788783 -400.885451)
			(xy 312.788783 -400.830949) (xy 312.79654 -400.777001) (xy 312.811895 -400.724706) (xy 312.834537 -400.675129)
			(xy 312.864003 -400.629279) (xy 312.899695 -400.588089) (xy 312.940886 -400.552398) (xy 312.986736 -400.522933)
			(xy 313.036314 -400.500292) (xy 313.088609 -400.484938) (xy 313.142557 -400.477183) (xy 313.169808 -400.47672)
			(xy 314.033408 -400.47672) (xy 314.060661 -400.47715) (xy 314.114612 -400.484908) (xy 314.166909 -400.500265)
			(xy 314.216489 -400.522909) (xy 314.262342 -400.552377) (xy 314.303534 -400.588071) (xy 314.339228 -400.629264)
			(xy 314.368695 -400.675118) (xy 314.391337 -400.724698) (xy 314.406693 -400.776996) (xy 314.41445 -400.830947)
			(xy 314.41445 -400.885453) (xy 315.851983 -400.885453) (xy 315.851983 -400.830947) (xy 315.859741 -400.776996)
			(xy 315.875098 -400.724698) (xy 315.897743 -400.675118) (xy 315.927213 -400.629266) (xy 315.962909 -400.588075)
			(xy 316.004105 -400.552384) (xy 316.04996 -400.52292) (xy 316.099543 -400.500282) (xy 316.151843 -400.484931)
			(xy 316.205795 -400.47718) (xy 316.233048 -400.47672) (xy 317.096648 -400.47672) (xy 317.123899 -400.477153)
			(xy 317.177846 -400.484916) (xy 317.230138 -400.500276) (xy 317.279713 -400.522922) (xy 317.325561 -400.552391)
			(xy 317.366748 -400.588086) (xy 317.402437 -400.629278) (xy 317.431901 -400.675129) (xy 317.454541 -400.724707)
			(xy 317.469894 -400.777001) (xy 317.47765 -400.830949) (xy 317.47765 -400.885449) (xy 318.915306 -400.885449)
			(xy 318.915306 -400.830951) (xy 318.923062 -400.777009) (xy 318.938415 -400.724719) (xy 318.961054 -400.675146)
			(xy 318.990517 -400.6293) (xy 319.026204 -400.588113) (xy 319.06739 -400.552424) (xy 319.113236 -400.52296)
			(xy 319.162808 -400.500319) (xy 319.215097 -400.484964) (xy 319.269039 -400.477207) (xy 319.296288 -400.47672)
			(xy 320.159888 -400.47672) (xy 320.187143 -400.477126) (xy 320.2411 -400.484882) (xy 320.293403 -400.500238)
			(xy 320.342988 -400.522882) (xy 320.388846 -400.552352) (xy 320.430043 -400.588048) (xy 320.465741 -400.629244)
			(xy 320.495212 -400.675101) (xy 320.517857 -400.724686) (xy 320.533215 -400.776989) (xy 320.540973 -400.830945)
			(xy 320.540973 -400.885452) (xy 321.978483 -400.885452) (xy 321.978483 -400.830948) (xy 321.98624 -400.776998)
			(xy 322.001597 -400.724702) (xy 322.02424 -400.675124) (xy 322.053708 -400.629273) (xy 322.089402 -400.588082)
			(xy 322.130595 -400.552391) (xy 322.176448 -400.522926) (xy 322.226028 -400.500287) (xy 322.278326 -400.484935)
			(xy 322.332276 -400.477181) (xy 322.359528 -400.47672) (xy 323.223128 -400.47672) (xy 323.25038 -400.477152)
			(xy 323.304329 -400.484912) (xy 323.356624 -400.500271) (xy 323.406201 -400.522915) (xy 323.452051 -400.552384)
			(xy 323.493241 -400.588079) (xy 323.528932 -400.629271) (xy 323.558398 -400.675123) (xy 323.581039 -400.724702)
			(xy 323.596394 -400.776999) (xy 323.60415 -400.830948) (xy 323.60415 -400.885448) (xy 325.041806 -400.885448)
			(xy 325.041806 -400.830952) (xy 325.049561 -400.777011) (xy 325.064914 -400.724723) (xy 325.087551 -400.675152)
			(xy 325.117012 -400.629306) (xy 325.152697 -400.58812) (xy 325.193881 -400.552431) (xy 325.239724 -400.522966)
			(xy 325.289293 -400.500325) (xy 325.34158 -400.484968) (xy 325.39552 -400.477208) (xy 325.422768 -400.47672)
			(xy 326.286368 -400.47672) (xy 326.313624 -400.477125) (xy 326.367583 -400.484879) (xy 326.419888 -400.500233)
			(xy 326.469476 -400.522875) (xy 326.515337 -400.552345) (xy 326.556536 -400.588041) (xy 326.592236 -400.629238)
			(xy 326.621709 -400.675096) (xy 326.644356 -400.724682) (xy 326.659715 -400.776986) (xy 326.667473 -400.830944)
			(xy 326.667473 -400.885451) (xy 328.104983 -400.885451) (xy 328.104983 -400.830949) (xy 328.11274 -400.777001)
			(xy 328.128095 -400.724706) (xy 328.150737 -400.675129) (xy 328.180203 -400.629279) (xy 328.215895 -400.588089)
			(xy 328.257086 -400.552398) (xy 328.302936 -400.522933) (xy 328.352514 -400.500292) (xy 328.404809 -400.484938)
			(xy 328.458757 -400.477183) (xy 328.486008 -400.47672) (xy 329.349608 -400.47672) (xy 329.376861 -400.47715)
			(xy 329.430812 -400.484908) (xy 329.483109 -400.500265) (xy 329.532689 -400.522909) (xy 329.578542 -400.552377)
			(xy 329.619734 -400.588071) (xy 329.655428 -400.629264) (xy 329.684895 -400.675118) (xy 329.707537 -400.724698)
			(xy 329.722893 -400.776996) (xy 329.73065 -400.830947) (xy 329.73065 -400.885453) (xy 331.168183 -400.885453)
			(xy 331.168183 -400.830947) (xy 331.175941 -400.776996) (xy 331.191298 -400.724698) (xy 331.213943 -400.675118)
			(xy 331.243413 -400.629266) (xy 331.279109 -400.588075) (xy 331.320305 -400.552384) (xy 331.36616 -400.52292)
			(xy 331.415743 -400.500282) (xy 331.468043 -400.484931) (xy 331.521995 -400.47718) (xy 331.549248 -400.47672)
			(xy 332.412848 -400.47672) (xy 332.440099 -400.477153) (xy 332.494046 -400.484916) (xy 332.546338 -400.500276)
			(xy 332.595913 -400.522922) (xy 332.641761 -400.552391) (xy 332.682948 -400.588086) (xy 332.718637 -400.629278)
			(xy 332.748101 -400.675129) (xy 332.770741 -400.724707) (xy 332.786094 -400.777001) (xy 332.79385 -400.830949)
			(xy 332.79385 -400.885449) (xy 334.231506 -400.885449) (xy 334.231506 -400.830951) (xy 334.239262 -400.777009)
			(xy 334.254615 -400.724719) (xy 334.277254 -400.675146) (xy 334.306717 -400.6293) (xy 334.342404 -400.588113)
			(xy 334.38359 -400.552424) (xy 334.429436 -400.52296) (xy 334.479008 -400.500319) (xy 334.531297 -400.484964)
			(xy 334.585239 -400.477207) (xy 334.612488 -400.47672) (xy 335.476088 -400.47672) (xy 335.503343 -400.477126)
			(xy 335.5573 -400.484882) (xy 335.609603 -400.500238) (xy 335.659188 -400.522882) (xy 335.705046 -400.552352)
			(xy 335.746243 -400.588048) (xy 335.781941 -400.629244) (xy 335.811412 -400.675101) (xy 335.834057 -400.724686)
			(xy 335.849415 -400.776989) (xy 335.857173 -400.830945) (xy 335.857173 -400.885452) (xy 337.294683 -400.885452)
			(xy 337.294683 -400.830948) (xy 337.30244 -400.776998) (xy 337.317797 -400.724702) (xy 337.34044 -400.675124)
			(xy 337.369908 -400.629273) (xy 337.405602 -400.588082) (xy 337.446795 -400.552391) (xy 337.492648 -400.522926)
			(xy 337.542228 -400.500287) (xy 337.594526 -400.484935) (xy 337.648476 -400.477181) (xy 337.675728 -400.47672)
			(xy 338.539328 -400.47672) (xy 338.56658 -400.477152) (xy 338.620529 -400.484912) (xy 338.672824 -400.500271)
			(xy 338.722401 -400.522915) (xy 338.768251 -400.552384) (xy 338.809441 -400.588079) (xy 338.845132 -400.629271)
			(xy 338.874598 -400.675123) (xy 338.897239 -400.724702) (xy 338.912594 -400.776999) (xy 338.92035 -400.830948)
			(xy 338.92035 -400.885448) (xy 340.358006 -400.885448) (xy 340.358006 -400.830952) (xy 340.365761 -400.777011)
			(xy 340.381114 -400.724723) (xy 340.403751 -400.675152) (xy 340.433212 -400.629306) (xy 340.468897 -400.58812)
			(xy 340.510081 -400.552431) (xy 340.555924 -400.522966) (xy 340.605493 -400.500325) (xy 340.65778 -400.484968)
			(xy 340.71172 -400.477208) (xy 340.738968 -400.47672) (xy 341.602568 -400.47672) (xy 341.629824 -400.477125)
			(xy 341.683783 -400.484879) (xy 341.736088 -400.500233) (xy 341.785676 -400.522875) (xy 341.831537 -400.552345)
			(xy 341.872736 -400.588041) (xy 341.908436 -400.629238) (xy 341.937909 -400.675096) (xy 341.960556 -400.724682)
			(xy 341.975915 -400.776986) (xy 341.983673 -400.830944) (xy 341.983673 -400.885451) (xy 343.421183 -400.885451)
			(xy 343.421183 -400.830949) (xy 343.42894 -400.777001) (xy 343.444295 -400.724706) (xy 343.466937 -400.675129)
			(xy 343.496403 -400.629279) (xy 343.532095 -400.588089) (xy 343.573286 -400.552398) (xy 343.619136 -400.522933)
			(xy 343.668714 -400.500292) (xy 343.721009 -400.484938) (xy 343.774957 -400.477183) (xy 343.802208 -400.47672)
			(xy 344.665808 -400.47672) (xy 344.693061 -400.47715) (xy 344.747012 -400.484908) (xy 344.799309 -400.500265)
			(xy 344.848889 -400.522909) (xy 344.894742 -400.552377) (xy 344.935934 -400.588071) (xy 344.971628 -400.629264)
			(xy 345.001095 -400.675118) (xy 345.023737 -400.724698) (xy 345.039093 -400.776996) (xy 345.04685 -400.830947)
			(xy 345.04685 -400.885453) (xy 346.484383 -400.885453) (xy 346.484383 -400.830947) (xy 346.492141 -400.776996)
			(xy 346.507498 -400.724698) (xy 346.530143 -400.675118) (xy 346.559613 -400.629266) (xy 346.595309 -400.588075)
			(xy 346.636505 -400.552384) (xy 346.68236 -400.52292) (xy 346.731943 -400.500282) (xy 346.784243 -400.484931)
			(xy 346.838195 -400.47718) (xy 346.865448 -400.47672) (xy 347.729048 -400.47672) (xy 347.756299 -400.477153)
			(xy 347.810246 -400.484916) (xy 347.862538 -400.500276) (xy 347.912113 -400.522922) (xy 347.957961 -400.552391)
			(xy 347.999148 -400.588086) (xy 348.034837 -400.629278) (xy 348.064301 -400.675129) (xy 348.086941 -400.724707)
			(xy 348.102294 -400.777001) (xy 348.11005 -400.830949) (xy 348.11005 -400.885449) (xy 349.547706 -400.885449)
			(xy 349.547706 -400.830951) (xy 349.555462 -400.777009) (xy 349.570815 -400.724719) (xy 349.593454 -400.675146)
			(xy 349.622917 -400.6293) (xy 349.658604 -400.588113) (xy 349.69979 -400.552424) (xy 349.745636 -400.52296)
			(xy 349.795208 -400.500319) (xy 349.847497 -400.484964) (xy 349.901439 -400.477207) (xy 349.928688 -400.47672)
			(xy 350.792288 -400.47672) (xy 350.819543 -400.477126) (xy 350.8735 -400.484882) (xy 350.925803 -400.500238)
			(xy 350.975388 -400.522882) (xy 351.021246 -400.552352) (xy 351.062443 -400.588048) (xy 351.098141 -400.629244)
			(xy 351.127612 -400.675101) (xy 351.150257 -400.724686) (xy 351.165615 -400.776989) (xy 351.173373 -400.830945)
			(xy 351.173373 -400.885452) (xy 371.041883 -400.885452) (xy 371.041883 -400.830948) (xy 371.049641 -400.776998)
			(xy 371.064997 -400.724702) (xy 371.08764 -400.675123) (xy 371.117109 -400.629272) (xy 371.152803 -400.588082)
			(xy 371.193996 -400.552391) (xy 371.23985 -400.522926) (xy 371.28943 -400.500286) (xy 371.341728 -400.484934)
			(xy 371.395678 -400.477181) (xy 371.42293 -400.47672) (xy 372.28653 -400.47672) (xy 372.313782 -400.477152)
			(xy 372.36773 -400.484912) (xy 372.420025 -400.500271) (xy 372.469602 -400.522916) (xy 372.515452 -400.552385)
			(xy 372.556642 -400.588079) (xy 372.592333 -400.629272) (xy 372.621799 -400.675124) (xy 372.644439 -400.724703)
			(xy 372.659794 -400.776999) (xy 372.66755 -400.830948) (xy 372.66755 -400.885448) (xy 374.105206 -400.885448)
			(xy 374.105206 -400.830952) (xy 374.112961 -400.777011) (xy 374.128314 -400.724723) (xy 374.150951 -400.675151)
			(xy 374.180412 -400.629306) (xy 374.216098 -400.588119) (xy 374.257281 -400.55243) (xy 374.303125 -400.522965)
			(xy 374.352694 -400.500324) (xy 374.404982 -400.484968) (xy 374.458922 -400.477208) (xy 374.48617 -400.47672)
			(xy 375.34977 -400.47672) (xy 375.377026 -400.477125) (xy 375.430984 -400.484879) (xy 375.48329 -400.500234)
			(xy 375.532877 -400.522876) (xy 375.578738 -400.552345) (xy 375.619937 -400.588042) (xy 375.655637 -400.629238)
			(xy 375.68511 -400.675096) (xy 375.707756 -400.724682) (xy 375.723115 -400.776986) (xy 375.730873 -400.830944)
			(xy 375.730873 -400.885451) (xy 377.168383 -400.885451) (xy 377.168383 -400.830949) (xy 377.17614 -400.777001)
			(xy 377.191495 -400.724706) (xy 377.214137 -400.675129) (xy 377.243604 -400.629279) (xy 377.279296 -400.588089)
			(xy 377.320487 -400.552398) (xy 377.366338 -400.522932) (xy 377.415915 -400.500292) (xy 377.468211 -400.484938)
			(xy 377.522159 -400.477183) (xy 377.54941 -400.47672) (xy 378.41301 -400.47672) (xy 378.440263 -400.477151)
			(xy 378.494213 -400.484909) (xy 378.546511 -400.500266) (xy 378.59609 -400.522909) (xy 378.641943 -400.552378)
			(xy 378.683135 -400.588072) (xy 378.718828 -400.629265) (xy 378.748296 -400.675118) (xy 378.770938 -400.724699)
			(xy 378.786293 -400.776996) (xy 378.79405 -400.830947) (xy 378.79405 -400.885447) (xy 380.231706 -400.885447)
			(xy 380.231706 -400.830953) (xy 380.239461 -400.777014) (xy 380.254812 -400.724727) (xy 380.277448 -400.675157)
			(xy 380.306907 -400.629312) (xy 380.342591 -400.588126) (xy 380.383772 -400.552437) (xy 380.429613 -400.522972)
			(xy 380.47918 -400.50033) (xy 380.531465 -400.484971) (xy 380.585403 -400.47721) (xy 380.61265 -400.47672)
			(xy 381.47625 -400.47672) (xy 381.503507 -400.477124) (xy 381.557468 -400.484875) (xy 381.609775 -400.500228)
			(xy 381.659365 -400.522869) (xy 381.705228 -400.552338) (xy 381.74643 -400.588035) (xy 381.782132 -400.629232)
			(xy 381.811607 -400.675091) (xy 381.834254 -400.724678) (xy 381.849614 -400.776983) (xy 381.857373 -400.830943)
			(xy 381.857373 -400.885449) (xy 383.294906 -400.885449) (xy 383.294906 -400.830951) (xy 383.302662 -400.777008)
			(xy 383.318015 -400.724718) (xy 383.340654 -400.675145) (xy 383.370117 -400.629299) (xy 383.405805 -400.588112)
			(xy 383.446991 -400.552423) (xy 383.492837 -400.522959) (xy 383.542409 -400.500319) (xy 383.594699 -400.484964)
			(xy 383.648641 -400.477207) (xy 383.67589 -400.47672) (xy 384.53949 -400.47672) (xy 384.566745 -400.477126)
			(xy 384.620701 -400.484883) (xy 384.673004 -400.500239) (xy 384.722589 -400.522883) (xy 384.768447 -400.552352)
			(xy 384.809644 -400.588049) (xy 384.845342 -400.629245) (xy 384.874813 -400.675102) (xy 384.897458 -400.724686)
			(xy 384.912815 -400.776989) (xy 384.920573 -400.830945) (xy 384.920573 -400.885452) (xy 386.358083 -400.885452)
			(xy 386.358083 -400.830948) (xy 386.365841 -400.776998) (xy 386.381197 -400.724702) (xy 386.40384 -400.675123)
			(xy 386.433309 -400.629272) (xy 386.469003 -400.588082) (xy 386.510196 -400.552391) (xy 386.55605 -400.522926)
			(xy 386.60563 -400.500286) (xy 386.657928 -400.484934) (xy 386.711878 -400.477181) (xy 386.73913 -400.47672)
			(xy 387.60273 -400.47672) (xy 387.629982 -400.477152) (xy 387.68393 -400.484912) (xy 387.736225 -400.500271)
			(xy 387.785802 -400.522916) (xy 387.831652 -400.552385) (xy 387.872842 -400.588079) (xy 387.908533 -400.629272)
			(xy 387.937999 -400.675124) (xy 387.960639 -400.724703) (xy 387.975994 -400.776999) (xy 387.98375 -400.830948)
			(xy 387.98375 -400.885448) (xy 389.421406 -400.885448) (xy 389.421406 -400.830952) (xy 389.429161 -400.777011)
			(xy 389.444514 -400.724723) (xy 389.467151 -400.675151) (xy 389.496612 -400.629306) (xy 389.532298 -400.588119)
			(xy 389.573481 -400.55243) (xy 389.619325 -400.522965) (xy 389.668894 -400.500324) (xy 389.721182 -400.484968)
			(xy 389.775122 -400.477208) (xy 389.80237 -400.47672) (xy 390.66597 -400.47672) (xy 390.693226 -400.477125)
			(xy 390.747184 -400.484879) (xy 390.79949 -400.500234) (xy 390.849077 -400.522876) (xy 390.894938 -400.552345)
			(xy 390.936137 -400.588042) (xy 390.971837 -400.629238) (xy 391.00131 -400.675096) (xy 391.023956 -400.724682)
			(xy 391.039315 -400.776986) (xy 391.047073 -400.830944) (xy 391.047073 -400.885451) (xy 392.484583 -400.885451)
			(xy 392.484583 -400.830949) (xy 392.49234 -400.777001) (xy 392.507695 -400.724706) (xy 392.530337 -400.675129)
			(xy 392.559804 -400.629279) (xy 392.595496 -400.588089) (xy 392.636687 -400.552398) (xy 392.682538 -400.522932)
			(xy 392.732115 -400.500292) (xy 392.784411 -400.484938) (xy 392.838359 -400.477183) (xy 392.86561 -400.47672)
			(xy 393.72921 -400.47672) (xy 393.756463 -400.477151) (xy 393.810413 -400.484909) (xy 393.862711 -400.500266)
			(xy 393.91229 -400.522909) (xy 393.958143 -400.552378) (xy 393.999335 -400.588072) (xy 394.035028 -400.629265)
			(xy 394.064496 -400.675118) (xy 394.087138 -400.724699) (xy 394.102493 -400.776996) (xy 394.11025 -400.830947)
			(xy 394.11025 -400.885447) (xy 395.547906 -400.885447) (xy 395.547906 -400.830953) (xy 395.555661 -400.777014)
			(xy 395.571012 -400.724727) (xy 395.593648 -400.675157) (xy 395.623107 -400.629312) (xy 395.658791 -400.588126)
			(xy 395.699972 -400.552437) (xy 395.745813 -400.522972) (xy 395.79538 -400.50033) (xy 395.847665 -400.484971)
			(xy 395.901603 -400.47721) (xy 395.92885 -400.47672) (xy 396.79245 -400.47672) (xy 396.819707 -400.477124)
			(xy 396.873668 -400.484875) (xy 396.925975 -400.500228) (xy 396.975565 -400.522869) (xy 397.021428 -400.552338)
			(xy 397.06263 -400.588035) (xy 397.098332 -400.629232) (xy 397.127807 -400.675091) (xy 397.150454 -400.724678)
			(xy 397.165814 -400.776983) (xy 397.173573 -400.830943) (xy 397.173573 -400.885449) (xy 398.611106 -400.885449)
			(xy 398.611106 -400.830951) (xy 398.618862 -400.777008) (xy 398.634215 -400.724718) (xy 398.656854 -400.675145)
			(xy 398.686317 -400.629299) (xy 398.722005 -400.588112) (xy 398.763191 -400.552423) (xy 398.809037 -400.522959)
			(xy 398.858609 -400.500319) (xy 398.910899 -400.484964) (xy 398.964841 -400.477207) (xy 398.99209 -400.47672)
			(xy 399.85569 -400.47672) (xy 399.882945 -400.477126) (xy 399.936901 -400.484883) (xy 399.989204 -400.500239)
			(xy 400.038789 -400.522883) (xy 400.084647 -400.552352) (xy 400.125844 -400.588049) (xy 400.161542 -400.629245)
			(xy 400.191013 -400.675102) (xy 400.213658 -400.724686) (xy 400.229015 -400.776989) (xy 400.236773 -400.830945)
			(xy 400.236773 -400.885452) (xy 401.674283 -400.885452) (xy 401.674283 -400.830948) (xy 401.682041 -400.776998)
			(xy 401.697397 -400.724702) (xy 401.72004 -400.675123) (xy 401.749509 -400.629272) (xy 401.785203 -400.588082)
			(xy 401.826396 -400.552391) (xy 401.87225 -400.522926) (xy 401.92183 -400.500286) (xy 401.974128 -400.484934)
			(xy 402.028078 -400.477181) (xy 402.05533 -400.47672) (xy 402.91893 -400.47672) (xy 402.946182 -400.477152)
			(xy 403.00013 -400.484912) (xy 403.052425 -400.500271) (xy 403.102002 -400.522916) (xy 403.147852 -400.552385)
			(xy 403.189042 -400.588079) (xy 403.224733 -400.629272) (xy 403.254199 -400.675124) (xy 403.276839 -400.724703)
			(xy 403.292194 -400.776999) (xy 403.29995 -400.830948) (xy 403.29995 -400.885448) (xy 404.737606 -400.885448)
			(xy 404.737606 -400.830952) (xy 404.745361 -400.777011) (xy 404.760714 -400.724723) (xy 404.783351 -400.675151)
			(xy 404.812812 -400.629306) (xy 404.848498 -400.588119) (xy 404.889681 -400.55243) (xy 404.935525 -400.522965)
			(xy 404.985094 -400.500324) (xy 405.037382 -400.484968) (xy 405.091322 -400.477208) (xy 405.11857 -400.47672)
			(xy 405.98217 -400.47672) (xy 406.009426 -400.477125) (xy 406.063384 -400.484879) (xy 406.11569 -400.500234)
			(xy 406.165277 -400.522876) (xy 406.211138 -400.552345) (xy 406.252337 -400.588042) (xy 406.288037 -400.629238)
			(xy 406.31751 -400.675096) (xy 406.340156 -400.724682) (xy 406.355515 -400.776986) (xy 406.363273 -400.830944)
			(xy 406.363273 -400.885451) (xy 407.800783 -400.885451) (xy 407.800783 -400.830949) (xy 407.80854 -400.777001)
			(xy 407.823895 -400.724706) (xy 407.846537 -400.675129) (xy 407.876004 -400.629279) (xy 407.911696 -400.588089)
			(xy 407.952887 -400.552398) (xy 407.998738 -400.522932) (xy 408.048315 -400.500292) (xy 408.100611 -400.484938)
			(xy 408.154559 -400.477183) (xy 408.18181 -400.47672) (xy 409.04541 -400.47672) (xy 409.072663 -400.477151)
			(xy 409.126613 -400.484909) (xy 409.178911 -400.500266) (xy 409.22849 -400.522909) (xy 409.274343 -400.552378)
			(xy 409.315535 -400.588072) (xy 409.351228 -400.629265) (xy 409.380696 -400.675118) (xy 409.403338 -400.724699)
			(xy 409.418693 -400.776996) (xy 409.42645 -400.830947) (xy 409.42645 -400.885447) (xy 410.864106 -400.885447)
			(xy 410.864106 -400.830953) (xy 410.871861 -400.777014) (xy 410.887212 -400.724727) (xy 410.909848 -400.675157)
			(xy 410.939307 -400.629312) (xy 410.974991 -400.588126) (xy 411.016172 -400.552437) (xy 411.062013 -400.522972)
			(xy 411.11158 -400.50033) (xy 411.163865 -400.484971) (xy 411.217803 -400.47721) (xy 411.24505 -400.47672)
			(xy 412.10865 -400.47672) (xy 412.135907 -400.477124) (xy 412.189868 -400.484875) (xy 412.242175 -400.500228)
			(xy 412.291765 -400.522869) (xy 412.337628 -400.552338) (xy 412.37883 -400.588035) (xy 412.414532 -400.629232)
			(xy 412.444007 -400.675091) (xy 412.466654 -400.724678) (xy 412.482014 -400.776983) (xy 412.489773 -400.830943)
			(xy 412.489773 -400.885449) (xy 413.927306 -400.885449) (xy 413.927306 -400.830951) (xy 413.935062 -400.777008)
			(xy 413.950415 -400.724718) (xy 413.973054 -400.675145) (xy 414.002517 -400.629299) (xy 414.038205 -400.588112)
			(xy 414.079391 -400.552423) (xy 414.125237 -400.522959) (xy 414.174809 -400.500319) (xy 414.227099 -400.484964)
			(xy 414.281041 -400.477207) (xy 414.30829 -400.47672) (xy 415.17189 -400.47672) (xy 415.199145 -400.477126)
			(xy 415.253101 -400.484883) (xy 415.305404 -400.500239) (xy 415.354989 -400.522883) (xy 415.400847 -400.552352)
			(xy 415.442044 -400.588049) (xy 415.477742 -400.629245) (xy 415.507213 -400.675102) (xy 415.529858 -400.724686)
			(xy 415.545215 -400.776989) (xy 415.552973 -400.830945) (xy 415.552973 -400.885452) (xy 416.990483 -400.885452)
			(xy 416.990483 -400.830948) (xy 416.998241 -400.776998) (xy 417.013597 -400.724702) (xy 417.03624 -400.675123)
			(xy 417.065709 -400.629272) (xy 417.101403 -400.588082) (xy 417.142596 -400.552391) (xy 417.18845 -400.522926)
			(xy 417.23803 -400.500286) (xy 417.290328 -400.484934) (xy 417.344278 -400.477181) (xy 417.37153 -400.47672)
			(xy 418.23513 -400.47672) (xy 418.262382 -400.477152) (xy 418.31633 -400.484912) (xy 418.368625 -400.500271)
			(xy 418.418202 -400.522916) (xy 418.464052 -400.552385) (xy 418.505242 -400.588079) (xy 418.540933 -400.629272)
			(xy 418.570399 -400.675124) (xy 418.593039 -400.724703) (xy 418.608394 -400.776999) (xy 418.61615 -400.830948)
			(xy 418.61615 -400.885452) (xy 418.608394 -400.939401) (xy 418.593039 -400.991697) (xy 418.570399 -401.041276)
			(xy 418.540933 -401.087128) (xy 418.505242 -401.128321) (xy 418.464052 -401.164015) (xy 418.418202 -401.193484)
			(xy 418.368625 -401.216129) (xy 418.31633 -401.231488) (xy 418.262382 -401.239248) (xy 418.23513 -401.239736)
			(xy 417.37153 -401.239736) (xy 417.344278 -401.239219) (xy 417.290328 -401.231466) (xy 417.23803 -401.216114)
			(xy 417.18845 -401.193474) (xy 417.142596 -401.164009) (xy 417.101403 -401.128318) (xy 417.065709 -401.087128)
			(xy 417.03624 -401.041277) (xy 417.013597 -400.991698) (xy 416.998241 -400.939402) (xy 416.990483 -400.885452)
			(xy 415.552973 -400.885452) (xy 415.552973 -400.885455) (xy 415.545215 -400.939411) (xy 415.529858 -400.991714)
			(xy 415.507213 -401.041298) (xy 415.477742 -401.087155) (xy 415.442044 -401.128351) (xy 415.400847 -401.164048)
			(xy 415.354989 -401.193517) (xy 415.305404 -401.216161) (xy 415.253101 -401.231517) (xy 415.199145 -401.239274)
			(xy 415.17189 -401.239736) (xy 414.30829 -401.239736) (xy 414.281041 -401.239193) (xy 414.227099 -401.231436)
			(xy 414.174809 -401.216081) (xy 414.125237 -401.193441) (xy 414.079391 -401.163977) (xy 414.038205 -401.128288)
			(xy 414.002517 -401.087101) (xy 413.973054 -401.041255) (xy 413.950415 -400.991682) (xy 413.935062 -400.939392)
			(xy 413.927306 -400.885449) (xy 412.489773 -400.885449) (xy 412.489773 -400.885457) (xy 412.482014 -400.939416)
			(xy 412.466654 -400.991722) (xy 412.444007 -401.041309) (xy 412.414532 -401.087168) (xy 412.37883 -401.128365)
			(xy 412.337628 -401.164062) (xy 412.291765 -401.193531) (xy 412.242175 -401.216172) (xy 412.189868 -401.231525)
			(xy 412.135907 -401.239276) (xy 412.10865 -401.239736) (xy 411.24505 -401.239736) (xy 411.217803 -401.23919)
			(xy 411.163865 -401.231429) (xy 411.11158 -401.21607) (xy 411.062013 -401.193428) (xy 411.016172 -401.163963)
			(xy 410.974991 -401.128274) (xy 410.939307 -401.087088) (xy 410.909848 -401.041243) (xy 410.887212 -400.991673)
			(xy 410.871861 -400.939386) (xy 410.864106 -400.885447) (xy 409.42645 -400.885447) (xy 409.42645 -400.885453)
			(xy 409.418693 -400.939404) (xy 409.403338 -400.991701) (xy 409.380696 -401.041282) (xy 409.351228 -401.087135)
			(xy 409.315535 -401.128328) (xy 409.274343 -401.164022) (xy 409.22849 -401.193491) (xy 409.178911 -401.216134)
			(xy 409.126613 -401.231491) (xy 409.072663 -401.239249) (xy 409.04541 -401.239736) (xy 408.18181 -401.239736)
			(xy 408.154559 -401.239217) (xy 408.100611 -401.231462) (xy 408.048315 -401.216108) (xy 407.998738 -401.193468)
			(xy 407.952887 -401.164002) (xy 407.911696 -401.128311) (xy 407.876004 -401.087121) (xy 407.846537 -401.041271)
			(xy 407.823895 -400.991694) (xy 407.80854 -400.939399) (xy 407.800783 -400.885451) (xy 406.363273 -400.885451)
			(xy 406.363273 -400.885456) (xy 406.355515 -400.939414) (xy 406.340156 -400.991718) (xy 406.31751 -401.041304)
			(xy 406.288037 -401.087162) (xy 406.252337 -401.128358) (xy 406.211138 -401.164055) (xy 406.165277 -401.193524)
			(xy 406.11569 -401.216166) (xy 406.063384 -401.231521) (xy 406.009426 -401.239275) (xy 405.98217 -401.239736)
			(xy 405.11857 -401.239736) (xy 405.091322 -401.239192) (xy 405.037382 -401.231432) (xy 404.985094 -401.216076)
			(xy 404.935525 -401.193435) (xy 404.889682 -401.16397) (xy 404.848498 -401.128281) (xy 404.812812 -401.087094)
			(xy 404.783351 -401.041249) (xy 404.760714 -400.991677) (xy 404.745361 -400.939389) (xy 404.737606 -400.885448)
			(xy 403.29995 -400.885448) (xy 403.29995 -400.885452) (xy 403.292194 -400.939401) (xy 403.276839 -400.991697)
			(xy 403.254199 -401.041276) (xy 403.224733 -401.087128) (xy 403.189042 -401.128321) (xy 403.147852 -401.164015)
			(xy 403.102002 -401.193484) (xy 403.052425 -401.216129) (xy 403.00013 -401.231488) (xy 402.946182 -401.239248)
			(xy 402.91893 -401.239736) (xy 402.05533 -401.239736) (xy 402.028078 -401.239219) (xy 401.974128 -401.231466)
			(xy 401.92183 -401.216114) (xy 401.87225 -401.193474) (xy 401.826396 -401.164009) (xy 401.785203 -401.128318)
			(xy 401.749509 -401.087128) (xy 401.72004 -401.041277) (xy 401.697397 -400.991698) (xy 401.682041 -400.939402)
			(xy 401.674283 -400.885452) (xy 400.236773 -400.885452) (xy 400.236773 -400.885455) (xy 400.229015 -400.939411)
			(xy 400.213658 -400.991714) (xy 400.191013 -401.041298) (xy 400.161542 -401.087155) (xy 400.125844 -401.128351)
			(xy 400.084647 -401.164048) (xy 400.038789 -401.193517) (xy 399.989204 -401.216161) (xy 399.936901 -401.231517)
			(xy 399.882945 -401.239274) (xy 399.85569 -401.239736) (xy 398.99209 -401.239736) (xy 398.964841 -401.239193)
			(xy 398.910899 -401.231436) (xy 398.858609 -401.216081) (xy 398.809037 -401.193441) (xy 398.763191 -401.163977)
			(xy 398.722005 -401.128288) (xy 398.686317 -401.087101) (xy 398.656854 -401.041255) (xy 398.634215 -400.991682)
			(xy 398.618862 -400.939392) (xy 398.611106 -400.885449) (xy 397.173573 -400.885449) (xy 397.173573 -400.885457)
			(xy 397.165814 -400.939416) (xy 397.150454 -400.991722) (xy 397.127807 -401.041309) (xy 397.098332 -401.087168)
			(xy 397.06263 -401.128365) (xy 397.021428 -401.164062) (xy 396.975565 -401.193531) (xy 396.925975 -401.216172)
			(xy 396.873668 -401.231525) (xy 396.819707 -401.239276) (xy 396.79245 -401.239736) (xy 395.92885 -401.239736)
			(xy 395.901603 -401.23919) (xy 395.847665 -401.231429) (xy 395.79538 -401.21607) (xy 395.745813 -401.193428)
			(xy 395.699972 -401.163963) (xy 395.658791 -401.128274) (xy 395.623107 -401.087088) (xy 395.593648 -401.041243)
			(xy 395.571012 -400.991673) (xy 395.555661 -400.939386) (xy 395.547906 -400.885447) (xy 394.11025 -400.885447)
			(xy 394.11025 -400.885453) (xy 394.102493 -400.939404) (xy 394.087138 -400.991701) (xy 394.064496 -401.041282)
			(xy 394.035028 -401.087135) (xy 393.999335 -401.128328) (xy 393.958143 -401.164022) (xy 393.91229 -401.193491)
			(xy 393.862711 -401.216134) (xy 393.810413 -401.231491) (xy 393.756463 -401.239249) (xy 393.72921 -401.239736)
			(xy 392.86561 -401.239736) (xy 392.838359 -401.239217) (xy 392.784411 -401.231462) (xy 392.732115 -401.216108)
			(xy 392.682538 -401.193468) (xy 392.636687 -401.164002) (xy 392.595496 -401.128311) (xy 392.559804 -401.087121)
			(xy 392.530337 -401.041271) (xy 392.507695 -400.991694) (xy 392.49234 -400.939399) (xy 392.484583 -400.885451)
			(xy 391.047073 -400.885451) (xy 391.047073 -400.885456) (xy 391.039315 -400.939414) (xy 391.023956 -400.991718)
			(xy 391.00131 -401.041304) (xy 390.971837 -401.087162) (xy 390.936137 -401.128358) (xy 390.894938 -401.164055)
			(xy 390.849077 -401.193524) (xy 390.79949 -401.216166) (xy 390.747184 -401.231521) (xy 390.693226 -401.239275)
			(xy 390.66597 -401.239736) (xy 389.80237 -401.239736) (xy 389.775122 -401.239192) (xy 389.721182 -401.231432)
			(xy 389.668894 -401.216076) (xy 389.619325 -401.193435) (xy 389.573482 -401.16397) (xy 389.532298 -401.128281)
			(xy 389.496612 -401.087094) (xy 389.467151 -401.041249) (xy 389.444514 -400.991677) (xy 389.429161 -400.939389)
			(xy 389.421406 -400.885448) (xy 387.98375 -400.885448) (xy 387.98375 -400.885452) (xy 387.975994 -400.939401)
			(xy 387.960639 -400.991697) (xy 387.937999 -401.041276) (xy 387.908533 -401.087128) (xy 387.872842 -401.128321)
			(xy 387.831652 -401.164015) (xy 387.785802 -401.193484) (xy 387.736225 -401.216129) (xy 387.68393 -401.231488)
			(xy 387.629982 -401.239248) (xy 387.60273 -401.239736) (xy 386.73913 -401.239736) (xy 386.711878 -401.239219)
			(xy 386.657928 -401.231466) (xy 386.60563 -401.216114) (xy 386.55605 -401.193474) (xy 386.510196 -401.164009)
			(xy 386.469003 -401.128318) (xy 386.433309 -401.087128) (xy 386.40384 -401.041277) (xy 386.381197 -400.991698)
			(xy 386.365841 -400.939402) (xy 386.358083 -400.885452) (xy 384.920573 -400.885452) (xy 384.920573 -400.885455)
			(xy 384.912815 -400.939411) (xy 384.897458 -400.991714) (xy 384.874813 -401.041298) (xy 384.845342 -401.087155)
			(xy 384.809644 -401.128351) (xy 384.768447 -401.164048) (xy 384.722589 -401.193517) (xy 384.673004 -401.216161)
			(xy 384.620701 -401.231517) (xy 384.566745 -401.239274) (xy 384.53949 -401.239736) (xy 383.67589 -401.239736)
			(xy 383.648641 -401.239193) (xy 383.594699 -401.231436) (xy 383.542409 -401.216081) (xy 383.492837 -401.193441)
			(xy 383.446991 -401.163977) (xy 383.405805 -401.128288) (xy 383.370117 -401.087101) (xy 383.340654 -401.041255)
			(xy 383.318015 -400.991682) (xy 383.302662 -400.939392) (xy 383.294906 -400.885449) (xy 381.857373 -400.885449)
			(xy 381.857373 -400.885457) (xy 381.849614 -400.939416) (xy 381.834254 -400.991722) (xy 381.811607 -401.041309)
			(xy 381.782132 -401.087168) (xy 381.74643 -401.128365) (xy 381.705228 -401.164062) (xy 381.659365 -401.193531)
			(xy 381.609775 -401.216172) (xy 381.557468 -401.231525) (xy 381.503507 -401.239276) (xy 381.47625 -401.239736)
			(xy 380.61265 -401.239736) (xy 380.585403 -401.23919) (xy 380.531465 -401.231429) (xy 380.47918 -401.21607)
			(xy 380.429613 -401.193428) (xy 380.383772 -401.163963) (xy 380.342591 -401.128274) (xy 380.306907 -401.087088)
			(xy 380.277448 -401.041243) (xy 380.254812 -400.991673) (xy 380.239461 -400.939386) (xy 380.231706 -400.885447)
			(xy 378.79405 -400.885447) (xy 378.79405 -400.885453) (xy 378.786293 -400.939404) (xy 378.770938 -400.991701)
			(xy 378.748296 -401.041282) (xy 378.718828 -401.087135) (xy 378.683135 -401.128328) (xy 378.641943 -401.164022)
			(xy 378.59609 -401.193491) (xy 378.546511 -401.216134) (xy 378.494213 -401.231491) (xy 378.440263 -401.239249)
			(xy 378.41301 -401.239736) (xy 377.54941 -401.239736) (xy 377.522159 -401.239217) (xy 377.468211 -401.231462)
			(xy 377.415915 -401.216108) (xy 377.366338 -401.193468) (xy 377.320487 -401.164002) (xy 377.279296 -401.128311)
			(xy 377.243604 -401.087121) (xy 377.214137 -401.041271) (xy 377.191495 -400.991694) (xy 377.17614 -400.939399)
			(xy 377.168383 -400.885451) (xy 375.730873 -400.885451) (xy 375.730873 -400.885456) (xy 375.723115 -400.939414)
			(xy 375.707756 -400.991718) (xy 375.68511 -401.041304) (xy 375.655637 -401.087162) (xy 375.619937 -401.128358)
			(xy 375.578738 -401.164055) (xy 375.532877 -401.193524) (xy 375.48329 -401.216166) (xy 375.430984 -401.231521)
			(xy 375.377026 -401.239275) (xy 375.34977 -401.239736) (xy 374.48617 -401.239736) (xy 374.458922 -401.239192)
			(xy 374.404982 -401.231432) (xy 374.352694 -401.216076) (xy 374.303125 -401.193435) (xy 374.257282 -401.16397)
			(xy 374.216098 -401.128281) (xy 374.180412 -401.087094) (xy 374.150951 -401.041249) (xy 374.128314 -400.991677)
			(xy 374.112961 -400.939389) (xy 374.105206 -400.885448) (xy 372.66755 -400.885448) (xy 372.66755 -400.885452)
			(xy 372.659794 -400.939401) (xy 372.644439 -400.991697) (xy 372.621799 -401.041276) (xy 372.592333 -401.087128)
			(xy 372.556642 -401.128321) (xy 372.515452 -401.164015) (xy 372.469602 -401.193484) (xy 372.420025 -401.216129)
			(xy 372.36773 -401.231488) (xy 372.313782 -401.239248) (xy 372.28653 -401.239736) (xy 371.42293 -401.239736)
			(xy 371.395678 -401.239219) (xy 371.341728 -401.231466) (xy 371.28943 -401.216114) (xy 371.23985 -401.193474)
			(xy 371.193996 -401.164009) (xy 371.152803 -401.128318) (xy 371.117109 -401.087128) (xy 371.08764 -401.041277)
			(xy 371.064997 -400.991698) (xy 371.049641 -400.939402) (xy 371.041883 -400.885452) (xy 351.173373 -400.885452)
			(xy 351.173373 -400.885455) (xy 351.165615 -400.939411) (xy 351.150257 -400.991714) (xy 351.127612 -401.041299)
			(xy 351.098141 -401.087156) (xy 351.062443 -401.128352) (xy 351.021246 -401.164048) (xy 350.975388 -401.193518)
			(xy 350.925803 -401.216162) (xy 350.8735 -401.231518) (xy 350.819543 -401.239274) (xy 350.792288 -401.239736)
			(xy 349.928688 -401.239736) (xy 349.901439 -401.239193) (xy 349.847497 -401.231436) (xy 349.795208 -401.216081)
			(xy 349.745636 -401.19344) (xy 349.69979 -401.163976) (xy 349.658604 -401.128287) (xy 349.622917 -401.0871)
			(xy 349.593454 -401.041254) (xy 349.570815 -400.991681) (xy 349.555462 -400.939391) (xy 349.547706 -400.885449)
			(xy 348.11005 -400.885449) (xy 348.11005 -400.885451) (xy 348.102294 -400.939399) (xy 348.086941 -400.991693)
			(xy 348.064301 -401.041271) (xy 348.034837 -401.087122) (xy 347.999148 -401.128314) (xy 347.957961 -401.164009)
			(xy 347.912113 -401.193478) (xy 347.862538 -401.216124) (xy 347.810245 -401.231484) (xy 347.756299 -401.239247)
			(xy 347.729048 -401.239736) (xy 346.865448 -401.239736) (xy 346.838195 -401.23922) (xy 346.784243 -401.231469)
			(xy 346.731943 -401.216118) (xy 346.68236 -401.19348) (xy 346.636505 -401.164016) (xy 346.595309 -401.128325)
			(xy 346.559613 -401.087134) (xy 346.530143 -401.041282) (xy 346.507498 -400.991702) (xy 346.492141 -400.939404)
			(xy 346.484383 -400.885453) (xy 345.04685 -400.885453) (xy 345.039093 -400.939404) (xy 345.023737 -400.991702)
			(xy 345.001095 -401.041282) (xy 344.971628 -401.087136) (xy 344.935934 -401.128329) (xy 344.894742 -401.164023)
			(xy 344.848889 -401.193491) (xy 344.799309 -401.216135) (xy 344.747012 -401.231492) (xy 344.693061 -401.23925)
			(xy 344.665808 -401.239736) (xy 343.802208 -401.239736) (xy 343.774957 -401.239217) (xy 343.721009 -401.231462)
			(xy 343.668714 -401.216108) (xy 343.619136 -401.193467) (xy 343.573286 -401.164002) (xy 343.532095 -401.128311)
			(xy 343.496403 -401.087121) (xy 343.466937 -401.041271) (xy 343.444295 -400.991694) (xy 343.42894 -400.939399)
			(xy 343.421183 -400.885451) (xy 341.983673 -400.885451) (xy 341.983673 -400.885456) (xy 341.975915 -400.939414)
			(xy 341.960556 -400.991718) (xy 341.937909 -401.041304) (xy 341.908436 -401.087162) (xy 341.872736 -401.128359)
			(xy 341.831537 -401.164055) (xy 341.785676 -401.193525) (xy 341.736088 -401.216167) (xy 341.683783 -401.231521)
			(xy 341.629824 -401.239275) (xy 341.602568 -401.239736) (xy 340.738968 -401.239736) (xy 340.71172 -401.239192)
			(xy 340.65778 -401.231432) (xy 340.605493 -401.216075) (xy 340.555924 -401.193434) (xy 340.510081 -401.163969)
			(xy 340.468897 -401.12828) (xy 340.433212 -401.087094) (xy 340.403751 -401.041248) (xy 340.381114 -400.991677)
			(xy 340.365761 -400.939389) (xy 340.358006 -400.885448) (xy 338.92035 -400.885448) (xy 338.92035 -400.885452)
			(xy 338.912594 -400.939401) (xy 338.897239 -400.991698) (xy 338.874598 -401.041277) (xy 338.845132 -401.087129)
			(xy 338.809441 -401.128321) (xy 338.768251 -401.164016) (xy 338.722401 -401.193485) (xy 338.672824 -401.216129)
			(xy 338.620529 -401.231488) (xy 338.56658 -401.239248) (xy 338.539328 -401.239736) (xy 337.675728 -401.239736)
			(xy 337.648476 -401.239219) (xy 337.594526 -401.231465) (xy 337.542228 -401.216113) (xy 337.492648 -401.193474)
			(xy 337.446795 -401.164009) (xy 337.405602 -401.128318) (xy 337.369908 -401.087127) (xy 337.34044 -401.041276)
			(xy 337.317797 -400.991698) (xy 337.30244 -400.939402) (xy 337.294683 -400.885452) (xy 335.857173 -400.885452)
			(xy 335.857173 -400.885455) (xy 335.849415 -400.939411) (xy 335.834057 -400.991714) (xy 335.811412 -401.041299)
			(xy 335.781941 -401.087156) (xy 335.746243 -401.128352) (xy 335.705046 -401.164048) (xy 335.659188 -401.193518)
			(xy 335.609603 -401.216162) (xy 335.5573 -401.231518) (xy 335.503343 -401.239274) (xy 335.476088 -401.239736)
			(xy 334.612488 -401.239736) (xy 334.585239 -401.239193) (xy 334.531297 -401.231436) (xy 334.479008 -401.216081)
			(xy 334.429436 -401.19344) (xy 334.38359 -401.163976) (xy 334.342404 -401.128287) (xy 334.306717 -401.0871)
			(xy 334.277254 -401.041254) (xy 334.254615 -400.991681) (xy 334.239262 -400.939391) (xy 334.231506 -400.885449)
			(xy 332.79385 -400.885449) (xy 332.79385 -400.885451) (xy 332.786094 -400.939399) (xy 332.770741 -400.991693)
			(xy 332.748101 -401.041271) (xy 332.718637 -401.087122) (xy 332.682948 -401.128314) (xy 332.641761 -401.164009)
			(xy 332.595913 -401.193478) (xy 332.546338 -401.216124) (xy 332.494045 -401.231484) (xy 332.440099 -401.239247)
			(xy 332.412848 -401.239736) (xy 331.549248 -401.239736) (xy 331.521995 -401.23922) (xy 331.468043 -401.231469)
			(xy 331.415743 -401.216118) (xy 331.36616 -401.19348) (xy 331.320305 -401.164016) (xy 331.279109 -401.128325)
			(xy 331.243413 -401.087134) (xy 331.213943 -401.041282) (xy 331.191298 -400.991702) (xy 331.175941 -400.939404)
			(xy 331.168183 -400.885453) (xy 329.73065 -400.885453) (xy 329.722893 -400.939404) (xy 329.707537 -400.991702)
			(xy 329.684895 -401.041282) (xy 329.655428 -401.087136) (xy 329.619734 -401.128329) (xy 329.578542 -401.164023)
			(xy 329.532689 -401.193491) (xy 329.483109 -401.216135) (xy 329.430812 -401.231492) (xy 329.376861 -401.23925)
			(xy 329.349608 -401.239736) (xy 328.486008 -401.239736) (xy 328.458757 -401.239217) (xy 328.404809 -401.231462)
			(xy 328.352514 -401.216108) (xy 328.302936 -401.193467) (xy 328.257086 -401.164002) (xy 328.215895 -401.128311)
			(xy 328.180203 -401.087121) (xy 328.150737 -401.041271) (xy 328.128095 -400.991694) (xy 328.11274 -400.939399)
			(xy 328.104983 -400.885451) (xy 326.667473 -400.885451) (xy 326.667473 -400.885456) (xy 326.659715 -400.939414)
			(xy 326.644356 -400.991718) (xy 326.621709 -401.041304) (xy 326.592236 -401.087162) (xy 326.556536 -401.128359)
			(xy 326.515337 -401.164055) (xy 326.469476 -401.193525) (xy 326.419888 -401.216167) (xy 326.367583 -401.231521)
			(xy 326.313624 -401.239275) (xy 326.286368 -401.239736) (xy 325.422768 -401.239736) (xy 325.39552 -401.239192)
			(xy 325.34158 -401.231432) (xy 325.289293 -401.216075) (xy 325.239724 -401.193434) (xy 325.193881 -401.163969)
			(xy 325.152697 -401.12828) (xy 325.117012 -401.087094) (xy 325.087551 -401.041248) (xy 325.064914 -400.991677)
			(xy 325.049561 -400.939389) (xy 325.041806 -400.885448) (xy 323.60415 -400.885448) (xy 323.60415 -400.885452)
			(xy 323.596394 -400.939401) (xy 323.581039 -400.991698) (xy 323.558398 -401.041277) (xy 323.528932 -401.087129)
			(xy 323.493241 -401.128321) (xy 323.452051 -401.164016) (xy 323.406201 -401.193485) (xy 323.356624 -401.216129)
			(xy 323.304329 -401.231488) (xy 323.25038 -401.239248) (xy 323.223128 -401.239736) (xy 322.359528 -401.239736)
			(xy 322.332276 -401.239219) (xy 322.278326 -401.231465) (xy 322.226028 -401.216113) (xy 322.176448 -401.193474)
			(xy 322.130595 -401.164009) (xy 322.089402 -401.128318) (xy 322.053708 -401.087127) (xy 322.02424 -401.041276)
			(xy 322.001597 -400.991698) (xy 321.98624 -400.939402) (xy 321.978483 -400.885452) (xy 320.540973 -400.885452)
			(xy 320.540973 -400.885455) (xy 320.533215 -400.939411) (xy 320.517857 -400.991714) (xy 320.495212 -401.041299)
			(xy 320.465741 -401.087156) (xy 320.430043 -401.128352) (xy 320.388846 -401.164048) (xy 320.342988 -401.193518)
			(xy 320.293403 -401.216162) (xy 320.2411 -401.231518) (xy 320.187143 -401.239274) (xy 320.159888 -401.239736)
			(xy 319.296288 -401.239736) (xy 319.269039 -401.239193) (xy 319.215097 -401.231436) (xy 319.162808 -401.216081)
			(xy 319.113236 -401.19344) (xy 319.06739 -401.163976) (xy 319.026204 -401.128287) (xy 318.990517 -401.0871)
			(xy 318.961054 -401.041254) (xy 318.938415 -400.991681) (xy 318.923062 -400.939391) (xy 318.915306 -400.885449)
			(xy 317.47765 -400.885449) (xy 317.47765 -400.885451) (xy 317.469894 -400.939399) (xy 317.454541 -400.991693)
			(xy 317.431901 -401.041271) (xy 317.402437 -401.087122) (xy 317.366748 -401.128314) (xy 317.325561 -401.164009)
			(xy 317.279713 -401.193478) (xy 317.230138 -401.216124) (xy 317.177845 -401.231484) (xy 317.123899 -401.239247)
			(xy 317.096648 -401.239736) (xy 316.233048 -401.239736) (xy 316.205795 -401.23922) (xy 316.151843 -401.231469)
			(xy 316.099543 -401.216118) (xy 316.04996 -401.19348) (xy 316.004105 -401.164016) (xy 315.962909 -401.128325)
			(xy 315.927213 -401.087134) (xy 315.897743 -401.041282) (xy 315.875098 -400.991702) (xy 315.859741 -400.939404)
			(xy 315.851983 -400.885453) (xy 314.41445 -400.885453) (xy 314.406693 -400.939404) (xy 314.391337 -400.991702)
			(xy 314.368695 -401.041282) (xy 314.339228 -401.087136) (xy 314.303534 -401.128329) (xy 314.262342 -401.164023)
			(xy 314.216489 -401.193491) (xy 314.166909 -401.216135) (xy 314.114612 -401.231492) (xy 314.060661 -401.23925)
			(xy 314.033408 -401.239736) (xy 313.169808 -401.239736) (xy 313.142557 -401.239217) (xy 313.088609 -401.231462)
			(xy 313.036314 -401.216108) (xy 312.986736 -401.193467) (xy 312.940886 -401.164002) (xy 312.899695 -401.128311)
			(xy 312.864003 -401.087121) (xy 312.834537 -401.041271) (xy 312.811895 -400.991694) (xy 312.79654 -400.939399)
			(xy 312.788783 -400.885451) (xy 311.351273 -400.885451) (xy 311.351273 -400.885456) (xy 311.343515 -400.939414)
			(xy 311.328156 -400.991718) (xy 311.305509 -401.041304) (xy 311.276036 -401.087162) (xy 311.240336 -401.128359)
			(xy 311.199137 -401.164055) (xy 311.153276 -401.193525) (xy 311.103688 -401.216167) (xy 311.051383 -401.231521)
			(xy 310.997424 -401.239275) (xy 310.970168 -401.239736) (xy 310.106568 -401.239736) (xy 310.07932 -401.239192)
			(xy 310.02538 -401.231432) (xy 309.973093 -401.216075) (xy 309.923524 -401.193434) (xy 309.877681 -401.163969)
			(xy 309.836497 -401.12828) (xy 309.800812 -401.087094) (xy 309.771351 -401.041248) (xy 309.748714 -400.991677)
			(xy 309.733361 -400.939389) (xy 309.725606 -400.885448) (xy 308.28795 -400.885448) (xy 308.28795 -400.885452)
			(xy 308.280194 -400.939401) (xy 308.264839 -400.991698) (xy 308.242198 -401.041277) (xy 308.212732 -401.087129)
			(xy 308.177041 -401.128321) (xy 308.135851 -401.164016) (xy 308.090001 -401.193485) (xy 308.040424 -401.216129)
			(xy 307.988129 -401.231488) (xy 307.93418 -401.239248) (xy 307.906928 -401.239736) (xy 307.043328 -401.239736)
			(xy 307.016076 -401.239219) (xy 306.962126 -401.231465) (xy 306.909828 -401.216113) (xy 306.860248 -401.193474)
			(xy 306.814395 -401.164009) (xy 306.773202 -401.128318) (xy 306.737508 -401.087127) (xy 306.70804 -401.041276)
			(xy 306.685397 -400.991698) (xy 306.67004 -400.939402) (xy 306.662283 -400.885452) (xy 305.224773 -400.885452)
			(xy 305.224773 -400.885455) (xy 305.217015 -400.939411) (xy 305.201657 -400.991714) (xy 305.179012 -401.041299)
			(xy 305.149541 -401.087156) (xy 305.113843 -401.128352) (xy 305.072646 -401.164048) (xy 305.026788 -401.193518)
			(xy 304.977203 -401.216162) (xy 304.9249 -401.231518) (xy 304.870943 -401.239274) (xy 304.843688 -401.239736)
			(xy 303.980088 -401.239736) (xy 303.952839 -401.239193) (xy 303.898897 -401.231436) (xy 303.846608 -401.216081)
			(xy 303.797036 -401.19344) (xy 303.75119 -401.163976) (xy 303.710004 -401.128287) (xy 303.674317 -401.0871)
			(xy 303.644854 -401.041254) (xy 303.622215 -400.991681) (xy 303.606862 -400.939391) (xy 303.599106 -400.885449)
			(xy 281.686508 -400.885449) (xy 281.686508 -402.0155) (xy 287.066441 -402.0155) (xy 287.070455 -401.951698)
			(xy 287.082434 -401.888902) (xy 287.102189 -401.828103) (xy 287.129408 -401.77026) (xy 287.163662 -401.716283)
			(xy 287.204411 -401.667026) (xy 287.251013 -401.623264) (xy 287.302731 -401.585688) (xy 287.358752 -401.55489)
			(xy 287.418191 -401.531357) (xy 287.48011 -401.515458) (xy 287.543534 -401.507446) (xy 287.575498 -401.506944)
			(xy 287.575752 -401.506944) (xy 287.607498 -401.507464) (xy 287.670494 -401.515393) (xy 287.732014 -401.531096)
			(xy 287.791102 -401.55433) (xy 287.846842 -401.584733) (xy 287.898367 -401.621834) (xy 287.921954 -401.643088)
			(xy 287.929217 -401.649272) (xy 287.946967 -401.656223) (xy 287.966029 -401.656223) (xy 287.983779 -401.649272)
			(xy 287.991042 -401.643088) (xy 288.014631 -401.621832) (xy 288.06614 -401.5847) (xy 288.121874 -401.554276)
			(xy 288.180965 -401.531035) (xy 288.242492 -401.515338) (xy 288.305495 -401.507431) (xy 288.337244 -401.506944)
			(xy 288.337498 -401.506944) (xy 288.369457 -401.507521) (xy 288.432872 -401.515532) (xy 288.494783 -401.531427)
			(xy 288.554213 -401.554957) (xy 288.610226 -401.58575) (xy 288.661937 -401.623321) (xy 288.708532 -401.667076)
			(xy 288.749276 -401.716326) (xy 288.783525 -401.770295) (xy 288.810741 -401.82813) (xy 288.830493 -401.888921)
			(xy 288.84247 -401.951707) (xy 288.846484 -402.0155) (xy 289.606441 -402.0155) (xy 289.610455 -401.951698)
			(xy 289.622434 -401.888902) (xy 289.642189 -401.828103) (xy 289.669408 -401.77026) (xy 289.703662 -401.716283)
			(xy 289.744411 -401.667026) (xy 289.791013 -401.623264) (xy 289.842731 -401.585688) (xy 289.898752 -401.55489)
			(xy 289.958191 -401.531357) (xy 290.02011 -401.515458) (xy 290.083534 -401.507446) (xy 290.115498 -401.506944)
			(xy 290.115752 -401.506944) (xy 290.147498 -401.507464) (xy 290.210494 -401.515393) (xy 290.272014 -401.531096)
			(xy 290.331102 -401.55433) (xy 290.386842 -401.584733) (xy 290.438367 -401.621834) (xy 290.461954 -401.643088)
			(xy 290.469217 -401.649272) (xy 290.486967 -401.656223) (xy 290.506029 -401.656223) (xy 290.523779 -401.649272)
			(xy 290.531042 -401.643088) (xy 290.554631 -401.621832) (xy 290.60614 -401.5847) (xy 290.661874 -401.554276)
			(xy 290.720965 -401.531035) (xy 290.782492 -401.515338) (xy 290.845495 -401.507431) (xy 290.877244 -401.506944)
			(xy 290.877498 -401.506944) (xy 290.909457 -401.507521) (xy 290.972872 -401.515532) (xy 291.034783 -401.531427)
			(xy 291.094213 -401.554957) (xy 291.150226 -401.58575) (xy 291.201937 -401.623321) (xy 291.248532 -401.667076)
			(xy 291.289276 -401.716326) (xy 291.323525 -401.770295) (xy 291.350741 -401.82813) (xy 291.370493 -401.888921)
			(xy 291.38247 -401.951707) (xy 291.386484 -402.0155) (xy 292.146441 -402.0155) (xy 292.150455 -401.951698)
			(xy 292.162434 -401.888902) (xy 292.182189 -401.828103) (xy 292.209408 -401.77026) (xy 292.243662 -401.716283)
			(xy 292.284411 -401.667026) (xy 292.331013 -401.623264) (xy 292.382731 -401.585688) (xy 292.438752 -401.55489)
			(xy 292.498191 -401.531357) (xy 292.56011 -401.515458) (xy 292.623534 -401.507446) (xy 292.655498 -401.506944)
			(xy 292.655752 -401.506944) (xy 292.687498 -401.507464) (xy 292.750494 -401.515393) (xy 292.812014 -401.531096)
			(xy 292.871102 -401.55433) (xy 292.926842 -401.584733) (xy 292.978367 -401.621834) (xy 293.001954 -401.643088)
			(xy 293.009217 -401.649272) (xy 293.026967 -401.656223) (xy 293.046029 -401.656223) (xy 293.063779 -401.649272)
			(xy 293.071042 -401.643088) (xy 293.094631 -401.621832) (xy 293.14614 -401.5847) (xy 293.201874 -401.554276)
			(xy 293.260965 -401.531035) (xy 293.322492 -401.515338) (xy 293.385495 -401.507431) (xy 293.417244 -401.506944)
			(xy 293.417498 -401.506944) (xy 293.449457 -401.507521) (xy 293.512872 -401.515532) (xy 293.574783 -401.531427)
			(xy 293.634213 -401.554957) (xy 293.690226 -401.58575) (xy 293.741937 -401.623321) (xy 293.788532 -401.667076)
			(xy 293.829276 -401.716326) (xy 293.863525 -401.770295) (xy 293.890741 -401.82813) (xy 293.910493 -401.888921)
			(xy 293.92247 -401.951707) (xy 293.926484 -402.0155) (xy 294.53602 -402.0155) (xy 294.540035 -401.951693)
			(xy 294.552015 -401.888892) (xy 294.571773 -401.828089) (xy 294.598995 -401.770241) (xy 294.633253 -401.716261)
			(xy 294.674007 -401.667001) (xy 294.720613 -401.623237) (xy 294.772338 -401.58566) (xy 294.828364 -401.554862)
			(xy 294.887809 -401.531329) (xy 294.949734 -401.515433) (xy 295.013163 -401.507423) (xy 295.04513 -401.506944)
			(xy 295.045384 -401.506944) (xy 295.077131 -401.507444) (xy 295.140127 -401.515377) (xy 295.201647 -401.531084)
			(xy 295.260736 -401.554322) (xy 295.316476 -401.584728) (xy 295.368 -401.621832) (xy 295.391586 -401.643088)
			(xy 295.398849 -401.649272) (xy 295.416599 -401.656223) (xy 295.435661 -401.656223) (xy 295.453411 -401.649272)
			(xy 295.460674 -401.643088) (xy 295.48425 -401.621817) (xy 295.535761 -401.584686) (xy 295.591498 -401.554265)
			(xy 295.650592 -401.531026) (xy 295.712121 -401.515332) (xy 295.775126 -401.507429) (xy 295.806876 -401.506944)
			(xy 295.80713 -401.506944) (xy 295.839087 -401.507544) (xy 295.902496 -401.515558) (xy 295.964401 -401.531455)
			(xy 296.023825 -401.554986) (xy 296.079832 -401.585779) (xy 296.131538 -401.623348) (xy 296.178128 -401.667102)
			(xy 296.218866 -401.716349) (xy 296.253112 -401.770314) (xy 296.280324 -401.828145) (xy 296.300074 -401.888931)
			(xy 296.312049 -401.951712) (xy 296.316063 -402.0155) (xy 297.07602 -402.0155) (xy 297.080035 -401.951693)
			(xy 297.092015 -401.888892) (xy 297.111773 -401.828089) (xy 297.138995 -401.770241) (xy 297.173253 -401.716261)
			(xy 297.214007 -401.667001) (xy 297.260613 -401.623237) (xy 297.312338 -401.58566) (xy 297.368364 -401.554862)
			(xy 297.427809 -401.531329) (xy 297.489734 -401.515433) (xy 297.553163 -401.507423) (xy 297.58513 -401.506944)
			(xy 297.585384 -401.506944) (xy 297.617131 -401.507444) (xy 297.680127 -401.515377) (xy 297.741647 -401.531084)
			(xy 297.800736 -401.554322) (xy 297.856476 -401.584728) (xy 297.908 -401.621832) (xy 297.931586 -401.643088)
			(xy 297.938849 -401.649272) (xy 297.956599 -401.656223) (xy 297.975661 -401.656223) (xy 297.993411 -401.649272)
			(xy 298.000674 -401.643088) (xy 298.02425 -401.621817) (xy 298.075761 -401.584686) (xy 298.131498 -401.554265)
			(xy 298.190592 -401.531026) (xy 298.252121 -401.515332) (xy 298.315126 -401.507429) (xy 298.346876 -401.506944)
			(xy 298.34713 -401.506944) (xy 298.379087 -401.507544) (xy 298.442496 -401.515558) (xy 298.504401 -401.531455)
			(xy 298.563825 -401.554986) (xy 298.619832 -401.585779) (xy 298.671538 -401.623348) (xy 298.718128 -401.667102)
			(xy 298.758866 -401.716349) (xy 298.793112 -401.770314) (xy 298.820324 -401.828145) (xy 298.840074 -401.888931)
			(xy 298.852049 -401.951712) (xy 298.856063 -402.0155) (xy 298.852049 -402.079288) (xy 298.840074 -402.142069)
			(xy 298.820324 -402.202855) (xy 298.793112 -402.260686) (xy 298.758866 -402.314651) (xy 298.718128 -402.363898)
			(xy 298.671538 -402.407652) (xy 298.619832 -402.445221) (xy 298.563825 -402.476014) (xy 298.504401 -402.499545)
			(xy 298.442496 -402.515442) (xy 298.379087 -402.523456) (xy 298.34713 -402.52396) (xy 298.346876 -402.52396)
			(xy 298.315131 -402.523422) (xy 298.252136 -402.515497) (xy 298.190616 -402.499797) (xy 298.131527 -402.476566)
			(xy 298.075787 -402.446166) (xy 298.024261 -402.409069) (xy 298.000674 -402.387816) (xy 297.993411 -402.381632)
			(xy 297.975661 -402.374681) (xy 297.956599 -402.374681) (xy 297.938849 -402.381632) (xy 297.931586 -402.387816)
			(xy 297.908028 -402.409107) (xy 297.856512 -402.446235) (xy 297.800771 -402.476654) (xy 297.741674 -402.499889)
			(xy 297.680142 -402.515579) (xy 297.617135 -402.523478) (xy 297.585384 -402.52396) (xy 297.58513 -402.52396)
			(xy 297.553163 -402.523577) (xy 297.489734 -402.515567) (xy 297.427809 -402.499671) (xy 297.368364 -402.476138)
			(xy 297.312338 -402.44534) (xy 297.260613 -402.407763) (xy 297.214007 -402.363999) (xy 297.173253 -402.314739)
			(xy 297.138995 -402.260759) (xy 297.111773 -402.202911) (xy 297.092015 -402.142108) (xy 297.080035 -402.079307)
			(xy 297.07602 -402.0155) (xy 296.316063 -402.0155) (xy 296.312049 -402.079288) (xy 296.300074 -402.142069)
			(xy 296.280324 -402.202855) (xy 296.253112 -402.260686) (xy 296.218866 -402.314651) (xy 296.178128 -402.363898)
			(xy 296.131538 -402.407652) (xy 296.079832 -402.445221) (xy 296.023825 -402.476014) (xy 295.964401 -402.499545)
			(xy 295.902496 -402.515442) (xy 295.839087 -402.523456) (xy 295.80713 -402.52396) (xy 295.806876 -402.52396)
			(xy 295.775131 -402.523422) (xy 295.712136 -402.515497) (xy 295.650616 -402.499797) (xy 295.591527 -402.476566)
			(xy 295.535787 -402.446166) (xy 295.484261 -402.409069) (xy 295.460674 -402.387816) (xy 295.453411 -402.381632)
			(xy 295.435661 -402.374681) (xy 295.416599 -402.374681) (xy 295.398849 -402.381632) (xy 295.391586 -402.387816)
			(xy 295.368028 -402.409107) (xy 295.316512 -402.446235) (xy 295.260771 -402.476654) (xy 295.201674 -402.499889)
			(xy 295.140142 -402.515579) (xy 295.077135 -402.523478) (xy 295.045384 -402.52396) (xy 295.04513 -402.52396)
			(xy 295.013163 -402.523577) (xy 294.949734 -402.515567) (xy 294.887809 -402.499671) (xy 294.828364 -402.476138)
			(xy 294.772338 -402.44534) (xy 294.720613 -402.407763) (xy 294.674007 -402.363999) (xy 294.633253 -402.314739)
			(xy 294.598995 -402.260759) (xy 294.571773 -402.202911) (xy 294.552015 -402.142108) (xy 294.540035 -402.079307)
			(xy 294.53602 -402.0155) (xy 293.926484 -402.0155) (xy 293.92247 -402.079293) (xy 293.910493 -402.142079)
			(xy 293.890741 -402.20287) (xy 293.863525 -402.260705) (xy 293.829276 -402.314674) (xy 293.788532 -402.363924)
			(xy 293.741937 -402.407679) (xy 293.690226 -402.44525) (xy 293.634213 -402.476043) (xy 293.574783 -402.499573)
			(xy 293.512872 -402.515468) (xy 293.449457 -402.523479) (xy 293.417498 -402.52396) (xy 293.417244 -402.52396)
			(xy 293.385498 -402.523442) (xy 293.322502 -402.515512) (xy 293.260982 -402.499809) (xy 293.201894 -402.476575)
			(xy 293.146154 -402.446171) (xy 293.094629 -402.40907) (xy 293.071042 -402.387816) (xy 293.063779 -402.381632)
			(xy 293.046029 -402.374681) (xy 293.026967 -402.374681) (xy 293.009217 -402.381632) (xy 293.001954 -402.387816)
			(xy 292.978367 -402.409074) (xy 292.926858 -402.446206) (xy 292.871123 -402.47663) (xy 292.812032 -402.499871)
			(xy 292.750504 -402.515567) (xy 292.687501 -402.523474) (xy 292.655752 -402.52396) (xy 292.655498 -402.52396)
			(xy 292.623534 -402.523554) (xy 292.56011 -402.515542) (xy 292.498191 -402.499643) (xy 292.438752 -402.47611)
			(xy 292.382731 -402.445312) (xy 292.331013 -402.407736) (xy 292.284411 -402.363974) (xy 292.243662 -402.314717)
			(xy 292.209408 -402.26074) (xy 292.182189 -402.202897) (xy 292.162434 -402.142098) (xy 292.150455 -402.079302)
			(xy 292.146441 -402.0155) (xy 291.386484 -402.0155) (xy 291.38247 -402.079293) (xy 291.370493 -402.142079)
			(xy 291.350741 -402.20287) (xy 291.323525 -402.260705) (xy 291.289276 -402.314674) (xy 291.248532 -402.363924)
			(xy 291.201937 -402.407679) (xy 291.150226 -402.44525) (xy 291.094213 -402.476043) (xy 291.034783 -402.499573)
			(xy 290.972872 -402.515468) (xy 290.909457 -402.523479) (xy 290.877498 -402.52396) (xy 290.877244 -402.52396)
			(xy 290.845498 -402.523442) (xy 290.782502 -402.515512) (xy 290.720982 -402.499809) (xy 290.661894 -402.476575)
			(xy 290.606154 -402.446171) (xy 290.554629 -402.40907) (xy 290.531042 -402.387816) (xy 290.523779 -402.381632)
			(xy 290.506029 -402.374681) (xy 290.486967 -402.374681) (xy 290.469217 -402.381632) (xy 290.461954 -402.387816)
			(xy 290.438367 -402.409074) (xy 290.386858 -402.446206) (xy 290.331123 -402.47663) (xy 290.272032 -402.499871)
			(xy 290.210504 -402.515567) (xy 290.147501 -402.523474) (xy 290.115752 -402.52396) (xy 290.115498 -402.52396)
			(xy 290.083534 -402.523554) (xy 290.02011 -402.515542) (xy 289.958191 -402.499643) (xy 289.898752 -402.47611)
			(xy 289.842731 -402.445312) (xy 289.791013 -402.407736) (xy 289.744411 -402.363974) (xy 289.703662 -402.314717)
			(xy 289.669408 -402.26074) (xy 289.642189 -402.202897) (xy 289.622434 -402.142098) (xy 289.610455 -402.079302)
			(xy 289.606441 -402.0155) (xy 288.846484 -402.0155) (xy 288.84247 -402.079293) (xy 288.830493 -402.142079)
			(xy 288.810741 -402.20287) (xy 288.783525 -402.260705) (xy 288.749276 -402.314674) (xy 288.708532 -402.363924)
			(xy 288.661937 -402.407679) (xy 288.610226 -402.44525) (xy 288.554213 -402.476043) (xy 288.494783 -402.499573)
			(xy 288.432872 -402.515468) (xy 288.369457 -402.523479) (xy 288.337498 -402.52396) (xy 288.337244 -402.52396)
			(xy 288.305498 -402.523442) (xy 288.242502 -402.515512) (xy 288.180982 -402.499809) (xy 288.121894 -402.476575)
			(xy 288.066154 -402.446171) (xy 288.014629 -402.40907) (xy 287.991042 -402.387816) (xy 287.983779 -402.381632)
			(xy 287.966029 -402.374681) (xy 287.946967 -402.374681) (xy 287.929217 -402.381632) (xy 287.921954 -402.387816)
			(xy 287.898367 -402.409074) (xy 287.846858 -402.446206) (xy 287.791123 -402.47663) (xy 287.732032 -402.499871)
			(xy 287.670504 -402.515567) (xy 287.607501 -402.523474) (xy 287.575752 -402.52396) (xy 287.575498 -402.52396)
			(xy 287.543534 -402.523554) (xy 287.48011 -402.515542) (xy 287.418191 -402.499643) (xy 287.358752 -402.47611)
			(xy 287.302731 -402.445312) (xy 287.251013 -402.407736) (xy 287.204411 -402.363974) (xy 287.163662 -402.314717)
			(xy 287.129408 -402.26074) (xy 287.102189 -402.202897) (xy 287.082434 -402.142098) (xy 287.070455 -402.079302)
			(xy 287.066441 -402.0155) (xy 281.686508 -402.0155) (xy 281.686508 -404.0475) (xy 287.066441 -404.0475)
			(xy 287.070455 -403.983698) (xy 287.082434 -403.920902) (xy 287.102189 -403.860103) (xy 287.129408 -403.80226)
			(xy 287.163662 -403.748283) (xy 287.204411 -403.699026) (xy 287.251013 -403.655264) (xy 287.302731 -403.617688)
			(xy 287.358752 -403.58689) (xy 287.418191 -403.563357) (xy 287.48011 -403.547458) (xy 287.543534 -403.539446)
			(xy 287.575498 -403.538944) (xy 287.575752 -403.538944) (xy 287.607498 -403.539464) (xy 287.670494 -403.547393)
			(xy 287.732014 -403.563096) (xy 287.791102 -403.58633) (xy 287.846842 -403.616733) (xy 287.898367 -403.653834)
			(xy 287.921954 -403.675088) (xy 287.929217 -403.681272) (xy 287.946967 -403.688223) (xy 287.966029 -403.688223)
			(xy 287.983779 -403.681272) (xy 287.991042 -403.675088) (xy 288.014631 -403.653832) (xy 288.06614 -403.6167)
			(xy 288.121874 -403.586276) (xy 288.180965 -403.563035) (xy 288.242492 -403.547338) (xy 288.305495 -403.539431)
			(xy 288.337244 -403.538944) (xy 288.337498 -403.538944) (xy 288.369457 -403.539521) (xy 288.432872 -403.547532)
			(xy 288.494783 -403.563427) (xy 288.554213 -403.586957) (xy 288.610226 -403.61775) (xy 288.661937 -403.655321)
			(xy 288.708532 -403.699076) (xy 288.749276 -403.748326) (xy 288.783525 -403.802295) (xy 288.810741 -403.86013)
			(xy 288.830493 -403.920921) (xy 288.84247 -403.983707) (xy 288.846484 -404.0475) (xy 289.606441 -404.0475)
			(xy 289.610455 -403.983698) (xy 289.622434 -403.920902) (xy 289.642189 -403.860103) (xy 289.669408 -403.80226)
			(xy 289.703662 -403.748283) (xy 289.744411 -403.699026) (xy 289.791013 -403.655264) (xy 289.842731 -403.617688)
			(xy 289.898752 -403.58689) (xy 289.958191 -403.563357) (xy 290.02011 -403.547458) (xy 290.083534 -403.539446)
			(xy 290.115498 -403.538944) (xy 290.115752 -403.538944) (xy 290.147498 -403.539464) (xy 290.210494 -403.547393)
			(xy 290.272014 -403.563096) (xy 290.331102 -403.58633) (xy 290.386842 -403.616733) (xy 290.438367 -403.653834)
			(xy 290.461954 -403.675088) (xy 290.469217 -403.681272) (xy 290.486967 -403.688223) (xy 290.506029 -403.688223)
			(xy 290.523779 -403.681272) (xy 290.531042 -403.675088) (xy 290.554631 -403.653832) (xy 290.60614 -403.6167)
			(xy 290.661874 -403.586276) (xy 290.720965 -403.563035) (xy 290.782492 -403.547338) (xy 290.845495 -403.539431)
			(xy 290.877244 -403.538944) (xy 290.877498 -403.538944) (xy 290.909457 -403.539521) (xy 290.972872 -403.547532)
			(xy 291.034783 -403.563427) (xy 291.094213 -403.586957) (xy 291.150226 -403.61775) (xy 291.201937 -403.655321)
			(xy 291.248532 -403.699076) (xy 291.289276 -403.748326) (xy 291.323525 -403.802295) (xy 291.350741 -403.86013)
			(xy 291.370493 -403.920921) (xy 291.38247 -403.983707) (xy 291.386484 -404.0475) (xy 292.146441 -404.0475)
			(xy 292.150455 -403.983698) (xy 292.162434 -403.920902) (xy 292.182189 -403.860103) (xy 292.209408 -403.80226)
			(xy 292.243662 -403.748283) (xy 292.284411 -403.699026) (xy 292.331013 -403.655264) (xy 292.382731 -403.617688)
			(xy 292.438752 -403.58689) (xy 292.498191 -403.563357) (xy 292.56011 -403.547458) (xy 292.623534 -403.539446)
			(xy 292.655498 -403.538944) (xy 292.655752 -403.538944) (xy 292.687498 -403.539464) (xy 292.750494 -403.547393)
			(xy 292.812014 -403.563096) (xy 292.871102 -403.58633) (xy 292.926842 -403.616733) (xy 292.978367 -403.653834)
			(xy 293.001954 -403.675088) (xy 293.009217 -403.681272) (xy 293.026967 -403.688223) (xy 293.046029 -403.688223)
			(xy 293.063779 -403.681272) (xy 293.071042 -403.675088) (xy 293.094631 -403.653832) (xy 293.14614 -403.6167)
			(xy 293.201874 -403.586276) (xy 293.260965 -403.563035) (xy 293.322492 -403.547338) (xy 293.385495 -403.539431)
			(xy 293.417244 -403.538944) (xy 293.417498 -403.538944) (xy 293.449457 -403.539521) (xy 293.512872 -403.547532)
			(xy 293.574783 -403.563427) (xy 293.634213 -403.586957) (xy 293.690226 -403.61775) (xy 293.741937 -403.655321)
			(xy 293.788532 -403.699076) (xy 293.829276 -403.748326) (xy 293.863525 -403.802295) (xy 293.890741 -403.86013)
			(xy 293.910493 -403.920921) (xy 293.92247 -403.983707) (xy 293.926484 -404.0475) (xy 294.53602 -404.0475)
			(xy 294.540035 -403.983693) (xy 294.552015 -403.920892) (xy 294.571773 -403.860089) (xy 294.598995 -403.802241)
			(xy 294.633253 -403.748261) (xy 294.674007 -403.699001) (xy 294.720613 -403.655237) (xy 294.772338 -403.61766)
			(xy 294.828364 -403.586862) (xy 294.887809 -403.563329) (xy 294.949734 -403.547433) (xy 295.013163 -403.539423)
			(xy 295.04513 -403.538944) (xy 295.045384 -403.538944) (xy 295.077131 -403.539444) (xy 295.140127 -403.547377)
			(xy 295.201647 -403.563084) (xy 295.260736 -403.586322) (xy 295.316476 -403.616728) (xy 295.368 -403.653832)
			(xy 295.391586 -403.675088) (xy 295.398849 -403.681272) (xy 295.416599 -403.688223) (xy 295.435661 -403.688223)
			(xy 295.453411 -403.681272) (xy 295.460674 -403.675088) (xy 295.48425 -403.653817) (xy 295.535761 -403.616686)
			(xy 295.591498 -403.586265) (xy 295.650592 -403.563026) (xy 295.712121 -403.547332) (xy 295.775126 -403.539429)
			(xy 295.806876 -403.538944) (xy 295.80713 -403.538944) (xy 295.839087 -403.539544) (xy 295.902496 -403.547558)
			(xy 295.964401 -403.563455) (xy 296.023825 -403.586986) (xy 296.079832 -403.617779) (xy 296.131538 -403.655348)
			(xy 296.178128 -403.699102) (xy 296.218866 -403.748349) (xy 296.253112 -403.802314) (xy 296.280324 -403.860145)
			(xy 296.300074 -403.920931) (xy 296.312049 -403.983712) (xy 296.316063 -404.0475) (xy 297.07602 -404.0475)
			(xy 297.080035 -403.983693) (xy 297.092015 -403.920892) (xy 297.111773 -403.860089) (xy 297.138995 -403.802241)
			(xy 297.173253 -403.748261) (xy 297.214007 -403.699001) (xy 297.260613 -403.655237) (xy 297.312338 -403.61766)
			(xy 297.368364 -403.586862) (xy 297.427809 -403.563329) (xy 297.489734 -403.547433) (xy 297.553163 -403.539423)
			(xy 297.58513 -403.538944) (xy 297.585384 -403.538944) (xy 297.617131 -403.539444) (xy 297.680127 -403.547377)
			(xy 297.741647 -403.563084) (xy 297.800736 -403.586322) (xy 297.856476 -403.616728) (xy 297.908 -403.653832)
			(xy 297.931586 -403.675088) (xy 297.938849 -403.681272) (xy 297.956599 -403.688223) (xy 297.975661 -403.688223)
			(xy 297.993411 -403.681272) (xy 298.000674 -403.675088) (xy 298.02425 -403.653817) (xy 298.075761 -403.616686)
			(xy 298.131498 -403.586265) (xy 298.190592 -403.563026) (xy 298.252121 -403.547332) (xy 298.315126 -403.539429)
			(xy 298.346876 -403.538944) (xy 298.34713 -403.538944) (xy 298.379087 -403.539544) (xy 298.442496 -403.547558)
			(xy 298.504401 -403.563455) (xy 298.563825 -403.586986) (xy 298.619832 -403.617779) (xy 298.671538 -403.655348)
			(xy 298.718128 -403.699102) (xy 298.758866 -403.748349) (xy 298.793112 -403.802314) (xy 298.820324 -403.860145)
			(xy 298.836897 -403.911152) (xy 303.599054 -403.911152) (xy 303.599054 -403.856648) (xy 303.60681 -403.802698)
			(xy 303.622166 -403.7504) (xy 303.644808 -403.700821) (xy 303.674275 -403.654968) (xy 303.709967 -403.613776)
			(xy 303.751159 -403.578082) (xy 303.79701 -403.548613) (xy 303.846589 -403.52597) (xy 303.898886 -403.510613)
			(xy 303.952836 -403.502855) (xy 303.980088 -403.502368) (xy 304.843688 -403.502368) (xy 304.87094 -403.502878)
			(xy 304.924889 -403.510634) (xy 304.977185 -403.525988) (xy 305.026763 -403.548628) (xy 305.072615 -403.578094)
			(xy 305.113806 -403.613785) (xy 305.149499 -403.654976) (xy 305.178966 -403.700826) (xy 305.201608 -403.750404)
			(xy 305.216964 -403.8027) (xy 305.224721 -403.856648) (xy 305.224721 -403.911152) (xy 305.22472 -403.911156)
			(xy 306.662231 -403.911156) (xy 306.662231 -403.856644) (xy 306.669989 -403.802687) (xy 306.685348 -403.750384)
			(xy 306.707994 -403.700799) (xy 306.737466 -403.654941) (xy 306.773165 -403.613745) (xy 306.814364 -403.578049)
			(xy 306.860223 -403.54858) (xy 306.90981 -403.525938) (xy 306.962115 -403.510583) (xy 307.016072 -403.502829)
			(xy 307.043328 -403.502368) (xy 307.906928 -403.502368) (xy 307.934176 -403.502904) (xy 307.988117 -403.510663)
			(xy 308.040405 -403.52602) (xy 308.089976 -403.548661) (xy 308.13582 -403.578126) (xy 308.177004 -403.613816)
			(xy 308.21269 -403.655002) (xy 308.242152 -403.700849) (xy 308.26479 -403.750421) (xy 308.280143 -403.80271)
			(xy 308.287898 -403.856652) (xy 308.287898 -403.911148) (xy 308.287897 -403.911152) (xy 309.725554 -403.911152)
			(xy 309.725554 -403.856648) (xy 309.73331 -403.8027) (xy 309.748664 -403.750405) (xy 309.771305 -403.700826)
			(xy 309.80077 -403.654975) (xy 309.83646 -403.613783) (xy 309.877649 -403.578089) (xy 309.923498 -403.54862)
			(xy 309.973075 -403.525976) (xy 310.025369 -403.510617) (xy 310.079317 -403.502856) (xy 310.106568 -403.502368)
			(xy 310.970168 -403.502368) (xy 310.997421 -403.502877) (xy 311.051372 -403.51063) (xy 311.10367 -403.525982)
			(xy 311.153251 -403.548621) (xy 311.199105 -403.578087) (xy 311.240299 -403.613778) (xy 311.275994 -403.654969)
			(xy 311.305463 -403.700821) (xy 311.328107 -403.7504) (xy 311.343463 -403.802697) (xy 311.351221 -403.856647)
			(xy 311.351221 -403.911153) (xy 311.351221 -403.911155) (xy 312.788731 -403.911155) (xy 312.788731 -403.856645)
			(xy 312.796489 -403.80269) (xy 312.811846 -403.750388) (xy 312.834491 -403.700804) (xy 312.863961 -403.654948)
			(xy 312.899658 -403.613752) (xy 312.940854 -403.578056) (xy 312.986711 -403.548587) (xy 313.036296 -403.525943)
			(xy 313.088598 -403.510587) (xy 313.142553 -403.50283) (xy 313.169808 -403.502368) (xy 314.033408 -403.502368)
			(xy 314.060657 -403.502903) (xy 314.114601 -403.51066) (xy 314.166891 -403.526015) (xy 314.216464 -403.548655)
			(xy 314.26231 -403.578119) (xy 314.303497 -403.613809) (xy 314.339186 -403.654996) (xy 314.368649 -403.700843)
			(xy 314.391288 -403.750417) (xy 314.406642 -403.802707) (xy 314.414398 -403.856651) (xy 314.414398 -403.911149)
			(xy 314.414397 -403.911157) (xy 315.851931 -403.911157) (xy 315.851931 -403.856643) (xy 315.85969 -403.802685)
			(xy 315.875049 -403.75038) (xy 315.897697 -403.700793) (xy 315.927171 -403.654935) (xy 315.962872 -403.613738)
			(xy 316.004073 -403.578042) (xy 316.049935 -403.548574) (xy 316.099525 -403.525932) (xy 316.151832 -403.51058)
			(xy 316.205791 -403.502828) (xy 316.233048 -403.502368) (xy 317.096648 -403.502368) (xy 317.123895 -403.502905)
			(xy 317.177834 -403.510667) (xy 317.23012 -403.526025) (xy 317.279688 -403.548668) (xy 317.325529 -403.578133)
			(xy 317.366711 -403.613823) (xy 317.402395 -403.655009) (xy 317.431855 -403.700854) (xy 317.454491 -403.750425)
			(xy 317.469843 -403.802713) (xy 317.477598 -403.856653) (xy 317.477598 -403.911147) (xy 317.477597 -403.911152)
			(xy 318.915254 -403.911152) (xy 318.915254 -403.856648) (xy 318.92301 -403.802698) (xy 318.938366 -403.7504)
			(xy 318.961008 -403.700821) (xy 318.990475 -403.654968) (xy 319.026167 -403.613776) (xy 319.067359 -403.578082)
			(xy 319.11321 -403.548613) (xy 319.162789 -403.52597) (xy 319.215086 -403.510613) (xy 319.269036 -403.502855)
			(xy 319.296288 -403.502368) (xy 320.159888 -403.502368) (xy 320.18714 -403.502878) (xy 320.241089 -403.510634)
			(xy 320.293385 -403.525988) (xy 320.342963 -403.548628) (xy 320.388815 -403.578094) (xy 320.430006 -403.613785)
			(xy 320.465699 -403.654976) (xy 320.495166 -403.700826) (xy 320.517808 -403.750404) (xy 320.533164 -403.8027)
			(xy 320.540921 -403.856648) (xy 320.540921 -403.911152) (xy 320.54092 -403.911156) (xy 321.978431 -403.911156)
			(xy 321.978431 -403.856644) (xy 321.986189 -403.802687) (xy 322.001548 -403.750384) (xy 322.024194 -403.700799)
			(xy 322.053666 -403.654941) (xy 322.089365 -403.613745) (xy 322.130564 -403.578049) (xy 322.176423 -403.54858)
			(xy 322.22601 -403.525938) (xy 322.278315 -403.510583) (xy 322.332272 -403.502829) (xy 322.359528 -403.502368)
			(xy 323.223128 -403.502368) (xy 323.250376 -403.502904) (xy 323.304317 -403.510663) (xy 323.356605 -403.52602)
			(xy 323.406176 -403.548661) (xy 323.45202 -403.578126) (xy 323.493204 -403.613816) (xy 323.52889 -403.655002)
			(xy 323.558352 -403.700849) (xy 323.58099 -403.750421) (xy 323.596343 -403.80271) (xy 323.604098 -403.856652)
			(xy 323.604098 -403.911148) (xy 323.604097 -403.911152) (xy 325.041754 -403.911152) (xy 325.041754 -403.856648)
			(xy 325.04951 -403.8027) (xy 325.064864 -403.750405) (xy 325.087505 -403.700826) (xy 325.11697 -403.654975)
			(xy 325.15266 -403.613783) (xy 325.193849 -403.578089) (xy 325.239698 -403.54862) (xy 325.289275 -403.525976)
			(xy 325.341569 -403.510617) (xy 325.395517 -403.502856) (xy 325.422768 -403.502368) (xy 326.286368 -403.502368)
			(xy 326.313621 -403.502877) (xy 326.367572 -403.51063) (xy 326.41987 -403.525982) (xy 326.469451 -403.548621)
			(xy 326.515305 -403.578087) (xy 326.556499 -403.613778) (xy 326.592194 -403.654969) (xy 326.621663 -403.700821)
			(xy 326.644307 -403.7504) (xy 326.659663 -403.802697) (xy 326.667421 -403.856647) (xy 326.667421 -403.911153)
			(xy 326.667421 -403.911155) (xy 328.104931 -403.911155) (xy 328.104931 -403.856645) (xy 328.112689 -403.80269)
			(xy 328.128046 -403.750388) (xy 328.150691 -403.700804) (xy 328.180161 -403.654948) (xy 328.215858 -403.613752)
			(xy 328.257054 -403.578056) (xy 328.302911 -403.548587) (xy 328.352496 -403.525943) (xy 328.404798 -403.510587)
			(xy 328.458753 -403.50283) (xy 328.486008 -403.502368) (xy 329.349608 -403.502368) (xy 329.376857 -403.502903)
			(xy 329.430801 -403.51066) (xy 329.483091 -403.526015) (xy 329.532664 -403.548655) (xy 329.57851 -403.578119)
			(xy 329.619697 -403.613809) (xy 329.655386 -403.654996) (xy 329.684849 -403.700843) (xy 329.707488 -403.750417)
			(xy 329.722842 -403.802707) (xy 329.730598 -403.856651) (xy 329.730598 -403.911149) (xy 329.730597 -403.911157)
			(xy 331.168131 -403.911157) (xy 331.168131 -403.856643) (xy 331.17589 -403.802685) (xy 331.191249 -403.75038)
			(xy 331.213897 -403.700793) (xy 331.243371 -403.654935) (xy 331.279072 -403.613738) (xy 331.320273 -403.578042)
			(xy 331.366135 -403.548574) (xy 331.415725 -403.525932) (xy 331.468032 -403.51058) (xy 331.521991 -403.502828)
			(xy 331.549248 -403.502368) (xy 332.412848 -403.502368) (xy 332.440095 -403.502905) (xy 332.494034 -403.510667)
			(xy 332.54632 -403.526025) (xy 332.595888 -403.548668) (xy 332.641729 -403.578133) (xy 332.682911 -403.613823)
			(xy 332.718595 -403.655009) (xy 332.748055 -403.700854) (xy 332.770691 -403.750425) (xy 332.786043 -403.802713)
			(xy 332.793798 -403.856653) (xy 332.793798 -403.911147) (xy 332.793797 -403.911152) (xy 334.231454 -403.911152)
			(xy 334.231454 -403.856648) (xy 334.23921 -403.802698) (xy 334.254566 -403.7504) (xy 334.277208 -403.700821)
			(xy 334.306675 -403.654968) (xy 334.342367 -403.613776) (xy 334.383559 -403.578082) (xy 334.42941 -403.548613)
			(xy 334.478989 -403.52597) (xy 334.531286 -403.510613) (xy 334.585236 -403.502855) (xy 334.612488 -403.502368)
			(xy 335.476088 -403.502368) (xy 335.50334 -403.502878) (xy 335.557289 -403.510634) (xy 335.609585 -403.525988)
			(xy 335.659163 -403.548628) (xy 335.705015 -403.578094) (xy 335.746206 -403.613785) (xy 335.781899 -403.654976)
			(xy 335.811366 -403.700826) (xy 335.834008 -403.750404) (xy 335.849364 -403.8027) (xy 335.857121 -403.856648)
			(xy 335.857121 -403.911152) (xy 335.85712 -403.911156) (xy 337.294631 -403.911156) (xy 337.294631 -403.856644)
			(xy 337.302389 -403.802687) (xy 337.317748 -403.750384) (xy 337.340394 -403.700799) (xy 337.369866 -403.654941)
			(xy 337.405565 -403.613745) (xy 337.446764 -403.578049) (xy 337.492623 -403.54858) (xy 337.54221 -403.525938)
			(xy 337.594515 -403.510583) (xy 337.648472 -403.502829) (xy 337.675728 -403.502368) (xy 338.539328 -403.502368)
			(xy 338.566576 -403.502904) (xy 338.620517 -403.510663) (xy 338.672805 -403.52602) (xy 338.722376 -403.548661)
			(xy 338.76822 -403.578126) (xy 338.809404 -403.613816) (xy 338.84509 -403.655002) (xy 338.874552 -403.700849)
			(xy 338.89719 -403.750421) (xy 338.912543 -403.80271) (xy 338.920298 -403.856652) (xy 338.920298 -403.911148)
			(xy 338.920297 -403.911152) (xy 340.357954 -403.911152) (xy 340.357954 -403.856648) (xy 340.36571 -403.8027)
			(xy 340.381064 -403.750405) (xy 340.403705 -403.700826) (xy 340.43317 -403.654975) (xy 340.46886 -403.613783)
			(xy 340.510049 -403.578089) (xy 340.555898 -403.54862) (xy 340.605475 -403.525976) (xy 340.657769 -403.510617)
			(xy 340.711717 -403.502856) (xy 340.738968 -403.502368) (xy 341.602568 -403.502368) (xy 341.629821 -403.502877)
			(xy 341.683772 -403.51063) (xy 341.73607 -403.525982) (xy 341.785651 -403.548621) (xy 341.831505 -403.578087)
			(xy 341.872699 -403.613778) (xy 341.908394 -403.654969) (xy 341.937863 -403.700821) (xy 341.960507 -403.7504)
			(xy 341.975863 -403.802697) (xy 341.983621 -403.856647) (xy 341.983621 -403.911153) (xy 341.983621 -403.911155)
			(xy 343.421131 -403.911155) (xy 343.421131 -403.856645) (xy 343.428889 -403.80269) (xy 343.444246 -403.750388)
			(xy 343.466891 -403.700804) (xy 343.496361 -403.654948) (xy 343.532058 -403.613752) (xy 343.573254 -403.578056)
			(xy 343.619111 -403.548587) (xy 343.668696 -403.525943) (xy 343.720998 -403.510587) (xy 343.774953 -403.50283)
			(xy 343.802208 -403.502368) (xy 344.665808 -403.502368) (xy 344.693057 -403.502903) (xy 344.747001 -403.51066)
			(xy 344.799291 -403.526015) (xy 344.848864 -403.548655) (xy 344.89471 -403.578119) (xy 344.935897 -403.613809)
			(xy 344.971586 -403.654996) (xy 345.001049 -403.700843) (xy 345.023688 -403.750417) (xy 345.039042 -403.802707)
			(xy 345.046798 -403.856651) (xy 345.046798 -403.911149) (xy 345.046797 -403.911157) (xy 346.484331 -403.911157)
			(xy 346.484331 -403.856643) (xy 346.49209 -403.802685) (xy 346.507449 -403.75038) (xy 346.530097 -403.700793)
			(xy 346.559571 -403.654935) (xy 346.595272 -403.613738) (xy 346.636473 -403.578042) (xy 346.682335 -403.548574)
			(xy 346.731925 -403.525932) (xy 346.784232 -403.51058) (xy 346.838191 -403.502828) (xy 346.865448 -403.502368)
			(xy 347.729048 -403.502368) (xy 347.756295 -403.502905) (xy 347.810234 -403.510667) (xy 347.86252 -403.526025)
			(xy 347.912088 -403.548668) (xy 347.957929 -403.578133) (xy 347.999111 -403.613823) (xy 348.034795 -403.655009)
			(xy 348.064255 -403.700854) (xy 348.086891 -403.750425) (xy 348.102243 -403.802713) (xy 348.109998 -403.856653)
			(xy 348.109998 -403.911147) (xy 348.109997 -403.911152) (xy 349.547654 -403.911152) (xy 349.547654 -403.856648)
			(xy 349.55541 -403.802698) (xy 349.570766 -403.7504) (xy 349.593408 -403.700821) (xy 349.622875 -403.654968)
			(xy 349.658567 -403.613776) (xy 349.699759 -403.578082) (xy 349.74561 -403.548613) (xy 349.795189 -403.52597)
			(xy 349.847486 -403.510613) (xy 349.901436 -403.502855) (xy 349.928688 -403.502368) (xy 350.792288 -403.502368)
			(xy 350.81954 -403.502878) (xy 350.873489 -403.510634) (xy 350.925785 -403.525988) (xy 350.975363 -403.548628)
			(xy 351.021215 -403.578094) (xy 351.062406 -403.613785) (xy 351.098099 -403.654976) (xy 351.127566 -403.700826)
			(xy 351.150208 -403.750404) (xy 351.165564 -403.8027) (xy 351.173321 -403.856648) (xy 351.173321 -403.911152)
			(xy 351.17332 -403.911156) (xy 371.041831 -403.911156) (xy 371.041831 -403.856644) (xy 371.049589 -403.802687)
			(xy 371.064948 -403.750383) (xy 371.087594 -403.700798) (xy 371.117067 -403.654941) (xy 371.152766 -403.613745)
			(xy 371.193965 -403.578049) (xy 371.239824 -403.54858) (xy 371.289412 -403.525937) (xy 371.341716 -403.510583)
			(xy 371.395674 -403.502829) (xy 371.42293 -403.502368) (xy 372.28653 -403.502368) (xy 372.313778 -403.502904)
			(xy 372.367719 -403.510664) (xy 372.420007 -403.52602) (xy 372.469577 -403.548662) (xy 372.515421 -403.578127)
			(xy 372.556605 -403.613816) (xy 372.592291 -403.655003) (xy 372.621753 -403.700849) (xy 372.64439 -403.750421)
			(xy 372.659743 -403.80271) (xy 372.667498 -403.856652) (xy 372.667498 -403.911148) (xy 372.667497 -403.911152)
			(xy 374.105154 -403.911152) (xy 374.105154 -403.856648) (xy 374.11291 -403.8027) (xy 374.128265 -403.750404)
			(xy 374.150905 -403.700826) (xy 374.18037 -403.654974) (xy 374.216061 -403.613782) (xy 374.25725 -403.578088)
			(xy 374.3031 -403.548619) (xy 374.352676 -403.525975) (xy 374.404971 -403.510616) (xy 374.458918 -403.502856)
			(xy 374.48617 -403.502368) (xy 375.34977 -403.502368) (xy 375.377023 -403.502877) (xy 375.430973 -403.51063)
			(xy 375.483271 -403.525983) (xy 375.532852 -403.548622) (xy 375.578706 -403.578087) (xy 375.6199 -403.613779)
			(xy 375.655595 -403.65497) (xy 375.685064 -403.700821) (xy 375.707707 -403.7504) (xy 375.723063 -403.802697)
			(xy 375.730821 -403.856647) (xy 375.730821 -403.911153) (xy 375.730821 -403.911155) (xy 377.168331 -403.911155)
			(xy 377.168331 -403.856645) (xy 377.176089 -403.80269) (xy 377.191446 -403.750388) (xy 377.214091 -403.700804)
			(xy 377.243562 -403.654947) (xy 377.279259 -403.613752) (xy 377.320455 -403.578056) (xy 377.366313 -403.548586)
			(xy 377.415897 -403.525943) (xy 377.468199 -403.510587) (xy 377.522155 -403.50283) (xy 377.54941 -403.502368)
			(xy 378.41301 -403.502368) (xy 378.440259 -403.502903) (xy 378.494202 -403.51066) (xy 378.546492 -403.526015)
			(xy 378.596065 -403.548655) (xy 378.641911 -403.57812) (xy 378.683098 -403.613809) (xy 378.718786 -403.654997)
			(xy 378.748249 -403.700844) (xy 378.770888 -403.750417) (xy 378.786242 -403.802708) (xy 378.793998 -403.856651)
			(xy 378.793998 -403.911149) (xy 378.793998 -403.911151) (xy 380.231654 -403.911151) (xy 380.231654 -403.856649)
			(xy 380.239409 -403.802703) (xy 380.254763 -403.750409) (xy 380.277402 -403.700832) (xy 380.306865 -403.654981)
			(xy 380.342554 -403.613789) (xy 380.383741 -403.578095) (xy 380.429588 -403.548626) (xy 380.479162 -403.52598)
			(xy 380.531454 -403.51062) (xy 380.585399 -403.502857) (xy 380.61265 -403.502368) (xy 381.47625 -403.502368)
			(xy 381.503503 -403.502876) (xy 381.557456 -403.510627) (xy 381.609757 -403.525977) (xy 381.65934 -403.548616)
			(xy 381.705197 -403.57808) (xy 381.746393 -403.613772) (xy 381.78209 -403.654963) (xy 381.81156 -403.700816)
			(xy 381.834205 -403.750396) (xy 381.849563 -403.802695) (xy 381.857321 -403.856647) (xy 381.857321 -403.911153)
			(xy 383.294854 -403.911153) (xy 383.294854 -403.856647) (xy 383.302611 -403.802697) (xy 383.317966 -403.7504)
			(xy 383.340608 -403.70082) (xy 383.370075 -403.654968) (xy 383.405768 -403.613775) (xy 383.44696 -403.578081)
			(xy 383.492812 -403.548613) (xy 383.542391 -403.52597) (xy 383.594687 -403.510613) (xy 383.648638 -403.502855)
			(xy 383.67589 -403.502368) (xy 384.53949 -403.502368) (xy 384.566742 -403.502879) (xy 384.62069 -403.510634)
			(xy 384.672986 -403.525988) (xy 384.722564 -403.548629) (xy 384.768416 -403.578095) (xy 384.809607 -403.613786)
			(xy 384.845299 -403.654976) (xy 384.874767 -403.700827) (xy 384.897408 -403.750405) (xy 384.912764 -403.8027)
			(xy 384.920521 -403.856648) (xy 384.920521 -403.911152) (xy 384.92052 -403.911156) (xy 386.358031 -403.911156)
			(xy 386.358031 -403.856644) (xy 386.365789 -403.802687) (xy 386.381148 -403.750383) (xy 386.403794 -403.700798)
			(xy 386.433267 -403.654941) (xy 386.468966 -403.613745) (xy 386.510165 -403.578049) (xy 386.556024 -403.54858)
			(xy 386.605612 -403.525937) (xy 386.657916 -403.510583) (xy 386.711874 -403.502829) (xy 386.73913 -403.502368)
			(xy 387.60273 -403.502368) (xy 387.629978 -403.502904) (xy 387.683919 -403.510664) (xy 387.736207 -403.52602)
			(xy 387.785777 -403.548662) (xy 387.831621 -403.578127) (xy 387.872805 -403.613816) (xy 387.908491 -403.655003)
			(xy 387.937953 -403.700849) (xy 387.96059 -403.750421) (xy 387.975943 -403.80271) (xy 387.983698 -403.856652)
			(xy 387.983698 -403.911148) (xy 387.983697 -403.911152) (xy 389.421354 -403.911152) (xy 389.421354 -403.856648)
			(xy 389.42911 -403.8027) (xy 389.444465 -403.750404) (xy 389.467105 -403.700826) (xy 389.49657 -403.654974)
			(xy 389.532261 -403.613782) (xy 389.57345 -403.578088) (xy 389.6193 -403.548619) (xy 389.668876 -403.525975)
			(xy 389.721171 -403.510616) (xy 389.775118 -403.502856) (xy 389.80237 -403.502368) (xy 390.66597 -403.502368)
			(xy 390.693223 -403.502877) (xy 390.747173 -403.51063) (xy 390.799471 -403.525983) (xy 390.849052 -403.548622)
			(xy 390.894906 -403.578087) (xy 390.9361 -403.613779) (xy 390.971795 -403.65497) (xy 391.001264 -403.700821)
			(xy 391.023907 -403.7504) (xy 391.039263 -403.802697) (xy 391.047021 -403.856647) (xy 391.047021 -403.911153)
			(xy 391.047021 -403.911155) (xy 392.484531 -403.911155) (xy 392.484531 -403.856645) (xy 392.492289 -403.80269)
			(xy 392.507646 -403.750388) (xy 392.530291 -403.700804) (xy 392.559762 -403.654947) (xy 392.595459 -403.613752)
			(xy 392.636655 -403.578056) (xy 392.682513 -403.548586) (xy 392.732097 -403.525943) (xy 392.784399 -403.510587)
			(xy 392.838355 -403.50283) (xy 392.86561 -403.502368) (xy 393.72921 -403.502368) (xy 393.756459 -403.502903)
			(xy 393.810402 -403.51066) (xy 393.862692 -403.526015) (xy 393.912265 -403.548655) (xy 393.958111 -403.57812)
			(xy 393.999298 -403.613809) (xy 394.034986 -403.654997) (xy 394.064449 -403.700844) (xy 394.087088 -403.750417)
			(xy 394.102442 -403.802708) (xy 394.110198 -403.856651) (xy 394.110198 -403.911149) (xy 394.110198 -403.911151)
			(xy 395.547854 -403.911151) (xy 395.547854 -403.856649) (xy 395.555609 -403.802703) (xy 395.570963 -403.750409)
			(xy 395.593602 -403.700832) (xy 395.623065 -403.654981) (xy 395.658754 -403.613789) (xy 395.699941 -403.578095)
			(xy 395.745788 -403.548626) (xy 395.795362 -403.52598) (xy 395.847654 -403.51062) (xy 395.901599 -403.502857)
			(xy 395.92885 -403.502368) (xy 396.79245 -403.502368) (xy 396.819703 -403.502876) (xy 396.873656 -403.510627)
			(xy 396.925957 -403.525977) (xy 396.97554 -403.548616) (xy 397.021397 -403.57808) (xy 397.062593 -403.613772)
			(xy 397.09829 -403.654963) (xy 397.12776 -403.700816) (xy 397.150405 -403.750396) (xy 397.165763 -403.802695)
			(xy 397.173521 -403.856647) (xy 397.173521 -403.911153) (xy 398.611054 -403.911153) (xy 398.611054 -403.856647)
			(xy 398.618811 -403.802697) (xy 398.634166 -403.7504) (xy 398.656808 -403.70082) (xy 398.686275 -403.654968)
			(xy 398.721968 -403.613775) (xy 398.76316 -403.578081) (xy 398.809012 -403.548613) (xy 398.858591 -403.52597)
			(xy 398.910887 -403.510613) (xy 398.964838 -403.502855) (xy 398.99209 -403.502368) (xy 399.85569 -403.502368)
			(xy 399.882942 -403.502879) (xy 399.93689 -403.510634) (xy 399.989186 -403.525988) (xy 400.038764 -403.548629)
			(xy 400.084616 -403.578095) (xy 400.125807 -403.613786) (xy 400.161499 -403.654976) (xy 400.190967 -403.700827)
			(xy 400.213608 -403.750405) (xy 400.228964 -403.8027) (xy 400.236721 -403.856648) (xy 400.236721 -403.911152)
			(xy 400.23672 -403.911156) (xy 401.674231 -403.911156) (xy 401.674231 -403.856644) (xy 401.681989 -403.802687)
			(xy 401.697348 -403.750383) (xy 401.719994 -403.700798) (xy 401.749467 -403.654941) (xy 401.785166 -403.613745)
			(xy 401.826365 -403.578049) (xy 401.872224 -403.54858) (xy 401.921812 -403.525937) (xy 401.974116 -403.510583)
			(xy 402.028074 -403.502829) (xy 402.05533 -403.502368) (xy 402.91893 -403.502368) (xy 402.946178 -403.502904)
			(xy 403.000119 -403.510664) (xy 403.052407 -403.52602) (xy 403.101977 -403.548662) (xy 403.147821 -403.578127)
			(xy 403.189005 -403.613816) (xy 403.224691 -403.655003) (xy 403.254153 -403.700849) (xy 403.27679 -403.750421)
			(xy 403.292143 -403.80271) (xy 403.299898 -403.856652) (xy 403.299898 -403.911148) (xy 403.299897 -403.911152)
			(xy 404.737554 -403.911152) (xy 404.737554 -403.856648) (xy 404.74531 -403.8027) (xy 404.760665 -403.750404)
			(xy 404.783305 -403.700826) (xy 404.81277 -403.654974) (xy 404.848461 -403.613782) (xy 404.88965 -403.578088)
			(xy 404.9355 -403.548619) (xy 404.985076 -403.525975) (xy 405.037371 -403.510616) (xy 405.091318 -403.502856)
			(xy 405.11857 -403.502368) (xy 405.98217 -403.502368) (xy 406.009423 -403.502877) (xy 406.063373 -403.51063)
			(xy 406.115671 -403.525983) (xy 406.165252 -403.548622) (xy 406.211106 -403.578087) (xy 406.2523 -403.613779)
			(xy 406.287995 -403.65497) (xy 406.317464 -403.700821) (xy 406.340107 -403.7504) (xy 406.355463 -403.802697)
			(xy 406.363221 -403.856647) (xy 406.363221 -403.911153) (xy 406.363221 -403.911155) (xy 407.800731 -403.911155)
			(xy 407.800731 -403.856645) (xy 407.808489 -403.80269) (xy 407.823846 -403.750388) (xy 407.846491 -403.700804)
			(xy 407.875962 -403.654947) (xy 407.911659 -403.613752) (xy 407.952855 -403.578056) (xy 407.998713 -403.548586)
			(xy 408.048297 -403.525943) (xy 408.100599 -403.510587) (xy 408.154555 -403.50283) (xy 408.18181 -403.502368)
			(xy 409.04541 -403.502368) (xy 409.072659 -403.502903) (xy 409.126602 -403.51066) (xy 409.178892 -403.526015)
			(xy 409.228465 -403.548655) (xy 409.274311 -403.57812) (xy 409.315498 -403.613809) (xy 409.351186 -403.654997)
			(xy 409.380649 -403.700844) (xy 409.403288 -403.750417) (xy 409.418642 -403.802708) (xy 409.426398 -403.856651)
			(xy 409.426398 -403.911149) (xy 409.426398 -403.911151) (xy 410.864054 -403.911151) (xy 410.864054 -403.856649)
			(xy 410.871809 -403.802703) (xy 410.887163 -403.750409) (xy 410.909802 -403.700832) (xy 410.939265 -403.654981)
			(xy 410.974954 -403.613789) (xy 411.016141 -403.578095) (xy 411.061988 -403.548626) (xy 411.111562 -403.52598)
			(xy 411.163854 -403.51062) (xy 411.217799 -403.502857) (xy 411.24505 -403.502368) (xy 412.10865 -403.502368)
			(xy 412.135903 -403.502876) (xy 412.189856 -403.510627) (xy 412.242157 -403.525977) (xy 412.29174 -403.548616)
			(xy 412.337597 -403.57808) (xy 412.378793 -403.613772) (xy 412.41449 -403.654963) (xy 412.44396 -403.700816)
			(xy 412.466605 -403.750396) (xy 412.481963 -403.802695) (xy 412.489721 -403.856647) (xy 412.489721 -403.911153)
			(xy 413.927254 -403.911153) (xy 413.927254 -403.856647) (xy 413.935011 -403.802697) (xy 413.950366 -403.7504)
			(xy 413.973008 -403.70082) (xy 414.002475 -403.654968) (xy 414.038168 -403.613775) (xy 414.07936 -403.578081)
			(xy 414.125212 -403.548613) (xy 414.174791 -403.52597) (xy 414.227087 -403.510613) (xy 414.281038 -403.502855)
			(xy 414.30829 -403.502368) (xy 415.17189 -403.502368) (xy 415.199142 -403.502879) (xy 415.25309 -403.510634)
			(xy 415.305386 -403.525988) (xy 415.354964 -403.548629) (xy 415.400816 -403.578095) (xy 415.442007 -403.613786)
			(xy 415.477699 -403.654976) (xy 415.507167 -403.700827) (xy 415.529808 -403.750405) (xy 415.545164 -403.8027)
			(xy 415.552921 -403.856648) (xy 415.552921 -403.911152) (xy 415.55292 -403.911156) (xy 416.990431 -403.911156)
			(xy 416.990431 -403.856644) (xy 416.998189 -403.802687) (xy 417.013548 -403.750383) (xy 417.036194 -403.700798)
			(xy 417.065667 -403.654941) (xy 417.101366 -403.613745) (xy 417.142565 -403.578049) (xy 417.188424 -403.54858)
			(xy 417.238012 -403.525937) (xy 417.290316 -403.510583) (xy 417.344274 -403.502829) (xy 417.37153 -403.502368)
			(xy 418.23513 -403.502368) (xy 418.262378 -403.502904) (xy 418.316319 -403.510664) (xy 418.368607 -403.52602)
			(xy 418.418177 -403.548662) (xy 418.464021 -403.578127) (xy 418.505205 -403.613816) (xy 418.540891 -403.655003)
			(xy 418.570353 -403.700849) (xy 418.59299 -403.750421) (xy 418.608343 -403.80271) (xy 418.616098 -403.856652)
			(xy 418.616098 -403.911148) (xy 418.608343 -403.96509) (xy 418.59299 -404.017379) (xy 418.570353 -404.066951)
			(xy 418.540891 -404.112797) (xy 418.505205 -404.153984) (xy 418.464021 -404.189673) (xy 418.418177 -404.219138)
			(xy 418.368607 -404.24178) (xy 418.316319 -404.257136) (xy 418.262378 -404.264896) (xy 418.23513 -404.265384)
			(xy 417.37153 -404.265384) (xy 417.344274 -404.264971) (xy 417.290316 -404.257217) (xy 417.238012 -404.241863)
			(xy 417.188424 -404.21922) (xy 417.142565 -404.189751) (xy 417.101366 -404.154055) (xy 417.065667 -404.112859)
			(xy 417.036194 -404.067002) (xy 417.013548 -404.017417) (xy 416.998189 -403.965113) (xy 416.990431 -403.911156)
			(xy 415.55292 -403.911156) (xy 415.545164 -403.9651) (xy 415.529808 -404.017395) (xy 415.507167 -404.066973)
			(xy 415.477699 -404.112824) (xy 415.442007 -404.154014) (xy 415.400816 -404.189705) (xy 415.354964 -404.219171)
			(xy 415.305386 -404.241812) (xy 415.25309 -404.257166) (xy 415.199142 -404.264921) (xy 415.17189 -404.265384)
			(xy 414.30829 -404.265384) (xy 414.281038 -404.264945) (xy 414.227087 -404.257187) (xy 414.174791 -404.24183)
			(xy 414.125212 -404.219187) (xy 414.07936 -404.189719) (xy 414.038168 -404.154025) (xy 414.002475 -404.112832)
			(xy 413.973008 -404.06698) (xy 413.950366 -404.0174) (xy 413.935011 -403.965103) (xy 413.927254 -403.911153)
			(xy 412.489721 -403.911153) (xy 412.481963 -403.965105) (xy 412.466605 -404.017404) (xy 412.44396 -404.066984)
			(xy 412.41449 -404.112837) (xy 412.378793 -404.154028) (xy 412.337597 -404.18972) (xy 412.29174 -404.219184)
			(xy 412.242157 -404.241823) (xy 412.189856 -404.257173) (xy 412.135903 -404.264924) (xy 412.10865 -404.265384)
			(xy 411.24505 -404.265384) (xy 411.217799 -404.264943) (xy 411.163854 -404.25718) (xy 411.111562 -404.24182)
			(xy 411.061988 -404.219174) (xy 411.016141 -404.189705) (xy 410.974954 -404.154011) (xy 410.939265 -404.112819)
			(xy 410.909802 -404.066968) (xy 410.887163 -404.017391) (xy 410.871809 -403.965097) (xy 410.864054 -403.911151)
			(xy 409.426398 -403.911151) (xy 409.418642 -403.965092) (xy 409.403288 -404.017383) (xy 409.380649 -404.066956)
			(xy 409.351186 -404.112803) (xy 409.315498 -404.153991) (xy 409.274311 -404.18968) (xy 409.228465 -404.219145)
			(xy 409.178892 -404.241785) (xy 409.126602 -404.25714) (xy 409.072659 -404.264897) (xy 409.04541 -404.265384)
			(xy 408.18181 -404.265384) (xy 408.154555 -404.26497) (xy 408.100599 -404.257213) (xy 408.048297 -404.241857)
			(xy 407.998713 -404.219214) (xy 407.952855 -404.189744) (xy 407.911659 -404.154048) (xy 407.875962 -404.112853)
			(xy 407.846491 -404.066996) (xy 407.823846 -404.017412) (xy 407.808489 -403.96511) (xy 407.800731 -403.911155)
			(xy 406.363221 -403.911155) (xy 406.355463 -403.965103) (xy 406.340107 -404.0174) (xy 406.317464 -404.066979)
			(xy 406.287995 -404.11283) (xy 406.2523 -404.154021) (xy 406.211106 -404.189713) (xy 406.165252 -404.219178)
			(xy 406.115671 -404.241817) (xy 406.063373 -404.25717) (xy 406.009423 -404.264923) (xy 405.98217 -404.265384)
			(xy 405.11857 -404.265384) (xy 405.091318 -404.264944) (xy 405.037371 -404.257184) (xy 404.985076 -404.241825)
			(xy 404.9355 -404.219181) (xy 404.88965 -404.189712) (xy 404.848461 -404.154018) (xy 404.81277 -404.112826)
			(xy 404.783305 -404.066974) (xy 404.760665 -404.017396) (xy 404.74531 -403.9651) (xy 404.737554 -403.911152)
			(xy 403.299897 -403.911152) (xy 403.292143 -403.96509) (xy 403.27679 -404.017379) (xy 403.254153 -404.066951)
			(xy 403.224691 -404.112797) (xy 403.189005 -404.153984) (xy 403.147821 -404.189673) (xy 403.101977 -404.219138)
			(xy 403.052407 -404.24178) (xy 403.000119 -404.257136) (xy 402.946178 -404.264896) (xy 402.91893 -404.265384)
			(xy 402.05533 -404.265384) (xy 402.028074 -404.264971) (xy 401.974116 -404.257217) (xy 401.921812 -404.241863)
			(xy 401.872224 -404.21922) (xy 401.826365 -404.189751) (xy 401.785166 -404.154055) (xy 401.749467 -404.112859)
			(xy 401.719994 -404.067002) (xy 401.697348 -404.017417) (xy 401.681989 -403.965113) (xy 401.674231 -403.911156)
			(xy 400.23672 -403.911156) (xy 400.228964 -403.9651) (xy 400.213608 -404.017395) (xy 400.190967 -404.066973)
			(xy 400.161499 -404.112824) (xy 400.125807 -404.154014) (xy 400.084616 -404.189705) (xy 400.038764 -404.219171)
			(xy 399.989186 -404.241812) (xy 399.93689 -404.257166) (xy 399.882942 -404.264921) (xy 399.85569 -404.265384)
			(xy 398.99209 -404.265384) (xy 398.964838 -404.264945) (xy 398.910887 -404.257187) (xy 398.858591 -404.24183)
			(xy 398.809012 -404.219187) (xy 398.76316 -404.189719) (xy 398.721968 -404.154025) (xy 398.686275 -404.112832)
			(xy 398.656808 -404.06698) (xy 398.634166 -404.0174) (xy 398.618811 -403.965103) (xy 398.611054 -403.911153)
			(xy 397.173521 -403.911153) (xy 397.165763 -403.965105) (xy 397.150405 -404.017404) (xy 397.12776 -404.066984)
			(xy 397.09829 -404.112837) (xy 397.062593 -404.154028) (xy 397.021397 -404.18972) (xy 396.97554 -404.219184)
			(xy 396.925957 -404.241823) (xy 396.873656 -404.257173) (xy 396.819703 -404.264924) (xy 396.79245 -404.265384)
			(xy 395.92885 -404.265384) (xy 395.901599 -404.264943) (xy 395.847654 -404.25718) (xy 395.795362 -404.24182)
			(xy 395.745788 -404.219174) (xy 395.699941 -404.189705) (xy 395.658754 -404.154011) (xy 395.623065 -404.112819)
			(xy 395.593602 -404.066968) (xy 395.570963 -404.017391) (xy 395.555609 -403.965097) (xy 395.547854 -403.911151)
			(xy 394.110198 -403.911151) (xy 394.102442 -403.965092) (xy 394.087088 -404.017383) (xy 394.064449 -404.066956)
			(xy 394.034986 -404.112803) (xy 393.999298 -404.153991) (xy 393.958111 -404.18968) (xy 393.912265 -404.219145)
			(xy 393.862692 -404.241785) (xy 393.810402 -404.25714) (xy 393.756459 -404.264897) (xy 393.72921 -404.265384)
			(xy 392.86561 -404.265384) (xy 392.838355 -404.26497) (xy 392.784399 -404.257213) (xy 392.732097 -404.241857)
			(xy 392.682513 -404.219214) (xy 392.636655 -404.189744) (xy 392.595459 -404.154048) (xy 392.559762 -404.112853)
			(xy 392.530291 -404.066996) (xy 392.507646 -404.017412) (xy 392.492289 -403.96511) (xy 392.484531 -403.911155)
			(xy 391.047021 -403.911155) (xy 391.039263 -403.965103) (xy 391.023907 -404.0174) (xy 391.001264 -404.066979)
			(xy 390.971795 -404.11283) (xy 390.9361 -404.154021) (xy 390.894906 -404.189713) (xy 390.849052 -404.219178)
			(xy 390.799471 -404.241817) (xy 390.747173 -404.25717) (xy 390.693223 -404.264923) (xy 390.66597 -404.265384)
			(xy 389.80237 -404.265384) (xy 389.775118 -404.264944) (xy 389.721171 -404.257184) (xy 389.668876 -404.241825)
			(xy 389.6193 -404.219181) (xy 389.57345 -404.189712) (xy 389.532261 -404.154018) (xy 389.49657 -404.112826)
			(xy 389.467105 -404.066974) (xy 389.444465 -404.017396) (xy 389.42911 -403.9651) (xy 389.421354 -403.911152)
			(xy 387.983697 -403.911152) (xy 387.975943 -403.96509) (xy 387.96059 -404.017379) (xy 387.937953 -404.066951)
			(xy 387.908491 -404.112797) (xy 387.872805 -404.153984) (xy 387.831621 -404.189673) (xy 387.785777 -404.219138)
			(xy 387.736207 -404.24178) (xy 387.683919 -404.257136) (xy 387.629978 -404.264896) (xy 387.60273 -404.265384)
			(xy 386.73913 -404.265384) (xy 386.711874 -404.264971) (xy 386.657916 -404.257217) (xy 386.605612 -404.241863)
			(xy 386.556024 -404.21922) (xy 386.510165 -404.189751) (xy 386.468966 -404.154055) (xy 386.433267 -404.112859)
			(xy 386.403794 -404.067002) (xy 386.381148 -404.017417) (xy 386.365789 -403.965113) (xy 386.358031 -403.911156)
			(xy 384.92052 -403.911156) (xy 384.912764 -403.9651) (xy 384.897408 -404.017395) (xy 384.874767 -404.066973)
			(xy 384.845299 -404.112824) (xy 384.809607 -404.154014) (xy 384.768416 -404.189705) (xy 384.722564 -404.219171)
			(xy 384.672986 -404.241812) (xy 384.62069 -404.257166) (xy 384.566742 -404.264921) (xy 384.53949 -404.265384)
			(xy 383.67589 -404.265384) (xy 383.648638 -404.264945) (xy 383.594687 -404.257187) (xy 383.542391 -404.24183)
			(xy 383.492812 -404.219187) (xy 383.44696 -404.189719) (xy 383.405768 -404.154025) (xy 383.370075 -404.112832)
			(xy 383.340608 -404.06698) (xy 383.317966 -404.0174) (xy 383.302611 -403.965103) (xy 383.294854 -403.911153)
			(xy 381.857321 -403.911153) (xy 381.849563 -403.965105) (xy 381.834205 -404.017404) (xy 381.81156 -404.066984)
			(xy 381.78209 -404.112837) (xy 381.746393 -404.154028) (xy 381.705197 -404.18972) (xy 381.65934 -404.219184)
			(xy 381.609757 -404.241823) (xy 381.557456 -404.257173) (xy 381.503503 -404.264924) (xy 381.47625 -404.265384)
			(xy 380.61265 -404.265384) (xy 380.585399 -404.264943) (xy 380.531454 -404.25718) (xy 380.479162 -404.24182)
			(xy 380.429588 -404.219174) (xy 380.383741 -404.189705) (xy 380.342554 -404.154011) (xy 380.306865 -404.112819)
			(xy 380.277402 -404.066968) (xy 380.254763 -404.017391) (xy 380.239409 -403.965097) (xy 380.231654 -403.911151)
			(xy 378.793998 -403.911151) (xy 378.786242 -403.965092) (xy 378.770888 -404.017383) (xy 378.748249 -404.066956)
			(xy 378.718786 -404.112803) (xy 378.683098 -404.153991) (xy 378.641911 -404.18968) (xy 378.596065 -404.219145)
			(xy 378.546492 -404.241785) (xy 378.494202 -404.25714) (xy 378.440259 -404.264897) (xy 378.41301 -404.265384)
			(xy 377.54941 -404.265384) (xy 377.522155 -404.26497) (xy 377.468199 -404.257213) (xy 377.415897 -404.241857)
			(xy 377.366313 -404.219214) (xy 377.320455 -404.189744) (xy 377.279259 -404.154048) (xy 377.243562 -404.112853)
			(xy 377.214091 -404.066996) (xy 377.191446 -404.017412) (xy 377.176089 -403.96511) (xy 377.168331 -403.911155)
			(xy 375.730821 -403.911155) (xy 375.723063 -403.965103) (xy 375.707707 -404.0174) (xy 375.685064 -404.066979)
			(xy 375.655595 -404.11283) (xy 375.6199 -404.154021) (xy 375.578706 -404.189713) (xy 375.532852 -404.219178)
			(xy 375.483271 -404.241817) (xy 375.430973 -404.25717) (xy 375.377023 -404.264923) (xy 375.34977 -404.265384)
			(xy 374.48617 -404.265384) (xy 374.458918 -404.264944) (xy 374.404971 -404.257184) (xy 374.352676 -404.241825)
			(xy 374.3031 -404.219181) (xy 374.25725 -404.189712) (xy 374.216061 -404.154018) (xy 374.18037 -404.112826)
			(xy 374.150905 -404.066974) (xy 374.128265 -404.017396) (xy 374.11291 -403.9651) (xy 374.105154 -403.911152)
			(xy 372.667497 -403.911152) (xy 372.659743 -403.96509) (xy 372.64439 -404.017379) (xy 372.621753 -404.066951)
			(xy 372.592291 -404.112797) (xy 372.556605 -404.153984) (xy 372.515421 -404.189673) (xy 372.469577 -404.219138)
			(xy 372.420007 -404.24178) (xy 372.367719 -404.257136) (xy 372.313778 -404.264896) (xy 372.28653 -404.265384)
			(xy 371.42293 -404.265384) (xy 371.395674 -404.264971) (xy 371.341716 -404.257217) (xy 371.289412 -404.241863)
			(xy 371.239824 -404.21922) (xy 371.193965 -404.189751) (xy 371.152766 -404.154055) (xy 371.117067 -404.112859)
			(xy 371.087594 -404.067002) (xy 371.064948 -404.017417) (xy 371.049589 -403.965113) (xy 371.041831 -403.911156)
			(xy 351.17332 -403.911156) (xy 351.165564 -403.9651) (xy 351.150208 -404.017396) (xy 351.127566 -404.066974)
			(xy 351.098099 -404.112824) (xy 351.062406 -404.154015) (xy 351.021215 -404.189706) (xy 350.975363 -404.219172)
			(xy 350.925785 -404.241812) (xy 350.873489 -404.257166) (xy 350.81954 -404.264922) (xy 350.792288 -404.265384)
			(xy 349.928688 -404.265384) (xy 349.901436 -404.264945) (xy 349.847486 -404.257187) (xy 349.795189 -404.24183)
			(xy 349.74561 -404.219187) (xy 349.699759 -404.189718) (xy 349.658567 -404.154024) (xy 349.622875 -404.112832)
			(xy 349.593408 -404.066979) (xy 349.570766 -404.0174) (xy 349.55541 -403.965102) (xy 349.547654 -403.911152)
			(xy 348.109997 -403.911152) (xy 348.102243 -403.965087) (xy 348.086891 -404.017375) (xy 348.064255 -404.066946)
			(xy 348.034795 -404.112791) (xy 347.999111 -404.153977) (xy 347.957929 -404.189667) (xy 347.912088 -404.219132)
			(xy 347.86252 -404.241775) (xy 347.810234 -404.257133) (xy 347.756295 -404.264895) (xy 347.729048 -404.265384)
			(xy 346.865448 -404.265384) (xy 346.838191 -404.264972) (xy 346.784232 -404.25722) (xy 346.731925 -404.241868)
			(xy 346.682335 -404.219226) (xy 346.636473 -404.189758) (xy 346.595272 -404.154062) (xy 346.559571 -404.112865)
			(xy 346.530097 -404.067007) (xy 346.507449 -404.01742) (xy 346.49209 -403.965115) (xy 346.484331 -403.911157)
			(xy 345.046797 -403.911157) (xy 345.039042 -403.965093) (xy 345.023688 -404.017383) (xy 345.001049 -404.066957)
			(xy 344.971586 -404.112804) (xy 344.935897 -404.153991) (xy 344.89471 -404.189681) (xy 344.848864 -404.219145)
			(xy 344.799291 -404.241785) (xy 344.747001 -404.25714) (xy 344.693057 -404.264897) (xy 344.665808 -404.265384)
			(xy 343.802208 -404.265384) (xy 343.774953 -404.26497) (xy 343.720998 -404.257213) (xy 343.668696 -404.241857)
			(xy 343.619111 -404.219213) (xy 343.573254 -404.189744) (xy 343.532058 -404.154048) (xy 343.496361 -404.112852)
			(xy 343.466891 -404.066996) (xy 343.444246 -404.017412) (xy 343.428889 -403.96511) (xy 343.421131 -403.911155)
			(xy 341.983621 -403.911155) (xy 341.975863 -403.965103) (xy 341.960507 -404.0174) (xy 341.937863 -404.066979)
			(xy 341.908394 -404.112831) (xy 341.872699 -404.154022) (xy 341.831505 -404.189713) (xy 341.785651 -404.219179)
			(xy 341.73607 -404.241818) (xy 341.683772 -404.25717) (xy 341.629821 -404.264923) (xy 341.602568 -404.265384)
			(xy 340.738968 -404.265384) (xy 340.711717 -404.264944) (xy 340.657769 -404.257183) (xy 340.605475 -404.241824)
			(xy 340.555898 -404.21918) (xy 340.510049 -404.189711) (xy 340.46886 -404.154017) (xy 340.43317 -404.112825)
			(xy 340.403705 -404.066974) (xy 340.381064 -404.017395) (xy 340.36571 -403.9651) (xy 340.357954 -403.911152)
			(xy 338.920297 -403.911152) (xy 338.912543 -403.96509) (xy 338.89719 -404.017379) (xy 338.874552 -404.066951)
			(xy 338.84509 -404.112798) (xy 338.809404 -404.153984) (xy 338.76822 -404.189674) (xy 338.722376 -404.219139)
			(xy 338.672805 -404.24178) (xy 338.620517 -404.257137) (xy 338.566576 -404.264896) (xy 338.539328 -404.265384)
			(xy 337.675728 -404.265384) (xy 337.648472 -404.264971) (xy 337.594515 -404.257217) (xy 337.54221 -404.241862)
			(xy 337.492623 -404.21922) (xy 337.446764 -404.189751) (xy 337.405565 -404.154055) (xy 337.369866 -404.112859)
			(xy 337.340394 -404.067001) (xy 337.317748 -404.017416) (xy 337.302389 -403.965113) (xy 337.294631 -403.911156)
			(xy 335.85712 -403.911156) (xy 335.849364 -403.9651) (xy 335.834008 -404.017396) (xy 335.811366 -404.066974)
			(xy 335.781899 -404.112824) (xy 335.746206 -404.154015) (xy 335.705015 -404.189706) (xy 335.659163 -404.219172)
			(xy 335.609585 -404.241812) (xy 335.557289 -404.257166) (xy 335.50334 -404.264922) (xy 335.476088 -404.265384)
			(xy 334.612488 -404.265384) (xy 334.585236 -404.264945) (xy 334.531286 -404.257187) (xy 334.478989 -404.24183)
			(xy 334.42941 -404.219187) (xy 334.383559 -404.189718) (xy 334.342367 -404.154024) (xy 334.306675 -404.112832)
			(xy 334.277208 -404.066979) (xy 334.254566 -404.0174) (xy 334.23921 -403.965102) (xy 334.231454 -403.911152)
			(xy 332.793797 -403.911152) (xy 332.786043 -403.965087) (xy 332.770691 -404.017375) (xy 332.748055 -404.066946)
			(xy 332.718595 -404.112791) (xy 332.682911 -404.153977) (xy 332.641729 -404.189667) (xy 332.595888 -404.219132)
			(xy 332.54632 -404.241775) (xy 332.494034 -404.257133) (xy 332.440095 -404.264895) (xy 332.412848 -404.265384)
			(xy 331.549248 -404.265384) (xy 331.521991 -404.264972) (xy 331.468032 -404.25722) (xy 331.415725 -404.241868)
			(xy 331.366135 -404.219226) (xy 331.320273 -404.189758) (xy 331.279072 -404.154062) (xy 331.243371 -404.112865)
			(xy 331.213897 -404.067007) (xy 331.191249 -404.01742) (xy 331.17589 -403.965115) (xy 331.168131 -403.911157)
			(xy 329.730597 -403.911157) (xy 329.722842 -403.965093) (xy 329.707488 -404.017383) (xy 329.684849 -404.066957)
			(xy 329.655386 -404.112804) (xy 329.619697 -404.153991) (xy 329.57851 -404.189681) (xy 329.532664 -404.219145)
			(xy 329.483091 -404.241785) (xy 329.430801 -404.25714) (xy 329.376857 -404.264897) (xy 329.349608 -404.265384)
			(xy 328.486008 -404.265384) (xy 328.458753 -404.26497) (xy 328.404798 -404.257213) (xy 328.352496 -404.241857)
			(xy 328.302911 -404.219213) (xy 328.257054 -404.189744) (xy 328.215858 -404.154048) (xy 328.180161 -404.112852)
			(xy 328.150691 -404.066996) (xy 328.128046 -404.017412) (xy 328.112689 -403.96511) (xy 328.104931 -403.911155)
			(xy 326.667421 -403.911155) (xy 326.659663 -403.965103) (xy 326.644307 -404.0174) (xy 326.621663 -404.066979)
			(xy 326.592194 -404.112831) (xy 326.556499 -404.154022) (xy 326.515305 -404.189713) (xy 326.469451 -404.219179)
			(xy 326.41987 -404.241818) (xy 326.367572 -404.25717) (xy 326.313621 -404.264923) (xy 326.286368 -404.265384)
			(xy 325.422768 -404.265384) (xy 325.395517 -404.264944) (xy 325.341569 -404.257183) (xy 325.289275 -404.241824)
			(xy 325.239698 -404.21918) (xy 325.193849 -404.189711) (xy 325.15266 -404.154017) (xy 325.11697 -404.112825)
			(xy 325.087505 -404.066974) (xy 325.064864 -404.017395) (xy 325.04951 -403.9651) (xy 325.041754 -403.911152)
			(xy 323.604097 -403.911152) (xy 323.596343 -403.96509) (xy 323.58099 -404.017379) (xy 323.558352 -404.066951)
			(xy 323.52889 -404.112798) (xy 323.493204 -404.153984) (xy 323.45202 -404.189674) (xy 323.406176 -404.219139)
			(xy 323.356605 -404.24178) (xy 323.304317 -404.257137) (xy 323.250376 -404.264896) (xy 323.223128 -404.265384)
			(xy 322.359528 -404.265384) (xy 322.332272 -404.264971) (xy 322.278315 -404.257217) (xy 322.22601 -404.241862)
			(xy 322.176423 -404.21922) (xy 322.130564 -404.189751) (xy 322.089365 -404.154055) (xy 322.053666 -404.112859)
			(xy 322.024194 -404.067001) (xy 322.001548 -404.017416) (xy 321.986189 -403.965113) (xy 321.978431 -403.911156)
			(xy 320.54092 -403.911156) (xy 320.533164 -403.9651) (xy 320.517808 -404.017396) (xy 320.495166 -404.066974)
			(xy 320.465699 -404.112824) (xy 320.430006 -404.154015) (xy 320.388815 -404.189706) (xy 320.342963 -404.219172)
			(xy 320.293385 -404.241812) (xy 320.241089 -404.257166) (xy 320.18714 -404.264922) (xy 320.159888 -404.265384)
			(xy 319.296288 -404.265384) (xy 319.269036 -404.264945) (xy 319.215086 -404.257187) (xy 319.162789 -404.24183)
			(xy 319.11321 -404.219187) (xy 319.067359 -404.189718) (xy 319.026167 -404.154024) (xy 318.990475 -404.112832)
			(xy 318.961008 -404.066979) (xy 318.938366 -404.0174) (xy 318.92301 -403.965102) (xy 318.915254 -403.911152)
			(xy 317.477597 -403.911152) (xy 317.469843 -403.965087) (xy 317.454491 -404.017375) (xy 317.431855 -404.066946)
			(xy 317.402395 -404.112791) (xy 317.366711 -404.153977) (xy 317.325529 -404.189667) (xy 317.279688 -404.219132)
			(xy 317.23012 -404.241775) (xy 317.177834 -404.257133) (xy 317.123895 -404.264895) (xy 317.096648 -404.265384)
			(xy 316.233048 -404.265384) (xy 316.205791 -404.264972) (xy 316.151832 -404.25722) (xy 316.099525 -404.241868)
			(xy 316.049935 -404.219226) (xy 316.004073 -404.189758) (xy 315.962872 -404.154062) (xy 315.927171 -404.112865)
			(xy 315.897697 -404.067007) (xy 315.875049 -404.01742) (xy 315.85969 -403.965115) (xy 315.851931 -403.911157)
			(xy 314.414397 -403.911157) (xy 314.406642 -403.965093) (xy 314.391288 -404.017383) (xy 314.368649 -404.066957)
			(xy 314.339186 -404.112804) (xy 314.303497 -404.153991) (xy 314.26231 -404.189681) (xy 314.216464 -404.219145)
			(xy 314.166891 -404.241785) (xy 314.114601 -404.25714) (xy 314.060657 -404.264897) (xy 314.033408 -404.265384)
			(xy 313.169808 -404.265384) (xy 313.142553 -404.26497) (xy 313.088598 -404.257213) (xy 313.036296 -404.241857)
			(xy 312.986711 -404.219213) (xy 312.940854 -404.189744) (xy 312.899658 -404.154048) (xy 312.863961 -404.112852)
			(xy 312.834491 -404.066996) (xy 312.811846 -404.017412) (xy 312.796489 -403.96511) (xy 312.788731 -403.911155)
			(xy 311.351221 -403.911155) (xy 311.343463 -403.965103) (xy 311.328107 -404.0174) (xy 311.305463 -404.066979)
			(xy 311.275994 -404.112831) (xy 311.240299 -404.154022) (xy 311.199105 -404.189713) (xy 311.153251 -404.219179)
			(xy 311.10367 -404.241818) (xy 311.051372 -404.25717) (xy 310.997421 -404.264923) (xy 310.970168 -404.265384)
			(xy 310.106568 -404.265384) (xy 310.079317 -404.264944) (xy 310.025369 -404.257183) (xy 309.973075 -404.241824)
			(xy 309.923498 -404.21918) (xy 309.877649 -404.189711) (xy 309.83646 -404.154017) (xy 309.80077 -404.112825)
			(xy 309.771305 -404.066974) (xy 309.748664 -404.017395) (xy 309.73331 -403.9651) (xy 309.725554 -403.911152)
			(xy 308.287897 -403.911152) (xy 308.280143 -403.96509) (xy 308.26479 -404.017379) (xy 308.242152 -404.066951)
			(xy 308.21269 -404.112798) (xy 308.177004 -404.153984) (xy 308.13582 -404.189674) (xy 308.089976 -404.219139)
			(xy 308.040405 -404.24178) (xy 307.988117 -404.257137) (xy 307.934176 -404.264896) (xy 307.906928 -404.265384)
			(xy 307.043328 -404.265384) (xy 307.016072 -404.264971) (xy 306.962115 -404.257217) (xy 306.90981 -404.241862)
			(xy 306.860223 -404.21922) (xy 306.814364 -404.189751) (xy 306.773165 -404.154055) (xy 306.737466 -404.112859)
			(xy 306.707994 -404.067001) (xy 306.685348 -404.017416) (xy 306.669989 -403.965113) (xy 306.662231 -403.911156)
			(xy 305.22472 -403.911156) (xy 305.216964 -403.9651) (xy 305.201608 -404.017396) (xy 305.178966 -404.066974)
			(xy 305.149499 -404.112824) (xy 305.113806 -404.154015) (xy 305.072615 -404.189706) (xy 305.026763 -404.219172)
			(xy 304.977185 -404.241812) (xy 304.924889 -404.257166) (xy 304.87094 -404.264922) (xy 304.843688 -404.265384)
			(xy 303.980088 -404.265384) (xy 303.952836 -404.264945) (xy 303.898886 -404.257187) (xy 303.846589 -404.24183)
			(xy 303.79701 -404.219187) (xy 303.751159 -404.189718) (xy 303.709967 -404.154024) (xy 303.674275 -404.112832)
			(xy 303.644808 -404.066979) (xy 303.622166 -404.0174) (xy 303.60681 -403.965102) (xy 303.599054 -403.911152)
			(xy 298.836897 -403.911152) (xy 298.840074 -403.920931) (xy 298.852049 -403.983712) (xy 298.856063 -404.0475)
			(xy 298.852049 -404.111288) (xy 298.840074 -404.174069) (xy 298.820324 -404.234855) (xy 298.793112 -404.292686)
			(xy 298.758866 -404.346651) (xy 298.718128 -404.395898) (xy 298.671538 -404.439652) (xy 298.619832 -404.477221)
			(xy 298.563825 -404.508014) (xy 298.504401 -404.531545) (xy 298.442496 -404.547442) (xy 298.379087 -404.555456)
			(xy 298.34713 -404.55596) (xy 298.346876 -404.55596) (xy 298.315131 -404.555422) (xy 298.252136 -404.547497)
			(xy 298.190616 -404.531797) (xy 298.131527 -404.508566) (xy 298.075787 -404.478166) (xy 298.024261 -404.441069)
			(xy 298.000674 -404.419816) (xy 297.993411 -404.413632) (xy 297.975661 -404.406681) (xy 297.956599 -404.406681)
			(xy 297.938849 -404.413632) (xy 297.931586 -404.419816) (xy 297.908028 -404.441107) (xy 297.856512 -404.478235)
			(xy 297.800771 -404.508654) (xy 297.741674 -404.531889) (xy 297.680142 -404.547579) (xy 297.617135 -404.555478)
			(xy 297.585384 -404.55596) (xy 297.58513 -404.55596) (xy 297.553163 -404.555577) (xy 297.489734 -404.547567)
			(xy 297.427809 -404.531671) (xy 297.368364 -404.508138) (xy 297.312338 -404.47734) (xy 297.260613 -404.439763)
			(xy 297.214007 -404.395999) (xy 297.173253 -404.346739) (xy 297.138995 -404.292759) (xy 297.111773 -404.234911)
			(xy 297.092015 -404.174108) (xy 297.080035 -404.111307) (xy 297.07602 -404.0475) (xy 296.316063 -404.0475)
			(xy 296.312049 -404.111288) (xy 296.300074 -404.174069) (xy 296.280324 -404.234855) (xy 296.253112 -404.292686)
			(xy 296.218866 -404.346651) (xy 296.178128 -404.395898) (xy 296.131538 -404.439652) (xy 296.079832 -404.477221)
			(xy 296.023825 -404.508014) (xy 295.964401 -404.531545) (xy 295.902496 -404.547442) (xy 295.839087 -404.555456)
			(xy 295.80713 -404.55596) (xy 295.806876 -404.55596) (xy 295.775131 -404.555422) (xy 295.712136 -404.547497)
			(xy 295.650616 -404.531797) (xy 295.591527 -404.508566) (xy 295.535787 -404.478166) (xy 295.484261 -404.441069)
			(xy 295.460674 -404.419816) (xy 295.453411 -404.413632) (xy 295.435661 -404.406681) (xy 295.416599 -404.406681)
			(xy 295.398849 -404.413632) (xy 295.391586 -404.419816) (xy 295.368028 -404.441107) (xy 295.316512 -404.478235)
			(xy 295.260771 -404.508654) (xy 295.201674 -404.531889) (xy 295.140142 -404.547579) (xy 295.077135 -404.555478)
			(xy 295.045384 -404.55596) (xy 295.04513 -404.55596) (xy 295.013163 -404.555577) (xy 294.949734 -404.547567)
			(xy 294.887809 -404.531671) (xy 294.828364 -404.508138) (xy 294.772338 -404.47734) (xy 294.720613 -404.439763)
			(xy 294.674007 -404.395999) (xy 294.633253 -404.346739) (xy 294.598995 -404.292759) (xy 294.571773 -404.234911)
			(xy 294.552015 -404.174108) (xy 294.540035 -404.111307) (xy 294.53602 -404.0475) (xy 293.926484 -404.0475)
			(xy 293.92247 -404.111293) (xy 293.910493 -404.174079) (xy 293.890741 -404.23487) (xy 293.863525 -404.292705)
			(xy 293.829276 -404.346674) (xy 293.788532 -404.395924) (xy 293.741937 -404.439679) (xy 293.690226 -404.47725)
			(xy 293.634213 -404.508043) (xy 293.574783 -404.531573) (xy 293.512872 -404.547468) (xy 293.449457 -404.555479)
			(xy 293.417498 -404.55596) (xy 293.417244 -404.55596) (xy 293.385498 -404.555442) (xy 293.322502 -404.547512)
			(xy 293.260982 -404.531809) (xy 293.201894 -404.508575) (xy 293.146154 -404.478171) (xy 293.094629 -404.44107)
			(xy 293.071042 -404.419816) (xy 293.063779 -404.413632) (xy 293.046029 -404.406681) (xy 293.026967 -404.406681)
			(xy 293.009217 -404.413632) (xy 293.001954 -404.419816) (xy 292.978367 -404.441074) (xy 292.926858 -404.478206)
			(xy 292.871123 -404.50863) (xy 292.812032 -404.531871) (xy 292.750504 -404.547567) (xy 292.687501 -404.555474)
			(xy 292.655752 -404.55596) (xy 292.655498 -404.55596) (xy 292.623534 -404.555554) (xy 292.56011 -404.547542)
			(xy 292.498191 -404.531643) (xy 292.438752 -404.50811) (xy 292.382731 -404.477312) (xy 292.331013 -404.439736)
			(xy 292.284411 -404.395974) (xy 292.243662 -404.346717) (xy 292.209408 -404.29274) (xy 292.182189 -404.234897)
			(xy 292.162434 -404.174098) (xy 292.150455 -404.111302) (xy 292.146441 -404.0475) (xy 291.386484 -404.0475)
			(xy 291.38247 -404.111293) (xy 291.370493 -404.174079) (xy 291.350741 -404.23487) (xy 291.323525 -404.292705)
			(xy 291.289276 -404.346674) (xy 291.248532 -404.395924) (xy 291.201937 -404.439679) (xy 291.150226 -404.47725)
			(xy 291.094213 -404.508043) (xy 291.034783 -404.531573) (xy 290.972872 -404.547468) (xy 290.909457 -404.555479)
			(xy 290.877498 -404.55596) (xy 290.877244 -404.55596) (xy 290.845498 -404.555442) (xy 290.782502 -404.547512)
			(xy 290.720982 -404.531809) (xy 290.661894 -404.508575) (xy 290.606154 -404.478171) (xy 290.554629 -404.44107)
			(xy 290.531042 -404.419816) (xy 290.523779 -404.413632) (xy 290.506029 -404.406681) (xy 290.486967 -404.406681)
			(xy 290.469217 -404.413632) (xy 290.461954 -404.419816) (xy 290.438367 -404.441074) (xy 290.386858 -404.478206)
			(xy 290.331123 -404.50863) (xy 290.272032 -404.531871) (xy 290.210504 -404.547567) (xy 290.147501 -404.555474)
			(xy 290.115752 -404.55596) (xy 290.115498 -404.55596) (xy 290.083534 -404.555554) (xy 290.02011 -404.547542)
			(xy 289.958191 -404.531643) (xy 289.898752 -404.50811) (xy 289.842731 -404.477312) (xy 289.791013 -404.439736)
			(xy 289.744411 -404.395974) (xy 289.703662 -404.346717) (xy 289.669408 -404.29274) (xy 289.642189 -404.234897)
			(xy 289.622434 -404.174098) (xy 289.610455 -404.111302) (xy 289.606441 -404.0475) (xy 288.846484 -404.0475)
			(xy 288.84247 -404.111293) (xy 288.830493 -404.174079) (xy 288.810741 -404.23487) (xy 288.783525 -404.292705)
			(xy 288.749276 -404.346674) (xy 288.708532 -404.395924) (xy 288.661937 -404.439679) (xy 288.610226 -404.47725)
			(xy 288.554213 -404.508043) (xy 288.494783 -404.531573) (xy 288.432872 -404.547468) (xy 288.369457 -404.555479)
			(xy 288.337498 -404.55596) (xy 288.337244 -404.55596) (xy 288.305498 -404.555442) (xy 288.242502 -404.547512)
			(xy 288.180982 -404.531809) (xy 288.121894 -404.508575) (xy 288.066154 -404.478171) (xy 288.014629 -404.44107)
			(xy 287.991042 -404.419816) (xy 287.983779 -404.413632) (xy 287.966029 -404.406681) (xy 287.946967 -404.406681)
			(xy 287.929217 -404.413632) (xy 287.921954 -404.419816) (xy 287.898367 -404.441074) (xy 287.846858 -404.478206)
			(xy 287.791123 -404.50863) (xy 287.732032 -404.531871) (xy 287.670504 -404.547567) (xy 287.607501 -404.555474)
			(xy 287.575752 -404.55596) (xy 287.575498 -404.55596) (xy 287.543534 -404.555554) (xy 287.48011 -404.547542)
			(xy 287.418191 -404.531643) (xy 287.358752 -404.50811) (xy 287.302731 -404.477312) (xy 287.251013 -404.439736)
			(xy 287.204411 -404.395974) (xy 287.163662 -404.346717) (xy 287.129408 -404.29274) (xy 287.102189 -404.234897)
			(xy 287.082434 -404.174098) (xy 287.070455 -404.111302) (xy 287.066441 -404.0475) (xy 281.686508 -404.0475)
			(xy 281.686508 -405.908764) (xy 281.686046 -405.933715) (xy 281.678225 -405.982999) (xy 281.6628 -406.030457)
			(xy 281.64015 -406.074922) (xy 281.610832 -406.115303) (xy 281.593544 -406.1333) (xy 281.262328 -406.464516)
			(xy 281.244327 -406.4818) (xy 281.203952 -406.511124) (xy 281.159488 -406.533773) (xy 281.112029 -406.549188)
			(xy 281.062742 -406.556992) (xy 281.037792 -406.55748) (xy 278.18334 -406.55748) (xy 278.180546 -406.557734)
			(xy 278.171247 -406.558785) (xy 278.152566 -406.559928) (xy 278.143208 -406.56002) (xy 275.351748 -406.56002)
			(xy 275.326798 -406.559547) (xy 275.277514 -406.551728) (xy 275.230056 -406.536305) (xy 275.185591 -406.513658)
			(xy 275.145209 -406.484343) (xy 275.127212 -406.467056) (xy 275.08835 -406.428194) (xy 275.077488 -406.4181)
			(xy 275.051415 -406.404014) (xy 275.022395 -406.398003) (xy 274.992872 -406.400573) (xy 274.965328 -406.411507)
			(xy 274.94208 -406.429886) (xy 274.925085 -406.454164) (xy 274.919948 -406.468072) (xy 274.906846 -406.505801)
			(xy 274.873042 -406.578165) (xy 274.831055 -406.646108) (xy 274.781453 -406.70871) (xy 274.753578 -406.737312)
			(xy 274.459335 -407.031749) (xy 304.945298 -407.031749) (xy 304.945298 -406.977251) (xy 304.953054 -406.923307)
			(xy 304.968408 -406.871016) (xy 304.991047 -406.821442) (xy 305.02051 -406.775595) (xy 305.056199 -406.734407)
			(xy 305.097385 -406.698718) (xy 305.143232 -406.669252) (xy 305.192805 -406.646612) (xy 305.245095 -406.631257)
			(xy 305.299039 -406.623499) (xy 305.326288 -406.623012) (xy 306.189888 -406.623012) (xy 306.217143 -406.623434)
			(xy 306.271098 -406.63119) (xy 306.3234 -406.646546) (xy 306.372984 -406.669189) (xy 306.418841 -406.698658)
			(xy 306.460038 -406.734354) (xy 306.495735 -406.775549) (xy 306.525205 -406.821405) (xy 306.54785 -406.870989)
			(xy 306.563207 -406.92329) (xy 306.570965 -406.977245) (xy 306.570965 -407.031753) (xy 308.008475 -407.031753)
			(xy 308.008475 -406.977247) (xy 308.016233 -406.923297) (xy 308.031589 -406.870999) (xy 308.054233 -406.82142)
			(xy 308.083702 -406.775568) (xy 308.119397 -406.734377) (xy 308.16059 -406.698685) (xy 308.206445 -406.669219)
			(xy 308.256026 -406.64658) (xy 308.308324 -406.631227) (xy 308.362275 -406.623473) (xy 308.389528 -406.623012)
			(xy 309.253128 -406.623012) (xy 309.280379 -406.62346) (xy 309.334327 -406.63122) (xy 309.386621 -406.646578)
			(xy 309.436197 -406.669222) (xy 309.482047 -406.698691) (xy 309.523236 -406.734384) (xy 309.558926 -406.775576)
			(xy 309.588391 -406.821427) (xy 309.611032 -406.871005) (xy 309.626386 -406.923301) (xy 309.634142 -406.977249)
			(xy 309.634142 -407.031748) (xy 311.071798 -407.031748) (xy 311.071798 -406.977252) (xy 311.079553 -406.92331)
			(xy 311.094906 -406.87102) (xy 311.117544 -406.821448) (xy 311.147005 -406.775601) (xy 311.182692 -406.734414)
			(xy 311.223876 -406.698725) (xy 311.26972 -406.669259) (xy 311.31929 -406.646617) (xy 311.371578 -406.63126)
			(xy 311.42552 -406.6235) (xy 311.452768 -406.623012) (xy 312.316368 -406.623012) (xy 312.343624 -406.623433)
			(xy 312.397581 -406.631186) (xy 312.449886 -406.64654) (xy 312.499472 -406.669182) (xy 312.545332 -406.698651)
			(xy 312.586531 -406.734347) (xy 312.62223 -406.775542) (xy 312.651702 -406.821399) (xy 312.674348 -406.870984)
			(xy 312.689707 -406.923288) (xy 312.697465 -406.977244) (xy 312.697465 -407.031752) (xy 314.134975 -407.031752)
			(xy 314.134975 -406.977248) (xy 314.142732 -406.923299) (xy 314.158088 -406.871004) (xy 314.18073 -406.821426)
			(xy 314.210197 -406.775575) (xy 314.245889 -406.734384) (xy 314.287081 -406.698692) (xy 314.332933 -406.669226)
			(xy 314.382511 -406.646585) (xy 314.434807 -406.63123) (xy 314.488756 -406.623475) (xy 314.516008 -406.623012)
			(xy 315.379608 -406.623012) (xy 315.40686 -406.623458) (xy 315.46081 -406.631216) (xy 315.513107 -406.646573)
			(xy 315.562685 -406.669216) (xy 315.608537 -406.698684) (xy 315.649729 -406.734377) (xy 315.685421 -406.775569)
			(xy 315.714888 -406.821422) (xy 315.73753 -406.871001) (xy 315.752885 -406.923298) (xy 315.760642 -406.977248)
			(xy 315.760642 -407.031752) (xy 315.760642 -407.031754) (xy 317.198175 -407.031754) (xy 317.198175 -406.977246)
			(xy 317.205933 -406.923294) (xy 317.221291 -406.870995) (xy 317.243936 -406.821414) (xy 317.273407 -406.775561)
			(xy 317.309104 -406.73437) (xy 317.3503 -406.698678) (xy 317.396157 -406.669213) (xy 317.44574 -406.646574)
			(xy 317.498041 -406.631223) (xy 317.551994 -406.623472) (xy 317.579248 -406.623012) (xy 318.442848 -406.623012)
			(xy 318.470098 -406.623461) (xy 318.524044 -406.631224) (xy 318.576336 -406.646584) (xy 318.625909 -406.669229)
			(xy 318.671756 -406.698698) (xy 318.712943 -406.734391) (xy 318.748631 -406.775582) (xy 318.778094 -406.821433)
			(xy 318.800733 -406.87101) (xy 318.816087 -406.923303) (xy 318.823842 -406.97725) (xy 318.823842 -407.031749)
			(xy 320.261498 -407.031749) (xy 320.261498 -406.977251) (xy 320.269254 -406.923307) (xy 320.284608 -406.871016)
			(xy 320.307247 -406.821442) (xy 320.33671 -406.775595) (xy 320.372399 -406.734407) (xy 320.413585 -406.698718)
			(xy 320.459432 -406.669252) (xy 320.509005 -406.646612) (xy 320.561295 -406.631257) (xy 320.615239 -406.623499)
			(xy 320.642488 -406.623012) (xy 321.506088 -406.623012) (xy 321.533343 -406.623434) (xy 321.587298 -406.63119)
			(xy 321.6396 -406.646546) (xy 321.689184 -406.669189) (xy 321.735041 -406.698658) (xy 321.776238 -406.734354)
			(xy 321.811935 -406.775549) (xy 321.841405 -406.821405) (xy 321.86405 -406.870989) (xy 321.879407 -406.92329)
			(xy 321.887165 -406.977245) (xy 321.887165 -407.031753) (xy 323.324675 -407.031753) (xy 323.324675 -406.977247)
			(xy 323.332433 -406.923297) (xy 323.347789 -406.870999) (xy 323.370433 -406.82142) (xy 323.399902 -406.775568)
			(xy 323.435597 -406.734377) (xy 323.47679 -406.698685) (xy 323.522645 -406.669219) (xy 323.572226 -406.64658)
			(xy 323.624524 -406.631227) (xy 323.678475 -406.623473) (xy 323.705728 -406.623012) (xy 324.569328 -406.623012)
			(xy 324.596579 -406.62346) (xy 324.650527 -406.63122) (xy 324.702821 -406.646578) (xy 324.752397 -406.669222)
			(xy 324.798247 -406.698691) (xy 324.839436 -406.734384) (xy 324.875126 -406.775576) (xy 324.904591 -406.821427)
			(xy 324.927232 -406.871005) (xy 324.942586 -406.923301) (xy 324.950342 -406.977249) (xy 324.950342 -407.031748)
			(xy 326.387998 -407.031748) (xy 326.387998 -406.977252) (xy 326.395753 -406.92331) (xy 326.411106 -406.87102)
			(xy 326.433744 -406.821448) (xy 326.463205 -406.775601) (xy 326.498892 -406.734414) (xy 326.540076 -406.698725)
			(xy 326.58592 -406.669259) (xy 326.63549 -406.646617) (xy 326.687778 -406.63126) (xy 326.74172 -406.6235)
			(xy 326.768968 -406.623012) (xy 327.632568 -406.623012) (xy 327.659824 -406.623433) (xy 327.713781 -406.631186)
			(xy 327.766086 -406.64654) (xy 327.815672 -406.669182) (xy 327.861532 -406.698651) (xy 327.902731 -406.734347)
			(xy 327.93843 -406.775542) (xy 327.967902 -406.821399) (xy 327.990548 -406.870984) (xy 328.005907 -406.923288)
			(xy 328.013665 -406.977244) (xy 328.013665 -407.031752) (xy 329.451175 -407.031752) (xy 329.451175 -406.977248)
			(xy 329.458932 -406.923299) (xy 329.474288 -406.871004) (xy 329.49693 -406.821426) (xy 329.526397 -406.775575)
			(xy 329.562089 -406.734384) (xy 329.603281 -406.698692) (xy 329.649133 -406.669226) (xy 329.698711 -406.646585)
			(xy 329.751007 -406.63123) (xy 329.804956 -406.623475) (xy 329.832208 -406.623012) (xy 330.695808 -406.623012)
			(xy 330.72306 -406.623458) (xy 330.77701 -406.631216) (xy 330.829307 -406.646573) (xy 330.878885 -406.669216)
			(xy 330.924737 -406.698684) (xy 330.965929 -406.734377) (xy 331.001621 -406.775569) (xy 331.031088 -406.821422)
			(xy 331.05373 -406.871001) (xy 331.069085 -406.923298) (xy 331.076842 -406.977248) (xy 331.076842 -407.031752)
			(xy 331.076842 -407.031754) (xy 332.514375 -407.031754) (xy 332.514375 -406.977246) (xy 332.522133 -406.923294)
			(xy 332.537491 -406.870995) (xy 332.560136 -406.821414) (xy 332.589607 -406.775561) (xy 332.625304 -406.73437)
			(xy 332.6665 -406.698678) (xy 332.712357 -406.669213) (xy 332.76194 -406.646574) (xy 332.814241 -406.631223)
			(xy 332.868194 -406.623472) (xy 332.895448 -406.623012) (xy 333.759048 -406.623012) (xy 333.786298 -406.623461)
			(xy 333.840244 -406.631224) (xy 333.892536 -406.646584) (xy 333.942109 -406.669229) (xy 333.987956 -406.698698)
			(xy 334.029143 -406.734391) (xy 334.064831 -406.775582) (xy 334.094294 -406.821433) (xy 334.116933 -406.87101)
			(xy 334.132287 -406.923303) (xy 334.140042 -406.97725) (xy 334.140042 -407.031749) (xy 335.577698 -407.031749)
			(xy 335.577698 -406.977251) (xy 335.585454 -406.923307) (xy 335.600808 -406.871016) (xy 335.623447 -406.821442)
			(xy 335.65291 -406.775595) (xy 335.688599 -406.734407) (xy 335.729785 -406.698718) (xy 335.775632 -406.669252)
			(xy 335.825205 -406.646612) (xy 335.877495 -406.631257) (xy 335.931439 -406.623499) (xy 335.958688 -406.623012)
			(xy 336.822288 -406.623012) (xy 336.849543 -406.623434) (xy 336.903498 -406.63119) (xy 336.9558 -406.646546)
			(xy 337.005384 -406.669189) (xy 337.051241 -406.698658) (xy 337.092438 -406.734354) (xy 337.128135 -406.775549)
			(xy 337.157605 -406.821405) (xy 337.18025 -406.870989) (xy 337.195607 -406.92329) (xy 337.203365 -406.977245)
			(xy 337.203365 -407.031753) (xy 338.640875 -407.031753) (xy 338.640875 -406.977247) (xy 338.648633 -406.923297)
			(xy 338.663989 -406.870999) (xy 338.686633 -406.82142) (xy 338.716102 -406.775568) (xy 338.751797 -406.734377)
			(xy 338.79299 -406.698685) (xy 338.838845 -406.669219) (xy 338.888426 -406.64658) (xy 338.940724 -406.631227)
			(xy 338.994675 -406.623473) (xy 339.021928 -406.623012) (xy 339.885528 -406.623012) (xy 339.912779 -406.62346)
			(xy 339.966727 -406.63122) (xy 340.019021 -406.646578) (xy 340.068597 -406.669222) (xy 340.114447 -406.698691)
			(xy 340.155636 -406.734384) (xy 340.191326 -406.775576) (xy 340.220791 -406.821427) (xy 340.243432 -406.871005)
			(xy 340.258786 -406.923301) (xy 340.266542 -406.977249) (xy 340.266542 -407.031748) (xy 341.704198 -407.031748)
			(xy 341.704198 -406.977252) (xy 341.711953 -406.92331) (xy 341.727306 -406.87102) (xy 341.749944 -406.821448)
			(xy 341.779405 -406.775601) (xy 341.815092 -406.734414) (xy 341.856276 -406.698725) (xy 341.90212 -406.669259)
			(xy 341.95169 -406.646617) (xy 342.003978 -406.63126) (xy 342.05792 -406.6235) (xy 342.085168 -406.623012)
			(xy 342.948768 -406.623012) (xy 342.976024 -406.623433) (xy 343.029981 -406.631186) (xy 343.082286 -406.64654)
			(xy 343.131872 -406.669182) (xy 343.177732 -406.698651) (xy 343.218931 -406.734347) (xy 343.25463 -406.775542)
			(xy 343.284102 -406.821399) (xy 343.306748 -406.870984) (xy 343.322107 -406.923288) (xy 343.329865 -406.977244)
			(xy 343.329865 -407.031752) (xy 344.767375 -407.031752) (xy 344.767375 -406.977248) (xy 344.775132 -406.923299)
			(xy 344.790488 -406.871004) (xy 344.81313 -406.821426) (xy 344.842597 -406.775575) (xy 344.878289 -406.734384)
			(xy 344.919481 -406.698692) (xy 344.965333 -406.669226) (xy 345.014911 -406.646585) (xy 345.067207 -406.63123)
			(xy 345.121156 -406.623475) (xy 345.148408 -406.623012) (xy 346.012008 -406.623012) (xy 346.03926 -406.623458)
			(xy 346.09321 -406.631216) (xy 346.145507 -406.646573) (xy 346.195085 -406.669216) (xy 346.240937 -406.698684)
			(xy 346.282129 -406.734377) (xy 346.317821 -406.775569) (xy 346.347288 -406.821422) (xy 346.36993 -406.871001)
			(xy 346.385285 -406.923298) (xy 346.393042 -406.977248) (xy 346.393042 -407.031752) (xy 346.393042 -407.031754)
			(xy 347.830575 -407.031754) (xy 347.830575 -406.977246) (xy 347.838333 -406.923294) (xy 347.853691 -406.870995)
			(xy 347.876336 -406.821414) (xy 347.905807 -406.775561) (xy 347.941504 -406.73437) (xy 347.9827 -406.698678)
			(xy 348.028557 -406.669213) (xy 348.07814 -406.646574) (xy 348.130441 -406.631223) (xy 348.184394 -406.623472)
			(xy 348.211648 -406.623012) (xy 349.075248 -406.623012) (xy 349.102498 -406.623461) (xy 349.156444 -406.631224)
			(xy 349.208736 -406.646584) (xy 349.258309 -406.669229) (xy 349.304156 -406.698698) (xy 349.345343 -406.734391)
			(xy 349.381031 -406.775582) (xy 349.410494 -406.821433) (xy 349.433133 -406.87101) (xy 349.448487 -406.923303)
			(xy 349.456242 -406.97725) (xy 349.456242 -407.031749) (xy 350.893898 -407.031749) (xy 350.893898 -406.977251)
			(xy 350.901654 -406.923307) (xy 350.917008 -406.871016) (xy 350.939647 -406.821442) (xy 350.96911 -406.775595)
			(xy 351.004799 -406.734407) (xy 351.045985 -406.698718) (xy 351.091832 -406.669252) (xy 351.141405 -406.646612)
			(xy 351.193695 -406.631257) (xy 351.247639 -406.623499) (xy 351.274888 -406.623012) (xy 352.138488 -406.623012)
			(xy 352.165743 -406.623434) (xy 352.219698 -406.63119) (xy 352.272 -406.646546) (xy 352.321584 -406.669189)
			(xy 352.367441 -406.698658) (xy 352.408638 -406.734354) (xy 352.444335 -406.775549) (xy 352.473805 -406.821405)
			(xy 352.49645 -406.870989) (xy 352.511807 -406.92329) (xy 352.519565 -406.977245) (xy 352.519565 -407.031753)
			(xy 372.388075 -407.031753) (xy 372.388075 -406.977247) (xy 372.395833 -406.923296) (xy 372.411189 -406.870999)
			(xy 372.433833 -406.821419) (xy 372.463302 -406.775567) (xy 372.498997 -406.734376) (xy 372.540191 -406.698684)
			(xy 372.586046 -406.669219) (xy 372.635627 -406.646579) (xy 372.687926 -406.631226) (xy 372.741877 -406.623473)
			(xy 372.76913 -406.623012) (xy 373.63273 -406.623012) (xy 373.659981 -406.62346) (xy 373.713929 -406.63122)
			(xy 373.766222 -406.646579) (xy 373.815799 -406.669223) (xy 373.861648 -406.698691) (xy 373.902836 -406.734385)
			(xy 373.938527 -406.775576) (xy 373.967992 -406.821428) (xy 373.990632 -406.871006) (xy 374.005986 -406.923301)
			(xy 374.013742 -406.977249) (xy 374.013742 -407.031748) (xy 375.451398 -407.031748) (xy 375.451398 -406.977252)
			(xy 375.459153 -406.923309) (xy 375.474506 -406.87102) (xy 375.497144 -406.821447) (xy 375.526606 -406.775601)
			(xy 375.562292 -406.734414) (xy 375.603477 -406.698724) (xy 375.649321 -406.669258) (xy 375.698892 -406.646617)
			(xy 375.75118 -406.63126) (xy 375.805122 -406.6235) (xy 375.83237 -406.623012) (xy 376.69597 -406.623012)
			(xy 376.723226 -406.623433) (xy 376.777183 -406.631187) (xy 376.829487 -406.646541) (xy 376.879074 -406.669183)
			(xy 376.924933 -406.698652) (xy 376.966131 -406.734347) (xy 377.00183 -406.775543) (xy 377.031303 -406.8214)
			(xy 377.053948 -406.870985) (xy 377.069307 -406.923288) (xy 377.077065 -406.977244) (xy 377.077065 -407.031752)
			(xy 378.514575 -407.031752) (xy 378.514575 -406.977248) (xy 378.522332 -406.923299) (xy 378.537688 -406.871003)
			(xy 378.56033 -406.821425) (xy 378.589797 -406.775574) (xy 378.62549 -406.734383) (xy 378.666682 -406.698691)
			(xy 378.712534 -406.669225) (xy 378.762113 -406.646584) (xy 378.814409 -406.63123) (xy 378.868358 -406.623475)
			(xy 378.89561 -406.623012) (xy 379.75921 -406.623012) (xy 379.786462 -406.623459) (xy 379.840412 -406.631217)
			(xy 379.892708 -406.646573) (xy 379.942287 -406.669216) (xy 379.988138 -406.698684) (xy 380.029329 -406.734378)
			(xy 380.065022 -406.77557) (xy 380.094489 -406.821422) (xy 380.11713 -406.871001) (xy 380.132486 -406.923298)
			(xy 380.140242 -406.977248) (xy 380.140242 -407.031748) (xy 381.577898 -407.031748) (xy 381.577898 -406.977252)
			(xy 381.585653 -406.923312) (xy 381.601005 -406.871024) (xy 381.623641 -406.821453) (xy 381.653101 -406.775607)
			(xy 381.688785 -406.734421) (xy 381.729967 -406.698731) (xy 381.775809 -406.669265) (xy 381.825377 -406.646622)
			(xy 381.877663 -406.631264) (xy 381.931603 -406.623502) (xy 381.95885 -406.623012) (xy 382.82245 -406.623012)
			(xy 382.849707 -406.623431) (xy 382.903666 -406.631183) (xy 382.955973 -406.646536) (xy 383.005562 -406.669176)
			(xy 383.051423 -406.698645) (xy 383.092624 -406.73434) (xy 383.128325 -406.775536) (xy 383.1578 -406.821394)
			(xy 383.180447 -406.870981) (xy 383.195806 -406.923285) (xy 383.203565 -406.977243) (xy 383.203565 -407.031749)
			(xy 384.641098 -407.031749) (xy 384.641098 -406.977251) (xy 384.648854 -406.923307) (xy 384.664208 -406.871016)
			(xy 384.686847 -406.821442) (xy 384.716311 -406.775594) (xy 384.751999 -406.734406) (xy 384.793186 -406.698717)
			(xy 384.839033 -406.669252) (xy 384.888606 -406.646611) (xy 384.940897 -406.631256) (xy 384.994841 -406.623499)
			(xy 385.02209 -406.623012) (xy 385.88569 -406.623012) (xy 385.912945 -406.623434) (xy 385.9669 -406.63119)
			(xy 386.019202 -406.646546) (xy 386.068786 -406.66919) (xy 386.114642 -406.698659) (xy 386.155838 -406.734354)
			(xy 386.191535 -406.77555) (xy 386.221006 -406.821406) (xy 386.24365 -406.870989) (xy 386.259007 -406.923291)
			(xy 386.266765 -406.977245) (xy 386.266765 -407.031753) (xy 387.704275 -407.031753) (xy 387.704275 -406.977247)
			(xy 387.712033 -406.923296) (xy 387.727389 -406.870999) (xy 387.750033 -406.821419) (xy 387.779502 -406.775567)
			(xy 387.815197 -406.734376) (xy 387.856391 -406.698684) (xy 387.902246 -406.669219) (xy 387.951827 -406.646579)
			(xy 388.004126 -406.631226) (xy 388.058077 -406.623473) (xy 388.08533 -406.623012) (xy 388.94893 -406.623012)
			(xy 388.976181 -406.62346) (xy 389.030129 -406.63122) (xy 389.082422 -406.646579) (xy 389.131999 -406.669223)
			(xy 389.177848 -406.698691) (xy 389.219036 -406.734385) (xy 389.254727 -406.775576) (xy 389.284192 -406.821428)
			(xy 389.306832 -406.871006) (xy 389.322186 -406.923301) (xy 389.329942 -406.977249) (xy 389.329942 -407.031748)
			(xy 390.767598 -407.031748) (xy 390.767598 -406.977252) (xy 390.775353 -406.923309) (xy 390.790706 -406.87102)
			(xy 390.813344 -406.821447) (xy 390.842806 -406.775601) (xy 390.878492 -406.734414) (xy 390.919677 -406.698724)
			(xy 390.965521 -406.669258) (xy 391.015092 -406.646617) (xy 391.06738 -406.63126) (xy 391.121322 -406.6235)
			(xy 391.14857 -406.623012) (xy 392.01217 -406.623012) (xy 392.039426 -406.623433) (xy 392.093383 -406.631187)
			(xy 392.145687 -406.646541) (xy 392.195274 -406.669183) (xy 392.241133 -406.698652) (xy 392.282331 -406.734347)
			(xy 392.31803 -406.775543) (xy 392.347503 -406.8214) (xy 392.370148 -406.870985) (xy 392.385507 -406.923288)
			(xy 392.393265 -406.977244) (xy 392.393265 -407.031752) (xy 393.830775 -407.031752) (xy 393.830775 -406.977248)
			(xy 393.838532 -406.923299) (xy 393.853888 -406.871003) (xy 393.87653 -406.821425) (xy 393.905997 -406.775574)
			(xy 393.94169 -406.734383) (xy 393.982882 -406.698691) (xy 394.028734 -406.669225) (xy 394.078313 -406.646584)
			(xy 394.130609 -406.63123) (xy 394.184558 -406.623475) (xy 394.21181 -406.623012) (xy 395.07541 -406.623012)
			(xy 395.102662 -406.623459) (xy 395.156612 -406.631217) (xy 395.208908 -406.646573) (xy 395.258487 -406.669216)
			(xy 395.304338 -406.698684) (xy 395.345529 -406.734378) (xy 395.381222 -406.77557) (xy 395.410689 -406.821422)
			(xy 395.43333 -406.871001) (xy 395.448686 -406.923298) (xy 395.456442 -406.977248) (xy 395.456442 -407.031748)
			(xy 396.894098 -407.031748) (xy 396.894098 -406.977252) (xy 396.901853 -406.923312) (xy 396.917205 -406.871024)
			(xy 396.939841 -406.821453) (xy 396.969301 -406.775607) (xy 397.004985 -406.734421) (xy 397.046167 -406.698731)
			(xy 397.092009 -406.669265) (xy 397.141577 -406.646622) (xy 397.193863 -406.631264) (xy 397.247803 -406.623502)
			(xy 397.27505 -406.623012) (xy 398.13865 -406.623012) (xy 398.165907 -406.623431) (xy 398.219866 -406.631183)
			(xy 398.272173 -406.646536) (xy 398.321762 -406.669176) (xy 398.367623 -406.698645) (xy 398.408824 -406.73434)
			(xy 398.444525 -406.775536) (xy 398.474 -406.821394) (xy 398.496647 -406.870981) (xy 398.512006 -406.923285)
			(xy 398.519765 -406.977243) (xy 398.519765 -407.031749) (xy 399.957298 -407.031749) (xy 399.957298 -406.977251)
			(xy 399.965054 -406.923307) (xy 399.980408 -406.871016) (xy 400.003047 -406.821442) (xy 400.032511 -406.775594)
			(xy 400.068199 -406.734406) (xy 400.109386 -406.698717) (xy 400.155233 -406.669252) (xy 400.204806 -406.646611)
			(xy 400.257097 -406.631256) (xy 400.311041 -406.623499) (xy 400.33829 -406.623012) (xy 401.20189 -406.623012)
			(xy 401.229145 -406.623434) (xy 401.2831 -406.63119) (xy 401.335402 -406.646546) (xy 401.384986 -406.66919)
			(xy 401.430842 -406.698659) (xy 401.472038 -406.734354) (xy 401.507735 -406.77555) (xy 401.537206 -406.821406)
			(xy 401.55985 -406.870989) (xy 401.575207 -406.923291) (xy 401.582965 -406.977245) (xy 401.582965 -407.031753)
			(xy 403.020475 -407.031753) (xy 403.020475 -406.977247) (xy 403.028233 -406.923296) (xy 403.043589 -406.870999)
			(xy 403.066233 -406.821419) (xy 403.095702 -406.775567) (xy 403.131397 -406.734376) (xy 403.172591 -406.698684)
			(xy 403.218446 -406.669219) (xy 403.268027 -406.646579) (xy 403.320326 -406.631226) (xy 403.374277 -406.623473)
			(xy 403.40153 -406.623012) (xy 404.26513 -406.623012) (xy 404.292381 -406.62346) (xy 404.346329 -406.63122)
			(xy 404.398622 -406.646579) (xy 404.448199 -406.669223) (xy 404.494048 -406.698691) (xy 404.535236 -406.734385)
			(xy 404.570927 -406.775576) (xy 404.600392 -406.821428) (xy 404.623032 -406.871006) (xy 404.638386 -406.923301)
			(xy 404.646142 -406.977249) (xy 404.646142 -407.031748) (xy 406.083798 -407.031748) (xy 406.083798 -406.977252)
			(xy 406.091553 -406.923309) (xy 406.106906 -406.87102) (xy 406.129544 -406.821447) (xy 406.159006 -406.775601)
			(xy 406.194692 -406.734414) (xy 406.235877 -406.698724) (xy 406.281721 -406.669258) (xy 406.331292 -406.646617)
			(xy 406.38358 -406.63126) (xy 406.437522 -406.6235) (xy 406.46477 -406.623012) (xy 407.32837 -406.623012)
			(xy 407.355626 -406.623433) (xy 407.409583 -406.631187) (xy 407.461887 -406.646541) (xy 407.511474 -406.669183)
			(xy 407.557333 -406.698652) (xy 407.598531 -406.734347) (xy 407.63423 -406.775543) (xy 407.663703 -406.8214)
			(xy 407.686348 -406.870985) (xy 407.701707 -406.923288) (xy 407.709465 -406.977244) (xy 407.709465 -407.031752)
			(xy 409.146975 -407.031752) (xy 409.146975 -406.977248) (xy 409.154732 -406.923299) (xy 409.170088 -406.871003)
			(xy 409.19273 -406.821425) (xy 409.222197 -406.775574) (xy 409.25789 -406.734383) (xy 409.299082 -406.698691)
			(xy 409.344934 -406.669225) (xy 409.394513 -406.646584) (xy 409.446809 -406.63123) (xy 409.500758 -406.623475)
			(xy 409.52801 -406.623012) (xy 410.39161 -406.623012) (xy 410.418862 -406.623459) (xy 410.472812 -406.631217)
			(xy 410.525108 -406.646573) (xy 410.574687 -406.669216) (xy 410.620538 -406.698684) (xy 410.661729 -406.734378)
			(xy 410.697422 -406.77557) (xy 410.726889 -406.821422) (xy 410.74953 -406.871001) (xy 410.764886 -406.923298)
			(xy 410.772642 -406.977248) (xy 410.772642 -407.031748) (xy 412.210298 -407.031748) (xy 412.210298 -406.977252)
			(xy 412.218053 -406.923312) (xy 412.233405 -406.871024) (xy 412.256041 -406.821453) (xy 412.285501 -406.775607)
			(xy 412.321185 -406.734421) (xy 412.362367 -406.698731) (xy 412.408209 -406.669265) (xy 412.457777 -406.646622)
			(xy 412.510063 -406.631264) (xy 412.564003 -406.623502) (xy 412.59125 -406.623012) (xy 413.45485 -406.623012)
			(xy 413.482107 -406.623431) (xy 413.536066 -406.631183) (xy 413.588373 -406.646536) (xy 413.637962 -406.669176)
			(xy 413.683823 -406.698645) (xy 413.725024 -406.73434) (xy 413.760725 -406.775536) (xy 413.7902 -406.821394)
			(xy 413.812847 -406.870981) (xy 413.828206 -406.923285) (xy 413.835965 -406.977243) (xy 413.835965 -407.031749)
			(xy 415.273498 -407.031749) (xy 415.273498 -406.977251) (xy 415.281254 -406.923307) (xy 415.296608 -406.871016)
			(xy 415.319247 -406.821442) (xy 415.348711 -406.775594) (xy 415.384399 -406.734406) (xy 415.425586 -406.698717)
			(xy 415.471433 -406.669252) (xy 415.521006 -406.646611) (xy 415.573297 -406.631256) (xy 415.627241 -406.623499)
			(xy 415.65449 -406.623012) (xy 416.51809 -406.623012) (xy 416.545345 -406.623434) (xy 416.5993 -406.63119)
			(xy 416.651602 -406.646546) (xy 416.701186 -406.66919) (xy 416.747042 -406.698659) (xy 416.788238 -406.734354)
			(xy 416.823935 -406.77555) (xy 416.853406 -406.821406) (xy 416.87605 -406.870989) (xy 416.891407 -406.923291)
			(xy 416.899165 -406.977245) (xy 416.899165 -407.031753) (xy 418.336675 -407.031753) (xy 418.336675 -406.977247)
			(xy 418.344433 -406.923296) (xy 418.359789 -406.870999) (xy 418.382433 -406.821419) (xy 418.411902 -406.775567)
			(xy 418.447597 -406.734376) (xy 418.488791 -406.698684) (xy 418.534646 -406.669219) (xy 418.584227 -406.646579)
			(xy 418.636526 -406.631226) (xy 418.690477 -406.623473) (xy 418.71773 -406.623012) (xy 419.58133 -406.623012)
			(xy 419.608581 -406.62346) (xy 419.662529 -406.63122) (xy 419.714822 -406.646579) (xy 419.764399 -406.669223)
			(xy 419.810248 -406.698691) (xy 419.851436 -406.734385) (xy 419.887127 -406.775576) (xy 419.916592 -406.821428)
			(xy 419.939232 -406.871006) (xy 419.954586 -406.923301) (xy 419.962342 -406.977249) (xy 419.962342 -407.031751)
			(xy 419.954586 -407.085699) (xy 419.939232 -407.137994) (xy 419.916592 -407.187572) (xy 419.887127 -407.233424)
			(xy 419.851436 -407.274615) (xy 419.810248 -407.310309) (xy 419.764399 -407.339777) (xy 419.714822 -407.362421)
			(xy 419.662529 -407.37778) (xy 419.608581 -407.38554) (xy 419.58133 -407.386028) (xy 418.71773 -407.386028)
			(xy 418.690477 -407.385527) (xy 418.636526 -407.377774) (xy 418.584227 -407.362421) (xy 418.534646 -407.339781)
			(xy 418.488791 -407.310316) (xy 418.447597 -407.274624) (xy 418.411902 -407.233433) (xy 418.382433 -407.187581)
			(xy 418.359789 -407.138001) (xy 418.344433 -407.085704) (xy 418.336675 -407.031753) (xy 416.899165 -407.031753)
			(xy 416.899165 -407.031755) (xy 416.891407 -407.085709) (xy 416.87605 -407.138011) (xy 416.853406 -407.187594)
			(xy 416.823935 -407.23345) (xy 416.788238 -407.274646) (xy 416.747042 -407.310341) (xy 416.701186 -407.33981)
			(xy 416.651602 -407.362454) (xy 416.5993 -407.37781) (xy 416.545345 -407.385566) (xy 416.51809 -407.386028)
			(xy 415.65449 -407.386028) (xy 415.627241 -407.385501) (xy 415.573297 -407.377744) (xy 415.521006 -407.362389)
			(xy 415.471433 -407.339748) (xy 415.425586 -407.310283) (xy 415.384399 -407.274594) (xy 415.348711 -407.233406)
			(xy 415.319247 -407.187558) (xy 415.296608 -407.137984) (xy 415.281254 -407.085693) (xy 415.273498 -407.031749)
			(xy 413.835965 -407.031749) (xy 413.835965 -407.031757) (xy 413.828206 -407.085715) (xy 413.812847 -407.138019)
			(xy 413.7902 -407.187606) (xy 413.760725 -407.233464) (xy 413.725024 -407.27466) (xy 413.683823 -407.310355)
			(xy 413.637962 -407.339824) (xy 413.588373 -407.362464) (xy 413.536066 -407.377817) (xy 413.482107 -407.385569)
			(xy 413.45485 -407.386028) (xy 412.59125 -407.386028) (xy 412.564003 -407.385498) (xy 412.510063 -407.377736)
			(xy 412.457777 -407.362378) (xy 412.408209 -407.339735) (xy 412.362367 -407.310269) (xy 412.321185 -407.274579)
			(xy 412.285501 -407.233393) (xy 412.256041 -407.187547) (xy 412.233405 -407.137976) (xy 412.218053 -407.085688)
			(xy 412.210298 -407.031748) (xy 410.772642 -407.031748) (xy 410.772642 -407.031752) (xy 410.764886 -407.085702)
			(xy 410.74953 -407.137999) (xy 410.726889 -407.187578) (xy 410.697422 -407.23343) (xy 410.661729 -407.274622)
			(xy 410.620538 -407.310316) (xy 410.574687 -407.339784) (xy 410.525108 -407.362427) (xy 410.472812 -407.377783)
			(xy 410.418862 -407.385541) (xy 410.39161 -407.386028) (xy 409.52801 -407.386028) (xy 409.500758 -407.385525)
			(xy 409.446809 -407.37777) (xy 409.394513 -407.362416) (xy 409.344934 -407.339775) (xy 409.299082 -407.310309)
			(xy 409.25789 -407.274617) (xy 409.222197 -407.233426) (xy 409.19273 -407.187575) (xy 409.170088 -407.137997)
			(xy 409.154732 -407.085701) (xy 409.146975 -407.031752) (xy 407.709465 -407.031752) (xy 407.709465 -407.031756)
			(xy 407.701707 -407.085712) (xy 407.686348 -407.138015) (xy 407.663703 -407.1876) (xy 407.63423 -407.233457)
			(xy 407.598531 -407.274653) (xy 407.557333 -407.310348) (xy 407.511474 -407.339817) (xy 407.461887 -407.362459)
			(xy 407.409583 -407.377813) (xy 407.355626 -407.385567) (xy 407.32837 -407.386028) (xy 406.46477 -407.386028)
			(xy 406.437522 -407.3855) (xy 406.38358 -407.37774) (xy 406.331292 -407.362383) (xy 406.281721 -407.339742)
			(xy 406.235877 -407.310276) (xy 406.194692 -407.274586) (xy 406.159006 -407.233399) (xy 406.129544 -407.187553)
			(xy 406.106906 -407.13798) (xy 406.091553 -407.085691) (xy 406.083798 -407.031748) (xy 404.646142 -407.031748)
			(xy 404.646142 -407.031751) (xy 404.638386 -407.085699) (xy 404.623032 -407.137994) (xy 404.600392 -407.187572)
			(xy 404.570927 -407.233424) (xy 404.535236 -407.274615) (xy 404.494048 -407.310309) (xy 404.448199 -407.339777)
			(xy 404.398622 -407.362421) (xy 404.346329 -407.37778) (xy 404.292381 -407.38554) (xy 404.26513 -407.386028)
			(xy 403.40153 -407.386028) (xy 403.374277 -407.385527) (xy 403.320326 -407.377774) (xy 403.268027 -407.362421)
			(xy 403.218446 -407.339781) (xy 403.172591 -407.310316) (xy 403.131397 -407.274624) (xy 403.095702 -407.233433)
			(xy 403.066233 -407.187581) (xy 403.043589 -407.138001) (xy 403.028233 -407.085704) (xy 403.020475 -407.031753)
			(xy 401.582965 -407.031753) (xy 401.582965 -407.031755) (xy 401.575207 -407.085709) (xy 401.55985 -407.138011)
			(xy 401.537206 -407.187594) (xy 401.507735 -407.23345) (xy 401.472038 -407.274646) (xy 401.430842 -407.310341)
			(xy 401.384986 -407.33981) (xy 401.335402 -407.362454) (xy 401.2831 -407.37781) (xy 401.229145 -407.385566)
			(xy 401.20189 -407.386028) (xy 400.33829 -407.386028) (xy 400.311041 -407.385501) (xy 400.257097 -407.377744)
			(xy 400.204806 -407.362389) (xy 400.155233 -407.339748) (xy 400.109386 -407.310283) (xy 400.068199 -407.274594)
			(xy 400.032511 -407.233406) (xy 400.003047 -407.187558) (xy 399.980408 -407.137984) (xy 399.965054 -407.085693)
			(xy 399.957298 -407.031749) (xy 398.519765 -407.031749) (xy 398.519765 -407.031757) (xy 398.512006 -407.085715)
			(xy 398.496647 -407.138019) (xy 398.474 -407.187606) (xy 398.444525 -407.233464) (xy 398.408824 -407.27466)
			(xy 398.367623 -407.310355) (xy 398.321762 -407.339824) (xy 398.272173 -407.362464) (xy 398.219866 -407.377817)
			(xy 398.165907 -407.385569) (xy 398.13865 -407.386028) (xy 397.27505 -407.386028) (xy 397.247803 -407.385498)
			(xy 397.193863 -407.377736) (xy 397.141577 -407.362378) (xy 397.092009 -407.339735) (xy 397.046167 -407.310269)
			(xy 397.004985 -407.274579) (xy 396.969301 -407.233393) (xy 396.939841 -407.187547) (xy 396.917205 -407.137976)
			(xy 396.901853 -407.085688) (xy 396.894098 -407.031748) (xy 395.456442 -407.031748) (xy 395.456442 -407.031752)
			(xy 395.448686 -407.085702) (xy 395.43333 -407.137999) (xy 395.410689 -407.187578) (xy 395.381222 -407.23343)
			(xy 395.345529 -407.274622) (xy 395.304338 -407.310316) (xy 395.258487 -407.339784) (xy 395.208908 -407.362427)
			(xy 395.156612 -407.377783) (xy 395.102662 -407.385541) (xy 395.07541 -407.386028) (xy 394.21181 -407.386028)
			(xy 394.184558 -407.385525) (xy 394.130609 -407.37777) (xy 394.078313 -407.362416) (xy 394.028734 -407.339775)
			(xy 393.982882 -407.310309) (xy 393.94169 -407.274617) (xy 393.905997 -407.233426) (xy 393.87653 -407.187575)
			(xy 393.853888 -407.137997) (xy 393.838532 -407.085701) (xy 393.830775 -407.031752) (xy 392.393265 -407.031752)
			(xy 392.393265 -407.031756) (xy 392.385507 -407.085712) (xy 392.370148 -407.138015) (xy 392.347503 -407.1876)
			(xy 392.31803 -407.233457) (xy 392.282331 -407.274653) (xy 392.241133 -407.310348) (xy 392.195274 -407.339817)
			(xy 392.145687 -407.362459) (xy 392.093383 -407.377813) (xy 392.039426 -407.385567) (xy 392.01217 -407.386028)
			(xy 391.14857 -407.386028) (xy 391.121322 -407.3855) (xy 391.06738 -407.37774) (xy 391.015092 -407.362383)
			(xy 390.965521 -407.339742) (xy 390.919677 -407.310276) (xy 390.878492 -407.274586) (xy 390.842806 -407.233399)
			(xy 390.813344 -407.187553) (xy 390.790706 -407.13798) (xy 390.775353 -407.085691) (xy 390.767598 -407.031748)
			(xy 389.329942 -407.031748) (xy 389.329942 -407.031751) (xy 389.322186 -407.085699) (xy 389.306832 -407.137994)
			(xy 389.284192 -407.187572) (xy 389.254727 -407.233424) (xy 389.219036 -407.274615) (xy 389.177848 -407.310309)
			(xy 389.131999 -407.339777) (xy 389.082422 -407.362421) (xy 389.030129 -407.37778) (xy 388.976181 -407.38554)
			(xy 388.94893 -407.386028) (xy 388.08533 -407.386028) (xy 388.058077 -407.385527) (xy 388.004126 -407.377774)
			(xy 387.951827 -407.362421) (xy 387.902246 -407.339781) (xy 387.856391 -407.310316) (xy 387.815197 -407.274624)
			(xy 387.779502 -407.233433) (xy 387.750033 -407.187581) (xy 387.727389 -407.138001) (xy 387.712033 -407.085704)
			(xy 387.704275 -407.031753) (xy 386.266765 -407.031753) (xy 386.266765 -407.031755) (xy 386.259007 -407.085709)
			(xy 386.24365 -407.138011) (xy 386.221006 -407.187594) (xy 386.191535 -407.23345) (xy 386.155838 -407.274646)
			(xy 386.114642 -407.310341) (xy 386.068786 -407.33981) (xy 386.019202 -407.362454) (xy 385.9669 -407.37781)
			(xy 385.912945 -407.385566) (xy 385.88569 -407.386028) (xy 385.02209 -407.386028) (xy 384.994841 -407.385501)
			(xy 384.940897 -407.377744) (xy 384.888606 -407.362389) (xy 384.839033 -407.339748) (xy 384.793186 -407.310283)
			(xy 384.751999 -407.274594) (xy 384.716311 -407.233406) (xy 384.686847 -407.187558) (xy 384.664208 -407.137984)
			(xy 384.648854 -407.085693) (xy 384.641098 -407.031749) (xy 383.203565 -407.031749) (xy 383.203565 -407.031757)
			(xy 383.195806 -407.085715) (xy 383.180447 -407.138019) (xy 383.1578 -407.187606) (xy 383.128325 -407.233464)
			(xy 383.092624 -407.27466) (xy 383.051423 -407.310355) (xy 383.005562 -407.339824) (xy 382.955973 -407.362464)
			(xy 382.903666 -407.377817) (xy 382.849707 -407.385569) (xy 382.82245 -407.386028) (xy 381.95885 -407.386028)
			(xy 381.931603 -407.385498) (xy 381.877663 -407.377736) (xy 381.825377 -407.362378) (xy 381.775809 -407.339735)
			(xy 381.729967 -407.310269) (xy 381.688785 -407.274579) (xy 381.653101 -407.233393) (xy 381.623641 -407.187547)
			(xy 381.601005 -407.137976) (xy 381.585653 -407.085688) (xy 381.577898 -407.031748) (xy 380.140242 -407.031748)
			(xy 380.140242 -407.031752) (xy 380.132486 -407.085702) (xy 380.11713 -407.137999) (xy 380.094489 -407.187578)
			(xy 380.065022 -407.23343) (xy 380.029329 -407.274622) (xy 379.988138 -407.310316) (xy 379.942287 -407.339784)
			(xy 379.892708 -407.362427) (xy 379.840412 -407.377783) (xy 379.786462 -407.385541) (xy 379.75921 -407.386028)
			(xy 378.89561 -407.386028) (xy 378.868358 -407.385525) (xy 378.814409 -407.37777) (xy 378.762113 -407.362416)
			(xy 378.712534 -407.339775) (xy 378.666682 -407.310309) (xy 378.62549 -407.274617) (xy 378.589797 -407.233426)
			(xy 378.56033 -407.187575) (xy 378.537688 -407.137997) (xy 378.522332 -407.085701) (xy 378.514575 -407.031752)
			(xy 377.077065 -407.031752) (xy 377.077065 -407.031756) (xy 377.069307 -407.085712) (xy 377.053948 -407.138015)
			(xy 377.031303 -407.1876) (xy 377.00183 -407.233457) (xy 376.966131 -407.274653) (xy 376.924933 -407.310348)
			(xy 376.879074 -407.339817) (xy 376.829487 -407.362459) (xy 376.777183 -407.377813) (xy 376.723226 -407.385567)
			(xy 376.69597 -407.386028) (xy 375.83237 -407.386028) (xy 375.805122 -407.3855) (xy 375.75118 -407.37774)
			(xy 375.698892 -407.362383) (xy 375.649321 -407.339742) (xy 375.603477 -407.310276) (xy 375.562292 -407.274586)
			(xy 375.526606 -407.233399) (xy 375.497144 -407.187553) (xy 375.474506 -407.13798) (xy 375.459153 -407.085691)
			(xy 375.451398 -407.031748) (xy 374.013742 -407.031748) (xy 374.013742 -407.031751) (xy 374.005986 -407.085699)
			(xy 373.990632 -407.137994) (xy 373.967992 -407.187572) (xy 373.938527 -407.233424) (xy 373.902836 -407.274615)
			(xy 373.861648 -407.310309) (xy 373.815799 -407.339777) (xy 373.766222 -407.362421) (xy 373.713929 -407.37778)
			(xy 373.659981 -407.38554) (xy 373.63273 -407.386028) (xy 372.76913 -407.386028) (xy 372.741877 -407.385527)
			(xy 372.687926 -407.377774) (xy 372.635627 -407.362421) (xy 372.586046 -407.339781) (xy 372.540191 -407.310316)
			(xy 372.498997 -407.274624) (xy 372.463302 -407.233433) (xy 372.433833 -407.187581) (xy 372.411189 -407.138001)
			(xy 372.395833 -407.085704) (xy 372.388075 -407.031753) (xy 352.519565 -407.031753) (xy 352.519565 -407.031755)
			(xy 352.511807 -407.08571) (xy 352.49645 -407.138011) (xy 352.473805 -407.187595) (xy 352.444335 -407.233451)
			(xy 352.408638 -407.274646) (xy 352.367441 -407.310342) (xy 352.321584 -407.339811) (xy 352.272 -407.362454)
			(xy 352.219698 -407.37781) (xy 352.165743 -407.385566) (xy 352.138488 -407.386028) (xy 351.274888 -407.386028)
			(xy 351.247639 -407.385501) (xy 351.193695 -407.377743) (xy 351.141405 -407.362388) (xy 351.091832 -407.339748)
			(xy 351.045985 -407.310282) (xy 351.004799 -407.274593) (xy 350.96911 -407.233405) (xy 350.939647 -407.187558)
			(xy 350.917008 -407.137984) (xy 350.901654 -407.085693) (xy 350.893898 -407.031749) (xy 349.456242 -407.031749)
			(xy 349.456242 -407.03175) (xy 349.448487 -407.085697) (xy 349.433133 -407.137991) (xy 349.410494 -407.187567)
			(xy 349.381031 -407.233418) (xy 349.345343 -407.274609) (xy 349.304156 -407.310302) (xy 349.258309 -407.339771)
			(xy 349.208736 -407.362416) (xy 349.156444 -407.377776) (xy 349.102498 -407.385539) (xy 349.075248 -407.386028)
			(xy 348.211648 -407.386028) (xy 348.184394 -407.385528) (xy 348.130441 -407.377777) (xy 348.07814 -407.362426)
			(xy 348.028557 -407.339787) (xy 347.9827 -407.310322) (xy 347.941504 -407.27463) (xy 347.905807 -407.233439)
			(xy 347.876336 -407.187586) (xy 347.853691 -407.138005) (xy 347.838333 -407.085706) (xy 347.830575 -407.031754)
			(xy 346.393042 -407.031754) (xy 346.385285 -407.085702) (xy 346.36993 -407.137999) (xy 346.347288 -407.187578)
			(xy 346.317821 -407.233431) (xy 346.282129 -407.274623) (xy 346.240937 -407.310316) (xy 346.195085 -407.339784)
			(xy 346.145507 -407.362427) (xy 346.09321 -407.377784) (xy 346.03926 -407.385542) (xy 346.012008 -407.386028)
			(xy 345.148408 -407.386028) (xy 345.121156 -407.385525) (xy 345.067207 -407.37777) (xy 345.014911 -407.362415)
			(xy 344.965333 -407.339774) (xy 344.919481 -407.310308) (xy 344.878289 -407.274616) (xy 344.842597 -407.233425)
			(xy 344.81313 -407.187574) (xy 344.790488 -407.137996) (xy 344.775132 -407.085701) (xy 344.767375 -407.031752)
			(xy 343.329865 -407.031752) (xy 343.329865 -407.031756) (xy 343.322107 -407.085712) (xy 343.306748 -407.138016)
			(xy 343.284102 -407.187601) (xy 343.25463 -407.233458) (xy 343.218931 -407.274653) (xy 343.177732 -407.310349)
			(xy 343.131872 -407.339818) (xy 343.082286 -407.36246) (xy 343.029981 -407.377814) (xy 342.976024 -407.385567)
			(xy 342.948768 -407.386028) (xy 342.085168 -407.386028) (xy 342.05792 -407.3855) (xy 342.003978 -407.37774)
			(xy 341.95169 -407.362383) (xy 341.90212 -407.339741) (xy 341.856276 -407.310275) (xy 341.815092 -407.274586)
			(xy 341.779405 -407.233399) (xy 341.749944 -407.187552) (xy 341.727306 -407.13798) (xy 341.711953 -407.08569)
			(xy 341.704198 -407.031748) (xy 340.266542 -407.031748) (xy 340.266542 -407.031751) (xy 340.258786 -407.0857)
			(xy 340.243432 -407.137995) (xy 340.220791 -407.187573) (xy 340.191326 -407.233424) (xy 340.155636 -407.274616)
			(xy 340.114447 -407.310309) (xy 340.068597 -407.339778) (xy 340.019021 -407.362422) (xy 339.966727 -407.37778)
			(xy 339.912779 -407.38554) (xy 339.885528 -407.386028) (xy 339.021928 -407.386028) (xy 338.994675 -407.385527)
			(xy 338.940724 -407.377773) (xy 338.888426 -407.36242) (xy 338.838845 -407.339781) (xy 338.79299 -407.310315)
			(xy 338.751797 -407.274623) (xy 338.716102 -407.233432) (xy 338.686633 -407.18758) (xy 338.663989 -407.138001)
			(xy 338.648633 -407.085703) (xy 338.640875 -407.031753) (xy 337.203365 -407.031753) (xy 337.203365 -407.031755)
			(xy 337.195607 -407.08571) (xy 337.18025 -407.138011) (xy 337.157605 -407.187595) (xy 337.128135 -407.233451)
			(xy 337.092438 -407.274646) (xy 337.051241 -407.310342) (xy 337.005384 -407.339811) (xy 336.9558 -407.362454)
			(xy 336.903498 -407.37781) (xy 336.849543 -407.385566) (xy 336.822288 -407.386028) (xy 335.958688 -407.386028)
			(xy 335.931439 -407.385501) (xy 335.877495 -407.377743) (xy 335.825205 -407.362388) (xy 335.775632 -407.339748)
			(xy 335.729785 -407.310282) (xy 335.688599 -407.274593) (xy 335.65291 -407.233405) (xy 335.623447 -407.187558)
			(xy 335.600808 -407.137984) (xy 335.585454 -407.085693) (xy 335.577698 -407.031749) (xy 334.140042 -407.031749)
			(xy 334.140042 -407.03175) (xy 334.132287 -407.085697) (xy 334.116933 -407.137991) (xy 334.094294 -407.187567)
			(xy 334.064831 -407.233418) (xy 334.029143 -407.274609) (xy 333.987956 -407.310302) (xy 333.942109 -407.339771)
			(xy 333.892536 -407.362416) (xy 333.840244 -407.377776) (xy 333.786298 -407.385539) (xy 333.759048 -407.386028)
			(xy 332.895448 -407.386028) (xy 332.868194 -407.385528) (xy 332.814241 -407.377777) (xy 332.76194 -407.362426)
			(xy 332.712357 -407.339787) (xy 332.6665 -407.310322) (xy 332.625304 -407.27463) (xy 332.589607 -407.233439)
			(xy 332.560136 -407.187586) (xy 332.537491 -407.138005) (xy 332.522133 -407.085706) (xy 332.514375 -407.031754)
			(xy 331.076842 -407.031754) (xy 331.069085 -407.085702) (xy 331.05373 -407.137999) (xy 331.031088 -407.187578)
			(xy 331.001621 -407.233431) (xy 330.965929 -407.274623) (xy 330.924737 -407.310316) (xy 330.878885 -407.339784)
			(xy 330.829307 -407.362427) (xy 330.77701 -407.377784) (xy 330.72306 -407.385542) (xy 330.695808 -407.386028)
			(xy 329.832208 -407.386028) (xy 329.804956 -407.385525) (xy 329.751007 -407.37777) (xy 329.698711 -407.362415)
			(xy 329.649133 -407.339774) (xy 329.603281 -407.310308) (xy 329.562089 -407.274616) (xy 329.526397 -407.233425)
			(xy 329.49693 -407.187574) (xy 329.474288 -407.137996) (xy 329.458932 -407.085701) (xy 329.451175 -407.031752)
			(xy 328.013665 -407.031752) (xy 328.013665 -407.031756) (xy 328.005907 -407.085712) (xy 327.990548 -407.138016)
			(xy 327.967902 -407.187601) (xy 327.93843 -407.233458) (xy 327.902731 -407.274653) (xy 327.861532 -407.310349)
			(xy 327.815672 -407.339818) (xy 327.766086 -407.36246) (xy 327.713781 -407.377814) (xy 327.659824 -407.385567)
			(xy 327.632568 -407.386028) (xy 326.768968 -407.386028) (xy 326.74172 -407.3855) (xy 326.687778 -407.37774)
			(xy 326.63549 -407.362383) (xy 326.58592 -407.339741) (xy 326.540076 -407.310275) (xy 326.498892 -407.274586)
			(xy 326.463205 -407.233399) (xy 326.433744 -407.187552) (xy 326.411106 -407.13798) (xy 326.395753 -407.08569)
			(xy 326.387998 -407.031748) (xy 324.950342 -407.031748) (xy 324.950342 -407.031751) (xy 324.942586 -407.0857)
			(xy 324.927232 -407.137995) (xy 324.904591 -407.187573) (xy 324.875126 -407.233424) (xy 324.839436 -407.274616)
			(xy 324.798247 -407.310309) (xy 324.752397 -407.339778) (xy 324.702821 -407.362422) (xy 324.650527 -407.37778)
			(xy 324.596579 -407.38554) (xy 324.569328 -407.386028) (xy 323.705728 -407.386028) (xy 323.678475 -407.385527)
			(xy 323.624524 -407.377773) (xy 323.572226 -407.36242) (xy 323.522645 -407.339781) (xy 323.47679 -407.310315)
			(xy 323.435597 -407.274623) (xy 323.399902 -407.233432) (xy 323.370433 -407.18758) (xy 323.347789 -407.138001)
			(xy 323.332433 -407.085703) (xy 323.324675 -407.031753) (xy 321.887165 -407.031753) (xy 321.887165 -407.031755)
			(xy 321.879407 -407.08571) (xy 321.86405 -407.138011) (xy 321.841405 -407.187595) (xy 321.811935 -407.233451)
			(xy 321.776238 -407.274646) (xy 321.735041 -407.310342) (xy 321.689184 -407.339811) (xy 321.6396 -407.362454)
			(xy 321.587298 -407.37781) (xy 321.533343 -407.385566) (xy 321.506088 -407.386028) (xy 320.642488 -407.386028)
			(xy 320.615239 -407.385501) (xy 320.561295 -407.377743) (xy 320.509005 -407.362388) (xy 320.459432 -407.339748)
			(xy 320.413585 -407.310282) (xy 320.372399 -407.274593) (xy 320.33671 -407.233405) (xy 320.307247 -407.187558)
			(xy 320.284608 -407.137984) (xy 320.269254 -407.085693) (xy 320.261498 -407.031749) (xy 318.823842 -407.031749)
			(xy 318.823842 -407.03175) (xy 318.816087 -407.085697) (xy 318.800733 -407.137991) (xy 318.778094 -407.187567)
			(xy 318.748631 -407.233418) (xy 318.712943 -407.274609) (xy 318.671756 -407.310302) (xy 318.625909 -407.339771)
			(xy 318.576336 -407.362416) (xy 318.524044 -407.377776) (xy 318.470098 -407.385539) (xy 318.442848 -407.386028)
			(xy 317.579248 -407.386028) (xy 317.551994 -407.385528) (xy 317.498041 -407.377777) (xy 317.44574 -407.362426)
			(xy 317.396157 -407.339787) (xy 317.3503 -407.310322) (xy 317.309104 -407.27463) (xy 317.273407 -407.233439)
			(xy 317.243936 -407.187586) (xy 317.221291 -407.138005) (xy 317.205933 -407.085706) (xy 317.198175 -407.031754)
			(xy 315.760642 -407.031754) (xy 315.752885 -407.085702) (xy 315.73753 -407.137999) (xy 315.714888 -407.187578)
			(xy 315.685421 -407.233431) (xy 315.649729 -407.274623) (xy 315.608537 -407.310316) (xy 315.562685 -407.339784)
			(xy 315.513107 -407.362427) (xy 315.46081 -407.377784) (xy 315.40686 -407.385542) (xy 315.379608 -407.386028)
			(xy 314.516008 -407.386028) (xy 314.488756 -407.385525) (xy 314.434807 -407.37777) (xy 314.382511 -407.362415)
			(xy 314.332933 -407.339774) (xy 314.287081 -407.310308) (xy 314.245889 -407.274616) (xy 314.210197 -407.233425)
			(xy 314.18073 -407.187574) (xy 314.158088 -407.137996) (xy 314.142732 -407.085701) (xy 314.134975 -407.031752)
			(xy 312.697465 -407.031752) (xy 312.697465 -407.031756) (xy 312.689707 -407.085712) (xy 312.674348 -407.138016)
			(xy 312.651702 -407.187601) (xy 312.62223 -407.233458) (xy 312.586531 -407.274653) (xy 312.545332 -407.310349)
			(xy 312.499472 -407.339818) (xy 312.449886 -407.36246) (xy 312.397581 -407.377814) (xy 312.343624 -407.385567)
			(xy 312.316368 -407.386028) (xy 311.452768 -407.386028) (xy 311.42552 -407.3855) (xy 311.371578 -407.37774)
			(xy 311.31929 -407.362383) (xy 311.26972 -407.339741) (xy 311.223876 -407.310275) (xy 311.182692 -407.274586)
			(xy 311.147005 -407.233399) (xy 311.117544 -407.187552) (xy 311.094906 -407.13798) (xy 311.079553 -407.08569)
			(xy 311.071798 -407.031748) (xy 309.634142 -407.031748) (xy 309.634142 -407.031751) (xy 309.626386 -407.0857)
			(xy 309.611032 -407.137995) (xy 309.588391 -407.187573) (xy 309.558926 -407.233424) (xy 309.523236 -407.274616)
			(xy 309.482047 -407.310309) (xy 309.436197 -407.339778) (xy 309.386621 -407.362422) (xy 309.334327 -407.37778)
			(xy 309.280379 -407.38554) (xy 309.253128 -407.386028) (xy 308.389528 -407.386028) (xy 308.362275 -407.385527)
			(xy 308.308324 -407.377773) (xy 308.256026 -407.36242) (xy 308.206445 -407.339781) (xy 308.16059 -407.310315)
			(xy 308.119397 -407.274623) (xy 308.083702 -407.233432) (xy 308.054233 -407.18758) (xy 308.031589 -407.138001)
			(xy 308.016233 -407.085703) (xy 308.008475 -407.031753) (xy 306.570965 -407.031753) (xy 306.570965 -407.031755)
			(xy 306.563207 -407.08571) (xy 306.54785 -407.138011) (xy 306.525205 -407.187595) (xy 306.495735 -407.233451)
			(xy 306.460038 -407.274646) (xy 306.418841 -407.310342) (xy 306.372984 -407.339811) (xy 306.3234 -407.362454)
			(xy 306.271098 -407.37781) (xy 306.217143 -407.385566) (xy 306.189888 -407.386028) (xy 305.326288 -407.386028)
			(xy 305.299039 -407.385501) (xy 305.245095 -407.377743) (xy 305.192805 -407.362388) (xy 305.143232 -407.339748)
			(xy 305.097385 -407.310282) (xy 305.056199 -407.274593) (xy 305.02051 -407.233405) (xy 304.991047 -407.187558)
			(xy 304.968408 -407.137984) (xy 304.953054 -407.085693) (xy 304.945298 -407.031749) (xy 274.459335 -407.031749)
			(xy 274.369276 -407.121868) (xy 274.369276 -407.203148) (xy 274.602448 -407.43632) (xy 280.100532 -407.43632)
			(xy 280.125481 -407.436823) (xy 280.174763 -407.444637) (xy 280.222219 -407.460054) (xy 280.266685 -407.482694)
			(xy 280.307069 -407.512001) (xy 280.325068 -407.529284) (xy 280.739596 -407.943812) (xy 280.756896 -407.961798)
			(xy 280.786219 -408.002177) (xy 280.808865 -408.046645) (xy 280.824276 -408.094108) (xy 280.832075 -408.143397)
			(xy 280.83256 -408.168348) (xy 280.83256 -410.057453) (xy 304.945246 -410.057453) (xy 304.945246 -410.002947)
			(xy 304.953003 -409.948996) (xy 304.968358 -409.896698) (xy 304.991001 -409.847117) (xy 305.020468 -409.801263)
			(xy 305.056162 -409.76007) (xy 305.097354 -409.724375) (xy 305.143207 -409.694906) (xy 305.192786 -409.672263)
			(xy 305.245084 -409.656905) (xy 305.299035 -409.649147) (xy 305.326288 -409.64866) (xy 306.189888 -409.64866)
			(xy 306.217139 -409.649186) (xy 306.271087 -409.656941) (xy 306.323382 -409.672295) (xy 306.372959 -409.694935)
			(xy 306.41881 -409.7244) (xy 306.460001 -409.760091) (xy 306.495693 -409.80128) (xy 306.525159 -409.84713)
			(xy 306.547801 -409.896707) (xy 306.563156 -409.949001) (xy 306.570913 -410.002949) (xy 306.570913 -410.057451)
			(xy 306.570912 -410.057456) (xy 308.008423 -410.057456) (xy 308.008423 -410.002944) (xy 308.016181 -409.948986)
			(xy 308.03154 -409.896681) (xy 308.054187 -409.847095) (xy 308.08366 -409.801236) (xy 308.119359 -409.76004)
			(xy 308.160559 -409.724343) (xy 308.206419 -409.694873) (xy 308.256007 -409.67223) (xy 308.308313 -409.656875)
			(xy 308.362272 -409.649121) (xy 308.389528 -409.64866) (xy 309.253128 -409.64866) (xy 309.280376 -409.649212)
			(xy 309.334316 -409.656971) (xy 309.386603 -409.672327) (xy 309.436172 -409.694968) (xy 309.482015 -409.724433)
			(xy 309.523199 -409.760121) (xy 309.558884 -409.801307) (xy 309.588345 -409.847152) (xy 309.610982 -409.896724)
			(xy 309.626335 -409.949012) (xy 309.63409 -410.002952) (xy 309.63409 -410.057448) (xy 309.634089 -410.057452)
			(xy 311.071746 -410.057452) (xy 311.071746 -410.002948) (xy 311.079502 -409.948998) (xy 311.094857 -409.896702)
			(xy 311.117498 -409.847123) (xy 311.146963 -409.80127) (xy 311.182654 -409.760077) (xy 311.223844 -409.724383)
			(xy 311.269695 -409.694913) (xy 311.319272 -409.672268) (xy 311.371567 -409.656909) (xy 311.425516 -409.649148)
			(xy 311.452768 -409.64866) (xy 312.316368 -409.64866) (xy 312.34362 -409.649185) (xy 312.39757 -409.656938)
			(xy 312.449867 -409.67229) (xy 312.499447 -409.694928) (xy 312.545301 -409.724393) (xy 312.586494 -409.760084)
			(xy 312.622188 -409.801274) (xy 312.651656 -409.847125) (xy 312.674299 -409.896703) (xy 312.689655 -409.948999)
			(xy 312.697413 -410.002948) (xy 312.697413 -410.057452) (xy 312.697412 -410.057456) (xy 314.134923 -410.057456)
			(xy 314.134923 -410.002944) (xy 314.142681 -409.948988) (xy 314.158039 -409.896685) (xy 314.180684 -409.8471)
			(xy 314.210155 -409.801243) (xy 314.245852 -409.760047) (xy 314.287049 -409.72435) (xy 314.332907 -409.69488)
			(xy 314.382493 -409.672236) (xy 314.434796 -409.656879) (xy 314.488752 -409.649122) (xy 314.516008 -409.64866)
			(xy 315.379608 -409.64866) (xy 315.406857 -409.649211) (xy 315.460799 -409.656968) (xy 315.513088 -409.672322)
			(xy 315.56266 -409.694962) (xy 315.608506 -409.724426) (xy 315.649691 -409.760114) (xy 315.685379 -409.801301)
			(xy 315.714842 -409.847147) (xy 315.737481 -409.896719) (xy 315.752834 -409.949009) (xy 315.76059 -410.002951)
			(xy 315.76059 -410.057449) (xy 315.760589 -410.057457) (xy 317.198123 -410.057457) (xy 317.198123 -410.002943)
			(xy 317.205882 -409.948983) (xy 317.221242 -409.896677) (xy 317.24389 -409.847089) (xy 317.273365 -409.80123)
			(xy 317.309066 -409.760033) (xy 317.350268 -409.724336) (xy 317.396131 -409.694867) (xy 317.445722 -409.672225)
			(xy 317.49803 -409.656872) (xy 317.551991 -409.64912) (xy 317.579248 -409.64866) (xy 318.442848 -409.64866)
			(xy 318.470095 -409.649213) (xy 318.524033 -409.656975) (xy 318.576317 -409.672333) (xy 318.625884 -409.694975)
			(xy 318.671725 -409.72444) (xy 318.712906 -409.760128) (xy 318.748589 -409.801314) (xy 318.778048 -409.847158)
			(xy 318.800684 -409.896728) (xy 318.816035 -409.949014) (xy 318.82379 -410.002953) (xy 318.82379 -410.057447)
			(xy 318.823789 -410.057453) (xy 320.261446 -410.057453) (xy 320.261446 -410.002947) (xy 320.269203 -409.948996)
			(xy 320.284558 -409.896698) (xy 320.307201 -409.847117) (xy 320.336668 -409.801263) (xy 320.372362 -409.76007)
			(xy 320.413554 -409.724375) (xy 320.459407 -409.694906) (xy 320.508986 -409.672263) (xy 320.561284 -409.656905)
			(xy 320.615235 -409.649147) (xy 320.642488 -409.64866) (xy 321.506088 -409.64866) (xy 321.533339 -409.649186)
			(xy 321.587287 -409.656941) (xy 321.639582 -409.672295) (xy 321.689159 -409.694935) (xy 321.73501 -409.7244)
			(xy 321.776201 -409.760091) (xy 321.811893 -409.80128) (xy 321.841359 -409.84713) (xy 321.864001 -409.896707)
			(xy 321.879356 -409.949001) (xy 321.887113 -410.002949) (xy 321.887113 -410.057451) (xy 321.887112 -410.057456)
			(xy 323.324623 -410.057456) (xy 323.324623 -410.002944) (xy 323.332381 -409.948986) (xy 323.34774 -409.896681)
			(xy 323.370387 -409.847095) (xy 323.39986 -409.801236) (xy 323.435559 -409.76004) (xy 323.476759 -409.724343)
			(xy 323.522619 -409.694873) (xy 323.572207 -409.67223) (xy 323.624513 -409.656875) (xy 323.678472 -409.649121)
			(xy 323.705728 -409.64866) (xy 324.569328 -409.64866) (xy 324.596576 -409.649212) (xy 324.650516 -409.656971)
			(xy 324.702803 -409.672327) (xy 324.752372 -409.694968) (xy 324.798215 -409.724433) (xy 324.839399 -409.760121)
			(xy 324.875084 -409.801307) (xy 324.904545 -409.847152) (xy 324.927182 -409.896724) (xy 324.942535 -409.949012)
			(xy 324.95029 -410.002952) (xy 324.95029 -410.057448) (xy 324.950289 -410.057452) (xy 326.387946 -410.057452)
			(xy 326.387946 -410.002948) (xy 326.395702 -409.948998) (xy 326.411057 -409.896702) (xy 326.433698 -409.847123)
			(xy 326.463163 -409.80127) (xy 326.498854 -409.760077) (xy 326.540044 -409.724383) (xy 326.585895 -409.694913)
			(xy 326.635472 -409.672268) (xy 326.687767 -409.656909) (xy 326.741716 -409.649148) (xy 326.768968 -409.64866)
			(xy 327.632568 -409.64866) (xy 327.65982 -409.649185) (xy 327.71377 -409.656938) (xy 327.766067 -409.67229)
			(xy 327.815647 -409.694928) (xy 327.861501 -409.724393) (xy 327.902694 -409.760084) (xy 327.938388 -409.801274)
			(xy 327.967856 -409.847125) (xy 327.990499 -409.896703) (xy 328.005855 -409.948999) (xy 328.013613 -410.002948)
			(xy 328.013613 -410.057452) (xy 328.013612 -410.057456) (xy 329.451123 -410.057456) (xy 329.451123 -410.002944)
			(xy 329.458881 -409.948988) (xy 329.474239 -409.896685) (xy 329.496884 -409.8471) (xy 329.526355 -409.801243)
			(xy 329.562052 -409.760047) (xy 329.603249 -409.72435) (xy 329.649107 -409.69488) (xy 329.698693 -409.672236)
			(xy 329.750996 -409.656879) (xy 329.804952 -409.649122) (xy 329.832208 -409.64866) (xy 330.695808 -409.64866)
			(xy 330.723057 -409.649211) (xy 330.776999 -409.656968) (xy 330.829288 -409.672322) (xy 330.87886 -409.694962)
			(xy 330.924706 -409.724426) (xy 330.965891 -409.760114) (xy 331.001579 -409.801301) (xy 331.031042 -409.847147)
			(xy 331.053681 -409.896719) (xy 331.069034 -409.949009) (xy 331.07679 -410.002951) (xy 331.07679 -410.057449)
			(xy 331.076789 -410.057457) (xy 332.514323 -410.057457) (xy 332.514323 -410.002943) (xy 332.522082 -409.948983)
			(xy 332.537442 -409.896677) (xy 332.56009 -409.847089) (xy 332.589565 -409.80123) (xy 332.625266 -409.760033)
			(xy 332.666468 -409.724336) (xy 332.712331 -409.694867) (xy 332.761922 -409.672225) (xy 332.81423 -409.656872)
			(xy 332.868191 -409.64912) (xy 332.895448 -409.64866) (xy 333.759048 -409.64866) (xy 333.786295 -409.649213)
			(xy 333.840233 -409.656975) (xy 333.892517 -409.672333) (xy 333.942084 -409.694975) (xy 333.987925 -409.72444)
			(xy 334.029106 -409.760128) (xy 334.064789 -409.801314) (xy 334.094248 -409.847158) (xy 334.116884 -409.896728)
			(xy 334.132235 -409.949014) (xy 334.13999 -410.002953) (xy 334.13999 -410.057447) (xy 334.139989 -410.057453)
			(xy 335.577646 -410.057453) (xy 335.577646 -410.002947) (xy 335.585403 -409.948996) (xy 335.600758 -409.896698)
			(xy 335.623401 -409.847117) (xy 335.652868 -409.801263) (xy 335.688562 -409.76007) (xy 335.729754 -409.724375)
			(xy 335.775607 -409.694906) (xy 335.825186 -409.672263) (xy 335.877484 -409.656905) (xy 335.931435 -409.649147)
			(xy 335.958688 -409.64866) (xy 336.822288 -409.64866) (xy 336.849539 -409.649186) (xy 336.903487 -409.656941)
			(xy 336.955782 -409.672295) (xy 337.005359 -409.694935) (xy 337.05121 -409.7244) (xy 337.092401 -409.760091)
			(xy 337.128093 -409.80128) (xy 337.157559 -409.84713) (xy 337.180201 -409.896707) (xy 337.195556 -409.949001)
			(xy 337.203313 -410.002949) (xy 337.203313 -410.057451) (xy 337.203312 -410.057456) (xy 338.640823 -410.057456)
			(xy 338.640823 -410.002944) (xy 338.648581 -409.948986) (xy 338.66394 -409.896681) (xy 338.686587 -409.847095)
			(xy 338.71606 -409.801236) (xy 338.751759 -409.76004) (xy 338.792959 -409.724343) (xy 338.838819 -409.694873)
			(xy 338.888407 -409.67223) (xy 338.940713 -409.656875) (xy 338.994672 -409.649121) (xy 339.021928 -409.64866)
			(xy 339.885528 -409.64866) (xy 339.912776 -409.649212) (xy 339.966716 -409.656971) (xy 340.019003 -409.672327)
			(xy 340.068572 -409.694968) (xy 340.114415 -409.724433) (xy 340.155599 -409.760121) (xy 340.191284 -409.801307)
			(xy 340.220745 -409.847152) (xy 340.243382 -409.896724) (xy 340.258735 -409.949012) (xy 340.26649 -410.002952)
			(xy 340.26649 -410.057448) (xy 340.266489 -410.057452) (xy 341.704146 -410.057452) (xy 341.704146 -410.002948)
			(xy 341.711902 -409.948998) (xy 341.727257 -409.896702) (xy 341.749898 -409.847123) (xy 341.779363 -409.80127)
			(xy 341.815054 -409.760077) (xy 341.856244 -409.724383) (xy 341.902095 -409.694913) (xy 341.951672 -409.672268)
			(xy 342.003967 -409.656909) (xy 342.057916 -409.649148) (xy 342.085168 -409.64866) (xy 342.948768 -409.64866)
			(xy 342.97602 -409.649185) (xy 343.02997 -409.656938) (xy 343.082267 -409.67229) (xy 343.131847 -409.694928)
			(xy 343.177701 -409.724393) (xy 343.218894 -409.760084) (xy 343.254588 -409.801274) (xy 343.284056 -409.847125)
			(xy 343.306699 -409.896703) (xy 343.322055 -409.948999) (xy 343.329813 -410.002948) (xy 343.329813 -410.057452)
			(xy 343.329812 -410.057456) (xy 344.767323 -410.057456) (xy 344.767323 -410.002944) (xy 344.775081 -409.948988)
			(xy 344.790439 -409.896685) (xy 344.813084 -409.8471) (xy 344.842555 -409.801243) (xy 344.878252 -409.760047)
			(xy 344.919449 -409.72435) (xy 344.965307 -409.69488) (xy 345.014893 -409.672236) (xy 345.067196 -409.656879)
			(xy 345.121152 -409.649122) (xy 345.148408 -409.64866) (xy 346.012008 -409.64866) (xy 346.039257 -409.649211)
			(xy 346.093199 -409.656968) (xy 346.145488 -409.672322) (xy 346.19506 -409.694962) (xy 346.240906 -409.724426)
			(xy 346.282091 -409.760114) (xy 346.317779 -409.801301) (xy 346.347242 -409.847147) (xy 346.369881 -409.896719)
			(xy 346.385234 -409.949009) (xy 346.39299 -410.002951) (xy 346.39299 -410.057449) (xy 346.392989 -410.057457)
			(xy 347.830523 -410.057457) (xy 347.830523 -410.002943) (xy 347.838282 -409.948983) (xy 347.853642 -409.896677)
			(xy 347.87629 -409.847089) (xy 347.905765 -409.80123) (xy 347.941466 -409.760033) (xy 347.982668 -409.724336)
			(xy 348.028531 -409.694867) (xy 348.078122 -409.672225) (xy 348.13043 -409.656872) (xy 348.184391 -409.64912)
			(xy 348.211648 -409.64866) (xy 349.075248 -409.64866) (xy 349.102495 -409.649213) (xy 349.156433 -409.656975)
			(xy 349.208717 -409.672333) (xy 349.258284 -409.694975) (xy 349.304125 -409.72444) (xy 349.345306 -409.760128)
			(xy 349.380989 -409.801314) (xy 349.410448 -409.847158) (xy 349.433084 -409.896728) (xy 349.448435 -409.949014)
			(xy 349.45619 -410.002953) (xy 349.45619 -410.057447) (xy 349.456189 -410.057453) (xy 350.893846 -410.057453)
			(xy 350.893846 -410.002947) (xy 350.901603 -409.948996) (xy 350.916958 -409.896698) (xy 350.939601 -409.847117)
			(xy 350.969068 -409.801263) (xy 351.004762 -409.76007) (xy 351.045954 -409.724375) (xy 351.091807 -409.694906)
			(xy 351.141386 -409.672263) (xy 351.193684 -409.656905) (xy 351.247635 -409.649147) (xy 351.274888 -409.64866)
			(xy 352.138488 -409.64866) (xy 352.165739 -409.649186) (xy 352.219687 -409.656941) (xy 352.271982 -409.672295)
			(xy 352.321559 -409.694935) (xy 352.36741 -409.7244) (xy 352.408601 -409.760091) (xy 352.444293 -409.80128)
			(xy 352.473759 -409.84713) (xy 352.496401 -409.896707) (xy 352.511756 -409.949001) (xy 352.519513 -410.002949)
			(xy 352.519513 -410.057451) (xy 352.519512 -410.057457) (xy 372.388023 -410.057457) (xy 372.388023 -410.002943)
			(xy 372.395781 -409.948985) (xy 372.41114 -409.896681) (xy 372.433787 -409.847094) (xy 372.46326 -409.801236)
			(xy 372.49896 -409.760039) (xy 372.54016 -409.724342) (xy 372.586021 -409.694872) (xy 372.635609 -409.67223)
			(xy 372.687915 -409.656875) (xy 372.741873 -409.649121) (xy 372.76913 -409.64866) (xy 373.63273 -409.64866)
			(xy 373.659978 -409.649212) (xy 373.713917 -409.656972) (xy 373.766204 -409.672328) (xy 373.815773 -409.694969)
			(xy 373.861616 -409.724434) (xy 373.902799 -409.760122) (xy 373.938484 -409.801308) (xy 373.967945 -409.847153)
			(xy 373.990583 -409.896724) (xy 374.005935 -409.949012) (xy 374.01369 -410.002952) (xy 374.01369 -410.057448)
			(xy 374.013689 -410.057452) (xy 375.451346 -410.057452) (xy 375.451346 -410.002948) (xy 375.459102 -409.948998)
			(xy 375.474457 -409.896701) (xy 375.497098 -409.847122) (xy 375.526564 -409.801269) (xy 375.562255 -409.760076)
			(xy 375.603445 -409.724382) (xy 375.649296 -409.694912) (xy 375.698873 -409.672268) (xy 375.751169 -409.656909)
			(xy 375.805118 -409.649148) (xy 375.83237 -409.64866) (xy 376.69597 -409.64866) (xy 376.723222 -409.649185)
			(xy 376.777172 -409.656938) (xy 376.829469 -409.67229) (xy 376.879048 -409.694929) (xy 376.924901 -409.724394)
			(xy 376.966094 -409.760084) (xy 377.001788 -409.801274) (xy 377.031257 -409.847125) (xy 377.053899 -409.896703)
			(xy 377.069256 -409.948999) (xy 377.077013 -410.002948) (xy 377.077013 -410.057452) (xy 377.077012 -410.057456)
			(xy 378.514523 -410.057456) (xy 378.514523 -410.002944) (xy 378.522281 -409.948988) (xy 378.537639 -409.896685)
			(xy 378.560284 -409.8471) (xy 378.589755 -409.801242) (xy 378.625453 -409.760046) (xy 378.66665 -409.724349)
			(xy 378.712509 -409.694879) (xy 378.762094 -409.672235) (xy 378.814398 -409.656879) (xy 378.868354 -409.649122)
			(xy 378.89561 -409.64866) (xy 379.75921 -409.64866) (xy 379.786458 -409.649211) (xy 379.840401 -409.656968)
			(xy 379.89269 -409.672323) (xy 379.942261 -409.694962) (xy 379.988107 -409.724426) (xy 380.029292 -409.760115)
			(xy 380.06498 -409.801301) (xy 380.094442 -409.847147) (xy 380.117081 -409.89672) (xy 380.132434 -409.949009)
			(xy 380.14019 -410.002952) (xy 380.14019 -410.057448) (xy 380.14019 -410.057451) (xy 381.577846 -410.057451)
			(xy 381.577846 -410.002949) (xy 381.585602 -409.949001) (xy 381.600955 -409.896706) (xy 381.623595 -409.847128)
			(xy 381.653059 -409.801276) (xy 381.688748 -409.760083) (xy 381.729936 -409.724389) (xy 381.775784 -409.694919)
			(xy 381.825359 -409.672273) (xy 381.877652 -409.656912) (xy 381.931599 -409.649149) (xy 381.95885 -409.64866)
			(xy 382.82245 -409.64866) (xy 382.849703 -409.649184) (xy 382.903655 -409.656934) (xy 382.955954 -409.672285)
			(xy 383.005536 -409.694923) (xy 383.051392 -409.724387) (xy 383.092587 -409.760077) (xy 383.128283 -409.801268)
			(xy 383.157753 -409.84712) (xy 383.180398 -409.896699) (xy 383.195755 -409.948996) (xy 383.203513 -410.002947)
			(xy 383.203513 -410.057453) (xy 384.641046 -410.057453) (xy 384.641046 -410.002947) (xy 384.648803 -409.948996)
			(xy 384.664159 -409.896697) (xy 384.686801 -409.847117) (xy 384.716269 -409.801263) (xy 384.751962 -409.760069)
			(xy 384.793155 -409.724375) (xy 384.839008 -409.694906) (xy 384.888588 -409.672262) (xy 384.940886 -409.656905)
			(xy 384.994837 -409.649147) (xy 385.02209 -409.64866) (xy 385.88569 -409.64866) (xy 385.912941 -409.649187)
			(xy 385.966889 -409.656942) (xy 386.019183 -409.672296) (xy 386.06876 -409.694936) (xy 386.114611 -409.724401)
			(xy 386.155801 -409.760092) (xy 386.191493 -409.801281) (xy 386.22096 -409.847131) (xy 386.243601 -409.896707)
			(xy 386.258956 -409.949002) (xy 386.266713 -410.002949) (xy 386.266713 -410.057451) (xy 386.266712 -410.057457)
			(xy 387.704223 -410.057457) (xy 387.704223 -410.002943) (xy 387.711981 -409.948985) (xy 387.72734 -409.896681)
			(xy 387.749987 -409.847094) (xy 387.77946 -409.801236) (xy 387.81516 -409.760039) (xy 387.85636 -409.724342)
			(xy 387.902221 -409.694872) (xy 387.951809 -409.67223) (xy 388.004115 -409.656875) (xy 388.058073 -409.649121)
			(xy 388.08533 -409.64866) (xy 388.94893 -409.64866) (xy 388.976178 -409.649212) (xy 389.030117 -409.656972)
			(xy 389.082404 -409.672328) (xy 389.131973 -409.694969) (xy 389.177816 -409.724434) (xy 389.218999 -409.760122)
			(xy 389.254684 -409.801308) (xy 389.284145 -409.847153) (xy 389.306783 -409.896724) (xy 389.322135 -409.949012)
			(xy 389.32989 -410.002952) (xy 389.32989 -410.057448) (xy 389.329889 -410.057452) (xy 390.767546 -410.057452)
			(xy 390.767546 -410.002948) (xy 390.775302 -409.948998) (xy 390.790657 -409.896701) (xy 390.813298 -409.847122)
			(xy 390.842764 -409.801269) (xy 390.878455 -409.760076) (xy 390.919645 -409.724382) (xy 390.965496 -409.694912)
			(xy 391.015073 -409.672268) (xy 391.067369 -409.656909) (xy 391.121318 -409.649148) (xy 391.14857 -409.64866)
			(xy 392.01217 -409.64866) (xy 392.039422 -409.649185) (xy 392.093372 -409.656938) (xy 392.145669 -409.67229)
			(xy 392.195248 -409.694929) (xy 392.241101 -409.724394) (xy 392.282294 -409.760084) (xy 392.317988 -409.801274)
			(xy 392.347457 -409.847125) (xy 392.370099 -409.896703) (xy 392.385456 -409.948999) (xy 392.393213 -410.002948)
			(xy 392.393213 -410.057452) (xy 392.393212 -410.057456) (xy 393.830723 -410.057456) (xy 393.830723 -410.002944)
			(xy 393.838481 -409.948988) (xy 393.853839 -409.896685) (xy 393.876484 -409.8471) (xy 393.905955 -409.801242)
			(xy 393.941653 -409.760046) (xy 393.98285 -409.724349) (xy 394.028709 -409.694879) (xy 394.078294 -409.672235)
			(xy 394.130598 -409.656879) (xy 394.184554 -409.649122) (xy 394.21181 -409.64866) (xy 395.07541 -409.64866)
			(xy 395.102658 -409.649211) (xy 395.156601 -409.656968) (xy 395.20889 -409.672323) (xy 395.258461 -409.694962)
			(xy 395.304307 -409.724426) (xy 395.345492 -409.760115) (xy 395.38118 -409.801301) (xy 395.410642 -409.847147)
			(xy 395.433281 -409.89672) (xy 395.448634 -409.949009) (xy 395.45639 -410.002952) (xy 395.45639 -410.057448)
			(xy 395.45639 -410.057451) (xy 396.894046 -410.057451) (xy 396.894046 -410.002949) (xy 396.901802 -409.949001)
			(xy 396.917155 -409.896706) (xy 396.939795 -409.847128) (xy 396.969259 -409.801276) (xy 397.004948 -409.760083)
			(xy 397.046136 -409.724389) (xy 397.091984 -409.694919) (xy 397.141559 -409.672273) (xy 397.193852 -409.656912)
			(xy 397.247799 -409.649149) (xy 397.27505 -409.64866) (xy 398.13865 -409.64866) (xy 398.165903 -409.649184)
			(xy 398.219855 -409.656934) (xy 398.272154 -409.672285) (xy 398.321736 -409.694923) (xy 398.367592 -409.724387)
			(xy 398.408787 -409.760077) (xy 398.444483 -409.801268) (xy 398.473953 -409.84712) (xy 398.496598 -409.896699)
			(xy 398.511955 -409.948996) (xy 398.519713 -410.002947) (xy 398.519713 -410.057453) (xy 399.957246 -410.057453)
			(xy 399.957246 -410.002947) (xy 399.965003 -409.948996) (xy 399.980359 -409.896697) (xy 400.003001 -409.847117)
			(xy 400.032469 -409.801263) (xy 400.068162 -409.760069) (xy 400.109355 -409.724375) (xy 400.155208 -409.694906)
			(xy 400.204788 -409.672262) (xy 400.257086 -409.656905) (xy 400.311037 -409.649147) (xy 400.33829 -409.64866)
			(xy 401.20189 -409.64866) (xy 401.229141 -409.649187) (xy 401.283089 -409.656942) (xy 401.335383 -409.672296)
			(xy 401.38496 -409.694936) (xy 401.430811 -409.724401) (xy 401.472001 -409.760092) (xy 401.507693 -409.801281)
			(xy 401.53716 -409.847131) (xy 401.559801 -409.896707) (xy 401.575156 -409.949002) (xy 401.582913 -410.002949)
			(xy 401.582913 -410.057451) (xy 401.582912 -410.057457) (xy 403.020423 -410.057457) (xy 403.020423 -410.002943)
			(xy 403.028181 -409.948985) (xy 403.04354 -409.896681) (xy 403.066187 -409.847094) (xy 403.09566 -409.801236)
			(xy 403.13136 -409.760039) (xy 403.17256 -409.724342) (xy 403.218421 -409.694872) (xy 403.268009 -409.67223)
			(xy 403.320315 -409.656875) (xy 403.374273 -409.649121) (xy 403.40153 -409.64866) (xy 404.26513 -409.64866)
			(xy 404.292378 -409.649212) (xy 404.346317 -409.656972) (xy 404.398604 -409.672328) (xy 404.448173 -409.694969)
			(xy 404.494016 -409.724434) (xy 404.535199 -409.760122) (xy 404.570884 -409.801308) (xy 404.600345 -409.847153)
			(xy 404.622983 -409.896724) (xy 404.638335 -409.949012) (xy 404.64609 -410.002952) (xy 404.64609 -410.057448)
			(xy 404.646089 -410.057452) (xy 406.083746 -410.057452) (xy 406.083746 -410.002948) (xy 406.091502 -409.948998)
			(xy 406.106857 -409.896701) (xy 406.129498 -409.847122) (xy 406.158964 -409.801269) (xy 406.194655 -409.760076)
			(xy 406.235845 -409.724382) (xy 406.281696 -409.694912) (xy 406.331273 -409.672268) (xy 406.383569 -409.656909)
			(xy 406.437518 -409.649148) (xy 406.46477 -409.64866) (xy 407.32837 -409.64866) (xy 407.355622 -409.649185)
			(xy 407.409572 -409.656938) (xy 407.461869 -409.67229) (xy 407.511448 -409.694929) (xy 407.557301 -409.724394)
			(xy 407.598494 -409.760084) (xy 407.634188 -409.801274) (xy 407.663657 -409.847125) (xy 407.686299 -409.896703)
			(xy 407.701656 -409.948999) (xy 407.709413 -410.002948) (xy 407.709413 -410.057452) (xy 407.709412 -410.057456)
			(xy 409.146923 -410.057456) (xy 409.146923 -410.002944) (xy 409.154681 -409.948988) (xy 409.170039 -409.896685)
			(xy 409.192684 -409.8471) (xy 409.222155 -409.801242) (xy 409.257853 -409.760046) (xy 409.29905 -409.724349)
			(xy 409.344909 -409.694879) (xy 409.394494 -409.672235) (xy 409.446798 -409.656879) (xy 409.500754 -409.649122)
			(xy 409.52801 -409.64866) (xy 410.39161 -409.64866) (xy 410.418858 -409.649211) (xy 410.472801 -409.656968)
			(xy 410.52509 -409.672323) (xy 410.574661 -409.694962) (xy 410.620507 -409.724426) (xy 410.661692 -409.760115)
			(xy 410.69738 -409.801301) (xy 410.726842 -409.847147) (xy 410.749481 -409.89672) (xy 410.764834 -409.949009)
			(xy 410.77259 -410.002952) (xy 410.77259 -410.057448) (xy 410.77259 -410.057451) (xy 412.210246 -410.057451)
			(xy 412.210246 -410.002949) (xy 412.218002 -409.949001) (xy 412.233355 -409.896706) (xy 412.255995 -409.847128)
			(xy 412.285459 -409.801276) (xy 412.321148 -409.760083) (xy 412.362336 -409.724389) (xy 412.408184 -409.694919)
			(xy 412.457759 -409.672273) (xy 412.510052 -409.656912) (xy 412.563999 -409.649149) (xy 412.59125 -409.64866)
			(xy 413.45485 -409.64866) (xy 413.482103 -409.649184) (xy 413.536055 -409.656934) (xy 413.588354 -409.672285)
			(xy 413.637936 -409.694923) (xy 413.683792 -409.724387) (xy 413.724987 -409.760077) (xy 413.760683 -409.801268)
			(xy 413.790153 -409.84712) (xy 413.812798 -409.896699) (xy 413.828155 -409.948996) (xy 413.835913 -410.002947)
			(xy 413.835913 -410.057453) (xy 415.273446 -410.057453) (xy 415.273446 -410.002947) (xy 415.281203 -409.948996)
			(xy 415.296559 -409.896697) (xy 415.319201 -409.847117) (xy 415.348669 -409.801263) (xy 415.384362 -409.760069)
			(xy 415.425555 -409.724375) (xy 415.471408 -409.694906) (xy 415.520988 -409.672262) (xy 415.573286 -409.656905)
			(xy 415.627237 -409.649147) (xy 415.65449 -409.64866) (xy 416.51809 -409.64866) (xy 416.545341 -409.649187)
			(xy 416.599289 -409.656942) (xy 416.651583 -409.672296) (xy 416.70116 -409.694936) (xy 416.747011 -409.724401)
			(xy 416.788201 -409.760092) (xy 416.823893 -409.801281) (xy 416.85336 -409.847131) (xy 416.876001 -409.896707)
			(xy 416.891356 -409.949002) (xy 416.899113 -410.002949) (xy 416.899113 -410.057451) (xy 416.899112 -410.057457)
			(xy 418.336623 -410.057457) (xy 418.336623 -410.002943) (xy 418.344381 -409.948985) (xy 418.35974 -409.896681)
			(xy 418.382387 -409.847094) (xy 418.41186 -409.801236) (xy 418.44756 -409.760039) (xy 418.48876 -409.724342)
			(xy 418.534621 -409.694872) (xy 418.584209 -409.67223) (xy 418.636515 -409.656875) (xy 418.690473 -409.649121)
			(xy 418.71773 -409.64866) (xy 419.58133 -409.64866) (xy 419.608578 -409.649212) (xy 419.662517 -409.656972)
			(xy 419.714804 -409.672328) (xy 419.764373 -409.694969) (xy 419.810216 -409.724434) (xy 419.851399 -409.760122)
			(xy 419.887084 -409.801308) (xy 419.916545 -409.847153) (xy 419.939183 -409.896724) (xy 419.954535 -409.949012)
			(xy 419.96229 -410.002952) (xy 419.96229 -410.057448) (xy 419.954535 -410.111388) (xy 419.939183 -410.163676)
			(xy 419.916545 -410.213247) (xy 419.887084 -410.259092) (xy 419.851399 -410.300278) (xy 419.810216 -410.335966)
			(xy 419.764373 -410.365431) (xy 419.714804 -410.388072) (xy 419.662517 -410.403428) (xy 419.608578 -410.411188)
			(xy 419.58133 -410.411676) (xy 418.71773 -410.411676) (xy 418.690473 -410.411279) (xy 418.636515 -410.403525)
			(xy 418.584209 -410.38817) (xy 418.534621 -410.365528) (xy 418.48876 -410.336058) (xy 418.44756 -410.300361)
			(xy 418.41186 -410.259164) (xy 418.382387 -410.213306) (xy 418.35974 -410.163719) (xy 418.344381 -410.111415)
			(xy 418.336623 -410.057457) (xy 416.899112 -410.057457) (xy 416.891356 -410.111398) (xy 416.876001 -410.163693)
			(xy 416.85336 -410.213269) (xy 416.823893 -410.259119) (xy 416.788201 -410.300308) (xy 416.747011 -410.335999)
			(xy 416.70116 -410.365464) (xy 416.651583 -410.388104) (xy 416.599289 -410.403458) (xy 416.545341 -410.411213)
			(xy 416.51809 -410.411676) (xy 415.65449 -410.411676) (xy 415.627237 -410.411253) (xy 415.573286 -410.403495)
			(xy 415.520988 -410.388138) (xy 415.471408 -410.365494) (xy 415.425555 -410.336025) (xy 415.384362 -410.300331)
			(xy 415.348669 -410.259137) (xy 415.319201 -410.213283) (xy 415.296559 -410.163703) (xy 415.281203 -410.111404)
			(xy 415.273446 -410.057453) (xy 413.835913 -410.057453) (xy 413.828155 -410.111404) (xy 413.812798 -410.163701)
			(xy 413.790153 -410.21328) (xy 413.760683 -410.259132) (xy 413.724987 -410.300323) (xy 413.683792 -410.336013)
			(xy 413.637936 -410.365477) (xy 413.588354 -410.388115) (xy 413.536055 -410.403466) (xy 413.482103 -410.411216)
			(xy 413.45485 -410.411676) (xy 412.59125 -410.411676) (xy 412.563999 -410.411251) (xy 412.510052 -410.403488)
			(xy 412.457759 -410.388127) (xy 412.408184 -410.365481) (xy 412.362336 -410.336011) (xy 412.321148 -410.300317)
			(xy 412.285459 -410.259124) (xy 412.255995 -410.213272) (xy 412.233355 -410.163694) (xy 412.218002 -410.111399)
			(xy 412.210246 -410.057451) (xy 410.77259 -410.057451) (xy 410.764834 -410.111391) (xy 410.749481 -410.16368)
			(xy 410.726842 -410.213253) (xy 410.69738 -410.259099) (xy 410.661692 -410.300285) (xy 410.620507 -410.335974)
			(xy 410.574661 -410.365438) (xy 410.52509 -410.388077) (xy 410.472801 -410.403432) (xy 410.418858 -410.411189)
			(xy 410.39161 -410.411676) (xy 409.52801 -410.411676) (xy 409.500754 -410.411278) (xy 409.446798 -410.403521)
			(xy 409.394494 -410.388165) (xy 409.344909 -410.365521) (xy 409.29905 -410.336051) (xy 409.257853 -410.300354)
			(xy 409.222155 -410.259158) (xy 409.192684 -410.2133) (xy 409.170039 -410.163715) (xy 409.154681 -410.111412)
			(xy 409.146923 -410.057456) (xy 407.709412 -410.057456) (xy 407.701656 -410.111401) (xy 407.686299 -410.163697)
			(xy 407.663657 -410.213275) (xy 407.634188 -410.259126) (xy 407.598494 -410.300316) (xy 407.557301 -410.336006)
			(xy 407.511448 -410.365471) (xy 407.461869 -410.38811) (xy 407.409572 -410.403462) (xy 407.355622 -410.411215)
			(xy 407.32837 -410.411676) (xy 406.46477 -410.411676) (xy 406.437518 -410.411252) (xy 406.383569 -410.403491)
			(xy 406.331273 -410.388132) (xy 406.281696 -410.365488) (xy 406.235845 -410.336018) (xy 406.194655 -410.300324)
			(xy 406.158964 -410.259131) (xy 406.129498 -410.213278) (xy 406.106857 -410.163699) (xy 406.091502 -410.111402)
			(xy 406.083746 -410.057452) (xy 404.646089 -410.057452) (xy 404.638335 -410.111388) (xy 404.622983 -410.163676)
			(xy 404.600345 -410.213247) (xy 404.570884 -410.259092) (xy 404.535199 -410.300278) (xy 404.494016 -410.335966)
			(xy 404.448173 -410.365431) (xy 404.398604 -410.388072) (xy 404.346317 -410.403428) (xy 404.292378 -410.411188)
			(xy 404.26513 -410.411676) (xy 403.40153 -410.411676) (xy 403.374273 -410.411279) (xy 403.320315 -410.403525)
			(xy 403.268009 -410.38817) (xy 403.218421 -410.365528) (xy 403.17256 -410.336058) (xy 403.13136 -410.300361)
			(xy 403.09566 -410.259164) (xy 403.066187 -410.213306) (xy 403.04354 -410.163719) (xy 403.028181 -410.111415)
			(xy 403.020423 -410.057457) (xy 401.582912 -410.057457) (xy 401.575156 -410.111398) (xy 401.559801 -410.163693)
			(xy 401.53716 -410.213269) (xy 401.507693 -410.259119) (xy 401.472001 -410.300308) (xy 401.430811 -410.335999)
			(xy 401.38496 -410.365464) (xy 401.335383 -410.388104) (xy 401.283089 -410.403458) (xy 401.229141 -410.411213)
			(xy 401.20189 -410.411676) (xy 400.33829 -410.411676) (xy 400.311037 -410.411253) (xy 400.257086 -410.403495)
			(xy 400.204788 -410.388138) (xy 400.155208 -410.365494) (xy 400.109355 -410.336025) (xy 400.068162 -410.300331)
			(xy 400.032469 -410.259137) (xy 400.003001 -410.213283) (xy 399.980359 -410.163703) (xy 399.965003 -410.111404)
			(xy 399.957246 -410.057453) (xy 398.519713 -410.057453) (xy 398.511955 -410.111404) (xy 398.496598 -410.163701)
			(xy 398.473953 -410.21328) (xy 398.444483 -410.259132) (xy 398.408787 -410.300323) (xy 398.367592 -410.336013)
			(xy 398.321736 -410.365477) (xy 398.272154 -410.388115) (xy 398.219855 -410.403466) (xy 398.165903 -410.411216)
			(xy 398.13865 -410.411676) (xy 397.27505 -410.411676) (xy 397.247799 -410.411251) (xy 397.193852 -410.403488)
			(xy 397.141559 -410.388127) (xy 397.091984 -410.365481) (xy 397.046136 -410.336011) (xy 397.004948 -410.300317)
			(xy 396.969259 -410.259124) (xy 396.939795 -410.213272) (xy 396.917155 -410.163694) (xy 396.901802 -410.111399)
			(xy 396.894046 -410.057451) (xy 395.45639 -410.057451) (xy 395.448634 -410.111391) (xy 395.433281 -410.16368)
			(xy 395.410642 -410.213253) (xy 395.38118 -410.259099) (xy 395.345492 -410.300285) (xy 395.304307 -410.335974)
			(xy 395.258461 -410.365438) (xy 395.20889 -410.388077) (xy 395.156601 -410.403432) (xy 395.102658 -410.411189)
			(xy 395.07541 -410.411676) (xy 394.21181 -410.411676) (xy 394.184554 -410.411278) (xy 394.130598 -410.403521)
			(xy 394.078294 -410.388165) (xy 394.028709 -410.365521) (xy 393.98285 -410.336051) (xy 393.941653 -410.300354)
			(xy 393.905955 -410.259158) (xy 393.876484 -410.2133) (xy 393.853839 -410.163715) (xy 393.838481 -410.111412)
			(xy 393.830723 -410.057456) (xy 392.393212 -410.057456) (xy 392.385456 -410.111401) (xy 392.370099 -410.163697)
			(xy 392.347457 -410.213275) (xy 392.317988 -410.259126) (xy 392.282294 -410.300316) (xy 392.241101 -410.336006)
			(xy 392.195248 -410.365471) (xy 392.145669 -410.38811) (xy 392.093372 -410.403462) (xy 392.039422 -410.411215)
			(xy 392.01217 -410.411676) (xy 391.14857 -410.411676) (xy 391.121318 -410.411252) (xy 391.067369 -410.403491)
			(xy 391.015073 -410.388132) (xy 390.965496 -410.365488) (xy 390.919645 -410.336018) (xy 390.878455 -410.300324)
			(xy 390.842764 -410.259131) (xy 390.813298 -410.213278) (xy 390.790657 -410.163699) (xy 390.775302 -410.111402)
			(xy 390.767546 -410.057452) (xy 389.329889 -410.057452) (xy 389.322135 -410.111388) (xy 389.306783 -410.163676)
			(xy 389.284145 -410.213247) (xy 389.254684 -410.259092) (xy 389.218999 -410.300278) (xy 389.177816 -410.335966)
			(xy 389.131973 -410.365431) (xy 389.082404 -410.388072) (xy 389.030117 -410.403428) (xy 388.976178 -410.411188)
			(xy 388.94893 -410.411676) (xy 388.08533 -410.411676) (xy 388.058073 -410.411279) (xy 388.004115 -410.403525)
			(xy 387.951809 -410.38817) (xy 387.902221 -410.365528) (xy 387.85636 -410.336058) (xy 387.81516 -410.300361)
			(xy 387.77946 -410.259164) (xy 387.749987 -410.213306) (xy 387.72734 -410.163719) (xy 387.711981 -410.111415)
			(xy 387.704223 -410.057457) (xy 386.266712 -410.057457) (xy 386.258956 -410.111398) (xy 386.243601 -410.163693)
			(xy 386.22096 -410.213269) (xy 386.191493 -410.259119) (xy 386.155801 -410.300308) (xy 386.114611 -410.335999)
			(xy 386.06876 -410.365464) (xy 386.019183 -410.388104) (xy 385.966889 -410.403458) (xy 385.912941 -410.411213)
			(xy 385.88569 -410.411676) (xy 385.02209 -410.411676) (xy 384.994837 -410.411253) (xy 384.940886 -410.403495)
			(xy 384.888588 -410.388138) (xy 384.839008 -410.365494) (xy 384.793155 -410.336025) (xy 384.751962 -410.300331)
			(xy 384.716269 -410.259137) (xy 384.686801 -410.213283) (xy 384.664159 -410.163703) (xy 384.648803 -410.111404)
			(xy 384.641046 -410.057453) (xy 383.203513 -410.057453) (xy 383.195755 -410.111404) (xy 383.180398 -410.163701)
			(xy 383.157753 -410.21328) (xy 383.128283 -410.259132) (xy 383.092587 -410.300323) (xy 383.051392 -410.336013)
			(xy 383.005536 -410.365477) (xy 382.955954 -410.388115) (xy 382.903655 -410.403466) (xy 382.849703 -410.411216)
			(xy 382.82245 -410.411676) (xy 381.95885 -410.411676) (xy 381.931599 -410.411251) (xy 381.877652 -410.403488)
			(xy 381.825359 -410.388127) (xy 381.775784 -410.365481) (xy 381.729936 -410.336011) (xy 381.688748 -410.300317)
			(xy 381.653059 -410.259124) (xy 381.623595 -410.213272) (xy 381.600955 -410.163694) (xy 381.585602 -410.111399)
			(xy 381.577846 -410.057451) (xy 380.14019 -410.057451) (xy 380.132434 -410.111391) (xy 380.117081 -410.16368)
			(xy 380.094442 -410.213253) (xy 380.06498 -410.259099) (xy 380.029292 -410.300285) (xy 379.988107 -410.335974)
			(xy 379.942261 -410.365438) (xy 379.89269 -410.388077) (xy 379.840401 -410.403432) (xy 379.786458 -410.411189)
			(xy 379.75921 -410.411676) (xy 378.89561 -410.411676) (xy 378.868354 -410.411278) (xy 378.814398 -410.403521)
			(xy 378.762094 -410.388165) (xy 378.712509 -410.365521) (xy 378.66665 -410.336051) (xy 378.625453 -410.300354)
			(xy 378.589755 -410.259158) (xy 378.560284 -410.2133) (xy 378.537639 -410.163715) (xy 378.522281 -410.111412)
			(xy 378.514523 -410.057456) (xy 377.077012 -410.057456) (xy 377.069256 -410.111401) (xy 377.053899 -410.163697)
			(xy 377.031257 -410.213275) (xy 377.001788 -410.259126) (xy 376.966094 -410.300316) (xy 376.924901 -410.336006)
			(xy 376.879048 -410.365471) (xy 376.829469 -410.38811) (xy 376.777172 -410.403462) (xy 376.723222 -410.411215)
			(xy 376.69597 -410.411676) (xy 375.83237 -410.411676) (xy 375.805118 -410.411252) (xy 375.751169 -410.403491)
			(xy 375.698873 -410.388132) (xy 375.649296 -410.365488) (xy 375.603445 -410.336018) (xy 375.562255 -410.300324)
			(xy 375.526564 -410.259131) (xy 375.497098 -410.213278) (xy 375.474457 -410.163699) (xy 375.459102 -410.111402)
			(xy 375.451346 -410.057452) (xy 374.013689 -410.057452) (xy 374.005935 -410.111388) (xy 373.990583 -410.163676)
			(xy 373.967945 -410.213247) (xy 373.938484 -410.259092) (xy 373.902799 -410.300278) (xy 373.861616 -410.335966)
			(xy 373.815773 -410.365431) (xy 373.766204 -410.388072) (xy 373.713917 -410.403428) (xy 373.659978 -410.411188)
			(xy 373.63273 -410.411676) (xy 372.76913 -410.411676) (xy 372.741873 -410.411279) (xy 372.687915 -410.403525)
			(xy 372.635609 -410.38817) (xy 372.586021 -410.365528) (xy 372.54016 -410.336058) (xy 372.49896 -410.300361)
			(xy 372.46326 -410.259164) (xy 372.433787 -410.213306) (xy 372.41114 -410.163719) (xy 372.395781 -410.111415)
			(xy 372.388023 -410.057457) (xy 352.519512 -410.057457) (xy 352.511756 -410.111399) (xy 352.496401 -410.163693)
			(xy 352.473759 -410.21327) (xy 352.444293 -410.25912) (xy 352.408601 -410.300309) (xy 352.36741 -410.336)
			(xy 352.321559 -410.365465) (xy 352.271982 -410.388105) (xy 352.219687 -410.403459) (xy 352.165739 -410.411214)
			(xy 352.138488 -410.411676) (xy 351.274888 -410.411676) (xy 351.247635 -410.411253) (xy 351.193684 -410.403495)
			(xy 351.141386 -410.388137) (xy 351.091807 -410.365494) (xy 351.045954 -410.336025) (xy 351.004762 -410.30033)
			(xy 350.969068 -410.259137) (xy 350.939601 -410.213283) (xy 350.916958 -410.163702) (xy 350.901603 -410.111404)
			(xy 350.893846 -410.057453) (xy 349.456189 -410.057453) (xy 349.448435 -410.111386) (xy 349.433084 -410.163672)
			(xy 349.410448 -410.213242) (xy 349.380989 -410.259086) (xy 349.345306 -410.300272) (xy 349.304125 -410.33596)
			(xy 349.258284 -410.365425) (xy 349.208717 -410.388067) (xy 349.156433 -410.403425) (xy 349.102495 -410.411187)
			(xy 349.075248 -410.411676) (xy 348.211648 -410.411676) (xy 348.184391 -410.41128) (xy 348.13043 -410.403528)
			(xy 348.078122 -410.388175) (xy 348.028531 -410.365533) (xy 347.982668 -410.336064) (xy 347.941466 -410.300367)
			(xy 347.905765 -410.25917) (xy 347.87629 -410.213311) (xy 347.853642 -410.163723) (xy 347.838282 -410.111417)
			(xy 347.830523 -410.057457) (xy 346.392989 -410.057457) (xy 346.385234 -410.111391) (xy 346.369881 -410.163681)
			(xy 346.347242 -410.213253) (xy 346.317779 -410.259099) (xy 346.282091 -410.300286) (xy 346.240906 -410.335974)
			(xy 346.19506 -410.365438) (xy 346.145488 -410.388078) (xy 346.093199 -410.403432) (xy 346.039257 -410.411189)
			(xy 346.012008 -410.411676) (xy 345.148408 -410.411676) (xy 345.121152 -410.411278) (xy 345.067196 -410.403521)
			(xy 345.014893 -410.388164) (xy 344.965307 -410.36552) (xy 344.919449 -410.33605) (xy 344.878252 -410.300353)
			(xy 344.842555 -410.259157) (xy 344.813084 -410.2133) (xy 344.790439 -410.163715) (xy 344.775081 -410.111412)
			(xy 344.767323 -410.057456) (xy 343.329812 -410.057456) (xy 343.322055 -410.111401) (xy 343.306699 -410.163697)
			(xy 343.284056 -410.213275) (xy 343.254588 -410.259126) (xy 343.218894 -410.300316) (xy 343.177701 -410.336007)
			(xy 343.131847 -410.365472) (xy 343.082267 -410.38811) (xy 343.02997 -410.403462) (xy 342.97602 -410.411215)
			(xy 342.948768 -410.411676) (xy 342.085168 -410.411676) (xy 342.057916 -410.411252) (xy 342.003967 -410.403491)
			(xy 341.951672 -410.388132) (xy 341.902095 -410.365487) (xy 341.856244 -410.336017) (xy 341.815054 -410.300323)
			(xy 341.779363 -410.25913) (xy 341.749898 -410.213277) (xy 341.727257 -410.163698) (xy 341.711902 -410.111402)
			(xy 341.704146 -410.057452) (xy 340.266489 -410.057452) (xy 340.258735 -410.111388) (xy 340.243382 -410.163676)
			(xy 340.220745 -410.213248) (xy 340.191284 -410.259093) (xy 340.155599 -410.300279) (xy 340.114415 -410.335967)
			(xy 340.068572 -410.365432) (xy 340.019003 -410.388073) (xy 339.966716 -410.403429) (xy 339.912776 -410.411188)
			(xy 339.885528 -410.411676) (xy 339.021928 -410.411676) (xy 338.994672 -410.411279) (xy 338.940713 -410.403525)
			(xy 338.888407 -410.38817) (xy 338.838819 -410.365527) (xy 338.792959 -410.336057) (xy 338.751759 -410.30036)
			(xy 338.71606 -410.259164) (xy 338.686587 -410.213305) (xy 338.66394 -410.163719) (xy 338.648581 -410.111414)
			(xy 338.640823 -410.057456) (xy 337.203312 -410.057456) (xy 337.195556 -410.111399) (xy 337.180201 -410.163693)
			(xy 337.157559 -410.21327) (xy 337.128093 -410.25912) (xy 337.092401 -410.300309) (xy 337.05121 -410.336)
			(xy 337.005359 -410.365465) (xy 336.955782 -410.388105) (xy 336.903487 -410.403459) (xy 336.849539 -410.411214)
			(xy 336.822288 -410.411676) (xy 335.958688 -410.411676) (xy 335.931435 -410.411253) (xy 335.877484 -410.403495)
			(xy 335.825186 -410.388137) (xy 335.775607 -410.365494) (xy 335.729754 -410.336025) (xy 335.688562 -410.30033)
			(xy 335.652868 -410.259137) (xy 335.623401 -410.213283) (xy 335.600758 -410.163702) (xy 335.585403 -410.111404)
			(xy 335.577646 -410.057453) (xy 334.139989 -410.057453) (xy 334.132235 -410.111386) (xy 334.116884 -410.163672)
			(xy 334.094248 -410.213242) (xy 334.064789 -410.259086) (xy 334.029106 -410.300272) (xy 333.987925 -410.33596)
			(xy 333.942084 -410.365425) (xy 333.892517 -410.388067) (xy 333.840233 -410.403425) (xy 333.786295 -410.411187)
			(xy 333.759048 -410.411676) (xy 332.895448 -410.411676) (xy 332.868191 -410.41128) (xy 332.81423 -410.403528)
			(xy 332.761922 -410.388175) (xy 332.712331 -410.365533) (xy 332.666468 -410.336064) (xy 332.625266 -410.300367)
			(xy 332.589565 -410.25917) (xy 332.56009 -410.213311) (xy 332.537442 -410.163723) (xy 332.522082 -410.111417)
			(xy 332.514323 -410.057457) (xy 331.076789 -410.057457) (xy 331.069034 -410.111391) (xy 331.053681 -410.163681)
			(xy 331.031042 -410.213253) (xy 331.001579 -410.259099) (xy 330.965891 -410.300286) (xy 330.924706 -410.335974)
			(xy 330.87886 -410.365438) (xy 330.829288 -410.388078) (xy 330.776999 -410.403432) (xy 330.723057 -410.411189)
			(xy 330.695808 -410.411676) (xy 329.832208 -410.411676) (xy 329.804952 -410.411278) (xy 329.750996 -410.403521)
			(xy 329.698693 -410.388164) (xy 329.649107 -410.36552) (xy 329.603249 -410.33605) (xy 329.562052 -410.300353)
			(xy 329.526355 -410.259157) (xy 329.496884 -410.2133) (xy 329.474239 -410.163715) (xy 329.458881 -410.111412)
			(xy 329.451123 -410.057456) (xy 328.013612 -410.057456) (xy 328.005855 -410.111401) (xy 327.990499 -410.163697)
			(xy 327.967856 -410.213275) (xy 327.938388 -410.259126) (xy 327.902694 -410.300316) (xy 327.861501 -410.336007)
			(xy 327.815647 -410.365472) (xy 327.766067 -410.38811) (xy 327.71377 -410.403462) (xy 327.65982 -410.411215)
			(xy 327.632568 -410.411676) (xy 326.768968 -410.411676) (xy 326.741716 -410.411252) (xy 326.687767 -410.403491)
			(xy 326.635472 -410.388132) (xy 326.585895 -410.365487) (xy 326.540044 -410.336017) (xy 326.498854 -410.300323)
			(xy 326.463163 -410.25913) (xy 326.433698 -410.213277) (xy 326.411057 -410.163698) (xy 326.395702 -410.111402)
			(xy 326.387946 -410.057452) (xy 324.950289 -410.057452) (xy 324.942535 -410.111388) (xy 324.927182 -410.163676)
			(xy 324.904545 -410.213248) (xy 324.875084 -410.259093) (xy 324.839399 -410.300279) (xy 324.798215 -410.335967)
			(xy 324.752372 -410.365432) (xy 324.702803 -410.388073) (xy 324.650516 -410.403429) (xy 324.596576 -410.411188)
			(xy 324.569328 -410.411676) (xy 323.705728 -410.411676) (xy 323.678472 -410.411279) (xy 323.624513 -410.403525)
			(xy 323.572207 -410.38817) (xy 323.522619 -410.365527) (xy 323.476759 -410.336057) (xy 323.435559 -410.30036)
			(xy 323.39986 -410.259164) (xy 323.370387 -410.213305) (xy 323.34774 -410.163719) (xy 323.332381 -410.111414)
			(xy 323.324623 -410.057456) (xy 321.887112 -410.057456) (xy 321.879356 -410.111399) (xy 321.864001 -410.163693)
			(xy 321.841359 -410.21327) (xy 321.811893 -410.25912) (xy 321.776201 -410.300309) (xy 321.73501 -410.336)
			(xy 321.689159 -410.365465) (xy 321.639582 -410.388105) (xy 321.587287 -410.403459) (xy 321.533339 -410.411214)
			(xy 321.506088 -410.411676) (xy 320.642488 -410.411676) (xy 320.615235 -410.411253) (xy 320.561284 -410.403495)
			(xy 320.508986 -410.388137) (xy 320.459407 -410.365494) (xy 320.413554 -410.336025) (xy 320.372362 -410.30033)
			(xy 320.336668 -410.259137) (xy 320.307201 -410.213283) (xy 320.284558 -410.163702) (xy 320.269203 -410.111404)
			(xy 320.261446 -410.057453) (xy 318.823789 -410.057453) (xy 318.816035 -410.111386) (xy 318.800684 -410.163672)
			(xy 318.778048 -410.213242) (xy 318.748589 -410.259086) (xy 318.712906 -410.300272) (xy 318.671725 -410.33596)
			(xy 318.625884 -410.365425) (xy 318.576317 -410.388067) (xy 318.524033 -410.403425) (xy 318.470095 -410.411187)
			(xy 318.442848 -410.411676) (xy 317.579248 -410.411676) (xy 317.551991 -410.41128) (xy 317.49803 -410.403528)
			(xy 317.445722 -410.388175) (xy 317.396131 -410.365533) (xy 317.350268 -410.336064) (xy 317.309066 -410.300367)
			(xy 317.273365 -410.25917) (xy 317.24389 -410.213311) (xy 317.221242 -410.163723) (xy 317.205882 -410.111417)
			(xy 317.198123 -410.057457) (xy 315.760589 -410.057457) (xy 315.752834 -410.111391) (xy 315.737481 -410.163681)
			(xy 315.714842 -410.213253) (xy 315.685379 -410.259099) (xy 315.649691 -410.300286) (xy 315.608506 -410.335974)
			(xy 315.56266 -410.365438) (xy 315.513088 -410.388078) (xy 315.460799 -410.403432) (xy 315.406857 -410.411189)
			(xy 315.379608 -410.411676) (xy 314.516008 -410.411676) (xy 314.488752 -410.411278) (xy 314.434796 -410.403521)
			(xy 314.382493 -410.388164) (xy 314.332907 -410.36552) (xy 314.287049 -410.33605) (xy 314.245852 -410.300353)
			(xy 314.210155 -410.259157) (xy 314.180684 -410.2133) (xy 314.158039 -410.163715) (xy 314.142681 -410.111412)
			(xy 314.134923 -410.057456) (xy 312.697412 -410.057456) (xy 312.689655 -410.111401) (xy 312.674299 -410.163697)
			(xy 312.651656 -410.213275) (xy 312.622188 -410.259126) (xy 312.586494 -410.300316) (xy 312.545301 -410.336007)
			(xy 312.499447 -410.365472) (xy 312.449867 -410.38811) (xy 312.39757 -410.403462) (xy 312.34362 -410.411215)
			(xy 312.316368 -410.411676) (xy 311.452768 -410.411676) (xy 311.425516 -410.411252) (xy 311.371567 -410.403491)
			(xy 311.319272 -410.388132) (xy 311.269695 -410.365487) (xy 311.223844 -410.336017) (xy 311.182654 -410.300323)
			(xy 311.146963 -410.25913) (xy 311.117498 -410.213277) (xy 311.094857 -410.163698) (xy 311.079502 -410.111402)
			(xy 311.071746 -410.057452) (xy 309.634089 -410.057452) (xy 309.626335 -410.111388) (xy 309.610982 -410.163676)
			(xy 309.588345 -410.213248) (xy 309.558884 -410.259093) (xy 309.523199 -410.300279) (xy 309.482015 -410.335967)
			(xy 309.436172 -410.365432) (xy 309.386603 -410.388073) (xy 309.334316 -410.403429) (xy 309.280376 -410.411188)
			(xy 309.253128 -410.411676) (xy 308.389528 -410.411676) (xy 308.362272 -410.411279) (xy 308.308313 -410.403525)
			(xy 308.256007 -410.38817) (xy 308.206419 -410.365527) (xy 308.160559 -410.336057) (xy 308.119359 -410.30036)
			(xy 308.08366 -410.259164) (xy 308.054187 -410.213305) (xy 308.03154 -410.163719) (xy 308.016181 -410.111414)
			(xy 308.008423 -410.057456) (xy 306.570912 -410.057456) (xy 306.563156 -410.111399) (xy 306.547801 -410.163693)
			(xy 306.525159 -410.21327) (xy 306.495693 -410.25912) (xy 306.460001 -410.300309) (xy 306.41881 -410.336)
			(xy 306.372959 -410.365465) (xy 306.323382 -410.388105) (xy 306.271087 -410.403459) (xy 306.217139 -410.411214)
			(xy 306.189888 -410.411676) (xy 305.326288 -410.411676) (xy 305.299035 -410.411253) (xy 305.245084 -410.403495)
			(xy 305.192786 -410.388137) (xy 305.143207 -410.365494) (xy 305.097354 -410.336025) (xy 305.056162 -410.30033)
			(xy 305.020468 -410.259137) (xy 304.991001 -410.213283) (xy 304.968358 -410.163702) (xy 304.953003 -410.111404)
			(xy 304.945246 -410.057453) (xy 280.83256 -410.057453) (xy 280.83256 -415.172652) (xy 280.832075 -415.197601)
			(xy 280.824257 -415.246884) (xy 280.808837 -415.294341) (xy 280.786193 -415.338807) (xy 280.756881 -415.37919)
			(xy 280.739596 -415.397188) (xy 280.152348 -415.984436) (xy 280.134386 -416.001764) (xy 280.094003 -416.03109)
			(xy 280.04953 -416.053738) (xy 280.002061 -416.069148) (xy 279.952766 -416.076943) (xy 279.927812 -416.0774)
			(xy 275.812504 -416.0774) (xy 270.706088 -421.183816) (xy 270.688105 -421.201119) (xy 270.647725 -421.230441)
			(xy 270.603256 -421.253086) (xy 270.555793 -421.268497) (xy 270.506503 -421.276295) (xy 270.481552 -421.27678)
			(xy 233.339132 -421.27678) (xy 231.01554 -423.600372) (xy 231.01554 -424.804386) (xy 357.679233 -424.804386)
			(xy 357.679233 -424.675246) (xy 357.687183 -424.546351) (xy 357.703053 -424.418191) (xy 357.726782 -424.29125)
			(xy 357.758281 -424.166011) (xy 357.79743 -424.042948) (xy 357.844081 -423.922529) (xy 357.898056 -423.80521)
			(xy 357.959151 -423.691436) (xy 358.027134 -423.581639) (xy 358.101748 -423.476236) (xy 358.182709 -423.375626)
			(xy 358.269709 -423.280191) (xy 358.36242 -423.190292) (xy 358.46049 -423.106271) (xy 358.563545 -423.028447)
			(xy 358.671196 -422.957115) (xy 358.783035 -422.892545) (xy 358.898636 -422.834983) (xy 359.017561 -422.784646)
			(xy 359.13936 -422.741726) (xy 359.26357 -422.706385) (xy 359.389719 -422.678758) (xy 359.517331 -422.658949)
			(xy 359.64592 -422.647033) (xy 359.774998 -422.643057) (xy 359.904076 -422.647033) (xy 360.032665 -422.658949)
			(xy 360.160277 -422.678758) (xy 360.286426 -422.706385) (xy 360.410636 -422.741726) (xy 360.532435 -422.784646)
			(xy 360.65136 -422.834983) (xy 360.766961 -422.892545) (xy 360.8788 -422.957115) (xy 360.986451 -423.028447)
			(xy 361.089506 -423.106271) (xy 361.187576 -423.190292) (xy 361.280287 -423.280191) (xy 361.367287 -423.375626)
			(xy 361.448248 -423.476236) (xy 361.522862 -423.581639) (xy 361.590845 -423.691436) (xy 361.65194 -423.80521)
			(xy 361.705915 -423.922529) (xy 361.752566 -424.042948) (xy 361.791715 -424.166011) (xy 361.823214 -424.29125)
			(xy 361.846943 -424.418191) (xy 361.853367 -424.470068) (xy 421.270176 -424.470068) (xy 421.270176 -417.770056)
			(xy 421.270681 -417.664527) (xy 421.278765 -417.453623) (xy 421.294922 -417.243184) (xy 421.319127 -417.033518)
			(xy 421.351345 -416.824934) (xy 421.391528 -416.617736) (xy 421.439619 -416.412229) (xy 421.495545 -416.208716)
			(xy 421.559226 -416.007493) (xy 421.630567 -415.808858) (xy 421.709464 -415.613101) (xy 421.795802 -415.420509)
			(xy 421.889452 -415.231366) (xy 421.990279 -415.045949) (xy 422.098134 -414.864529) (xy 422.212858 -414.687374)
			(xy 422.334284 -414.514743) (xy 422.462233 -414.34689) (xy 422.596517 -414.184061) (xy 422.73694 -414.026495)
			(xy 422.883295 -413.874423) (xy 423.035367 -413.728068) (xy 423.192933 -413.587645) (xy 423.355762 -413.453361)
			(xy 423.523615 -413.325412) (xy 423.696246 -413.203986) (xy 423.873401 -413.089262) (xy 424.054821 -412.981407)
			(xy 424.240238 -412.88058) (xy 424.429381 -412.78693) (xy 424.621973 -412.700592) (xy 424.81773 -412.621695)
			(xy 425.016365 -412.550354) (xy 425.217588 -412.486673) (xy 425.421101 -412.430747) (xy 425.626608 -412.382656)
			(xy 425.833806 -412.342473) (xy 426.04239 -412.310255) (xy 426.252056 -412.28605) (xy 426.462495 -412.269893)
			(xy 426.673399 -412.261809) (xy 426.884457 -412.261809) (xy 427.095361 -412.269893) (xy 427.3058 -412.28605)
			(xy 427.515466 -412.310255) (xy 427.72405 -412.342473) (xy 427.931248 -412.382656) (xy 428.136755 -412.430747)
			(xy 428.340268 -412.486673) (xy 428.541491 -412.550354) (xy 428.740126 -412.621695) (xy 428.935883 -412.700592)
			(xy 429.128475 -412.78693) (xy 429.317618 -412.88058) (xy 429.503035 -412.981407) (xy 429.684455 -413.089262)
			(xy 429.86161 -413.203986) (xy 430.034241 -413.325412) (xy 430.202094 -413.453361) (xy 430.364923 -413.587645)
			(xy 430.522489 -413.728068) (xy 430.674561 -413.874423) (xy 430.820916 -414.026495) (xy 430.961339 -414.184061)
			(xy 431.095623 -414.34689) (xy 431.223572 -414.514743) (xy 431.344998 -414.687374) (xy 431.459722 -414.864529)
			(xy 431.567577 -415.045949) (xy 431.668404 -415.231366) (xy 431.762054 -415.420509) (xy 431.848392 -415.613101)
			(xy 431.927289 -415.808858) (xy 431.99863 -416.007493) (xy 432.062311 -416.208716) (xy 432.118237 -416.412229)
			(xy 432.166328 -416.617736) (xy 432.206511 -416.824934) (xy 432.238729 -417.033518) (xy 432.262934 -417.243184)
			(xy 432.279091 -417.453623) (xy 432.287175 -417.664527) (xy 432.28768 -417.770056) (xy 432.28768 -424.470068)
			(xy 432.287175 -424.575597) (xy 432.279091 -424.786501) (xy 432.262934 -424.99694) (xy 432.238729 -425.206606)
			(xy 432.206511 -425.41519) (xy 432.166328 -425.622388) (xy 432.118237 -425.827895) (xy 432.062311 -426.031408)
			(xy 431.99863 -426.232631) (xy 431.927289 -426.431266) (xy 431.848392 -426.627023) (xy 431.762054 -426.819615)
			(xy 431.668404 -427.008758) (xy 431.567577 -427.194175) (xy 431.459722 -427.375595) (xy 431.344998 -427.55275)
			(xy 431.223572 -427.725381) (xy 431.095623 -427.893234) (xy 430.961339 -428.056063) (xy 430.820916 -428.213629)
			(xy 430.674561 -428.365701) (xy 430.522489 -428.512056) (xy 430.364923 -428.652479) (xy 430.202094 -428.786763)
			(xy 430.034241 -428.914712) (xy 429.86161 -429.036138) (xy 429.684455 -429.150862) (xy 429.503035 -429.258717)
			(xy 429.317618 -429.359544) (xy 429.128475 -429.453194) (xy 428.935883 -429.539532) (xy 428.740126 -429.618429)
			(xy 428.541491 -429.68977) (xy 428.340268 -429.753451) (xy 428.136755 -429.809377) (xy 427.931248 -429.857468)
			(xy 427.72405 -429.897651) (xy 427.515466 -429.929869) (xy 427.3058 -429.954074) (xy 427.095361 -429.970231)
			(xy 426.884457 -429.978315) (xy 426.673399 -429.978315) (xy 426.462495 -429.970231) (xy 426.252056 -429.954074)
			(xy 426.04239 -429.929869) (xy 425.833806 -429.897651) (xy 425.626608 -429.857468) (xy 425.421101 -429.809377)
			(xy 425.217588 -429.753451) (xy 425.016365 -429.68977) (xy 424.81773 -429.618429) (xy 424.621973 -429.539532)
			(xy 424.429381 -429.453194) (xy 424.240238 -429.359544) (xy 424.054821 -429.258717) (xy 423.873401 -429.150862)
			(xy 423.696246 -429.036138) (xy 423.523615 -428.914712) (xy 423.355762 -428.786763) (xy 423.192933 -428.652479)
			(xy 423.035367 -428.512056) (xy 422.883295 -428.365701) (xy 422.73694 -428.213629) (xy 422.596517 -428.056063)
			(xy 422.462233 -427.893234) (xy 422.334284 -427.725381) (xy 422.212858 -427.55275) (xy 422.098134 -427.375595)
			(xy 421.990279 -427.194175) (xy 421.889452 -427.008758) (xy 421.795802 -426.819615) (xy 421.709464 -426.627023)
			(xy 421.630567 -426.431266) (xy 421.559226 -426.232631) (xy 421.495545 -426.031408) (xy 421.439619 -425.827895)
			(xy 421.391528 -425.622388) (xy 421.351345 -425.41519) (xy 421.319127 -425.206606) (xy 421.294922 -424.99694)
			(xy 421.278765 -424.786501) (xy 421.270681 -424.575597) (xy 421.270176 -424.470068) (xy 361.853367 -424.470068)
			(xy 361.862813 -424.546351) (xy 361.870763 -424.675246) (xy 361.87126 -424.739816) (xy 361.870763 -424.804386)
			(xy 361.862813 -424.933281) (xy 361.846943 -425.061441) (xy 361.823214 -425.188382) (xy 361.791715 -425.313621)
			(xy 361.752566 -425.436684) (xy 361.705915 -425.557103) (xy 361.65194 -425.674422) (xy 361.590845 -425.788196)
			(xy 361.522862 -425.897993) (xy 361.448248 -426.003396) (xy 361.367287 -426.104006) (xy 361.280287 -426.199441)
			(xy 361.187576 -426.28934) (xy 361.089506 -426.373361) (xy 360.986451 -426.451185) (xy 360.8788 -426.522517)
			(xy 360.766961 -426.587087) (xy 360.65136 -426.644649) (xy 360.532435 -426.694986) (xy 360.410636 -426.737906)
			(xy 360.286426 -426.773247) (xy 360.160277 -426.800874) (xy 360.032665 -426.820683) (xy 359.904076 -426.832599)
			(xy 359.774998 -426.836576) (xy 359.64592 -426.832599) (xy 359.517331 -426.820683) (xy 359.389719 -426.800874)
			(xy 359.26357 -426.773247) (xy 359.13936 -426.737906) (xy 359.017561 -426.694986) (xy 358.898636 -426.644649)
			(xy 358.783035 -426.587087) (xy 358.671196 -426.522517) (xy 358.563545 -426.451185) (xy 358.46049 -426.373361)
			(xy 358.36242 -426.28934) (xy 358.269709 -426.199441) (xy 358.182709 -426.104006) (xy 358.101748 -426.003396)
			(xy 358.027134 -425.897993) (xy 357.959151 -425.788196) (xy 357.898056 -425.674422) (xy 357.844081 -425.557103)
			(xy 357.79743 -425.436684) (xy 357.758281 -425.313621) (xy 357.726782 -425.188382) (xy 357.703053 -425.061441)
			(xy 357.687183 -424.933281) (xy 357.679233 -424.804386) (xy 231.01554 -424.804386) (xy 231.01554 -427.289976)
			(xy 314.118498 -427.289976) (xy 314.118995 -427.25742) (xy 314.126943 -427.192795) (xy 314.142729 -427.129626)
			(xy 314.166116 -427.068859) (xy 314.196754 -427.011407) (xy 314.234184 -426.958128) (xy 314.277844 -426.909824)
			(xy 314.30214 -426.888148) (xy 314.382912 -426.723302) (xy 314.387599 -426.71278) (xy 314.391094 -426.690025)
			(xy 314.387614 -426.667268) (xy 314.382912 -426.656754) (xy 314.301886 -426.491654) (xy 314.277618 -426.469963)
			(xy 314.234022 -426.421629) (xy 314.196648 -426.368337) (xy 314.166056 -426.310884) (xy 314.142701 -426.250127)
			(xy 314.126934 -426.186975) (xy 314.11899 -426.122371) (xy 314.118498 -426.089826) (xy 314.119217 -426.050501)
			(xy 314.130827 -425.972711) (xy 314.141612 -425.934886) (xy 314.141612 -425.419012) (xy 314.142023 -425.406928)
			(xy 314.14949 -425.383942) (xy 314.163696 -425.36439) (xy 314.183249 -425.350186) (xy 314.206236 -425.342722)
			(xy 314.21832 -425.342304) (xy 315.15812 -425.342304) (xy 315.170197 -425.342748) (xy 315.193167 -425.350217)
			(xy 315.212704 -425.364419) (xy 315.226898 -425.383962) (xy 315.234357 -425.406935) (xy 315.234828 -425.419012)
			(xy 315.234828 -427.960536) (xy 315.234367 -427.97261) (xy 315.226897 -427.995576) (xy 315.212699 -428.01511)
			(xy 315.193161 -428.029304) (xy 315.170195 -428.036769) (xy 315.15812 -428.037244) (xy 314.21832 -428.037244)
			(xy 314.20625 -428.036719) (xy 314.18329 -428.029267) (xy 314.163755 -428.015085) (xy 314.149559 -427.995561)
			(xy 314.142089 -427.972606) (xy 314.141612 -427.960536) (xy 314.141612 -427.444916) (xy 314.130808 -427.407096)
			(xy 314.119205 -427.329303) (xy 314.118498 -427.289976) (xy 231.01554 -427.289976) (xy 231.01554 -428.28972)
			(xy 316.118494 -428.28972) (xy 316.119031 -428.257141) (xy 316.127002 -428.192471) (xy 316.142815 -428.12926)
			(xy 316.166234 -428.068455) (xy 316.196906 -428.010967) (xy 316.234373 -427.957658) (xy 316.278073 -427.909326)
			(xy 316.30239 -427.887638) (xy 316.382908 -427.7233) (xy 316.387597 -427.712779) (xy 316.391091 -427.690023)
			(xy 316.387611 -427.667266) (xy 316.382908 -427.656752) (xy 316.301882 -427.491652) (xy 316.277613 -427.469963)
			(xy 316.234017 -427.421628) (xy 316.196643 -427.368336) (xy 316.166051 -427.310883) (xy 316.142697 -427.250126)
			(xy 316.12693 -427.186974) (xy 316.118985 -427.122369) (xy 316.118494 -427.089824) (xy 316.119213 -427.050499)
			(xy 316.130823 -426.972709) (xy 316.141608 -426.934884) (xy 316.141608 -426.41901) (xy 316.142115 -426.406924)
			(xy 316.149565 -426.383929) (xy 316.163743 -426.364352) (xy 316.183266 -426.3501) (xy 316.206232 -426.342562)
			(xy 316.218316 -426.342048) (xy 317.158116 -426.342048) (xy 317.170221 -426.342502) (xy 317.193239 -426.349999)
			(xy 317.212808 -426.364253) (xy 317.227004 -426.383863) (xy 317.234433 -426.406904) (xy 317.234824 -426.41901)
			(xy 317.234824 -427.289976) (xy 318.11849 -427.289976) (xy 318.118956 -427.257419) (xy 318.126905 -427.192792)
			(xy 318.142694 -427.129621) (xy 318.166086 -427.068853) (xy 318.196729 -427.0114) (xy 318.234166 -426.958124)
			(xy 318.277833 -426.909822) (xy 318.302132 -426.888148) (xy 318.382904 -426.723302) (xy 318.387592 -426.71278)
			(xy 318.391087 -426.690025) (xy 318.387607 -426.667268) (xy 318.382904 -426.656754) (xy 318.301878 -426.491654)
			(xy 318.277609 -426.469964) (xy 318.234013 -426.42163) (xy 318.19664 -426.368338) (xy 318.166047 -426.310884)
			(xy 318.142693 -426.250128) (xy 318.126926 -426.186975) (xy 318.118982 -426.122371) (xy 318.11849 -426.089826)
			(xy 318.119209 -426.050501) (xy 318.13082 -425.972711) (xy 318.141604 -425.934886) (xy 318.141604 -425.419012)
			(xy 318.142023 -425.406929) (xy 318.149489 -425.383944) (xy 318.163693 -425.364393) (xy 318.183244 -425.350189)
			(xy 318.206229 -425.342723) (xy 318.218312 -425.342304) (xy 319.158112 -425.342304) (xy 319.170188 -425.342754)
			(xy 319.193158 -425.350222) (xy 319.212696 -425.364421) (xy 319.226889 -425.383964) (xy 319.234349 -425.406935)
			(xy 319.23482 -425.419012) (xy 319.23482 -427.960536) (xy 319.234367 -427.972611) (xy 319.226896 -427.995578)
			(xy 319.212696 -428.015113) (xy 319.193156 -428.029307) (xy 319.170187 -428.036771) (xy 319.158112 -428.037244)
			(xy 318.218312 -428.037244) (xy 318.206242 -428.036726) (xy 318.183281 -428.029271) (xy 318.163747 -428.015087)
			(xy 318.149551 -427.995562) (xy 318.142081 -427.972606) (xy 318.141604 -427.960536) (xy 318.141604 -427.444916)
			(xy 318.1308 -427.407096) (xy 318.119197 -427.329303) (xy 318.11849 -427.289976) (xy 317.234824 -427.289976)
			(xy 317.234824 -428.28972) (xy 320.118486 -428.28972) (xy 320.119026 -428.257141) (xy 320.126997 -428.192472)
			(xy 320.14281 -428.129261) (xy 320.166228 -428.068456) (xy 320.1969 -428.010968) (xy 320.234366 -427.957658)
			(xy 320.278066 -427.909326) (xy 320.302382 -427.887638) (xy 320.3829 -427.7233) (xy 320.387589 -427.712779)
			(xy 320.391084 -427.690023) (xy 320.387603 -427.667266) (xy 320.3829 -427.656752) (xy 320.301874 -427.491652)
			(xy 320.277603 -427.469964) (xy 320.234007 -427.42163) (xy 320.196634 -427.368337) (xy 320.166042 -427.310883)
			(xy 320.142688 -427.250126) (xy 320.126922 -427.186974) (xy 320.118977 -427.122369) (xy 320.118486 -427.089824)
			(xy 320.119205 -427.050499) (xy 320.130816 -426.972709) (xy 320.1416 -426.934884) (xy 320.1416 -426.41901)
			(xy 320.142115 -426.406925) (xy 320.149564 -426.383931) (xy 320.16374 -426.364355) (xy 320.183261 -426.350103)
			(xy 320.206225 -426.342563) (xy 320.218308 -426.342048) (xy 321.158108 -426.342048) (xy 321.170212 -426.342509)
			(xy 321.193231 -426.350004) (xy 321.212799 -426.364256) (xy 321.226996 -426.383865) (xy 321.234425 -426.406905)
			(xy 321.234816 -426.41901) (xy 321.234816 -427.289976) (xy 322.118482 -427.289976) (xy 322.118951 -427.257419)
			(xy 322.1269 -427.192792) (xy 322.142688 -427.129621) (xy 322.16608 -427.068854) (xy 322.196723 -427.011401)
			(xy 322.234159 -426.958124) (xy 322.277825 -426.909822) (xy 322.302124 -426.888148) (xy 322.382896 -426.723302)
			(xy 322.387584 -426.71278) (xy 322.391079 -426.690025) (xy 322.387599 -426.667268) (xy 322.382896 -426.656754)
			(xy 322.30187 -426.491654) (xy 322.277619 -426.469944) (xy 322.234019 -426.421616) (xy 322.196641 -426.368328)
			(xy 322.166045 -426.310878) (xy 322.142688 -426.250124) (xy 322.126919 -426.186973) (xy 322.118974 -426.122371)
			(xy 322.118482 -426.089826) (xy 322.119202 -426.050501) (xy 322.130812 -425.972711) (xy 322.141596 -425.934886)
			(xy 322.141596 -425.419012) (xy 322.142023 -425.40693) (xy 322.149488 -425.383947) (xy 322.16369 -425.364396)
			(xy 322.183239 -425.350191) (xy 322.206222 -425.342724) (xy 322.218304 -425.342304) (xy 323.158104 -425.342304)
			(xy 323.170188 -425.342709) (xy 323.193173 -425.350179) (xy 323.212724 -425.364387) (xy 323.226928 -425.383941)
			(xy 323.234393 -425.406928) (xy 323.234812 -425.419012) (xy 323.234812 -427.960536) (xy 323.234367 -427.972612)
			(xy 323.226895 -427.99558) (xy 323.212693 -428.015116) (xy 323.193151 -428.029309) (xy 323.17018 -428.036772)
			(xy 323.158104 -428.037244) (xy 322.218304 -428.037244) (xy 322.206233 -428.036733) (xy 322.183272 -428.029276)
			(xy 322.163738 -428.01509) (xy 322.149542 -427.995564) (xy 322.142073 -427.972607) (xy 322.141596 -427.960536)
			(xy 322.141596 -427.444916) (xy 322.130792 -427.407096) (xy 322.119188 -427.329303) (xy 322.118482 -427.289976)
			(xy 321.234816 -427.289976) (xy 321.234816 -428.28972) (xy 324.118478 -428.28972) (xy 324.11902 -428.257141)
			(xy 324.126991 -428.192472) (xy 324.142804 -428.129261) (xy 324.166222 -428.068456) (xy 324.196893 -428.010968)
			(xy 324.234359 -427.957659) (xy 324.278058 -427.909326) (xy 324.302374 -427.887638) (xy 324.382892 -427.7233)
			(xy 324.387582 -427.712779) (xy 324.391077 -427.690023) (xy 324.387596 -427.667266) (xy 324.382892 -427.656752)
			(xy 324.301866 -427.491652) (xy 324.277614 -427.469944) (xy 324.234013 -427.421615) (xy 324.196636 -427.368327)
			(xy 324.16604 -427.310877) (xy 324.142684 -427.250122) (xy 324.126915 -427.186972) (xy 324.11897 -427.122369)
			(xy 324.118478 -427.089824) (xy 324.119197 -427.050499) (xy 324.130808 -426.972709) (xy 324.141592 -426.934884)
			(xy 324.141592 -426.41901) (xy 324.142115 -426.406926) (xy 324.149563 -426.383934) (xy 324.163737 -426.364358)
			(xy 324.183256 -426.350105) (xy 324.206218 -426.342564) (xy 324.2183 -426.342048) (xy 325.1581 -426.342048)
			(xy 325.170204 -426.342515) (xy 325.193222 -426.350009) (xy 325.212791 -426.364259) (xy 325.226987 -426.383866)
			(xy 325.234417 -426.406905) (xy 325.234808 -426.41901) (xy 325.234808 -427.289976) (xy 326.118474 -427.289976)
			(xy 326.118945 -427.257419) (xy 326.126894 -427.192792) (xy 326.142682 -427.129621) (xy 326.166073 -427.068854)
			(xy 326.196716 -427.011401) (xy 326.234151 -426.958124) (xy 326.277817 -426.909822) (xy 326.302116 -426.888148)
			(xy 326.382888 -426.723302) (xy 326.387576 -426.71278) (xy 326.391072 -426.690025) (xy 326.387592 -426.667268)
			(xy 326.382888 -426.656754) (xy 326.301862 -426.491654) (xy 326.27761 -426.469946) (xy 326.23401 -426.421617)
			(xy 326.196633 -426.368329) (xy 326.166037 -426.310878) (xy 326.14268 -426.250124) (xy 326.126911 -426.186974)
			(xy 326.118966 -426.122371) (xy 326.118474 -426.089826) (xy 326.119194 -426.050501) (xy 326.130804 -425.972711)
			(xy 326.141588 -425.934886) (xy 326.141588 -425.419012) (xy 326.142023 -425.40693) (xy 326.149487 -425.383949)
			(xy 326.163687 -425.364399) (xy 326.183234 -425.350194) (xy 326.206214 -425.342726) (xy 326.218296 -425.342304)
			(xy 327.158096 -425.342304) (xy 327.17018 -425.342716) (xy 327.193164 -425.350184) (xy 327.212716 -425.36439)
			(xy 327.22692 -425.383943) (xy 327.234385 -425.406928) (xy 327.234804 -425.419012) (xy 327.234804 -427.960536)
			(xy 327.234367 -427.972613) (xy 327.226894 -427.995582) (xy 327.21269 -428.015119) (xy 327.193146 -428.029312)
			(xy 327.170173 -428.036773) (xy 327.158096 -428.037244) (xy 326.218296 -428.037244) (xy 326.206225 -428.03674)
			(xy 326.183264 -428.02928) (xy 326.16373 -428.015093) (xy 326.149534 -427.995565) (xy 326.142065 -427.972607)
			(xy 326.141588 -427.960536) (xy 326.141588 -427.444916) (xy 326.130784 -427.407096) (xy 326.11918 -427.329303)
			(xy 326.118474 -427.289976) (xy 325.234808 -427.289976) (xy 325.234808 -428.28972) (xy 328.11847 -428.28972)
			(xy 328.119015 -428.257141) (xy 328.126986 -428.192472) (xy 328.142799 -428.129262) (xy 328.166216 -428.068457)
			(xy 328.196887 -428.010969) (xy 328.234352 -427.957659) (xy 328.27805 -427.909326) (xy 328.302366 -427.887638)
			(xy 328.382884 -427.7233) (xy 328.387574 -427.712779) (xy 328.39107 -427.690023) (xy 328.387588 -427.667266)
			(xy 328.382884 -427.656752) (xy 328.301858 -427.491652) (xy 328.277604 -427.469946) (xy 328.234004 -427.421616)
			(xy 328.196627 -427.368328) (xy 328.166032 -427.310877) (xy 328.142675 -427.250123) (xy 328.126907 -427.186972)
			(xy 328.118962 -427.122369) (xy 328.11847 -427.089824) (xy 328.11919 -427.050499) (xy 328.1308 -426.972709)
			(xy 328.141584 -426.934884) (xy 328.141584 -426.41901) (xy 328.142017 -426.406917) (xy 328.149476 -426.383909)
			(xy 328.16367 -426.364325) (xy 328.183214 -426.350076) (xy 328.2062 -426.342551) (xy 328.218292 -426.342048)
			(xy 329.158092 -426.342048) (xy 329.170195 -426.342522) (xy 329.193214 -426.350013) (xy 329.212782 -426.364262)
			(xy 329.226979 -426.383868) (xy 329.234409 -426.406906) (xy 329.2348 -426.41901) (xy 329.2348 -427.289976)
			(xy 331.118464 -427.289976) (xy 331.118938 -427.257419) (xy 331.126887 -427.192793) (xy 331.142675 -427.129622)
			(xy 331.166066 -427.068855) (xy 331.196708 -427.011402) (xy 331.234142 -426.958125) (xy 331.277808 -426.909822)
			(xy 331.302106 -426.888148) (xy 331.382878 -426.723302) (xy 331.387567 -426.71278) (xy 331.391063 -426.690025)
			(xy 331.387582 -426.667268) (xy 331.382878 -426.656754) (xy 331.301852 -426.491654) (xy 331.277598 -426.469948)
			(xy 331.233998 -426.421618) (xy 331.196621 -426.36833) (xy 331.166026 -426.310879) (xy 331.14267 -426.250124)
			(xy 331.126901 -426.186974) (xy 331.118956 -426.122371) (xy 331.118464 -426.089826) (xy 331.119168 -426.0507)
			(xy 331.13064 -425.973293) (xy 331.141324 -425.935648) (xy 331.141324 -425.419012) (xy 331.141727 -425.406901)
			(xy 331.149226 -425.38387) (xy 331.16349 -425.364295) (xy 331.183116 -425.350101) (xy 331.206174 -425.342684)
			(xy 331.218286 -425.342304) (xy 332.158086 -425.342304) (xy 332.170171 -425.342819) (xy 332.193165 -425.350267)
			(xy 332.212742 -425.364443) (xy 332.226995 -425.383964) (xy 332.234533 -425.406929) (xy 332.235048 -425.419012)
			(xy 332.235048 -427.960536) (xy 332.234615 -427.972642) (xy 332.227111 -427.995662) (xy 332.212852 -428.01523)
			(xy 332.193238 -428.029426) (xy 332.170193 -428.036854) (xy 332.158086 -428.037244) (xy 331.218286 -428.037244)
			(xy 331.206194 -428.036804) (xy 331.18319 -428.029342) (xy 331.163609 -428.015149) (xy 331.14936 -427.995609)
			(xy 331.141831 -427.972627) (xy 331.141324 -427.960536) (xy 331.141324 -427.444154) (xy 331.130632 -427.40651)
			(xy 331.119158 -427.329103) (xy 331.118464 -427.289976) (xy 329.2348 -427.289976) (xy 329.2348 -428.28972)
			(xy 333.11846 -428.28972) (xy 333.118975 -428.25714) (xy 333.126947 -428.192469) (xy 333.142763 -428.129257)
			(xy 333.166184 -428.068451) (xy 333.19686 -428.010963) (xy 333.234332 -427.957654) (xy 333.278037 -427.909324)
			(xy 333.302356 -427.887638) (xy 333.382874 -427.7233) (xy 333.387565 -427.712779) (xy 333.391061 -427.690023)
			(xy 333.387579 -427.667266) (xy 333.382874 -427.656752) (xy 333.301848 -427.491652) (xy 333.277592 -427.469948)
			(xy 333.233993 -427.421618) (xy 333.196616 -427.368329) (xy 333.166021 -427.310878) (xy 333.142665 -427.250123)
			(xy 333.126897 -427.186972) (xy 333.118952 -427.122369) (xy 333.11846 -427.089824) (xy 333.119164 -427.050698)
			(xy 333.130636 -426.973291) (xy 333.14132 -426.935646) (xy 333.14132 -426.41901) (xy 333.14182 -426.406898)
			(xy 333.149302 -426.383858) (xy 333.163538 -426.364258) (xy 333.183133 -426.350015) (xy 333.20617 -426.342525)
			(xy 333.218282 -426.342048) (xy 334.158082 -426.342048) (xy 334.170205 -426.342475) (xy 334.193265 -426.349964)
			(xy 334.212881 -426.364213) (xy 334.227132 -426.383828) (xy 334.234623 -426.406887) (xy 334.235044 -426.41901)
			(xy 334.235044 -427.289976) (xy 335.118456 -427.289976) (xy 335.118933 -427.257419) (xy 335.126882 -427.192793)
			(xy 335.14267 -427.129623) (xy 335.16606 -427.068855) (xy 335.196701 -427.011402) (xy 335.234135 -426.958125)
			(xy 335.2778 -426.909822) (xy 335.302098 -426.888148) (xy 335.38287 -426.723302) (xy 335.387559 -426.712781)
			(xy 335.391056 -426.690025) (xy 335.387575 -426.667268) (xy 335.38287 -426.656754) (xy 335.301844 -426.491654)
			(xy 335.277588 -426.46995) (xy 335.233989 -426.42162) (xy 335.196613 -426.368331) (xy 335.166018 -426.31088)
			(xy 335.142661 -426.250125) (xy 335.126893 -426.186974) (xy 335.118948 -426.122371) (xy 335.118456 -426.089826)
			(xy 335.119161 -426.0507) (xy 335.130632 -425.973293) (xy 335.141316 -425.935648) (xy 335.141316 -425.419012)
			(xy 335.141727 -425.406902) (xy 335.149225 -425.383873) (xy 335.163487 -425.364298) (xy 335.183111 -425.350104)
			(xy 335.206167 -425.342685) (xy 335.218278 -425.342304) (xy 336.158078 -425.342304) (xy 336.170163 -425.342825)
			(xy 336.193157 -425.350272) (xy 336.212734 -425.364446) (xy 336.226986 -425.383966) (xy 336.234525 -425.406929)
			(xy 336.23504 -425.419012) (xy 336.23504 -427.960536) (xy 336.234615 -427.972643) (xy 336.22711 -427.995664)
			(xy 336.21285 -428.015233) (xy 336.193233 -428.029428) (xy 336.170186 -428.036855) (xy 336.158078 -428.037244)
			(xy 335.218278 -428.037244) (xy 335.206186 -428.036811) (xy 335.183182 -428.029347) (xy 335.163601 -428.015152)
			(xy 335.149351 -427.99561) (xy 335.141823 -427.972627) (xy 335.141316 -427.960536) (xy 335.141316 -427.444154)
			(xy 335.130624 -427.40651) (xy 335.11915 -427.329103) (xy 335.118456 -427.289976) (xy 334.235044 -427.289976)
			(xy 334.235044 -428.28972) (xy 337.118452 -428.28972) (xy 337.118969 -428.25714) (xy 337.126942 -428.192469)
			(xy 337.142757 -428.129257) (xy 337.166178 -428.068451) (xy 337.196854 -428.010963) (xy 337.234325 -427.957655)
			(xy 337.278029 -427.909325) (xy 337.302348 -427.887638) (xy 337.382866 -427.7233) (xy 337.387552 -427.712778)
			(xy 337.391044 -427.690023) (xy 337.387566 -427.667267) (xy 337.382866 -427.656752) (xy 337.30184 -427.491652)
			(xy 337.277582 -427.46995) (xy 337.233983 -427.421619) (xy 337.196607 -427.36833) (xy 337.166013 -427.310879)
			(xy 337.142657 -427.250123) (xy 337.126888 -427.186972) (xy 337.118944 -427.122369) (xy 337.118452 -427.089824)
			(xy 337.119157 -427.050698) (xy 337.130628 -426.973291) (xy 337.141312 -426.935646) (xy 337.141312 -426.41901)
			(xy 337.14182 -426.406899) (xy 337.149301 -426.38386) (xy 337.163535 -426.36426) (xy 337.183128 -426.350018)
			(xy 337.206163 -426.342526) (xy 337.218274 -426.342048) (xy 338.158074 -426.342048) (xy 338.170196 -426.342482)
			(xy 338.193256 -426.349969) (xy 338.212872 -426.364216) (xy 338.227124 -426.38383) (xy 338.234615 -426.406888)
			(xy 338.235036 -426.41901) (xy 338.235036 -427.289976) (xy 339.118448 -427.289976) (xy 339.118928 -427.257419)
			(xy 339.126876 -427.192793) (xy 339.142664 -427.129623) (xy 339.166054 -427.068856) (xy 339.196695 -427.011403)
			(xy 339.234128 -426.958126) (xy 339.277792 -426.909823) (xy 339.30209 -426.888148) (xy 339.382862 -426.723302)
			(xy 339.387547 -426.712779) (xy 339.391039 -426.690025) (xy 339.387562 -426.667269) (xy 339.382862 -426.656754)
			(xy 339.301836 -426.491654) (xy 339.277579 -426.469951) (xy 339.23398 -426.421621) (xy 339.196604 -426.368332)
			(xy 339.166009 -426.31088) (xy 339.142653 -426.250125) (xy 339.126885 -426.186974) (xy 339.11894 -426.122371)
			(xy 339.118448 -426.089826) (xy 339.119153 -426.0507) (xy 339.130624 -425.973293) (xy 339.141308 -425.935648)
			(xy 339.141308 -425.419012) (xy 339.141727 -425.406903) (xy 339.149224 -425.383875) (xy 339.163485 -425.364301)
			(xy 339.183106 -425.350106) (xy 339.20616 -425.342687) (xy 339.21827 -425.342304) (xy 340.15807 -425.342304)
			(xy 340.170154 -425.342832) (xy 340.193148 -425.350276) (xy 340.212725 -425.364448) (xy 340.226978 -425.383967)
			(xy 340.234517 -425.40693) (xy 340.235032 -425.419012) (xy 340.235032 -427.960536) (xy 340.234615 -427.972644)
			(xy 340.227109 -427.995667) (xy 340.212847 -428.015236) (xy 340.193228 -428.029431) (xy 340.170179 -428.036856)
			(xy 340.15807 -428.037244) (xy 339.21827 -428.037244) (xy 339.206177 -428.036818) (xy 339.183173 -428.029351)
			(xy 339.163592 -428.015154) (xy 339.149343 -427.995612) (xy 339.141815 -427.972627) (xy 339.141308 -427.960536)
			(xy 339.141308 -427.444154) (xy 339.130615 -427.40651) (xy 339.119142 -427.329103) (xy 339.118448 -427.289976)
			(xy 338.235036 -427.289976) (xy 338.235036 -428.28972) (xy 341.118444 -428.28972) (xy 341.118956 -428.257164)
			(xy 341.1269 -428.19254) (xy 341.142682 -428.12937) (xy 341.166066 -428.068603) (xy 341.196703 -428.01115)
			(xy 341.234131 -427.957872) (xy 341.277791 -427.909568) (xy 341.302086 -427.887892) (xy 341.382858 -427.723046)
			(xy 341.387582 -427.712539) (xy 341.39106 -427.689775) (xy 341.387567 -427.667013) (xy 341.382858 -427.656498)
			(xy 341.302086 -427.491652) (xy 341.277781 -427.469987) (xy 341.23413 -427.421675) (xy 341.196706 -427.368392)
			(xy 341.166071 -427.310938) (xy 341.142684 -427.250171) (xy 341.126894 -427.187003) (xy 341.118937 -427.12238)
			(xy 341.118444 -427.089824) (xy 341.119149 -427.050698) (xy 341.13062 -426.973291) (xy 341.141304 -426.935646)
			(xy 341.141304 -426.418756) (xy 341.141679 -426.406644) (xy 341.149191 -426.383615) (xy 341.163463 -426.364042)
			(xy 341.183093 -426.349849) (xy 341.206153 -426.342431) (xy 341.218266 -426.342048) (xy 342.158066 -426.342048)
			(xy 342.170155 -426.342536) (xy 342.193155 -426.349985) (xy 342.212737 -426.364166) (xy 342.226988 -426.383695)
			(xy 342.234519 -426.406669) (xy 342.235028 -426.418756) (xy 342.235028 -427.289976) (xy 343.11844 -427.289976)
			(xy 343.118922 -427.257419) (xy 343.126871 -427.192794) (xy 343.142658 -427.129623) (xy 343.166048 -427.068856)
			(xy 343.196688 -427.011404) (xy 343.234121 -426.958126) (xy 343.277785 -426.909823) (xy 343.302082 -426.888148)
			(xy 343.382854 -426.723302) (xy 343.387539 -426.71278) (xy 343.391032 -426.690025) (xy 343.387554 -426.667269)
			(xy 343.382854 -426.656754) (xy 343.301828 -426.491654) (xy 343.277569 -426.469953) (xy 343.233971 -426.421622)
			(xy 343.196595 -426.368333) (xy 343.166001 -426.310881) (xy 343.142645 -426.250126) (xy 343.126877 -426.186974)
			(xy 343.118932 -426.122371) (xy 343.11844 -426.089826) (xy 343.119145 -426.0507) (xy 343.130616 -425.973293)
			(xy 343.1413 -425.935648) (xy 343.1413 -425.419012) (xy 343.141727 -425.406904) (xy 343.149223 -425.383877)
			(xy 343.163482 -425.364304) (xy 343.183101 -425.350109) (xy 343.206152 -425.342688) (xy 343.218262 -425.342304)
			(xy 344.158062 -425.342304) (xy 344.170146 -425.342839) (xy 344.193139 -425.350281) (xy 344.212717 -425.364451)
			(xy 344.22697 -425.383968) (xy 344.234509 -425.40693) (xy 344.235024 -425.419012) (xy 344.235024 -427.960536)
			(xy 344.234615 -427.972644) (xy 344.227108 -427.995669) (xy 344.212844 -428.015239) (xy 344.193223 -428.029433)
			(xy 344.170172 -428.036857) (xy 344.158062 -428.037244) (xy 343.218262 -428.037244) (xy 343.206169 -428.036825)
			(xy 343.183164 -428.029356) (xy 343.163584 -428.015157) (xy 343.149335 -427.995613) (xy 343.141807 -427.972628)
			(xy 343.1413 -427.960536) (xy 343.1413 -427.444154) (xy 343.130607 -427.40651) (xy 343.119134 -427.329103)
			(xy 343.11844 -427.289976) (xy 342.235028 -427.289976) (xy 342.235028 -428.28972) (xy 345.118436 -428.28972)
			(xy 345.118959 -428.25714) (xy 345.126931 -428.19247) (xy 345.142746 -428.129258) (xy 345.166166 -428.068452)
			(xy 345.196841 -428.010965) (xy 345.234311 -427.957656) (xy 345.278014 -427.909325) (xy 345.302332 -427.887638)
			(xy 345.38285 -427.7233) (xy 345.387537 -427.712778) (xy 345.391029 -427.690023) (xy 345.387551 -427.667267)
			(xy 345.38285 -427.656752) (xy 345.301824 -427.491652) (xy 345.277563 -427.469953) (xy 345.233965 -427.421622)
			(xy 345.19659 -427.368332) (xy 345.165996 -427.31088) (xy 345.14264 -427.250124) (xy 345.126872 -427.186973)
			(xy 345.118927 -427.122369) (xy 345.118436 -427.089824) (xy 345.119141 -427.050698) (xy 345.130612 -426.973291)
			(xy 345.141296 -426.935646) (xy 345.141296 -426.41901) (xy 345.14182 -426.4069) (xy 345.149299 -426.383864)
			(xy 345.163529 -426.364266) (xy 345.183118 -426.350023) (xy 345.206148 -426.342528) (xy 345.218258 -426.342048)
			(xy 346.158058 -426.342048) (xy 346.17018 -426.342496) (xy 346.193239 -426.349978) (xy 346.212855 -426.364222)
			(xy 346.227108 -426.383833) (xy 346.234599 -426.406889) (xy 346.23502 -426.41901) (xy 346.23502 -427.289976)
			(xy 381.237998 -427.289976) (xy 381.238088 -427.275402) (xy 381.239743 -427.246301) (xy 381.2413 -427.23181)
			(xy 381.2413 -426.147992) (xy 381.239757 -426.1335) (xy 381.238104 -426.1044) (xy 381.237998 -426.089826)
			(xy 381.238093 -426.075252) (xy 381.239744 -426.046151) (xy 381.2413 -426.03166) (xy 381.2413 -425.419012)
			(xy 381.241727 -425.406904) (xy 381.249223 -425.383877) (xy 381.263482 -425.364304) (xy 381.283101 -425.350109)
			(xy 381.306152 -425.342688) (xy 381.318262 -425.342304) (xy 382.258062 -425.342304) (xy 382.270146 -425.342839)
			(xy 382.293139 -425.350281) (xy 382.312717 -425.364451) (xy 382.32697 -425.383968) (xy 382.334509 -425.40693)
			(xy 382.335024 -425.419012) (xy 382.335024 -427.960536) (xy 382.334615 -427.972644) (xy 382.327108 -427.995669)
			(xy 382.312844 -428.015239) (xy 382.293223 -428.029433) (xy 382.270172 -428.036857) (xy 382.258062 -428.037244)
			(xy 381.318262 -428.037244) (xy 381.306169 -428.036825) (xy 381.283164 -428.029356) (xy 381.263584 -428.015157)
			(xy 381.249335 -427.995613) (xy 381.241807 -427.972628) (xy 381.2413 -427.960536) (xy 381.2413 -427.348142)
			(xy 381.239753 -427.33365) (xy 381.238103 -427.30455) (xy 381.237998 -427.289976) (xy 346.23502 -427.289976)
			(xy 346.23502 -428.960534) (xy 346.234669 -428.972663) (xy 346.227162 -428.99573) (xy 346.212894 -429.015348)
			(xy 346.193262 -429.029597) (xy 346.170187 -429.03708) (xy 346.158058 -429.037496) (xy 345.218258 -429.037496)
			(xy 345.206145 -429.037025) (xy 345.183106 -429.02953) (xy 345.163508 -429.015287) (xy 345.149266 -428.995687)
			(xy 345.141774 -428.972647) (xy 345.141296 -428.960534) (xy 345.141296 -428.443898) (xy 345.130613 -428.406252)
			(xy 345.119133 -428.328846) (xy 345.118436 -428.28972) (xy 342.235028 -428.28972) (xy 342.235028 -428.96028)
			(xy 342.234567 -428.972385) (xy 342.227076 -428.995407) (xy 342.212825 -429.014978) (xy 342.193215 -429.029174)
			(xy 342.170172 -429.0366) (xy 342.158066 -429.036988) (xy 341.218266 -429.036988) (xy 341.206177 -429.036522)
			(xy 341.18318 -429.02906) (xy 341.163603 -429.014872) (xy 341.149353 -428.99534) (xy 341.141817 -428.972367)
			(xy 341.141304 -428.96028) (xy 341.141304 -428.443898) (xy 341.130621 -428.406252) (xy 341.119141 -428.328846)
			(xy 341.118444 -428.28972) (xy 338.235036 -428.28972) (xy 338.235036 -428.960534) (xy 338.234617 -428.972653)
			(xy 338.227117 -428.995702) (xy 338.212862 -429.015305) (xy 338.193248 -429.029545) (xy 338.170193 -429.037026)
			(xy 338.158074 -429.037496) (xy 337.218274 -429.037496) (xy 337.206161 -429.037011) (xy 337.183123 -429.029521)
			(xy 337.163525 -429.015281) (xy 337.149283 -428.995684) (xy 337.14179 -428.972646) (xy 337.141312 -428.960534)
			(xy 337.141312 -428.443898) (xy 337.130629 -428.406252) (xy 337.119149 -428.328846) (xy 337.118452 -428.28972)
			(xy 334.235044 -428.28972) (xy 334.235044 -428.960534) (xy 334.234617 -428.972652) (xy 334.227118 -428.9957)
			(xy 334.212865 -429.015302) (xy 334.193253 -429.029542) (xy 334.1702 -429.037025) (xy 334.158082 -429.037496)
			(xy 333.218282 -429.037496) (xy 333.20617 -429.037004) (xy 333.183132 -429.029516) (xy 333.163533 -429.015278)
			(xy 333.149291 -428.995683) (xy 333.141798 -428.972646) (xy 333.14132 -428.960534) (xy 333.14132 -428.443898)
			(xy 333.130637 -428.406252) (xy 333.119157 -428.328846) (xy 333.11846 -428.28972) (xy 329.2348 -428.28972)
			(xy 329.2348 -428.960534) (xy 329.234322 -428.972621) (xy 329.226861 -428.995616) (xy 329.212676 -429.015192)
			(xy 329.193148 -429.029443) (xy 329.170178 -429.036981) (xy 329.158092 -429.037496) (xy 328.218292 -429.037496)
			(xy 328.206182 -429.037091) (xy 328.183154 -429.029588) (xy 328.163581 -429.015324) (xy 328.149386 -428.9957)
			(xy 328.141967 -428.972645) (xy 328.141584 -428.960534) (xy 328.141584 -428.44466) (xy 328.130788 -428.406838)
			(xy 328.119179 -428.329046) (xy 328.11847 -428.28972) (xy 325.234808 -428.28972) (xy 325.234808 -428.960534)
			(xy 325.234323 -428.972621) (xy 325.226862 -428.995614) (xy 325.212679 -429.01519) (xy 325.193153 -429.029441)
			(xy 325.170185 -429.03698) (xy 325.1581 -429.037496) (xy 324.2183 -429.037496) (xy 324.206191 -429.037084)
			(xy 324.183163 -429.029584) (xy 324.163589 -429.015321) (xy 324.149395 -428.995699) (xy 324.141975 -428.972645)
			(xy 324.141592 -428.960534) (xy 324.141592 -428.44466) (xy 324.130797 -428.406837) (xy 324.119188 -428.329046)
			(xy 324.118478 -428.28972) (xy 321.234816 -428.28972) (xy 321.234816 -428.960534) (xy 321.234421 -428.97263)
			(xy 321.226949 -428.995639) (xy 321.212746 -429.015222) (xy 321.193195 -429.02947) (xy 321.170203 -429.036993)
			(xy 321.158108 -429.037496) (xy 320.218308 -429.037496) (xy 320.206199 -429.037077) (xy 320.183171 -429.029579)
			(xy 320.163598 -429.015319) (xy 320.149403 -428.995697) (xy 320.141983 -428.972644) (xy 320.1416 -428.960534)
			(xy 320.1416 -428.44466) (xy 320.130805 -428.406837) (xy 320.119196 -428.329046) (xy 320.118486 -428.28972)
			(xy 317.234824 -428.28972) (xy 317.234824 -428.960534) (xy 317.234421 -428.972629) (xy 317.226951 -428.995637)
			(xy 317.212749 -429.015219) (xy 317.1932 -429.029467) (xy 317.17021 -429.036992) (xy 317.158116 -429.037496)
			(xy 316.218316 -429.037496) (xy 316.206208 -429.03707) (xy 316.18318 -429.029574) (xy 316.163607 -429.015315)
			(xy 316.149412 -428.995695) (xy 316.141991 -428.972644) (xy 316.141608 -428.960534) (xy 316.141608 -428.44466)
			(xy 316.130813 -428.406837) (xy 316.119204 -428.329046) (xy 316.118494 -428.28972) (xy 231.01554 -428.28972)
			(xy 231.01554 -433.130695) (xy 266.885917 -433.130695) (xy 266.885917 -432.953425) (xy 266.89387 -432.776334)
			(xy 266.909761 -432.599778) (xy 266.933556 -432.424113) (xy 266.965209 -432.249692) (xy 267.004655 -432.076867)
			(xy 267.051815 -431.905986) (xy 267.106594 -431.737392) (xy 267.168882 -431.571427) (xy 267.238554 -431.408422)
			(xy 267.315468 -431.248708) (xy 267.399471 -431.092605) (xy 267.490392 -430.940428) (xy 267.588049 -430.792484)
			(xy 267.692246 -430.64907) (xy 267.802772 -430.510475) (xy 267.919404 -430.376978) (xy 268.041909 -430.248849)
			(xy 268.170038 -430.126344) (xy 268.303535 -430.009712) (xy 268.44213 -429.899186) (xy 268.585544 -429.794989)
			(xy 268.733488 -429.697332) (xy 268.885665 -429.606411) (xy 269.041768 -429.522408) (xy 269.201482 -429.445494)
			(xy 269.364487 -429.375822) (xy 269.530452 -429.313534) (xy 269.699046 -429.258755) (xy 269.869927 -429.211595)
			(xy 270.042752 -429.172149) (xy 270.217173 -429.140496) (xy 270.392838 -429.116701) (xy 270.569394 -429.10081)
			(xy 270.746485 -429.092857) (xy 270.923755 -429.092857) (xy 271.100846 -429.10081) (xy 271.277402 -429.116701)
			(xy 271.453067 -429.140496) (xy 271.627488 -429.172149) (xy 271.800313 -429.211595) (xy 271.971194 -429.258755)
			(xy 272.139788 -429.313534) (xy 272.305753 -429.375822) (xy 272.468758 -429.445494) (xy 272.628472 -429.522408)
			(xy 272.784575 -429.606411) (xy 272.936752 -429.697332) (xy 273.084696 -429.794989) (xy 273.22811 -429.899186)
			(xy 273.366705 -430.009712) (xy 273.500202 -430.126344) (xy 273.628331 -430.248849) (xy 273.750836 -430.376978)
			(xy 273.867468 -430.510475) (xy 273.977994 -430.64907) (xy 274.082191 -430.792484) (xy 274.146507 -430.889918)
			(xy 314.138056 -430.889918) (xy 314.138165 -430.874832) (xy 314.139947 -430.844714) (xy 314.141612 -430.82972)
			(xy 314.141612 -429.749966) (xy 314.139947 -429.734972) (xy 314.138166 -429.704854) (xy 314.138056 -429.689768)
			(xy 314.13817 -429.674682) (xy 314.139948 -429.644564) (xy 314.141612 -429.62957) (xy 314.141612 -429.018954)
			(xy 314.142068 -429.006865) (xy 314.149534 -428.983867) (xy 314.163724 -428.964291) (xy 314.183258 -428.950041)
			(xy 314.206232 -428.942505) (xy 314.21832 -428.941992) (xy 315.15812 -428.941992) (xy 315.170229 -428.942399)
			(xy 315.193256 -428.949903) (xy 315.212828 -428.964167) (xy 315.227022 -428.98379) (xy 315.234444 -429.006843)
			(xy 315.234828 -429.018954) (xy 315.234828 -431.560478) (xy 315.234373 -431.57257) (xy 315.226919 -431.595575)
			(xy 315.21273 -431.615158) (xy 315.193192 -431.629408) (xy 315.17021 -431.636935) (xy 315.15812 -431.63744)
			(xy 314.21832 -431.63744) (xy 314.206216 -431.636967) (xy 314.183196 -431.629478) (xy 314.163627 -431.61523)
			(xy 314.14943 -431.595622) (xy 314.142001 -431.572583) (xy 314.141612 -431.560478) (xy 314.141612 -430.950116)
			(xy 314.139943 -430.935123) (xy 314.138165 -430.905004) (xy 314.138056 -430.889918) (xy 274.146507 -430.889918)
			(xy 274.179848 -430.940428) (xy 274.270769 -431.092605) (xy 274.354772 -431.248708) (xy 274.431686 -431.408422)
			(xy 274.501358 -431.571427) (xy 274.563646 -431.737392) (xy 274.613204 -431.889916) (xy 316.138052 -431.889916)
			(xy 316.138161 -431.87483) (xy 316.139943 -431.844712) (xy 316.141608 -431.829718) (xy 316.141608 -430.749964)
			(xy 316.139943 -430.73497) (xy 316.138162 -430.704852) (xy 316.138052 -430.689766) (xy 316.138166 -430.67468)
			(xy 316.139944 -430.644562) (xy 316.141608 -430.629568) (xy 316.141608 -430.018952) (xy 316.142023 -430.006873)
			(xy 316.149501 -429.983902) (xy 316.16371 -429.964364) (xy 316.183259 -429.950172) (xy 316.206237 -429.942713)
			(xy 316.218316 -429.942244) (xy 317.158116 -429.942244) (xy 317.170187 -429.94275) (xy 317.193146 -429.950211)
			(xy 317.212679 -429.964399) (xy 317.226874 -429.983925) (xy 317.234345 -430.006882) (xy 317.234824 -430.018952)
			(xy 317.234824 -430.889918) (xy 318.138048 -430.889918) (xy 318.138157 -430.874832) (xy 318.139939 -430.844714)
			(xy 318.141604 -430.82972) (xy 318.141604 -429.749966) (xy 318.139939 -429.734972) (xy 318.138158 -429.704854)
			(xy 318.138048 -429.689768) (xy 318.138162 -429.674682) (xy 318.13994 -429.644564) (xy 318.141604 -429.62957)
			(xy 318.141604 -429.018954) (xy 318.142067 -429.006866) (xy 318.149532 -428.98387) (xy 318.163721 -428.964293)
			(xy 318.183253 -428.950043) (xy 318.206225 -428.942506) (xy 318.218312 -428.941992) (xy 319.158112 -428.941992)
			(xy 319.170221 -428.942406) (xy 319.193247 -428.949908) (xy 319.212819 -428.96417) (xy 319.227014 -428.983792)
			(xy 319.234436 -429.006844) (xy 319.23482 -429.018954) (xy 319.23482 -431.560478) (xy 319.234373 -431.57257)
			(xy 319.226918 -431.595577) (xy 319.212727 -431.615161) (xy 319.193187 -431.629411) (xy 319.170203 -431.636936)
			(xy 319.158112 -431.63744) (xy 318.218312 -431.63744) (xy 318.206208 -431.636974) (xy 318.183188 -431.629483)
			(xy 318.163618 -431.615232) (xy 318.149422 -431.595624) (xy 318.141993 -431.572583) (xy 318.141604 -431.560478)
			(xy 318.141604 -430.950116) (xy 318.139935 -430.935123) (xy 318.138157 -430.905004) (xy 318.138048 -430.889918)
			(xy 317.234824 -430.889918) (xy 317.234824 -431.889916) (xy 320.138044 -431.889916) (xy 320.138153 -431.87483)
			(xy 320.139935 -431.844712) (xy 320.1416 -431.829718) (xy 320.1416 -430.749964) (xy 320.139935 -430.73497)
			(xy 320.138154 -430.704852) (xy 320.138044 -430.689766) (xy 320.138158 -430.67468) (xy 320.139936 -430.644562)
			(xy 320.1416 -430.629568) (xy 320.1416 -430.018952) (xy 320.142023 -430.006874) (xy 320.1495 -429.983904)
			(xy 320.163707 -429.964367) (xy 320.183254 -429.950174) (xy 320.20623 -429.942714) (xy 320.218308 -429.942244)
			(xy 321.158108 -429.942244) (xy 321.170178 -429.942757) (xy 321.193137 -429.950216) (xy 321.21267 -429.964401)
			(xy 321.226866 -429.983927) (xy 321.234337 -430.006882) (xy 321.234816 -430.018952) (xy 321.234816 -430.889918)
			(xy 322.13804 -430.889918) (xy 322.138151 -430.874832) (xy 322.139933 -430.844714) (xy 322.141596 -430.82972)
			(xy 322.141596 -429.749966) (xy 322.139931 -429.734972) (xy 322.13815 -429.704854) (xy 322.13804 -429.689768)
			(xy 322.138154 -429.674682) (xy 322.139932 -429.644564) (xy 322.141596 -429.62957) (xy 322.141596 -429.018954)
			(xy 322.142067 -429.006866) (xy 322.149531 -428.983872) (xy 322.163718 -428.964296) (xy 322.183248 -428.950046)
			(xy 322.206218 -428.942507) (xy 322.218304 -428.941992) (xy 323.158104 -428.941992) (xy 323.170212 -428.942413)
			(xy 323.193238 -428.949912) (xy 323.212811 -428.964173) (xy 323.227006 -428.983793) (xy 323.234428 -429.006844)
			(xy 323.234812 -429.018954) (xy 323.234812 -431.560478) (xy 323.234373 -431.572571) (xy 323.226916 -431.595579)
			(xy 323.212724 -431.615164) (xy 323.193182 -431.629413) (xy 323.170196 -431.636937) (xy 323.158104 -431.63744)
			(xy 322.218304 -431.63744) (xy 322.206199 -431.636981) (xy 322.183179 -431.629488) (xy 322.163609 -431.615236)
			(xy 322.149413 -431.595625) (xy 322.141985 -431.572584) (xy 322.141596 -431.560478) (xy 322.141596 -430.950116)
			(xy 322.139927 -430.935123) (xy 322.138149 -430.905004) (xy 322.13804 -430.889918) (xy 321.234816 -430.889918)
			(xy 321.234816 -431.889916) (xy 324.138036 -431.889916) (xy 324.138147 -431.87483) (xy 324.139929 -431.844712)
			(xy 324.141592 -431.829718) (xy 324.141592 -430.749964) (xy 324.139927 -430.73497) (xy 324.138146 -430.704852)
			(xy 324.138036 -430.689766) (xy 324.138152 -430.674681) (xy 324.13993 -430.644562) (xy 324.141592 -430.629568)
			(xy 324.141592 -430.018952) (xy 324.142023 -430.006875) (xy 324.149499 -429.983906) (xy 324.163704 -429.96437)
			(xy 324.183249 -429.950177) (xy 324.206223 -429.942716) (xy 324.2183 -429.942244) (xy 325.1581 -429.942244)
			(xy 325.17017 -429.942764) (xy 325.193129 -429.95022) (xy 325.212662 -429.964404) (xy 325.226858 -429.983928)
			(xy 325.234329 -430.006883) (xy 325.234808 -430.018952) (xy 325.234808 -430.889918) (xy 326.138032 -430.889918)
			(xy 326.138143 -430.874832) (xy 326.139925 -430.844714) (xy 326.141588 -430.82972) (xy 326.141588 -429.749966)
			(xy 326.139923 -429.734972) (xy 326.138142 -429.704854) (xy 326.138032 -429.689768) (xy 326.138148 -429.674683)
			(xy 326.139926 -429.644564) (xy 326.141588 -429.62957) (xy 326.141588 -429.018954) (xy 326.141969 -429.006857)
			(xy 326.149444 -428.983847) (xy 326.163651 -428.964264) (xy 326.183205 -428.950016) (xy 326.2062 -428.942494)
			(xy 326.218296 -428.941992) (xy 327.158096 -428.941992) (xy 327.170204 -428.942419) (xy 327.19323 -428.949917)
			(xy 327.212802 -428.964176) (xy 327.226997 -428.983795) (xy 327.23442 -429.006845) (xy 327.234804 -429.018954)
			(xy 327.234804 -431.560478) (xy 327.234275 -431.572562) (xy 327.226829 -431.595555) (xy 327.212657 -431.615131)
			(xy 327.19314 -431.629384) (xy 327.170178 -431.636924) (xy 327.158096 -431.63744) (xy 326.218296 -431.63744)
			(xy 326.206191 -431.636988) (xy 326.18317 -431.629492) (xy 326.163601 -431.615238) (xy 326.149405 -431.595627)
			(xy 326.141977 -431.572584) (xy 326.141588 -431.560478) (xy 326.141588 -430.950116) (xy 326.139919 -430.935123)
			(xy 326.138141 -430.905004) (xy 326.138032 -430.889918) (xy 325.234808 -430.889918) (xy 325.234808 -431.889916)
			(xy 328.138028 -431.889916) (xy 328.138139 -431.87483) (xy 328.139921 -431.844712) (xy 328.141584 -431.829718)
			(xy 328.141584 -430.749964) (xy 328.139919 -430.73497) (xy 328.138138 -430.704852) (xy 328.138028 -430.689766)
			(xy 328.138144 -430.674681) (xy 328.139922 -430.644562) (xy 328.141584 -430.629568) (xy 328.141584 -430.018952)
			(xy 328.142023 -430.006876) (xy 328.149498 -429.983908) (xy 328.163701 -429.964373) (xy 328.183244 -429.95018)
			(xy 328.206215 -429.942717) (xy 328.218292 -429.942244) (xy 329.158092 -429.942244) (xy 329.170161 -429.94277)
			(xy 329.19312 -429.950225) (xy 329.212653 -429.964407) (xy 329.22685 -429.98393) (xy 329.234321 -430.006883)
			(xy 329.2348 -430.018952) (xy 329.2348 -430.889918) (xy 331.138022 -430.889918) (xy 331.138116 -430.875344)
			(xy 331.139768 -430.846243) (xy 331.141324 -430.831752) (xy 331.141324 -429.747934) (xy 331.139776 -429.733442)
			(xy 331.138126 -429.704342) (xy 331.138022 -429.689768) (xy 331.138121 -429.675194) (xy 331.13977 -429.646093)
			(xy 331.141324 -429.631602) (xy 331.141324 -429.018954) (xy 331.141772 -429.006838) (xy 331.14927 -428.983796)
			(xy 331.163519 -428.964196) (xy 331.183125 -428.949956) (xy 331.20617 -428.942467) (xy 331.218286 -428.941992)
			(xy 332.158086 -428.941992) (xy 332.170195 -428.942523) (xy 332.19323 -428.950001) (xy 332.212828 -428.964229)
			(xy 332.227072 -428.983816) (xy 332.234568 -429.006845) (xy 332.235048 -429.018954) (xy 332.235048 -431.560478)
			(xy 332.234621 -431.572601) (xy 332.227133 -431.595662) (xy 332.212884 -431.615278) (xy 332.193269 -431.62953)
			(xy 332.170209 -431.63702) (xy 332.158086 -431.63744) (xy 331.218286 -431.63744) (xy 331.20616 -431.637051)
			(xy 331.183097 -431.629553) (xy 331.163481 -431.615294) (xy 331.149231 -431.59567) (xy 331.141743 -431.572604)
			(xy 331.141324 -431.560478) (xy 331.141324 -430.948084) (xy 331.139781 -430.933592) (xy 331.138128 -430.904492)
			(xy 331.138022 -430.889918) (xy 329.2348 -430.889918) (xy 329.2348 -431.889916) (xy 333.138018 -431.889916)
			(xy 333.138112 -431.875342) (xy 333.139764 -431.846241) (xy 333.14132 -431.83175) (xy 333.14132 -430.747932)
			(xy 333.139772 -430.73344) (xy 333.138122 -430.70434) (xy 333.138018 -430.689766) (xy 333.138117 -430.675192)
			(xy 333.139766 -430.646091) (xy 333.14132 -430.6316) (xy 333.14132 -430.018952) (xy 333.141676 -430.006839)
			(xy 333.149191 -429.983806) (xy 333.163467 -429.964232) (xy 333.183103 -429.95004) (xy 333.206167 -429.942624)
			(xy 333.218282 -429.942244) (xy 334.158082 -429.942244) (xy 334.170171 -429.942723) (xy 334.193172 -429.950175)
			(xy 334.212752 -429.964358) (xy 334.227003 -429.98389) (xy 334.234535 -430.006865) (xy 334.235044 -430.018952)
			(xy 334.235044 -430.889918) (xy 335.138014 -430.889918) (xy 335.138108 -430.875344) (xy 335.13976 -430.846243)
			(xy 335.141316 -430.831752) (xy 335.141316 -429.747934) (xy 335.139768 -429.733442) (xy 335.138118 -429.704342)
			(xy 335.138014 -429.689768) (xy 335.138112 -429.675194) (xy 335.139762 -429.646093) (xy 335.141316 -429.631602)
			(xy 335.141316 -429.018954) (xy 335.141772 -429.006839) (xy 335.149269 -428.983798) (xy 335.163516 -428.964199)
			(xy 335.18312 -428.949958) (xy 335.206163 -428.942468) (xy 335.218278 -428.941992) (xy 336.158078 -428.941992)
			(xy 336.170187 -428.94253) (xy 336.193222 -428.950005) (xy 336.21282 -428.964232) (xy 336.227064 -428.983817)
			(xy 336.234559 -429.006846) (xy 336.23504 -429.018954) (xy 336.23504 -431.560478) (xy 336.234621 -431.572602)
			(xy 336.227132 -431.595664) (xy 336.212881 -431.615281) (xy 336.193264 -431.629532) (xy 336.170202 -431.637021)
			(xy 336.158078 -431.63744) (xy 335.218278 -431.63744) (xy 335.20616 -431.637007) (xy 335.183112 -431.629511)
			(xy 335.163509 -431.61526) (xy 335.149269 -431.595648) (xy 335.141786 -431.572596) (xy 335.141316 -431.560478)
			(xy 335.141316 -430.948084) (xy 335.139773 -430.933592) (xy 335.13812 -430.904492) (xy 335.138014 -430.889918)
			(xy 334.235044 -430.889918) (xy 334.235044 -431.889916) (xy 337.13801 -431.889916) (xy 337.138104 -431.875342)
			(xy 337.139756 -431.846241) (xy 337.141312 -431.83175) (xy 337.141312 -430.747932) (xy 337.139764 -430.73344)
			(xy 337.138114 -430.70434) (xy 337.13801 -430.689766) (xy 337.138108 -430.675192) (xy 337.139757 -430.646091)
			(xy 337.141312 -430.6316) (xy 337.141312 -430.018952) (xy 337.141676 -430.006839) (xy 337.14919 -429.983809)
			(xy 337.163465 -429.964235) (xy 337.183098 -429.950043) (xy 337.20616 -429.942625) (xy 337.218274 -429.942244)
			(xy 338.158074 -429.942244) (xy 338.170163 -429.94273) (xy 338.193163 -429.95018) (xy 338.212744 -429.964361)
			(xy 338.226995 -429.983891) (xy 338.234527 -430.006865) (xy 338.235036 -430.018952) (xy 338.235036 -430.889918)
			(xy 339.138006 -430.889918) (xy 339.1381 -430.875344) (xy 339.139752 -430.846243) (xy 339.141308 -430.831752)
			(xy 339.141308 -429.747934) (xy 339.13976 -429.733442) (xy 339.13811 -429.704342) (xy 339.138006 -429.689768)
			(xy 339.138104 -429.675194) (xy 339.139754 -429.646093) (xy 339.141308 -429.631602) (xy 339.141308 -429.018954)
			(xy 339.141772 -429.00684) (xy 339.149268 -428.9838) (xy 339.163513 -428.964202) (xy 339.183115 -428.949961)
			(xy 339.206156 -428.94247) (xy 339.21827 -428.941992) (xy 340.15807 -428.941992) (xy 340.170178 -428.942537)
			(xy 340.193213 -428.95001) (xy 340.212811 -428.964235) (xy 340.227055 -428.983819) (xy 340.234551 -429.006846)
			(xy 340.235032 -429.018954) (xy 340.235032 -431.560478) (xy 340.234621 -431.572603) (xy 340.227131 -431.595666)
			(xy 340.212878 -431.615284) (xy 340.193259 -431.629535) (xy 340.170195 -431.637022) (xy 340.15807 -431.63744)
			(xy 339.21827 -431.63744) (xy 339.206152 -431.637014) (xy 339.183104 -431.629515) (xy 339.163501 -431.615262)
			(xy 339.149261 -431.59565) (xy 339.141778 -431.572597) (xy 339.141308 -431.560478) (xy 339.141308 -430.948084)
			(xy 339.139764 -430.933592) (xy 339.138112 -430.904492) (xy 339.138006 -430.889918) (xy 338.235036 -430.889918)
			(xy 338.235036 -431.889916) (xy 341.138002 -431.889916) (xy 341.138096 -431.875342) (xy 341.139748 -431.846241)
			(xy 341.141304 -431.83175) (xy 341.141304 -430.747932) (xy 341.139756 -430.73344) (xy 341.138106 -430.70434)
			(xy 341.138002 -430.689766) (xy 341.1381 -430.675192) (xy 341.13975 -430.646091) (xy 341.141304 -430.6316)
			(xy 341.141304 -430.018952) (xy 341.141676 -430.00684) (xy 341.149189 -429.983811) (xy 341.163462 -429.964238)
			(xy 341.183093 -429.950045) (xy 341.206153 -429.942626) (xy 341.218266 -429.942244) (xy 342.158066 -429.942244)
			(xy 342.170154 -429.942736) (xy 342.193154 -429.950184) (xy 342.212735 -429.964364) (xy 342.226987 -429.983893)
			(xy 342.234519 -430.006866) (xy 342.235028 -430.018952) (xy 342.235028 -430.889918) (xy 343.137998 -430.889918)
			(xy 343.138092 -430.875344) (xy 343.139744 -430.846243) (xy 343.1413 -430.831752) (xy 343.1413 -429.747934)
			(xy 343.139752 -429.733442) (xy 343.138102 -429.704342) (xy 343.137998 -429.689768) (xy 343.138096 -429.675194)
			(xy 343.139746 -429.646093) (xy 343.1413 -429.631602) (xy 343.1413 -429.018954) (xy 343.141772 -429.006841)
			(xy 343.149267 -428.983803) (xy 343.163511 -428.964205) (xy 343.18311 -428.949964) (xy 343.206149 -428.942471)
			(xy 343.218262 -428.941992) (xy 344.158062 -428.941992) (xy 344.17017 -428.942543) (xy 344.193204 -428.950015)
			(xy 344.212803 -428.964238) (xy 344.227047 -428.98382) (xy 344.234543 -429.006847) (xy 344.235024 -429.018954)
			(xy 344.235024 -431.560478) (xy 344.234621 -431.572603) (xy 344.22713 -431.595668) (xy 344.212875 -431.615287)
			(xy 344.193254 -431.629537) (xy 344.170187 -431.637023) (xy 344.158062 -431.63744) (xy 343.218262 -431.63744)
			(xy 343.206143 -431.63702) (xy 343.183095 -431.62952) (xy 343.163492 -431.615265) (xy 343.149253 -431.595651)
			(xy 343.14177 -431.572597) (xy 343.1413 -431.560478) (xy 343.1413 -430.948084) (xy 343.139756 -430.933592)
			(xy 343.138104 -430.904492) (xy 343.137998 -430.889918) (xy 342.235028 -430.889918) (xy 342.235028 -431.889916)
			(xy 345.137994 -431.889916) (xy 345.138088 -431.875342) (xy 345.13974 -431.846241) (xy 345.141296 -431.83175)
			(xy 345.141296 -430.747932) (xy 345.139748 -430.73344) (xy 345.138098 -430.70434) (xy 345.137994 -430.689766)
			(xy 345.138092 -430.675192) (xy 345.139742 -430.646091) (xy 345.141296 -430.6316) (xy 345.141296 -430.018952)
			(xy 345.141676 -430.006841) (xy 345.149188 -429.983813) (xy 345.163459 -429.964241) (xy 345.183088 -429.950048)
			(xy 345.206145 -429.942628) (xy 345.218258 -429.942244) (xy 346.158058 -429.942244) (xy 346.170146 -429.942743)
			(xy 346.193146 -429.950189) (xy 346.212727 -429.964367) (xy 346.226979 -429.983894) (xy 346.234511 -430.006866)
			(xy 346.23502 -430.018952) (xy 346.23502 -431.359818) (xy 356.154736 -431.359818) (xy 356.155234 -431.274938)
			(xy 356.163191 -431.105365) (xy 356.179087 -430.936351) (xy 356.202888 -430.768268) (xy 356.234542 -430.601485)
			(xy 356.273978 -430.436369) (xy 356.32111 -430.273284) (xy 356.375834 -430.112586) (xy 356.438031 -429.954631)
			(xy 356.507563 -429.799764) (xy 356.584278 -429.648327) (xy 356.668006 -429.500651) (xy 356.758564 -429.357063)
			(xy 356.855753 -429.217877) (xy 356.95936 -429.0834) (xy 357.069155 -428.953927) (xy 357.184899 -428.829742)
			(xy 357.306336 -428.711119) (xy 357.4332 -428.598318) (xy 357.565211 -428.491588) (xy 357.702081 -428.391163)
			(xy 357.843506 -428.297264) (xy 357.989178 -428.210096) (xy 358.138776 -428.129853) (xy 358.29197 -428.056709)
			(xy 358.448424 -427.990827) (xy 358.607794 -427.93235) (xy 358.76973 -427.881408) (xy 358.933876 -427.838112)
			(xy 359.099871 -427.802557) (xy 359.26735 -427.774822) (xy 359.435945 -427.754968) (xy 359.605285 -427.743038)
			(xy 359.774998 -427.739059) (xy 359.944711 -427.743038) (xy 360.114051 -427.754968) (xy 360.282646 -427.774822)
			(xy 360.450125 -427.802557) (xy 360.61612 -427.838112) (xy 360.780266 -427.881408) (xy 360.942202 -427.93235)
			(xy 361.101572 -427.990827) (xy 361.258026 -428.056709) (xy 361.41122 -428.129853) (xy 361.560818 -428.210096)
			(xy 361.693883 -428.28972) (xy 383.237994 -428.28972) (xy 383.238088 -428.275146) (xy 383.23974 -428.246045)
			(xy 383.241296 -428.231554) (xy 383.241296 -427.14799) (xy 383.239753 -427.133498) (xy 383.2381 -427.104398)
			(xy 383.237994 -427.089824) (xy 383.238088 -427.07525) (xy 383.23974 -427.046149) (xy 383.241296 -427.031658)
			(xy 383.241296 -426.41901) (xy 383.24182 -426.4069) (xy 383.249299 -426.383864) (xy 383.263529 -426.364266)
			(xy 383.283118 -426.350023) (xy 383.306148 -426.342528) (xy 383.318258 -426.342048) (xy 384.258058 -426.342048)
			(xy 384.27018 -426.342496) (xy 384.293239 -426.349978) (xy 384.312855 -426.364222) (xy 384.327108 -426.383833)
			(xy 384.334599 -426.406889) (xy 384.33502 -426.41901) (xy 384.33502 -427.289976) (xy 385.23799 -427.289976)
			(xy 385.23808 -427.275402) (xy 385.239735 -427.246301) (xy 385.241292 -427.23181) (xy 385.241292 -426.147992)
			(xy 385.239749 -426.1335) (xy 385.238096 -426.1044) (xy 385.23799 -426.089826) (xy 385.238085 -426.075252)
			(xy 385.239736 -426.046151) (xy 385.241292 -426.03166) (xy 385.241292 -425.419012) (xy 385.241727 -425.406905)
			(xy 385.249222 -425.383879) (xy 385.263479 -425.364307) (xy 385.283096 -425.350111) (xy 385.306145 -425.342689)
			(xy 385.318254 -425.342304) (xy 386.258054 -425.342304) (xy 386.270138 -425.342846) (xy 386.293131 -425.350286)
			(xy 386.312708 -425.364454) (xy 386.326962 -425.38397) (xy 386.334501 -425.40693) (xy 386.335016 -425.419012)
			(xy 386.335016 -427.960536) (xy 386.334615 -427.972645) (xy 386.327107 -427.995671) (xy 386.312841 -428.015242)
			(xy 386.293218 -428.029436) (xy 386.270165 -428.036859) (xy 386.258054 -428.037244) (xy 385.318254 -428.037244)
			(xy 385.30616 -428.036832) (xy 385.283156 -428.02936) (xy 385.263575 -428.01516) (xy 385.249327 -427.995615)
			(xy 385.241799 -427.972628) (xy 385.241292 -427.960536) (xy 385.241292 -427.348142) (xy 385.239745 -427.33365)
			(xy 385.238095 -427.30455) (xy 385.23799 -427.289976) (xy 384.33502 -427.289976) (xy 384.33502 -428.28972)
			(xy 387.237986 -428.28972) (xy 387.23808 -428.275146) (xy 387.239732 -428.246045) (xy 387.241288 -428.231554)
			(xy 387.241288 -427.14799) (xy 387.239745 -427.133498) (xy 387.238092 -427.104398) (xy 387.237986 -427.089824)
			(xy 387.238081 -427.07525) (xy 387.239732 -427.046149) (xy 387.241288 -427.031658) (xy 387.241288 -426.41901)
			(xy 387.24182 -426.406901) (xy 387.249298 -426.383867) (xy 387.263526 -426.364269) (xy 387.283113 -426.350025)
			(xy 387.306141 -426.342529) (xy 387.31825 -426.342048) (xy 388.25805 -426.342048) (xy 388.270168 -426.342469)
			(xy 388.293215 -426.349972) (xy 388.312816 -426.364226) (xy 388.327056 -426.383839) (xy 388.33454 -426.406891)
			(xy 388.335012 -426.41901) (xy 388.335012 -427.289976) (xy 389.237982 -427.289976) (xy 389.238072 -427.275402)
			(xy 389.239727 -427.246301) (xy 389.241284 -427.23181) (xy 389.241284 -426.147992) (xy 389.239741 -426.1335)
			(xy 389.238088 -426.1044) (xy 389.237982 -426.089826) (xy 389.238077 -426.075252) (xy 389.239728 -426.046151)
			(xy 389.241284 -426.03166) (xy 389.241284 -425.419012) (xy 389.241727 -425.406905) (xy 389.249221 -425.383881)
			(xy 389.263476 -425.364309) (xy 389.283091 -425.350114) (xy 389.306138 -425.34269) (xy 389.318246 -425.342304)
			(xy 390.258046 -425.342304) (xy 390.270134 -425.342767) (xy 390.29313 -425.350232) (xy 390.312707 -425.364421)
			(xy 390.326957 -425.383953) (xy 390.334494 -425.406925) (xy 390.335008 -425.419012) (xy 390.335008 -427.960536)
			(xy 390.334614 -427.972646) (xy 390.327106 -427.995673) (xy 390.312838 -428.015245) (xy 390.293213 -428.029438)
			(xy 390.270157 -428.03686) (xy 390.258046 -428.037244) (xy 389.318246 -428.037244) (xy 389.306157 -428.036753)
			(xy 389.283155 -428.029307) (xy 389.263573 -428.015127) (xy 389.249322 -427.995597) (xy 389.241791 -427.972623)
			(xy 389.241284 -427.960536) (xy 389.241284 -427.348142) (xy 389.239737 -427.33365) (xy 389.238087 -427.30455)
			(xy 389.237982 -427.289976) (xy 388.335012 -427.289976) (xy 388.335012 -428.28972) (xy 391.237978 -428.28972)
			(xy 391.238072 -428.275146) (xy 391.239724 -428.246045) (xy 391.24128 -428.231554) (xy 391.24128 -427.14799)
			(xy 391.239737 -427.133498) (xy 391.238084 -427.104398) (xy 391.237978 -427.089824) (xy 391.238073 -427.07525)
			(xy 391.239724 -427.046149) (xy 391.24128 -427.031658) (xy 391.24128 -426.41901) (xy 391.241669 -426.406884)
			(xy 391.249164 -426.383818) (xy 391.263422 -426.364199) (xy 391.283047 -426.349949) (xy 391.306115 -426.342464)
			(xy 391.318242 -426.342048) (xy 392.258042 -426.342048) (xy 392.27016 -426.342476) (xy 392.293206 -426.349976)
			(xy 392.312808 -426.364229) (xy 392.327048 -426.383841) (xy 392.334532 -426.406892) (xy 392.335004 -426.41901)
			(xy 392.335004 -427.289976) (xy 393.237974 -427.289976) (xy 393.238064 -427.275402) (xy 393.239719 -427.246301)
			(xy 393.241276 -427.23181) (xy 393.241276 -426.147992) (xy 393.239733 -426.1335) (xy 393.23808 -426.1044)
			(xy 393.237974 -426.089826) (xy 393.238069 -426.075252) (xy 393.23972 -426.046151) (xy 393.241276 -426.03166)
			(xy 393.241276 -425.419012) (xy 393.241726 -425.406906) (xy 393.24922 -425.383883) (xy 393.263473 -425.364312)
			(xy 393.283086 -425.350116) (xy 393.306131 -425.342691) (xy 393.318238 -425.342304) (xy 394.258038 -425.342304)
			(xy 394.270126 -425.342774) (xy 394.293122 -425.350237) (xy 394.312698 -425.364424) (xy 394.326949 -425.383954)
			(xy 394.334486 -425.406926) (xy 394.335 -425.419012) (xy 394.335 -427.960536) (xy 394.334614 -427.972647)
			(xy 394.327105 -427.995675) (xy 394.312835 -428.015248) (xy 394.293208 -428.029441) (xy 394.27015 -428.036861)
			(xy 394.258038 -428.037244) (xy 393.318238 -428.037244) (xy 393.306149 -428.03676) (xy 393.283147 -428.029312)
			(xy 393.263565 -428.01513) (xy 393.249314 -427.995599) (xy 393.241783 -427.972623) (xy 393.241276 -427.960536)
			(xy 393.241276 -427.348142) (xy 393.239729 -427.33365) (xy 393.238079 -427.30455) (xy 393.237974 -427.289976)
			(xy 392.335004 -427.289976) (xy 392.335004 -428.28972) (xy 395.23797 -428.28972) (xy 395.238064 -428.275146)
			(xy 395.239716 -428.246045) (xy 395.241272 -428.231554) (xy 395.241272 -427.14799) (xy 395.239729 -427.133498)
			(xy 395.238076 -427.104398) (xy 395.23797 -427.089824) (xy 395.238065 -427.07525) (xy 395.239716 -427.046149)
			(xy 395.241272 -427.031658) (xy 395.241272 -426.41901) (xy 395.241669 -426.406884) (xy 395.249163 -426.38382)
			(xy 395.263419 -426.364202) (xy 395.283042 -426.349952) (xy 395.306108 -426.342465) (xy 395.318234 -426.342048)
			(xy 396.258034 -426.342048) (xy 396.270151 -426.342483) (xy 396.293197 -426.349981) (xy 396.312799 -426.364232)
			(xy 396.327039 -426.383842) (xy 396.334524 -426.406892) (xy 396.334996 -426.41901) (xy 396.334996 -427.289976)
			(xy 398.237964 -427.289976) (xy 398.238078 -427.274891) (xy 398.239856 -427.244772) (xy 398.24152 -427.229778)
			(xy 398.24152 -426.150024) (xy 398.239851 -426.135031) (xy 398.238073 -426.104912) (xy 398.237964 -426.089826)
			(xy 398.238074 -426.07474) (xy 398.239855 -426.044622) (xy 398.24152 -426.029628) (xy 398.24152 -425.419012)
			(xy 398.241924 -425.406927) (xy 398.249391 -425.38394) (xy 398.263599 -425.364387) (xy 398.283154 -425.350184)
			(xy 398.306143 -425.342721) (xy 398.318228 -425.342304) (xy 399.258028 -425.342304) (xy 399.270105 -425.34274)
			(xy 399.293075 -425.350212) (xy 399.312613 -425.364415) (xy 399.326806 -425.38396) (xy 399.334266 -425.406935)
			(xy 399.334736 -425.419012) (xy 399.334736 -427.960536) (xy 399.334267 -427.97261) (xy 399.326798 -427.995573)
			(xy 399.312602 -428.015107) (xy 399.293066 -428.029302) (xy 399.270102 -428.036768) (xy 399.258028 -428.037244)
			(xy 398.318228 -428.037244) (xy 398.306158 -428.036713) (xy 398.283198 -428.029262) (xy 398.263664 -428.015082)
			(xy 398.249467 -427.995559) (xy 398.241997 -427.972605) (xy 398.24152 -427.960536) (xy 398.24152 -427.350174)
			(xy 398.239856 -427.33518) (xy 398.238074 -427.305062) (xy 398.237964 -427.289976) (xy 396.334996 -427.289976)
			(xy 396.334996 -428.28972) (xy 400.23796 -428.28972) (xy 400.238069 -428.274634) (xy 400.239851 -428.244516)
			(xy 400.241516 -428.229522) (xy 400.241516 -427.150022) (xy 400.239847 -427.135029) (xy 400.238069 -427.10491)
			(xy 400.23796 -427.089824) (xy 400.23807 -427.074738) (xy 400.239851 -427.04462) (xy 400.241516 -427.029626)
			(xy 400.241516 -426.41901) (xy 400.242016 -426.406923) (xy 400.249467 -426.383927) (xy 400.263646 -426.364349)
			(xy 400.283171 -426.350097) (xy 400.306139 -426.342561) (xy 400.318224 -426.342048) (xy 401.258024 -426.342048)
			(xy 401.270129 -426.342495) (xy 401.293148 -426.349995) (xy 401.312716 -426.36425) (xy 401.326912 -426.383862)
			(xy 401.334341 -426.406904) (xy 401.334732 -426.41901) (xy 401.334732 -427.289976) (xy 402.237956 -427.289976)
			(xy 402.23807 -427.274891) (xy 402.239848 -427.244772) (xy 402.241512 -427.229778) (xy 402.241512 -426.150024)
			(xy 402.239843 -426.135031) (xy 402.238065 -426.104912) (xy 402.237956 -426.089826) (xy 402.238066 -426.07474)
			(xy 402.239847 -426.044622) (xy 402.241512 -426.029628) (xy 402.241512 -425.419012) (xy 402.241923 -425.406928)
			(xy 402.24939 -425.383942) (xy 402.263596 -425.36439) (xy 402.283149 -425.350186) (xy 402.306136 -425.342722)
			(xy 402.31822 -425.342304) (xy 403.25802 -425.342304) (xy 403.270097 -425.342748) (xy 403.293067 -425.350217)
			(xy 403.312604 -425.364419) (xy 403.326798 -425.383962) (xy 403.334257 -425.406935) (xy 403.334728 -425.419012)
			(xy 403.334728 -427.960536) (xy 403.334267 -427.97261) (xy 403.326797 -427.995576) (xy 403.312599 -428.01511)
			(xy 403.293061 -428.029304) (xy 403.270095 -428.036769) (xy 403.25802 -428.037244) (xy 402.31822 -428.037244)
			(xy 402.30615 -428.036719) (xy 402.28319 -428.029267) (xy 402.263655 -428.015085) (xy 402.249459 -427.995561)
			(xy 402.241989 -427.972606) (xy 402.241512 -427.960536) (xy 402.241512 -427.350174) (xy 402.239848 -427.33518)
			(xy 402.238066 -427.305062) (xy 402.237956 -427.289976) (xy 401.334732 -427.289976) (xy 401.334732 -428.28972)
			(xy 404.237952 -428.28972) (xy 404.238062 -428.274634) (xy 404.239843 -428.244516) (xy 404.241508 -428.229522)
			(xy 404.241508 -427.150022) (xy 404.239839 -427.135029) (xy 404.238061 -427.10491) (xy 404.237952 -427.089824)
			(xy 404.238062 -427.074738) (xy 404.239843 -427.04462) (xy 404.241508 -427.029626) (xy 404.241508 -426.41901)
			(xy 404.242015 -426.406924) (xy 404.249465 -426.383929) (xy 404.263643 -426.364352) (xy 404.283166 -426.3501)
			(xy 404.306132 -426.342562) (xy 404.318216 -426.342048) (xy 405.258016 -426.342048) (xy 405.270121 -426.342502)
			(xy 405.293139 -426.349999) (xy 405.312708 -426.364253) (xy 405.326904 -426.383863) (xy 405.334333 -426.406904)
			(xy 405.334724 -426.41901) (xy 405.334724 -427.289976) (xy 406.237948 -427.289976) (xy 406.238062 -427.274891)
			(xy 406.23984 -427.244772) (xy 406.241504 -427.229778) (xy 406.241504 -426.150024) (xy 406.239835 -426.135031)
			(xy 406.238057 -426.104912) (xy 406.237948 -426.089826) (xy 406.238058 -426.07474) (xy 406.239839 -426.044622)
			(xy 406.241504 -426.029628) (xy 406.241504 -425.419012) (xy 406.241923 -425.406929) (xy 406.249389 -425.383944)
			(xy 406.263593 -425.364393) (xy 406.283144 -425.350189) (xy 406.306129 -425.342723) (xy 406.318212 -425.342304)
			(xy 407.258012 -425.342304) (xy 407.270088 -425.342754) (xy 407.293058 -425.350222) (xy 407.312596 -425.364421)
			(xy 407.326789 -425.383964) (xy 407.334249 -425.406935) (xy 407.33472 -425.419012) (xy 407.33472 -427.960536)
			(xy 407.334267 -427.972611) (xy 407.326796 -427.995578) (xy 407.312596 -428.015113) (xy 407.293056 -428.029307)
			(xy 407.270087 -428.036771) (xy 407.258012 -428.037244) (xy 406.318212 -428.037244) (xy 406.306142 -428.036726)
			(xy 406.283181 -428.029271) (xy 406.263647 -428.015087) (xy 406.249451 -427.995562) (xy 406.241981 -427.972606)
			(xy 406.241504 -427.960536) (xy 406.241504 -427.350174) (xy 406.23984 -427.33518) (xy 406.238058 -427.305062)
			(xy 406.237948 -427.289976) (xy 405.334724 -427.289976) (xy 405.334724 -428.28972) (xy 408.237944 -428.28972)
			(xy 408.238054 -428.274634) (xy 408.239835 -428.244516) (xy 408.2415 -428.229522) (xy 408.2415 -427.150022)
			(xy 408.239831 -427.135029) (xy 408.238053 -427.10491) (xy 408.237944 -427.089824) (xy 408.238054 -427.074738)
			(xy 408.239835 -427.04462) (xy 408.2415 -427.029626) (xy 408.2415 -426.41901) (xy 408.242015 -426.406925)
			(xy 408.249464 -426.383931) (xy 408.26364 -426.364355) (xy 408.283161 -426.350103) (xy 408.306125 -426.342563)
			(xy 408.318208 -426.342048) (xy 409.258008 -426.342048) (xy 409.270112 -426.342509) (xy 409.293131 -426.350004)
			(xy 409.312699 -426.364256) (xy 409.326896 -426.383865) (xy 409.334325 -426.406905) (xy 409.334716 -426.41901)
			(xy 409.334716 -427.289976) (xy 410.23794 -427.289976) (xy 410.238055 -427.274891) (xy 410.239832 -427.244772)
			(xy 410.241496 -427.229778) (xy 410.241496 -426.150024) (xy 410.239827 -426.135031) (xy 410.238049 -426.104912)
			(xy 410.23794 -426.089826) (xy 410.23805 -426.07474) (xy 410.239831 -426.044622) (xy 410.241496 -426.029628)
			(xy 410.241496 -425.419012) (xy 410.241923 -425.40693) (xy 410.249388 -425.383947) (xy 410.26359 -425.364396)
			(xy 410.283139 -425.350191) (xy 410.306122 -425.342724) (xy 410.318204 -425.342304) (xy 411.258004 -425.342304)
			(xy 411.270088 -425.342709) (xy 411.293073 -425.350179) (xy 411.312624 -425.364387) (xy 411.326828 -425.383941)
			(xy 411.334293 -425.406928) (xy 411.334712 -425.419012) (xy 411.334712 -427.960536) (xy 411.334267 -427.972612)
			(xy 411.326795 -427.99558) (xy 411.312593 -428.015116) (xy 411.293051 -428.029309) (xy 411.27008 -428.036772)
			(xy 411.258004 -428.037244) (xy 410.318204 -428.037244) (xy 410.306133 -428.036733) (xy 410.283172 -428.029276)
			(xy 410.263638 -428.01509) (xy 410.249442 -427.995564) (xy 410.241973 -427.972607) (xy 410.241496 -427.960536)
			(xy 410.241496 -427.350174) (xy 410.239832 -427.33518) (xy 410.23805 -427.305062) (xy 410.23794 -427.289976)
			(xy 409.334716 -427.289976) (xy 409.334716 -428.28972) (xy 412.237936 -428.28972) (xy 412.238048 -428.274634)
			(xy 412.239829 -428.244516) (xy 412.241492 -428.229522) (xy 412.241492 -427.150022) (xy 412.239823 -427.135029)
			(xy 412.238045 -427.10491) (xy 412.237936 -427.089824) (xy 412.238048 -427.074738) (xy 412.239829 -427.04462)
			(xy 412.241492 -427.029626) (xy 412.241492 -426.41901) (xy 412.242015 -426.406926) (xy 412.249463 -426.383934)
			(xy 412.263637 -426.364358) (xy 412.283156 -426.350105) (xy 412.306118 -426.342564) (xy 412.3182 -426.342048)
			(xy 413.258 -426.342048) (xy 413.270104 -426.342515) (xy 413.293122 -426.350009) (xy 413.312691 -426.364259)
			(xy 413.326887 -426.383866) (xy 413.334317 -426.406905) (xy 413.334708 -426.41901) (xy 413.334708 -428.960534)
			(xy 413.334223 -428.972621) (xy 413.326762 -428.995614) (xy 413.312579 -429.01519) (xy 413.293053 -429.029441)
			(xy 413.270085 -429.03698) (xy 413.258 -429.037496) (xy 412.3182 -429.037496) (xy 412.306091 -429.037084)
			(xy 412.283063 -429.029584) (xy 412.263489 -429.015321) (xy 412.249295 -428.995699) (xy 412.241875 -428.972645)
			(xy 412.241492 -428.960534) (xy 412.241492 -428.349918) (xy 412.239823 -428.334925) (xy 412.238045 -428.304806)
			(xy 412.237936 -428.28972) (xy 409.334716 -428.28972) (xy 409.334716 -428.960534) (xy 409.334321 -428.97263)
			(xy 409.326849 -428.995639) (xy 409.312646 -429.015222) (xy 409.293095 -429.02947) (xy 409.270103 -429.036993)
			(xy 409.258008 -429.037496) (xy 408.318208 -429.037496) (xy 408.306099 -429.037077) (xy 408.283071 -429.029579)
			(xy 408.263498 -429.015319) (xy 408.249303 -428.995697) (xy 408.241883 -428.972644) (xy 408.2415 -428.960534)
			(xy 408.2415 -428.349918) (xy 408.239831 -428.334925) (xy 408.238053 -428.304806) (xy 408.237944 -428.28972)
			(xy 405.334724 -428.28972) (xy 405.334724 -428.960534) (xy 405.334321 -428.972629) (xy 405.326851 -428.995637)
			(xy 405.312649 -429.015219) (xy 405.2931 -429.029467) (xy 405.27011 -429.036992) (xy 405.258016 -429.037496)
			(xy 404.318216 -429.037496) (xy 404.306108 -429.03707) (xy 404.28308 -429.029574) (xy 404.263507 -429.015315)
			(xy 404.249312 -428.995695) (xy 404.241891 -428.972644) (xy 404.241508 -428.960534) (xy 404.241508 -428.349918)
			(xy 404.239839 -428.334925) (xy 404.238061 -428.304806) (xy 404.237952 -428.28972) (xy 401.334732 -428.28972)
			(xy 401.334732 -428.960534) (xy 401.334321 -428.972628) (xy 401.326852 -428.995635) (xy 401.312652 -429.015216)
			(xy 401.293105 -429.029465) (xy 401.270117 -429.036991) (xy 401.258024 -429.037496) (xy 400.318224 -429.037496)
			(xy 400.306116 -429.037063) (xy 400.283089 -429.02957) (xy 400.263515 -429.015313) (xy 400.24932 -428.995694)
			(xy 400.241899 -428.972643) (xy 400.241516 -428.960534) (xy 400.241516 -428.349918) (xy 400.239847 -428.334925)
			(xy 400.238069 -428.304806) (xy 400.23796 -428.28972) (xy 396.334996 -428.28972) (xy 396.334996 -428.960534)
			(xy 396.334518 -428.972647) (xy 396.327025 -428.995686) (xy 396.312784 -429.015284) (xy 396.293186 -429.029525)
			(xy 396.270147 -429.037018) (xy 396.258034 -429.037496) (xy 395.318234 -429.037496) (xy 395.306125 -429.03696)
			(xy 395.283088 -429.029486) (xy 395.263489 -429.01526) (xy 395.249245 -428.995673) (xy 395.241751 -428.972643)
			(xy 395.241272 -428.960534) (xy 395.241272 -428.347886) (xy 395.239729 -428.333394) (xy 395.238076 -428.304294)
			(xy 395.23797 -428.28972) (xy 392.335004 -428.28972) (xy 392.335004 -428.960534) (xy 392.334518 -428.972646)
			(xy 392.327027 -428.995683) (xy 392.312787 -429.015281) (xy 392.293191 -429.029523) (xy 392.270154 -429.037017)
			(xy 392.258042 -429.037496) (xy 391.318242 -429.037496) (xy 391.306125 -429.037005) (xy 391.283073 -429.029528)
			(xy 391.26346 -429.015294) (xy 391.249206 -428.995695) (xy 391.241707 -428.972651) (xy 391.24128 -428.960534)
			(xy 391.24128 -428.347886) (xy 391.239737 -428.333394) (xy 391.238084 -428.304294) (xy 391.237978 -428.28972)
			(xy 388.335012 -428.28972) (xy 388.335012 -428.960534) (xy 388.334518 -428.972645) (xy 388.327028 -428.995681)
			(xy 388.31279 -429.015278) (xy 388.293196 -429.02952) (xy 388.270161 -429.037016) (xy 388.25805 -429.037496)
			(xy 387.31825 -429.037496) (xy 387.306136 -429.037031) (xy 387.283097 -429.029535) (xy 387.263499 -429.015289)
			(xy 387.249258 -428.995689) (xy 387.241766 -428.972648) (xy 387.241288 -428.960534) (xy 387.241288 -428.347886)
			(xy 387.239745 -428.333394) (xy 387.238092 -428.304294) (xy 387.237986 -428.28972) (xy 384.33502 -428.28972)
			(xy 384.33502 -428.960534) (xy 384.334669 -428.972663) (xy 384.327162 -428.99573) (xy 384.312894 -429.015348)
			(xy 384.293262 -429.029597) (xy 384.270187 -429.03708) (xy 384.258058 -429.037496) (xy 383.318258 -429.037496)
			(xy 383.306145 -429.037025) (xy 383.283106 -429.02953) (xy 383.263508 -429.015287) (xy 383.249266 -428.995687)
			(xy 383.241774 -428.972647) (xy 383.241296 -428.960534) (xy 383.241296 -428.347886) (xy 383.239753 -428.333394)
			(xy 383.2381 -428.304294) (xy 383.237994 -428.28972) (xy 361.693883 -428.28972) (xy 361.70649 -428.297264)
			(xy 361.847915 -428.391163) (xy 361.984785 -428.491588) (xy 362.116796 -428.598318) (xy 362.24366 -428.711119)
			(xy 362.365097 -428.829742) (xy 362.480841 -428.953927) (xy 362.590636 -429.0834) (xy 362.694243 -429.217877)
			(xy 362.791432 -429.357063) (xy 362.88199 -429.500651) (xy 362.965718 -429.648327) (xy 363.042433 -429.799764)
			(xy 363.111965 -429.954631) (xy 363.174162 -430.112586) (xy 363.228886 -430.273284) (xy 363.276018 -430.436369)
			(xy 363.315454 -430.601485) (xy 363.347108 -430.768268) (xy 363.364334 -430.889918) (xy 381.21844 -430.889918)
			(xy 381.218952 -430.857362) (xy 381.226896 -430.792738) (xy 381.242678 -430.729568) (xy 381.266063 -430.668801)
			(xy 381.296699 -430.611348) (xy 381.334127 -430.55807) (xy 381.377787 -430.509766) (xy 381.402082 -430.48809)
			(xy 381.482854 -430.323244) (xy 381.487579 -430.312737) (xy 381.491058 -430.289973) (xy 381.487563 -430.267211)
			(xy 381.482854 -430.256696) (xy 381.401828 -430.091596) (xy 381.377589 -430.069873) (xy 381.33399 -430.021546)
			(xy 381.296612 -429.968261) (xy 381.266015 -429.910813) (xy 381.242656 -429.850061) (xy 381.226884 -429.786913)
			(xy 381.218934 -429.722312) (xy 381.21844 -429.689768) (xy 381.219133 -429.650641) (xy 381.230612 -429.573235)
			(xy 381.2413 -429.53559) (xy 381.2413 -429.018954) (xy 381.241772 -429.006841) (xy 381.249267 -428.983803)
			(xy 381.263511 -428.964205) (xy 381.28311 -428.949964) (xy 381.306149 -428.942471) (xy 381.318262 -428.941992)
			(xy 382.258062 -428.941992) (xy 382.27017 -428.942543) (xy 382.293204 -428.950015) (xy 382.312803 -428.964238)
			(xy 382.327047 -428.98382) (xy 382.334543 -429.006847) (xy 382.335024 -429.018954) (xy 382.335024 -431.560478)
			(xy 382.334621 -431.572603) (xy 382.32713 -431.595668) (xy 382.312875 -431.615287) (xy 382.293254 -431.629537)
			(xy 382.270187 -431.637023) (xy 382.258062 -431.63744) (xy 381.318262 -431.63744) (xy 381.306143 -431.63702)
			(xy 381.283095 -431.62952) (xy 381.263492 -431.615265) (xy 381.249253 -431.595651) (xy 381.24177 -431.572597)
			(xy 381.2413 -431.560478) (xy 381.2413 -431.044096) (xy 381.230616 -431.00645) (xy 381.219137 -430.929044)
			(xy 381.21844 -430.889918) (xy 363.364334 -430.889918) (xy 363.370909 -430.936351) (xy 363.386805 -431.105365)
			(xy 363.394762 -431.274938) (xy 363.39526 -431.359818) (xy 363.39483 -431.445421) (xy 363.38674 -431.616436)
			(xy 363.370574 -431.786877) (xy 363.355859 -431.889916) (xy 383.218436 -431.889916) (xy 383.218948 -431.85736)
			(xy 383.226892 -431.792736) (xy 383.242674 -431.729566) (xy 383.266059 -431.6688) (xy 383.296695 -431.611346)
			(xy 383.334123 -431.558068) (xy 383.377783 -431.509764) (xy 383.402078 -431.488088) (xy 383.48285 -431.323242)
			(xy 383.487577 -431.312736) (xy 383.491055 -431.289971) (xy 383.48756 -431.267209) (xy 383.48285 -431.256694)
			(xy 383.401824 -431.091594) (xy 383.377584 -431.069873) (xy 383.333984 -431.021546) (xy 383.296607 -430.96826)
			(xy 383.26601 -430.910811) (xy 383.242651 -430.850059) (xy 383.226879 -430.786911) (xy 383.21893 -430.72231)
			(xy 383.218436 -430.689766) (xy 383.219129 -430.650639) (xy 383.230608 -430.573233) (xy 383.241296 -430.535588)
			(xy 383.241296 -430.018952) (xy 383.241676 -430.006841) (xy 383.249188 -429.983813) (xy 383.263459 -429.964241)
			(xy 383.283088 -429.950048) (xy 383.306145 -429.942628) (xy 383.318258 -429.942244) (xy 384.258058 -429.942244)
			(xy 384.270146 -429.942743) (xy 384.293146 -429.950189) (xy 384.312727 -429.964367) (xy 384.326979 -429.983894)
			(xy 384.334511 -430.006866) (xy 384.33502 -430.018952) (xy 384.33502 -430.889918) (xy 385.218432 -430.889918)
			(xy 385.218947 -430.857362) (xy 385.22689 -430.792738) (xy 385.242672 -430.729569) (xy 385.266057 -430.668802)
			(xy 385.296692 -430.611349) (xy 385.33412 -430.558071) (xy 385.377779 -430.509766) (xy 385.402074 -430.48809)
			(xy 385.482846 -430.323244) (xy 385.487572 -430.312737) (xy 385.49105 -430.289973) (xy 385.487556 -430.267211)
			(xy 385.482846 -430.256696) (xy 385.40182 -430.091596) (xy 385.37758 -430.069875) (xy 385.33398 -430.021547)
			(xy 385.296603 -429.968261) (xy 385.266007 -429.910813) (xy 385.242648 -429.850061) (xy 385.226876 -429.786913)
			(xy 385.218926 -429.722312) (xy 385.218432 -429.689768) (xy 385.219125 -429.650642) (xy 385.230604 -429.573235)
			(xy 385.241292 -429.53559) (xy 385.241292 -429.018954) (xy 385.241772 -429.006842) (xy 385.249266 -428.983805)
			(xy 385.263508 -428.964208) (xy 385.283105 -428.949966) (xy 385.306142 -428.942472) (xy 385.318254 -428.941992)
			(xy 386.258054 -428.941992) (xy 386.270162 -428.94255) (xy 386.293196 -428.950019) (xy 386.312794 -428.96424)
			(xy 386.327039 -428.983822) (xy 386.334535 -429.006847) (xy 386.335016 -429.018954) (xy 386.335016 -431.560478)
			(xy 386.334621 -431.572604) (xy 386.327129 -431.59567) (xy 386.312872 -431.61529) (xy 386.293249 -431.62954)
			(xy 386.27018 -431.637024) (xy 386.258054 -431.63744) (xy 385.318254 -431.63744) (xy 385.306135 -431.637027)
			(xy 385.283086 -431.629525) (xy 385.263484 -431.615268) (xy 385.249244 -431.595653) (xy 385.241762 -431.572598)
			(xy 385.241292 -431.560478) (xy 385.241292 -431.044096) (xy 385.230608 -431.00645) (xy 385.219129 -430.929044)
			(xy 385.218432 -430.889918) (xy 384.33502 -430.889918) (xy 384.33502 -431.889916) (xy 387.218428 -431.889916)
			(xy 387.218942 -431.85736) (xy 387.226886 -431.792736) (xy 387.242668 -431.729567) (xy 387.266052 -431.6688)
			(xy 387.296688 -431.611347) (xy 387.334116 -431.558068) (xy 387.377775 -431.509764) (xy 387.40207 -431.488088)
			(xy 387.482842 -431.323242) (xy 387.487569 -431.312736) (xy 387.491048 -431.289971) (xy 387.487552 -431.267209)
			(xy 387.482842 -431.256694) (xy 387.401816 -431.091594) (xy 387.377574 -431.069875) (xy 387.333975 -431.021547)
			(xy 387.296598 -430.968261) (xy 387.266002 -430.910812) (xy 387.242643 -430.85006) (xy 387.226871 -430.786911)
			(xy 387.218922 -430.72231) (xy 387.218428 -430.689766) (xy 387.219121 -430.650639) (xy 387.2306 -430.573233)
			(xy 387.241288 -430.535588) (xy 387.241288 -430.018952) (xy 387.241675 -430.006842) (xy 387.249187 -429.983815)
			(xy 387.263456 -429.964244) (xy 387.283083 -429.95005) (xy 387.306138 -429.942629) (xy 387.31825 -429.942244)
			(xy 388.25805 -429.942244) (xy 388.270137 -429.94275) (xy 388.293137 -429.950193) (xy 388.312718 -429.96437)
			(xy 388.32697 -429.983896) (xy 388.334503 -430.006866) (xy 388.335012 -430.018952) (xy 388.335012 -430.889918)
			(xy 389.218424 -430.889918) (xy 389.218941 -430.857363) (xy 389.226884 -430.792738) (xy 389.242666 -430.729569)
			(xy 389.26605 -430.668802) (xy 389.296685 -430.611349) (xy 389.334113 -430.558071) (xy 389.377771 -430.509766)
			(xy 389.402066 -430.48809) (xy 389.482838 -430.323244) (xy 389.487564 -430.312737) (xy 389.491043 -430.289973)
			(xy 389.487548 -430.267211) (xy 389.482838 -430.256696) (xy 389.401812 -430.091596) (xy 389.37757 -430.069877)
			(xy 389.333971 -430.021549) (xy 389.296594 -429.968262) (xy 389.265998 -429.910814) (xy 389.242639 -429.850061)
			(xy 389.226868 -429.786913) (xy 389.218918 -429.722312) (xy 389.218424 -429.689768) (xy 389.219118 -429.650642)
			(xy 389.230597 -429.573235) (xy 389.241284 -429.53559) (xy 389.241284 -429.018954) (xy 389.241673 -429.006832)
			(xy 389.249179 -428.98378) (xy 389.26344 -428.964175) (xy 389.283062 -428.949937) (xy 389.306124 -428.942459)
			(xy 389.318246 -428.941992) (xy 390.258046 -428.941992) (xy 390.270158 -428.942472) (xy 390.293195 -428.949966)
			(xy 390.312792 -428.964208) (xy 390.327034 -428.983805) (xy 390.334528 -429.006842) (xy 390.335008 -429.018954)
			(xy 390.335008 -431.560478) (xy 390.33447 -431.572587) (xy 390.326995 -431.595622) (xy 390.312768 -431.61522)
			(xy 390.293183 -431.629464) (xy 390.270154 -431.636959) (xy 390.258046 -431.63744) (xy 389.318246 -431.63744)
			(xy 389.306123 -431.637001) (xy 389.283062 -431.629518) (xy 389.263445 -431.615273) (xy 389.249193 -431.595659)
			(xy 389.241703 -431.5726) (xy 389.241284 -431.560478) (xy 389.241284 -431.044096) (xy 389.2306 -431.00645)
			(xy 389.219121 -430.929044) (xy 389.218424 -430.889918) (xy 388.335012 -430.889918) (xy 388.335012 -431.889916)
			(xy 391.21842 -431.889916) (xy 391.218937 -431.857361) (xy 391.226881 -431.792736) (xy 391.242663 -431.729567)
			(xy 391.266046 -431.668801) (xy 391.296682 -431.611347) (xy 391.334109 -431.558069) (xy 391.377767 -431.509764)
			(xy 391.402062 -431.488088) (xy 391.482834 -431.323242) (xy 391.487562 -431.312736) (xy 391.49104 -431.289971)
			(xy 391.487545 -431.267209) (xy 391.482834 -431.256694) (xy 391.401808 -431.091594) (xy 391.377564 -431.069877)
			(xy 391.333966 -431.021548) (xy 391.296589 -430.968261) (xy 391.265993 -430.910812) (xy 391.242635 -430.85006)
			(xy 391.226863 -430.786911) (xy 391.218914 -430.72231) (xy 391.21842 -430.689766) (xy 391.219113 -430.65064)
			(xy 391.230593 -430.573233) (xy 391.24128 -430.535588) (xy 391.24128 -430.018952) (xy 391.241675 -430.006843)
			(xy 391.249186 -429.983817) (xy 391.263453 -429.964247) (xy 391.283077 -429.950053) (xy 391.306131 -429.94263)
			(xy 391.318242 -429.942244) (xy 392.258042 -429.942244) (xy 392.270134 -429.942672) (xy 392.293137 -429.95014)
			(xy 392.312716 -429.964337) (xy 392.326965 -429.983879) (xy 392.334496 -430.006861) (xy 392.335004 -430.018952)
			(xy 392.335004 -430.889918) (xy 393.218416 -430.889918) (xy 393.218936 -430.857363) (xy 393.226879 -430.792739)
			(xy 393.242661 -430.72957) (xy 393.266044 -430.668803) (xy 393.296679 -430.61135) (xy 393.334106 -430.558071)
			(xy 393.377763 -430.509766) (xy 393.402058 -430.48809) (xy 393.48283 -430.323244) (xy 393.487557 -430.312738)
			(xy 393.491036 -430.289973) (xy 393.48754 -430.267211) (xy 393.48283 -430.256696) (xy 393.401804 -430.091596)
			(xy 393.37756 -430.069879) (xy 393.333962 -430.02155) (xy 393.296585 -429.968263) (xy 393.265989 -429.910814)
			(xy 393.242631 -429.850062) (xy 393.226859 -429.786913) (xy 393.21891 -429.722312) (xy 393.218416 -429.689768)
			(xy 393.219106 -429.650641) (xy 393.230587 -429.573235) (xy 393.241276 -429.53559) (xy 393.241276 -429.018954)
			(xy 393.241673 -429.006833) (xy 393.249178 -428.983782) (xy 393.263438 -428.964178) (xy 393.283057 -428.949939)
			(xy 393.306117 -428.94246) (xy 393.318238 -428.941992) (xy 394.258038 -428.941992) (xy 394.27015 -428.942479)
			(xy 394.293187 -428.949971) (xy 394.312784 -428.964211) (xy 394.327026 -428.983806) (xy 394.33452 -429.006842)
			(xy 394.335 -429.018954) (xy 394.335 -431.560478) (xy 394.33447 -431.572588) (xy 394.326994 -431.595624)
			(xy 394.312765 -431.615223) (xy 394.293177 -431.629466) (xy 394.270147 -431.636961) (xy 394.258038 -431.63744)
			(xy 393.318238 -431.63744) (xy 393.306115 -431.637007) (xy 393.283054 -431.629523) (xy 393.263436 -431.615275)
			(xy 393.249184 -431.595661) (xy 393.241695 -431.572601) (xy 393.241276 -431.560478) (xy 393.241276 -431.044096)
			(xy 393.230592 -431.00645) (xy 393.219113 -430.929044) (xy 393.218416 -430.889918) (xy 392.335004 -430.889918)
			(xy 392.335004 -431.889916) (xy 395.218412 -431.889916) (xy 395.218932 -431.857361) (xy 395.226875 -431.792737)
			(xy 395.242657 -431.729568) (xy 395.26604 -431.668801) (xy 395.296675 -431.611348) (xy 395.334102 -431.558069)
			(xy 395.377759 -431.509764) (xy 395.402054 -431.488088) (xy 395.482826 -431.323242) (xy 395.487554 -431.312736)
			(xy 395.491033 -431.289971) (xy 395.487537 -431.267209) (xy 395.482826 -431.256694) (xy 395.4018 -431.091594)
			(xy 395.377555 -431.069879) (xy 395.333956 -431.021549) (xy 395.29658 -430.968262) (xy 395.265985 -430.910813)
			(xy 395.242626 -430.85006) (xy 395.226855 -430.786911) (xy 395.218906 -430.72231) (xy 395.218412 -430.689766)
			(xy 395.219102 -430.650639) (xy 395.230583 -430.573233) (xy 395.241272 -430.535588) (xy 395.241272 -430.018952)
			(xy 395.241675 -430.006843) (xy 395.249184 -429.983819) (xy 395.26345 -429.96425) (xy 395.283072 -429.950056)
			(xy 395.306124 -429.942631) (xy 395.318234 -429.942244) (xy 396.258034 -429.942244) (xy 396.270126 -429.942678)
			(xy 396.293128 -429.950145) (xy 396.312708 -429.96434) (xy 396.326957 -429.98388) (xy 396.334488 -430.006862)
			(xy 396.334996 -430.018952) (xy 396.334996 -430.889918) (xy 398.218406 -430.889918) (xy 398.218929 -430.857363)
			(xy 398.226872 -430.792739) (xy 398.242654 -430.72957) (xy 398.266037 -430.668804) (xy 398.296671 -430.61135)
			(xy 398.334097 -430.558072) (xy 398.377754 -430.509766) (xy 398.402048 -430.48809) (xy 398.48282 -430.323244)
			(xy 398.487547 -430.312738) (xy 398.491027 -430.289973) (xy 398.487531 -430.267211) (xy 398.48282 -430.256696)
			(xy 398.401794 -430.091596) (xy 398.377548 -430.069881) (xy 398.33395 -430.021552) (xy 398.296574 -429.968264)
			(xy 398.265979 -429.910815) (xy 398.242621 -429.850062) (xy 398.226849 -429.786913) (xy 398.2189 -429.722312)
			(xy 398.218406 -429.689768) (xy 398.219134 -429.650443) (xy 398.230738 -429.572653) (xy 398.24152 -429.534828)
			(xy 398.24152 -429.018954) (xy 398.241968 -429.006864) (xy 398.249435 -428.983865) (xy 398.263627 -428.964288)
			(xy 398.283163 -428.950038) (xy 398.306139 -428.942504) (xy 398.318228 -428.941992) (xy 399.258028 -428.941992)
			(xy 399.270138 -428.942392) (xy 399.293164 -428.949899) (xy 399.312736 -428.964165) (xy 399.32693 -428.983789)
			(xy 399.334352 -429.006843) (xy 399.334736 -429.018954) (xy 399.334736 -431.560478) (xy 399.334273 -431.572569)
			(xy 399.32682 -431.595573) (xy 399.312633 -431.615155) (xy 399.293097 -431.629405) (xy 399.270117 -431.636934)
			(xy 399.258028 -431.63744) (xy 398.318228 -431.63744) (xy 398.306125 -431.63696) (xy 398.283105 -431.629473)
			(xy 398.263535 -431.615227) (xy 398.249338 -431.595621) (xy 398.241909 -431.572582) (xy 398.24152 -431.560478)
			(xy 398.24152 -431.044858) (xy 398.230725 -431.007035) (xy 398.219116 -430.929244) (xy 398.218406 -430.889918)
			(xy 396.334996 -430.889918) (xy 396.334996 -431.889916) (xy 400.218402 -431.889916) (xy 400.218925 -431.857361)
			(xy 400.226868 -431.792737) (xy 400.24265 -431.729568) (xy 400.266033 -431.668802) (xy 400.296667 -431.611349)
			(xy 400.334093 -431.55807) (xy 400.37775 -431.509764) (xy 400.402044 -431.488088) (xy 400.482816 -431.323242)
			(xy 400.487545 -431.312736) (xy 400.491024 -431.289971) (xy 400.487528 -431.267209) (xy 400.482816 -431.256694)
			(xy 400.40179 -431.091594) (xy 400.377543 -431.069881) (xy 400.333945 -431.021551) (xy 400.296569 -430.968263)
			(xy 400.265974 -430.910814) (xy 400.242616 -430.850061) (xy 400.226845 -430.786912) (xy 400.218896 -430.72231)
			(xy 400.218402 -430.689766) (xy 400.219129 -430.650441) (xy 400.230734 -430.572651) (xy 400.241516 -430.534826)
			(xy 400.241516 -430.018952) (xy 400.241924 -430.006873) (xy 400.249402 -429.9839) (xy 400.263613 -429.964361)
			(xy 400.283164 -429.950169) (xy 400.306144 -429.942712) (xy 400.318224 -429.942244) (xy 401.258024 -429.942244)
			(xy 401.270095 -429.942743) (xy 401.293055 -429.950206) (xy 401.312587 -429.964396) (xy 401.326783 -429.983924)
			(xy 401.334253 -430.006881) (xy 401.334732 -430.018952) (xy 401.334732 -430.889918) (xy 402.218398 -430.889918)
			(xy 402.218924 -430.857363) (xy 402.226867 -430.792739) (xy 402.242648 -430.729571) (xy 402.266031 -430.668804)
			(xy 402.296664 -430.611351) (xy 402.33409 -430.558072) (xy 402.377746 -430.509767) (xy 402.40204 -430.48809)
			(xy 402.482812 -430.323244) (xy 402.48754 -430.312738) (xy 402.49102 -430.289973) (xy 402.487523 -430.267211)
			(xy 402.482812 -430.256696) (xy 402.401786 -430.091596) (xy 402.377539 -430.069883) (xy 402.333941 -430.021553)
			(xy 402.296566 -429.968265) (xy 402.26597 -429.910816) (xy 402.242613 -429.850062) (xy 402.226841 -429.786914)
			(xy 402.218892 -429.722312) (xy 402.218398 -429.689768) (xy 402.219126 -429.650443) (xy 402.23073 -429.572653)
			(xy 402.241512 -429.534828) (xy 402.241512 -429.018954) (xy 402.241968 -429.006865) (xy 402.249434 -428.983867)
			(xy 402.263624 -428.964291) (xy 402.283158 -428.950041) (xy 402.306132 -428.942505) (xy 402.31822 -428.941992)
			(xy 403.25802 -428.941992) (xy 403.270129 -428.942399) (xy 403.293156 -428.949903) (xy 403.312728 -428.964167)
			(xy 403.326922 -428.98379) (xy 403.334344 -429.006843) (xy 403.334728 -429.018954) (xy 403.334728 -431.560478)
			(xy 403.334273 -431.57257) (xy 403.326819 -431.595575) (xy 403.31263 -431.615158) (xy 403.293092 -431.629408)
			(xy 403.27011 -431.636935) (xy 403.25802 -431.63744) (xy 402.31822 -431.63744) (xy 402.306116 -431.636967)
			(xy 402.283096 -431.629478) (xy 402.263527 -431.61523) (xy 402.24933 -431.595622) (xy 402.241901 -431.572583)
			(xy 402.241512 -431.560478) (xy 402.241512 -431.044858) (xy 402.230717 -431.007035) (xy 402.219108 -430.929244)
			(xy 402.218398 -430.889918) (xy 401.334732 -430.889918) (xy 401.334732 -431.889916) (xy 404.218394 -431.889916)
			(xy 404.218886 -431.85736) (xy 404.226831 -431.792733) (xy 404.242615 -431.729563) (xy 404.266003 -431.668795)
			(xy 404.296642 -431.611342) (xy 404.334075 -431.558065) (xy 404.377738 -431.509763) (xy 404.402036 -431.488088)
			(xy 404.482808 -431.323242) (xy 404.487537 -431.312736) (xy 404.491017 -431.289971) (xy 404.48752 -431.267208)
			(xy 404.482808 -431.256694) (xy 404.401782 -431.091594) (xy 404.377533 -431.069883) (xy 404.333936 -431.021552)
			(xy 404.29656 -430.968264) (xy 404.265965 -430.910814) (xy 404.242608 -430.850061) (xy 404.226837 -430.786912)
			(xy 404.218888 -430.72231) (xy 404.218394 -430.689766) (xy 404.219122 -430.650441) (xy 404.230726 -430.572651)
			(xy 404.241508 -430.534826) (xy 404.241508 -430.018952) (xy 404.241923 -430.006873) (xy 404.249401 -429.983902)
			(xy 404.26361 -429.964364) (xy 404.283159 -429.950172) (xy 404.306137 -429.942713) (xy 404.318216 -429.942244)
			(xy 405.258016 -429.942244) (xy 405.270087 -429.94275) (xy 405.293046 -429.950211) (xy 405.312579 -429.964399)
			(xy 405.326774 -429.983925) (xy 405.334245 -430.006882) (xy 405.334724 -430.018952) (xy 405.334724 -430.889918)
			(xy 406.21839 -430.889918) (xy 406.218885 -430.857362) (xy 406.226829 -430.792736) (xy 406.242613 -430.729565)
			(xy 406.266 -430.668798) (xy 406.296639 -430.611345) (xy 406.334071 -430.558067) (xy 406.377735 -430.509765)
			(xy 406.402032 -430.48809) (xy 406.482804 -430.323244) (xy 406.487532 -430.312738) (xy 406.491013 -430.289973)
			(xy 406.487516 -430.26721) (xy 406.482804 -430.256696) (xy 406.401778 -430.091596) (xy 406.377529 -430.069884)
			(xy 406.333932 -430.021554) (xy 406.296557 -429.968266) (xy 406.265962 -429.910816) (xy 406.242604 -429.850063)
			(xy 406.226833 -429.786914) (xy 406.218884 -429.722312) (xy 406.21839 -429.689768) (xy 406.219118 -429.650443)
			(xy 406.230723 -429.572653) (xy 406.241504 -429.534828) (xy 406.241504 -429.018954) (xy 406.241967 -429.006866)
			(xy 406.249432 -428.98387) (xy 406.263621 -428.964293) (xy 406.283153 -428.950043) (xy 406.306125 -428.942506)
			(xy 406.318212 -428.941992) (xy 407.258012 -428.941992) (xy 407.270121 -428.942406) (xy 407.293147 -428.949908)
			(xy 407.312719 -428.96417) (xy 407.326914 -428.983792) (xy 407.334336 -429.006844) (xy 407.33472 -429.018954)
			(xy 407.33472 -431.560478) (xy 407.334273 -431.57257) (xy 407.326818 -431.595577) (xy 407.312627 -431.615161)
			(xy 407.293087 -431.629411) (xy 407.270103 -431.636936) (xy 407.258012 -431.63744) (xy 406.318212 -431.63744)
			(xy 406.306108 -431.636974) (xy 406.283088 -431.629483) (xy 406.263518 -431.615232) (xy 406.249322 -431.595624)
			(xy 406.241893 -431.572583) (xy 406.241504 -431.560478) (xy 406.241504 -431.044858) (xy 406.230709 -431.007035)
			(xy 406.2191 -430.929244) (xy 406.21839 -430.889918) (xy 405.334724 -430.889918) (xy 405.334724 -431.889916)
			(xy 408.218386 -431.889916) (xy 408.218881 -431.85736) (xy 408.226825 -431.792734) (xy 408.24261 -431.729563)
			(xy 408.265997 -431.668796) (xy 408.296636 -431.611343) (xy 408.334068 -431.558065) (xy 408.377731 -431.509763)
			(xy 408.402028 -431.488088) (xy 408.4828 -431.323242) (xy 408.48753 -431.312736) (xy 408.49101 -431.289971)
			(xy 408.487512 -431.267208) (xy 408.4828 -431.256694) (xy 408.401774 -431.091594) (xy 408.377523 -431.069884)
			(xy 408.333926 -431.021554) (xy 408.296551 -430.968265) (xy 408.265957 -430.910815) (xy 408.2426 -430.850061)
			(xy 408.226829 -430.786912) (xy 408.21888 -430.72231) (xy 408.218386 -430.689766) (xy 408.219114 -430.650441)
			(xy 408.230719 -430.572651) (xy 408.2415 -430.534826) (xy 408.2415 -430.018952) (xy 408.241923 -430.006874)
			(xy 408.2494 -429.983904) (xy 408.263607 -429.964367) (xy 408.283154 -429.950174) (xy 408.30613 -429.942714)
			(xy 408.318208 -429.942244) (xy 409.258008 -429.942244) (xy 409.270078 -429.942757) (xy 409.293037 -429.950216)
			(xy 409.31257 -429.964401) (xy 409.326766 -429.983927) (xy 409.334237 -430.006882) (xy 409.334716 -430.018952)
			(xy 409.334716 -430.889918) (xy 410.218382 -430.889918) (xy 410.21888 -430.857362) (xy 410.226824 -430.792736)
			(xy 410.242608 -430.729566) (xy 410.265994 -430.668798) (xy 410.296633 -430.611345) (xy 410.334064 -430.558068)
			(xy 410.377727 -430.509765) (xy 410.402024 -430.48809) (xy 410.482796 -430.323244) (xy 410.487525 -430.312738)
			(xy 410.491005 -430.289973) (xy 410.487508 -430.26721) (xy 410.482796 -430.256696) (xy 410.40177 -430.091596)
			(xy 410.37754 -430.069864) (xy 410.333938 -430.02154) (xy 410.296558 -429.968256) (xy 410.26596 -429.91081)
			(xy 410.242599 -429.850059) (xy 410.226826 -429.786912) (xy 410.218876 -429.722312) (xy 410.218382 -429.689768)
			(xy 410.219111 -429.650443) (xy 410.230715 -429.572653) (xy 410.241496 -429.534828) (xy 410.241496 -429.018954)
			(xy 410.241967 -429.006866) (xy 410.249431 -428.983872) (xy 410.263618 -428.964296) (xy 410.283148 -428.950046)
			(xy 410.306118 -428.942507) (xy 410.318204 -428.941992) (xy 411.258004 -428.941992) (xy 411.270112 -428.942413)
			(xy 411.293138 -428.949912) (xy 411.312711 -428.964173) (xy 411.326906 -428.983793) (xy 411.334328 -429.006844)
			(xy 411.334712 -429.018954) (xy 411.334712 -431.560478) (xy 411.334273 -431.572571) (xy 411.326816 -431.595579)
			(xy 411.312624 -431.615164) (xy 411.293082 -431.629413) (xy 411.270096 -431.636937) (xy 411.258004 -431.63744)
			(xy 410.318204 -431.63744) (xy 410.306099 -431.636981) (xy 410.283079 -431.629488) (xy 410.263509 -431.615236)
			(xy 410.249313 -431.595625) (xy 410.241885 -431.572584) (xy 410.241496 -431.560478) (xy 410.241496 -431.044858)
			(xy 410.230701 -431.007035) (xy 410.219092 -430.929244) (xy 410.218382 -430.889918) (xy 409.334716 -430.889918)
			(xy 409.334716 -431.889916) (xy 412.218378 -431.889916) (xy 412.218876 -431.85736) (xy 412.22682 -431.792734)
			(xy 412.242604 -431.729564) (xy 412.265991 -431.668797) (xy 412.296629 -431.611343) (xy 412.33406 -431.558066)
			(xy 412.377723 -431.509763) (xy 412.40202 -431.488088) (xy 412.482792 -431.323242) (xy 412.487522 -431.312737)
			(xy 412.491003 -431.289971) (xy 412.487505 -431.267208) (xy 412.482792 -431.256694) (xy 412.401766 -431.091594)
			(xy 412.377534 -431.069864) (xy 412.333932 -431.021539) (xy 412.296553 -430.968255) (xy 412.265955 -430.910808)
			(xy 412.242595 -430.850057) (xy 412.226822 -430.78691) (xy 412.218872 -430.72231) (xy 412.218378 -430.689766)
			(xy 412.219106 -430.650441) (xy 412.230711 -430.572651) (xy 412.241492 -430.534826) (xy 412.241492 -430.018952)
			(xy 412.241923 -430.006875) (xy 412.249399 -429.983906) (xy 412.263604 -429.96437) (xy 412.283149 -429.950177)
			(xy 412.306123 -429.942716) (xy 412.3182 -429.942244) (xy 413.258 -429.942244) (xy 413.27007 -429.942764)
			(xy 413.293029 -429.95022) (xy 413.312562 -429.964404) (xy 413.326758 -429.983928) (xy 413.334229 -430.006883)
			(xy 413.334708 -430.018952) (xy 413.334708 -432.560476) (xy 413.334267 -432.572557) (xy 413.326806 -432.595539)
			(xy 413.312607 -432.61509) (xy 413.293061 -432.629295) (xy 413.270081 -432.636763) (xy 413.258 -432.637184)
			(xy 412.3182 -432.637184) (xy 412.306115 -432.636787) (xy 412.283128 -432.629317) (xy 412.263576 -432.615107)
			(xy 412.249372 -432.59555) (xy 412.241909 -432.572561) (xy 412.241492 -432.560476) (xy 412.241492 -432.044856)
			(xy 412.230696 -432.007034) (xy 412.219087 -431.929242) (xy 412.218378 -431.889916) (xy 409.334716 -431.889916)
			(xy 409.334716 -432.560476) (xy 409.334267 -432.572557) (xy 409.326807 -432.595537) (xy 409.31261 -432.615087)
			(xy 409.293066 -432.629292) (xy 409.270088 -432.636762) (xy 409.258008 -432.637184) (xy 408.318208 -432.637184)
			(xy 408.306123 -432.63678) (xy 408.283137 -432.629312) (xy 408.263584 -432.615105) (xy 408.249381 -432.595549)
			(xy 408.241917 -432.572561) (xy 408.2415 -432.560476) (xy 408.2415 -432.044856) (xy 408.230704 -432.007034)
			(xy 408.219095 -431.929242) (xy 408.218386 -431.889916) (xy 405.334724 -431.889916) (xy 405.334724 -432.560476)
			(xy 405.334267 -432.572556) (xy 405.326808 -432.595535) (xy 405.312613 -432.615084) (xy 405.293071 -432.62929)
			(xy 405.270096 -432.636761) (xy 405.258016 -432.637184) (xy 404.318216 -432.637184) (xy 404.306132 -432.636773)
			(xy 404.283146 -432.629307) (xy 404.263593 -432.615101) (xy 404.249389 -432.595547) (xy 404.241926 -432.57256)
			(xy 404.241508 -432.560476) (xy 404.241508 -432.044856) (xy 404.230713 -432.007034) (xy 404.219103 -431.929242)
			(xy 404.218394 -431.889916) (xy 401.334732 -431.889916) (xy 401.334732 -432.560476) (xy 401.334216 -432.572547)
			(xy 401.326763 -432.595509) (xy 401.312579 -432.615045) (xy 401.293052 -432.629241) (xy 401.270095 -432.636708)
			(xy 401.258024 -432.637184) (xy 400.318224 -432.637184) (xy 400.30614 -432.636766) (xy 400.283154 -432.629303)
			(xy 400.263601 -432.615099) (xy 400.249397 -432.595546) (xy 400.241934 -432.57256) (xy 400.241516 -432.560476)
			(xy 400.241516 -432.044856) (xy 400.230721 -432.007033) (xy 400.219111 -431.929242) (xy 400.218402 -431.889916)
			(xy 396.334996 -431.889916) (xy 396.334996 -432.560476) (xy 396.334563 -432.572584) (xy 396.32707 -432.595611)
			(xy 396.312813 -432.615185) (xy 396.293194 -432.62938) (xy 396.270143 -432.636801) (xy 396.258034 -432.637184)
			(xy 395.318234 -432.637184) (xy 395.306149 -432.636664) (xy 395.283153 -432.62922) (xy 395.263575 -432.615046)
			(xy 395.249322 -432.595525) (xy 395.241785 -432.572559) (xy 395.241272 -432.560476) (xy 395.241272 -432.044094)
			(xy 395.230587 -432.006448) (xy 395.219109 -431.929042) (xy 395.218412 -431.889916) (xy 392.335004 -431.889916)
			(xy 392.335004 -432.560476) (xy 392.334563 -432.572583) (xy 392.327071 -432.595609) (xy 392.312815 -432.615182)
			(xy 392.293199 -432.629378) (xy 392.27015 -432.6368) (xy 392.258042 -432.637184) (xy 391.318242 -432.637184)
			(xy 391.306157 -432.636657) (xy 391.283162 -432.629215) (xy 391.263583 -432.615043) (xy 391.24933 -432.595523)
			(xy 391.241793 -432.572559) (xy 391.24128 -432.560476) (xy 391.24128 -432.044094) (xy 391.230595 -432.006448)
			(xy 391.219117 -431.929042) (xy 391.21842 -431.889916) (xy 388.335012 -431.889916) (xy 388.335012 -432.560476)
			(xy 388.334563 -432.572582) (xy 388.327072 -432.595607) (xy 388.312818 -432.615179) (xy 388.293204 -432.629375)
			(xy 388.270158 -432.636799) (xy 388.25805 -432.637184) (xy 387.31825 -432.637184) (xy 387.306165 -432.636651)
			(xy 387.28317 -432.62921) (xy 387.263592 -432.61504) (xy 387.249339 -432.595522) (xy 387.241801 -432.572559)
			(xy 387.241288 -432.560476) (xy 387.241288 -432.044094) (xy 387.230604 -432.006448) (xy 387.219125 -431.929042)
			(xy 387.218428 -431.889916) (xy 384.33502 -431.889916) (xy 384.33502 -432.560476) (xy 384.334563 -432.572582)
			(xy 384.327073 -432.595605) (xy 384.312821 -432.615176) (xy 384.293209 -432.629373) (xy 384.270165 -432.636797)
			(xy 384.258058 -432.637184) (xy 383.318258 -432.637184) (xy 383.306169 -432.636729) (xy 383.283171 -432.629264)
			(xy 383.263593 -432.615073) (xy 383.249343 -432.595539) (xy 383.241808 -432.572564) (xy 383.241296 -432.560476)
			(xy 383.241296 -432.044094) (xy 383.230612 -432.006448) (xy 383.219133 -431.929042) (xy 383.218436 -431.889916)
			(xy 363.355859 -431.889916) (xy 363.346369 -431.956363) (xy 363.314178 -432.124516) (xy 363.274074 -432.290959)
			(xy 363.226145 -432.455319) (xy 363.170501 -432.61723) (xy 363.107264 -432.776329) (xy 363.036576 -432.932261)
			(xy 362.958595 -433.084677) (xy 362.873496 -433.233236) (xy 362.781469 -433.377605) (xy 362.68272 -433.517463)
			(xy 362.577469 -433.652495) (xy 362.465953 -433.782401) (xy 362.348419 -433.90689) (xy 362.225132 -434.025683)
			(xy 362.096367 -434.138515) (xy 361.962411 -434.245133) (xy 361.823565 -434.345299) (xy 361.680139 -434.438789)
			(xy 361.593049 -434.48986) (xy 381.237998 -434.48986) (xy 381.238096 -434.475286) (xy 381.239745 -434.446185)
			(xy 381.2413 -434.431694) (xy 381.2413 -433.34813) (xy 381.239752 -433.333638) (xy 381.238102 -433.304538)
			(xy 381.237998 -433.289964) (xy 381.238096 -433.27539) (xy 381.239745 -433.246289) (xy 381.2413 -433.231798)
			(xy 381.2413 -432.618896) (xy 381.241713 -432.606787) (xy 381.249213 -432.583759) (xy 381.263476 -432.564186)
			(xy 381.283098 -432.549992) (xy 381.306152 -432.542571) (xy 381.318262 -432.542188) (xy 382.258062 -432.542188)
			(xy 382.270154 -432.542641) (xy 382.293162 -432.550093) (xy 382.312747 -432.564281) (xy 382.326997 -432.583821)
			(xy 382.334521 -432.606805) (xy 382.335024 -432.618896) (xy 382.335024 -435.16042) (xy 382.334601 -435.172528)
			(xy 382.327099 -435.195551) (xy 382.312838 -435.215122) (xy 382.29322 -435.229317) (xy 382.270171 -435.236741)
			(xy 382.258062 -435.237128) (xy 381.318262 -435.237128) (xy 381.306167 -435.236724) (xy 381.28316 -435.229253)
			(xy 381.263578 -435.215052) (xy 381.24933 -435.195503) (xy 381.241804 -435.172514) (xy 381.2413 -435.16042)
			(xy 381.2413 -434.548026) (xy 381.239752 -434.533534) (xy 381.238102 -434.504434) (xy 381.237998 -434.48986)
			(xy 361.593049 -434.48986) (xy 361.532453 -434.525394) (xy 361.380838 -434.60492) (xy 361.225633 -434.67719)
			(xy 361.146598 -434.710078) (xy 361.132966 -434.716266) (xy 361.109724 -434.735103) (xy 361.092944 -434.759873)
			(xy 361.084069 -434.788444) (xy 361.083862 -434.818361) (xy 361.092341 -434.847052) (xy 361.108777 -434.872051)
			(xy 361.119928 -434.882036) (xy 361.169374 -434.924045) (xy 361.263563 -435.013299) (xy 361.352051 -435.108208)
			(xy 361.434498 -435.208409) (xy 361.510589 -435.313518) (xy 361.580032 -435.423133) (xy 361.616728 -435.489858)
			(xy 383.237994 -435.489858) (xy 383.238091 -435.475284) (xy 383.239741 -435.446183) (xy 383.241296 -435.431692)
			(xy 383.241296 -434.348128) (xy 383.239748 -434.333636) (xy 383.238098 -434.304536) (xy 383.237994 -434.289962)
			(xy 383.238092 -434.275388) (xy 383.239741 -434.246287) (xy 383.241296 -434.231796) (xy 383.241296 -433.618894)
			(xy 383.241806 -433.606783) (xy 383.24929 -433.583747) (xy 383.263524 -433.564149) (xy 383.283115 -433.549906)
			(xy 383.306148 -433.542412) (xy 383.318258 -433.541932) (xy 384.258058 -433.541932) (xy 384.270178 -433.542396)
			(xy 384.293234 -433.549876) (xy 384.31285 -433.564116) (xy 384.327103 -433.583722) (xy 384.334597 -433.606774)
			(xy 384.33502 -433.618894) (xy 384.33502 -434.48986) (xy 385.23799 -434.48986) (xy 385.238088 -434.475286)
			(xy 385.239737 -434.446185) (xy 385.241292 -434.431694) (xy 385.241292 -433.34813) (xy 385.239744 -433.333638)
			(xy 385.238094 -433.304538) (xy 385.23799 -433.289964) (xy 385.238088 -433.27539) (xy 385.239737 -433.246289)
			(xy 385.241292 -433.231798) (xy 385.241292 -432.618896) (xy 385.241713 -432.606788) (xy 385.249212 -432.583762)
			(xy 385.263473 -432.564189) (xy 385.283093 -432.549994) (xy 385.306144 -432.542572) (xy 385.318254 -432.542188)
			(xy 386.258054 -432.542188) (xy 386.270146 -432.542647) (xy 386.293153 -432.550097) (xy 386.312738 -432.564284)
			(xy 386.326988 -432.583823) (xy 386.334513 -432.606806) (xy 386.335016 -432.618896) (xy 386.335016 -435.16042)
			(xy 386.334601 -435.172528) (xy 386.327098 -435.195554) (xy 386.312836 -435.215125) (xy 386.293215 -435.229319)
			(xy 386.270164 -435.236743) (xy 386.258054 -435.237128) (xy 385.318254 -435.237128) (xy 385.306159 -435.236731)
			(xy 385.283151 -435.229258) (xy 385.263569 -435.215054) (xy 385.249322 -435.195505) (xy 385.241796 -435.172514)
			(xy 385.241292 -435.16042) (xy 385.241292 -434.548026) (xy 385.239744 -434.533534) (xy 385.238094 -434.504434)
			(xy 385.23799 -434.48986) (xy 384.33502 -434.48986) (xy 384.33502 -435.489858) (xy 387.237986 -435.489858)
			(xy 387.238083 -435.475284) (xy 387.239733 -435.446183) (xy 387.241288 -435.431692) (xy 387.241288 -434.348128)
			(xy 387.23974 -434.333636) (xy 387.23809 -434.304536) (xy 387.237986 -434.289962) (xy 387.238084 -434.275388)
			(xy 387.239733 -434.246287) (xy 387.241288 -434.231796) (xy 387.241288 -433.618894) (xy 387.241806 -433.606784)
			(xy 387.249289 -433.583749) (xy 387.263521 -433.564152) (xy 387.28311 -433.549909) (xy 387.30614 -433.542413)
			(xy 387.31825 -433.541932) (xy 388.25805 -433.541932) (xy 388.270167 -433.542369) (xy 388.29321 -433.549869)
			(xy 388.312811 -433.564121) (xy 388.327051 -433.583729) (xy 388.334538 -433.606777) (xy 388.335012 -433.618894)
			(xy 388.335012 -434.48986) (xy 389.237982 -434.48986) (xy 389.23808 -434.475286) (xy 389.239729 -434.446185)
			(xy 389.241284 -434.431694) (xy 389.241284 -433.34813) (xy 389.239736 -433.333638) (xy 389.238086 -433.304538)
			(xy 389.237982 -433.289964) (xy 389.23808 -433.27539) (xy 389.23973 -433.246289) (xy 389.241284 -433.231798)
			(xy 389.241284 -432.618896) (xy 389.241713 -432.606789) (xy 389.249211 -432.583764) (xy 389.26347 -432.564192)
			(xy 389.283088 -432.549997) (xy 389.306137 -432.542573) (xy 389.318246 -432.542188) (xy 390.258046 -432.542188)
			(xy 390.270143 -432.542569) (xy 390.293153 -432.550044) (xy 390.312736 -432.564251) (xy 390.326984 -432.583805)
			(xy 390.334506 -432.6068) (xy 390.335008 -432.618896) (xy 390.335008 -435.16042) (xy 390.334601 -435.172529)
			(xy 390.327097 -435.195556) (xy 390.312833 -435.215128) (xy 390.29321 -435.229322) (xy 390.270157 -435.236744)
			(xy 390.258046 -435.237128) (xy 389.318246 -435.237128) (xy 389.306156 -435.236653) (xy 389.283151 -435.229205)
			(xy 389.263568 -435.215022) (xy 389.249317 -435.195487) (xy 389.241789 -435.172509) (xy 389.241284 -435.16042)
			(xy 389.241284 -434.548026) (xy 389.239736 -434.533534) (xy 389.238086 -434.504434) (xy 389.237982 -434.48986)
			(xy 388.335012 -434.48986) (xy 388.335012 -435.489858) (xy 391.237978 -435.489858) (xy 391.238076 -435.475284)
			(xy 391.239725 -435.446183) (xy 391.24128 -435.431692) (xy 391.24128 -434.348128) (xy 391.239732 -434.333636)
			(xy 391.238082 -434.304536) (xy 391.237978 -434.289962) (xy 391.238076 -434.275388) (xy 391.239725 -434.246287)
			(xy 391.24128 -434.231796) (xy 391.24128 -433.618894) (xy 391.241656 -433.606767) (xy 391.249155 -433.583701)
			(xy 391.263416 -433.564082) (xy 391.283044 -433.549833) (xy 391.306115 -433.542348) (xy 391.318242 -433.541932)
			(xy 392.258042 -433.541932) (xy 392.270158 -433.542376) (xy 392.293202 -433.549874) (xy 392.312802 -433.564123)
			(xy 392.327043 -433.583731) (xy 392.33453 -433.606778) (xy 392.335004 -433.618894) (xy 392.335004 -434.48986)
			(xy 393.237974 -434.48986) (xy 393.238072 -434.475286) (xy 393.239721 -434.446185) (xy 393.241276 -434.431694)
			(xy 393.241276 -433.34813) (xy 393.239728 -433.333638) (xy 393.238078 -433.304538) (xy 393.237974 -433.289964)
			(xy 393.238072 -433.27539) (xy 393.239722 -433.246289) (xy 393.241276 -433.231798) (xy 393.241276 -432.618896)
			(xy 393.241712 -432.606789) (xy 393.24921 -432.583766) (xy 393.263467 -432.564195) (xy 393.283083 -432.55)
			(xy 393.30613 -432.542575) (xy 393.318238 -432.542188) (xy 394.258038 -432.542188) (xy 394.270134 -432.542576)
			(xy 394.293144 -432.550049) (xy 394.312728 -432.564254) (xy 394.326975 -432.583807) (xy 394.334498 -432.606801)
			(xy 394.335 -432.618896) (xy 394.335 -435.16042) (xy 394.334601 -435.17253) (xy 394.327096 -435.195558)
			(xy 394.31283 -435.215131) (xy 394.293205 -435.229325) (xy 394.270149 -435.236745) (xy 394.258038 -435.237128)
			(xy 393.318238 -435.237128) (xy 393.306147 -435.23666) (xy 393.283142 -435.22921) (xy 393.263559 -435.215024)
			(xy 393.249308 -435.195489) (xy 393.241781 -435.172509) (xy 393.241276 -435.16042) (xy 393.241276 -434.548026)
			(xy 393.239728 -434.533534) (xy 393.238078 -434.504434) (xy 393.237974 -434.48986) (xy 392.335004 -434.48986)
			(xy 392.335004 -435.489858) (xy 395.23797 -435.489858) (xy 395.238068 -435.475284) (xy 395.239717 -435.446183)
			(xy 395.241272 -435.431692) (xy 395.241272 -434.348128) (xy 395.239724 -434.333636) (xy 395.238074 -434.304536)
			(xy 395.23797 -434.289962) (xy 395.238068 -434.275388) (xy 395.239717 -434.246287) (xy 395.241272 -434.231796)
			(xy 395.241272 -433.618894) (xy 395.241656 -433.606768) (xy 395.249154 -433.583703) (xy 395.263413 -433.564085)
			(xy 395.283039 -433.549835) (xy 395.306107 -433.542349) (xy 395.318234 -433.541932) (xy 396.258034 -433.541932)
			(xy 396.27015 -433.542383) (xy 396.293193 -433.549878) (xy 396.312794 -433.564126) (xy 396.327034 -433.583732)
			(xy 396.334522 -433.606778) (xy 396.334996 -433.618894) (xy 396.334996 -434.48986) (xy 398.237964 -434.48986)
			(xy 398.238077 -434.474774) (xy 398.239856 -434.444656) (xy 398.24152 -434.429662) (xy 398.24152 -433.350162)
			(xy 398.239855 -433.335168) (xy 398.238074 -433.30505) (xy 398.237964 -433.289964) (xy 398.238077 -433.274878)
			(xy 398.239856 -433.24476) (xy 398.24152 -433.229766) (xy 398.24152 -432.618896) (xy 398.241909 -432.60681)
			(xy 398.249382 -432.583823) (xy 398.263593 -432.56427) (xy 398.283151 -432.550067) (xy 398.306142 -432.542604)
			(xy 398.318228 -432.542188) (xy 399.258028 -432.542188) (xy 399.270104 -432.54264) (xy 399.293071 -432.55011)
			(xy 399.312607 -432.56431) (xy 399.326801 -432.58385) (xy 399.334264 -432.60682) (xy 399.334736 -432.618896)
			(xy 399.334736 -435.16042) (xy 399.334253 -435.172493) (xy 399.326788 -435.195456) (xy 399.312596 -435.21499)
			(xy 399.293063 -435.229185) (xy 399.270101 -435.236652) (xy 399.258028 -435.237128) (xy 398.318228 -435.237128)
			(xy 398.306149 -435.236664) (xy 398.28317 -435.229206) (xy 398.263621 -435.215013) (xy 398.249416 -435.195473)
			(xy 398.241944 -435.172499) (xy 398.24152 -435.16042) (xy 398.24152 -434.550058) (xy 398.239854 -434.535064)
			(xy 398.238074 -434.504946) (xy 398.237964 -434.48986) (xy 396.334996 -434.48986) (xy 396.334996 -435.489858)
			(xy 400.23796 -435.489858) (xy 400.238073 -435.474772) (xy 400.239852 -435.444654) (xy 400.241516 -435.42966)
			(xy 400.241516 -434.35016) (xy 400.239851 -434.335166) (xy 400.23807 -434.305048) (xy 400.23796 -434.289962)
			(xy 400.238073 -434.274876) (xy 400.239852 -434.244758) (xy 400.241516 -434.229764) (xy 400.241516 -433.618894)
			(xy 400.242002 -433.606807) (xy 400.249457 -433.58381) (xy 400.26364 -433.564232) (xy 400.283168 -433.549981)
			(xy 400.306138 -433.542445) (xy 400.318224 -433.541932) (xy 401.258024 -433.541932) (xy 401.270137 -433.542296)
			(xy 401.293171 -433.549806) (xy 401.312746 -433.56408) (xy 401.326939 -433.583715) (xy 401.334353 -433.606779)
			(xy 401.334732 -433.618894) (xy 401.334732 -434.48986) (xy 402.237956 -434.48986) (xy 402.238069 -434.474774)
			(xy 402.239848 -434.444656) (xy 402.241512 -434.429662) (xy 402.241512 -433.350162) (xy 402.239847 -433.335168)
			(xy 402.238066 -433.30505) (xy 402.237956 -433.289964) (xy 402.238069 -433.274878) (xy 402.239848 -433.24476)
			(xy 402.241512 -433.229766) (xy 402.241512 -432.618896) (xy 402.241909 -432.606811) (xy 402.24938 -432.583825)
			(xy 402.26359 -432.564273) (xy 402.283146 -432.550069) (xy 402.306135 -432.542606) (xy 402.31822 -432.542188)
			(xy 403.25802 -432.542188) (xy 403.270095 -432.542647) (xy 403.293062 -432.550115) (xy 403.312599 -432.564313)
			(xy 403.326793 -432.583852) (xy 403.334255 -432.606821) (xy 403.334728 -432.618896) (xy 403.334728 -435.16042)
			(xy 403.334253 -435.172494) (xy 403.326787 -435.195458) (xy 403.312593 -435.214993) (xy 403.293058 -435.229187)
			(xy 403.270094 -435.236653) (xy 403.25802 -435.237128) (xy 402.31822 -435.237128) (xy 402.306148 -435.236619)
			(xy 402.283185 -435.229165) (xy 402.26365 -435.214979) (xy 402.249454 -435.195451) (xy 402.241987 -435.172491)
			(xy 402.241512 -435.16042) (xy 402.241512 -434.550058) (xy 402.239846 -434.535064) (xy 402.238066 -434.504946)
			(xy 402.237956 -434.48986) (xy 401.334732 -434.48986) (xy 401.334732 -435.489858) (xy 404.237952 -435.489858)
			(xy 404.238065 -435.474772) (xy 404.239844 -435.444654) (xy 404.241508 -435.42966) (xy 404.241508 -434.35016)
			(xy 404.239843 -434.335166) (xy 404.238062 -434.305048) (xy 404.237952 -434.289962) (xy 404.238065 -434.274876)
			(xy 404.239844 -434.244758) (xy 404.241508 -434.229764) (xy 404.241508 -433.618894) (xy 404.242002 -433.606807)
			(xy 404.249456 -433.583812) (xy 404.263637 -433.564235) (xy 404.283163 -433.549984) (xy 404.306131 -433.542446)
			(xy 404.318216 -433.541932) (xy 405.258016 -433.541932) (xy 405.270129 -433.542303) (xy 405.293162 -433.549811)
			(xy 405.312738 -433.564083) (xy 405.326931 -433.583716) (xy 405.334345 -433.606779) (xy 405.334724 -433.618894)
			(xy 405.334724 -434.48986) (xy 406.237948 -434.48986) (xy 406.238061 -434.474774) (xy 406.23984 -434.444656)
			(xy 406.241504 -434.429662) (xy 406.241504 -433.350162) (xy 406.239839 -433.335168) (xy 406.238058 -433.30505)
			(xy 406.237948 -433.289964) (xy 406.238061 -433.274878) (xy 406.23984 -433.24476) (xy 406.241504 -433.229766)
			(xy 406.241504 -432.618896) (xy 406.241909 -432.606812) (xy 406.249379 -432.583827) (xy 406.263587 -432.564276)
			(xy 406.283141 -432.550072) (xy 406.306128 -432.542607) (xy 406.318212 -432.542188) (xy 407.258012 -432.542188)
			(xy 407.270087 -432.542654) (xy 407.293054 -432.550119) (xy 407.31259 -432.564316) (xy 407.326784 -432.583854)
			(xy 407.334247 -432.606821) (xy 407.33472 -432.618896) (xy 407.33472 -435.16042) (xy 407.334253 -435.172494)
			(xy 407.326786 -435.19546) (xy 407.31259 -435.214996) (xy 407.293053 -435.22919) (xy 407.270086 -435.236654)
			(xy 407.258012 -435.237128) (xy 406.318212 -435.237128) (xy 406.30614 -435.236626) (xy 406.283177 -435.229169)
			(xy 406.263641 -435.214982) (xy 406.249446 -435.195452) (xy 406.241979 -435.172492) (xy 406.241504 -435.16042)
			(xy 406.241504 -434.550058) (xy 406.239838 -434.535064) (xy 406.238058 -434.504946) (xy 406.237948 -434.48986)
			(xy 405.334724 -434.48986) (xy 405.334724 -435.489858) (xy 408.237944 -435.489858) (xy 408.238057 -435.474772)
			(xy 408.239836 -435.444654) (xy 408.2415 -435.42966) (xy 408.2415 -434.35016) (xy 408.239834 -434.335166)
			(xy 408.238054 -434.305048) (xy 408.237944 -434.289962) (xy 408.238057 -434.274876) (xy 408.239836 -434.244758)
			(xy 408.2415 -434.229764) (xy 408.2415 -433.618894) (xy 408.242002 -433.606808) (xy 408.249455 -433.583814)
			(xy 408.263634 -433.564238) (xy 408.283158 -433.549986) (xy 408.306124 -433.542447) (xy 408.318208 -433.541932)
			(xy 409.258008 -433.541932) (xy 409.270121 -433.54231) (xy 409.293154 -433.549815) (xy 409.312729 -433.564086)
			(xy 409.326923 -433.583717) (xy 409.334337 -433.60678) (xy 409.334716 -433.618894) (xy 409.334716 -434.48986)
			(xy 410.23794 -434.48986) (xy 410.238053 -434.474774) (xy 410.239832 -434.444656) (xy 410.241496 -434.429662)
			(xy 410.241496 -433.350162) (xy 410.239831 -433.335168) (xy 410.23805 -433.30505) (xy 410.23794 -433.289964)
			(xy 410.238053 -433.274878) (xy 410.239832 -433.24476) (xy 410.241496 -433.229766) (xy 410.241496 -432.618896)
			(xy 410.241961 -432.606821) (xy 410.249425 -432.583853) (xy 410.263621 -432.564316) (xy 410.28316 -432.550121)
			(xy 410.306129 -432.54266) (xy 410.318204 -432.542188) (xy 411.258004 -432.542188) (xy 411.270078 -432.542661)
			(xy 411.293045 -432.550124) (xy 411.312582 -432.564318) (xy 411.326776 -432.583855) (xy 411.334239 -432.606822)
			(xy 411.334712 -432.618896) (xy 411.334712 -435.16042) (xy 411.334253 -435.172495) (xy 411.326785 -435.195462)
			(xy 411.312587 -435.214999) (xy 411.293048 -435.229193) (xy 411.270079 -435.236655) (xy 411.258004 -435.237128)
			(xy 410.318204 -435.237128) (xy 410.306132 -435.236633) (xy 410.283168 -435.229174) (xy 410.263633 -435.214984)
			(xy 410.249437 -435.195454) (xy 410.241971 -435.172492) (xy 410.241496 -435.16042) (xy 410.241496 -434.550058)
			(xy 410.23983 -434.535064) (xy 410.23805 -434.504946) (xy 410.23794 -434.48986) (xy 409.334716 -434.48986)
			(xy 409.334716 -435.489858) (xy 412.237936 -435.489858) (xy 412.238051 -435.474773) (xy 412.23983 -435.444654)
			(xy 412.241492 -435.42966) (xy 412.241492 -434.35016) (xy 412.239826 -434.335166) (xy 412.238046 -434.305048)
			(xy 412.237936 -434.289962) (xy 412.238051 -434.274877) (xy 412.23983 -434.244758) (xy 412.241492 -434.229764)
			(xy 412.241492 -433.618894) (xy 412.242002 -433.606809) (xy 412.249454 -433.583816) (xy 412.263631 -433.564241)
			(xy 412.283153 -433.549989) (xy 412.306117 -433.542448) (xy 412.3182 -433.541932) (xy 413.258 -433.541932)
			(xy 413.270112 -433.542317) (xy 413.293145 -433.54982) (xy 413.312721 -433.564088) (xy 413.326914 -433.583719)
			(xy 413.334329 -433.60678) (xy 413.334708 -433.618894) (xy 413.334708 -436.160418) (xy 413.334209 -436.172504)
			(xy 413.326753 -436.195497) (xy 413.312573 -436.215072) (xy 413.29305 -436.229324) (xy 413.270084 -436.236864)
			(xy 413.258 -436.23738) (xy 412.3182 -436.23738) (xy 412.306089 -436.236984) (xy 412.283058 -436.229482)
			(xy 412.263483 -436.215216) (xy 412.24929 -436.195589) (xy 412.241872 -436.17253) (xy 412.241492 -436.160418)
			(xy 412.241492 -435.550056) (xy 412.239826 -435.535062) (xy 412.238046 -435.504944) (xy 412.237936 -435.489858)
			(xy 409.334716 -435.489858) (xy 409.334716 -436.160418) (xy 409.334307 -436.172513) (xy 409.32684 -436.195522)
			(xy 409.31264 -436.215105) (xy 409.293092 -436.229353) (xy 409.270102 -436.236877) (xy 409.258008 -436.23738)
			(xy 408.318208 -436.23738) (xy 408.306098 -436.236977) (xy 408.283067 -436.229477) (xy 408.263492 -436.215213)
			(xy 408.249298 -436.195587) (xy 408.24188 -436.17253) (xy 408.2415 -436.160418) (xy 408.2415 -435.550056)
			(xy 408.239834 -435.535062) (xy 408.238054 -435.504944) (xy 408.237944 -435.489858) (xy 405.334724 -435.489858)
			(xy 405.334724 -436.160418) (xy 405.334307 -436.172512) (xy 405.326841 -436.195519) (xy 405.312643 -436.215102)
			(xy 405.293097 -436.229351) (xy 405.270109 -436.236876) (xy 405.258016 -436.23738) (xy 404.318216 -436.23738)
			(xy 404.306106 -436.23697) (xy 404.283076 -436.229472) (xy 404.263501 -436.21521) (xy 404.249306 -436.195585)
			(xy 404.241889 -436.172529) (xy 404.241508 -436.160418) (xy 404.241508 -435.550056) (xy 404.239842 -435.535062)
			(xy 404.238062 -435.504944) (xy 404.237952 -435.489858) (xy 401.334732 -435.489858) (xy 401.334732 -436.160418)
			(xy 401.334308 -436.172511) (xy 401.326843 -436.195517) (xy 401.312646 -436.215099) (xy 401.293102 -436.229348)
			(xy 401.270116 -436.236875) (xy 401.258024 -436.23738) (xy 400.318224 -436.23738) (xy 400.306114 -436.236963)
			(xy 400.283085 -436.229468) (xy 400.263509 -436.215207) (xy 400.249315 -436.195584) (xy 400.241897 -436.172529)
			(xy 400.241516 -436.160418) (xy 400.241516 -435.550056) (xy 400.23985 -435.535062) (xy 400.23807 -435.504944)
			(xy 400.23796 -435.489858) (xy 396.334996 -435.489858) (xy 396.334996 -436.160418) (xy 396.334504 -436.17253)
			(xy 396.327016 -436.195568) (xy 396.312778 -436.215167) (xy 396.293183 -436.229409) (xy 396.270146 -436.236902)
			(xy 396.258034 -436.23738) (xy 395.318234 -436.23738) (xy 395.306115 -436.236911) (xy 395.28306 -436.229431)
			(xy 395.263446 -436.215191) (xy 395.249193 -436.195587) (xy 395.241697 -436.172537) (xy 395.241272 -436.160418)
			(xy 395.241272 -435.548024) (xy 395.239724 -435.533532) (xy 395.238074 -435.504432) (xy 395.23797 -435.489858)
			(xy 392.335004 -435.489858) (xy 392.335004 -436.160418) (xy 392.334504 -436.172529) (xy 392.327017 -436.195566)
			(xy 392.312781 -436.215164) (xy 392.293188 -436.229406) (xy 392.270153 -436.236901) (xy 392.258042 -436.23738)
			(xy 391.318242 -436.23738) (xy 391.306123 -436.236905) (xy 391.283069 -436.229426) (xy 391.263455 -436.215188)
			(xy 391.249201 -436.195585) (xy 391.241705 -436.172536) (xy 391.24128 -436.160418) (xy 391.24128 -435.548024)
			(xy 391.239732 -435.533532) (xy 391.238082 -435.504432) (xy 391.237978 -435.489858) (xy 388.335012 -435.489858)
			(xy 388.335012 -436.160418) (xy 388.334505 -436.172529) (xy 388.327018 -436.195564) (xy 388.312784 -436.215161)
			(xy 388.293193 -436.229404) (xy 388.27016 -436.2369) (xy 388.25805 -436.23738) (xy 387.31825 -436.23738)
			(xy 387.306135 -436.236931) (xy 387.283093 -436.229432) (xy 387.263493 -436.215184) (xy 387.249253 -436.195578)
			(xy 387.241764 -436.172534) (xy 387.241288 -436.160418) (xy 387.241288 -435.548024) (xy 387.23974 -435.533532)
			(xy 387.23809 -435.504432) (xy 387.237986 -435.489858) (xy 384.33502 -435.489858) (xy 384.33502 -436.160418)
			(xy 384.334654 -436.172546) (xy 384.327152 -436.195612) (xy 384.312888 -436.215231) (xy 384.293258 -436.22948)
			(xy 384.270186 -436.236964) (xy 384.258058 -436.23738) (xy 383.318258 -436.23738) (xy 383.306143 -436.236924)
			(xy 383.283101 -436.229428) (xy 383.263502 -436.215181) (xy 383.249261 -436.195577) (xy 383.241772 -436.172533)
			(xy 383.241296 -436.160418) (xy 383.241296 -435.548024) (xy 383.239748 -435.533532) (xy 383.238098 -435.504432)
			(xy 383.237994 -435.489858) (xy 361.616728 -435.489858) (xy 361.642562 -435.536833) (xy 361.697938 -435.654184)
			(xy 361.74595 -435.774736) (xy 361.786412 -435.898026) (xy 361.81917 -436.023584) (xy 361.844098 -436.150927)
			(xy 361.861101 -436.279569) (xy 361.870114 -436.409016) (xy 361.871103 -436.538773) (xy 361.864062 -436.668342)
			(xy 361.849021 -436.797228) (xy 361.826035 -436.924936) (xy 361.795194 -437.050978) (xy 361.756614 -437.174871)
			(xy 361.710445 -437.29614) (xy 361.656862 -437.41432) (xy 361.596072 -437.52896) (xy 361.528306 -437.63962)
			(xy 361.453825 -437.745876) (xy 361.372914 -437.847321) (xy 361.285882 -437.943567) (xy 361.193064 -438.034245)
			(xy 361.128666 -438.089802) (xy 381.237998 -438.089802) (xy 381.238091 -438.075228) (xy 381.239744 -438.046127)
			(xy 381.2413 -438.031636) (xy 381.2413 -436.948072) (xy 381.239755 -436.93358) (xy 381.238103 -436.90448)
			(xy 381.237998 -436.889906) (xy 381.238091 -436.875332) (xy 381.239744 -436.846231) (xy 381.2413 -436.83174)
			(xy 381.2413 -436.218838) (xy 381.241843 -436.206729) (xy 381.249316 -436.183694) (xy 381.26354 -436.164094)
			(xy 381.283125 -436.14985) (xy 381.306154 -436.142355) (xy 381.318262 -436.141876) (xy 382.258062 -436.141876)
			(xy 382.270187 -436.142293) (xy 382.293251 -436.149779) (xy 382.31287 -436.16403) (xy 382.327121 -436.183649)
			(xy 382.334607 -436.206713) (xy 382.335024 -436.218838) (xy 382.335024 -438.760362) (xy 382.334607 -438.772487)
			(xy 382.327121 -438.795551) (xy 382.31287 -438.81517) (xy 382.293251 -438.829421) (xy 382.270187 -438.836907)
			(xy 382.258062 -438.837324) (xy 381.318262 -438.837324) (xy 381.306142 -438.83692) (xy 381.283091 -438.829418)
			(xy 381.263486 -438.81516) (xy 381.249247 -438.795541) (xy 381.241768 -438.772483) (xy 381.2413 -438.760362)
			(xy 381.2413 -438.147968) (xy 381.239755 -438.133476) (xy 381.238103 -438.104376) (xy 381.237998 -438.089802)
			(xy 361.128666 -438.089802) (xy 361.094814 -438.119007) (xy 360.991508 -438.19753) (xy 360.883543 -438.269512)
			(xy 360.771333 -438.334677) (xy 360.655306 -438.392776) (xy 360.535907 -438.443587) (xy 360.413594 -438.486915)
			(xy 360.288835 -438.522593) (xy 360.162108 -438.550485) (xy 360.033898 -438.570485) (xy 359.904696 -438.582516)
			(xy 359.774998 -438.586531) (xy 359.6453 -438.582516) (xy 359.516098 -438.570485) (xy 359.387888 -438.550485)
			(xy 359.261161 -438.522593) (xy 359.136402 -438.486915) (xy 359.014089 -438.443587) (xy 358.89469 -438.392776)
			(xy 358.778663 -438.334677) (xy 358.666453 -438.269512) (xy 358.558488 -438.19753) (xy 358.455182 -438.119007)
			(xy 358.356932 -438.034245) (xy 358.264114 -437.943567) (xy 358.177082 -437.847321) (xy 358.096171 -437.745876)
			(xy 358.02169 -437.63962) (xy 357.953924 -437.52896) (xy 357.893134 -437.41432) (xy 357.839551 -437.29614)
			(xy 357.793382 -437.174871) (xy 357.754802 -437.050978) (xy 357.723961 -436.924936) (xy 357.700975 -436.797228)
			(xy 357.685934 -436.668342) (xy 357.678893 -436.538773) (xy 357.679882 -436.409016) (xy 357.688895 -436.279569)
			(xy 357.705898 -436.150927) (xy 357.730826 -436.023584) (xy 357.763584 -435.898026) (xy 357.804046 -435.774736)
			(xy 357.852058 -435.654184) (xy 357.907434 -435.536833) (xy 357.969964 -435.423133) (xy 358.039407 -435.313518)
			(xy 358.115498 -435.208409) (xy 358.197945 -435.108208) (xy 358.286433 -435.013299) (xy 358.380622 -434.924045)
			(xy 358.430068 -434.882036) (xy 358.441235 -434.872067) (xy 358.457661 -434.847056) (xy 358.466134 -434.818358)
			(xy 358.465926 -434.788437) (xy 358.457055 -434.759859) (xy 358.440283 -434.735079) (xy 358.417049 -434.716224)
			(xy 358.403398 -434.710078) (xy 358.324356 -434.677212) (xy 358.169157 -434.604934) (xy 358.017549 -434.5254)
			(xy 357.869871 -434.438788) (xy 357.726451 -434.345291) (xy 357.587612 -434.24512) (xy 357.453663 -434.138498)
			(xy 357.324904 -434.025662) (xy 357.201623 -433.906867) (xy 357.084096 -433.782376) (xy 356.972584 -433.652469)
			(xy 356.867339 -433.517435) (xy 356.768594 -433.377578) (xy 356.676571 -433.233209) (xy 356.591476 -433.084651)
			(xy 356.513498 -432.932237) (xy 356.442812 -432.776307) (xy 356.379576 -432.61721) (xy 356.323932 -432.455301)
			(xy 356.276004 -432.290943) (xy 356.235899 -432.124503) (xy 356.203706 -431.956354) (xy 356.179498 -431.78687)
			(xy 356.163329 -431.616432) (xy 356.155235 -431.44542) (xy 356.154736 -431.359818) (xy 346.23502 -431.359818)
			(xy 346.23502 -432.560476) (xy 346.234563 -432.572582) (xy 346.227073 -432.595605) (xy 346.212821 -432.615176)
			(xy 346.193209 -432.629373) (xy 346.170165 -432.636797) (xy 346.158058 -432.637184) (xy 345.218258 -432.637184)
			(xy 345.206169 -432.636729) (xy 345.183171 -432.629264) (xy 345.163593 -432.615073) (xy 345.149343 -432.595539)
			(xy 345.141808 -432.572564) (xy 345.141296 -432.560476) (xy 345.141296 -431.948082) (xy 345.139753 -431.93359)
			(xy 345.1381 -431.90449) (xy 345.137994 -431.889916) (xy 342.235028 -431.889916) (xy 342.235028 -432.560476)
			(xy 342.234563 -432.572581) (xy 342.227074 -432.595602) (xy 342.212824 -432.615174) (xy 342.193214 -432.62937)
			(xy 342.170172 -432.636796) (xy 342.158066 -432.637184) (xy 341.218266 -432.637184) (xy 341.206177 -432.636722)
			(xy 341.183179 -432.629259) (xy 341.163602 -432.61507) (xy 341.149352 -432.595538) (xy 341.141816 -432.572563)
			(xy 341.141304 -432.560476) (xy 341.141304 -431.948082) (xy 341.13976 -431.93359) (xy 341.138108 -431.90449)
			(xy 341.138002 -431.889916) (xy 338.235036 -431.889916) (xy 338.235036 -432.560476) (xy 338.234564 -432.57258)
			(xy 338.227075 -432.5956) (xy 338.212827 -432.615171) (xy 338.193219 -432.629367) (xy 338.170179 -432.636795)
			(xy 338.158074 -432.637184) (xy 337.218274 -432.637184) (xy 337.206185 -432.636715) (xy 337.183188 -432.629254)
			(xy 337.163611 -432.615067) (xy 337.14936 -432.595536) (xy 337.141824 -432.572563) (xy 337.141312 -432.560476)
			(xy 337.141312 -431.948082) (xy 337.139768 -431.93359) (xy 337.138116 -431.90449) (xy 337.13801 -431.889916)
			(xy 334.235044 -431.889916) (xy 334.235044 -432.560476) (xy 334.234564 -432.572579) (xy 334.227076 -432.595598)
			(xy 334.21283 -432.615168) (xy 334.193224 -432.629365) (xy 334.170186 -432.636794) (xy 334.158082 -432.637184)
			(xy 333.218282 -432.637184) (xy 333.206194 -432.636709) (xy 333.183197 -432.62925) (xy 333.163619 -432.615065)
			(xy 333.149368 -432.595535) (xy 333.141832 -432.572563) (xy 333.14132 -432.560476) (xy 333.14132 -431.948082)
			(xy 333.139776 -431.93359) (xy 333.138124 -431.90449) (xy 333.138018 -431.889916) (xy 329.2348 -431.889916)
			(xy 329.2348 -432.560476) (xy 329.234367 -432.572558) (xy 329.226905 -432.595542) (xy 329.212704 -432.615093)
			(xy 329.193156 -432.629297) (xy 329.170174 -432.636764) (xy 329.158092 -432.637184) (xy 328.218292 -432.637184)
			(xy 328.206206 -432.636794) (xy 328.183219 -432.629321) (xy 328.163667 -432.61511) (xy 328.149464 -432.595552)
			(xy 328.142001 -432.572562) (xy 328.141584 -432.560476) (xy 328.141584 -431.950114) (xy 328.139914 -431.935121)
			(xy 328.138137 -431.905002) (xy 328.138028 -431.889916) (xy 325.234808 -431.889916) (xy 325.234808 -432.560476)
			(xy 325.234367 -432.572557) (xy 325.226906 -432.595539) (xy 325.212707 -432.61509) (xy 325.193161 -432.629295)
			(xy 325.170181 -432.636763) (xy 325.1581 -432.637184) (xy 324.2183 -432.637184) (xy 324.206215 -432.636787)
			(xy 324.183228 -432.629317) (xy 324.163676 -432.615107) (xy 324.149472 -432.59555) (xy 324.142009 -432.572561)
			(xy 324.141592 -432.560476) (xy 324.141592 -431.950114) (xy 324.139922 -431.935121) (xy 324.138145 -431.905002)
			(xy 324.138036 -431.889916) (xy 321.234816 -431.889916) (xy 321.234816 -432.560476) (xy 321.234367 -432.572557)
			(xy 321.226907 -432.595537) (xy 321.21271 -432.615087) (xy 321.193166 -432.629292) (xy 321.170188 -432.636762)
			(xy 321.158108 -432.637184) (xy 320.218308 -432.637184) (xy 320.206223 -432.63678) (xy 320.183237 -432.629312)
			(xy 320.163684 -432.615105) (xy 320.149481 -432.595549) (xy 320.142017 -432.572561) (xy 320.1416 -432.560476)
			(xy 320.1416 -431.950114) (xy 320.13993 -431.935121) (xy 320.138153 -431.905002) (xy 320.138044 -431.889916)
			(xy 317.234824 -431.889916) (xy 317.234824 -432.560476) (xy 317.234367 -432.572556) (xy 317.226908 -432.595535)
			(xy 317.212713 -432.615084) (xy 317.193171 -432.62929) (xy 317.170196 -432.636761) (xy 317.158116 -432.637184)
			(xy 316.218316 -432.637184) (xy 316.206232 -432.636773) (xy 316.183246 -432.629307) (xy 316.163693 -432.615101)
			(xy 316.149489 -432.595547) (xy 316.142026 -432.57256) (xy 316.141608 -432.560476) (xy 316.141608 -431.950114)
			(xy 316.139938 -431.935121) (xy 316.138161 -431.905002) (xy 316.138052 -431.889916) (xy 274.613204 -431.889916)
			(xy 274.618425 -431.905986) (xy 274.665585 -432.076867) (xy 274.705031 -432.249692) (xy 274.736684 -432.424113)
			(xy 274.760479 -432.599778) (xy 274.77637 -432.776334) (xy 274.784323 -432.953425) (xy 274.78482 -433.04206)
			(xy 274.784323 -433.130695) (xy 274.77637 -433.307786) (xy 274.760479 -433.484342) (xy 274.736684 -433.660007)
			(xy 274.705031 -433.834428) (xy 274.665585 -434.007253) (xy 274.618425 -434.178134) (xy 274.563646 -434.346728)
			(xy 274.509927 -434.48986) (xy 314.138056 -434.48986) (xy 314.138169 -434.474774) (xy 314.139948 -434.444656)
			(xy 314.141612 -434.429662) (xy 314.141612 -433.350162) (xy 314.139947 -433.335168) (xy 314.138166 -433.30505)
			(xy 314.138056 -433.289964) (xy 314.138169 -433.274878) (xy 314.139948 -433.24476) (xy 314.141612 -433.229766)
			(xy 314.141612 -432.618896) (xy 314.142009 -432.606811) (xy 314.14948 -432.583825) (xy 314.16369 -432.564273)
			(xy 314.183246 -432.550069) (xy 314.206235 -432.542606) (xy 314.21832 -432.542188) (xy 315.15812 -432.542188)
			(xy 315.170195 -432.542647) (xy 315.193162 -432.550115) (xy 315.212699 -432.564313) (xy 315.226893 -432.583852)
			(xy 315.234355 -432.606821) (xy 315.234828 -432.618896) (xy 315.234828 -435.16042) (xy 315.234353 -435.172494)
			(xy 315.226887 -435.195458) (xy 315.212693 -435.214993) (xy 315.193158 -435.229187) (xy 315.170194 -435.236653)
			(xy 315.15812 -435.237128) (xy 314.21832 -435.237128) (xy 314.206248 -435.236619) (xy 314.183285 -435.229165)
			(xy 314.16375 -435.214979) (xy 314.149554 -435.195451) (xy 314.142087 -435.172491) (xy 314.141612 -435.16042)
			(xy 314.141612 -434.550058) (xy 314.139946 -434.535064) (xy 314.138166 -434.504946) (xy 314.138056 -434.48986)
			(xy 274.509927 -434.48986) (xy 274.501358 -434.512693) (xy 274.431686 -434.675698) (xy 274.354772 -434.835412)
			(xy 274.270769 -434.991515) (xy 274.179848 -435.143692) (xy 274.082191 -435.291636) (xy 273.977994 -435.43505)
			(xy 273.934286 -435.489858) (xy 316.138052 -435.489858) (xy 316.138165 -435.474772) (xy 316.139944 -435.444654)
			(xy 316.141608 -435.42966) (xy 316.141608 -434.35016) (xy 316.139943 -434.335166) (xy 316.138162 -434.305048)
			(xy 316.138052 -434.289962) (xy 316.138165 -434.274876) (xy 316.139944 -434.244758) (xy 316.141608 -434.229764)
			(xy 316.141608 -433.618894) (xy 316.142102 -433.606807) (xy 316.149556 -433.583812) (xy 316.163737 -433.564235)
			(xy 316.183263 -433.549984) (xy 316.206231 -433.542446) (xy 316.218316 -433.541932) (xy 317.158116 -433.541932)
			(xy 317.170229 -433.542303) (xy 317.193262 -433.549811) (xy 317.212838 -433.564083) (xy 317.227031 -433.583716)
			(xy 317.234445 -433.606779) (xy 317.234824 -433.618894) (xy 317.234824 -434.48986) (xy 318.138048 -434.48986)
			(xy 318.138161 -434.474774) (xy 318.13994 -434.444656) (xy 318.141604 -434.429662) (xy 318.141604 -433.350162)
			(xy 318.139939 -433.335168) (xy 318.138158 -433.30505) (xy 318.138048 -433.289964) (xy 318.138161 -433.274878)
			(xy 318.13994 -433.24476) (xy 318.141604 -433.229766) (xy 318.141604 -432.618896) (xy 318.142009 -432.606812)
			(xy 318.149479 -432.583827) (xy 318.163687 -432.564276) (xy 318.183241 -432.550072) (xy 318.206228 -432.542607)
			(xy 318.218312 -432.542188) (xy 319.158112 -432.542188) (xy 319.170187 -432.542654) (xy 319.193154 -432.550119)
			(xy 319.21269 -432.564316) (xy 319.226884 -432.583854) (xy 319.234347 -432.606821) (xy 319.23482 -432.618896)
			(xy 319.23482 -435.16042) (xy 319.234353 -435.172494) (xy 319.226886 -435.19546) (xy 319.21269 -435.214996)
			(xy 319.193153 -435.22919) (xy 319.170186 -435.236654) (xy 319.158112 -435.237128) (xy 318.218312 -435.237128)
			(xy 318.20624 -435.236626) (xy 318.183277 -435.229169) (xy 318.163741 -435.214982) (xy 318.149546 -435.195452)
			(xy 318.142079 -435.172492) (xy 318.141604 -435.16042) (xy 318.141604 -434.550058) (xy 318.139938 -434.535064)
			(xy 318.138158 -434.504946) (xy 318.138048 -434.48986) (xy 317.234824 -434.48986) (xy 317.234824 -435.489858)
			(xy 320.138044 -435.489858) (xy 320.138157 -435.474772) (xy 320.139936 -435.444654) (xy 320.1416 -435.42966)
			(xy 320.1416 -434.35016) (xy 320.139934 -434.335166) (xy 320.138154 -434.305048) (xy 320.138044 -434.289962)
			(xy 320.138157 -434.274876) (xy 320.139936 -434.244758) (xy 320.1416 -434.229764) (xy 320.1416 -433.618894)
			(xy 320.142102 -433.606808) (xy 320.149555 -433.583814) (xy 320.163734 -433.564238) (xy 320.183258 -433.549986)
			(xy 320.206224 -433.542447) (xy 320.218308 -433.541932) (xy 321.158108 -433.541932) (xy 321.170221 -433.54231)
			(xy 321.193254 -433.549815) (xy 321.212829 -433.564086) (xy 321.227023 -433.583717) (xy 321.234437 -433.60678)
			(xy 321.234816 -433.618894) (xy 321.234816 -434.48986) (xy 322.13804 -434.48986) (xy 322.138153 -434.474774)
			(xy 322.139932 -434.444656) (xy 322.141596 -434.429662) (xy 322.141596 -433.350162) (xy 322.139931 -433.335168)
			(xy 322.13815 -433.30505) (xy 322.13804 -433.289964) (xy 322.138153 -433.274878) (xy 322.139932 -433.24476)
			(xy 322.141596 -433.229766) (xy 322.141596 -432.618896) (xy 322.142061 -432.606821) (xy 322.149525 -432.583853)
			(xy 322.163721 -432.564316) (xy 322.18326 -432.550121) (xy 322.206229 -432.54266) (xy 322.218304 -432.542188)
			(xy 323.158104 -432.542188) (xy 323.170178 -432.542661) (xy 323.193145 -432.550124) (xy 323.212682 -432.564318)
			(xy 323.226876 -432.583855) (xy 323.234339 -432.606822) (xy 323.234812 -432.618896) (xy 323.234812 -435.16042)
			(xy 323.234353 -435.172495) (xy 323.226885 -435.195462) (xy 323.212687 -435.214999) (xy 323.193148 -435.229193)
			(xy 323.170179 -435.236655) (xy 323.158104 -435.237128) (xy 322.218304 -435.237128) (xy 322.206232 -435.236633)
			(xy 322.183268 -435.229174) (xy 322.163733 -435.214984) (xy 322.149537 -435.195454) (xy 322.142071 -435.172492)
			(xy 322.141596 -435.16042) (xy 322.141596 -434.550058) (xy 322.13993 -434.535064) (xy 322.13815 -434.504946)
			(xy 322.13804 -434.48986) (xy 321.234816 -434.48986) (xy 321.234816 -435.489858) (xy 324.138036 -435.489858)
			(xy 324.138151 -435.474773) (xy 324.13993 -435.444654) (xy 324.141592 -435.42966) (xy 324.141592 -434.35016)
			(xy 324.139926 -434.335166) (xy 324.138146 -434.305048) (xy 324.138036 -434.289962) (xy 324.138151 -434.274877)
			(xy 324.13993 -434.244758) (xy 324.141592 -434.229764) (xy 324.141592 -433.618894) (xy 324.142102 -433.606809)
			(xy 324.149554 -433.583816) (xy 324.163731 -433.564241) (xy 324.183253 -433.549989) (xy 324.206217 -433.542448)
			(xy 324.2183 -433.541932) (xy 325.1581 -433.541932) (xy 325.170212 -433.542317) (xy 325.193245 -433.54982)
			(xy 325.212821 -433.564088) (xy 325.227014 -433.583719) (xy 325.234429 -433.60678) (xy 325.234808 -433.618894)
			(xy 325.234808 -434.48986) (xy 326.138032 -434.48986) (xy 326.138147 -434.474775) (xy 326.139926 -434.444656)
			(xy 326.141588 -434.429662) (xy 326.141588 -433.350162) (xy 326.139923 -433.335168) (xy 326.138142 -433.30505)
			(xy 326.138032 -433.289964) (xy 326.138148 -433.274879) (xy 326.139926 -433.24476) (xy 326.141588 -433.229766)
			(xy 326.141588 -432.618896) (xy 326.142061 -432.606822) (xy 326.149524 -432.583855) (xy 326.163718 -432.564318)
			(xy 326.183255 -432.550124) (xy 326.206222 -432.542661) (xy 326.218296 -432.542188) (xy 327.158096 -432.542188)
			(xy 327.17017 -432.542668) (xy 327.193136 -432.550129) (xy 327.212673 -432.564321) (xy 327.226868 -432.583857)
			(xy 327.234331 -432.606822) (xy 327.234804 -432.618896) (xy 327.234804 -435.16042) (xy 327.234353 -435.172496)
			(xy 327.226884 -435.195464) (xy 327.212684 -435.215001) (xy 327.193143 -435.229195) (xy 327.170172 -435.236656)
			(xy 327.158096 -435.237128) (xy 326.218296 -435.237128) (xy 326.206223 -435.236639) (xy 326.183259 -435.229178)
			(xy 326.163724 -435.214987) (xy 326.149529 -435.195455) (xy 326.142063 -435.172493) (xy 326.141588 -435.16042)
			(xy 326.141588 -434.550058) (xy 326.139922 -434.535064) (xy 326.138142 -434.504946) (xy 326.138032 -434.48986)
			(xy 325.234808 -434.48986) (xy 325.234808 -435.489858) (xy 328.138028 -435.489858) (xy 328.138143 -435.474773)
			(xy 328.139922 -435.444654) (xy 328.141584 -435.42966) (xy 328.141584 -434.35016) (xy 328.139918 -434.335166)
			(xy 328.138138 -434.305048) (xy 328.138028 -434.289962) (xy 328.138143 -434.274877) (xy 328.139922 -434.244758)
			(xy 328.141584 -434.229764) (xy 328.141584 -433.618894) (xy 328.142003 -433.6068) (xy 328.149467 -433.583792)
			(xy 328.163664 -433.564208) (xy 328.183211 -433.549959) (xy 328.206199 -433.542435) (xy 328.218292 -433.541932)
			(xy 329.158092 -433.541932) (xy 329.170204 -433.542323) (xy 329.193236 -433.549824) (xy 329.212812 -433.564091)
			(xy 329.227006 -433.58372) (xy 329.234421 -433.606781) (xy 329.2348 -433.618894) (xy 329.2348 -434.48986)
			(xy 331.138022 -434.48986) (xy 331.13812 -434.475286) (xy 331.13977 -434.446185) (xy 331.141324 -434.431694)
			(xy 331.141324 -433.34813) (xy 331.139776 -433.333638) (xy 331.138126 -433.304538) (xy 331.138022 -433.289964)
			(xy 331.13812 -433.27539) (xy 331.13977 -433.246289) (xy 331.141324 -433.231798) (xy 331.141324 -432.618896)
			(xy 331.141713 -432.606785) (xy 331.149217 -432.583753) (xy 331.163484 -432.564178) (xy 331.183113 -432.549984)
			(xy 331.206173 -432.542568) (xy 331.218286 -432.542188) (xy 332.158086 -432.542188) (xy 332.17018 -432.54262)
			(xy 332.193188 -432.550079) (xy 332.212772 -432.564273) (xy 332.227021 -432.583817) (xy 332.234545 -432.606804)
			(xy 332.235048 -432.618896) (xy 332.235048 -435.16042) (xy 332.234601 -435.172525) (xy 332.227102 -435.195545)
			(xy 332.212847 -435.215113) (xy 332.193235 -435.229309) (xy 332.170192 -435.236738) (xy 332.158086 -435.237128)
			(xy 331.218286 -435.237128) (xy 331.206192 -435.236704) (xy 331.183186 -435.22924) (xy 331.163603 -435.215043)
			(xy 331.149354 -435.195499) (xy 331.141828 -435.172512) (xy 331.141324 -435.16042) (xy 331.141324 -434.548026)
			(xy 331.139776 -434.533534) (xy 331.138126 -434.504434) (xy 331.138022 -434.48986) (xy 329.2348 -434.48986)
			(xy 329.2348 -435.489858) (xy 333.138018 -435.489858) (xy 333.138116 -435.475284) (xy 333.139766 -435.446183)
			(xy 333.14132 -435.431692) (xy 333.14132 -434.348128) (xy 333.139772 -434.333636) (xy 333.138122 -434.304536)
			(xy 333.138018 -434.289962) (xy 333.138116 -434.275388) (xy 333.139766 -434.246287) (xy 333.14132 -434.231796)
			(xy 333.14132 -433.618894) (xy 333.141807 -433.606781) (xy 333.149293 -433.583741) (xy 333.163532 -433.564141)
			(xy 333.18313 -433.549899) (xy 333.206169 -433.542408) (xy 333.218282 -433.541932) (xy 334.158082 -433.541932)
			(xy 334.170203 -433.542375) (xy 334.19326 -433.549862) (xy 334.212875 -433.564108) (xy 334.227127 -433.583718)
			(xy 334.234621 -433.606773) (xy 334.235044 -433.618894) (xy 334.235044 -434.48986) (xy 335.138014 -434.48986)
			(xy 335.138111 -434.475286) (xy 335.139761 -434.446185) (xy 335.141316 -434.431694) (xy 335.141316 -433.34813)
			(xy 335.139768 -433.333638) (xy 335.138118 -433.304538) (xy 335.138014 -433.289964) (xy 335.138112 -433.27539)
			(xy 335.139761 -433.246289) (xy 335.141316 -433.231798) (xy 335.141316 -432.618896) (xy 335.141713 -432.606785)
			(xy 335.149215 -432.583755) (xy 335.163481 -432.564181) (xy 335.183108 -432.549987) (xy 335.206166 -432.542569)
			(xy 335.218278 -432.542188) (xy 336.158078 -432.542188) (xy 336.170171 -432.542627) (xy 336.193179 -432.550084)
			(xy 336.212764 -432.564276) (xy 336.227013 -432.583818) (xy 336.234537 -432.606804) (xy 336.23504 -432.618896)
			(xy 336.23504 -435.16042) (xy 336.234601 -435.172526) (xy 336.227101 -435.195547) (xy 336.212844 -435.215116)
			(xy 336.19323 -435.229312) (xy 336.170185 -435.236739) (xy 336.158078 -435.237128) (xy 335.218278 -435.237128)
			(xy 335.206184 -435.236711) (xy 335.183177 -435.229244) (xy 335.163595 -435.215046) (xy 335.149346 -435.1955)
			(xy 335.14182 -435.172513) (xy 335.141316 -435.16042) (xy 335.141316 -434.548026) (xy 335.139768 -434.533534)
			(xy 335.138118 -434.504434) (xy 335.138014 -434.48986) (xy 334.235044 -434.48986) (xy 334.235044 -435.489858)
			(xy 337.13801 -435.489858) (xy 337.138107 -435.475284) (xy 337.139757 -435.446183) (xy 337.141312 -435.431692)
			(xy 337.141312 -434.348128) (xy 337.139764 -434.333636) (xy 337.138114 -434.304536) (xy 337.13801 -434.289962)
			(xy 337.138108 -434.275388) (xy 337.139757 -434.246287) (xy 337.141312 -434.231796) (xy 337.141312 -433.618894)
			(xy 337.141806 -433.606782) (xy 337.149292 -433.583743) (xy 337.163529 -433.564143) (xy 337.183125 -433.549901)
			(xy 337.206162 -433.54241) (xy 337.218274 -433.541932) (xy 338.158074 -433.541932) (xy 338.170195 -433.542382)
			(xy 338.193252 -433.549866) (xy 338.212867 -433.56411) (xy 338.227119 -433.58372) (xy 338.234613 -433.606773)
			(xy 338.235036 -433.618894) (xy 338.235036 -434.48986) (xy 339.138006 -434.48986) (xy 339.138104 -434.475286)
			(xy 339.139753 -434.446185) (xy 339.141308 -434.431694) (xy 339.141308 -433.34813) (xy 339.13976 -433.333638)
			(xy 339.13811 -433.304538) (xy 339.138006 -433.289964) (xy 339.138104 -433.27539) (xy 339.139753 -433.246289)
			(xy 339.141308 -433.231798) (xy 339.141308 -432.618896) (xy 339.141713 -432.606786) (xy 339.149214 -432.583757)
			(xy 339.163479 -432.564184) (xy 339.183103 -432.549989) (xy 339.206159 -432.54257) (xy 339.21827 -432.542188)
			(xy 340.15807 -432.542188) (xy 340.170163 -432.542634) (xy 340.19317 -432.550088) (xy 340.212755 -432.564278)
			(xy 340.227005 -432.58382) (xy 340.234529 -432.606805) (xy 340.235032 -432.618896) (xy 340.235032 -435.16042)
			(xy 340.234601 -435.172527) (xy 340.2271 -435.195549) (xy 340.212841 -435.215119) (xy 340.193225 -435.229314)
			(xy 340.170178 -435.23674) (xy 340.15807 -435.237128) (xy 339.21827 -435.237128) (xy 339.206176 -435.236718)
			(xy 339.183169 -435.229249) (xy 339.163586 -435.215049) (xy 339.149338 -435.195502) (xy 339.141812 -435.172513)
			(xy 339.141308 -435.16042) (xy 339.141308 -434.548026) (xy 339.13976 -434.533534) (xy 339.13811 -434.504434)
			(xy 339.138006 -434.48986) (xy 338.235036 -434.48986) (xy 338.235036 -435.489858) (xy 341.138002 -435.489858)
			(xy 341.138099 -435.475284) (xy 341.139749 -435.446183) (xy 341.141304 -435.431692) (xy 341.141304 -434.348128)
			(xy 341.139756 -434.333636) (xy 341.138106 -434.304536) (xy 341.138002 -434.289962) (xy 341.1381 -434.275388)
			(xy 341.139749 -434.246287) (xy 341.141304 -434.231796) (xy 341.141304 -433.618894) (xy 341.141806 -433.606783)
			(xy 341.149291 -433.583745) (xy 341.163526 -433.564146) (xy 341.18312 -433.549904) (xy 341.206155 -433.542411)
			(xy 341.218266 -433.541932) (xy 342.158066 -433.541932) (xy 342.170186 -433.542389) (xy 342.193243 -433.549871)
			(xy 342.212858 -433.564113) (xy 342.227111 -433.583721) (xy 342.234605 -433.606774) (xy 342.235028 -433.618894)
			(xy 342.235028 -434.48986) (xy 343.137998 -434.48986) (xy 343.138096 -434.475286) (xy 343.139745 -434.446185)
			(xy 343.1413 -434.431694) (xy 343.1413 -433.34813) (xy 343.139752 -433.333638) (xy 343.138102 -433.304538)
			(xy 343.137998 -433.289964) (xy 343.138096 -433.27539) (xy 343.139745 -433.246289) (xy 343.1413 -433.231798)
			(xy 343.1413 -432.618896) (xy 343.141713 -432.606787) (xy 343.149213 -432.583759) (xy 343.163476 -432.564186)
			(xy 343.183098 -432.549992) (xy 343.206152 -432.542571) (xy 343.218262 -432.542188) (xy 344.158062 -432.542188)
			(xy 344.170154 -432.542641) (xy 344.193162 -432.550093) (xy 344.212747 -432.564281) (xy 344.226997 -432.583821)
			(xy 344.234521 -432.606805) (xy 344.235024 -432.618896) (xy 344.235024 -435.16042) (xy 344.234601 -435.172528)
			(xy 344.227099 -435.195551) (xy 344.212838 -435.215122) (xy 344.19322 -435.229317) (xy 344.170171 -435.236741)
			(xy 344.158062 -435.237128) (xy 343.218262 -435.237128) (xy 343.206167 -435.236724) (xy 343.18316 -435.229253)
			(xy 343.163578 -435.215052) (xy 343.14933 -435.195503) (xy 343.141804 -435.172514) (xy 343.1413 -435.16042)
			(xy 343.1413 -434.548026) (xy 343.139752 -434.533534) (xy 343.138102 -434.504434) (xy 343.137998 -434.48986)
			(xy 342.235028 -434.48986) (xy 342.235028 -435.489858) (xy 345.137994 -435.489858) (xy 345.138091 -435.475284)
			(xy 345.139741 -435.446183) (xy 345.141296 -435.431692) (xy 345.141296 -434.348128) (xy 345.139748 -434.333636)
			(xy 345.138098 -434.304536) (xy 345.137994 -434.289962) (xy 345.138092 -434.275388) (xy 345.139741 -434.246287)
			(xy 345.141296 -434.231796) (xy 345.141296 -433.618894) (xy 345.141806 -433.606783) (xy 345.14929 -433.583747)
			(xy 345.163524 -433.564149) (xy 345.183115 -433.549906) (xy 345.206148 -433.542412) (xy 345.218258 -433.541932)
			(xy 346.158058 -433.541932) (xy 346.170178 -433.542396) (xy 346.193234 -433.549876) (xy 346.21285 -433.564116)
			(xy 346.227103 -433.583722) (xy 346.234597 -433.606774) (xy 346.23502 -433.618894) (xy 346.23502 -436.160418)
			(xy 346.234654 -436.172546) (xy 346.227152 -436.195612) (xy 346.212888 -436.215231) (xy 346.193258 -436.22948)
			(xy 346.170186 -436.236964) (xy 346.158058 -436.23738) (xy 345.218258 -436.23738) (xy 345.206143 -436.236924)
			(xy 345.183101 -436.229428) (xy 345.163502 -436.215181) (xy 345.149261 -436.195577) (xy 345.141772 -436.172533)
			(xy 345.141296 -436.160418) (xy 345.141296 -435.548024) (xy 345.139748 -435.533532) (xy 345.138098 -435.504432)
			(xy 345.137994 -435.489858) (xy 342.235028 -435.489858) (xy 342.235028 -436.160418) (xy 342.234655 -436.172545)
			(xy 342.227153 -436.19561) (xy 342.212891 -436.215228) (xy 342.193264 -436.229477) (xy 342.170193 -436.236963)
			(xy 342.158066 -436.23738) (xy 341.218266 -436.23738) (xy 341.206151 -436.236918) (xy 341.18311 -436.229423)
			(xy 341.16351 -436.215178) (xy 341.149269 -436.195576) (xy 341.14178 -436.172533) (xy 341.141304 -436.160418)
			(xy 341.141304 -435.548024) (xy 341.139755 -435.533532) (xy 341.138106 -435.504432) (xy 341.138002 -435.489858)
			(xy 338.235036 -435.489858) (xy 338.235036 -436.160418) (xy 338.234655 -436.172544) (xy 338.227154 -436.195608)
			(xy 338.212894 -436.215225) (xy 338.193269 -436.229474) (xy 338.1702 -436.236962) (xy 338.158074 -436.23738)
			(xy 337.218274 -436.23738) (xy 337.20616 -436.236911) (xy 337.183119 -436.229419) (xy 337.163519 -436.215175)
			(xy 337.149278 -436.195574) (xy 337.141788 -436.172532) (xy 337.141312 -436.160418) (xy 337.141312 -435.548024)
			(xy 337.139763 -435.533532) (xy 337.138114 -435.504432) (xy 337.13801 -435.489858) (xy 334.235044 -435.489858)
			(xy 334.235044 -436.160418) (xy 334.234604 -436.172535) (xy 334.227109 -436.195582) (xy 334.21286 -436.215185)
			(xy 334.19325 -436.229426) (xy 334.1702 -436.236909) (xy 334.158082 -436.23738) (xy 333.218282 -436.23738)
			(xy 333.206168 -436.236904) (xy 333.183127 -436.229414) (xy 333.163528 -436.215172) (xy 333.149286 -436.195573)
			(xy 333.141796 -436.172532) (xy 333.14132 -436.160418) (xy 333.14132 -435.548024) (xy 333.139771 -435.533532)
			(xy 333.138122 -435.504432) (xy 333.138018 -435.489858) (xy 329.2348 -435.489858) (xy 329.2348 -436.160418)
			(xy 329.234309 -436.172505) (xy 329.226852 -436.195499) (xy 329.21267 -436.215075) (xy 329.193145 -436.229327)
			(xy 329.170177 -436.236865) (xy 329.158092 -436.23738) (xy 328.218292 -436.23738) (xy 328.206181 -436.23699)
			(xy 328.18315 -436.229486) (xy 328.163575 -436.215219) (xy 328.149381 -436.19559) (xy 328.141964 -436.172531)
			(xy 328.141584 -436.160418) (xy 328.141584 -435.550056) (xy 328.139918 -435.535062) (xy 328.138138 -435.504944)
			(xy 328.138028 -435.489858) (xy 325.234808 -435.489858) (xy 325.234808 -436.160418) (xy 325.234309 -436.172504)
			(xy 325.226853 -436.195497) (xy 325.212673 -436.215072) (xy 325.19315 -436.229324) (xy 325.170184 -436.236864)
			(xy 325.1581 -436.23738) (xy 324.2183 -436.23738) (xy 324.206189 -436.236984) (xy 324.183158 -436.229482)
			(xy 324.163583 -436.215216) (xy 324.14939 -436.195589) (xy 324.141972 -436.17253) (xy 324.141592 -436.160418)
			(xy 324.141592 -435.550056) (xy 324.139926 -435.535062) (xy 324.138146 -435.504944) (xy 324.138036 -435.489858)
			(xy 321.234816 -435.489858) (xy 321.234816 -436.160418) (xy 321.234407 -436.172513) (xy 321.22694 -436.195522)
			(xy 321.21274 -436.215105) (xy 321.193192 -436.229353) (xy 321.170202 -436.236877) (xy 321.158108 -436.23738)
			(xy 320.218308 -436.23738) (xy 320.206198 -436.236977) (xy 320.183167 -436.229477) (xy 320.163592 -436.215213)
			(xy 320.149398 -436.195587) (xy 320.14198 -436.17253) (xy 320.1416 -436.160418) (xy 320.1416 -435.550056)
			(xy 320.139934 -435.535062) (xy 320.138154 -435.504944) (xy 320.138044 -435.489858) (xy 317.234824 -435.489858)
			(xy 317.234824 -436.160418) (xy 317.234407 -436.172512) (xy 317.226941 -436.195519) (xy 317.212743 -436.215102)
			(xy 317.193197 -436.229351) (xy 317.170209 -436.236876) (xy 317.158116 -436.23738) (xy 316.218316 -436.23738)
			(xy 316.206206 -436.23697) (xy 316.183176 -436.229472) (xy 316.163601 -436.21521) (xy 316.149406 -436.195585)
			(xy 316.141989 -436.172529) (xy 316.141608 -436.160418) (xy 316.141608 -435.550056) (xy 316.139942 -435.535062)
			(xy 316.138162 -435.504944) (xy 316.138052 -435.489858) (xy 273.934286 -435.489858) (xy 273.867468 -435.573645)
			(xy 273.750836 -435.707142) (xy 273.628331 -435.835271) (xy 273.500202 -435.957776) (xy 273.366705 -436.074408)
			(xy 273.22811 -436.184934) (xy 273.084696 -436.289131) (xy 272.936752 -436.386788) (xy 272.784575 -436.477709)
			(xy 272.628472 -436.561712) (xy 272.468758 -436.638626) (xy 272.305753 -436.708298) (xy 272.139788 -436.770586)
			(xy 271.971194 -436.825365) (xy 271.800313 -436.872525) (xy 271.627488 -436.911971) (xy 271.453067 -436.943624)
			(xy 271.277402 -436.967419) (xy 271.100846 -436.98331) (xy 270.923755 -436.991263) (xy 270.746485 -436.991263)
			(xy 270.569394 -436.98331) (xy 270.392838 -436.967419) (xy 270.217173 -436.943624) (xy 270.042752 -436.911971)
			(xy 269.869927 -436.872525) (xy 269.699046 -436.825365) (xy 269.530452 -436.770586) (xy 269.364487 -436.708298)
			(xy 269.201482 -436.638626) (xy 269.041768 -436.561712) (xy 268.885665 -436.477709) (xy 268.733488 -436.386788)
			(xy 268.585544 -436.289131) (xy 268.44213 -436.184934) (xy 268.303535 -436.074408) (xy 268.170038 -435.957776)
			(xy 268.041909 -435.835271) (xy 267.919404 -435.707142) (xy 267.802772 -435.573645) (xy 267.692246 -435.43505)
			(xy 267.588049 -435.291636) (xy 267.490392 -435.143692) (xy 267.399471 -434.991515) (xy 267.315468 -434.835412)
			(xy 267.238554 -434.675698) (xy 267.168882 -434.512693) (xy 267.106594 -434.346728) (xy 267.051815 -434.178134)
			(xy 267.004655 -434.007253) (xy 266.965209 -433.834428) (xy 266.933556 -433.660007) (xy 266.909761 -433.484342)
			(xy 266.89387 -433.307786) (xy 266.885917 -433.130695) (xy 231.01554 -433.130695) (xy 231.01554 -435.063392)
			(xy 231.015024 -435.08834) (xy 231.007214 -435.137622) (xy 230.991802 -435.185079) (xy 230.969165 -435.229545)
			(xy 230.939859 -435.269929) (xy 230.922576 -435.287928) (xy 229.133908 -437.076596) (xy 229.115913 -437.093886)
			(xy 229.075537 -437.12321) (xy 229.031071 -437.145858) (xy 228.98361 -437.161272) (xy 228.934323 -437.169073)
			(xy 228.909372 -437.16956) (xy 207.503268 -437.16956) (xy 207.478319 -437.169063) (xy 207.429037 -437.161248)
			(xy 207.38158 -437.14583) (xy 207.337114 -437.123189) (xy 207.296731 -437.09388) (xy 207.278732 -437.076596)
			(xy 205.949804 -435.747668) (xy 205.932495 -435.72969) (xy 205.903173 -435.68931) (xy 205.880529 -435.64484)
			(xy 205.865119 -435.597375) (xy 205.857324 -435.548084) (xy 205.85684 -435.523132) (xy 205.85684 -429.817784)
			(xy 197.285356 -421.2463) (xy 192.77076 -421.2463) (xy 192.74581 -421.245825) (xy 192.696526 -421.238007)
			(xy 192.649068 -421.222586) (xy 192.604603 -421.199939) (xy 192.564221 -421.170623) (xy 192.546224 -421.153336)
			(xy 184.781952 -413.389064) (xy 184.76463 -413.371097) (xy 184.735303 -413.330715) (xy 184.712655 -413.286243)
			(xy 184.697243 -413.238776) (xy 184.689446 -413.189482) (xy 184.688988 -413.164528) (xy 184.688988 -408.491182)
			(xy 184.68948 -408.466233) (xy 184.697294 -408.416949) (xy 184.712712 -408.369492) (xy 184.735355 -408.325026)
			(xy 184.764667 -408.284644) (xy 184.781952 -408.266646) (xy 184.892188 -408.15641) (xy 184.892188 -407.290778)
			(xy 184.874462 -407.269826) (xy 184.844586 -407.223792) (xy 184.821621 -407.173948) (xy 184.806044 -407.121325)
			(xy 184.798176 -407.067012) (xy 184.7977 -407.039572) (xy 184.798716 -407.01341) (xy 184.80024 -406.99055)
			(xy 184.654952 -406.845262) (xy 184.637629 -406.827296) (xy 184.608302 -406.786914) (xy 184.585654 -406.742442)
			(xy 184.570242 -406.694974) (xy 184.562446 -406.64568) (xy 184.561988 -406.620726) (xy 16.741648 -406.620726)
			(xy 16.741648 -407.031753) (xy 48.944975 -407.031753) (xy 48.944975 -406.977247) (xy 48.952733 -406.923295)
			(xy 48.96809 -406.870997) (xy 48.990734 -406.821417) (xy 49.020204 -406.775565) (xy 49.0559 -406.734373)
			(xy 49.097095 -406.698681) (xy 49.142951 -406.669216) (xy 49.192533 -406.646577) (xy 49.244833 -406.631225)
			(xy 49.298785 -406.623473) (xy 49.326038 -406.623012) (xy 50.189638 -406.623012) (xy 50.216889 -406.62346)
			(xy 50.270835 -406.631222) (xy 50.323128 -406.646581) (xy 50.372703 -406.669225) (xy 50.418551 -406.698694)
			(xy 50.459739 -406.734388) (xy 50.495428 -406.775579) (xy 50.524893 -406.82143) (xy 50.547532 -406.871007)
			(xy 50.562886 -406.923302) (xy 50.570642 -406.977249) (xy 50.570642 -407.031749) (xy 52.008298 -407.031749)
			(xy 52.008298 -406.977251) (xy 52.016054 -406.923308) (xy 52.031407 -406.871018) (xy 52.054045 -406.821445)
			(xy 52.083508 -406.775598) (xy 52.119195 -406.734411) (xy 52.16038 -406.698721) (xy 52.206226 -406.669256)
			(xy 52.255797 -406.646615) (xy 52.308087 -406.631258) (xy 52.362029 -406.6235) (xy 52.389278 -406.623012)
			(xy 53.252878 -406.623012) (xy 53.280133 -406.623433) (xy 53.33409 -406.631188) (xy 53.386393 -406.646543)
			(xy 53.435978 -406.669186) (xy 53.481837 -406.698655) (xy 53.523034 -406.73435) (xy 53.558732 -406.775546)
			(xy 53.588204 -406.821402) (xy 53.610849 -406.870987) (xy 53.626207 -406.923289) (xy 53.633965 -406.977245)
			(xy 53.633965 -407.031752) (xy 55.071475 -407.031752) (xy 55.071475 -406.977248) (xy 55.079232 -406.923298)
			(xy 55.094589 -406.871002) (xy 55.117231 -406.821423) (xy 55.146699 -406.775571) (xy 55.182393 -406.73438)
			(xy 55.223586 -406.698688) (xy 55.269439 -406.669222) (xy 55.319018 -406.646582) (xy 55.371316 -406.631229)
			(xy 55.425266 -406.623474) (xy 55.452518 -406.623012) (xy 56.316118 -406.623012) (xy 56.34337 -406.623459)
			(xy 56.397318 -406.631218) (xy 56.449614 -406.646576) (xy 56.499191 -406.669219) (xy 56.545042 -406.698687)
			(xy 56.586232 -406.734381) (xy 56.621924 -406.775573) (xy 56.65139 -406.821424) (xy 56.674031 -406.871003)
			(xy 56.689386 -406.923299) (xy 56.697142 -406.977248) (xy 56.697142 -407.031748) (xy 58.134798 -407.031748)
			(xy 58.134798 -406.977252) (xy 58.142553 -406.923311) (xy 58.157905 -406.871022) (xy 58.180542 -406.821451)
			(xy 58.210003 -406.775605) (xy 58.245688 -406.734418) (xy 58.286871 -406.698728) (xy 58.332714 -406.669262)
			(xy 58.382283 -406.64662) (xy 58.43457 -406.631262) (xy 58.48851 -406.623501) (xy 58.515758 -406.623012)
			(xy 59.379358 -406.623012) (xy 59.406614 -406.623432) (xy 59.460573 -406.631185) (xy 59.512878 -406.646538)
			(xy 59.562466 -406.669179) (xy 59.608327 -406.698648) (xy 59.649527 -406.734343) (xy 59.685227 -406.775539)
			(xy 59.714701 -406.821397) (xy 59.737348 -406.870982) (xy 59.752707 -406.923286) (xy 59.760465 -406.977244)
			(xy 59.760465 -407.03175) (xy 61.197998 -407.03175) (xy 61.197998 -406.97725) (xy 61.205754 -406.923306)
			(xy 61.221108 -406.871014) (xy 61.243748 -406.821439) (xy 61.273213 -406.775592) (xy 61.308902 -406.734404)
			(xy 61.35009 -406.698714) (xy 61.395938 -406.669249) (xy 61.445512 -406.646609) (xy 61.497804 -406.631255)
			(xy 61.551748 -406.623498) (xy 61.578998 -406.623012) (xy 62.442598 -406.623012) (xy 62.469852 -406.623435)
			(xy 62.523806 -406.631192) (xy 62.576107 -406.646549) (xy 62.62569 -406.669192) (xy 62.671546 -406.698662)
			(xy 62.712741 -406.734357) (xy 62.748437 -406.775552) (xy 62.777907 -406.821408) (xy 62.800551 -406.870991)
			(xy 62.815908 -406.923292) (xy 62.823665 -406.977246) (xy 62.823665 -407.031753) (xy 64.261175 -407.031753)
			(xy 64.261175 -406.977247) (xy 64.268933 -406.923295) (xy 64.28429 -406.870997) (xy 64.306934 -406.821417)
			(xy 64.336404 -406.775565) (xy 64.3721 -406.734373) (xy 64.413295 -406.698681) (xy 64.459151 -406.669216)
			(xy 64.508733 -406.646577) (xy 64.561033 -406.631225) (xy 64.614985 -406.623473) (xy 64.642238 -406.623012)
			(xy 65.505838 -406.623012) (xy 65.533089 -406.62346) (xy 65.587035 -406.631222) (xy 65.639328 -406.646581)
			(xy 65.688903 -406.669225) (xy 65.734751 -406.698694) (xy 65.775939 -406.734388) (xy 65.811628 -406.775579)
			(xy 65.841093 -406.82143) (xy 65.863732 -406.871007) (xy 65.879086 -406.923302) (xy 65.886842 -406.977249)
			(xy 65.886842 -407.031749) (xy 67.324498 -407.031749) (xy 67.324498 -406.977251) (xy 67.332254 -406.923308)
			(xy 67.347607 -406.871018) (xy 67.370245 -406.821445) (xy 67.399708 -406.775598) (xy 67.435395 -406.734411)
			(xy 67.47658 -406.698721) (xy 67.522426 -406.669256) (xy 67.571997 -406.646615) (xy 67.624287 -406.631258)
			(xy 67.678229 -406.6235) (xy 67.705478 -406.623012) (xy 68.569078 -406.623012) (xy 68.596333 -406.623433)
			(xy 68.65029 -406.631188) (xy 68.702593 -406.646543) (xy 68.752178 -406.669186) (xy 68.798037 -406.698655)
			(xy 68.839234 -406.73435) (xy 68.874932 -406.775546) (xy 68.904404 -406.821402) (xy 68.927049 -406.870987)
			(xy 68.942407 -406.923289) (xy 68.950165 -406.977245) (xy 68.950165 -407.031752) (xy 70.387675 -407.031752)
			(xy 70.387675 -406.977248) (xy 70.395432 -406.923298) (xy 70.410789 -406.871002) (xy 70.433431 -406.821423)
			(xy 70.462899 -406.775571) (xy 70.498593 -406.73438) (xy 70.539786 -406.698688) (xy 70.585639 -406.669222)
			(xy 70.635218 -406.646582) (xy 70.687516 -406.631229) (xy 70.741466 -406.623474) (xy 70.768718 -406.623012)
			(xy 71.632318 -406.623012) (xy 71.65957 -406.623459) (xy 71.713518 -406.631218) (xy 71.765814 -406.646576)
			(xy 71.815391 -406.669219) (xy 71.861242 -406.698687) (xy 71.902432 -406.734381) (xy 71.938124 -406.775573)
			(xy 71.96759 -406.821424) (xy 71.990231 -406.871003) (xy 72.005586 -406.923299) (xy 72.013342 -406.977248)
			(xy 72.013342 -407.031748) (xy 73.450998 -407.031748) (xy 73.450998 -406.977252) (xy 73.458753 -406.923311)
			(xy 73.474105 -406.871022) (xy 73.496742 -406.821451) (xy 73.526203 -406.775605) (xy 73.561888 -406.734418)
			(xy 73.603071 -406.698728) (xy 73.648914 -406.669262) (xy 73.698483 -406.64662) (xy 73.75077 -406.631262)
			(xy 73.80471 -406.623501) (xy 73.831958 -406.623012) (xy 74.695558 -406.623012) (xy 74.722814 -406.623432)
			(xy 74.776773 -406.631185) (xy 74.829078 -406.646538) (xy 74.878666 -406.669179) (xy 74.924527 -406.698648)
			(xy 74.965727 -406.734343) (xy 75.001427 -406.775539) (xy 75.030901 -406.821397) (xy 75.053548 -406.870982)
			(xy 75.068907 -406.923286) (xy 75.076665 -406.977244) (xy 75.076665 -407.03175) (xy 76.514198 -407.03175)
			(xy 76.514198 -406.97725) (xy 76.521954 -406.923306) (xy 76.537308 -406.871014) (xy 76.559948 -406.821439)
			(xy 76.589413 -406.775592) (xy 76.625102 -406.734404) (xy 76.66629 -406.698714) (xy 76.712138 -406.669249)
			(xy 76.761712 -406.646609) (xy 76.814004 -406.631255) (xy 76.867948 -406.623498) (xy 76.895198 -406.623012)
			(xy 77.758798 -406.623012) (xy 77.786052 -406.623435) (xy 77.840006 -406.631192) (xy 77.892307 -406.646549)
			(xy 77.94189 -406.669192) (xy 77.987746 -406.698662) (xy 78.028941 -406.734357) (xy 78.064637 -406.775552)
			(xy 78.094107 -406.821408) (xy 78.116751 -406.870991) (xy 78.132108 -406.923292) (xy 78.139865 -406.977246)
			(xy 78.139865 -407.031753) (xy 79.577375 -407.031753) (xy 79.577375 -406.977247) (xy 79.585133 -406.923295)
			(xy 79.60049 -406.870997) (xy 79.623134 -406.821417) (xy 79.652604 -406.775565) (xy 79.6883 -406.734373)
			(xy 79.729495 -406.698681) (xy 79.775351 -406.669216) (xy 79.824933 -406.646577) (xy 79.877233 -406.631225)
			(xy 79.931185 -406.623473) (xy 79.958438 -406.623012) (xy 80.822038 -406.623012) (xy 80.849289 -406.62346)
			(xy 80.903235 -406.631222) (xy 80.955528 -406.646581) (xy 81.005103 -406.669225) (xy 81.050951 -406.698694)
			(xy 81.092139 -406.734388) (xy 81.127828 -406.775579) (xy 81.157293 -406.82143) (xy 81.179932 -406.871007)
			(xy 81.195286 -406.923302) (xy 81.203042 -406.977249) (xy 81.203042 -407.031749) (xy 82.640698 -407.031749)
			(xy 82.640698 -406.977251) (xy 82.648454 -406.923308) (xy 82.663807 -406.871018) (xy 82.686445 -406.821445)
			(xy 82.715908 -406.775598) (xy 82.751595 -406.734411) (xy 82.79278 -406.698721) (xy 82.838626 -406.669256)
			(xy 82.888197 -406.646615) (xy 82.940487 -406.631258) (xy 82.994429 -406.6235) (xy 83.021678 -406.623012)
			(xy 83.885278 -406.623012) (xy 83.912533 -406.623433) (xy 83.96649 -406.631188) (xy 84.018793 -406.646543)
			(xy 84.068378 -406.669186) (xy 84.114237 -406.698655) (xy 84.155434 -406.73435) (xy 84.191132 -406.775546)
			(xy 84.220604 -406.821402) (xy 84.243249 -406.870987) (xy 84.258607 -406.923289) (xy 84.266365 -406.977245)
			(xy 84.266365 -407.031752) (xy 85.703875 -407.031752) (xy 85.703875 -406.977248) (xy 85.711632 -406.923298)
			(xy 85.726989 -406.871002) (xy 85.749631 -406.821423) (xy 85.779099 -406.775571) (xy 85.814793 -406.73438)
			(xy 85.855986 -406.698688) (xy 85.901839 -406.669222) (xy 85.951418 -406.646582) (xy 86.003716 -406.631229)
			(xy 86.057666 -406.623474) (xy 86.084918 -406.623012) (xy 86.948518 -406.623012) (xy 86.97577 -406.623459)
			(xy 87.029718 -406.631218) (xy 87.082014 -406.646576) (xy 87.131591 -406.669219) (xy 87.177442 -406.698687)
			(xy 87.218632 -406.734381) (xy 87.254324 -406.775573) (xy 87.28379 -406.821424) (xy 87.306431 -406.871003)
			(xy 87.321786 -406.923299) (xy 87.329542 -406.977248) (xy 87.329542 -407.031748) (xy 88.767198 -407.031748)
			(xy 88.767198 -406.977252) (xy 88.774953 -406.923311) (xy 88.790305 -406.871022) (xy 88.812942 -406.821451)
			(xy 88.842403 -406.775605) (xy 88.878088 -406.734418) (xy 88.919271 -406.698728) (xy 88.965114 -406.669262)
			(xy 89.014683 -406.64662) (xy 89.06697 -406.631262) (xy 89.12091 -406.623501) (xy 89.148158 -406.623012)
			(xy 90.011758 -406.623012) (xy 90.039014 -406.623432) (xy 90.092973 -406.631185) (xy 90.145278 -406.646538)
			(xy 90.194866 -406.669179) (xy 90.240727 -406.698648) (xy 90.281927 -406.734343) (xy 90.317627 -406.775539)
			(xy 90.347101 -406.821397) (xy 90.369748 -406.870982) (xy 90.385107 -406.923286) (xy 90.392865 -406.977244)
			(xy 90.392865 -407.03175) (xy 91.830398 -407.03175) (xy 91.830398 -406.97725) (xy 91.838154 -406.923306)
			(xy 91.853508 -406.871014) (xy 91.876148 -406.821439) (xy 91.905613 -406.775592) (xy 91.941302 -406.734404)
			(xy 91.98249 -406.698714) (xy 92.028338 -406.669249) (xy 92.077912 -406.646609) (xy 92.130204 -406.631255)
			(xy 92.184148 -406.623498) (xy 92.211398 -406.623012) (xy 93.074998 -406.623012) (xy 93.102252 -406.623435)
			(xy 93.156206 -406.631192) (xy 93.208507 -406.646549) (xy 93.25809 -406.669192) (xy 93.303946 -406.698662)
			(xy 93.345141 -406.734357) (xy 93.380837 -406.775552) (xy 93.410307 -406.821408) (xy 93.432951 -406.870991)
			(xy 93.448308 -406.923292) (xy 93.456065 -406.977246) (xy 93.456065 -407.031753) (xy 94.893575 -407.031753)
			(xy 94.893575 -406.977247) (xy 94.901333 -406.923295) (xy 94.91669 -406.870997) (xy 94.939334 -406.821417)
			(xy 94.968804 -406.775565) (xy 95.0045 -406.734373) (xy 95.045695 -406.698681) (xy 95.091551 -406.669216)
			(xy 95.141133 -406.646577) (xy 95.193433 -406.631225) (xy 95.247385 -406.623473) (xy 95.274638 -406.623012)
			(xy 96.138238 -406.623012) (xy 96.165489 -406.62346) (xy 96.219435 -406.631222) (xy 96.271728 -406.646581)
			(xy 96.321303 -406.669225) (xy 96.367151 -406.698694) (xy 96.408339 -406.734388) (xy 96.444028 -406.775579)
			(xy 96.473493 -406.82143) (xy 96.496132 -406.871007) (xy 96.511486 -406.923302) (xy 96.519242 -406.977249)
			(xy 96.519242 -407.031751) (xy 96.511486 -407.085698) (xy 96.496132 -407.137993) (xy 96.495694 -407.138953)
			(xy 106.243063 -407.138953) (xy 106.243063 -407.084447) (xy 106.250821 -407.030495) (xy 106.266177 -406.978197)
			(xy 106.288821 -406.928617) (xy 106.31829 -406.882763) (xy 106.353985 -406.841571) (xy 106.395179 -406.805878)
			(xy 106.441034 -406.776411) (xy 106.490616 -406.75377) (xy 106.542915 -406.738416) (xy 106.596867 -406.730662)
			(xy 106.62412 -406.7302) (xy 107.48772 -406.7302) (xy 107.514971 -406.730671) (xy 107.568918 -406.73843)
			(xy 107.621211 -406.753787) (xy 107.670787 -406.77643) (xy 107.716636 -406.805898) (xy 107.757824 -406.84159)
			(xy 107.793514 -406.88278) (xy 107.82298 -406.928631) (xy 107.84562 -406.978208) (xy 107.860974 -407.030502)
			(xy 107.861153 -407.031748) (xy 121.120198 -407.031748) (xy 121.120198 -406.977252) (xy 121.127953 -406.923312)
			(xy 121.143305 -406.871023) (xy 121.165942 -406.821452) (xy 121.195402 -406.775606) (xy 121.231087 -406.734419)
			(xy 121.272269 -406.69873) (xy 121.318111 -406.669264) (xy 121.36768 -406.646621) (xy 121.419967 -406.631263)
			(xy 121.473906 -406.623501) (xy 121.501154 -406.623012) (xy 122.364754 -406.623012) (xy 122.39201 -406.623432)
			(xy 122.445969 -406.631184) (xy 122.498275 -406.646537) (xy 122.547864 -406.669178) (xy 122.593725 -406.698646)
			(xy 122.634926 -406.734342) (xy 122.670626 -406.775538) (xy 122.7001 -406.821396) (xy 122.722747 -406.870981)
			(xy 122.738106 -406.923286) (xy 122.745865 -406.977244) (xy 122.745865 -407.03175) (xy 124.183398 -407.03175)
			(xy 124.183398 -406.97725) (xy 124.191154 -406.923306) (xy 124.206508 -406.871015) (xy 124.229148 -406.821441)
			(xy 124.258612 -406.775593) (xy 124.294301 -406.734405) (xy 124.335488 -406.698715) (xy 124.381335 -406.669251)
			(xy 124.430909 -406.64661) (xy 124.4832 -406.631255) (xy 124.537144 -406.623499) (xy 124.564394 -406.623012)
			(xy 125.427994 -406.623012) (xy 125.455249 -406.623434) (xy 125.509203 -406.631191) (xy 125.561504 -406.646548)
			(xy 125.611088 -406.669191) (xy 125.656944 -406.69866) (xy 125.69814 -406.734356) (xy 125.733836 -406.775551)
			(xy 125.763306 -406.821407) (xy 125.78595 -406.87099) (xy 125.801308 -406.923291) (xy 125.809065 -406.977245)
			(xy 125.809065 -407.031753) (xy 127.246575 -407.031753) (xy 127.246575 -406.977247) (xy 127.254333 -406.923296)
			(xy 127.26969 -406.870998) (xy 127.292334 -406.821418) (xy 127.321803 -406.775566) (xy 127.357499 -406.734375)
			(xy 127.398693 -406.698683) (xy 127.444548 -406.669217) (xy 127.49413 -406.646578) (xy 127.546429 -406.631226)
			(xy 127.600381 -406.623473) (xy 127.627634 -406.623012) (xy 128.491234 -406.623012) (xy 128.518485 -406.62346)
			(xy 128.572432 -406.631221) (xy 128.624725 -406.64658) (xy 128.674301 -406.669224) (xy 128.720149 -406.698693)
			(xy 128.761338 -406.734386) (xy 128.797028 -406.775578) (xy 128.826492 -406.821429) (xy 128.849132 -406.871007)
			(xy 128.864486 -406.923301) (xy 128.872242 -406.977249) (xy 128.872242 -407.031749) (xy 130.309898 -407.031749)
			(xy 130.309898 -406.977251) (xy 130.317654 -406.923309) (xy 130.333007 -406.871019) (xy 130.355645 -406.821446)
			(xy 130.385107 -406.775599) (xy 130.420794 -406.734412) (xy 130.461979 -406.698722) (xy 130.507823 -406.669257)
			(xy 130.557395 -406.646616) (xy 130.609683 -406.631259) (xy 130.663625 -406.6235) (xy 130.690874 -406.623012)
			(xy 131.554474 -406.623012) (xy 131.58173 -406.623433) (xy 131.635686 -406.631187) (xy 131.68799 -406.646542)
			(xy 131.737576 -406.669184) (xy 131.783435 -406.698653) (xy 131.824633 -406.734349) (xy 131.860331 -406.775544)
			(xy 131.889803 -406.821401) (xy 131.912449 -406.870986) (xy 131.927807 -406.923288) (xy 131.935565 -406.977245)
			(xy 131.935565 -407.031752) (xy 133.373075 -407.031752) (xy 133.373075 -406.977248) (xy 133.380832 -406.923299)
			(xy 133.396188 -406.871002) (xy 133.418831 -406.821424) (xy 133.448298 -406.775573) (xy 133.483992 -406.734382)
			(xy 133.525184 -406.69869) (xy 133.571036 -406.669224) (xy 133.620616 -406.646583) (xy 133.672912 -406.631229)
			(xy 133.726862 -406.623474) (xy 133.754114 -406.623012) (xy 134.617714 -406.623012) (xy 134.644966 -406.623459)
			(xy 134.698915 -406.631217) (xy 134.751211 -406.646574) (xy 134.800789 -406.669218) (xy 134.84664 -406.698686)
			(xy 134.887831 -406.734379) (xy 134.923523 -406.775571) (xy 134.952989 -406.821423) (xy 134.97563 -406.871002)
			(xy 134.990986 -406.923299) (xy 134.998742 -406.977248) (xy 134.998742 -407.031748) (xy 136.436398 -407.031748)
			(xy 136.436398 -406.977252) (xy 136.444153 -406.923312) (xy 136.459505 -406.871023) (xy 136.482142 -406.821452)
			(xy 136.511602 -406.775606) (xy 136.547287 -406.734419) (xy 136.588469 -406.69873) (xy 136.634311 -406.669264)
			(xy 136.68388 -406.646621) (xy 136.736167 -406.631263) (xy 136.790106 -406.623501) (xy 136.817354 -406.623012)
			(xy 137.680954 -406.623012) (xy 137.70821 -406.623432) (xy 137.762169 -406.631184) (xy 137.814475 -406.646537)
			(xy 137.864064 -406.669178) (xy 137.909925 -406.698646) (xy 137.951126 -406.734342) (xy 137.986826 -406.775538)
			(xy 138.0163 -406.821396) (xy 138.038947 -406.870981) (xy 138.054306 -406.923286) (xy 138.062065 -406.977244)
			(xy 138.062065 -407.03175) (xy 139.499598 -407.03175) (xy 139.499598 -406.97725) (xy 139.507354 -406.923306)
			(xy 139.522708 -406.871015) (xy 139.545348 -406.821441) (xy 139.574812 -406.775593) (xy 139.610501 -406.734405)
			(xy 139.651688 -406.698715) (xy 139.697535 -406.669251) (xy 139.747109 -406.64661) (xy 139.7994 -406.631255)
			(xy 139.853344 -406.623499) (xy 139.880594 -406.623012) (xy 140.744194 -406.623012) (xy 140.771449 -406.623434)
			(xy 140.825403 -406.631191) (xy 140.877704 -406.646548) (xy 140.927288 -406.669191) (xy 140.973144 -406.69866)
			(xy 141.01434 -406.734356) (xy 141.050036 -406.775551) (xy 141.079506 -406.821407) (xy 141.10215 -406.87099)
			(xy 141.117508 -406.923291) (xy 141.125265 -406.977245) (xy 141.125265 -407.031753) (xy 142.562775 -407.031753)
			(xy 142.562775 -406.977247) (xy 142.570533 -406.923296) (xy 142.58589 -406.870998) (xy 142.608534 -406.821418)
			(xy 142.638003 -406.775566) (xy 142.673699 -406.734375) (xy 142.714893 -406.698683) (xy 142.760748 -406.669217)
			(xy 142.81033 -406.646578) (xy 142.862629 -406.631226) (xy 142.916581 -406.623473) (xy 142.943834 -406.623012)
			(xy 143.807434 -406.623012) (xy 143.834685 -406.62346) (xy 143.888632 -406.631221) (xy 143.940925 -406.64658)
			(xy 143.990501 -406.669224) (xy 144.036349 -406.698693) (xy 144.077538 -406.734386) (xy 144.113228 -406.775578)
			(xy 144.142692 -406.821429) (xy 144.165332 -406.871007) (xy 144.180686 -406.923301) (xy 144.188442 -406.977249)
			(xy 144.188442 -407.031749) (xy 145.626098 -407.031749) (xy 145.626098 -406.977251) (xy 145.633854 -406.923309)
			(xy 145.649207 -406.871019) (xy 145.671845 -406.821446) (xy 145.701307 -406.775599) (xy 145.736994 -406.734412)
			(xy 145.778179 -406.698722) (xy 145.824023 -406.669257) (xy 145.873595 -406.646616) (xy 145.925883 -406.631259)
			(xy 145.979825 -406.6235) (xy 146.007074 -406.623012) (xy 146.870674 -406.623012) (xy 146.89793 -406.623433)
			(xy 146.951886 -406.631187) (xy 147.00419 -406.646542) (xy 147.053776 -406.669184) (xy 147.099635 -406.698653)
			(xy 147.140833 -406.734349) (xy 147.176531 -406.775544) (xy 147.206003 -406.821401) (xy 147.228649 -406.870986)
			(xy 147.244007 -406.923288) (xy 147.251765 -406.977245) (xy 147.251765 -407.031752) (xy 148.689275 -407.031752)
			(xy 148.689275 -406.977248) (xy 148.697032 -406.923299) (xy 148.712388 -406.871002) (xy 148.735031 -406.821424)
			(xy 148.764498 -406.775573) (xy 148.800192 -406.734382) (xy 148.841384 -406.69869) (xy 148.887236 -406.669224)
			(xy 148.936816 -406.646583) (xy 148.989112 -406.631229) (xy 149.043062 -406.623474) (xy 149.070314 -406.623012)
			(xy 149.933914 -406.623012) (xy 149.961166 -406.623459) (xy 150.015115 -406.631217) (xy 150.067411 -406.646574)
			(xy 150.116989 -406.669218) (xy 150.16284 -406.698686) (xy 150.204031 -406.734379) (xy 150.239723 -406.775571)
			(xy 150.269189 -406.821423) (xy 150.29183 -406.871002) (xy 150.307186 -406.923299) (xy 150.314942 -406.977248)
			(xy 150.314942 -407.031748) (xy 151.752598 -407.031748) (xy 151.752598 -406.977252) (xy 151.760353 -406.923312)
			(xy 151.775705 -406.871023) (xy 151.798342 -406.821452) (xy 151.827802 -406.775606) (xy 151.863487 -406.734419)
			(xy 151.904669 -406.69873) (xy 151.950511 -406.669264) (xy 152.00008 -406.646621) (xy 152.052367 -406.631263)
			(xy 152.106306 -406.623501) (xy 152.133554 -406.623012) (xy 152.997154 -406.623012) (xy 153.02441 -406.623432)
			(xy 153.078369 -406.631184) (xy 153.130675 -406.646537) (xy 153.180264 -406.669178) (xy 153.226125 -406.698646)
			(xy 153.267326 -406.734342) (xy 153.303026 -406.775538) (xy 153.3325 -406.821396) (xy 153.355147 -406.870981)
			(xy 153.370506 -406.923286) (xy 153.378265 -406.977244) (xy 153.378265 -407.03175) (xy 154.815798 -407.03175)
			(xy 154.815798 -406.97725) (xy 154.823554 -406.923306) (xy 154.838908 -406.871015) (xy 154.861548 -406.821441)
			(xy 154.891012 -406.775593) (xy 154.926701 -406.734405) (xy 154.967888 -406.698715) (xy 155.013735 -406.669251)
			(xy 155.063309 -406.64661) (xy 155.1156 -406.631255) (xy 155.169544 -406.623499) (xy 155.196794 -406.623012)
			(xy 156.060394 -406.623012) (xy 156.087649 -406.623434) (xy 156.141603 -406.631191) (xy 156.193904 -406.646548)
			(xy 156.243488 -406.669191) (xy 156.289344 -406.69866) (xy 156.33054 -406.734356) (xy 156.366236 -406.775551)
			(xy 156.395706 -406.821407) (xy 156.41835 -406.87099) (xy 156.433708 -406.923291) (xy 156.441465 -406.977245)
			(xy 156.441465 -407.031753) (xy 157.878975 -407.031753) (xy 157.878975 -406.977247) (xy 157.886733 -406.923296)
			(xy 157.90209 -406.870998) (xy 157.924734 -406.821418) (xy 157.954203 -406.775566) (xy 157.989899 -406.734375)
			(xy 158.031093 -406.698683) (xy 158.076948 -406.669217) (xy 158.12653 -406.646578) (xy 158.178829 -406.631226)
			(xy 158.232781 -406.623473) (xy 158.260034 -406.623012) (xy 159.123634 -406.623012) (xy 159.150885 -406.62346)
			(xy 159.204832 -406.631221) (xy 159.257125 -406.64658) (xy 159.306701 -406.669224) (xy 159.352549 -406.698693)
			(xy 159.393738 -406.734386) (xy 159.429428 -406.775578) (xy 159.458892 -406.821429) (xy 159.481532 -406.871007)
			(xy 159.496886 -406.923301) (xy 159.504642 -406.977249) (xy 159.504642 -407.031749) (xy 160.942298 -407.031749)
			(xy 160.942298 -406.977251) (xy 160.950054 -406.923309) (xy 160.965407 -406.871019) (xy 160.988045 -406.821446)
			(xy 161.017507 -406.775599) (xy 161.053194 -406.734412) (xy 161.094379 -406.698722) (xy 161.140223 -406.669257)
			(xy 161.189795 -406.646616) (xy 161.242083 -406.631259) (xy 161.296025 -406.6235) (xy 161.323274 -406.623012)
			(xy 162.186874 -406.623012) (xy 162.21413 -406.623433) (xy 162.268086 -406.631187) (xy 162.32039 -406.646542)
			(xy 162.369976 -406.669184) (xy 162.415835 -406.698653) (xy 162.457033 -406.734349) (xy 162.492731 -406.775544)
			(xy 162.522203 -406.821401) (xy 162.544849 -406.870986) (xy 162.560207 -406.923288) (xy 162.567965 -406.977245)
			(xy 162.567965 -407.031752) (xy 164.005475 -407.031752) (xy 164.005475 -406.977248) (xy 164.013232 -406.923299)
			(xy 164.028588 -406.871002) (xy 164.051231 -406.821424) (xy 164.080698 -406.775573) (xy 164.116392 -406.734382)
			(xy 164.157584 -406.69869) (xy 164.203436 -406.669224) (xy 164.253016 -406.646583) (xy 164.305312 -406.631229)
			(xy 164.359262 -406.623474) (xy 164.386514 -406.623012) (xy 165.250114 -406.623012) (xy 165.277366 -406.623459)
			(xy 165.331315 -406.631217) (xy 165.383611 -406.646574) (xy 165.433189 -406.669218) (xy 165.47904 -406.698686)
			(xy 165.520231 -406.734379) (xy 165.555923 -406.775571) (xy 165.585389 -406.821423) (xy 165.60803 -406.871002)
			(xy 165.623386 -406.923299) (xy 165.631142 -406.977248) (xy 165.631142 -407.031748) (xy 167.068798 -407.031748)
			(xy 167.068798 -406.977252) (xy 167.076553 -406.923312) (xy 167.091905 -406.871023) (xy 167.114542 -406.821452)
			(xy 167.144002 -406.775606) (xy 167.179687 -406.734419) (xy 167.220869 -406.69873) (xy 167.266711 -406.669264)
			(xy 167.31628 -406.646621) (xy 167.368567 -406.631263) (xy 167.422506 -406.623501) (xy 167.449754 -406.623012)
			(xy 168.313354 -406.623012) (xy 168.34061 -406.623432) (xy 168.394569 -406.631184) (xy 168.446875 -406.646537)
			(xy 168.496464 -406.669178) (xy 168.542325 -406.698646) (xy 168.583526 -406.734342) (xy 168.619226 -406.775538)
			(xy 168.6487 -406.821396) (xy 168.671347 -406.870981) (xy 168.686706 -406.923286) (xy 168.694465 -406.977244)
			(xy 168.694465 -407.031756) (xy 168.686706 -407.085714) (xy 168.671347 -407.138019) (xy 168.6487 -407.187604)
			(xy 168.619226 -407.233462) (xy 168.583526 -407.274658) (xy 168.542325 -407.310354) (xy 168.496464 -407.339822)
			(xy 168.446875 -407.362463) (xy 168.394569 -407.377816) (xy 168.34061 -407.385568) (xy 168.313354 -407.386028)
			(xy 167.449754 -407.386028) (xy 167.422506 -407.385499) (xy 167.368567 -407.377737) (xy 167.31628 -407.362379)
			(xy 167.266711 -407.339736) (xy 167.220869 -407.31027) (xy 167.179687 -407.274581) (xy 167.144002 -407.233394)
			(xy 167.114542 -407.187548) (xy 167.091905 -407.137977) (xy 167.076553 -407.085688) (xy 167.068798 -407.031748)
			(xy 165.631142 -407.031748) (xy 165.631142 -407.031752) (xy 165.623386 -407.085701) (xy 165.60803 -407.137998)
			(xy 165.585389 -407.187577) (xy 165.555923 -407.233429) (xy 165.520231 -407.274621) (xy 165.47904 -407.310314)
			(xy 165.433189 -407.339782) (xy 165.383611 -407.362426) (xy 165.331315 -407.377783) (xy 165.277366 -407.385541)
			(xy 165.250114 -407.386028) (xy 164.386514 -407.386028) (xy 164.359262 -407.385526) (xy 164.305312 -407.377771)
			(xy 164.253016 -407.362417) (xy 164.203436 -407.339776) (xy 164.157584 -407.31031) (xy 164.116392 -407.274618)
			(xy 164.080698 -407.233427) (xy 164.051231 -407.187576) (xy 164.028588 -407.137998) (xy 164.013232 -407.085701)
			(xy 164.005475 -407.031752) (xy 162.567965 -407.031752) (xy 162.567965 -407.031755) (xy 162.560207 -407.085712)
			(xy 162.544849 -407.138014) (xy 162.522203 -407.187599) (xy 162.492731 -407.233456) (xy 162.457033 -407.274651)
			(xy 162.415835 -407.310347) (xy 162.369976 -407.339816) (xy 162.32039 -407.362458) (xy 162.268086 -407.377813)
			(xy 162.21413 -407.385567) (xy 162.186874 -407.386028) (xy 161.323274 -407.386028) (xy 161.296025 -407.3855)
			(xy 161.242083 -407.377741) (xy 161.189795 -407.362384) (xy 161.140223 -407.339743) (xy 161.094379 -407.310278)
			(xy 161.053194 -407.274588) (xy 161.017507 -407.233401) (xy 160.988045 -407.187554) (xy 160.965407 -407.137981)
			(xy 160.950054 -407.085691) (xy 160.942298 -407.031749) (xy 159.504642 -407.031749) (xy 159.504642 -407.031751)
			(xy 159.496886 -407.085699) (xy 159.481532 -407.137993) (xy 159.458892 -407.187571) (xy 159.429428 -407.233422)
			(xy 159.393738 -407.274614) (xy 159.352549 -407.310307) (xy 159.306701 -407.339776) (xy 159.257125 -407.36242)
			(xy 159.204832 -407.377779) (xy 159.150885 -407.38554) (xy 159.123634 -407.386028) (xy 158.260034 -407.386028)
			(xy 158.232781 -407.385527) (xy 158.178829 -407.377774) (xy 158.12653 -407.362422) (xy 158.076948 -407.339783)
			(xy 158.031093 -407.310317) (xy 157.989899 -407.274625) (xy 157.954203 -407.233434) (xy 157.924734 -407.187582)
			(xy 157.90209 -407.138002) (xy 157.886733 -407.085704) (xy 157.878975 -407.031753) (xy 156.441465 -407.031753)
			(xy 156.441465 -407.031755) (xy 156.433708 -407.085709) (xy 156.41835 -407.13801) (xy 156.395706 -407.187593)
			(xy 156.366236 -407.233449) (xy 156.33054 -407.274644) (xy 156.289344 -407.31034) (xy 156.243488 -407.339809)
			(xy 156.193904 -407.362452) (xy 156.141603 -407.377809) (xy 156.087649 -407.385566) (xy 156.060394 -407.386028)
			(xy 155.196794 -407.386028) (xy 155.169544 -407.385501) (xy 155.1156 -407.377745) (xy 155.063309 -407.36239)
			(xy 155.013735 -407.339749) (xy 154.967888 -407.310285) (xy 154.926701 -407.274595) (xy 154.891012 -407.233407)
			(xy 154.861548 -407.187559) (xy 154.838908 -407.137985) (xy 154.823554 -407.085694) (xy 154.815798 -407.03175)
			(xy 153.378265 -407.03175) (xy 153.378265 -407.031756) (xy 153.370506 -407.085714) (xy 153.355147 -407.138019)
			(xy 153.3325 -407.187604) (xy 153.303026 -407.233462) (xy 153.267326 -407.274658) (xy 153.226125 -407.310354)
			(xy 153.180264 -407.339822) (xy 153.130675 -407.362463) (xy 153.078369 -407.377816) (xy 153.02441 -407.385568)
			(xy 152.997154 -407.386028) (xy 152.133554 -407.386028) (xy 152.106306 -407.385499) (xy 152.052367 -407.377737)
			(xy 152.00008 -407.362379) (xy 151.950511 -407.339736) (xy 151.904669 -407.31027) (xy 151.863487 -407.274581)
			(xy 151.827802 -407.233394) (xy 151.798342 -407.187548) (xy 151.775705 -407.137977) (xy 151.760353 -407.085688)
			(xy 151.752598 -407.031748) (xy 150.314942 -407.031748) (xy 150.314942 -407.031752) (xy 150.307186 -407.085701)
			(xy 150.29183 -407.137998) (xy 150.269189 -407.187577) (xy 150.239723 -407.233429) (xy 150.204031 -407.274621)
			(xy 150.16284 -407.310314) (xy 150.116989 -407.339782) (xy 150.067411 -407.362426) (xy 150.015115 -407.377783)
			(xy 149.961166 -407.385541) (xy 149.933914 -407.386028) (xy 149.070314 -407.386028) (xy 149.043062 -407.385526)
			(xy 148.989112 -407.377771) (xy 148.936816 -407.362417) (xy 148.887236 -407.339776) (xy 148.841384 -407.31031)
			(xy 148.800192 -407.274618) (xy 148.764498 -407.233427) (xy 148.735031 -407.187576) (xy 148.712388 -407.137998)
			(xy 148.697032 -407.085701) (xy 148.689275 -407.031752) (xy 147.251765 -407.031752) (xy 147.251765 -407.031755)
			(xy 147.244007 -407.085712) (xy 147.228649 -407.138014) (xy 147.206003 -407.187599) (xy 147.176531 -407.233456)
			(xy 147.140833 -407.274651) (xy 147.099635 -407.310347) (xy 147.053776 -407.339816) (xy 147.00419 -407.362458)
			(xy 146.951886 -407.377813) (xy 146.89793 -407.385567) (xy 146.870674 -407.386028) (xy 146.007074 -407.386028)
			(xy 145.979825 -407.3855) (xy 145.925883 -407.377741) (xy 145.873595 -407.362384) (xy 145.824023 -407.339743)
			(xy 145.778179 -407.310278) (xy 145.736994 -407.274588) (xy 145.701307 -407.233401) (xy 145.671845 -407.187554)
			(xy 145.649207 -407.137981) (xy 145.633854 -407.085691) (xy 145.626098 -407.031749) (xy 144.188442 -407.031749)
			(xy 144.188442 -407.031751) (xy 144.180686 -407.085699) (xy 144.165332 -407.137993) (xy 144.142692 -407.187571)
			(xy 144.113228 -407.233422) (xy 144.077538 -407.274614) (xy 144.036349 -407.310307) (xy 143.990501 -407.339776)
			(xy 143.940925 -407.36242) (xy 143.888632 -407.377779) (xy 143.834685 -407.38554) (xy 143.807434 -407.386028)
			(xy 142.943834 -407.386028) (xy 142.916581 -407.385527) (xy 142.862629 -407.377774) (xy 142.81033 -407.362422)
			(xy 142.760748 -407.339783) (xy 142.714893 -407.310317) (xy 142.673699 -407.274625) (xy 142.638003 -407.233434)
			(xy 142.608534 -407.187582) (xy 142.58589 -407.138002) (xy 142.570533 -407.085704) (xy 142.562775 -407.031753)
			(xy 141.125265 -407.031753) (xy 141.125265 -407.031755) (xy 141.117508 -407.085709) (xy 141.10215 -407.13801)
			(xy 141.079506 -407.187593) (xy 141.050036 -407.233449) (xy 141.01434 -407.274644) (xy 140.973144 -407.31034)
			(xy 140.927288 -407.339809) (xy 140.877704 -407.362452) (xy 140.825403 -407.377809) (xy 140.771449 -407.385566)
			(xy 140.744194 -407.386028) (xy 139.880594 -407.386028) (xy 139.853344 -407.385501) (xy 139.7994 -407.377745)
			(xy 139.747109 -407.36239) (xy 139.697535 -407.339749) (xy 139.651688 -407.310285) (xy 139.610501 -407.274595)
			(xy 139.574812 -407.233407) (xy 139.545348 -407.187559) (xy 139.522708 -407.137985) (xy 139.507354 -407.085694)
			(xy 139.499598 -407.03175) (xy 138.062065 -407.03175) (xy 138.062065 -407.031756) (xy 138.054306 -407.085714)
			(xy 138.038947 -407.138019) (xy 138.0163 -407.187604) (xy 137.986826 -407.233462) (xy 137.951126 -407.274658)
			(xy 137.909925 -407.310354) (xy 137.864064 -407.339822) (xy 137.814475 -407.362463) (xy 137.762169 -407.377816)
			(xy 137.70821 -407.385568) (xy 137.680954 -407.386028) (xy 136.817354 -407.386028) (xy 136.790106 -407.385499)
			(xy 136.736167 -407.377737) (xy 136.68388 -407.362379) (xy 136.634311 -407.339736) (xy 136.588469 -407.31027)
			(xy 136.547287 -407.274581) (xy 136.511602 -407.233394) (xy 136.482142 -407.187548) (xy 136.459505 -407.137977)
			(xy 136.444153 -407.085688) (xy 136.436398 -407.031748) (xy 134.998742 -407.031748) (xy 134.998742 -407.031752)
			(xy 134.990986 -407.085701) (xy 134.97563 -407.137998) (xy 134.952989 -407.187577) (xy 134.923523 -407.233429)
			(xy 134.887831 -407.274621) (xy 134.84664 -407.310314) (xy 134.800789 -407.339782) (xy 134.751211 -407.362426)
			(xy 134.698915 -407.377783) (xy 134.644966 -407.385541) (xy 134.617714 -407.386028) (xy 133.754114 -407.386028)
			(xy 133.726862 -407.385526) (xy 133.672912 -407.377771) (xy 133.620616 -407.362417) (xy 133.571036 -407.339776)
			(xy 133.525184 -407.31031) (xy 133.483992 -407.274618) (xy 133.448298 -407.233427) (xy 133.418831 -407.187576)
			(xy 133.396188 -407.137998) (xy 133.380832 -407.085701) (xy 133.373075 -407.031752) (xy 131.935565 -407.031752)
			(xy 131.935565 -407.031755) (xy 131.927807 -407.085712) (xy 131.912449 -407.138014) (xy 131.889803 -407.187599)
			(xy 131.860331 -407.233456) (xy 131.824633 -407.274651) (xy 131.783435 -407.310347) (xy 131.737576 -407.339816)
			(xy 131.68799 -407.362458) (xy 131.635686 -407.377813) (xy 131.58173 -407.385567) (xy 131.554474 -407.386028)
			(xy 130.690874 -407.386028) (xy 130.663625 -407.3855) (xy 130.609683 -407.377741) (xy 130.557395 -407.362384)
			(xy 130.507823 -407.339743) (xy 130.461979 -407.310278) (xy 130.420794 -407.274588) (xy 130.385107 -407.233401)
			(xy 130.355645 -407.187554) (xy 130.333007 -407.137981) (xy 130.317654 -407.085691) (xy 130.309898 -407.031749)
			(xy 128.872242 -407.031749) (xy 128.872242 -407.031751) (xy 128.864486 -407.085699) (xy 128.849132 -407.137993)
			(xy 128.826492 -407.187571) (xy 128.797028 -407.233422) (xy 128.761338 -407.274614) (xy 128.720149 -407.310307)
			(xy 128.674301 -407.339776) (xy 128.624725 -407.36242) (xy 128.572432 -407.377779) (xy 128.518485 -407.38554)
			(xy 128.491234 -407.386028) (xy 127.627634 -407.386028) (xy 127.600381 -407.385527) (xy 127.546429 -407.377774)
			(xy 127.49413 -407.362422) (xy 127.444548 -407.339783) (xy 127.398693 -407.310317) (xy 127.357499 -407.274625)
			(xy 127.321803 -407.233434) (xy 127.292334 -407.187582) (xy 127.26969 -407.138002) (xy 127.254333 -407.085704)
			(xy 127.246575 -407.031753) (xy 125.809065 -407.031753) (xy 125.809065 -407.031755) (xy 125.801308 -407.085709)
			(xy 125.78595 -407.13801) (xy 125.763306 -407.187593) (xy 125.733836 -407.233449) (xy 125.69814 -407.274644)
			(xy 125.656944 -407.31034) (xy 125.611088 -407.339809) (xy 125.561504 -407.362452) (xy 125.509203 -407.377809)
			(xy 125.455249 -407.385566) (xy 125.427994 -407.386028) (xy 124.564394 -407.386028) (xy 124.537144 -407.385501)
			(xy 124.4832 -407.377745) (xy 124.430909 -407.36239) (xy 124.381335 -407.339749) (xy 124.335488 -407.310285)
			(xy 124.294301 -407.274595) (xy 124.258612 -407.233407) (xy 124.229148 -407.187559) (xy 124.206508 -407.137985)
			(xy 124.191154 -407.085694) (xy 124.183398 -407.03175) (xy 122.745865 -407.03175) (xy 122.745865 -407.031756)
			(xy 122.738106 -407.085714) (xy 122.722747 -407.138019) (xy 122.7001 -407.187604) (xy 122.670626 -407.233462)
			(xy 122.634926 -407.274658) (xy 122.593725 -407.310354) (xy 122.547864 -407.339822) (xy 122.498275 -407.362463)
			(xy 122.445969 -407.377816) (xy 122.39201 -407.385568) (xy 122.364754 -407.386028) (xy 121.501154 -407.386028)
			(xy 121.473906 -407.385499) (xy 121.419967 -407.377737) (xy 121.36768 -407.362379) (xy 121.318111 -407.339736)
			(xy 121.272269 -407.31027) (xy 121.231087 -407.274581) (xy 121.195402 -407.233394) (xy 121.165942 -407.187548)
			(xy 121.143305 -407.137977) (xy 121.127953 -407.085688) (xy 121.120198 -407.031748) (xy 107.861153 -407.031748)
			(xy 107.86873 -407.084449) (xy 107.86873 -407.138951) (xy 107.860974 -407.192898) (xy 107.84562 -407.245192)
			(xy 107.822979 -407.294769) (xy 107.793514 -407.34062) (xy 107.757824 -407.38181) (xy 107.716636 -407.417502)
			(xy 107.670787 -407.44697) (xy 107.621211 -407.469613) (xy 107.568918 -407.48497) (xy 107.514971 -407.492729)
			(xy 107.48772 -407.493216) (xy 106.62412 -407.493216) (xy 106.596867 -407.492738) (xy 106.542915 -407.484984)
			(xy 106.490616 -407.46963) (xy 106.441034 -407.446989) (xy 106.395179 -407.417522) (xy 106.353985 -407.381829)
			(xy 106.31829 -407.340637) (xy 106.288821 -407.294783) (xy 106.266177 -407.245203) (xy 106.250821 -407.192905)
			(xy 106.243063 -407.138953) (xy 96.495694 -407.138953) (xy 96.473493 -407.18757) (xy 96.444028 -407.233421)
			(xy 96.408339 -407.274612) (xy 96.367151 -407.310306) (xy 96.321303 -407.339775) (xy 96.271728 -407.362419)
			(xy 96.219435 -407.377778) (xy 96.165489 -407.38554) (xy 96.138238 -407.386028) (xy 95.274638 -407.386028)
			(xy 95.247385 -407.385527) (xy 95.193433 -407.377775) (xy 95.141133 -407.362423) (xy 95.091551 -407.339784)
			(xy 95.045695 -407.310319) (xy 95.0045 -407.274627) (xy 94.968804 -407.233435) (xy 94.939334 -407.187583)
			(xy 94.91669 -407.138003) (xy 94.901333 -407.085705) (xy 94.893575 -407.031753) (xy 93.456065 -407.031753)
			(xy 93.456065 -407.031754) (xy 93.448308 -407.085708) (xy 93.432951 -407.138009) (xy 93.410307 -407.187592)
			(xy 93.380837 -407.233448) (xy 93.345141 -407.274643) (xy 93.303946 -407.310338) (xy 93.25809 -407.339808)
			(xy 93.208507 -407.362451) (xy 93.156206 -407.377808) (xy 93.102252 -407.385565) (xy 93.074998 -407.386028)
			(xy 92.211398 -407.386028) (xy 92.184148 -407.385502) (xy 92.130204 -407.377745) (xy 92.077912 -407.362391)
			(xy 92.028338 -407.339751) (xy 91.98249 -407.310286) (xy 91.941302 -407.274596) (xy 91.905613 -407.233408)
			(xy 91.876148 -407.187561) (xy 91.853508 -407.137986) (xy 91.838154 -407.085694) (xy 91.830398 -407.03175)
			(xy 90.392865 -407.03175) (xy 90.392865 -407.031756) (xy 90.385107 -407.085714) (xy 90.369748 -407.138018)
			(xy 90.347101 -407.187603) (xy 90.317627 -407.233461) (xy 90.281927 -407.274657) (xy 90.240727 -407.310352)
			(xy 90.194866 -407.339821) (xy 90.145278 -407.362462) (xy 90.092973 -407.377815) (xy 90.039014 -407.385568)
			(xy 90.011758 -407.386028) (xy 89.148158 -407.386028) (xy 89.12091 -407.385499) (xy 89.06697 -407.377738)
			(xy 89.014683 -407.36238) (xy 88.965114 -407.339738) (xy 88.919271 -407.310272) (xy 88.878088 -407.274582)
			(xy 88.842403 -407.233395) (xy 88.812942 -407.187549) (xy 88.790305 -407.137978) (xy 88.774953 -407.085689)
			(xy 88.767198 -407.031748) (xy 87.329542 -407.031748) (xy 87.329542 -407.031752) (xy 87.321786 -407.085701)
			(xy 87.306431 -407.137997) (xy 87.28379 -407.187576) (xy 87.254324 -407.233427) (xy 87.218632 -407.274619)
			(xy 87.177442 -407.310313) (xy 87.131591 -407.339781) (xy 87.082014 -407.362424) (xy 87.029718 -407.377782)
			(xy 86.97577 -407.385541) (xy 86.948518 -407.386028) (xy 86.084918 -407.386028) (xy 86.057666 -407.385526)
			(xy 86.003716 -407.377771) (xy 85.951418 -407.362418) (xy 85.901839 -407.339778) (xy 85.855986 -407.310312)
			(xy 85.814793 -407.27462) (xy 85.779099 -407.233429) (xy 85.749631 -407.187577) (xy 85.726989 -407.137998)
			(xy 85.711632 -407.085702) (xy 85.703875 -407.031752) (xy 84.266365 -407.031752) (xy 84.266365 -407.031755)
			(xy 84.258607 -407.085711) (xy 84.243249 -407.138013) (xy 84.220604 -407.187598) (xy 84.191132 -407.233454)
			(xy 84.155434 -407.27465) (xy 84.114237 -407.310345) (xy 84.068378 -407.339814) (xy 84.018793 -407.362457)
			(xy 83.96649 -407.377812) (xy 83.912533 -407.385567) (xy 83.885278 -407.386028) (xy 83.021678 -407.386028)
			(xy 82.994429 -407.3855) (xy 82.940487 -407.377742) (xy 82.888197 -407.362385) (xy 82.838626 -407.339744)
			(xy 82.79278 -407.310279) (xy 82.751595 -407.274589) (xy 82.715908 -407.233402) (xy 82.686445 -407.187555)
			(xy 82.663807 -407.137982) (xy 82.648454 -407.085692) (xy 82.640698 -407.031749) (xy 81.203042 -407.031749)
			(xy 81.203042 -407.031751) (xy 81.195286 -407.085698) (xy 81.179932 -407.137993) (xy 81.157293 -407.18757)
			(xy 81.127828 -407.233421) (xy 81.092139 -407.274612) (xy 81.050951 -407.310306) (xy 81.005103 -407.339775)
			(xy 80.955528 -407.362419) (xy 80.903235 -407.377778) (xy 80.849289 -407.38554) (xy 80.822038 -407.386028)
			(xy 79.958438 -407.386028) (xy 79.931185 -407.385527) (xy 79.877233 -407.377775) (xy 79.824933 -407.362423)
			(xy 79.775351 -407.339784) (xy 79.729495 -407.310319) (xy 79.6883 -407.274627) (xy 79.652604 -407.233435)
			(xy 79.623134 -407.187583) (xy 79.60049 -407.138003) (xy 79.585133 -407.085705) (xy 79.577375 -407.031753)
			(xy 78.139865 -407.031753) (xy 78.139865 -407.031754) (xy 78.132108 -407.085708) (xy 78.116751 -407.138009)
			(xy 78.094107 -407.187592) (xy 78.064637 -407.233448) (xy 78.028941 -407.274643) (xy 77.987746 -407.310338)
			(xy 77.94189 -407.339808) (xy 77.892307 -407.362451) (xy 77.840006 -407.377808) (xy 77.786052 -407.385565)
			(xy 77.758798 -407.386028) (xy 76.895198 -407.386028) (xy 76.867948 -407.385502) (xy 76.814004 -407.377745)
			(xy 76.761712 -407.362391) (xy 76.712138 -407.339751) (xy 76.66629 -407.310286) (xy 76.625102 -407.274596)
			(xy 76.589413 -407.233408) (xy 76.559948 -407.187561) (xy 76.537308 -407.137986) (xy 76.521954 -407.085694)
			(xy 76.514198 -407.03175) (xy 75.076665 -407.03175) (xy 75.076665 -407.031756) (xy 75.068907 -407.085714)
			(xy 75.053548 -407.138018) (xy 75.030901 -407.187603) (xy 75.001427 -407.233461) (xy 74.965727 -407.274657)
			(xy 74.924527 -407.310352) (xy 74.878666 -407.339821) (xy 74.829078 -407.362462) (xy 74.776773 -407.377815)
			(xy 74.722814 -407.385568) (xy 74.695558 -407.386028) (xy 73.831958 -407.386028) (xy 73.80471 -407.385499)
			(xy 73.75077 -407.377738) (xy 73.698483 -407.36238) (xy 73.648914 -407.339738) (xy 73.603071 -407.310272)
			(xy 73.561888 -407.274582) (xy 73.526203 -407.233395) (xy 73.496742 -407.187549) (xy 73.474105 -407.137978)
			(xy 73.458753 -407.085689) (xy 73.450998 -407.031748) (xy 72.013342 -407.031748) (xy 72.013342 -407.031752)
			(xy 72.005586 -407.085701) (xy 71.990231 -407.137997) (xy 71.96759 -407.187576) (xy 71.938124 -407.233427)
			(xy 71.902432 -407.274619) (xy 71.861242 -407.310313) (xy 71.815391 -407.339781) (xy 71.765814 -407.362424)
			(xy 71.713518 -407.377782) (xy 71.65957 -407.385541) (xy 71.632318 -407.386028) (xy 70.768718 -407.386028)
			(xy 70.741466 -407.385526) (xy 70.687516 -407.377771) (xy 70.635218 -407.362418) (xy 70.585639 -407.339778)
			(xy 70.539786 -407.310312) (xy 70.498593 -407.27462) (xy 70.462899 -407.233429) (xy 70.433431 -407.187577)
			(xy 70.410789 -407.137998) (xy 70.395432 -407.085702) (xy 70.387675 -407.031752) (xy 68.950165 -407.031752)
			(xy 68.950165 -407.031755) (xy 68.942407 -407.085711) (xy 68.927049 -407.138013) (xy 68.904404 -407.187598)
			(xy 68.874932 -407.233454) (xy 68.839234 -407.27465) (xy 68.798037 -407.310345) (xy 68.752178 -407.339814)
			(xy 68.702593 -407.362457) (xy 68.65029 -407.377812) (xy 68.596333 -407.385567) (xy 68.569078 -407.386028)
			(xy 67.705478 -407.386028) (xy 67.678229 -407.3855) (xy 67.624287 -407.377742) (xy 67.571997 -407.362385)
			(xy 67.522426 -407.339744) (xy 67.47658 -407.310279) (xy 67.435395 -407.274589) (xy 67.399708 -407.233402)
			(xy 67.370245 -407.187555) (xy 67.347607 -407.137982) (xy 67.332254 -407.085692) (xy 67.324498 -407.031749)
			(xy 65.886842 -407.031749) (xy 65.886842 -407.031751) (xy 65.879086 -407.085698) (xy 65.863732 -407.137993)
			(xy 65.841093 -407.18757) (xy 65.811628 -407.233421) (xy 65.775939 -407.274612) (xy 65.734751 -407.310306)
			(xy 65.688903 -407.339775) (xy 65.639328 -407.362419) (xy 65.587035 -407.377778) (xy 65.533089 -407.38554)
			(xy 65.505838 -407.386028) (xy 64.642238 -407.386028) (xy 64.614985 -407.385527) (xy 64.561033 -407.377775)
			(xy 64.508733 -407.362423) (xy 64.459151 -407.339784) (xy 64.413295 -407.310319) (xy 64.3721 -407.274627)
			(xy 64.336404 -407.233435) (xy 64.306934 -407.187583) (xy 64.28429 -407.138003) (xy 64.268933 -407.085705)
			(xy 64.261175 -407.031753) (xy 62.823665 -407.031753) (xy 62.823665 -407.031754) (xy 62.815908 -407.085708)
			(xy 62.800551 -407.138009) (xy 62.777907 -407.187592) (xy 62.748437 -407.233448) (xy 62.712741 -407.274643)
			(xy 62.671546 -407.310338) (xy 62.62569 -407.339808) (xy 62.576107 -407.362451) (xy 62.523806 -407.377808)
			(xy 62.469852 -407.385565) (xy 62.442598 -407.386028) (xy 61.578998 -407.386028) (xy 61.551748 -407.385502)
			(xy 61.497804 -407.377745) (xy 61.445512 -407.362391) (xy 61.395938 -407.339751) (xy 61.35009 -407.310286)
			(xy 61.308902 -407.274596) (xy 61.273213 -407.233408) (xy 61.243748 -407.187561) (xy 61.221108 -407.137986)
			(xy 61.205754 -407.085694) (xy 61.197998 -407.03175) (xy 59.760465 -407.03175) (xy 59.760465 -407.031756)
			(xy 59.752707 -407.085714) (xy 59.737348 -407.138018) (xy 59.714701 -407.187603) (xy 59.685227 -407.233461)
			(xy 59.649527 -407.274657) (xy 59.608327 -407.310352) (xy 59.562466 -407.339821) (xy 59.512878 -407.362462)
			(xy 59.460573 -407.377815) (xy 59.406614 -407.385568) (xy 59.379358 -407.386028) (xy 58.515758 -407.386028)
			(xy 58.48851 -407.385499) (xy 58.43457 -407.377738) (xy 58.382283 -407.36238) (xy 58.332714 -407.339738)
			(xy 58.286871 -407.310272) (xy 58.245688 -407.274582) (xy 58.210003 -407.233395) (xy 58.180542 -407.187549)
			(xy 58.157905 -407.137978) (xy 58.142553 -407.085689) (xy 58.134798 -407.031748) (xy 56.697142 -407.031748)
			(xy 56.697142 -407.031752) (xy 56.689386 -407.085701) (xy 56.674031 -407.137997) (xy 56.65139 -407.187576)
			(xy 56.621924 -407.233427) (xy 56.586232 -407.274619) (xy 56.545042 -407.310313) (xy 56.499191 -407.339781)
			(xy 56.449614 -407.362424) (xy 56.397318 -407.377782) (xy 56.34337 -407.385541) (xy 56.316118 -407.386028)
			(xy 55.452518 -407.386028) (xy 55.425266 -407.385526) (xy 55.371316 -407.377771) (xy 55.319018 -407.362418)
			(xy 55.269439 -407.339778) (xy 55.223586 -407.310312) (xy 55.182393 -407.27462) (xy 55.146699 -407.233429)
			(xy 55.117231 -407.187577) (xy 55.094589 -407.137998) (xy 55.079232 -407.085702) (xy 55.071475 -407.031752)
			(xy 53.633965 -407.031752) (xy 53.633965 -407.031755) (xy 53.626207 -407.085711) (xy 53.610849 -407.138013)
			(xy 53.588204 -407.187598) (xy 53.558732 -407.233454) (xy 53.523034 -407.27465) (xy 53.481837 -407.310345)
			(xy 53.435978 -407.339814) (xy 53.386393 -407.362457) (xy 53.33409 -407.377812) (xy 53.280133 -407.385567)
			(xy 53.252878 -407.386028) (xy 52.389278 -407.386028) (xy 52.362029 -407.3855) (xy 52.308087 -407.377742)
			(xy 52.255797 -407.362385) (xy 52.206226 -407.339744) (xy 52.16038 -407.310279) (xy 52.119195 -407.274589)
			(xy 52.083508 -407.233402) (xy 52.054045 -407.187555) (xy 52.031407 -407.137982) (xy 52.016054 -407.085692)
			(xy 52.008298 -407.031749) (xy 50.570642 -407.031749) (xy 50.570642 -407.031751) (xy 50.562886 -407.085698)
			(xy 50.547532 -407.137993) (xy 50.524893 -407.18757) (xy 50.495428 -407.233421) (xy 50.459739 -407.274612)
			(xy 50.418551 -407.310306) (xy 50.372703 -407.339775) (xy 50.323128 -407.362419) (xy 50.270835 -407.377778)
			(xy 50.216889 -407.38554) (xy 50.189638 -407.386028) (xy 49.326038 -407.386028) (xy 49.298785 -407.385527)
			(xy 49.244833 -407.377775) (xy 49.192533 -407.362423) (xy 49.142951 -407.339784) (xy 49.097095 -407.310319)
			(xy 49.0559 -407.274627) (xy 49.020204 -407.233435) (xy 48.990734 -407.187583) (xy 48.96809 -407.138003)
			(xy 48.952733 -407.085705) (xy 48.944975 -407.031753) (xy 16.741648 -407.031753) (xy 16.741648 -407.035508)
			(xy 16.741162 -407.062759) (xy 16.733406 -407.116707) (xy 16.718051 -407.169002) (xy 16.695409 -407.218579)
			(xy 16.665943 -407.264429) (xy 16.630252 -407.30562) (xy 16.589061 -407.341311) (xy 16.543211 -407.370777)
			(xy 16.493634 -407.393419) (xy 16.441339 -407.408774) (xy 16.387391 -407.41653) (xy 16.332889 -407.41653)
			(xy 16.278941 -407.408774) (xy 16.226646 -407.393419) (xy 16.177069 -407.370777) (xy 16.131219 -407.341311)
			(xy 16.090028 -407.30562) (xy 16.054337 -407.264429) (xy 16.024871 -407.218579) (xy 16.002229 -407.169002)
			(xy 15.986874 -407.116707) (xy 15.979118 -407.062759) (xy 15.978632 -407.035508) (xy 5.555234 -407.035508)
			(xy 6.274054 -407.754328) (xy 6.323476 -407.804436) (xy 6.417282 -407.909377) (xy 6.505056 -408.019414)
			(xy 6.586523 -408.134198) (xy 6.661426 -408.25337) (xy 6.729529 -408.376554) (xy 6.790618 -408.503362)
			(xy 6.844501 -408.633397) (xy 6.891008 -408.766247) (xy 6.929993 -408.901497) (xy 6.961334 -409.03872)
			(xy 6.984932 -409.177484) (xy 7.000712 -409.317352) (xy 7.008625 -409.457886) (xy 7.00913 -409.528264)
			(xy 7.00913 -410.057457) (xy 48.944923 -410.057457) (xy 48.944923 -410.002943) (xy 48.952682 -409.948984)
			(xy 48.968041 -409.896679) (xy 48.990688 -409.847092) (xy 49.020162 -409.801233) (xy 49.055863 -409.760036)
			(xy 49.097064 -409.724339) (xy 49.142925 -409.69487) (xy 49.192515 -409.672228) (xy 49.244821 -409.656874)
			(xy 49.298781 -409.64912) (xy 49.326038 -409.64866) (xy 50.189638 -409.64866) (xy 50.216885 -409.649213)
			(xy 50.270824 -409.656973) (xy 50.32311 -409.67233) (xy 50.372678 -409.694972) (xy 50.41852 -409.724436)
			(xy 50.459702 -409.760125) (xy 50.495386 -409.801311) (xy 50.524847 -409.847155) (xy 50.547483 -409.896726)
			(xy 50.562835 -409.949013) (xy 50.57059 -410.002953) (xy 50.57059 -410.057447) (xy 50.570589 -410.057453)
			(xy 52.008246 -410.057453) (xy 52.008246 -410.002947) (xy 52.016002 -409.948997) (xy 52.031358 -409.8967)
			(xy 52.053999 -409.84712) (xy 52.083466 -409.801267) (xy 52.119158 -409.760074) (xy 52.160349 -409.724379)
			(xy 52.206201 -409.69491) (xy 52.255779 -409.672265) (xy 52.308076 -409.656907) (xy 52.362025 -409.649147)
			(xy 52.389278 -409.64866) (xy 53.252878 -409.64866) (xy 53.28013 -409.649186) (xy 53.334078 -409.65694)
			(xy 53.386374 -409.672292) (xy 53.435953 -409.694932) (xy 53.481805 -409.724397) (xy 53.522997 -409.760087)
			(xy 53.55869 -409.801277) (xy 53.588158 -409.847127) (xy 53.6108 -409.896705) (xy 53.626156 -409.949)
			(xy 53.633913 -410.002948) (xy 53.633913 -410.057452) (xy 53.633912 -410.057456) (xy 55.071423 -410.057456)
			(xy 55.071423 -410.002944) (xy 55.079181 -409.948987) (xy 55.094539 -409.896683) (xy 55.117185 -409.847098)
			(xy 55.146657 -409.80124) (xy 55.182356 -409.760043) (xy 55.223554 -409.724346) (xy 55.269413 -409.694876)
			(xy 55.319 -409.672233) (xy 55.371305 -409.656877) (xy 55.425262 -409.649122) (xy 55.452518 -409.64866)
			(xy 56.316118 -409.64866) (xy 56.343366 -409.649211) (xy 56.397307 -409.656969) (xy 56.449595 -409.672325)
			(xy 56.499166 -409.694965) (xy 56.54501 -409.724429) (xy 56.586195 -409.760118) (xy 56.621882 -409.801304)
			(xy 56.651344 -409.84715) (xy 56.673982 -409.896721) (xy 56.689334 -409.94901) (xy 56.69709 -410.002952)
			(xy 56.69709 -410.057448) (xy 56.697089 -410.057452) (xy 58.134746 -410.057452) (xy 58.134746 -410.002948)
			(xy 58.142502 -409.949) (xy 58.157856 -409.896704) (xy 58.180496 -409.847125) (xy 58.209961 -409.801273)
			(xy 58.245651 -409.760081) (xy 58.28684 -409.724386) (xy 58.332689 -409.694916) (xy 58.382265 -409.672271)
			(xy 58.434559 -409.656911) (xy 58.488506 -409.649149) (xy 58.515758 -409.64866) (xy 59.379358 -409.64866)
			(xy 59.406611 -409.649184) (xy 59.460561 -409.656936) (xy 59.51286 -409.672287) (xy 59.562441 -409.694925)
			(xy 59.608296 -409.72439) (xy 59.64949 -409.76008) (xy 59.685185 -409.801271) (xy 59.714655 -409.847122)
			(xy 59.737298 -409.896701) (xy 59.752655 -409.948997) (xy 59.760413 -410.002948) (xy 59.760413 -410.057452)
			(xy 59.760413 -410.057453) (xy 61.197946 -410.057453) (xy 61.197946 -410.002947) (xy 61.205703 -409.948994)
			(xy 61.221059 -409.896695) (xy 61.243702 -409.847114) (xy 61.273171 -409.80126) (xy 61.308865 -409.760066)
			(xy 61.350059 -409.724372) (xy 61.395913 -409.694903) (xy 61.445494 -409.67226) (xy 61.497793 -409.656903)
			(xy 61.551745 -409.649146) (xy 61.578998 -409.64866) (xy 62.442598 -409.64866) (xy 62.469849 -409.649187)
			(xy 62.523795 -409.656943) (xy 62.576089 -409.672298) (xy 62.625665 -409.694938) (xy 62.671515 -409.724404)
			(xy 62.712704 -409.760094) (xy 62.748395 -409.801284) (xy 62.777861 -409.847133) (xy 62.800502 -409.896709)
			(xy 62.815856 -409.949003) (xy 62.823613 -410.002949) (xy 62.823613 -410.057451) (xy 62.823612 -410.057457)
			(xy 64.261123 -410.057457) (xy 64.261123 -410.002943) (xy 64.268882 -409.948984) (xy 64.284241 -409.896679)
			(xy 64.306888 -409.847092) (xy 64.336362 -409.801233) (xy 64.372063 -409.760036) (xy 64.413264 -409.724339)
			(xy 64.459125 -409.69487) (xy 64.508715 -409.672228) (xy 64.561021 -409.656874) (xy 64.614981 -409.64912)
			(xy 64.642238 -409.64866) (xy 65.505838 -409.64866) (xy 65.533085 -409.649213) (xy 65.587024 -409.656973)
			(xy 65.63931 -409.67233) (xy 65.688878 -409.694972) (xy 65.73472 -409.724436) (xy 65.775902 -409.760125)
			(xy 65.811586 -409.801311) (xy 65.841047 -409.847155) (xy 65.863683 -409.896726) (xy 65.879035 -409.949013)
			(xy 65.88679 -410.002953) (xy 65.88679 -410.057447) (xy 65.886789 -410.057453) (xy 67.324446 -410.057453)
			(xy 67.324446 -410.002947) (xy 67.332202 -409.948997) (xy 67.347558 -409.8967) (xy 67.370199 -409.84712)
			(xy 67.399666 -409.801267) (xy 67.435358 -409.760074) (xy 67.476549 -409.724379) (xy 67.522401 -409.69491)
			(xy 67.571979 -409.672265) (xy 67.624276 -409.656907) (xy 67.678225 -409.649147) (xy 67.705478 -409.64866)
			(xy 68.569078 -409.64866) (xy 68.59633 -409.649186) (xy 68.650278 -409.65694) (xy 68.702574 -409.672292)
			(xy 68.752153 -409.694932) (xy 68.798005 -409.724397) (xy 68.839197 -409.760087) (xy 68.87489 -409.801277)
			(xy 68.904358 -409.847127) (xy 68.927 -409.896705) (xy 68.942356 -409.949) (xy 68.950113 -410.002948)
			(xy 68.950113 -410.057452) (xy 68.950112 -410.057456) (xy 70.387623 -410.057456) (xy 70.387623 -410.002944)
			(xy 70.395381 -409.948987) (xy 70.410739 -409.896683) (xy 70.433385 -409.847098) (xy 70.462857 -409.80124)
			(xy 70.498556 -409.760043) (xy 70.539754 -409.724346) (xy 70.585613 -409.694876) (xy 70.6352 -409.672233)
			(xy 70.687505 -409.656877) (xy 70.741462 -409.649122) (xy 70.768718 -409.64866) (xy 71.632318 -409.64866)
			(xy 71.659566 -409.649211) (xy 71.713507 -409.656969) (xy 71.765795 -409.672325) (xy 71.815366 -409.694965)
			(xy 71.86121 -409.724429) (xy 71.902395 -409.760118) (xy 71.938082 -409.801304) (xy 71.967544 -409.84715)
			(xy 71.990182 -409.896721) (xy 72.005534 -409.94901) (xy 72.01329 -410.002952) (xy 72.01329 -410.057448)
			(xy 72.013289 -410.057452) (xy 73.450946 -410.057452) (xy 73.450946 -410.002948) (xy 73.458702 -409.949)
			(xy 73.474056 -409.896704) (xy 73.496696 -409.847125) (xy 73.526161 -409.801273) (xy 73.561851 -409.760081)
			(xy 73.60304 -409.724386) (xy 73.648889 -409.694916) (xy 73.698465 -409.672271) (xy 73.750759 -409.656911)
			(xy 73.804706 -409.649149) (xy 73.831958 -409.64866) (xy 74.695558 -409.64866) (xy 74.722811 -409.649184)
			(xy 74.776761 -409.656936) (xy 74.82906 -409.672287) (xy 74.878641 -409.694925) (xy 74.924496 -409.72439)
			(xy 74.96569 -409.76008) (xy 75.001385 -409.801271) (xy 75.030855 -409.847122) (xy 75.053498 -409.896701)
			(xy 75.068855 -409.948997) (xy 75.076613 -410.002948) (xy 75.076613 -410.057452) (xy 75.076613 -410.057453)
			(xy 76.514146 -410.057453) (xy 76.514146 -410.002947) (xy 76.521903 -409.948994) (xy 76.537259 -409.896695)
			(xy 76.559902 -409.847114) (xy 76.589371 -409.80126) (xy 76.625065 -409.760066) (xy 76.666259 -409.724372)
			(xy 76.712113 -409.694903) (xy 76.761694 -409.67226) (xy 76.813993 -409.656903) (xy 76.867945 -409.649146)
			(xy 76.895198 -409.64866) (xy 77.758798 -409.64866) (xy 77.786049 -409.649187) (xy 77.839995 -409.656943)
			(xy 77.892289 -409.672298) (xy 77.941865 -409.694938) (xy 77.987715 -409.724404) (xy 78.028904 -409.760094)
			(xy 78.064595 -409.801284) (xy 78.094061 -409.847133) (xy 78.116702 -409.896709) (xy 78.132056 -409.949003)
			(xy 78.139813 -410.002949) (xy 78.139813 -410.057451) (xy 78.139812 -410.057457) (xy 79.577323 -410.057457)
			(xy 79.577323 -410.002943) (xy 79.585082 -409.948984) (xy 79.600441 -409.896679) (xy 79.623088 -409.847092)
			(xy 79.652562 -409.801233) (xy 79.688263 -409.760036) (xy 79.729464 -409.724339) (xy 79.775325 -409.69487)
			(xy 79.824915 -409.672228) (xy 79.877221 -409.656874) (xy 79.931181 -409.64912) (xy 79.958438 -409.64866)
			(xy 80.822038 -409.64866) (xy 80.849285 -409.649213) (xy 80.903224 -409.656973) (xy 80.95551 -409.67233)
			(xy 81.005078 -409.694972) (xy 81.05092 -409.724436) (xy 81.092102 -409.760125) (xy 81.127786 -409.801311)
			(xy 81.157247 -409.847155) (xy 81.179883 -409.896726) (xy 81.195235 -409.949013) (xy 81.20299 -410.002953)
			(xy 81.20299 -410.057447) (xy 81.202989 -410.057453) (xy 82.640646 -410.057453) (xy 82.640646 -410.002947)
			(xy 82.648402 -409.948997) (xy 82.663758 -409.8967) (xy 82.686399 -409.84712) (xy 82.715866 -409.801267)
			(xy 82.751558 -409.760074) (xy 82.792749 -409.724379) (xy 82.838601 -409.69491) (xy 82.888179 -409.672265)
			(xy 82.940476 -409.656907) (xy 82.994425 -409.649147) (xy 83.021678 -409.64866) (xy 83.885278 -409.64866)
			(xy 83.91253 -409.649186) (xy 83.966478 -409.65694) (xy 84.018774 -409.672292) (xy 84.068353 -409.694932)
			(xy 84.114205 -409.724397) (xy 84.155397 -409.760087) (xy 84.19109 -409.801277) (xy 84.220558 -409.847127)
			(xy 84.2432 -409.896705) (xy 84.258556 -409.949) (xy 84.266313 -410.002948) (xy 84.266313 -410.057452)
			(xy 84.266312 -410.057456) (xy 85.703823 -410.057456) (xy 85.703823 -410.002944) (xy 85.711581 -409.948987)
			(xy 85.726939 -409.896683) (xy 85.749585 -409.847098) (xy 85.779057 -409.80124) (xy 85.814756 -409.760043)
			(xy 85.855954 -409.724346) (xy 85.901813 -409.694876) (xy 85.9514 -409.672233) (xy 86.003705 -409.656877)
			(xy 86.057662 -409.649122) (xy 86.084918 -409.64866) (xy 86.948518 -409.64866) (xy 86.975766 -409.649211)
			(xy 87.029707 -409.656969) (xy 87.081995 -409.672325) (xy 87.131566 -409.694965) (xy 87.17741 -409.724429)
			(xy 87.218595 -409.760118) (xy 87.254282 -409.801304) (xy 87.283744 -409.84715) (xy 87.306382 -409.896721)
			(xy 87.321734 -409.94901) (xy 87.32949 -410.002952) (xy 87.32949 -410.057448) (xy 87.329489 -410.057452)
			(xy 88.767146 -410.057452) (xy 88.767146 -410.002948) (xy 88.774902 -409.949) (xy 88.790256 -409.896704)
			(xy 88.812896 -409.847125) (xy 88.842361 -409.801273) (xy 88.878051 -409.760081) (xy 88.91924 -409.724386)
			(xy 88.965089 -409.694916) (xy 89.014665 -409.672271) (xy 89.066959 -409.656911) (xy 89.120906 -409.649149)
			(xy 89.148158 -409.64866) (xy 90.011758 -409.64866) (xy 90.039011 -409.649184) (xy 90.092961 -409.656936)
			(xy 90.14526 -409.672287) (xy 90.194841 -409.694925) (xy 90.240696 -409.72439) (xy 90.28189 -409.76008)
			(xy 90.317585 -409.801271) (xy 90.347055 -409.847122) (xy 90.369698 -409.896701) (xy 90.385055 -409.948997)
			(xy 90.392813 -410.002948) (xy 90.392813 -410.057452) (xy 90.392813 -410.057453) (xy 91.830346 -410.057453)
			(xy 91.830346 -410.002947) (xy 91.838103 -409.948994) (xy 91.853459 -409.896695) (xy 91.876102 -409.847114)
			(xy 91.905571 -409.80126) (xy 91.941265 -409.760066) (xy 91.982459 -409.724372) (xy 92.028313 -409.694903)
			(xy 92.077894 -409.67226) (xy 92.130193 -409.656903) (xy 92.184145 -409.649146) (xy 92.211398 -409.64866)
			(xy 93.074998 -409.64866) (xy 93.102249 -409.649187) (xy 93.156195 -409.656943) (xy 93.208489 -409.672298)
			(xy 93.258065 -409.694938) (xy 93.303915 -409.724404) (xy 93.345104 -409.760094) (xy 93.380795 -409.801284)
			(xy 93.410261 -409.847133) (xy 93.432902 -409.896709) (xy 93.448256 -409.949003) (xy 93.456013 -410.002949)
			(xy 93.456013 -410.057451) (xy 93.456012 -410.057457) (xy 94.893523 -410.057457) (xy 94.893523 -410.002943)
			(xy 94.901282 -409.948984) (xy 94.916641 -409.896679) (xy 94.939288 -409.847092) (xy 94.968762 -409.801233)
			(xy 95.004463 -409.760036) (xy 95.045664 -409.724339) (xy 95.091525 -409.69487) (xy 95.141115 -409.672228)
			(xy 95.193421 -409.656874) (xy 95.247381 -409.64912) (xy 95.274638 -409.64866) (xy 96.138238 -409.64866)
			(xy 96.165485 -409.649213) (xy 96.219424 -409.656973) (xy 96.27171 -409.67233) (xy 96.321278 -409.694972)
			(xy 96.36712 -409.724436) (xy 96.408302 -409.760125) (xy 96.443986 -409.801311) (xy 96.473447 -409.847155)
			(xy 96.496083 -409.896726) (xy 96.511435 -409.949013) (xy 96.51919 -410.002953) (xy 96.51919 -410.057447)
			(xy 96.519189 -410.057451) (xy 121.120146 -410.057451) (xy 121.120146 -410.002949) (xy 121.127902 -409.949)
			(xy 121.143256 -409.896705) (xy 121.165895 -409.847127) (xy 121.19536 -409.801275) (xy 121.231049 -409.760082)
			(xy 121.272238 -409.724388) (xy 121.318086 -409.694918) (xy 121.367662 -409.672272) (xy 121.419955 -409.656911)
			(xy 121.473903 -409.649149) (xy 121.501154 -409.64866) (xy 122.364754 -409.64866) (xy 122.392007 -409.649184)
			(xy 122.445958 -409.656935) (xy 122.498257 -409.672286) (xy 122.547839 -409.694924) (xy 122.593694 -409.724388)
			(xy 122.634889 -409.760079) (xy 122.670584 -409.801269) (xy 122.700054 -409.847121) (xy 122.722698 -409.8967)
			(xy 122.738055 -409.948997) (xy 122.745813 -410.002947) (xy 122.745813 -410.057453) (xy 124.183346 -410.057453)
			(xy 124.183346 -410.002947) (xy 124.191103 -409.948995) (xy 124.206459 -409.896696) (xy 124.229102 -409.847115)
			(xy 124.25857 -409.801261) (xy 124.294264 -409.760068) (xy 124.335457 -409.724373) (xy 124.38131 -409.694904)
			(xy 124.430891 -409.672261) (xy 124.483189 -409.656904) (xy 124.537141 -409.649146) (xy 124.564394 -409.64866)
			(xy 125.427994 -409.64866) (xy 125.455245 -409.649187) (xy 125.509192 -409.656942) (xy 125.561486 -409.672297)
			(xy 125.611063 -409.694937) (xy 125.656913 -409.724402) (xy 125.698103 -409.760093) (xy 125.733794 -409.801282)
			(xy 125.76326 -409.847132) (xy 125.785901 -409.896708) (xy 125.801256 -409.949002) (xy 125.809013 -410.002949)
			(xy 125.809013 -410.057451) (xy 125.809012 -410.057457) (xy 127.246523 -410.057457) (xy 127.246523 -410.002943)
			(xy 127.254282 -409.948985) (xy 127.269641 -409.89668) (xy 127.292287 -409.847093) (xy 127.321761 -409.801235)
			(xy 127.357462 -409.760037) (xy 127.398662 -409.724341) (xy 127.444523 -409.694871) (xy 127.494112 -409.672229)
			(xy 127.546418 -409.656874) (xy 127.600377 -409.649121) (xy 127.627634 -409.64866) (xy 128.491234 -409.64866)
			(xy 128.518481 -409.649213) (xy 128.572421 -409.656972) (xy 128.624707 -409.672329) (xy 128.674276 -409.69497)
			(xy 128.720118 -409.724435) (xy 128.761301 -409.760123) (xy 128.796985 -409.801309) (xy 128.826446 -409.847154)
			(xy 128.849083 -409.896725) (xy 128.864435 -409.949012) (xy 128.87219 -410.002953) (xy 128.87219 -410.057447)
			(xy 128.872189 -410.057452) (xy 130.309846 -410.057452) (xy 130.309846 -410.002948) (xy 130.317602 -409.948998)
			(xy 130.332957 -409.896701) (xy 130.355599 -409.847121) (xy 130.385065 -409.801268) (xy 130.420757 -409.760075)
			(xy 130.461947 -409.72438) (xy 130.507798 -409.694911) (xy 130.557376 -409.672266) (xy 130.609672 -409.656908)
			(xy 130.663622 -409.649148) (xy 130.690874 -409.64866) (xy 131.554474 -409.64866) (xy 131.581726 -409.649185)
			(xy 131.635675 -409.656939) (xy 131.687972 -409.672291) (xy 131.737551 -409.69493) (xy 131.783403 -409.724395)
			(xy 131.824596 -409.760086) (xy 131.860289 -409.801276) (xy 131.889757 -409.847126) (xy 131.9124 -409.896704)
			(xy 131.927756 -409.949) (xy 131.935513 -410.002948) (xy 131.935513 -410.057452) (xy 131.935512 -410.057456)
			(xy 133.373023 -410.057456) (xy 133.373023 -410.002944) (xy 133.380781 -409.948987) (xy 133.396139 -409.896684)
			(xy 133.418784 -409.847099) (xy 133.448256 -409.801241) (xy 133.483954 -409.760045) (xy 133.525152 -409.724348)
			(xy 133.571011 -409.694878) (xy 133.620597 -409.672234) (xy 133.672901 -409.656878) (xy 133.726858 -409.649122)
			(xy 133.754114 -409.64866) (xy 134.617714 -409.64866) (xy 134.644962 -409.649211) (xy 134.698904 -409.656969)
			(xy 134.751193 -409.672324) (xy 134.800764 -409.694964) (xy 134.846609 -409.724428) (xy 134.887794 -409.760116)
			(xy 134.923481 -409.801303) (xy 134.952943 -409.847149) (xy 134.975581 -409.896721) (xy 134.990934 -409.94901)
			(xy 134.99869 -410.002952) (xy 134.99869 -410.057448) (xy 134.99869 -410.057451) (xy 136.436346 -410.057451)
			(xy 136.436346 -410.002949) (xy 136.444102 -409.949) (xy 136.459456 -409.896705) (xy 136.482095 -409.847127)
			(xy 136.51156 -409.801275) (xy 136.547249 -409.760082) (xy 136.588438 -409.724388) (xy 136.634286 -409.694918)
			(xy 136.683862 -409.672272) (xy 136.736155 -409.656911) (xy 136.790103 -409.649149) (xy 136.817354 -409.64866)
			(xy 137.680954 -409.64866) (xy 137.708207 -409.649184) (xy 137.762158 -409.656935) (xy 137.814457 -409.672286)
			(xy 137.864039 -409.694924) (xy 137.909894 -409.724388) (xy 137.951089 -409.760079) (xy 137.986784 -409.801269)
			(xy 138.016254 -409.847121) (xy 138.038898 -409.8967) (xy 138.054255 -409.948997) (xy 138.062013 -410.002947)
			(xy 138.062013 -410.057453) (xy 139.499546 -410.057453) (xy 139.499546 -410.002947) (xy 139.507303 -409.948995)
			(xy 139.522659 -409.896696) (xy 139.545302 -409.847115) (xy 139.57477 -409.801261) (xy 139.610464 -409.760068)
			(xy 139.651657 -409.724373) (xy 139.69751 -409.694904) (xy 139.747091 -409.672261) (xy 139.799389 -409.656904)
			(xy 139.853341 -409.649146) (xy 139.880594 -409.64866) (xy 140.744194 -409.64866) (xy 140.771445 -409.649187)
			(xy 140.825392 -409.656942) (xy 140.877686 -409.672297) (xy 140.927263 -409.694937) (xy 140.973113 -409.724402)
			(xy 141.014303 -409.760093) (xy 141.049994 -409.801282) (xy 141.07946 -409.847132) (xy 141.102101 -409.896708)
			(xy 141.117456 -409.949002) (xy 141.125213 -410.002949) (xy 141.125213 -410.057451) (xy 141.125212 -410.057457)
			(xy 142.562723 -410.057457) (xy 142.562723 -410.002943) (xy 142.570482 -409.948985) (xy 142.585841 -409.89668)
			(xy 142.608487 -409.847093) (xy 142.637961 -409.801235) (xy 142.673662 -409.760037) (xy 142.714862 -409.724341)
			(xy 142.760723 -409.694871) (xy 142.810312 -409.672229) (xy 142.862618 -409.656874) (xy 142.916577 -409.649121)
			(xy 142.943834 -409.64866) (xy 143.807434 -409.64866) (xy 143.834681 -409.649213) (xy 143.888621 -409.656972)
			(xy 143.940907 -409.672329) (xy 143.990476 -409.69497) (xy 144.036318 -409.724435) (xy 144.077501 -409.760123)
			(xy 144.113185 -409.801309) (xy 144.142646 -409.847154) (xy 144.165283 -409.896725) (xy 144.180635 -409.949012)
			(xy 144.18839 -410.002953) (xy 144.18839 -410.057447) (xy 144.188389 -410.057452) (xy 145.626046 -410.057452)
			(xy 145.626046 -410.002948) (xy 145.633802 -409.948998) (xy 145.649157 -409.896701) (xy 145.671799 -409.847121)
			(xy 145.701265 -409.801268) (xy 145.736957 -409.760075) (xy 145.778147 -409.72438) (xy 145.823998 -409.694911)
			(xy 145.873576 -409.672266) (xy 145.925872 -409.656908) (xy 145.979822 -409.649148) (xy 146.007074 -409.64866)
			(xy 146.870674 -409.64866) (xy 146.897926 -409.649185) (xy 146.951875 -409.656939) (xy 147.004172 -409.672291)
			(xy 147.053751 -409.69493) (xy 147.099603 -409.724395) (xy 147.140796 -409.760086) (xy 147.176489 -409.801276)
			(xy 147.205957 -409.847126) (xy 147.2286 -409.896704) (xy 147.243956 -409.949) (xy 147.251713 -410.002948)
			(xy 147.251713 -410.057452) (xy 147.251712 -410.057456) (xy 148.689223 -410.057456) (xy 148.689223 -410.002944)
			(xy 148.696981 -409.948987) (xy 148.712339 -409.896684) (xy 148.734984 -409.847099) (xy 148.764456 -409.801241)
			(xy 148.800154 -409.760045) (xy 148.841352 -409.724348) (xy 148.887211 -409.694878) (xy 148.936797 -409.672234)
			(xy 148.989101 -409.656878) (xy 149.043058 -409.649122) (xy 149.070314 -409.64866) (xy 149.933914 -409.64866)
			(xy 149.961162 -409.649211) (xy 150.015104 -409.656969) (xy 150.067393 -409.672324) (xy 150.116964 -409.694964)
			(xy 150.162809 -409.724428) (xy 150.203994 -409.760116) (xy 150.239681 -409.801303) (xy 150.269143 -409.847149)
			(xy 150.291781 -409.896721) (xy 150.307134 -409.94901) (xy 150.31489 -410.002952) (xy 150.31489 -410.057448)
			(xy 150.31489 -410.057451) (xy 151.752546 -410.057451) (xy 151.752546 -410.002949) (xy 151.760302 -409.949)
			(xy 151.775656 -409.896705) (xy 151.798295 -409.847127) (xy 151.82776 -409.801275) (xy 151.863449 -409.760082)
			(xy 151.904638 -409.724388) (xy 151.950486 -409.694918) (xy 152.000062 -409.672272) (xy 152.052355 -409.656911)
			(xy 152.106303 -409.649149) (xy 152.133554 -409.64866) (xy 152.997154 -409.64866) (xy 153.024407 -409.649184)
			(xy 153.078358 -409.656935) (xy 153.130657 -409.672286) (xy 153.180239 -409.694924) (xy 153.226094 -409.724388)
			(xy 153.267289 -409.760079) (xy 153.302984 -409.801269) (xy 153.332454 -409.847121) (xy 153.355098 -409.8967)
			(xy 153.370455 -409.948997) (xy 153.378213 -410.002947) (xy 153.378213 -410.057453) (xy 154.815746 -410.057453)
			(xy 154.815746 -410.002947) (xy 154.823503 -409.948995) (xy 154.838859 -409.896696) (xy 154.861502 -409.847115)
			(xy 154.89097 -409.801261) (xy 154.926664 -409.760068) (xy 154.967857 -409.724373) (xy 155.01371 -409.694904)
			(xy 155.063291 -409.672261) (xy 155.115589 -409.656904) (xy 155.169541 -409.649146) (xy 155.196794 -409.64866)
			(xy 156.060394 -409.64866) (xy 156.087645 -409.649187) (xy 156.141592 -409.656942) (xy 156.193886 -409.672297)
			(xy 156.243463 -409.694937) (xy 156.289313 -409.724402) (xy 156.330503 -409.760093) (xy 156.366194 -409.801282)
			(xy 156.39566 -409.847132) (xy 156.418301 -409.896708) (xy 156.433656 -409.949002) (xy 156.441413 -410.002949)
			(xy 156.441413 -410.057451) (xy 156.441412 -410.057457) (xy 157.878923 -410.057457) (xy 157.878923 -410.002943)
			(xy 157.886682 -409.948985) (xy 157.902041 -409.89668) (xy 157.924687 -409.847093) (xy 157.954161 -409.801235)
			(xy 157.989862 -409.760037) (xy 158.031062 -409.724341) (xy 158.076923 -409.694871) (xy 158.126512 -409.672229)
			(xy 158.178818 -409.656874) (xy 158.232777 -409.649121) (xy 158.260034 -409.64866) (xy 159.123634 -409.64866)
			(xy 159.150881 -409.649213) (xy 159.204821 -409.656972) (xy 159.257107 -409.672329) (xy 159.306676 -409.69497)
			(xy 159.352518 -409.724435) (xy 159.393701 -409.760123) (xy 159.429385 -409.801309) (xy 159.458846 -409.847154)
			(xy 159.481483 -409.896725) (xy 159.496835 -409.949012) (xy 159.50459 -410.002953) (xy 159.50459 -410.057447)
			(xy 159.504589 -410.057452) (xy 160.942246 -410.057452) (xy 160.942246 -410.002948) (xy 160.950002 -409.948998)
			(xy 160.965357 -409.896701) (xy 160.987999 -409.847121) (xy 161.017465 -409.801268) (xy 161.053157 -409.760075)
			(xy 161.094347 -409.72438) (xy 161.140198 -409.694911) (xy 161.189776 -409.672266) (xy 161.242072 -409.656908)
			(xy 161.296022 -409.649148) (xy 161.323274 -409.64866) (xy 162.186874 -409.64866) (xy 162.214126 -409.649185)
			(xy 162.268075 -409.656939) (xy 162.320372 -409.672291) (xy 162.369951 -409.69493) (xy 162.415803 -409.724395)
			(xy 162.456996 -409.760086) (xy 162.492689 -409.801276) (xy 162.522157 -409.847126) (xy 162.5448 -409.896704)
			(xy 162.560156 -409.949) (xy 162.567913 -410.002948) (xy 162.567913 -410.057452) (xy 162.567912 -410.057456)
			(xy 164.005423 -410.057456) (xy 164.005423 -410.002944) (xy 164.013181 -409.948987) (xy 164.028539 -409.896684)
			(xy 164.051184 -409.847099) (xy 164.080656 -409.801241) (xy 164.116354 -409.760045) (xy 164.157552 -409.724348)
			(xy 164.203411 -409.694878) (xy 164.252997 -409.672234) (xy 164.305301 -409.656878) (xy 164.359258 -409.649122)
			(xy 164.386514 -409.64866) (xy 165.250114 -409.64866) (xy 165.277362 -409.649211) (xy 165.331304 -409.656969)
			(xy 165.383593 -409.672324) (xy 165.433164 -409.694964) (xy 165.479009 -409.724428) (xy 165.520194 -409.760116)
			(xy 165.555881 -409.801303) (xy 165.585343 -409.847149) (xy 165.607981 -409.896721) (xy 165.623334 -409.94901)
			(xy 165.63109 -410.002952) (xy 165.63109 -410.057448) (xy 165.63109 -410.057451) (xy 167.068746 -410.057451)
			(xy 167.068746 -410.002949) (xy 167.076502 -409.949) (xy 167.091856 -409.896705) (xy 167.114495 -409.847127)
			(xy 167.14396 -409.801275) (xy 167.179649 -409.760082) (xy 167.220838 -409.724388) (xy 167.266686 -409.694918)
			(xy 167.316262 -409.672272) (xy 167.368555 -409.656911) (xy 167.422503 -409.649149) (xy 167.449754 -409.64866)
			(xy 168.313354 -409.64866) (xy 168.340607 -409.649184) (xy 168.394558 -409.656935) (xy 168.446857 -409.672286)
			(xy 168.496439 -409.694924) (xy 168.542294 -409.724388) (xy 168.583489 -409.760079) (xy 168.619184 -409.801269)
			(xy 168.648654 -409.847121) (xy 168.671298 -409.8967) (xy 168.686655 -409.948997) (xy 168.694413 -410.002947)
			(xy 168.694413 -410.057453) (xy 168.686655 -410.111403) (xy 168.671298 -410.1637) (xy 168.648654 -410.213279)
			(xy 168.619184 -410.259131) (xy 168.583489 -410.300321) (xy 168.542294 -410.336012) (xy 168.496439 -410.365476)
			(xy 168.446857 -410.388114) (xy 168.394558 -410.403465) (xy 168.340607 -410.411216) (xy 168.313354 -410.411676)
			(xy 167.449754 -410.411676) (xy 167.422503 -410.411251) (xy 167.368555 -410.403489) (xy 167.316262 -410.388128)
			(xy 167.266686 -410.365482) (xy 167.220838 -410.336012) (xy 167.179649 -410.300318) (xy 167.14396 -410.259125)
			(xy 167.114495 -410.213273) (xy 167.091856 -410.163695) (xy 167.076502 -410.1114) (xy 167.068746 -410.057451)
			(xy 165.63109 -410.057451) (xy 165.623334 -410.11139) (xy 165.607981 -410.163679) (xy 165.585343 -410.213251)
			(xy 165.555881 -410.259097) (xy 165.520194 -410.300284) (xy 165.479009 -410.335972) (xy 165.433164 -410.365436)
			(xy 165.383593 -410.388076) (xy 165.331304 -410.403431) (xy 165.277362 -410.411189) (xy 165.250114 -410.411676)
			(xy 164.386514 -410.411676) (xy 164.359258 -410.411278) (xy 164.305301 -410.403522) (xy 164.252997 -410.388166)
			(xy 164.203411 -410.365522) (xy 164.157552 -410.336052) (xy 164.116354 -410.300355) (xy 164.080656 -410.259159)
			(xy 164.051184 -410.213301) (xy 164.028539 -410.163716) (xy 164.013181 -410.111413) (xy 164.005423 -410.057456)
			(xy 162.567912 -410.057456) (xy 162.560156 -410.1114) (xy 162.5448 -410.163696) (xy 162.522157 -410.213274)
			(xy 162.492689 -410.259124) (xy 162.456996 -410.300314) (xy 162.415803 -410.336005) (xy 162.369951 -410.36547)
			(xy 162.320372 -410.388109) (xy 162.268075 -410.403461) (xy 162.214126 -410.411215) (xy 162.186874 -410.411676)
			(xy 161.323274 -410.411676) (xy 161.296022 -410.411252) (xy 161.242072 -410.403492) (xy 161.189776 -410.388134)
			(xy 161.140198 -410.365489) (xy 161.094347 -410.33602) (xy 161.053157 -410.300325) (xy 161.017465 -410.259132)
			(xy 160.987999 -410.213279) (xy 160.965357 -410.163699) (xy 160.950002 -410.111402) (xy 160.942246 -410.057452)
			(xy 159.504589 -410.057452) (xy 159.496835 -410.111388) (xy 159.481483 -410.163675) (xy 159.458846 -410.213246)
			(xy 159.429385 -410.259091) (xy 159.393701 -410.300277) (xy 159.352518 -410.335965) (xy 159.306676 -410.36543)
			(xy 159.257107 -410.388071) (xy 159.204821 -410.403428) (xy 159.150881 -410.411187) (xy 159.123634 -410.411676)
			(xy 158.260034 -410.411676) (xy 158.232777 -410.411279) (xy 158.178818 -410.403526) (xy 158.126512 -410.388171)
			(xy 158.076923 -410.365529) (xy 158.031062 -410.336059) (xy 157.989862 -410.300363) (xy 157.954161 -410.259165)
			(xy 157.924687 -410.213307) (xy 157.902041 -410.16372) (xy 157.886682 -410.111415) (xy 157.878923 -410.057457)
			(xy 156.441412 -410.057457) (xy 156.433656 -410.111398) (xy 156.418301 -410.163692) (xy 156.39566 -410.213268)
			(xy 156.366194 -410.259118) (xy 156.330503 -410.300307) (xy 156.289313 -410.335998) (xy 156.243463 -410.365463)
			(xy 156.193886 -410.388103) (xy 156.141592 -410.403458) (xy 156.087645 -410.411213) (xy 156.060394 -410.411676)
			(xy 155.196794 -410.411676) (xy 155.169541 -410.411254) (xy 155.115589 -410.403496) (xy 155.063291 -410.388139)
			(xy 155.01371 -410.365496) (xy 154.967857 -410.336027) (xy 154.926664 -410.300332) (xy 154.89097 -410.259139)
			(xy 154.861502 -410.213285) (xy 154.838859 -410.163704) (xy 154.823503 -410.111405) (xy 154.815746 -410.057453)
			(xy 153.378213 -410.057453) (xy 153.370455 -410.111403) (xy 153.355098 -410.1637) (xy 153.332454 -410.213279)
			(xy 153.302984 -410.259131) (xy 153.267289 -410.300321) (xy 153.226094 -410.336012) (xy 153.180239 -410.365476)
			(xy 153.130657 -410.388114) (xy 153.078358 -410.403465) (xy 153.024407 -410.411216) (xy 152.997154 -410.411676)
			(xy 152.133554 -410.411676) (xy 152.106303 -410.411251) (xy 152.052355 -410.403489) (xy 152.000062 -410.388128)
			(xy 151.950486 -410.365482) (xy 151.904638 -410.336012) (xy 151.863449 -410.300318) (xy 151.82776 -410.259125)
			(xy 151.798295 -410.213273) (xy 151.775656 -410.163695) (xy 151.760302 -410.1114) (xy 151.752546 -410.057451)
			(xy 150.31489 -410.057451) (xy 150.307134 -410.11139) (xy 150.291781 -410.163679) (xy 150.269143 -410.213251)
			(xy 150.239681 -410.259097) (xy 150.203994 -410.300284) (xy 150.162809 -410.335972) (xy 150.116964 -410.365436)
			(xy 150.067393 -410.388076) (xy 150.015104 -410.403431) (xy 149.961162 -410.411189) (xy 149.933914 -410.411676)
			(xy 149.070314 -410.411676) (xy 149.043058 -410.411278) (xy 148.989101 -410.403522) (xy 148.936797 -410.388166)
			(xy 148.887211 -410.365522) (xy 148.841352 -410.336052) (xy 148.800154 -410.300355) (xy 148.764456 -410.259159)
			(xy 148.734984 -410.213301) (xy 148.712339 -410.163716) (xy 148.696981 -410.111413) (xy 148.689223 -410.057456)
			(xy 147.251712 -410.057456) (xy 147.243956 -410.1114) (xy 147.2286 -410.163696) (xy 147.205957 -410.213274)
			(xy 147.176489 -410.259124) (xy 147.140796 -410.300314) (xy 147.099603 -410.336005) (xy 147.053751 -410.36547)
			(xy 147.004172 -410.388109) (xy 146.951875 -410.403461) (xy 146.897926 -410.411215) (xy 146.870674 -410.411676)
			(xy 146.007074 -410.411676) (xy 145.979822 -410.411252) (xy 145.925872 -410.403492) (xy 145.873576 -410.388134)
			(xy 145.823998 -410.365489) (xy 145.778147 -410.33602) (xy 145.736957 -410.300325) (xy 145.701265 -410.259132)
			(xy 145.671799 -410.213279) (xy 145.649157 -410.163699) (xy 145.633802 -410.111402) (xy 145.626046 -410.057452)
			(xy 144.188389 -410.057452) (xy 144.180635 -410.111388) (xy 144.165283 -410.163675) (xy 144.142646 -410.213246)
			(xy 144.113185 -410.259091) (xy 144.077501 -410.300277) (xy 144.036318 -410.335965) (xy 143.990476 -410.36543)
			(xy 143.940907 -410.388071) (xy 143.888621 -410.403428) (xy 143.834681 -410.411187) (xy 143.807434 -410.411676)
			(xy 142.943834 -410.411676) (xy 142.916577 -410.411279) (xy 142.862618 -410.403526) (xy 142.810312 -410.388171)
			(xy 142.760723 -410.365529) (xy 142.714862 -410.336059) (xy 142.673662 -410.300363) (xy 142.637961 -410.259165)
			(xy 142.608487 -410.213307) (xy 142.585841 -410.16372) (xy 142.570482 -410.111415) (xy 142.562723 -410.057457)
			(xy 141.125212 -410.057457) (xy 141.117456 -410.111398) (xy 141.102101 -410.163692) (xy 141.07946 -410.213268)
			(xy 141.049994 -410.259118) (xy 141.014303 -410.300307) (xy 140.973113 -410.335998) (xy 140.927263 -410.365463)
			(xy 140.877686 -410.388103) (xy 140.825392 -410.403458) (xy 140.771445 -410.411213) (xy 140.744194 -410.411676)
			(xy 139.880594 -410.411676) (xy 139.853341 -410.411254) (xy 139.799389 -410.403496) (xy 139.747091 -410.388139)
			(xy 139.69751 -410.365496) (xy 139.651657 -410.336027) (xy 139.610464 -410.300332) (xy 139.57477 -410.259139)
			(xy 139.545302 -410.213285) (xy 139.522659 -410.163704) (xy 139.507303 -410.111405) (xy 139.499546 -410.057453)
			(xy 138.062013 -410.057453) (xy 138.054255 -410.111403) (xy 138.038898 -410.1637) (xy 138.016254 -410.213279)
			(xy 137.986784 -410.259131) (xy 137.951089 -410.300321) (xy 137.909894 -410.336012) (xy 137.864039 -410.365476)
			(xy 137.814457 -410.388114) (xy 137.762158 -410.403465) (xy 137.708207 -410.411216) (xy 137.680954 -410.411676)
			(xy 136.817354 -410.411676) (xy 136.790103 -410.411251) (xy 136.736155 -410.403489) (xy 136.683862 -410.388128)
			(xy 136.634286 -410.365482) (xy 136.588438 -410.336012) (xy 136.547249 -410.300318) (xy 136.51156 -410.259125)
			(xy 136.482095 -410.213273) (xy 136.459456 -410.163695) (xy 136.444102 -410.1114) (xy 136.436346 -410.057451)
			(xy 134.99869 -410.057451) (xy 134.990934 -410.11139) (xy 134.975581 -410.163679) (xy 134.952943 -410.213251)
			(xy 134.923481 -410.259097) (xy 134.887794 -410.300284) (xy 134.846609 -410.335972) (xy 134.800764 -410.365436)
			(xy 134.751193 -410.388076) (xy 134.698904 -410.403431) (xy 134.644962 -410.411189) (xy 134.617714 -410.411676)
			(xy 133.754114 -410.411676) (xy 133.726858 -410.411278) (xy 133.672901 -410.403522) (xy 133.620597 -410.388166)
			(xy 133.571011 -410.365522) (xy 133.525152 -410.336052) (xy 133.483954 -410.300355) (xy 133.448256 -410.259159)
			(xy 133.418784 -410.213301) (xy 133.396139 -410.163716) (xy 133.380781 -410.111413) (xy 133.373023 -410.057456)
			(xy 131.935512 -410.057456) (xy 131.927756 -410.1114) (xy 131.9124 -410.163696) (xy 131.889757 -410.213274)
			(xy 131.860289 -410.259124) (xy 131.824596 -410.300314) (xy 131.783403 -410.336005) (xy 131.737551 -410.36547)
			(xy 131.687972 -410.388109) (xy 131.635675 -410.403461) (xy 131.581726 -410.411215) (xy 131.554474 -410.411676)
			(xy 130.690874 -410.411676) (xy 130.663622 -410.411252) (xy 130.609672 -410.403492) (xy 130.557376 -410.388134)
			(xy 130.507798 -410.365489) (xy 130.461947 -410.33602) (xy 130.420757 -410.300325) (xy 130.385065 -410.259132)
			(xy 130.355599 -410.213279) (xy 130.332957 -410.163699) (xy 130.317602 -410.111402) (xy 130.309846 -410.057452)
			(xy 128.872189 -410.057452) (xy 128.864435 -410.111388) (xy 128.849083 -410.163675) (xy 128.826446 -410.213246)
			(xy 128.796985 -410.259091) (xy 128.761301 -410.300277) (xy 128.720118 -410.335965) (xy 128.674276 -410.36543)
			(xy 128.624707 -410.388071) (xy 128.572421 -410.403428) (xy 128.518481 -410.411187) (xy 128.491234 -410.411676)
			(xy 127.627634 -410.411676) (xy 127.600377 -410.411279) (xy 127.546418 -410.403526) (xy 127.494112 -410.388171)
			(xy 127.444523 -410.365529) (xy 127.398662 -410.336059) (xy 127.357462 -410.300363) (xy 127.321761 -410.259165)
			(xy 127.292287 -410.213307) (xy 127.269641 -410.16372) (xy 127.254282 -410.111415) (xy 127.246523 -410.057457)
			(xy 125.809012 -410.057457) (xy 125.801256 -410.111398) (xy 125.785901 -410.163692) (xy 125.76326 -410.213268)
			(xy 125.733794 -410.259118) (xy 125.698103 -410.300307) (xy 125.656913 -410.335998) (xy 125.611063 -410.365463)
			(xy 125.561486 -410.388103) (xy 125.509192 -410.403458) (xy 125.455245 -410.411213) (xy 125.427994 -410.411676)
			(xy 124.564394 -410.411676) (xy 124.537141 -410.411254) (xy 124.483189 -410.403496) (xy 124.430891 -410.388139)
			(xy 124.38131 -410.365496) (xy 124.335457 -410.336027) (xy 124.294264 -410.300332) (xy 124.25857 -410.259139)
			(xy 124.229102 -410.213285) (xy 124.206459 -410.163704) (xy 124.191103 -410.111405) (xy 124.183346 -410.057453)
			(xy 122.745813 -410.057453) (xy 122.738055 -410.111403) (xy 122.722698 -410.1637) (xy 122.700054 -410.213279)
			(xy 122.670584 -410.259131) (xy 122.634889 -410.300321) (xy 122.593694 -410.336012) (xy 122.547839 -410.365476)
			(xy 122.498257 -410.388114) (xy 122.445958 -410.403465) (xy 122.392007 -410.411216) (xy 122.364754 -410.411676)
			(xy 121.501154 -410.411676) (xy 121.473903 -410.411251) (xy 121.419955 -410.403489) (xy 121.367662 -410.388128)
			(xy 121.318086 -410.365482) (xy 121.272238 -410.336012) (xy 121.231049 -410.300318) (xy 121.19536 -410.259125)
			(xy 121.165895 -410.213273) (xy 121.143256 -410.163695) (xy 121.127902 -410.1114) (xy 121.120146 -410.057451)
			(xy 96.519189 -410.057451) (xy 96.511435 -410.111387) (xy 96.496083 -410.163674) (xy 96.473447 -410.213245)
			(xy 96.443986 -410.259089) (xy 96.408302 -410.300275) (xy 96.36712 -410.335964) (xy 96.321278 -410.365428)
			(xy 96.27171 -410.38807) (xy 96.219424 -410.403427) (xy 96.165485 -410.411187) (xy 96.138238 -410.411676)
			(xy 95.274638 -410.411676) (xy 95.247381 -410.41128) (xy 95.193421 -410.403526) (xy 95.141115 -410.388172)
			(xy 95.091525 -410.36553) (xy 95.045664 -410.336061) (xy 95.004463 -410.300364) (xy 94.968762 -410.259167)
			(xy 94.939288 -410.213308) (xy 94.916641 -410.163721) (xy 94.901282 -410.111416) (xy 94.893523 -410.057457)
			(xy 93.456012 -410.057457) (xy 93.448256 -410.111397) (xy 93.432902 -410.163691) (xy 93.410261 -410.213267)
			(xy 93.380795 -410.259116) (xy 93.345104 -410.300306) (xy 93.303915 -410.335996) (xy 93.258065 -410.365462)
			(xy 93.208489 -410.388102) (xy 93.156195 -410.403457) (xy 93.102249 -410.411213) (xy 93.074998 -410.411676)
			(xy 92.211398 -410.411676) (xy 92.184145 -410.411254) (xy 92.130193 -410.403497) (xy 92.077894 -410.38814)
			(xy 92.028313 -410.365497) (xy 91.982459 -410.336028) (xy 91.941265 -410.300334) (xy 91.905571 -410.25914)
			(xy 91.876102 -410.213286) (xy 91.853459 -410.163705) (xy 91.838103 -410.111406) (xy 91.830346 -410.057453)
			(xy 90.392813 -410.057453) (xy 90.385055 -410.111403) (xy 90.369698 -410.163699) (xy 90.347055 -410.213278)
			(xy 90.317585 -410.259129) (xy 90.28189 -410.30032) (xy 90.240696 -410.33601) (xy 90.194841 -410.365475)
			(xy 90.14526 -410.388113) (xy 90.092961 -410.403464) (xy 90.039011 -410.411216) (xy 90.011758 -410.411676)
			(xy 89.148158 -410.411676) (xy 89.120906 -410.411251) (xy 89.066959 -410.403489) (xy 89.014665 -410.388129)
			(xy 88.965089 -410.365484) (xy 88.91924 -410.336014) (xy 88.878051 -410.300319) (xy 88.842361 -410.259127)
			(xy 88.812896 -410.213275) (xy 88.790256 -410.163696) (xy 88.774902 -410.1114) (xy 88.767146 -410.057452)
			(xy 87.329489 -410.057452) (xy 87.321734 -410.11139) (xy 87.306382 -410.163679) (xy 87.283744 -410.21325)
			(xy 87.254282 -410.259096) (xy 87.218595 -410.300282) (xy 87.17741 -410.335971) (xy 87.131566 -410.365435)
			(xy 87.081995 -410.388075) (xy 87.029707 -410.403431) (xy 86.975766 -410.411189) (xy 86.948518 -410.411676)
			(xy 86.084918 -410.411676) (xy 86.057662 -410.411278) (xy 86.003705 -410.403523) (xy 85.9514 -410.388167)
			(xy 85.901813 -410.365524) (xy 85.855954 -410.336054) (xy 85.814756 -410.300357) (xy 85.779057 -410.25916)
			(xy 85.749585 -410.213302) (xy 85.726939 -410.163717) (xy 85.711581 -410.111413) (xy 85.703823 -410.057456)
			(xy 84.266312 -410.057456) (xy 84.258556 -410.1114) (xy 84.2432 -410.163695) (xy 84.220558 -410.213273)
			(xy 84.19109 -410.259123) (xy 84.155397 -410.300313) (xy 84.114205 -410.336003) (xy 84.068353 -410.365468)
			(xy 84.018774 -410.388108) (xy 83.966478 -410.40346) (xy 83.91253 -410.411214) (xy 83.885278 -410.411676)
			(xy 83.021678 -410.411676) (xy 82.994425 -410.411253) (xy 82.940476 -410.403493) (xy 82.888179 -410.388135)
			(xy 82.838601 -410.36549) (xy 82.792749 -410.336021) (xy 82.751558 -410.300326) (xy 82.715866 -410.259133)
			(xy 82.686399 -410.21328) (xy 82.663758 -410.1637) (xy 82.648402 -410.111403) (xy 82.640646 -410.057453)
			(xy 81.202989 -410.057453) (xy 81.195235 -410.111387) (xy 81.179883 -410.163674) (xy 81.157247 -410.213245)
			(xy 81.127786 -410.259089) (xy 81.092102 -410.300275) (xy 81.05092 -410.335964) (xy 81.005078 -410.365428)
			(xy 80.95551 -410.38807) (xy 80.903224 -410.403427) (xy 80.849285 -410.411187) (xy 80.822038 -410.411676)
			(xy 79.958438 -410.411676) (xy 79.931181 -410.41128) (xy 79.877221 -410.403526) (xy 79.824915 -410.388172)
			(xy 79.775325 -410.36553) (xy 79.729464 -410.336061) (xy 79.688263 -410.300364) (xy 79.652562 -410.259167)
			(xy 79.623088 -410.213308) (xy 79.600441 -410.163721) (xy 79.585082 -410.111416) (xy 79.577323 -410.057457)
			(xy 78.139812 -410.057457) (xy 78.132056 -410.111397) (xy 78.116702 -410.163691) (xy 78.094061 -410.213267)
			(xy 78.064595 -410.259116) (xy 78.028904 -410.300306) (xy 77.987715 -410.335996) (xy 77.941865 -410.365462)
			(xy 77.892289 -410.388102) (xy 77.839995 -410.403457) (xy 77.786049 -410.411213) (xy 77.758798 -410.411676)
			(xy 76.895198 -410.411676) (xy 76.867945 -410.411254) (xy 76.813993 -410.403497) (xy 76.761694 -410.38814)
			(xy 76.712113 -410.365497) (xy 76.666259 -410.336028) (xy 76.625065 -410.300334) (xy 76.589371 -410.25914)
			(xy 76.559902 -410.213286) (xy 76.537259 -410.163705) (xy 76.521903 -410.111406) (xy 76.514146 -410.057453)
			(xy 75.076613 -410.057453) (xy 75.068855 -410.111403) (xy 75.053498 -410.163699) (xy 75.030855 -410.213278)
			(xy 75.001385 -410.259129) (xy 74.96569 -410.30032) (xy 74.924496 -410.33601) (xy 74.878641 -410.365475)
			(xy 74.82906 -410.388113) (xy 74.776761 -410.403464) (xy 74.722811 -410.411216) (xy 74.695558 -410.411676)
			(xy 73.831958 -410.411676) (xy 73.804706 -410.411251) (xy 73.750759 -410.403489) (xy 73.698465 -410.388129)
			(xy 73.648889 -410.365484) (xy 73.60304 -410.336014) (xy 73.561851 -410.300319) (xy 73.526161 -410.259127)
			(xy 73.496696 -410.213275) (xy 73.474056 -410.163696) (xy 73.458702 -410.1114) (xy 73.450946 -410.057452)
			(xy 72.013289 -410.057452) (xy 72.005534 -410.11139) (xy 71.990182 -410.163679) (xy 71.967544 -410.21325)
			(xy 71.938082 -410.259096) (xy 71.902395 -410.300282) (xy 71.86121 -410.335971) (xy 71.815366 -410.365435)
			(xy 71.765795 -410.388075) (xy 71.713507 -410.403431) (xy 71.659566 -410.411189) (xy 71.632318 -410.411676)
			(xy 70.768718 -410.411676) (xy 70.741462 -410.411278) (xy 70.687505 -410.403523) (xy 70.6352 -410.388167)
			(xy 70.585613 -410.365524) (xy 70.539754 -410.336054) (xy 70.498556 -410.300357) (xy 70.462857 -410.25916)
			(xy 70.433385 -410.213302) (xy 70.410739 -410.163717) (xy 70.395381 -410.111413) (xy 70.387623 -410.057456)
			(xy 68.950112 -410.057456) (xy 68.942356 -410.1114) (xy 68.927 -410.163695) (xy 68.904358 -410.213273)
			(xy 68.87489 -410.259123) (xy 68.839197 -410.300313) (xy 68.798005 -410.336003) (xy 68.752153 -410.365468)
			(xy 68.702574 -410.388108) (xy 68.650278 -410.40346) (xy 68.59633 -410.411214) (xy 68.569078 -410.411676)
			(xy 67.705478 -410.411676) (xy 67.678225 -410.411253) (xy 67.624276 -410.403493) (xy 67.571979 -410.388135)
			(xy 67.522401 -410.36549) (xy 67.476549 -410.336021) (xy 67.435358 -410.300326) (xy 67.399666 -410.259133)
			(xy 67.370199 -410.21328) (xy 67.347558 -410.1637) (xy 67.332202 -410.111403) (xy 67.324446 -410.057453)
			(xy 65.886789 -410.057453) (xy 65.879035 -410.111387) (xy 65.863683 -410.163674) (xy 65.841047 -410.213245)
			(xy 65.811586 -410.259089) (xy 65.775902 -410.300275) (xy 65.73472 -410.335964) (xy 65.688878 -410.365428)
			(xy 65.63931 -410.38807) (xy 65.587024 -410.403427) (xy 65.533085 -410.411187) (xy 65.505838 -410.411676)
			(xy 64.642238 -410.411676) (xy 64.614981 -410.41128) (xy 64.561021 -410.403526) (xy 64.508715 -410.388172)
			(xy 64.459125 -410.36553) (xy 64.413264 -410.336061) (xy 64.372063 -410.300364) (xy 64.336362 -410.259167)
			(xy 64.306888 -410.213308) (xy 64.284241 -410.163721) (xy 64.268882 -410.111416) (xy 64.261123 -410.057457)
			(xy 62.823612 -410.057457) (xy 62.815856 -410.111397) (xy 62.800502 -410.163691) (xy 62.777861 -410.213267)
			(xy 62.748395 -410.259116) (xy 62.712704 -410.300306) (xy 62.671515 -410.335996) (xy 62.625665 -410.365462)
			(xy 62.576089 -410.388102) (xy 62.523795 -410.403457) (xy 62.469849 -410.411213) (xy 62.442598 -410.411676)
			(xy 61.578998 -410.411676) (xy 61.551745 -410.411254) (xy 61.497793 -410.403497) (xy 61.445494 -410.38814)
			(xy 61.395913 -410.365497) (xy 61.350059 -410.336028) (xy 61.308865 -410.300334) (xy 61.273171 -410.25914)
			(xy 61.243702 -410.213286) (xy 61.221059 -410.163705) (xy 61.205703 -410.111406) (xy 61.197946 -410.057453)
			(xy 59.760413 -410.057453) (xy 59.752655 -410.111403) (xy 59.737298 -410.163699) (xy 59.714655 -410.213278)
			(xy 59.685185 -410.259129) (xy 59.64949 -410.30032) (xy 59.608296 -410.33601) (xy 59.562441 -410.365475)
			(xy 59.51286 -410.388113) (xy 59.460561 -410.403464) (xy 59.406611 -410.411216) (xy 59.379358 -410.411676)
			(xy 58.515758 -410.411676) (xy 58.488506 -410.411251) (xy 58.434559 -410.403489) (xy 58.382265 -410.388129)
			(xy 58.332689 -410.365484) (xy 58.28684 -410.336014) (xy 58.245651 -410.300319) (xy 58.209961 -410.259127)
			(xy 58.180496 -410.213275) (xy 58.157856 -410.163696) (xy 58.142502 -410.1114) (xy 58.134746 -410.057452)
			(xy 56.697089 -410.057452) (xy 56.689334 -410.11139) (xy 56.673982 -410.163679) (xy 56.651344 -410.21325)
			(xy 56.621882 -410.259096) (xy 56.586195 -410.300282) (xy 56.54501 -410.335971) (xy 56.499166 -410.365435)
			(xy 56.449595 -410.388075) (xy 56.397307 -410.403431) (xy 56.343366 -410.411189) (xy 56.316118 -410.411676)
			(xy 55.452518 -410.411676) (xy 55.425262 -410.411278) (xy 55.371305 -410.403523) (xy 55.319 -410.388167)
			(xy 55.269413 -410.365524) (xy 55.223554 -410.336054) (xy 55.182356 -410.300357) (xy 55.146657 -410.25916)
			(xy 55.117185 -410.213302) (xy 55.094539 -410.163717) (xy 55.079181 -410.111413) (xy 55.071423 -410.057456)
			(xy 53.633912 -410.057456) (xy 53.626156 -410.1114) (xy 53.6108 -410.163695) (xy 53.588158 -410.213273)
			(xy 53.55869 -410.259123) (xy 53.522997 -410.300313) (xy 53.481805 -410.336003) (xy 53.435953 -410.365468)
			(xy 53.386374 -410.388108) (xy 53.334078 -410.40346) (xy 53.28013 -410.411214) (xy 53.252878 -410.411676)
			(xy 52.389278 -410.411676) (xy 52.362025 -410.411253) (xy 52.308076 -410.403493) (xy 52.255779 -410.388135)
			(xy 52.206201 -410.36549) (xy 52.160349 -410.336021) (xy 52.119158 -410.300326) (xy 52.083466 -410.259133)
			(xy 52.053999 -410.21328) (xy 52.031358 -410.1637) (xy 52.016002 -410.111403) (xy 52.008246 -410.057453)
			(xy 50.570589 -410.057453) (xy 50.562835 -410.111387) (xy 50.547483 -410.163674) (xy 50.524847 -410.213245)
			(xy 50.495386 -410.259089) (xy 50.459702 -410.300275) (xy 50.41852 -410.335964) (xy 50.372678 -410.365428)
			(xy 50.32311 -410.38807) (xy 50.270824 -410.403427) (xy 50.216885 -410.411187) (xy 50.189638 -410.411676)
			(xy 49.326038 -410.411676) (xy 49.298781 -410.41128) (xy 49.244821 -410.403526) (xy 49.192515 -410.388172)
			(xy 49.142925 -410.36553) (xy 49.097064 -410.336061) (xy 49.055863 -410.300364) (xy 49.020162 -410.259167)
			(xy 48.990688 -410.213308) (xy 48.968041 -410.163721) (xy 48.952682 -410.111416) (xy 48.944923 -410.057457)
			(xy 7.00913 -410.057457) (xy 7.00913 -411.241049) (xy 101.876886 -411.241049) (xy 101.876886 -411.186551)
			(xy 101.884641 -411.132608) (xy 101.899994 -411.080318) (xy 101.922631 -411.030744) (xy 101.952093 -410.984897)
			(xy 101.98778 -410.943708) (xy 102.028964 -410.908017) (xy 102.074809 -410.878551) (xy 102.12438 -410.855908)
			(xy 102.176669 -410.840549) (xy 102.230611 -410.832788) (xy 102.25786 -410.8323) (xy 103.12146 -410.8323)
			(xy 103.148715 -410.832745) (xy 103.202672 -410.840497) (xy 103.254975 -410.85585) (xy 103.304562 -410.878491)
			(xy 103.350421 -410.907958) (xy 103.391619 -410.943653) (xy 103.427318 -410.984847) (xy 103.45679 -411.030703)
			(xy 103.479436 -411.080287) (xy 103.494794 -411.132589) (xy 103.502553 -411.186545) (xy 103.502553 -411.241055)
			(xy 103.494794 -411.295011) (xy 103.479436 -411.347313) (xy 103.45679 -411.396897) (xy 103.427318 -411.442753)
			(xy 103.391619 -411.483947) (xy 103.350421 -411.519642) (xy 103.304562 -411.549109) (xy 103.254975 -411.57175)
			(xy 103.202672 -411.587103) (xy 103.148715 -411.594855) (xy 103.12146 -411.595316) (xy 102.25786 -411.595316)
			(xy 102.230611 -411.594812) (xy 102.176669 -411.587051) (xy 102.12438 -411.571692) (xy 102.074809 -411.549049)
			(xy 102.028964 -411.519583) (xy 101.98778 -411.483892) (xy 101.952093 -411.442703) (xy 101.922631 -411.396856)
			(xy 101.899994 -411.347282) (xy 101.884641 -411.294992) (xy 101.876886 -411.241049) (xy 7.00913 -411.241049)
			(xy 7.00913 -424.470068) (xy 39.528496 -424.470068) (xy 39.528496 -417.770056) (xy 39.529001 -417.664532)
			(xy 39.537085 -417.453638) (xy 39.553241 -417.243209) (xy 39.577444 -417.033552) (xy 39.609661 -416.824977)
			(xy 39.649843 -416.617789) (xy 39.697931 -416.412292) (xy 39.753855 -416.208788) (xy 39.817532 -416.007575)
			(xy 39.88887 -415.808948) (xy 39.967764 -415.6132) (xy 40.054097 -415.420618) (xy 40.147744 -415.231483)
			(xy 40.248566 -415.046074) (xy 40.356416 -414.864663) (xy 40.471135 -414.687516) (xy 40.592555 -414.514894)
			(xy 40.720498 -414.347048) (xy 40.854776 -414.184226) (xy 40.995192 -414.026667) (xy 41.14154 -413.874602)
			(xy 41.293605 -413.728254) (xy 41.451164 -413.587838) (xy 41.613986 -413.45356) (xy 41.781832 -413.325617)
			(xy 41.954454 -413.204197) (xy 42.131601 -413.089478) (xy 42.313012 -412.981628) (xy 42.498421 -412.880806)
			(xy 42.687556 -412.787159) (xy 42.880138 -412.700826) (xy 43.075886 -412.621932) (xy 43.274513 -412.550594)
			(xy 43.475726 -412.486917) (xy 43.67923 -412.430993) (xy 43.884727 -412.382905) (xy 44.091915 -412.342723)
			(xy 44.30049 -412.310506) (xy 44.510147 -412.286303) (xy 44.720576 -412.270147) (xy 44.93147 -412.262063)
			(xy 45.142518 -412.262063) (xy 45.353412 -412.270147) (xy 45.563841 -412.286303) (xy 45.773498 -412.310506)
			(xy 45.982073 -412.342723) (xy 46.189261 -412.382905) (xy 46.394758 -412.430993) (xy 46.598262 -412.486917)
			(xy 46.799475 -412.550594) (xy 46.998102 -412.621932) (xy 47.19385 -412.700826) (xy 47.386432 -412.787159)
			(xy 47.575567 -412.880806) (xy 47.760976 -412.981628) (xy 47.942387 -413.089478) (xy 48.119534 -413.204197)
			(xy 48.292156 -413.325617) (xy 48.460002 -413.45356) (xy 48.622824 -413.587838) (xy 48.649451 -413.611568)
			(xy 104.877616 -413.611568) (xy 104.877616 -412.747968) (xy 104.878102 -412.720717) (xy 104.885858 -412.666769)
			(xy 104.901213 -412.614474) (xy 104.923855 -412.564897) (xy 104.953321 -412.519047) (xy 104.989012 -412.477856)
			(xy 105.030203 -412.442165) (xy 105.076053 -412.412699) (xy 105.12563 -412.390057) (xy 105.177925 -412.374702)
			(xy 105.231873 -412.366946) (xy 105.286375 -412.366946) (xy 105.340323 -412.374702) (xy 105.392618 -412.390057)
			(xy 105.442195 -412.412699) (xy 105.488045 -412.442165) (xy 105.529236 -412.477856) (xy 105.564927 -412.519047)
			(xy 105.594393 -412.564897) (xy 105.617035 -412.614474) (xy 105.63239 -412.666769) (xy 105.640146 -412.720717)
			(xy 105.640632 -412.747968) (xy 105.640632 -413.611568) (xy 105.640146 -413.638819) (xy 105.63239 -413.692767)
			(xy 105.617035 -413.745062) (xy 105.594393 -413.794639) (xy 105.584722 -413.809688) (xy 116.689632 -413.809688)
			(xy 116.689632 -412.946088) (xy 116.690118 -412.918837) (xy 116.697874 -412.864889) (xy 116.713229 -412.812594)
			(xy 116.735871 -412.763017) (xy 116.765337 -412.717167) (xy 116.801028 -412.675976) (xy 116.842219 -412.640285)
			(xy 116.888069 -412.610819) (xy 116.937646 -412.588177) (xy 116.989941 -412.572822) (xy 117.043889 -412.565066)
			(xy 117.098391 -412.565066) (xy 117.152339 -412.572822) (xy 117.204634 -412.588177) (xy 117.254211 -412.610819)
			(xy 117.300061 -412.640285) (xy 117.341252 -412.675976) (xy 117.376943 -412.717167) (xy 117.406409 -412.763017)
			(xy 117.429051 -412.812594) (xy 117.444406 -412.864889) (xy 117.452162 -412.918837) (xy 117.452648 -412.946088)
			(xy 117.452648 -413.809688) (xy 117.452162 -413.836939) (xy 117.444406 -413.890887) (xy 117.429051 -413.943182)
			(xy 117.406409 -413.992759) (xy 117.376943 -414.038609) (xy 117.341252 -414.0798) (xy 117.300061 -414.115491)
			(xy 117.254211 -414.144957) (xy 117.204634 -414.167599) (xy 117.152339 -414.182954) (xy 117.098391 -414.19071)
			(xy 117.043889 -414.19071) (xy 116.989941 -414.182954) (xy 116.937646 -414.167599) (xy 116.888069 -414.144957)
			(xy 116.842219 -414.115491) (xy 116.801028 -414.0798) (xy 116.765337 -414.038609) (xy 116.735871 -413.992759)
			(xy 116.713229 -413.943182) (xy 116.697874 -413.890887) (xy 116.690118 -413.836939) (xy 116.689632 -413.809688)
			(xy 105.584722 -413.809688) (xy 105.564927 -413.840489) (xy 105.529236 -413.88168) (xy 105.488045 -413.917371)
			(xy 105.442195 -413.946837) (xy 105.392618 -413.969479) (xy 105.340323 -413.984834) (xy 105.286375 -413.99259)
			(xy 105.231873 -413.99259) (xy 105.177925 -413.984834) (xy 105.12563 -413.969479) (xy 105.076053 -413.946837)
			(xy 105.030203 -413.917371) (xy 104.989012 -413.88168) (xy 104.953321 -413.840489) (xy 104.923855 -413.794639)
			(xy 104.901213 -413.745062) (xy 104.885858 -413.692767) (xy 104.878102 -413.638819) (xy 104.877616 -413.611568)
			(xy 48.649451 -413.611568) (xy 48.780383 -413.728254) (xy 48.932448 -413.874602) (xy 49.078796 -414.026667)
			(xy 49.219212 -414.184226) (xy 49.35349 -414.347048) (xy 49.481433 -414.514894) (xy 49.602853 -414.687516)
			(xy 49.717572 -414.864663) (xy 49.825422 -415.046074) (xy 49.926244 -415.231483) (xy 50.019891 -415.420618)
			(xy 50.106224 -415.6132) (xy 50.133819 -415.681668) (xy 100.559616 -415.681668) (xy 100.559616 -414.818068)
			(xy 100.560102 -414.790817) (xy 100.567858 -414.736869) (xy 100.583213 -414.684574) (xy 100.605855 -414.634997)
			(xy 100.635321 -414.589147) (xy 100.671012 -414.547956) (xy 100.712203 -414.512265) (xy 100.758053 -414.482799)
			(xy 100.80763 -414.460157) (xy 100.859925 -414.444802) (xy 100.913873 -414.437046) (xy 100.968375 -414.437046)
			(xy 101.022323 -414.444802) (xy 101.074618 -414.460157) (xy 101.124195 -414.482799) (xy 101.170045 -414.512265)
			(xy 101.211236 -414.547956) (xy 101.246927 -414.589147) (xy 101.276393 -414.634997) (xy 101.299035 -414.684574)
			(xy 101.31439 -414.736869) (xy 101.322146 -414.790817) (xy 101.322632 -414.818068) (xy 101.322632 -415.681668)
			(xy 101.322146 -415.708919) (xy 101.31439 -415.762867) (xy 101.299035 -415.815162) (xy 101.276393 -415.864739)
			(xy 101.246927 -415.910589) (xy 101.211236 -415.95178) (xy 101.170045 -415.987471) (xy 101.124195 -416.016937)
			(xy 101.074618 -416.039579) (xy 101.022323 -416.054934) (xy 100.968375 -416.06269) (xy 100.913873 -416.06269)
			(xy 100.859925 -416.054934) (xy 100.80763 -416.039579) (xy 100.758053 -416.016937) (xy 100.712203 -415.987471)
			(xy 100.671012 -415.95178) (xy 100.635321 -415.910589) (xy 100.605855 -415.864739) (xy 100.583213 -415.815162)
			(xy 100.567858 -415.762867) (xy 100.560102 -415.708919) (xy 100.559616 -415.681668) (xy 50.133819 -415.681668)
			(xy 50.185118 -415.808948) (xy 50.256456 -416.007575) (xy 50.320133 -416.208788) (xy 50.376057 -416.412292)
			(xy 50.424145 -416.617789) (xy 50.464327 -416.824977) (xy 50.496544 -417.033552) (xy 50.520747 -417.243209)
			(xy 50.536903 -417.453638) (xy 50.544987 -417.664532) (xy 50.545492 -417.770056) (xy 50.545492 -420.089838)
			(xy 58.13806 -420.089838) (xy 58.138171 -420.074752) (xy 58.139951 -420.044634) (xy 58.141616 -420.02964)
			(xy 58.141616 -418.95014) (xy 58.139949 -418.935146) (xy 58.138169 -418.905028) (xy 58.13806 -418.889942)
			(xy 58.138171 -418.874856) (xy 58.139951 -418.844738) (xy 58.141616 -418.829744) (xy 58.141616 -418.218874)
			(xy 58.142085 -418.206785) (xy 58.149546 -418.183788) (xy 58.163733 -418.164211) (xy 58.183264 -418.14996)
			(xy 58.206237 -418.142424) (xy 58.218324 -418.141912) (xy 59.158124 -418.141912) (xy 59.170235 -418.142296)
			(xy 59.193265 -418.149803) (xy 59.212839 -418.164073) (xy 59.227033 -418.183702) (xy 59.234451 -418.206761)
			(xy 59.234832 -418.218874) (xy 59.234832 -420.760398) (xy 59.23439 -420.77249) (xy 59.226931 -420.795495)
			(xy 59.212739 -420.815078) (xy 59.193198 -420.829327) (xy 59.170215 -420.836854) (xy 59.158124 -420.83736)
			(xy 58.218324 -420.83736) (xy 58.206212 -420.836963) (xy 58.183179 -420.829465) (xy 58.163602 -420.8152)
			(xy 58.149408 -420.795571) (xy 58.141994 -420.772511) (xy 58.141616 -420.760398) (xy 58.141616 -420.150036)
			(xy 58.139948 -420.135042) (xy 58.138169 -420.104924) (xy 58.13806 -420.089838) (xy 50.545492 -420.089838)
			(xy 50.545492 -421.089836) (xy 60.138056 -421.089836) (xy 60.138167 -421.07475) (xy 60.139947 -421.044632)
			(xy 60.141612 -421.029638) (xy 60.141612 -419.950138) (xy 60.139945 -419.935144) (xy 60.138165 -419.905026)
			(xy 60.138056 -419.88994) (xy 60.138167 -419.874854) (xy 60.139947 -419.844736) (xy 60.141612 -419.829742)
			(xy 60.141612 -419.218872) (xy 60.14204 -419.206794) (xy 60.149513 -419.183822) (xy 60.163718 -419.164284)
			(xy 60.183265 -419.150091) (xy 60.206242 -419.142633) (xy 60.21832 -419.142164) (xy 61.15812 -419.142164)
			(xy 61.170193 -419.142647) (xy 61.193156 -419.150112) (xy 61.21269 -419.164304) (xy 61.226885 -419.183837)
			(xy 61.234352 -419.206799) (xy 61.234828 -419.218872) (xy 61.234828 -421.089836) (xy 68.13804 -421.089836)
			(xy 68.138151 -421.07475) (xy 68.139931 -421.044632) (xy 68.141596 -421.029638) (xy 68.141596 -419.950138)
			(xy 68.139929 -419.935144) (xy 68.138149 -419.905026) (xy 68.13804 -419.88994) (xy 68.138151 -419.874854)
			(xy 68.139931 -419.844736) (xy 68.141596 -419.829742) (xy 68.141596 -419.218872) (xy 68.14204 -419.206796)
			(xy 68.149511 -419.183827) (xy 68.163712 -419.16429) (xy 68.183255 -419.150096) (xy 68.206227 -419.142635)
			(xy 68.218304 -419.142164) (xy 69.158104 -419.142164) (xy 69.170176 -419.14266) (xy 69.193139 -419.150121)
			(xy 69.212673 -419.16431) (xy 69.226868 -419.18384) (xy 69.234336 -419.2068) (xy 69.234812 -419.218872)
			(xy 69.234812 -420.089838) (xy 70.138036 -420.089838) (xy 70.138149 -420.074753) (xy 70.139929 -420.044634)
			(xy 70.141592 -420.02964) (xy 70.141592 -418.95014) (xy 70.139925 -418.935146) (xy 70.138145 -418.905028)
			(xy 70.138036 -418.889942) (xy 70.13815 -418.874857) (xy 70.139929 -418.844738) (xy 70.141592 -418.829744)
			(xy 70.141592 -418.218874) (xy 70.142084 -418.206788) (xy 70.149542 -418.183794) (xy 70.163724 -418.164219)
			(xy 70.183249 -418.149968) (xy 70.206216 -418.142428) (xy 70.2183 -418.141912) (xy 71.1581 -418.141912)
			(xy 71.17021 -418.142316) (xy 71.193239 -418.149817) (xy 71.212814 -418.164081) (xy 71.227008 -418.183706)
			(xy 71.234426 -418.206762) (xy 71.234808 -418.218874) (xy 71.234808 -420.760398) (xy 71.234292 -420.772483)
			(xy 71.226841 -420.795475) (xy 71.212666 -420.815051) (xy 71.193146 -420.829303) (xy 71.170183 -420.836844)
			(xy 71.1581 -420.83736) (xy 70.2183 -420.83736) (xy 70.206187 -420.836983) (xy 70.183153 -420.829479)
			(xy 70.163576 -420.815209) (xy 70.149383 -420.795576) (xy 70.14197 -420.772512) (xy 70.141592 -420.760398)
			(xy 70.141592 -420.150036) (xy 70.139924 -420.135042) (xy 70.138145 -420.104924) (xy 70.138036 -420.089838)
			(xy 69.234812 -420.089838) (xy 69.234812 -421.089836) (xy 72.138032 -421.089836) (xy 72.138145 -421.074751)
			(xy 72.139925 -421.044632) (xy 72.141588 -421.029638) (xy 72.141588 -419.950138) (xy 72.13992 -419.935144)
			(xy 72.138141 -419.905026) (xy 72.138032 -419.88994) (xy 72.138145 -419.874855) (xy 72.139925 -419.844736)
			(xy 72.141588 -419.829742) (xy 72.141588 -419.218872) (xy 72.14204 -419.206796) (xy 72.14951 -419.183829)
			(xy 72.16371 -419.164293) (xy 72.18325 -419.150099) (xy 72.20622 -419.142636) (xy 72.218296 -419.142164)
			(xy 73.158096 -419.142164) (xy 73.170168 -419.142667) (xy 73.19313 -419.150125) (xy 73.212665 -419.164313)
			(xy 73.22686 -419.183841) (xy 73.234328 -419.206801) (xy 73.234804 -419.218872) (xy 73.234804 -419.702852)
			(xy 110.957342 -419.702852) (xy 110.957342 -419.648348) (xy 110.965098 -419.594399) (xy 110.980453 -419.542102)
			(xy 111.003093 -419.492523) (xy 111.032558 -419.44667) (xy 111.068249 -419.405477) (xy 111.109438 -419.369782)
			(xy 111.155288 -419.340312) (xy 111.204865 -419.317667) (xy 111.25716 -419.302306) (xy 111.311108 -419.294545)
			(xy 111.33836 -419.294056) (xy 112.20196 -419.294056) (xy 112.229212 -419.294589) (xy 112.283162 -419.30234)
			(xy 112.33546 -419.317691) (xy 112.385041 -419.340329) (xy 112.430894 -419.369793) (xy 112.472088 -419.405484)
			(xy 112.507783 -419.446674) (xy 112.537251 -419.492524) (xy 112.559895 -419.542102) (xy 112.575251 -419.594399)
			(xy 112.583009 -419.648348) (xy 112.583009 -419.702852) (xy 112.575251 -419.756801) (xy 112.559895 -419.809098)
			(xy 112.537251 -419.858676) (xy 112.507783 -419.904526) (xy 112.472088 -419.945716) (xy 112.430894 -419.981407)
			(xy 112.385041 -420.010871) (xy 112.33546 -420.033509) (xy 112.283162 -420.04886) (xy 112.229212 -420.056611)
			(xy 112.20196 -420.057072) (xy 111.33836 -420.057072) (xy 111.311108 -420.056655) (xy 111.25716 -420.048894)
			(xy 111.204865 -420.033533) (xy 111.155288 -420.010888) (xy 111.109438 -419.981418) (xy 111.068249 -419.945723)
			(xy 111.032558 -419.90453) (xy 111.003093 -419.858677) (xy 110.980453 -419.809098) (xy 110.965098 -419.756801)
			(xy 110.957342 -419.702852) (xy 73.234804 -419.702852) (xy 73.234804 -421.760396) (xy 73.234384 -421.772479)
			(xy 73.226917 -421.795462) (xy 73.212713 -421.815013) (xy 73.193162 -421.829217) (xy 73.170179 -421.836684)
			(xy 73.158096 -421.837104) (xy 72.218296 -421.837104) (xy 72.206221 -421.836639) (xy 72.183253 -421.829175)
			(xy 72.163716 -421.814979) (xy 72.149521 -421.79544) (xy 72.14206 -421.772471) (xy 72.141588 -421.760396)
			(xy 72.141588 -421.150034) (xy 72.13992 -421.13504) (xy 72.138141 -421.104922) (xy 72.138032 -421.089836)
			(xy 69.234812 -421.089836) (xy 69.234812 -421.760396) (xy 69.234332 -421.77247) (xy 69.226871 -421.795436)
			(xy 69.212679 -421.814973) (xy 69.193143 -421.829168) (xy 69.170178 -421.836631) (xy 69.158104 -421.837104)
			(xy 68.218304 -421.837104) (xy 68.206221 -421.836684) (xy 68.183238 -421.829217) (xy 68.163687 -421.815013)
			(xy 68.149483 -421.795462) (xy 68.142016 -421.772479) (xy 68.141596 -421.760396) (xy 68.141596 -421.150034)
			(xy 68.139928 -421.13504) (xy 68.138149 -421.104922) (xy 68.13804 -421.089836) (xy 61.234828 -421.089836)
			(xy 61.234828 -421.760396) (xy 61.234333 -421.772468) (xy 61.226874 -421.795432) (xy 61.212684 -421.814967)
			(xy 61.193154 -421.829163) (xy 61.170192 -421.836629) (xy 61.15812 -421.837104) (xy 60.21832 -421.837104)
			(xy 60.206238 -421.83667) (xy 60.183255 -421.829208) (xy 60.163704 -421.815007) (xy 60.1495 -421.795459)
			(xy 60.142032 -421.772478) (xy 60.141612 -421.760396) (xy 60.141612 -421.150034) (xy 60.139944 -421.13504)
			(xy 60.138165 -421.104922) (xy 60.138056 -421.089836) (xy 50.545492 -421.089836) (xy 50.545492 -423.68978)
			(xy 58.13806 -423.68978) (xy 58.138175 -423.674695) (xy 58.139953 -423.644576) (xy 58.141616 -423.629582)
			(xy 58.141616 -422.550082) (xy 58.139952 -422.535088) (xy 58.138171 -422.50497) (xy 58.13806 -422.489884)
			(xy 58.138175 -422.474799) (xy 58.139953 -422.44468) (xy 58.141616 -422.429686) (xy 58.141616 -421.81907)
			(xy 58.142081 -421.806981) (xy 58.149543 -421.783984) (xy 58.163731 -421.764406) (xy 58.183263 -421.750156)
			(xy 58.206237 -421.74262) (xy 58.218324 -421.742108) (xy 59.158124 -421.742108) (xy 59.170235 -421.742496)
			(xy 59.193264 -421.750003) (xy 59.212838 -421.764272) (xy 59.227031 -421.783899) (xy 59.23445 -421.806958)
			(xy 59.234832 -421.81907) (xy 59.234832 -423.68978) (xy 62.138052 -423.68978) (xy 62.138167 -423.674695)
			(xy 62.139945 -423.644576) (xy 62.141608 -423.629582) (xy 62.141608 -422.550082) (xy 62.139944 -422.535088)
			(xy 62.138163 -422.50497) (xy 62.138052 -422.489884) (xy 62.138167 -422.474799) (xy 62.139945 -422.44468)
			(xy 62.141608 -422.429686) (xy 62.141608 -421.81907) (xy 62.142081 -421.806982) (xy 62.149542 -421.783986)
			(xy 62.163728 -421.764409) (xy 62.183258 -421.750158) (xy 62.20623 -421.742621) (xy 62.218316 -421.742108)
			(xy 63.158116 -421.742108) (xy 63.170227 -421.742503) (xy 63.193256 -421.750008) (xy 63.212829 -421.764274)
			(xy 63.227023 -421.783901) (xy 63.234442 -421.806958) (xy 63.234824 -421.81907) (xy 63.234824 -424.360594)
			(xy 63.234387 -424.372687) (xy 63.226927 -424.395693) (xy 63.212734 -424.415276) (xy 63.193192 -424.429526)
			(xy 63.170207 -424.437051) (xy 63.158116 -424.437556) (xy 62.218316 -424.437556) (xy 62.206214 -424.437071)
			(xy 62.183196 -424.429582) (xy 62.163628 -424.415337) (xy 62.149431 -424.395733) (xy 62.142 -424.372697)
			(xy 62.141608 -424.360594) (xy 62.141608 -423.749978) (xy 62.139944 -423.734984) (xy 62.138162 -423.704866)
			(xy 62.138052 -423.68978) (xy 59.234832 -423.68978) (xy 59.234832 -424.360594) (xy 59.234387 -424.372686)
			(xy 59.226928 -424.395691) (xy 59.212737 -424.415274) (xy 59.193197 -424.429523) (xy 59.170215 -424.43705)
			(xy 59.158124 -424.437556) (xy 58.218324 -424.437556) (xy 58.206222 -424.437064) (xy 58.183205 -424.429578)
			(xy 58.163637 -424.415334) (xy 58.149439 -424.395732) (xy 58.142008 -424.372697) (xy 58.141616 -424.360594)
			(xy 58.141616 -423.749978) (xy 58.139952 -423.734984) (xy 58.13817 -423.704866) (xy 58.13806 -423.68978)
			(xy 50.545492 -423.68978) (xy 50.545492 -424.470068) (xy 50.544987 -424.575592) (xy 50.54061 -424.689778)
			(xy 64.138048 -424.689778) (xy 64.138163 -424.674693) (xy 64.139941 -424.644574) (xy 64.141604 -424.62958)
			(xy 64.141604 -423.55008) (xy 64.13994 -423.535086) (xy 64.138158 -423.504968) (xy 64.138048 -423.489882)
			(xy 64.138163 -423.474797) (xy 64.139941 -423.444678) (xy 64.141604 -423.429684) (xy 64.141604 -422.819068)
			(xy 64.142037 -422.806991) (xy 64.14951 -422.78402) (xy 64.163714 -422.764483) (xy 64.18326 -422.75029)
			(xy 64.206234 -422.74283) (xy 64.218312 -422.74236) (xy 65.158112 -422.74236) (xy 65.170184 -422.742854)
			(xy 65.193146 -422.750316) (xy 65.21268 -422.764506) (xy 65.226875 -422.784036) (xy 65.234343 -422.806996)
			(xy 65.23482 -422.819068) (xy 65.23482 -424.689778) (xy 68.13804 -424.689778) (xy 68.138155 -424.674693)
			(xy 68.139933 -424.644574) (xy 68.141596 -424.62958) (xy 68.141596 -423.55008) (xy 68.139932 -423.535086)
			(xy 68.13815 -423.504968) (xy 68.13804 -423.489882) (xy 68.138155 -423.474797) (xy 68.139933 -423.444678)
			(xy 68.141596 -423.429684) (xy 68.141596 -422.819068) (xy 68.142037 -422.806991) (xy 68.149509 -422.784022)
			(xy 68.163711 -422.764485) (xy 68.183255 -422.750292) (xy 68.206227 -422.742831) (xy 68.218304 -422.74236)
			(xy 69.158104 -422.74236) (xy 69.170176 -422.74286) (xy 69.193137 -422.75032) (xy 69.212672 -422.764508)
			(xy 69.226867 -422.784037) (xy 69.234335 -422.806997) (xy 69.234812 -422.819068) (xy 69.234812 -423.68978)
			(xy 70.138036 -423.68978) (xy 70.138153 -423.674695) (xy 70.139931 -423.644576) (xy 70.141592 -423.629582)
			(xy 70.141592 -422.550082) (xy 70.139928 -422.535088) (xy 70.138147 -422.50497) (xy 70.138036 -422.489884)
			(xy 70.138153 -422.474799) (xy 70.139931 -422.44468) (xy 70.141592 -422.429686) (xy 70.141592 -421.81907)
			(xy 70.142081 -421.806984) (xy 70.14954 -421.78399) (xy 70.163723 -421.764415) (xy 70.183248 -421.750163)
			(xy 70.206215 -421.742624) (xy 70.2183 -421.742108) (xy 71.1581 -421.742108) (xy 71.17021 -421.742516)
			(xy 71.193238 -421.750017) (xy 71.212812 -421.76428) (xy 71.227007 -421.783904) (xy 71.234426 -421.806959)
			(xy 71.234808 -421.81907) (xy 71.234808 -424.360594) (xy 71.234288 -424.372678) (xy 71.226839 -424.395671)
			(xy 71.212664 -424.415247) (xy 71.193145 -424.429499) (xy 71.170183 -424.43704) (xy 71.1581 -424.437556)
			(xy 70.2183 -424.437556) (xy 70.206197 -424.437085) (xy 70.183179 -424.429592) (xy 70.163611 -424.415343)
			(xy 70.149414 -424.395736) (xy 70.141983 -424.372698) (xy 70.141592 -424.360594) (xy 70.141592 -423.749978)
			(xy 70.139928 -423.734984) (xy 70.138146 -423.704866) (xy 70.138036 -423.68978) (xy 69.234812 -423.68978)
			(xy 69.234812 -424.689778) (xy 72.138032 -424.689778) (xy 72.138149 -424.674693) (xy 72.139927 -424.644574)
			(xy 72.141588 -424.62958) (xy 72.141588 -423.55008) (xy 72.139924 -423.535086) (xy 72.138142 -423.504968)
			(xy 72.138032 -423.489882) (xy 72.138149 -423.474797) (xy 72.139927 -423.444678) (xy 72.141588 -423.429684)
			(xy 72.141588 -422.819068) (xy 72.142037 -422.806992) (xy 72.149508 -422.784025) (xy 72.163708 -422.764488)
			(xy 72.18325 -422.750295) (xy 72.20622 -422.742832) (xy 72.218296 -422.74236) (xy 73.158096 -422.74236)
			(xy 73.170167 -422.742867) (xy 73.193129 -422.750325) (xy 73.212663 -422.764511) (xy 73.226859 -422.784039)
			(xy 73.234327 -422.806997) (xy 73.234804 -422.819068) (xy 73.234804 -424.80464) (xy 109.929157 -424.80464)
			(xy 109.929157 -424.6755) (xy 109.937107 -424.546605) (xy 109.952977 -424.418445) (xy 109.976706 -424.291504)
			(xy 110.008205 -424.166265) (xy 110.047354 -424.043202) (xy 110.094005 -423.922783) (xy 110.14798 -423.805464)
			(xy 110.209075 -423.69169) (xy 110.277058 -423.581893) (xy 110.351672 -423.47649) (xy 110.432633 -423.37588)
			(xy 110.519633 -423.280445) (xy 110.612344 -423.190546) (xy 110.710414 -423.106525) (xy 110.813469 -423.028701)
			(xy 110.92112 -422.957369) (xy 111.032959 -422.892799) (xy 111.14856 -422.835237) (xy 111.267485 -422.7849)
			(xy 111.389284 -422.74198) (xy 111.513494 -422.706639) (xy 111.639643 -422.679012) (xy 111.767255 -422.659203)
			(xy 111.895844 -422.647287) (xy 112.024922 -422.643311) (xy 112.154 -422.647287) (xy 112.282589 -422.659203)
			(xy 112.410201 -422.679012) (xy 112.53635 -422.706639) (xy 112.66056 -422.74198) (xy 112.782359 -422.7849)
			(xy 112.901284 -422.835237) (xy 113.016885 -422.892799) (xy 113.128724 -422.957369) (xy 113.236375 -423.028701)
			(xy 113.33943 -423.106525) (xy 113.4375 -423.190546) (xy 113.530211 -423.280445) (xy 113.617211 -423.37588)
			(xy 113.698172 -423.47649) (xy 113.772786 -423.581893) (xy 113.840769 -423.69169) (xy 113.901864 -423.805464)
			(xy 113.955839 -423.922783) (xy 114.00249 -424.043202) (xy 114.041639 -424.166265) (xy 114.073138 -424.291504)
			(xy 114.096867 -424.418445) (xy 114.112737 -424.546605) (xy 114.120687 -424.6755) (xy 114.121184 -424.74007)
			(xy 114.120687 -424.80464) (xy 114.112737 -424.933535) (xy 114.096867 -425.061695) (xy 114.073138 -425.188636)
			(xy 114.041639 -425.313875) (xy 114.00249 -425.436938) (xy 113.955839 -425.557357) (xy 113.901864 -425.674676)
			(xy 113.840769 -425.78845) (xy 113.772786 -425.898247) (xy 113.698172 -426.00365) (xy 113.617211 -426.10426)
			(xy 113.530211 -426.199695) (xy 113.4375 -426.289594) (xy 113.33943 -426.373615) (xy 113.236375 -426.451439)
			(xy 113.128724 -426.522771) (xy 113.016885 -426.587341) (xy 112.901284 -426.644903) (xy 112.782359 -426.69524)
			(xy 112.66056 -426.73816) (xy 112.53635 -426.773501) (xy 112.410201 -426.801128) (xy 112.282589 -426.820937)
			(xy 112.154 -426.832853) (xy 112.024922 -426.83683) (xy 111.895844 -426.832853) (xy 111.767255 -426.820937)
			(xy 111.639643 -426.801128) (xy 111.513494 -426.773501) (xy 111.389284 -426.73816) (xy 111.267485 -426.69524)
			(xy 111.14856 -426.644903) (xy 111.032959 -426.587341) (xy 110.92112 -426.522771) (xy 110.813469 -426.451439)
			(xy 110.710414 -426.373615) (xy 110.612344 -426.289594) (xy 110.519633 -426.199695) (xy 110.432633 -426.10426)
			(xy 110.351672 -426.00365) (xy 110.277058 -425.898247) (xy 110.209075 -425.78845) (xy 110.14798 -425.674676)
			(xy 110.094005 -425.557357) (xy 110.047354 -425.436938) (xy 110.008205 -425.313875) (xy 109.976706 -425.188636)
			(xy 109.952977 -425.061695) (xy 109.937107 -424.933535) (xy 109.929157 -424.80464) (xy 73.234804 -424.80464)
			(xy 73.234804 -425.360592) (xy 73.234381 -425.372675) (xy 73.226915 -425.395658) (xy 73.212712 -425.415209)
			(xy 73.193162 -425.429413) (xy 73.170179 -425.43688) (xy 73.158096 -425.4373) (xy 72.218296 -425.4373)
			(xy 72.206212 -425.436891) (xy 72.183228 -425.429421) (xy 72.163677 -425.415214) (xy 72.149473 -425.395661)
			(xy 72.142007 -425.372676) (xy 72.141588 -425.360592) (xy 72.141588 -424.749976) (xy 72.139924 -424.734982)
			(xy 72.138142 -424.704864) (xy 72.138032 -424.689778) (xy 69.234812 -424.689778) (xy 69.234812 -425.360592)
			(xy 69.234381 -425.372674) (xy 69.226916 -425.395656) (xy 69.212714 -425.415206) (xy 69.193167 -425.429411)
			(xy 69.170186 -425.436879) (xy 69.158104 -425.4373) (xy 68.218304 -425.4373) (xy 68.206221 -425.436884)
			(xy 68.183237 -425.429417) (xy 68.163686 -425.415212) (xy 68.149482 -425.39566) (xy 68.142015 -425.372675)
			(xy 68.141596 -425.360592) (xy 68.141596 -424.749976) (xy 68.139932 -424.734982) (xy 68.13815 -424.704864)
			(xy 68.13804 -424.689778) (xy 65.23482 -424.689778) (xy 65.23482 -425.360592) (xy 65.234329 -425.372665)
			(xy 65.22687 -425.39563) (xy 65.21268 -425.415166) (xy 65.193148 -425.429361) (xy 65.170185 -425.436826)
			(xy 65.158112 -425.4373) (xy 64.218312 -425.4373) (xy 64.206229 -425.436877) (xy 64.183246 -425.429412)
			(xy 64.163694 -425.415208) (xy 64.14949 -425.395658) (xy 64.142024 -425.372675) (xy 64.141604 -425.360592)
			(xy 64.141604 -424.749976) (xy 64.13994 -424.734982) (xy 64.138158 -424.704864) (xy 64.138048 -424.689778)
			(xy 50.54061 -424.689778) (xy 50.536903 -424.786486) (xy 50.520747 -424.996915) (xy 50.496544 -425.206572)
			(xy 50.464327 -425.415147) (xy 50.424145 -425.622335) (xy 50.376057 -425.827832) (xy 50.320133 -426.031336)
			(xy 50.256456 -426.232549) (xy 50.185118 -426.431176) (xy 50.106224 -426.626924) (xy 50.019891 -426.819506)
			(xy 49.926244 -427.008641) (xy 49.825422 -427.19405) (xy 49.768393 -427.289976) (xy 58.118502 -427.289976)
			(xy 58.118998 -427.25742) (xy 58.126945 -427.192795) (xy 58.142732 -427.129626) (xy 58.166119 -427.068859)
			(xy 58.196758 -427.011406) (xy 58.234188 -426.958128) (xy 58.277848 -426.909824) (xy 58.302144 -426.888148)
			(xy 58.382916 -426.723302) (xy 58.387603 -426.71278) (xy 58.391097 -426.690025) (xy 58.387618 -426.667268)
			(xy 58.382916 -426.656754) (xy 58.30189 -426.491654) (xy 58.277623 -426.469962) (xy 58.234027 -426.421628)
			(xy 58.196653 -426.368337) (xy 58.16606 -426.310884) (xy 58.142706 -426.250127) (xy 58.126938 -426.186975)
			(xy 58.118994 -426.122371) (xy 58.118502 -426.089826) (xy 58.119221 -426.050501) (xy 58.130831 -425.972711)
			(xy 58.141616 -425.934886) (xy 58.141616 -425.419012) (xy 58.142023 -425.406928) (xy 58.149491 -425.383941)
			(xy 58.163697 -425.364389) (xy 58.183252 -425.350185) (xy 58.206239 -425.342722) (xy 58.218324 -425.342304)
			(xy 59.158124 -425.342304) (xy 59.170201 -425.342744) (xy 59.193171 -425.350215) (xy 59.212709 -425.364417)
			(xy 59.226902 -425.383961) (xy 59.234361 -425.406935) (xy 59.234832 -425.419012) (xy 59.234832 -427.960536)
			(xy 59.234367 -427.97261) (xy 59.226898 -427.995574) (xy 59.2127 -428.015109) (xy 59.193164 -428.029303)
			(xy 59.170198 -428.036769) (xy 59.158124 -428.037244) (xy 58.218324 -428.037244) (xy 58.206254 -428.036716)
			(xy 58.183294 -428.029264) (xy 58.16376 -428.015083) (xy 58.149563 -427.99556) (xy 58.142093 -427.972605)
			(xy 58.141616 -427.960536) (xy 58.141616 -427.444916) (xy 58.130812 -427.407096) (xy 58.119209 -427.329303)
			(xy 58.118502 -427.289976) (xy 49.768393 -427.289976) (xy 49.717572 -427.375461) (xy 49.602853 -427.552608)
			(xy 49.481433 -427.72523) (xy 49.35349 -427.893076) (xy 49.219212 -428.055898) (xy 49.078796 -428.213457)
			(xy 49.0054 -428.28972) (xy 60.118498 -428.28972) (xy 60.119034 -428.257141) (xy 60.127005 -428.192471)
			(xy 60.142819 -428.12926) (xy 60.166237 -428.068455) (xy 60.19691 -428.010967) (xy 60.234377 -427.957658)
			(xy 60.278077 -427.909326) (xy 60.302394 -427.887638) (xy 60.382912 -427.7233) (xy 60.387601 -427.712779)
			(xy 60.391095 -427.690023) (xy 60.387615 -427.667266) (xy 60.382912 -427.656752) (xy 60.301886 -427.491652)
			(xy 60.277617 -427.469962) (xy 60.234021 -427.421628) (xy 60.196648 -427.368336) (xy 60.166055 -427.310882)
			(xy 60.142701 -427.250126) (xy 60.126934 -427.186973) (xy 60.118989 -427.122369) (xy 60.118498 -427.089824)
			(xy 60.119217 -427.050499) (xy 60.130827 -426.972709) (xy 60.141612 -426.934884) (xy 60.141612 -426.41901)
			(xy 60.142115 -426.406924) (xy 60.149566 -426.383928) (xy 60.163744 -426.364351) (xy 60.183268 -426.350099)
			(xy 60.206236 -426.342562) (xy 60.21832 -426.342048) (xy 61.15812 -426.342048) (xy 61.170225 -426.342499)
			(xy 61.193244 -426.349997) (xy 61.212812 -426.364252) (xy 61.227008 -426.383863) (xy 61.234437 -426.406904)
			(xy 61.234828 -426.41901) (xy 61.234828 -427.289976) (xy 62.118494 -427.289976) (xy 62.118958 -427.257419)
			(xy 62.126908 -427.192791) (xy 62.142697 -427.12962) (xy 62.166089 -427.068853) (xy 62.196733 -427.0114)
			(xy 62.234169 -426.958123) (xy 62.277837 -426.909822) (xy 62.302136 -426.888148) (xy 62.382908 -426.723302)
			(xy 62.387595 -426.71278) (xy 62.39109 -426.690025) (xy 62.387611 -426.667268) (xy 62.382908 -426.656754)
			(xy 62.301882 -426.491654) (xy 62.277614 -426.469963) (xy 62.234017 -426.42163) (xy 62.196644 -426.368338)
			(xy 62.166052 -426.310884) (xy 62.142697 -426.250128) (xy 62.12693 -426.186975) (xy 62.118986 -426.122371)
			(xy 62.118494 -426.089826) (xy 62.119213 -426.050501) (xy 62.130824 -425.972711) (xy 62.141608 -425.934886)
			(xy 62.141608 -425.419012) (xy 62.142023 -425.406928) (xy 62.149489 -425.383943) (xy 62.163694 -425.364392)
			(xy 62.183247 -425.350188) (xy 62.206232 -425.342723) (xy 62.218316 -425.342304) (xy 63.158116 -425.342304)
			(xy 63.170193 -425.342751) (xy 63.193162 -425.350219) (xy 63.2127 -425.36442) (xy 63.226894 -425.383963)
			(xy 63.234353 -425.406935) (xy 63.234824 -425.419012) (xy 63.234824 -427.960536) (xy 63.234367 -427.972611)
			(xy 63.226896 -427.995577) (xy 63.212697 -428.015112) (xy 63.193159 -428.029306) (xy 63.170191 -428.03677)
			(xy 63.158116 -428.037244) (xy 62.218316 -428.037244) (xy 62.206246 -428.036723) (xy 62.183285 -428.029269)
			(xy 62.163751 -428.015086) (xy 62.149555 -427.995561) (xy 62.142085 -427.972606) (xy 62.141608 -427.960536)
			(xy 62.141608 -427.444916) (xy 62.130804 -427.407096) (xy 62.119201 -427.329303) (xy 62.118494 -427.289976)
			(xy 61.234828 -427.289976) (xy 61.234828 -428.28972) (xy 64.11849 -428.28972) (xy 64.119028 -428.257141)
			(xy 64.126999 -428.192471) (xy 64.142813 -428.129261) (xy 64.166231 -428.068456) (xy 64.196903 -428.010968)
			(xy 64.23437 -427.957658) (xy 64.278069 -427.909326) (xy 64.302386 -427.887638) (xy 64.382904 -427.7233)
			(xy 64.387593 -427.712779) (xy 64.391087 -427.690023) (xy 64.387607 -427.667266) (xy 64.382904 -427.656752)
			(xy 64.301878 -427.491652) (xy 64.277608 -427.469963) (xy 64.234012 -427.421629) (xy 64.196639 -427.368337)
			(xy 64.166047 -427.310883) (xy 64.142693 -427.250126) (xy 64.126926 -427.186974) (xy 64.118981 -427.122369)
			(xy 64.11849 -427.089824) (xy 64.119209 -427.050499) (xy 64.130819 -426.972709) (xy 64.141604 -426.934884)
			(xy 64.141604 -426.41901) (xy 64.142115 -426.406925) (xy 64.149565 -426.38393) (xy 64.163741 -426.364353)
			(xy 64.183263 -426.350101) (xy 64.206228 -426.342563) (xy 64.218312 -426.342048) (xy 65.158112 -426.342048)
			(xy 65.170216 -426.342505) (xy 65.193235 -426.350002) (xy 65.212804 -426.364255) (xy 65.227 -426.383864)
			(xy 65.234429 -426.406905) (xy 65.23482 -426.41901) (xy 65.23482 -427.289976) (xy 66.118486 -427.289976)
			(xy 66.118953 -427.257419) (xy 66.126902 -427.192792) (xy 66.142691 -427.129621) (xy 66.166083 -427.068853)
			(xy 66.196726 -427.0114) (xy 66.234162 -426.958124) (xy 66.277829 -426.909822) (xy 66.302128 -426.888148)
			(xy 66.3829 -426.723302) (xy 66.387588 -426.71278) (xy 66.391083 -426.690025) (xy 66.387603 -426.667268)
			(xy 66.3829 -426.656754) (xy 66.301874 -426.491654) (xy 66.277604 -426.469965) (xy 66.234008 -426.421631)
			(xy 66.196635 -426.368339) (xy 66.166043 -426.310885) (xy 66.142689 -426.250128) (xy 66.126922 -426.186976)
			(xy 66.118978 -426.122371) (xy 66.118486 -426.089826) (xy 66.119205 -426.050501) (xy 66.130816 -425.972711)
			(xy 66.1416 -425.934886) (xy 66.1416 -425.419012) (xy 66.142023 -425.406929) (xy 66.149488 -425.383946)
			(xy 66.163692 -425.364394) (xy 66.183242 -425.35019) (xy 66.206225 -425.342724) (xy 66.218308 -425.342304)
			(xy 67.158108 -425.342304) (xy 67.170192 -425.342706) (xy 67.193177 -425.350177) (xy 67.212729 -425.364386)
			(xy 67.226932 -425.383941) (xy 67.234397 -425.406928) (xy 67.234816 -425.419012) (xy 67.234816 -427.960536)
			(xy 67.234367 -427.972612) (xy 67.226895 -427.995579) (xy 67.212695 -428.015115) (xy 67.193154 -428.029308)
			(xy 67.170184 -428.036771) (xy 67.158108 -428.037244) (xy 66.218308 -428.037244) (xy 66.206237 -428.03673)
			(xy 66.183277 -428.029274) (xy 66.163743 -428.015089) (xy 66.149547 -427.995563) (xy 66.142077 -427.972606)
			(xy 66.1416 -427.960536) (xy 66.1416 -427.444916) (xy 66.130796 -427.407096) (xy 66.119192 -427.329303)
			(xy 66.118486 -427.289976) (xy 65.23482 -427.289976) (xy 65.23482 -428.28972) (xy 68.118482 -428.28972)
			(xy 68.119023 -428.257141) (xy 68.126994 -428.192472) (xy 68.142807 -428.129261) (xy 68.166225 -428.068456)
			(xy 68.196897 -428.010968) (xy 68.234363 -427.957658) (xy 68.278062 -427.909326) (xy 68.302378 -427.887638)
			(xy 68.382896 -427.7233) (xy 68.387585 -427.712779) (xy 68.39108 -427.690023) (xy 68.387599 -427.667266)
			(xy 68.382896 -427.656752) (xy 68.30187 -427.491652) (xy 68.277618 -427.469943) (xy 68.234018 -427.421614)
			(xy 68.196641 -427.368327) (xy 68.166045 -427.310876) (xy 68.142688 -427.250122) (xy 68.126919 -427.186972)
			(xy 68.118974 -427.122369) (xy 68.118482 -427.089824) (xy 68.119201 -427.050499) (xy 68.130812 -426.972709)
			(xy 68.141596 -426.934884) (xy 68.141596 -426.41901) (xy 68.142115 -426.406925) (xy 68.149564 -426.383932)
			(xy 68.163739 -426.364356) (xy 68.183258 -426.350104) (xy 68.206221 -426.342564) (xy 68.218304 -426.342048)
			(xy 69.158104 -426.342048) (xy 69.170208 -426.342512) (xy 69.193227 -426.350006) (xy 69.212795 -426.364257)
			(xy 69.226991 -426.383866) (xy 69.234421 -426.406905) (xy 69.234812 -426.41901) (xy 69.234812 -427.289976)
			(xy 70.118478 -427.289976) (xy 70.118947 -427.257419) (xy 70.126897 -427.192792) (xy 70.142685 -427.129621)
			(xy 70.166076 -427.068854) (xy 70.196719 -427.011401) (xy 70.234155 -426.958124) (xy 70.277821 -426.909822)
			(xy 70.30212 -426.888148) (xy 70.382892 -426.723302) (xy 70.38758 -426.71278) (xy 70.391076 -426.690025)
			(xy 70.387595 -426.667268) (xy 70.382892 -426.656754) (xy 70.301866 -426.491654) (xy 70.277615 -426.469945)
			(xy 70.234014 -426.421616) (xy 70.196637 -426.368329) (xy 70.166041 -426.310878) (xy 70.142684 -426.250124)
			(xy 70.126915 -426.186973) (xy 70.11897 -426.122371) (xy 70.118478 -426.089826) (xy 70.119198 -426.050501)
			(xy 70.130808 -425.972711) (xy 70.141592 -425.934886) (xy 70.141592 -425.419012) (xy 70.142023 -425.40693)
			(xy 70.149487 -425.383948) (xy 70.163689 -425.364397) (xy 70.183237 -425.350193) (xy 70.206218 -425.342725)
			(xy 70.2183 -425.342304) (xy 71.1581 -425.342304) (xy 71.170184 -425.342713) (xy 71.193169 -425.350182)
			(xy 71.21272 -425.364388) (xy 71.226924 -425.383942) (xy 71.234389 -425.406928) (xy 71.234808 -425.419012)
			(xy 71.234808 -427.960536) (xy 71.234367 -427.972612) (xy 71.226894 -427.995581) (xy 71.212692 -428.015117)
			(xy 71.193149 -428.029311) (xy 71.170177 -428.036772) (xy 71.1581 -428.037244) (xy 70.2183 -428.037244)
			(xy 70.206229 -428.036736) (xy 70.183268 -428.029278) (xy 70.163734 -428.015092) (xy 70.149538 -427.995564)
			(xy 70.142069 -427.972607) (xy 70.141592 -427.960536) (xy 70.141592 -427.444916) (xy 70.130788 -427.407096)
			(xy 70.119184 -427.329303) (xy 70.118478 -427.289976) (xy 69.234812 -427.289976) (xy 69.234812 -428.28972)
			(xy 72.118474 -428.28972) (xy 72.119018 -428.257141) (xy 72.126989 -428.192472) (xy 72.142801 -428.129262)
			(xy 72.166219 -428.068457) (xy 72.19689 -428.010969) (xy 72.234356 -427.957659) (xy 72.278054 -427.909326)
			(xy 72.30237 -427.887638) (xy 72.382888 -427.7233) (xy 72.387578 -427.712779) (xy 72.391073 -427.690023)
			(xy 72.387592 -427.667266) (xy 72.382888 -427.656752) (xy 72.301862 -427.491652) (xy 72.277609 -427.469945)
			(xy 72.234009 -427.421616) (xy 72.196632 -427.368328) (xy 72.166036 -427.310877) (xy 72.14268 -427.250122)
			(xy 72.126911 -427.186972) (xy 72.118966 -427.122369) (xy 72.118474 -427.089824) (xy 72.119193 -427.050499)
			(xy 72.130804 -426.972709) (xy 72.141588 -426.934884) (xy 72.141588 -426.41901) (xy 72.142017 -426.406916)
			(xy 72.149477 -426.383908) (xy 72.163671 -426.364324) (xy 72.183216 -426.350075) (xy 72.206204 -426.342551)
			(xy 72.218296 -426.342048) (xy 73.158096 -426.342048) (xy 73.170199 -426.342519) (xy 73.193218 -426.350011)
			(xy 73.212787 -426.36426) (xy 73.226983 -426.383867) (xy 73.234413 -426.406905) (xy 73.234804 -426.41901)
			(xy 73.234804 -427.289976) (xy 75.118468 -427.289976) (xy 75.118941 -427.257419) (xy 75.12689 -427.192792)
			(xy 75.142678 -427.129622) (xy 75.166069 -427.068854) (xy 75.196711 -427.011401) (xy 75.234146 -426.958124)
			(xy 75.277811 -426.909822) (xy 75.30211 -426.888148) (xy 75.382882 -426.723302) (xy 75.387571 -426.71278)
			(xy 75.391067 -426.690025) (xy 75.387586 -426.667268) (xy 75.382882 -426.656754) (xy 75.301856 -426.491654)
			(xy 75.277603 -426.469947) (xy 75.234003 -426.421618) (xy 75.196626 -426.36833) (xy 75.166031 -426.310879)
			(xy 75.142674 -426.250124) (xy 75.126905 -426.186974) (xy 75.11896 -426.122371) (xy 75.118468 -426.089826)
			(xy 75.119172 -426.0507) (xy 75.130644 -425.973293) (xy 75.141328 -425.935648) (xy 75.141328 -425.419012)
			(xy 75.141727 -425.406901) (xy 75.149227 -425.383869) (xy 75.163492 -425.364294) (xy 75.183119 -425.3501)
			(xy 75.206178 -425.342684) (xy 75.21829 -425.342304) (xy 76.15809 -425.342304) (xy 76.170175 -425.342815)
			(xy 76.19317 -425.350265) (xy 76.212747 -425.364441) (xy 76.226999 -425.383963) (xy 76.234537 -425.406928)
			(xy 76.235052 -425.419012) (xy 76.235052 -427.960536) (xy 76.234615 -427.972642) (xy 76.227112 -427.995661)
			(xy 76.212854 -428.015229) (xy 76.19324 -428.029424) (xy 76.170197 -428.036854) (xy 76.15809 -428.037244)
			(xy 75.21829 -428.037244) (xy 75.206198 -428.036801) (xy 75.183195 -428.029339) (xy 75.163614 -428.015147)
			(xy 75.149364 -427.995608) (xy 75.141835 -427.972626) (xy 75.141328 -427.960536) (xy 75.141328 -427.444154)
			(xy 75.130636 -427.40651) (xy 75.119162 -427.329103) (xy 75.118468 -427.289976) (xy 73.234804 -427.289976)
			(xy 73.234804 -428.28972) (xy 77.118464 -428.28972) (xy 77.118977 -428.25714) (xy 77.12695 -428.192469)
			(xy 77.142765 -428.129256) (xy 77.166187 -428.06845) (xy 77.196864 -428.010962) (xy 77.234335 -427.957654)
			(xy 77.278041 -427.909324) (xy 77.30236 -427.887638) (xy 77.382878 -427.7233) (xy 77.387568 -427.712779)
			(xy 77.391064 -427.690023) (xy 77.387582 -427.667266) (xy 77.382878 -427.656752) (xy 77.301852 -427.491652)
			(xy 77.277597 -427.469947) (xy 77.233997 -427.421617) (xy 77.196621 -427.368329) (xy 77.166026 -427.310878)
			(xy 77.142669 -427.250123) (xy 77.126901 -427.186972) (xy 77.118956 -427.122369) (xy 77.118464 -427.089824)
			(xy 77.119168 -427.050698) (xy 77.13064 -426.973291) (xy 77.141324 -426.935646) (xy 77.141324 -426.41901)
			(xy 77.14182 -426.406897) (xy 77.149303 -426.383857) (xy 77.163539 -426.364256) (xy 77.183135 -426.350014)
			(xy 77.206174 -426.342524) (xy 77.218286 -426.342048) (xy 78.158086 -426.342048) (xy 78.170209 -426.342472)
			(xy 78.193269 -426.349962) (xy 78.212885 -426.364212) (xy 78.227136 -426.383827) (xy 78.234627 -426.406887)
			(xy 78.235048 -426.41901) (xy 78.235048 -427.289976) (xy 79.11846 -427.289976) (xy 79.118936 -427.257419)
			(xy 79.126885 -427.192793) (xy 79.142672 -427.129622) (xy 79.166063 -427.068855) (xy 79.196705 -427.011402)
			(xy 79.234139 -426.958125) (xy 79.277804 -426.909822) (xy 79.302102 -426.888148) (xy 79.382874 -426.723302)
			(xy 79.387563 -426.71278) (xy 79.39106 -426.690025) (xy 79.387578 -426.667268) (xy 79.382874 -426.656754)
			(xy 79.301848 -426.491654) (xy 79.277593 -426.469949) (xy 79.233994 -426.421619) (xy 79.196617 -426.36833)
			(xy 79.166022 -426.310879) (xy 79.142666 -426.250125) (xy 79.126897 -426.186974) (xy 79.118952 -426.122371)
			(xy 79.11846 -426.089826) (xy 79.119165 -426.0507) (xy 79.130636 -425.973293) (xy 79.14132 -425.935648)
			(xy 79.14132 -425.419012) (xy 79.141727 -425.406902) (xy 79.149226 -425.383872) (xy 79.163489 -425.364297)
			(xy 79.183114 -425.350102) (xy 79.20617 -425.342685) (xy 79.218282 -425.342304) (xy 80.158082 -425.342304)
			(xy 80.170167 -425.342822) (xy 80.193161 -425.35027) (xy 80.212738 -425.364444) (xy 80.226991 -425.383965)
			(xy 80.234529 -425.406929) (xy 80.235044 -425.419012) (xy 80.235044 -427.960536) (xy 80.234615 -427.972642)
			(xy 80.227111 -427.995663) (xy 80.212851 -428.015232) (xy 80.193235 -428.029427) (xy 80.17019 -428.036855)
			(xy 80.158082 -428.037244) (xy 79.218282 -428.037244) (xy 79.20619 -428.036808) (xy 79.183186 -428.029344)
			(xy 79.163605 -428.01515) (xy 79.149355 -427.995609) (xy 79.141827 -427.972627) (xy 79.14132 -427.960536)
			(xy 79.14132 -427.444154) (xy 79.130628 -427.40651) (xy 79.119154 -427.329103) (xy 79.11846 -427.289976)
			(xy 78.235048 -427.289976) (xy 78.235048 -428.28972) (xy 81.118456 -428.28972) (xy 81.118972 -428.25714)
			(xy 81.126944 -428.192469) (xy 81.14276 -428.129257) (xy 81.166181 -428.068451) (xy 81.196857 -428.010963)
			(xy 81.234328 -427.957655) (xy 81.278033 -427.909325) (xy 81.302352 -427.887638) (xy 81.38287 -427.7233)
			(xy 81.387561 -427.712779) (xy 81.391057 -427.690023) (xy 81.387575 -427.667266) (xy 81.38287 -427.656752)
			(xy 81.301844 -427.491652) (xy 81.277587 -427.469949) (xy 81.233988 -427.421619) (xy 81.196612 -427.36833)
			(xy 81.166017 -427.310878) (xy 81.142661 -427.250123) (xy 81.126893 -427.186972) (xy 81.118948 -427.122369)
			(xy 81.118456 -427.089824) (xy 81.11916 -427.050698) (xy 81.130632 -426.973291) (xy 81.141316 -426.935646)
			(xy 81.141316 -426.41901) (xy 81.14182 -426.406898) (xy 81.149302 -426.383859) (xy 81.163536 -426.364259)
			(xy 81.18313 -426.350016) (xy 81.206166 -426.342525) (xy 81.218278 -426.342048) (xy 82.158078 -426.342048)
			(xy 82.170201 -426.342479) (xy 82.19326 -426.349966) (xy 82.212877 -426.364215) (xy 82.227128 -426.383829)
			(xy 82.234619 -426.406887) (xy 82.23504 -426.41901) (xy 82.23504 -427.289976) (xy 83.118452 -427.289976)
			(xy 83.11893 -427.257419) (xy 83.126879 -427.192793) (xy 83.142667 -427.129623) (xy 83.166057 -427.068856)
			(xy 83.196698 -427.011403) (xy 83.234132 -426.958125) (xy 83.277796 -426.909823) (xy 83.302094 -426.888148)
			(xy 83.382866 -426.723302) (xy 83.387551 -426.712779) (xy 83.391043 -426.690025) (xy 83.387566 -426.667269)
			(xy 83.382866 -426.656754) (xy 83.30184 -426.491654) (xy 83.277583 -426.469951) (xy 83.233984 -426.42162)
			(xy 83.196608 -426.368331) (xy 83.166013 -426.31088) (xy 83.142657 -426.250125) (xy 83.126889 -426.186974)
			(xy 83.118944 -426.122371) (xy 83.118452 -426.089826) (xy 83.119157 -426.0507) (xy 83.130628 -425.973293)
			(xy 83.141312 -425.935648) (xy 83.141312 -425.419012) (xy 83.141727 -425.406903) (xy 83.149224 -425.383874)
			(xy 83.163486 -425.364299) (xy 83.183109 -425.350105) (xy 83.206163 -425.342686) (xy 83.218274 -425.342304)
			(xy 84.158074 -425.342304) (xy 84.170159 -425.342829) (xy 84.193152 -425.350274) (xy 84.21273 -425.364447)
			(xy 84.226982 -425.383966) (xy 84.234521 -425.406929) (xy 84.235036 -425.419012) (xy 84.235036 -427.960536)
			(xy 84.234615 -427.972643) (xy 84.22711 -427.995665) (xy 84.212848 -428.015235) (xy 84.19323 -428.029429)
			(xy 84.170183 -428.036856) (xy 84.158074 -428.037244) (xy 83.218274 -428.037244) (xy 83.206181 -428.036815)
			(xy 83.183177 -428.029349) (xy 83.163596 -428.015153) (xy 83.149347 -427.995611) (xy 83.141819 -427.972627)
			(xy 83.141312 -427.960536) (xy 83.141312 -427.444154) (xy 83.13062 -427.40651) (xy 83.119146 -427.329103)
			(xy 83.118452 -427.289976) (xy 82.23504 -427.289976) (xy 82.23504 -428.28972) (xy 85.118448 -428.28972)
			(xy 85.118967 -428.25714) (xy 85.126939 -428.192469) (xy 85.142754 -428.129257) (xy 85.166175 -428.068452)
			(xy 85.196851 -428.010964) (xy 85.234321 -427.957655) (xy 85.278025 -427.909325) (xy 85.302344 -427.887638)
			(xy 85.382862 -427.7233) (xy 85.387548 -427.712778) (xy 85.39104 -427.690023) (xy 85.387562 -427.667267)
			(xy 85.382862 -427.656752) (xy 85.301836 -427.491652) (xy 85.277578 -427.469951) (xy 85.233979 -427.42162)
			(xy 85.196603 -427.36833) (xy 85.166008 -427.310879) (xy 85.142653 -427.250123) (xy 85.126884 -427.186972)
			(xy 85.11894 -427.122369) (xy 85.118448 -427.089824) (xy 85.119153 -427.050698) (xy 85.130624 -426.973291)
			(xy 85.141308 -426.935646) (xy 85.141308 -426.41901) (xy 85.14182 -426.406899) (xy 85.149301 -426.383861)
			(xy 85.163533 -426.364262) (xy 85.183125 -426.350019) (xy 85.206159 -426.342526) (xy 85.21827 -426.342048)
			(xy 86.15807 -426.342048) (xy 86.170192 -426.342486) (xy 86.193252 -426.349971) (xy 86.212868 -426.364218)
			(xy 86.22712 -426.38383) (xy 86.234611 -426.406888) (xy 86.235032 -426.41901) (xy 86.235032 -427.289976)
			(xy 87.118444 -427.289976) (xy 87.118925 -427.257419) (xy 87.126874 -427.192793) (xy 87.142661 -427.129623)
			(xy 87.166051 -427.068856) (xy 87.196692 -427.011403) (xy 87.234125 -426.958126) (xy 87.277788 -426.909823)
			(xy 87.302086 -426.888148) (xy 87.382858 -426.723302) (xy 87.387543 -426.71278) (xy 87.391036 -426.690025)
			(xy 87.387558 -426.667269) (xy 87.382858 -426.656754) (xy 87.301832 -426.491654) (xy 87.277574 -426.469952)
			(xy 87.233975 -426.421622) (xy 87.196599 -426.368332) (xy 87.166005 -426.310881) (xy 87.142649 -426.250125)
			(xy 87.126881 -426.186974) (xy 87.118936 -426.122371) (xy 87.118444 -426.089826) (xy 87.119149 -426.0507)
			(xy 87.13062 -425.973293) (xy 87.141304 -425.935648) (xy 87.141304 -425.419012) (xy 87.141727 -425.406903)
			(xy 87.149223 -425.383876) (xy 87.163483 -425.364302) (xy 87.183104 -425.350107) (xy 87.206156 -425.342687)
			(xy 87.218266 -425.342304) (xy 88.158066 -425.342304) (xy 88.17015 -425.342836) (xy 88.193144 -425.350279)
			(xy 88.212721 -425.36445) (xy 88.226974 -425.383968) (xy 88.234513 -425.40693) (xy 88.235028 -425.419012)
			(xy 88.235028 -427.960536) (xy 88.234615 -427.972644) (xy 88.227109 -427.995668) (xy 88.212845 -428.015238)
			(xy 88.193225 -428.029432) (xy 88.170175 -428.036857) (xy 88.158066 -428.037244) (xy 87.218266 -428.037244)
			(xy 87.206173 -428.036821) (xy 87.183169 -428.029353) (xy 87.163588 -428.015156) (xy 87.149339 -427.995612)
			(xy 87.141811 -427.972628) (xy 87.141304 -427.960536) (xy 87.141304 -427.444154) (xy 87.130611 -427.40651)
			(xy 87.119138 -427.329103) (xy 87.118444 -427.289976) (xy 86.235032 -427.289976) (xy 86.235032 -428.28972)
			(xy 89.11844 -428.28972) (xy 89.118962 -428.25714) (xy 89.126934 -428.192469) (xy 89.142748 -428.129258)
			(xy 89.166169 -428.068452) (xy 89.196844 -428.010964) (xy 89.234314 -427.957655) (xy 89.278018 -427.909325)
			(xy 89.302336 -427.887638) (xy 89.382854 -427.7233) (xy 89.387541 -427.712778) (xy 89.391033 -427.690023)
			(xy 89.387555 -427.667267) (xy 89.382854 -427.656752) (xy 89.301828 -427.491652) (xy 89.277568 -427.469952)
			(xy 89.23397 -427.421621) (xy 89.196594 -427.368331) (xy 89.166 -427.310879) (xy 89.142644 -427.250124)
			(xy 89.126876 -427.186972) (xy 89.118931 -427.122369) (xy 89.11844 -427.089824) (xy 89.119145 -427.050698)
			(xy 89.130616 -426.973291) (xy 89.1413 -426.935646) (xy 89.1413 -426.41901) (xy 89.14182 -426.4069)
			(xy 89.1493 -426.383863) (xy 89.163531 -426.364265) (xy 89.18312 -426.350022) (xy 89.206152 -426.342527)
			(xy 89.218262 -426.342048) (xy 90.158062 -426.342048) (xy 90.170184 -426.342492) (xy 90.193243 -426.349975)
			(xy 90.21286 -426.36422) (xy 90.227112 -426.383832) (xy 90.234603 -426.406888) (xy 90.235024 -426.41901)
			(xy 90.235024 -427.289976) (xy 125.238002 -427.289976) (xy 125.238092 -427.275402) (xy 125.239747 -427.246301)
			(xy 125.241304 -427.23181) (xy 125.241304 -426.147992) (xy 125.239761 -426.1335) (xy 125.238108 -426.1044)
			(xy 125.238002 -426.089826) (xy 125.238097 -426.075252) (xy 125.239748 -426.046151) (xy 125.241304 -426.03166)
			(xy 125.241304 -425.419012) (xy 125.241727 -425.406903) (xy 125.249223 -425.383876) (xy 125.263483 -425.364302)
			(xy 125.283104 -425.350107) (xy 125.306156 -425.342687) (xy 125.318266 -425.342304) (xy 126.258066 -425.342304)
			(xy 126.27015 -425.342836) (xy 126.293144 -425.350279) (xy 126.312721 -425.36445) (xy 126.326974 -425.383968)
			(xy 126.334513 -425.40693) (xy 126.335028 -425.419012) (xy 126.335028 -427.960536) (xy 126.334615 -427.972644)
			(xy 126.327109 -427.995668) (xy 126.312845 -428.015238) (xy 126.293225 -428.029432) (xy 126.270175 -428.036857)
			(xy 126.258066 -428.037244) (xy 125.318266 -428.037244) (xy 125.306173 -428.036821) (xy 125.283169 -428.029353)
			(xy 125.263588 -428.015156) (xy 125.249339 -427.995612) (xy 125.241811 -427.972628) (xy 125.241304 -427.960536)
			(xy 125.241304 -427.348142) (xy 125.239757 -427.33365) (xy 125.238107 -427.30455) (xy 125.238002 -427.289976)
			(xy 90.235024 -427.289976) (xy 90.235024 -428.960534) (xy 90.234669 -428.972662) (xy 90.227162 -428.995729)
			(xy 90.212895 -429.015347) (xy 90.193264 -429.029595) (xy 90.170191 -429.03708) (xy 90.158062 -429.037496)
			(xy 89.218262 -429.037496) (xy 89.206149 -429.037021) (xy 89.18311 -429.029528) (xy 89.163512 -429.015285)
			(xy 89.14927 -428.995686) (xy 89.141778 -428.972647) (xy 89.1413 -428.960534) (xy 89.1413 -428.443898)
			(xy 89.130617 -428.406252) (xy 89.119137 -428.328846) (xy 89.11844 -428.28972) (xy 86.235032 -428.28972)
			(xy 86.235032 -428.960534) (xy 86.234617 -428.972653) (xy 86.227117 -428.995703) (xy 86.212861 -429.015307)
			(xy 86.193245 -429.029546) (xy 86.17019 -429.037027) (xy 86.15807 -429.037496) (xy 85.21827 -429.037496)
			(xy 85.206157 -429.037014) (xy 85.183119 -429.029523) (xy 85.16352 -429.015282) (xy 85.149279 -428.995685)
			(xy 85.141786 -428.972647) (xy 85.141308 -428.960534) (xy 85.141308 -428.443898) (xy 85.130625 -428.406252)
			(xy 85.119145 -428.328846) (xy 85.118448 -428.28972) (xy 82.23504 -428.28972) (xy 82.23504 -428.960534)
			(xy 82.234617 -428.972653) (xy 82.227118 -428.995701) (xy 82.212864 -429.015304) (xy 82.19325 -429.029543)
			(xy 82.170197 -429.037026) (xy 82.158078 -429.037496) (xy 81.218278 -429.037496) (xy 81.206166 -429.037008)
			(xy 81.183127 -429.029519) (xy 81.163529 -429.01528) (xy 81.149287 -428.995683) (xy 81.141794 -428.972646)
			(xy 81.141316 -428.960534) (xy 81.141316 -428.443898) (xy 81.130633 -428.406252) (xy 81.119153 -428.328846)
			(xy 81.118456 -428.28972) (xy 78.235048 -428.28972) (xy 78.235048 -428.960534) (xy 78.234617 -428.972652)
			(xy 78.227119 -428.995698) (xy 78.212867 -429.015301) (xy 78.193255 -429.029541) (xy 78.170204 -429.037025)
			(xy 78.158086 -429.037496) (xy 77.218286 -429.037496) (xy 77.206174 -429.037001) (xy 77.183136 -429.029514)
			(xy 77.163537 -429.015277) (xy 77.149295 -428.995682) (xy 77.141802 -428.972646) (xy 77.141324 -428.960534)
			(xy 77.141324 -428.443898) (xy 77.130641 -428.406252) (xy 77.119161 -428.328846) (xy 77.118464 -428.28972)
			(xy 73.234804 -428.28972) (xy 73.234804 -428.960534) (xy 73.234323 -428.972621) (xy 73.226862 -428.995615)
			(xy 73.212677 -429.015191) (xy 73.19315 -429.029442) (xy 73.170181 -429.036981) (xy 73.158096 -429.037496)
			(xy 72.218296 -429.037496) (xy 72.206187 -429.037087) (xy 72.183158 -429.029586) (xy 72.163585 -429.015323)
			(xy 72.149391 -428.995699) (xy 72.141971 -428.972645) (xy 72.141588 -428.960534) (xy 72.141588 -428.44466)
			(xy 72.130793 -428.406837) (xy 72.119184 -428.329046) (xy 72.118474 -428.28972) (xy 69.234812 -428.28972)
			(xy 69.234812 -428.960534) (xy 69.234421 -428.97263) (xy 69.226949 -428.99564) (xy 69.212744 -429.015223)
			(xy 69.193192 -429.029471) (xy 69.170199 -429.036994) (xy 69.158104 -429.037496) (xy 68.218304 -429.037496)
			(xy 68.206195 -429.03708) (xy 68.183167 -429.029582) (xy 68.163593 -429.01532) (xy 68.149399 -428.995698)
			(xy 68.141979 -428.972644) (xy 68.141596 -428.960534) (xy 68.141596 -428.44466) (xy 68.130801 -428.406837)
			(xy 68.119192 -428.329046) (xy 68.118482 -428.28972) (xy 65.23482 -428.28972) (xy 65.23482 -428.960534)
			(xy 65.234421 -428.972629) (xy 65.22695 -428.995638) (xy 65.212747 -429.015221) (xy 65.193197 -429.029469)
			(xy 65.170206 -429.036993) (xy 65.158112 -429.037496) (xy 64.218312 -429.037496) (xy 64.206203 -429.037073)
			(xy 64.183176 -429.029577) (xy 64.163602 -429.015317) (xy 64.149407 -428.995696) (xy 64.141987 -428.972644)
			(xy 64.141604 -428.960534) (xy 64.141604 -428.44466) (xy 64.130809 -428.406837) (xy 64.1192 -428.329046)
			(xy 64.11849 -428.28972) (xy 61.234828 -428.28972) (xy 61.234828 -428.960534) (xy 61.234421 -428.972629)
			(xy 61.226951 -428.995636) (xy 61.21275 -429.015218) (xy 61.193202 -429.029466) (xy 61.170213 -429.036992)
			(xy 61.15812 -429.037496) (xy 60.21832 -429.037496) (xy 60.206212 -429.037066) (xy 60.183185 -429.029572)
			(xy 60.163611 -429.015314) (xy 60.149416 -428.995695) (xy 60.141995 -428.972643) (xy 60.141612 -428.960534)
			(xy 60.141612 -428.44466) (xy 60.130818 -428.406837) (xy 60.119208 -428.329046) (xy 60.118498 -428.28972)
			(xy 49.0054 -428.28972) (xy 48.932448 -428.365522) (xy 48.780383 -428.51187) (xy 48.622824 -428.652286)
			(xy 48.460002 -428.786564) (xy 48.292156 -428.914507) (xy 48.119534 -429.035927) (xy 47.942387 -429.150646)
			(xy 47.760976 -429.258496) (xy 47.575567 -429.359318) (xy 47.386432 -429.452965) (xy 47.19385 -429.539298)
			(xy 46.998102 -429.618192) (xy 46.799475 -429.68953) (xy 46.598262 -429.753207) (xy 46.394758 -429.809131)
			(xy 46.189261 -429.857219) (xy 45.982073 -429.897401) (xy 45.773498 -429.929618) (xy 45.563841 -429.953821)
			(xy 45.353412 -429.969977) (xy 45.142518 -429.978061) (xy 44.93147 -429.978061) (xy 44.720576 -429.969977)
			(xy 44.510147 -429.953821) (xy 44.30049 -429.929618) (xy 44.091915 -429.897401) (xy 43.884727 -429.857219)
			(xy 43.67923 -429.809131) (xy 43.475726 -429.753207) (xy 43.274513 -429.68953) (xy 43.075886 -429.618192)
			(xy 42.880138 -429.539298) (xy 42.687556 -429.452965) (xy 42.498421 -429.359318) (xy 42.313012 -429.258496)
			(xy 42.131601 -429.150646) (xy 41.954454 -429.035927) (xy 41.781832 -428.914507) (xy 41.613986 -428.786564)
			(xy 41.451164 -428.652286) (xy 41.293605 -428.51187) (xy 41.14154 -428.365522) (xy 40.995192 -428.213457)
			(xy 40.854776 -428.055898) (xy 40.720498 -427.893076) (xy 40.592555 -427.72523) (xy 40.471135 -427.552608)
			(xy 40.356416 -427.375461) (xy 40.248566 -427.19405) (xy 40.147744 -427.008641) (xy 40.054097 -426.819506)
			(xy 39.967764 -426.626924) (xy 39.88887 -426.431176) (xy 39.817532 -426.232549) (xy 39.753855 -426.031336)
			(xy 39.697931 -425.827832) (xy 39.649843 -425.622335) (xy 39.609661 -425.415147) (xy 39.577444 -425.206572)
			(xy 39.553241 -424.996915) (xy 39.537085 -424.786486) (xy 39.529001 -424.575592) (xy 39.528496 -424.470068)
			(xy 7.00913 -424.470068) (xy 7.00913 -430.889918) (xy 58.13806 -430.889918) (xy 58.138169 -430.874832)
			(xy 58.139951 -430.844714) (xy 58.141616 -430.82972) (xy 58.141616 -429.749966) (xy 58.139951 -429.734972)
			(xy 58.13817 -429.704854) (xy 58.13806 -429.689768) (xy 58.138174 -429.674682) (xy 58.139952 -429.644564)
			(xy 58.141616 -429.62957) (xy 58.141616 -429.018954) (xy 58.142068 -429.006864) (xy 58.149534 -428.983866)
			(xy 58.163726 -428.964289) (xy 58.18326 -428.950039) (xy 58.206236 -428.942504) (xy 58.218324 -428.941992)
			(xy 59.158124 -428.941992) (xy 59.170233 -428.942396) (xy 59.19326 -428.949901) (xy 59.212832 -428.964166)
			(xy 59.227026 -428.983789) (xy 59.234448 -429.006843) (xy 59.234832 -429.018954) (xy 59.234832 -431.560478)
			(xy 59.234373 -431.572569) (xy 59.226919 -431.595574) (xy 59.212732 -431.615156) (xy 59.193194 -431.629407)
			(xy 59.170214 -431.636934) (xy 59.158124 -431.63744) (xy 58.218324 -431.63744) (xy 58.20622 -431.636964)
			(xy 58.183201 -431.629476) (xy 58.163631 -431.615228) (xy 58.149434 -431.595622) (xy 58.142005 -431.572583)
			(xy 58.141616 -431.560478) (xy 58.141616 -430.950116) (xy 58.139947 -430.935123) (xy 58.138169 -430.905004)
			(xy 58.13806 -430.889918) (xy 7.00913 -430.889918) (xy 7.00913 -431.889916) (xy 60.138056 -431.889916)
			(xy 60.138165 -431.87483) (xy 60.139947 -431.844712) (xy 60.141612 -431.829718) (xy 60.141612 -430.749964)
			(xy 60.139947 -430.73497) (xy 60.138166 -430.704852) (xy 60.138056 -430.689766) (xy 60.13817 -430.67468)
			(xy 60.139948 -430.644562) (xy 60.141612 -430.629568) (xy 60.141612 -430.018952) (xy 60.142024 -430.006873)
			(xy 60.149502 -429.983901) (xy 60.163711 -429.964363) (xy 60.183262 -429.950171) (xy 60.206241 -429.942713)
			(xy 60.21832 -429.942244) (xy 61.15812 -429.942244) (xy 61.170191 -429.942747) (xy 61.19315 -429.950209)
			(xy 61.212683 -429.964397) (xy 61.226878 -429.983924) (xy 61.234349 -430.006881) (xy 61.234828 -430.018952)
			(xy 61.234828 -430.889918) (xy 62.138052 -430.889918) (xy 62.138161 -430.874832) (xy 62.139943 -430.844714)
			(xy 62.141608 -430.82972) (xy 62.141608 -429.749966) (xy 62.139943 -429.734972) (xy 62.138162 -429.704854)
			(xy 62.138052 -429.689768) (xy 62.138166 -429.674682) (xy 62.139944 -429.644564) (xy 62.141608 -429.62957)
			(xy 62.141608 -429.018954) (xy 62.142068 -429.006865) (xy 62.149533 -428.983868) (xy 62.163723 -428.964292)
			(xy 62.183255 -428.950042) (xy 62.206229 -428.942505) (xy 62.218316 -428.941992) (xy 63.158116 -428.941992)
			(xy 63.170225 -428.942402) (xy 63.193251 -428.949905) (xy 63.212824 -428.964169) (xy 63.227018 -428.983791)
			(xy 63.23444 -429.006844) (xy 63.234824 -429.018954) (xy 63.234824 -431.560478) (xy 63.234373 -431.57257)
			(xy 63.226918 -431.595576) (xy 63.212729 -431.615159) (xy 63.193189 -431.629409) (xy 63.170206 -431.636935)
			(xy 63.158116 -431.63744) (xy 62.218316 -431.63744) (xy 62.206212 -431.63697) (xy 62.183192 -431.62948)
			(xy 62.163622 -431.615231) (xy 62.149426 -431.595623) (xy 62.141997 -431.572583) (xy 62.141608 -431.560478)
			(xy 62.141608 -430.950116) (xy 62.139939 -430.935123) (xy 62.138161 -430.905004) (xy 62.138052 -430.889918)
			(xy 61.234828 -430.889918) (xy 61.234828 -431.889916) (xy 64.138048 -431.889916) (xy 64.138157 -431.87483)
			(xy 64.139939 -431.844712) (xy 64.141604 -431.829718) (xy 64.141604 -430.749964) (xy 64.139939 -430.73497)
			(xy 64.138158 -430.704852) (xy 64.138048 -430.689766) (xy 64.138162 -430.67468) (xy 64.13994 -430.644562)
			(xy 64.141604 -430.629568) (xy 64.141604 -430.018952) (xy 64.142023 -430.006874) (xy 64.149501 -429.983903)
			(xy 64.163708 -429.964366) (xy 64.183257 -429.950173) (xy 64.206233 -429.942714) (xy 64.218312 -429.942244)
			(xy 65.158112 -429.942244) (xy 65.170182 -429.942753) (xy 65.193142 -429.950213) (xy 65.212674 -429.9644)
			(xy 65.22687 -429.983926) (xy 65.234341 -430.006882) (xy 65.23482 -430.018952) (xy 65.23482 -430.889918)
			(xy 66.138044 -430.889918) (xy 66.138153 -430.874832) (xy 66.139935 -430.844714) (xy 66.1416 -430.82972)
			(xy 66.1416 -429.749966) (xy 66.139935 -429.734972) (xy 66.138154 -429.704854) (xy 66.138044 -429.689768)
			(xy 66.138158 -429.674682) (xy 66.139936 -429.644564) (xy 66.1416 -429.62957) (xy 66.1416 -429.018954)
			(xy 66.142067 -429.006866) (xy 66.149532 -428.983871) (xy 66.16372 -428.964295) (xy 66.18325 -428.950044)
			(xy 66.206222 -428.942507) (xy 66.218308 -428.941992) (xy 67.158108 -428.941992) (xy 67.170217 -428.942409)
			(xy 67.193243 -428.94991) (xy 67.212815 -428.964172) (xy 67.22701 -428.983792) (xy 67.234432 -429.006844)
			(xy 67.234816 -429.018954) (xy 67.234816 -431.560478) (xy 67.234373 -431.572571) (xy 67.226917 -431.595578)
			(xy 67.212726 -431.615162) (xy 67.193184 -431.629412) (xy 67.170199 -431.636937) (xy 67.158108 -431.63744)
			(xy 66.218308 -431.63744) (xy 66.206204 -431.636978) (xy 66.183183 -431.629485) (xy 66.163613 -431.615234)
			(xy 66.149417 -431.595625) (xy 66.141989 -431.572584) (xy 66.1416 -431.560478) (xy 66.1416 -430.950116)
			(xy 66.139931 -430.935123) (xy 66.138153 -430.905004) (xy 66.138044 -430.889918) (xy 65.23482 -430.889918)
			(xy 65.23482 -431.889916) (xy 68.13804 -431.889916) (xy 68.138151 -431.87483) (xy 68.139933 -431.844712)
			(xy 68.141596 -431.829718) (xy 68.141596 -430.749964) (xy 68.139931 -430.73497) (xy 68.13815 -430.704852)
			(xy 68.13804 -430.689766) (xy 68.138154 -430.67468) (xy 68.139932 -430.644562) (xy 68.141596 -430.629568)
			(xy 68.141596 -430.018952) (xy 68.142023 -430.006875) (xy 68.149499 -429.983905) (xy 68.163705 -429.964368)
			(xy 68.183252 -429.950176) (xy 68.206226 -429.942715) (xy 68.218304 -429.942244) (xy 69.158104 -429.942244)
			(xy 69.170174 -429.94276) (xy 69.193133 -429.950218) (xy 69.212666 -429.964403) (xy 69.226862 -429.983927)
			(xy 69.234333 -430.006882) (xy 69.234812 -430.018952) (xy 69.234812 -430.889918) (xy 70.138036 -430.889918)
			(xy 70.138147 -430.874832) (xy 70.139929 -430.844714) (xy 70.141592 -430.82972) (xy 70.141592 -429.749966)
			(xy 70.139927 -429.734972) (xy 70.138146 -429.704854) (xy 70.138036 -429.689768) (xy 70.138152 -429.674683)
			(xy 70.13993 -429.644564) (xy 70.141592 -429.62957) (xy 70.141592 -429.018954) (xy 70.142067 -429.006867)
			(xy 70.149531 -428.983873) (xy 70.163717 -428.964298) (xy 70.183245 -428.950047) (xy 70.206214 -428.942508)
			(xy 70.2183 -428.941992) (xy 71.1581 -428.941992) (xy 71.170208 -428.942416) (xy 71.193234 -428.949914)
			(xy 71.212807 -428.964174) (xy 71.227001 -428.983794) (xy 71.234424 -429.006845) (xy 71.234808 -429.018954)
			(xy 71.234808 -431.560478) (xy 71.234275 -431.572562) (xy 71.22683 -431.595553) (xy 71.212659 -431.61513)
			(xy 71.193142 -431.629383) (xy 71.170182 -431.636924) (xy 71.1581 -431.63744) (xy 70.2183 -431.63744)
			(xy 70.206195 -431.636984) (xy 70.183175 -431.62949) (xy 70.163605 -431.615237) (xy 70.149409 -431.595626)
			(xy 70.141981 -431.572584) (xy 70.141592 -431.560478) (xy 70.141592 -430.950116) (xy 70.139923 -430.935123)
			(xy 70.138145 -430.905004) (xy 70.138036 -430.889918) (xy 69.234812 -430.889918) (xy 69.234812 -431.889916)
			(xy 72.138032 -431.889916) (xy 72.138143 -431.87483) (xy 72.139925 -431.844712) (xy 72.141588 -431.829718)
			(xy 72.141588 -430.749964) (xy 72.139923 -430.73497) (xy 72.138142 -430.704852) (xy 72.138032 -430.689766)
			(xy 72.138148 -430.674681) (xy 72.139926 -430.644562) (xy 72.141588 -430.629568) (xy 72.141588 -430.018952)
			(xy 72.142023 -430.006875) (xy 72.149498 -429.983907) (xy 72.163703 -429.964371) (xy 72.183247 -429.950178)
			(xy 72.206219 -429.942716) (xy 72.218296 -429.942244) (xy 73.158096 -429.942244) (xy 73.170166 -429.942767)
			(xy 73.193124 -429.950222) (xy 73.212657 -429.964406) (xy 73.226854 -429.983929) (xy 73.234325 -430.006883)
			(xy 73.234804 -430.018952) (xy 73.234804 -430.889918) (xy 75.138026 -430.889918) (xy 75.13812 -430.875344)
			(xy 75.139772 -430.846243) (xy 75.141328 -430.831752) (xy 75.141328 -429.747934) (xy 75.13978 -429.733442)
			(xy 75.13813 -429.704342) (xy 75.138026 -429.689768) (xy 75.138125 -429.675194) (xy 75.139774 -429.646093)
			(xy 75.141328 -429.631602) (xy 75.141328 -429.018954) (xy 75.141772 -429.006838) (xy 75.149271 -428.983795)
			(xy 75.163521 -428.964195) (xy 75.183127 -428.949955) (xy 75.206174 -428.942467) (xy 75.21829 -428.941992)
			(xy 76.15809 -428.941992) (xy 76.170199 -428.94252) (xy 76.193235 -428.949999) (xy 76.212832 -428.964228)
			(xy 76.227076 -428.983815) (xy 76.234572 -429.006845) (xy 76.235052 -429.018954) (xy 76.235052 -431.560478)
			(xy 76.234621 -431.572601) (xy 76.227134 -431.59566) (xy 76.212885 -431.615277) (xy 76.193271 -431.629528)
			(xy 76.170213 -431.637019) (xy 76.15809 -431.63744) (xy 75.21829 -431.63744) (xy 75.206165 -431.637048)
			(xy 75.183102 -431.62955) (xy 75.163485 -431.615292) (xy 75.149235 -431.59567) (xy 75.141747 -431.572604)
			(xy 75.141328 -431.560478) (xy 75.141328 -430.948084) (xy 75.139785 -430.933592) (xy 75.138132 -430.904492)
			(xy 75.138026 -430.889918) (xy 73.234804 -430.889918) (xy 73.234804 -431.889916) (xy 77.138022 -431.889916)
			(xy 77.138116 -431.875342) (xy 77.139768 -431.846241) (xy 77.141324 -431.83175) (xy 77.141324 -430.747932)
			(xy 77.139776 -430.73344) (xy 77.138126 -430.70434) (xy 77.138022 -430.689766) (xy 77.138121 -430.675192)
			(xy 77.13977 -430.646091) (xy 77.141324 -430.6316) (xy 77.141324 -430.018952) (xy 77.141676 -430.006838)
			(xy 77.149191 -429.983805) (xy 77.163469 -429.964231) (xy 77.183105 -429.950039) (xy 77.20617 -429.942624)
			(xy 77.218286 -429.942244) (xy 78.158086 -429.942244) (xy 78.170175 -429.942719) (xy 78.193176 -429.950173)
			(xy 78.212757 -429.964357) (xy 78.227007 -429.983889) (xy 78.234539 -430.006864) (xy 78.235048 -430.018952)
			(xy 78.235048 -430.889918) (xy 79.138018 -430.889918) (xy 79.138112 -430.875344) (xy 79.139764 -430.846243)
			(xy 79.14132 -430.831752) (xy 79.14132 -429.747934) (xy 79.139772 -429.733442) (xy 79.138122 -429.704342)
			(xy 79.138018 -429.689768) (xy 79.138117 -429.675194) (xy 79.139766 -429.646093) (xy 79.14132 -429.631602)
			(xy 79.14132 -429.018954) (xy 79.141772 -429.006839) (xy 79.14927 -428.983797) (xy 79.163518 -428.964198)
			(xy 79.183122 -428.949957) (xy 79.206167 -428.942468) (xy 79.218282 -428.941992) (xy 80.158082 -428.941992)
			(xy 80.170191 -428.942526) (xy 80.193226 -428.950003) (xy 80.212824 -428.964231) (xy 80.227068 -428.983817)
			(xy 80.234563 -429.006845) (xy 80.235044 -429.018954) (xy 80.235044 -431.560478) (xy 80.234621 -431.572601)
			(xy 80.227133 -431.595663) (xy 80.212882 -431.61528) (xy 80.193266 -431.629531) (xy 80.170205 -431.63702)
			(xy 80.158082 -431.63744) (xy 79.218282 -431.63744) (xy 79.206156 -431.637055) (xy 79.183093 -431.629555)
			(xy 79.163476 -431.615295) (xy 79.149227 -431.595671) (xy 79.141739 -431.572604) (xy 79.14132 -431.560478)
			(xy 79.14132 -430.948084) (xy 79.139777 -430.933592) (xy 79.138124 -430.904492) (xy 79.138018 -430.889918)
			(xy 78.235048 -430.889918) (xy 78.235048 -431.889916) (xy 81.138014 -431.889916) (xy 81.138108 -431.875342)
			(xy 81.13976 -431.846241) (xy 81.141316 -431.83175) (xy 81.141316 -430.747932) (xy 81.139768 -430.73344)
			(xy 81.138118 -430.70434) (xy 81.138014 -430.689766) (xy 81.138112 -430.675192) (xy 81.139761 -430.646091)
			(xy 81.141316 -430.6316) (xy 81.141316 -430.018952) (xy 81.141676 -430.006839) (xy 81.14919 -429.983807)
			(xy 81.163466 -429.964234) (xy 81.1831 -429.950041) (xy 81.206163 -429.942625) (xy 81.218278 -429.942244)
			(xy 82.158078 -429.942244) (xy 82.170167 -429.942726) (xy 82.193167 -429.950177) (xy 82.212748 -429.96436)
			(xy 82.226999 -429.983891) (xy 82.234531 -430.006865) (xy 82.23504 -430.018952) (xy 82.23504 -430.889918)
			(xy 83.13801 -430.889918) (xy 83.138104 -430.875344) (xy 83.139756 -430.846243) (xy 83.141312 -430.831752)
			(xy 83.141312 -429.747934) (xy 83.139764 -429.733442) (xy 83.138114 -429.704342) (xy 83.13801 -429.689768)
			(xy 83.138108 -429.675194) (xy 83.139758 -429.646093) (xy 83.141312 -429.631602) (xy 83.141312 -429.018954)
			(xy 83.141772 -429.00684) (xy 83.149269 -428.983799) (xy 83.163515 -428.964201) (xy 83.183117 -428.94996)
			(xy 83.20616 -428.942469) (xy 83.218274 -428.941992) (xy 84.158074 -428.941992) (xy 84.170183 -428.942533)
			(xy 84.193217 -428.950008) (xy 84.212815 -428.964233) (xy 84.227059 -428.983818) (xy 84.234555 -429.006846)
			(xy 84.235036 -429.018954) (xy 84.235036 -431.560478) (xy 84.234621 -431.572602) (xy 84.227132 -431.595665)
			(xy 84.21288 -431.615282) (xy 84.193261 -431.629533) (xy 84.170198 -431.637022) (xy 84.158074 -431.63744)
			(xy 83.218274 -431.63744) (xy 83.206156 -431.63701) (xy 83.183108 -431.629513) (xy 83.163505 -431.615261)
			(xy 83.149265 -431.595649) (xy 83.141782 -431.572596) (xy 83.141312 -431.560478) (xy 83.141312 -430.948084)
			(xy 83.139769 -430.933592) (xy 83.138116 -430.904492) (xy 83.13801 -430.889918) (xy 82.23504 -430.889918)
			(xy 82.23504 -431.889916) (xy 85.138006 -431.889916) (xy 85.1381 -431.875342) (xy 85.139752 -431.846241)
			(xy 85.141308 -431.83175) (xy 85.141308 -430.747932) (xy 85.13976 -430.73344) (xy 85.13811 -430.70434)
			(xy 85.138006 -430.689766) (xy 85.138104 -430.675192) (xy 85.139753 -430.646091) (xy 85.141308 -430.6316)
			(xy 85.141308 -430.018952) (xy 85.141676 -430.00684) (xy 85.149189 -429.98381) (xy 85.163463 -429.964237)
			(xy 85.183095 -429.950044) (xy 85.206156 -429.942626) (xy 85.21827 -429.942244) (xy 86.15807 -429.942244)
			(xy 86.170158 -429.942733) (xy 86.193159 -429.950182) (xy 86.212739 -429.964363) (xy 86.226991 -429.983892)
			(xy 86.234523 -430.006865) (xy 86.235032 -430.018952) (xy 86.235032 -430.889918) (xy 87.138002 -430.889918)
			(xy 87.138096 -430.875344) (xy 87.139748 -430.846243) (xy 87.141304 -430.831752) (xy 87.141304 -429.747934)
			(xy 87.139756 -429.733442) (xy 87.138106 -429.704342) (xy 87.138002 -429.689768) (xy 87.1381 -429.675194)
			(xy 87.13975 -429.646093) (xy 87.141304 -429.631602) (xy 87.141304 -429.018954) (xy 87.141772 -429.00684)
			(xy 87.149268 -428.983801) (xy 87.163512 -428.964203) (xy 87.183112 -428.949962) (xy 87.206152 -428.94247)
			(xy 87.218266 -428.941992) (xy 88.158066 -428.941992) (xy 88.170174 -428.94254) (xy 88.193209 -428.950012)
			(xy 88.212807 -428.964236) (xy 88.227051 -428.98382) (xy 88.234547 -429.006846) (xy 88.235028 -429.018954)
			(xy 88.235028 -431.560478) (xy 88.234621 -431.572603) (xy 88.22713 -431.595667) (xy 88.212877 -431.615285)
			(xy 88.193256 -431.629536) (xy 88.170191 -431.637023) (xy 88.158066 -431.63744) (xy 87.218266 -431.63744)
			(xy 87.206147 -431.637017) (xy 87.183099 -431.629518) (xy 87.163496 -431.615264) (xy 87.149257 -431.59565)
			(xy 87.141774 -431.572597) (xy 87.141304 -431.560478) (xy 87.141304 -430.948084) (xy 87.13976 -430.933592)
			(xy 87.138108 -430.904492) (xy 87.138002 -430.889918) (xy 86.235032 -430.889918) (xy 86.235032 -431.889916)
			(xy 89.137998 -431.889916) (xy 89.138092 -431.875342) (xy 89.139744 -431.846241) (xy 89.1413 -431.83175)
			(xy 89.1413 -430.747932) (xy 89.139752 -430.73344) (xy 89.138102 -430.70434) (xy 89.137998 -430.689766)
			(xy 89.138096 -430.675192) (xy 89.139746 -430.646091) (xy 89.1413 -430.6316) (xy 89.1413 -430.018952)
			(xy 89.141676 -430.006841) (xy 89.149188 -429.983812) (xy 89.16346 -429.96424) (xy 89.18309 -429.950047)
			(xy 89.206149 -429.942627) (xy 89.218262 -429.942244) (xy 90.158062 -429.942244) (xy 90.17015 -429.94274)
			(xy 90.19315 -429.950187) (xy 90.212731 -429.964366) (xy 90.226983 -429.983894) (xy 90.234515 -430.006866)
			(xy 90.235024 -430.018952) (xy 90.235024 -431.360072) (xy 108.40466 -431.360072) (xy 108.405158 -431.275192)
			(xy 108.413115 -431.105619) (xy 108.429011 -430.936605) (xy 108.452812 -430.768522) (xy 108.484466 -430.601739)
			(xy 108.523902 -430.436623) (xy 108.571034 -430.273538) (xy 108.625758 -430.11284) (xy 108.687955 -429.954885)
			(xy 108.757487 -429.800018) (xy 108.834202 -429.648581) (xy 108.91793 -429.500905) (xy 109.008488 -429.357317)
			(xy 109.105677 -429.218131) (xy 109.209284 -429.083654) (xy 109.319079 -428.954181) (xy 109.434823 -428.829996)
			(xy 109.55626 -428.711373) (xy 109.683124 -428.598572) (xy 109.815135 -428.491842) (xy 109.952005 -428.391417)
			(xy 110.09343 -428.297518) (xy 110.239102 -428.21035) (xy 110.3887 -428.130107) (xy 110.541894 -428.056963)
			(xy 110.698348 -427.991081) (xy 110.857718 -427.932604) (xy 111.019654 -427.881662) (xy 111.1838 -427.838366)
			(xy 111.349795 -427.802811) (xy 111.517274 -427.775076) (xy 111.685869 -427.755222) (xy 111.855209 -427.743292)
			(xy 112.024922 -427.739313) (xy 112.194635 -427.743292) (xy 112.363975 -427.755222) (xy 112.53257 -427.775076)
			(xy 112.700049 -427.802811) (xy 112.866044 -427.838366) (xy 113.03019 -427.881662) (xy 113.192126 -427.932604)
			(xy 113.351496 -427.991081) (xy 113.50795 -428.056963) (xy 113.661144 -428.130107) (xy 113.810742 -428.21035)
			(xy 113.943382 -428.28972) (xy 127.237998 -428.28972) (xy 127.238092 -428.275146) (xy 127.239744 -428.246045)
			(xy 127.2413 -428.231554) (xy 127.2413 -427.14799) (xy 127.239757 -427.133498) (xy 127.238104 -427.104398)
			(xy 127.237998 -427.089824) (xy 127.238092 -427.07525) (xy 127.239744 -427.046149) (xy 127.2413 -427.031658)
			(xy 127.2413 -426.41901) (xy 127.24182 -426.4069) (xy 127.2493 -426.383863) (xy 127.263531 -426.364265)
			(xy 127.28312 -426.350022) (xy 127.306152 -426.342527) (xy 127.318262 -426.342048) (xy 128.258062 -426.342048)
			(xy 128.270184 -426.342492) (xy 128.293243 -426.349975) (xy 128.31286 -426.36422) (xy 128.327112 -426.383832)
			(xy 128.334603 -426.406888) (xy 128.335024 -426.41901) (xy 128.335024 -427.289976) (xy 129.237994 -427.289976)
			(xy 129.238084 -427.275402) (xy 129.239739 -427.246301) (xy 129.241296 -427.23181) (xy 129.241296 -426.147992)
			(xy 129.239753 -426.1335) (xy 129.2381 -426.1044) (xy 129.237994 -426.089826) (xy 129.238089 -426.075252)
			(xy 129.23974 -426.046151) (xy 129.241296 -426.03166) (xy 129.241296 -425.419012) (xy 129.241727 -425.406904)
			(xy 129.249222 -425.383878) (xy 129.26348 -425.364305) (xy 129.283099 -425.35011) (xy 129.306149 -425.342688)
			(xy 129.318258 -425.342304) (xy 130.258058 -425.342304) (xy 130.270142 -425.342842) (xy 130.293135 -425.350283)
			(xy 130.312713 -425.364453) (xy 130.326966 -425.383969) (xy 130.334505 -425.40693) (xy 130.33502 -425.419012)
			(xy 130.33502 -427.960536) (xy 130.334615 -427.972645) (xy 130.327108 -427.99567) (xy 130.312843 -428.01524)
			(xy 130.29322 -428.029435) (xy 130.270168 -428.036858) (xy 130.258058 -428.037244) (xy 129.318258 -428.037244)
			(xy 129.306165 -428.036828) (xy 129.28316 -428.029358) (xy 129.263579 -428.015159) (xy 129.249331 -427.995614)
			(xy 129.241803 -427.972628) (xy 129.241296 -427.960536) (xy 129.241296 -427.348142) (xy 129.239749 -427.33365)
			(xy 129.238099 -427.30455) (xy 129.237994 -427.289976) (xy 128.335024 -427.289976) (xy 128.335024 -428.28972)
			(xy 131.23799 -428.28972) (xy 131.238084 -428.275146) (xy 131.239736 -428.246045) (xy 131.241292 -428.231554)
			(xy 131.241292 -427.14799) (xy 131.239749 -427.133498) (xy 131.238096 -427.104398) (xy 131.23799 -427.089824)
			(xy 131.238085 -427.07525) (xy 131.239736 -427.046149) (xy 131.241292 -427.031658) (xy 131.241292 -426.41901)
			(xy 131.24182 -426.406901) (xy 131.249299 -426.383865) (xy 131.263528 -426.364268) (xy 131.283115 -426.350024)
			(xy 131.306145 -426.342528) (xy 131.318254 -426.342048) (xy 132.258054 -426.342048) (xy 132.270175 -426.342499)
			(xy 132.293234 -426.34998) (xy 132.312851 -426.364223) (xy 132.327104 -426.383833) (xy 132.334595 -426.406889)
			(xy 132.335016 -426.41901) (xy 132.335016 -427.289976) (xy 133.237986 -427.289976) (xy 133.238076 -427.275402)
			(xy 133.239731 -427.246301) (xy 133.241288 -427.23181) (xy 133.241288 -426.147992) (xy 133.239745 -426.1335)
			(xy 133.238092 -426.1044) (xy 133.237986 -426.089826) (xy 133.238081 -426.075252) (xy 133.239732 -426.046151)
			(xy 133.241288 -426.03166) (xy 133.241288 -425.419012) (xy 133.241727 -425.406905) (xy 133.249221 -425.38388)
			(xy 133.263477 -425.364308) (xy 133.283094 -425.350113) (xy 133.306142 -425.342689) (xy 133.31825 -425.342304)
			(xy 134.25805 -425.342304) (xy 134.270133 -425.342849) (xy 134.293126 -425.350288) (xy 134.312704 -425.364455)
			(xy 134.326958 -425.383971) (xy 134.334497 -425.406931) (xy 134.335012 -425.419012) (xy 134.335012 -427.960536)
			(xy 134.334614 -427.972646) (xy 134.327107 -427.995672) (xy 134.31284 -428.015243) (xy 134.293215 -428.029437)
			(xy 134.270161 -428.036859) (xy 134.25805 -428.037244) (xy 133.31825 -428.037244) (xy 133.306161 -428.03675)
			(xy 133.28316 -428.029305) (xy 133.263578 -428.015126) (xy 133.249326 -427.995597) (xy 133.241795 -427.972623)
			(xy 133.241288 -427.960536) (xy 133.241288 -427.348142) (xy 133.239741 -427.33365) (xy 133.238091 -427.30455)
			(xy 133.237986 -427.289976) (xy 132.335016 -427.289976) (xy 132.335016 -428.28972) (xy 135.237982 -428.28972)
			(xy 135.238076 -428.275146) (xy 135.239728 -428.246045) (xy 135.241284 -428.231554) (xy 135.241284 -427.14799)
			(xy 135.239741 -427.133498) (xy 135.238088 -427.104398) (xy 135.237982 -427.089824) (xy 135.238077 -427.07525)
			(xy 135.239728 -427.046149) (xy 135.241284 -427.031658) (xy 135.241284 -426.41901) (xy 135.241669 -426.406883)
			(xy 135.249164 -426.383817) (xy 135.263423 -426.364198) (xy 135.283049 -426.349948) (xy 135.306119 -426.342464)
			(xy 135.318246 -426.342048) (xy 136.258046 -426.342048) (xy 136.270164 -426.342473) (xy 136.29321 -426.349974)
			(xy 136.312812 -426.364228) (xy 136.327052 -426.38384) (xy 136.334536 -426.406892) (xy 136.335008 -426.41901)
			(xy 136.335008 -427.289976) (xy 137.237978 -427.289976) (xy 137.238068 -427.275402) (xy 137.239723 -427.246301)
			(xy 137.24128 -427.23181) (xy 137.24128 -426.147992) (xy 137.239737 -426.1335) (xy 137.238084 -426.1044)
			(xy 137.237978 -426.089826) (xy 137.238073 -426.075252) (xy 137.239724 -426.046151) (xy 137.24128 -426.03166)
			(xy 137.24128 -425.419012) (xy 137.241727 -425.406906) (xy 137.24922 -425.383882) (xy 137.263475 -425.364311)
			(xy 137.283089 -425.350115) (xy 137.306135 -425.342691) (xy 137.318242 -425.342304) (xy 138.258042 -425.342304)
			(xy 138.27013 -425.342771) (xy 138.293126 -425.350235) (xy 138.312702 -425.364423) (xy 138.326953 -425.383953)
			(xy 138.33449 -425.406925) (xy 138.335004 -425.419012) (xy 138.335004 -427.960536) (xy 138.334614 -427.972646)
			(xy 138.327106 -427.995674) (xy 138.312837 -428.015246) (xy 138.29321 -428.02944) (xy 138.270154 -428.03686)
			(xy 138.258042 -428.037244) (xy 137.318242 -428.037244) (xy 137.306153 -428.036757) (xy 137.283151 -428.029309)
			(xy 137.263569 -428.015129) (xy 137.249318 -427.995598) (xy 137.241787 -427.972623) (xy 137.24128 -427.960536)
			(xy 137.24128 -427.348142) (xy 137.239733 -427.33365) (xy 137.238083 -427.30455) (xy 137.237978 -427.289976)
			(xy 136.335008 -427.289976) (xy 136.335008 -428.28972) (xy 139.237974 -428.28972) (xy 139.238068 -428.275146)
			(xy 139.23972 -428.246045) (xy 139.241276 -428.231554) (xy 139.241276 -427.14799) (xy 139.239733 -427.133498)
			(xy 139.23808 -427.104398) (xy 139.237974 -427.089824) (xy 139.238069 -427.07525) (xy 139.23972 -427.046149)
			(xy 139.241276 -427.031658) (xy 139.241276 -426.41901) (xy 139.241669 -426.406884) (xy 139.249163 -426.383819)
			(xy 139.26342 -426.364201) (xy 139.283044 -426.34995) (xy 139.306112 -426.342465) (xy 139.318238 -426.342048)
			(xy 140.258038 -426.342048) (xy 140.270156 -426.342479) (xy 140.293202 -426.349978) (xy 140.312804 -426.36423)
			(xy 140.327044 -426.383841) (xy 140.334528 -426.406892) (xy 140.335 -426.41901) (xy 140.335 -427.289976)
			(xy 142.237968 -427.289976) (xy 142.238082 -427.274891) (xy 142.23986 -427.244772) (xy 142.241524 -427.229778)
			(xy 142.241524 -426.150024) (xy 142.239855 -426.135031) (xy 142.238077 -426.104912) (xy 142.237968 -426.089826)
			(xy 142.238078 -426.07474) (xy 142.239859 -426.044622) (xy 142.241524 -426.029628) (xy 142.241524 -425.419012)
			(xy 142.241924 -425.406927) (xy 142.249392 -425.383939) (xy 142.2636 -425.364386) (xy 142.283157 -425.350183)
			(xy 142.306147 -425.34272) (xy 142.318232 -425.342304) (xy 143.258032 -425.342304) (xy 143.270109 -425.342737)
			(xy 143.29308 -425.35021) (xy 143.312617 -425.364414) (xy 143.32681 -425.38396) (xy 143.33427 -425.406934)
			(xy 143.33474 -425.419012) (xy 143.33474 -427.960536) (xy 143.334267 -427.972609) (xy 143.326799 -427.995572)
			(xy 143.312603 -428.015106) (xy 143.293069 -428.0293) (xy 143.270105 -428.036768) (xy 143.258032 -428.037244)
			(xy 142.318232 -428.037244) (xy 142.306163 -428.036709) (xy 142.283203 -428.02926) (xy 142.263668 -428.01508)
			(xy 142.249471 -427.995558) (xy 142.242001 -427.972605) (xy 142.241524 -427.960536) (xy 142.241524 -427.350174)
			(xy 142.23986 -427.33518) (xy 142.238078 -427.305062) (xy 142.237968 -427.289976) (xy 140.335 -427.289976)
			(xy 140.335 -428.28972) (xy 144.237964 -428.28972) (xy 144.238073 -428.274634) (xy 144.239855 -428.244516)
			(xy 144.24152 -428.229522) (xy 144.24152 -427.150022) (xy 144.239851 -427.135029) (xy 144.238073 -427.10491)
			(xy 144.237964 -427.089824) (xy 144.238074 -427.074738) (xy 144.239855 -427.04462) (xy 144.24152 -427.029626)
			(xy 144.24152 -426.41901) (xy 144.242016 -426.406923) (xy 144.249467 -426.383926) (xy 144.263647 -426.364348)
			(xy 144.283173 -426.350096) (xy 144.306143 -426.34256) (xy 144.318228 -426.342048) (xy 145.258028 -426.342048)
			(xy 145.270133 -426.342492) (xy 145.293152 -426.349993) (xy 145.312721 -426.364249) (xy 145.326916 -426.383861)
			(xy 145.334345 -426.406904) (xy 145.334736 -426.41901) (xy 145.334736 -427.289976) (xy 146.23796 -427.289976)
			(xy 146.238074 -427.274891) (xy 146.239852 -427.244772) (xy 146.241516 -427.229778) (xy 146.241516 -426.150024)
			(xy 146.239847 -426.135031) (xy 146.238069 -426.104912) (xy 146.23796 -426.089826) (xy 146.23807 -426.07474)
			(xy 146.239851 -426.044622) (xy 146.241516 -426.029628) (xy 146.241516 -425.419012) (xy 146.241923 -425.406928)
			(xy 146.249391 -425.383941) (xy 146.263597 -425.364389) (xy 146.283152 -425.350185) (xy 146.306139 -425.342722)
			(xy 146.318224 -425.342304) (xy 147.258024 -425.342304) (xy 147.270101 -425.342744) (xy 147.293071 -425.350215)
			(xy 147.312609 -425.364417) (xy 147.326802 -425.383961) (xy 147.334261 -425.406935) (xy 147.334732 -425.419012)
			(xy 147.334732 -427.960536) (xy 147.334267 -427.97261) (xy 147.326798 -427.995574) (xy 147.3126 -428.015109)
			(xy 147.293064 -428.029303) (xy 147.270098 -428.036769) (xy 147.258024 -428.037244) (xy 146.318224 -428.037244)
			(xy 146.306154 -428.036716) (xy 146.283194 -428.029264) (xy 146.26366 -428.015083) (xy 146.249463 -427.99556)
			(xy 146.241993 -427.972605) (xy 146.241516 -427.960536) (xy 146.241516 -427.350174) (xy 146.239852 -427.33518)
			(xy 146.23807 -427.305062) (xy 146.23796 -427.289976) (xy 145.334736 -427.289976) (xy 145.334736 -428.28972)
			(xy 148.237956 -428.28972) (xy 148.238066 -428.274634) (xy 148.239847 -428.244516) (xy 148.241512 -428.229522)
			(xy 148.241512 -427.150022) (xy 148.239843 -427.135029) (xy 148.238065 -427.10491) (xy 148.237956 -427.089824)
			(xy 148.238066 -427.074738) (xy 148.239847 -427.04462) (xy 148.241512 -427.029626) (xy 148.241512 -426.41901)
			(xy 148.242015 -426.406924) (xy 148.249466 -426.383928) (xy 148.263644 -426.364351) (xy 148.283168 -426.350099)
			(xy 148.306136 -426.342562) (xy 148.31822 -426.342048) (xy 149.25802 -426.342048) (xy 149.270125 -426.342499)
			(xy 149.293144 -426.349997) (xy 149.312712 -426.364252) (xy 149.326908 -426.383863) (xy 149.334337 -426.406904)
			(xy 149.334728 -426.41901) (xy 149.334728 -427.289976) (xy 150.237952 -427.289976) (xy 150.238066 -427.274891)
			(xy 150.239844 -427.244772) (xy 150.241508 -427.229778) (xy 150.241508 -426.150024) (xy 150.239839 -426.135031)
			(xy 150.238061 -426.104912) (xy 150.237952 -426.089826) (xy 150.238062 -426.07474) (xy 150.239843 -426.044622)
			(xy 150.241508 -426.029628) (xy 150.241508 -425.419012) (xy 150.241923 -425.406928) (xy 150.249389 -425.383943)
			(xy 150.263594 -425.364392) (xy 150.283147 -425.350188) (xy 150.306132 -425.342723) (xy 150.318216 -425.342304)
			(xy 151.258016 -425.342304) (xy 151.270093 -425.342751) (xy 151.293062 -425.350219) (xy 151.3126 -425.36442)
			(xy 151.326794 -425.383963) (xy 151.334253 -425.406935) (xy 151.334724 -425.419012) (xy 151.334724 -427.960536)
			(xy 151.334267 -427.972611) (xy 151.326796 -427.995577) (xy 151.312597 -428.015112) (xy 151.293059 -428.029306)
			(xy 151.270091 -428.03677) (xy 151.258016 -428.037244) (xy 150.318216 -428.037244) (xy 150.306146 -428.036723)
			(xy 150.283185 -428.029269) (xy 150.263651 -428.015086) (xy 150.249455 -427.995561) (xy 150.241985 -427.972606)
			(xy 150.241508 -427.960536) (xy 150.241508 -427.350174) (xy 150.239844 -427.33518) (xy 150.238062 -427.305062)
			(xy 150.237952 -427.289976) (xy 149.334728 -427.289976) (xy 149.334728 -428.28972) (xy 152.237948 -428.28972)
			(xy 152.238058 -428.274634) (xy 152.239839 -428.244516) (xy 152.241504 -428.229522) (xy 152.241504 -427.150022)
			(xy 152.239835 -427.135029) (xy 152.238057 -427.10491) (xy 152.237948 -427.089824) (xy 152.238058 -427.074738)
			(xy 152.239839 -427.04462) (xy 152.241504 -427.029626) (xy 152.241504 -426.41901) (xy 152.242015 -426.406925)
			(xy 152.249465 -426.38393) (xy 152.263641 -426.364353) (xy 152.283163 -426.350101) (xy 152.306128 -426.342563)
			(xy 152.318212 -426.342048) (xy 153.258012 -426.342048) (xy 153.270116 -426.342505) (xy 153.293135 -426.350002)
			(xy 153.312704 -426.364255) (xy 153.3269 -426.383864) (xy 153.334329 -426.406905) (xy 153.33472 -426.41901)
			(xy 153.33472 -427.289976) (xy 154.237944 -427.289976) (xy 154.238059 -427.274891) (xy 154.239836 -427.244772)
			(xy 154.2415 -427.229778) (xy 154.2415 -426.150024) (xy 154.239831 -426.135031) (xy 154.238053 -426.104912)
			(xy 154.237944 -426.089826) (xy 154.238054 -426.07474) (xy 154.239835 -426.044622) (xy 154.2415 -426.029628)
			(xy 154.2415 -425.419012) (xy 154.241923 -425.406929) (xy 154.249388 -425.383946) (xy 154.263592 -425.364394)
			(xy 154.283142 -425.35019) (xy 154.306125 -425.342724) (xy 154.318208 -425.342304) (xy 155.258008 -425.342304)
			(xy 155.270092 -425.342706) (xy 155.293077 -425.350177) (xy 155.312629 -425.364386) (xy 155.326832 -425.383941)
			(xy 155.334297 -425.406928) (xy 155.334716 -425.419012) (xy 155.334716 -427.960536) (xy 155.334267 -427.972612)
			(xy 155.326795 -427.995579) (xy 155.312595 -428.015115) (xy 155.293054 -428.029308) (xy 155.270084 -428.036771)
			(xy 155.258008 -428.037244) (xy 154.318208 -428.037244) (xy 154.306137 -428.03673) (xy 154.283177 -428.029274)
			(xy 154.263643 -428.015089) (xy 154.249447 -427.995563) (xy 154.241977 -427.972606) (xy 154.2415 -427.960536)
			(xy 154.2415 -427.350174) (xy 154.239836 -427.33518) (xy 154.238054 -427.305062) (xy 154.237944 -427.289976)
			(xy 153.33472 -427.289976) (xy 153.33472 -428.28972) (xy 156.23794 -428.28972) (xy 156.238052 -428.274634)
			(xy 156.239833 -428.244516) (xy 156.241496 -428.229522) (xy 156.241496 -427.150022) (xy 156.239827 -427.135029)
			(xy 156.238049 -427.10491) (xy 156.23794 -427.089824) (xy 156.23805 -427.074738) (xy 156.239831 -427.04462)
			(xy 156.241496 -427.029626) (xy 156.241496 -426.41901) (xy 156.242015 -426.406925) (xy 156.249464 -426.383932)
			(xy 156.263639 -426.364356) (xy 156.283158 -426.350104) (xy 156.306121 -426.342564) (xy 156.318204 -426.342048)
			(xy 157.258004 -426.342048) (xy 157.270108 -426.342512) (xy 157.293127 -426.350006) (xy 157.312695 -426.364257)
			(xy 157.326891 -426.383866) (xy 157.334321 -426.406905) (xy 157.334712 -426.41901) (xy 157.334712 -428.960534)
			(xy 157.334321 -428.97263) (xy 157.326849 -428.99564) (xy 157.312644 -429.015223) (xy 157.293092 -429.029471)
			(xy 157.270099 -429.036994) (xy 157.258004 -429.037496) (xy 156.318204 -429.037496) (xy 156.306095 -429.03708)
			(xy 156.283067 -429.029582) (xy 156.263493 -429.01532) (xy 156.249299 -428.995698) (xy 156.241879 -428.972644)
			(xy 156.241496 -428.960534) (xy 156.241496 -428.349918) (xy 156.239827 -428.334925) (xy 156.238049 -428.304806)
			(xy 156.23794 -428.28972) (xy 153.33472 -428.28972) (xy 153.33472 -428.960534) (xy 153.334321 -428.972629)
			(xy 153.32685 -428.995638) (xy 153.312647 -429.015221) (xy 153.293097 -429.029469) (xy 153.270106 -429.036993)
			(xy 153.258012 -429.037496) (xy 152.318212 -429.037496) (xy 152.306103 -429.037073) (xy 152.283076 -429.029577)
			(xy 152.263502 -429.015317) (xy 152.249307 -428.995696) (xy 152.241887 -428.972644) (xy 152.241504 -428.960534)
			(xy 152.241504 -428.349918) (xy 152.239835 -428.334925) (xy 152.238057 -428.304806) (xy 152.237948 -428.28972)
			(xy 149.334728 -428.28972) (xy 149.334728 -428.960534) (xy 149.334321 -428.972629) (xy 149.326851 -428.995636)
			(xy 149.31265 -429.015218) (xy 149.293102 -429.029466) (xy 149.270113 -429.036992) (xy 149.25802 -429.037496)
			(xy 148.31822 -429.037496) (xy 148.306112 -429.037066) (xy 148.283085 -429.029572) (xy 148.263511 -429.015314)
			(xy 148.249316 -428.995695) (xy 148.241895 -428.972643) (xy 148.241512 -428.960534) (xy 148.241512 -428.349918)
			(xy 148.239843 -428.334925) (xy 148.238065 -428.304806) (xy 148.237956 -428.28972) (xy 145.334736 -428.28972)
			(xy 145.334736 -428.960534) (xy 145.334321 -428.972628) (xy 145.326852 -428.995634) (xy 145.312653 -429.015215)
			(xy 145.293107 -429.029464) (xy 145.27012 -429.03699) (xy 145.258028 -429.037496) (xy 144.318228 -429.037496)
			(xy 144.30612 -429.03706) (xy 144.283093 -429.029567) (xy 144.263519 -429.015311) (xy 144.249324 -428.995693)
			(xy 144.241903 -428.972643) (xy 144.24152 -428.960534) (xy 144.24152 -428.349918) (xy 144.239851 -428.334925)
			(xy 144.238073 -428.304806) (xy 144.237964 -428.28972) (xy 140.335 -428.28972) (xy 140.335 -428.960534)
			(xy 140.334518 -428.972647) (xy 140.327026 -428.995684) (xy 140.312785 -429.015282) (xy 140.293188 -429.029524)
			(xy 140.270151 -429.037017) (xy 140.258038 -429.037496) (xy 139.318238 -429.037496) (xy 139.306121 -429.037008)
			(xy 139.283069 -429.029531) (xy 139.263456 -429.015295) (xy 139.249202 -428.995696) (xy 139.241703 -428.972651)
			(xy 139.241276 -428.960534) (xy 139.241276 -428.347886) (xy 139.239733 -428.333394) (xy 139.23808 -428.304294)
			(xy 139.237974 -428.28972) (xy 136.335008 -428.28972) (xy 136.335008 -428.960534) (xy 136.334518 -428.972646)
			(xy 136.327027 -428.995682) (xy 136.312788 -429.01528) (xy 136.293193 -429.029522) (xy 136.270158 -429.037016)
			(xy 136.258046 -429.037496) (xy 135.318246 -429.037496) (xy 135.306129 -429.037002) (xy 135.283077 -429.029526)
			(xy 135.263464 -429.015292) (xy 135.249211 -428.995694) (xy 135.241711 -428.972651) (xy 135.241284 -428.960534)
			(xy 135.241284 -428.347886) (xy 135.239741 -428.333394) (xy 135.238088 -428.304294) (xy 135.237982 -428.28972)
			(xy 132.335016 -428.28972) (xy 132.335016 -428.960534) (xy 132.334668 -428.972663) (xy 132.327161 -428.995731)
			(xy 132.312892 -429.015349) (xy 132.293259 -429.029598) (xy 132.270184 -429.037081) (xy 132.258054 -429.037496)
			(xy 131.318254 -429.037496) (xy 131.30614 -429.037028) (xy 131.283101 -429.029532) (xy 131.263503 -429.015288)
			(xy 131.249262 -428.995688) (xy 131.24177 -428.972648) (xy 131.241292 -428.960534) (xy 131.241292 -428.347886)
			(xy 131.239749 -428.333394) (xy 131.238096 -428.304294) (xy 131.23799 -428.28972) (xy 128.335024 -428.28972)
			(xy 128.335024 -428.960534) (xy 128.334669 -428.972662) (xy 128.327162 -428.995729) (xy 128.312895 -429.015347)
			(xy 128.293264 -429.029595) (xy 128.270191 -429.03708) (xy 128.258062 -429.037496) (xy 127.318262 -429.037496)
			(xy 127.306149 -429.037021) (xy 127.28311 -429.029528) (xy 127.263512 -429.015285) (xy 127.24927 -428.995686)
			(xy 127.241778 -428.972647) (xy 127.2413 -428.960534) (xy 127.2413 -428.347886) (xy 127.239757 -428.333394)
			(xy 127.238104 -428.304294) (xy 127.237998 -428.28972) (xy 113.943382 -428.28972) (xy 113.956414 -428.297518)
			(xy 114.097839 -428.391417) (xy 114.234709 -428.491842) (xy 114.36672 -428.598572) (xy 114.493584 -428.711373)
			(xy 114.615021 -428.829996) (xy 114.730765 -428.954181) (xy 114.84056 -429.083654) (xy 114.944167 -429.218131)
			(xy 115.041356 -429.357317) (xy 115.131914 -429.500905) (xy 115.215642 -429.648581) (xy 115.292357 -429.800018)
			(xy 115.361889 -429.954885) (xy 115.424086 -430.11284) (xy 115.47881 -430.273538) (xy 115.525942 -430.436623)
			(xy 115.565378 -430.601739) (xy 115.597032 -430.768522) (xy 115.614222 -430.889918) (xy 125.218444 -430.889918)
			(xy 125.218955 -430.857362) (xy 125.226898 -430.792738) (xy 125.242681 -430.729568) (xy 125.266066 -430.668801)
			(xy 125.296702 -430.611348) (xy 125.334131 -430.55807) (xy 125.377791 -430.509766) (xy 125.402086 -430.48809)
			(xy 125.482858 -430.323244) (xy 125.487583 -430.312737) (xy 125.491061 -430.289973) (xy 125.487567 -430.267211)
			(xy 125.482858 -430.256696) (xy 125.401832 -430.091596) (xy 125.377594 -430.069872) (xy 125.333994 -430.021546)
			(xy 125.296616 -429.96826) (xy 125.266019 -429.910812) (xy 125.24266 -429.85006) (xy 125.226888 -429.786912)
			(xy 125.218938 -429.722312) (xy 125.218444 -429.689768) (xy 125.219137 -429.650641) (xy 125.230616 -429.573235)
			(xy 125.241304 -429.53559) (xy 125.241304 -429.018954) (xy 125.241772 -429.00684) (xy 125.249268 -428.983801)
			(xy 125.263512 -428.964203) (xy 125.283112 -428.949962) (xy 125.306152 -428.94247) (xy 125.318266 -428.941992)
			(xy 126.258066 -428.941992) (xy 126.270174 -428.94254) (xy 126.293209 -428.950012) (xy 126.312807 -428.964236)
			(xy 126.327051 -428.98382) (xy 126.334547 -429.006846) (xy 126.335028 -429.018954) (xy 126.335028 -431.560478)
			(xy 126.334621 -431.572603) (xy 126.32713 -431.595667) (xy 126.312877 -431.615285) (xy 126.293256 -431.629536)
			(xy 126.270191 -431.637023) (xy 126.258066 -431.63744) (xy 125.318266 -431.63744) (xy 125.306147 -431.637017)
			(xy 125.283099 -431.629518) (xy 125.263496 -431.615264) (xy 125.249257 -431.59565) (xy 125.241774 -431.572597)
			(xy 125.241304 -431.560478) (xy 125.241304 -431.044096) (xy 125.23062 -431.00645) (xy 125.219141 -430.929044)
			(xy 125.218444 -430.889918) (xy 115.614222 -430.889918) (xy 115.620833 -430.936605) (xy 115.636729 -431.105619)
			(xy 115.644686 -431.275192) (xy 115.645184 -431.360072) (xy 115.644698 -431.445674) (xy 115.63661 -431.616688)
			(xy 115.620446 -431.787128) (xy 115.605768 -431.889916) (xy 127.21844 -431.889916) (xy 127.218951 -431.85736)
			(xy 127.226895 -431.792736) (xy 127.242677 -431.729566) (xy 127.266062 -431.668799) (xy 127.296698 -431.611346)
			(xy 127.334127 -431.558068) (xy 127.377787 -431.509764) (xy 127.402082 -431.488088) (xy 127.482854 -431.323242)
			(xy 127.487581 -431.312736) (xy 127.491058 -431.289971) (xy 127.487563 -431.267209) (xy 127.482854 -431.256694)
			(xy 127.401828 -431.091594) (xy 127.377588 -431.069872) (xy 127.333989 -431.021545) (xy 127.296611 -430.968259)
			(xy 127.266014 -430.910811) (xy 127.242655 -430.850059) (xy 127.226883 -430.786911) (xy 127.218934 -430.72231)
			(xy 127.21844 -430.689766) (xy 127.219132 -430.650639) (xy 127.230612 -430.573233) (xy 127.2413 -430.535588)
			(xy 127.2413 -430.018952) (xy 127.241676 -430.006841) (xy 127.249188 -429.983812) (xy 127.26346 -429.96424)
			(xy 127.28309 -429.950047) (xy 127.306149 -429.942627) (xy 127.318262 -429.942244) (xy 128.258062 -429.942244)
			(xy 128.27015 -429.94274) (xy 128.29315 -429.950187) (xy 128.312731 -429.964366) (xy 128.326983 -429.983894)
			(xy 128.334515 -430.006866) (xy 128.335024 -430.018952) (xy 128.335024 -430.889918) (xy 129.218436 -430.889918)
			(xy 129.21895 -430.857362) (xy 129.226893 -430.792738) (xy 129.242675 -430.729569) (xy 129.26606 -430.668802)
			(xy 129.296696 -430.611349) (xy 129.334124 -430.55807) (xy 129.377783 -430.509766) (xy 129.402078 -430.48809)
			(xy 129.48285 -430.323244) (xy 129.487576 -430.312737) (xy 129.491054 -430.289973) (xy 129.487559 -430.267211)
			(xy 129.48285 -430.256696) (xy 129.401824 -430.091596) (xy 129.377585 -430.069874) (xy 129.333985 -430.021547)
			(xy 129.296608 -429.968261) (xy 129.266011 -429.910813) (xy 129.242652 -429.850061) (xy 129.22688 -429.786913)
			(xy 129.21893 -429.722312) (xy 129.218436 -429.689768) (xy 129.219129 -429.650642) (xy 129.230608 -429.573235)
			(xy 129.241296 -429.53559) (xy 129.241296 -429.018954) (xy 129.241772 -429.006841) (xy 129.249267 -428.983804)
			(xy 129.263509 -428.964206) (xy 129.283107 -428.949965) (xy 129.306145 -428.942471) (xy 129.318258 -428.941992)
			(xy 130.258058 -428.941992) (xy 130.270166 -428.942547) (xy 130.2932 -428.950017) (xy 130.312798 -428.964239)
			(xy 130.327043 -428.983821) (xy 130.334539 -429.006847) (xy 130.33502 -429.018954) (xy 130.33502 -431.560478)
			(xy 130.334621 -431.572604) (xy 130.327129 -431.595669) (xy 130.312874 -431.615288) (xy 130.293251 -431.629538)
			(xy 130.270184 -431.637024) (xy 130.258058 -431.63744) (xy 129.318258 -431.63744) (xy 129.306139 -431.637024)
			(xy 129.283091 -431.629522) (xy 129.263488 -431.615267) (xy 129.249248 -431.595652) (xy 129.241766 -431.572597)
			(xy 129.241296 -431.560478) (xy 129.241296 -431.044096) (xy 129.230612 -431.00645) (xy 129.219133 -430.929044)
			(xy 129.218436 -430.889918) (xy 128.335024 -430.889918) (xy 128.335024 -431.889916) (xy 131.218432 -431.889916)
			(xy 131.218945 -431.85736) (xy 131.226889 -431.792736) (xy 131.242671 -431.729567) (xy 131.266055 -431.6688)
			(xy 131.296691 -431.611346) (xy 131.334119 -431.558068) (xy 131.377779 -431.509764) (xy 131.402074 -431.488088)
			(xy 131.482846 -431.323242) (xy 131.487573 -431.312736) (xy 131.491051 -431.289971) (xy 131.487556 -431.267209)
			(xy 131.482846 -431.256694) (xy 131.40182 -431.091594) (xy 131.377579 -431.069874) (xy 131.333979 -431.021546)
			(xy 131.296602 -430.96826) (xy 131.266006 -430.910812) (xy 131.242647 -430.850059) (xy 131.226875 -430.786911)
			(xy 131.218926 -430.72231) (xy 131.218432 -430.689766) (xy 131.219125 -430.650639) (xy 131.230604 -430.573233)
			(xy 131.241292 -430.535588) (xy 131.241292 -430.018952) (xy 131.241675 -430.006841) (xy 131.249187 -429.983814)
			(xy 131.263458 -429.964242) (xy 131.283085 -429.950049) (xy 131.306142 -429.942628) (xy 131.318254 -429.942244)
			(xy 132.258054 -429.942244) (xy 132.270142 -429.942747) (xy 132.293141 -429.950191) (xy 132.312722 -429.964368)
			(xy 132.326974 -429.983895) (xy 132.334507 -430.006866) (xy 132.335016 -430.018952) (xy 132.335016 -430.889918)
			(xy 133.218428 -430.889918) (xy 133.218944 -430.857362) (xy 133.226887 -430.792738) (xy 133.242669 -430.729569)
			(xy 133.266053 -430.668802) (xy 133.296689 -430.611349) (xy 133.334116 -430.55807) (xy 133.377775 -430.509766)
			(xy 133.40207 -430.48809) (xy 133.482842 -430.323244) (xy 133.487568 -430.312737) (xy 133.491047 -430.289973)
			(xy 133.487552 -430.267211) (xy 133.482842 -430.256696) (xy 133.401816 -430.091596) (xy 133.377575 -430.069876)
			(xy 133.333976 -430.021548) (xy 133.296599 -429.968262) (xy 133.266002 -429.910813) (xy 133.242644 -429.850061)
			(xy 133.226872 -429.786913) (xy 133.218922 -429.722312) (xy 133.218428 -429.689768) (xy 133.219121 -429.650642)
			(xy 133.230601 -429.573235) (xy 133.241288 -429.53559) (xy 133.241288 -429.018954) (xy 133.241772 -429.006842)
			(xy 133.249266 -428.983806) (xy 133.263506 -428.964209) (xy 133.283102 -428.949967) (xy 133.306138 -428.942472)
			(xy 133.31825 -428.941992) (xy 134.25805 -428.941992) (xy 134.270163 -428.942468) (xy 134.2932 -428.949964)
			(xy 134.312797 -428.964206) (xy 134.327038 -428.983804) (xy 134.334532 -429.006841) (xy 134.335012 -429.018954)
			(xy 134.335012 -431.560478) (xy 134.33447 -431.572586) (xy 134.326995 -431.59562) (xy 134.312769 -431.615218)
			(xy 134.293185 -431.629462) (xy 134.270158 -431.636959) (xy 134.25805 -431.63744) (xy 133.31825 -431.63744)
			(xy 133.306131 -431.63703) (xy 133.283082 -431.629527) (xy 133.263479 -431.615269) (xy 133.24924 -431.595653)
			(xy 133.241758 -431.572598) (xy 133.241288 -431.560478) (xy 133.241288 -431.044096) (xy 133.230604 -431.00645)
			(xy 133.219125 -430.929044) (xy 133.218428 -430.889918) (xy 132.335016 -430.889918) (xy 132.335016 -431.889916)
			(xy 135.218424 -431.889916) (xy 135.21894 -431.857361) (xy 135.226883 -431.792736) (xy 135.242665 -431.729567)
			(xy 135.266049 -431.6688) (xy 135.296685 -431.611347) (xy 135.334112 -431.558069) (xy 135.377771 -431.509764)
			(xy 135.402066 -431.488088) (xy 135.482838 -431.323242) (xy 135.487566 -431.312736) (xy 135.491044 -431.289971)
			(xy 135.487548 -431.267209) (xy 135.482838 -431.256694) (xy 135.401812 -431.091594) (xy 135.377569 -431.069876)
			(xy 135.33397 -431.021548) (xy 135.296594 -430.968261) (xy 135.265997 -430.910812) (xy 135.242639 -430.85006)
			(xy 135.226867 -430.786911) (xy 135.218918 -430.72231) (xy 135.218424 -430.689766) (xy 135.219117 -430.65064)
			(xy 135.230596 -430.573233) (xy 135.241284 -430.535588) (xy 135.241284 -430.018952) (xy 135.241675 -430.006842)
			(xy 135.249186 -429.983816) (xy 135.263455 -429.964245) (xy 135.28308 -429.950052) (xy 135.306135 -429.942629)
			(xy 135.318246 -429.942244) (xy 136.258046 -429.942244) (xy 136.270138 -429.942668) (xy 136.293141 -429.950138)
			(xy 136.312721 -429.964336) (xy 136.32697 -429.983878) (xy 136.3345 -430.006861) (xy 136.335008 -430.018952)
			(xy 136.335008 -430.889918) (xy 137.21842 -430.889918) (xy 137.218939 -430.857363) (xy 137.226882 -430.792738)
			(xy 137.242663 -430.729569) (xy 137.266047 -430.668803) (xy 137.296682 -430.611349) (xy 137.334109 -430.558071)
			(xy 137.377767 -430.509766) (xy 137.402062 -430.48809) (xy 137.482834 -430.323244) (xy 137.48756 -430.312737)
			(xy 137.49104 -430.289973) (xy 137.487544 -430.267211) (xy 137.482834 -430.256696) (xy 137.401808 -430.091596)
			(xy 137.377565 -430.069878) (xy 137.333967 -430.021549) (xy 137.29659 -429.968263) (xy 137.265994 -429.910814)
			(xy 137.242635 -429.850062) (xy 137.226864 -429.786913) (xy 137.218914 -429.722312) (xy 137.21842 -429.689768)
			(xy 137.219114 -429.650642) (xy 137.230593 -429.573235) (xy 137.24128 -429.53559) (xy 137.24128 -429.018954)
			(xy 137.241673 -429.006833) (xy 137.249178 -428.983781) (xy 137.263439 -428.964176) (xy 137.28306 -428.949938)
			(xy 137.30612 -428.942459) (xy 137.318242 -428.941992) (xy 138.258042 -428.941992) (xy 138.270154 -428.942475)
			(xy 138.293191 -428.949968) (xy 138.312788 -428.964209) (xy 138.32703 -428.983805) (xy 138.334524 -429.006842)
			(xy 138.335004 -429.018954) (xy 138.335004 -431.560478) (xy 138.33447 -431.572587) (xy 138.326994 -431.595623)
			(xy 138.312767 -431.615221) (xy 138.29318 -431.629465) (xy 138.270151 -431.63696) (xy 138.258042 -431.63744)
			(xy 137.318242 -431.63744) (xy 137.306119 -431.637004) (xy 137.283058 -431.629521) (xy 137.26344 -431.615274)
			(xy 137.249188 -431.59566) (xy 137.241699 -431.572601) (xy 137.24128 -431.560478) (xy 137.24128 -431.044096)
			(xy 137.230596 -431.00645) (xy 137.219117 -430.929044) (xy 137.21842 -430.889918) (xy 136.335008 -430.889918)
			(xy 136.335008 -431.889916) (xy 139.218416 -431.889916) (xy 139.218935 -431.857361) (xy 139.226878 -431.792736)
			(xy 139.24266 -431.729568) (xy 139.266043 -431.668801) (xy 139.296678 -431.611348) (xy 139.334105 -431.558069)
			(xy 139.377763 -431.509764) (xy 139.402058 -431.488088) (xy 139.48283 -431.323242) (xy 139.487558 -431.312736)
			(xy 139.491037 -431.289971) (xy 139.487541 -431.267209) (xy 139.48283 -431.256694) (xy 139.401804 -431.091594)
			(xy 139.37756 -431.069878) (xy 139.333961 -431.021549) (xy 139.296585 -430.968262) (xy 139.265989 -430.910813)
			(xy 139.242631 -430.85006) (xy 139.226859 -430.786911) (xy 139.21891 -430.72231) (xy 139.218416 -430.689766)
			(xy 139.219105 -430.650639) (xy 139.230587 -430.573233) (xy 139.241276 -430.535588) (xy 139.241276 -430.018952)
			(xy 139.241675 -430.006843) (xy 139.249185 -429.983818) (xy 139.263452 -429.964248) (xy 139.283075 -429.950054)
			(xy 139.306128 -429.94263) (xy 139.318238 -429.942244) (xy 140.258038 -429.942244) (xy 140.27013 -429.942675)
			(xy 140.293133 -429.950143) (xy 140.312712 -429.964338) (xy 140.326961 -429.983879) (xy 140.334492 -430.006861)
			(xy 140.335 -430.018952) (xy 140.335 -430.889918) (xy 142.21841 -430.889918) (xy 142.218932 -430.857363)
			(xy 142.226875 -430.792739) (xy 142.242656 -430.72957) (xy 142.26604 -430.668803) (xy 142.296674 -430.61135)
			(xy 142.3341 -430.558071) (xy 142.377758 -430.509766) (xy 142.402052 -430.48809) (xy 142.482824 -430.323244)
			(xy 142.487551 -430.312738) (xy 142.491031 -430.289973) (xy 142.487535 -430.267211) (xy 142.482824 -430.256696)
			(xy 142.401798 -430.091596) (xy 142.377553 -430.06988) (xy 142.333955 -430.021551) (xy 142.296579 -429.968264)
			(xy 142.265983 -429.910815) (xy 142.242625 -429.850062) (xy 142.226853 -429.786913) (xy 142.218904 -429.722312)
			(xy 142.21841 -429.689768) (xy 142.219138 -429.650443) (xy 142.230742 -429.572653) (xy 142.241524 -429.534828)
			(xy 142.241524 -429.018954) (xy 142.241968 -429.006864) (xy 142.249435 -428.983864) (xy 142.263628 -428.964286)
			(xy 142.283165 -428.950037) (xy 142.306143 -428.942503) (xy 142.318232 -428.941992) (xy 143.258032 -428.941992)
			(xy 143.270142 -428.942389) (xy 143.293169 -428.949896) (xy 143.312741 -428.964163) (xy 143.326934 -428.983788)
			(xy 143.334356 -429.006843) (xy 143.33474 -429.018954) (xy 143.33474 -431.560478) (xy 143.334273 -431.572568)
			(xy 143.32682 -431.595572) (xy 143.312634 -431.615154) (xy 143.293099 -431.629404) (xy 143.270121 -431.636933)
			(xy 143.258032 -431.63744) (xy 142.318232 -431.63744) (xy 142.306129 -431.636957) (xy 142.283109 -431.629471)
			(xy 142.263539 -431.615225) (xy 142.249342 -431.59562) (xy 142.241913 -431.572582) (xy 142.241524 -431.560478)
			(xy 142.241524 -431.044858) (xy 142.230729 -431.007035) (xy 142.21912 -430.929244) (xy 142.21841 -430.889918)
			(xy 140.335 -430.889918) (xy 140.335 -431.889916) (xy 144.218406 -431.889916) (xy 144.218928 -431.857361)
			(xy 144.226871 -431.792737) (xy 144.242653 -431.729568) (xy 144.266036 -431.668802) (xy 144.29667 -431.611348)
			(xy 144.334097 -431.55807) (xy 144.377754 -431.509764) (xy 144.402048 -431.488088) (xy 144.48282 -431.323242)
			(xy 144.487549 -431.312736) (xy 144.491028 -431.289971) (xy 144.487531 -431.267209) (xy 144.48282 -431.256694)
			(xy 144.401794 -431.091594) (xy 144.377548 -431.06988) (xy 144.33395 -431.02155) (xy 144.296574 -430.968263)
			(xy 144.265978 -430.910813) (xy 144.24262 -430.85006) (xy 144.226849 -430.786912) (xy 144.2189 -430.72231)
			(xy 144.218406 -430.689766) (xy 144.219133 -430.650441) (xy 144.230738 -430.572651) (xy 144.24152 -430.534826)
			(xy 144.24152 -430.018952) (xy 144.241924 -430.006872) (xy 144.249403 -429.983899) (xy 144.263614 -429.96436)
			(xy 144.283167 -429.950168) (xy 144.306148 -429.942712) (xy 144.318228 -429.942244) (xy 145.258028 -429.942244)
			(xy 145.270099 -429.942739) (xy 145.293059 -429.950204) (xy 145.312592 -429.964394) (xy 145.326787 -429.983923)
			(xy 145.334258 -430.006881) (xy 145.334736 -430.018952) (xy 145.334736 -430.889918) (xy 146.218402 -430.889918)
			(xy 146.218927 -430.857363) (xy 146.22687 -430.792739) (xy 146.242651 -430.72957) (xy 146.266034 -430.668804)
			(xy 146.296668 -430.611351) (xy 146.334093 -430.558072) (xy 146.37775 -430.509766) (xy 146.402044 -430.48809)
			(xy 146.482816 -430.323244) (xy 146.487543 -430.312738) (xy 146.491023 -430.289973) (xy 146.487527 -430.267211)
			(xy 146.482816 -430.256696) (xy 146.40179 -430.091596) (xy 146.377544 -430.069882) (xy 146.333946 -430.021552)
			(xy 146.29657 -429.968265) (xy 146.265975 -429.910815) (xy 146.242617 -429.850062) (xy 146.226845 -429.786913)
			(xy 146.218896 -429.722312) (xy 146.218402 -429.689768) (xy 146.21913 -429.650443) (xy 146.230734 -429.572653)
			(xy 146.241516 -429.534828) (xy 146.241516 -429.018954) (xy 146.241968 -429.006864) (xy 146.249434 -428.983866)
			(xy 146.263626 -428.964289) (xy 146.28316 -428.950039) (xy 146.306136 -428.942504) (xy 146.318224 -428.941992)
			(xy 147.258024 -428.941992) (xy 147.270133 -428.942396) (xy 147.29316 -428.949901) (xy 147.312732 -428.964166)
			(xy 147.326926 -428.983789) (xy 147.334348 -429.006843) (xy 147.334732 -429.018954) (xy 147.334732 -431.560478)
			(xy 147.334273 -431.572569) (xy 147.326819 -431.595574) (xy 147.312632 -431.615156) (xy 147.293094 -431.629407)
			(xy 147.270114 -431.636934) (xy 147.258024 -431.63744) (xy 146.318224 -431.63744) (xy 146.30612 -431.636964)
			(xy 146.283101 -431.629476) (xy 146.263531 -431.615228) (xy 146.249334 -431.595622) (xy 146.241905 -431.572583)
			(xy 146.241516 -431.560478) (xy 146.241516 -431.044858) (xy 146.230721 -431.007035) (xy 146.219112 -430.929244)
			(xy 146.218402 -430.889918) (xy 145.334736 -430.889918) (xy 145.334736 -431.889916) (xy 148.218398 -431.889916)
			(xy 148.218923 -431.857361) (xy 148.226866 -431.792737) (xy 148.242647 -431.729569) (xy 148.26603 -431.668802)
			(xy 148.296664 -431.611349) (xy 148.334089 -431.55807) (xy 148.377746 -431.509764) (xy 148.40204 -431.488088)
			(xy 148.482812 -431.323242) (xy 148.487541 -431.312736) (xy 148.491021 -431.289971) (xy 148.487524 -431.267209)
			(xy 148.482812 -431.256694) (xy 148.401786 -431.091594) (xy 148.377538 -431.069882) (xy 148.33394 -431.021552)
			(xy 148.296565 -430.968264) (xy 148.26597 -430.910814) (xy 148.242612 -430.850061) (xy 148.226841 -430.786912)
			(xy 148.218892 -430.72231) (xy 148.218398 -430.689766) (xy 148.219126 -430.650441) (xy 148.23073 -430.572651)
			(xy 148.241512 -430.534826) (xy 148.241512 -430.018952) (xy 148.241924 -430.006873) (xy 148.249402 -429.983901)
			(xy 148.263611 -429.964363) (xy 148.283162 -429.950171) (xy 148.306141 -429.942713) (xy 148.31822 -429.942244)
			(xy 149.25802 -429.942244) (xy 149.270091 -429.942747) (xy 149.29305 -429.950209) (xy 149.312583 -429.964397)
			(xy 149.326778 -429.983924) (xy 149.334249 -430.006881) (xy 149.334728 -430.018952) (xy 149.334728 -430.889918)
			(xy 150.218394 -430.889918) (xy 150.218888 -430.857362) (xy 150.226832 -430.792736) (xy 150.242616 -430.729565)
			(xy 150.266003 -430.668798) (xy 150.296643 -430.611344) (xy 150.334075 -430.558067) (xy 150.377739 -430.509765)
			(xy 150.402036 -430.48809) (xy 150.482808 -430.323244) (xy 150.487536 -430.312738) (xy 150.491016 -430.289973)
			(xy 150.48752 -430.26721) (xy 150.482808 -430.256696) (xy 150.401782 -430.091596) (xy 150.377534 -430.069883)
			(xy 150.333937 -430.021553) (xy 150.296561 -429.968266) (xy 150.265966 -429.910816) (xy 150.242608 -429.850063)
			(xy 150.226837 -429.786914) (xy 150.218888 -429.722312) (xy 150.218394 -429.689768) (xy 150.219122 -429.650443)
			(xy 150.230727 -429.572653) (xy 150.241508 -429.534828) (xy 150.241508 -429.018954) (xy 150.241968 -429.006865)
			(xy 150.249433 -428.983868) (xy 150.263623 -428.964292) (xy 150.283155 -428.950042) (xy 150.306129 -428.942505)
			(xy 150.318216 -428.941992) (xy 151.258016 -428.941992) (xy 151.270125 -428.942402) (xy 151.293151 -428.949905)
			(xy 151.312724 -428.964169) (xy 151.326918 -428.983791) (xy 151.33434 -429.006844) (xy 151.334724 -429.018954)
			(xy 151.334724 -431.560478) (xy 151.334273 -431.57257) (xy 151.326818 -431.595576) (xy 151.312629 -431.615159)
			(xy 151.293089 -431.629409) (xy 151.270106 -431.636935) (xy 151.258016 -431.63744) (xy 150.318216 -431.63744)
			(xy 150.306112 -431.63697) (xy 150.283092 -431.62948) (xy 150.263522 -431.615231) (xy 150.249326 -431.595623)
			(xy 150.241897 -431.572583) (xy 150.241508 -431.560478) (xy 150.241508 -431.044858) (xy 150.230713 -431.007035)
			(xy 150.219104 -430.929244) (xy 150.218394 -430.889918) (xy 149.334728 -430.889918) (xy 149.334728 -431.889916)
			(xy 152.21839 -431.889916) (xy 152.218884 -431.85736) (xy 152.226828 -431.792734) (xy 152.242612 -431.729563)
			(xy 152.266 -431.668796) (xy 152.296639 -431.611343) (xy 152.334071 -431.558065) (xy 152.377735 -431.509763)
			(xy 152.402032 -431.488088) (xy 152.482804 -431.323242) (xy 152.487534 -431.312736) (xy 152.491014 -431.289971)
			(xy 152.487516 -431.267208) (xy 152.482804 -431.256694) (xy 152.401778 -431.091594) (xy 152.377528 -431.069883)
			(xy 152.333931 -431.021553) (xy 152.296556 -430.968265) (xy 152.265961 -430.910815) (xy 152.242604 -430.850061)
			(xy 152.226833 -430.786912) (xy 152.218884 -430.72231) (xy 152.21839 -430.689766) (xy 152.219118 -430.650441)
			(xy 152.230722 -430.572651) (xy 152.241504 -430.534826) (xy 152.241504 -430.018952) (xy 152.241923 -430.006874)
			(xy 152.249401 -429.983903) (xy 152.263608 -429.964366) (xy 152.283157 -429.950173) (xy 152.306133 -429.942714)
			(xy 152.318212 -429.942244) (xy 153.258012 -429.942244) (xy 153.270082 -429.942753) (xy 153.293042 -429.950213)
			(xy 153.312574 -429.9644) (xy 153.32677 -429.983926) (xy 153.334241 -430.006882) (xy 153.33472 -430.018952)
			(xy 153.33472 -430.889918) (xy 154.218386 -430.889918) (xy 154.218882 -430.857362) (xy 154.226827 -430.792736)
			(xy 154.24261 -430.729566) (xy 154.265997 -430.668798) (xy 154.296636 -430.611345) (xy 154.334068 -430.558067)
			(xy 154.377731 -430.509765) (xy 154.402028 -430.48809) (xy 154.4828 -430.323244) (xy 154.487528 -430.312738)
			(xy 154.491009 -430.289973) (xy 154.487512 -430.26721) (xy 154.4828 -430.256696) (xy 154.401774 -430.091596)
			(xy 154.377524 -430.069885) (xy 154.333927 -430.021555) (xy 154.296552 -429.968266) (xy 154.265957 -429.910816)
			(xy 154.2426 -429.850063) (xy 154.226829 -429.786914) (xy 154.21888 -429.722312) (xy 154.218386 -429.689768)
			(xy 154.219115 -429.650443) (xy 154.230719 -429.572653) (xy 154.2415 -429.534828) (xy 154.2415 -429.018954)
			(xy 154.241967 -429.006866) (xy 154.249432 -428.983871) (xy 154.26362 -428.964295) (xy 154.28315 -428.950044)
			(xy 154.306122 -428.942507) (xy 154.318208 -428.941992) (xy 155.258008 -428.941992) (xy 155.270117 -428.942409)
			(xy 155.293143 -428.94991) (xy 155.312715 -428.964172) (xy 155.32691 -428.983792) (xy 155.334332 -429.006844)
			(xy 155.334716 -429.018954) (xy 155.334716 -431.560478) (xy 155.334273 -431.572571) (xy 155.326817 -431.595578)
			(xy 155.312626 -431.615162) (xy 155.293084 -431.629412) (xy 155.270099 -431.636937) (xy 155.258008 -431.63744)
			(xy 154.318208 -431.63744) (xy 154.306104 -431.636978) (xy 154.283083 -431.629485) (xy 154.263513 -431.615234)
			(xy 154.249317 -431.595625) (xy 154.241889 -431.572584) (xy 154.2415 -431.560478) (xy 154.2415 -431.044858)
			(xy 154.230705 -431.007035) (xy 154.219096 -430.929244) (xy 154.218386 -430.889918) (xy 153.33472 -430.889918)
			(xy 153.33472 -431.889916) (xy 156.218382 -431.889916) (xy 156.218878 -431.85736) (xy 156.226823 -431.792734)
			(xy 156.242607 -431.729564) (xy 156.265994 -431.668796) (xy 156.296632 -431.611343) (xy 156.334064 -431.558066)
			(xy 156.377727 -431.509763) (xy 156.402024 -431.488088) (xy 156.482796 -431.323242) (xy 156.487526 -431.312737)
			(xy 156.491006 -431.289971) (xy 156.487509 -431.267208) (xy 156.482796 -431.256694) (xy 156.40177 -431.091594)
			(xy 156.377539 -431.069863) (xy 156.333937 -431.021538) (xy 156.296558 -430.968255) (xy 156.265959 -430.910808)
			(xy 156.242599 -430.850057) (xy 156.226826 -430.78691) (xy 156.218876 -430.72231) (xy 156.218382 -430.689766)
			(xy 156.21911 -430.650441) (xy 156.230715 -430.572651) (xy 156.241496 -430.534826) (xy 156.241496 -430.018952)
			(xy 156.241923 -430.006875) (xy 156.249399 -429.983905) (xy 156.263605 -429.964368) (xy 156.283152 -429.950176)
			(xy 156.306126 -429.942715) (xy 156.318204 -429.942244) (xy 157.258004 -429.942244) (xy 157.270074 -429.94276)
			(xy 157.293033 -429.950218) (xy 157.312566 -429.964403) (xy 157.326762 -429.983927) (xy 157.334233 -430.006882)
			(xy 157.334712 -430.018952) (xy 157.334712 -432.560476) (xy 157.334267 -432.572557) (xy 157.326806 -432.595538)
			(xy 157.312609 -432.615089) (xy 157.293063 -432.629294) (xy 157.270085 -432.636762) (xy 157.258004 -432.637184)
			(xy 156.318204 -432.637184) (xy 156.306119 -432.636784) (xy 156.283132 -432.629314) (xy 156.26358 -432.615106)
			(xy 156.249376 -432.59555) (xy 156.241913 -432.572561) (xy 156.241496 -432.560476) (xy 156.241496 -432.044856)
			(xy 156.2307 -432.007034) (xy 156.219091 -431.929242) (xy 156.218382 -431.889916) (xy 153.33472 -431.889916)
			(xy 153.33472 -432.560476) (xy 153.334267 -432.572556) (xy 153.326807 -432.595536) (xy 153.312611 -432.615086)
			(xy 153.293068 -432.629291) (xy 153.270092 -432.636761) (xy 153.258012 -432.637184) (xy 152.318212 -432.637184)
			(xy 152.306128 -432.636777) (xy 152.283141 -432.629309) (xy 152.263589 -432.615103) (xy 152.249385 -432.595548)
			(xy 152.241922 -432.572561) (xy 152.241504 -432.560476) (xy 152.241504 -432.044856) (xy 152.230708 -432.007034)
			(xy 152.219099 -431.929242) (xy 152.21839 -431.889916) (xy 149.334728 -431.889916) (xy 149.334728 -432.560476)
			(xy 149.334267 -432.572555) (xy 149.326809 -432.595534) (xy 149.312614 -432.615083) (xy 149.293073 -432.629288)
			(xy 149.270099 -432.63676) (xy 149.25802 -432.637184) (xy 148.31822 -432.637184) (xy 148.306136 -432.63677)
			(xy 148.28315 -432.629305) (xy 148.263597 -432.6151) (xy 148.249393 -432.595547) (xy 148.24193 -432.57256)
			(xy 148.241512 -432.560476) (xy 148.241512 -432.044856) (xy 148.230717 -432.007033) (xy 148.219107 -431.929242)
			(xy 148.218398 -431.889916) (xy 145.334736 -431.889916) (xy 145.334736 -432.560476) (xy 145.334216 -432.572547)
			(xy 145.326763 -432.595508) (xy 145.31258 -432.615043) (xy 145.293055 -432.62924) (xy 145.270098 -432.636708)
			(xy 145.258028 -432.637184) (xy 144.318228 -432.637184) (xy 144.306144 -432.636763) (xy 144.283159 -432.6293)
			(xy 144.263606 -432.615097) (xy 144.249402 -432.595545) (xy 144.241938 -432.57256) (xy 144.24152 -432.560476)
			(xy 144.24152 -432.044856) (xy 144.230725 -432.007033) (xy 144.219115 -431.929242) (xy 144.218406 -431.889916)
			(xy 140.335 -431.889916) (xy 140.335 -432.560476) (xy 140.334563 -432.572584) (xy 140.32707 -432.59561)
			(xy 140.312814 -432.615184) (xy 140.293196 -432.629379) (xy 140.270147 -432.6368) (xy 140.258038 -432.637184)
			(xy 139.318238 -432.637184) (xy 139.306153 -432.636661) (xy 139.283157 -432.629217) (xy 139.263579 -432.615044)
			(xy 139.249326 -432.595524) (xy 139.241789 -432.572559) (xy 139.241276 -432.560476) (xy 139.241276 -432.044094)
			(xy 139.230591 -432.006448) (xy 139.219113 -431.929042) (xy 139.218416 -431.889916) (xy 136.335008 -431.889916)
			(xy 136.335008 -432.560476) (xy 136.334563 -432.572583) (xy 136.327071 -432.595608) (xy 136.312817 -432.615181)
			(xy 136.293201 -432.629376) (xy 136.270154 -432.636799) (xy 136.258046 -432.637184) (xy 135.318246 -432.637184)
			(xy 135.306161 -432.636654) (xy 135.283166 -432.629213) (xy 135.263587 -432.615042) (xy 135.249334 -432.595522)
			(xy 135.241797 -432.572559) (xy 135.241284 -432.560476) (xy 135.241284 -432.044094) (xy 135.230599 -432.006448)
			(xy 135.219121 -431.929042) (xy 135.218424 -431.889916) (xy 132.335016 -431.889916) (xy 132.335016 -432.560476)
			(xy 132.334563 -432.572582) (xy 132.327072 -432.595606) (xy 132.31282 -432.615178) (xy 132.293206 -432.629374)
			(xy 132.270161 -432.636798) (xy 132.258054 -432.637184) (xy 131.318254 -432.637184) (xy 131.306164 -432.636732)
			(xy 131.283166 -432.629266) (xy 131.263589 -432.615074) (xy 131.249339 -432.59554) (xy 131.241804 -432.572564)
			(xy 131.241292 -432.560476) (xy 131.241292 -432.044094) (xy 131.230608 -432.006448) (xy 131.219129 -431.929042)
			(xy 131.218432 -431.889916) (xy 128.335024 -431.889916) (xy 128.335024 -432.560476) (xy 128.334563 -432.572581)
			(xy 128.327074 -432.595604) (xy 128.312823 -432.615175) (xy 128.293212 -432.629371) (xy 128.270168 -432.636797)
			(xy 128.258062 -432.637184) (xy 127.318262 -432.637184) (xy 127.306173 -432.636726) (xy 127.283175 -432.629261)
			(xy 127.263598 -432.615072) (xy 127.249348 -432.595538) (xy 127.241812 -432.572564) (xy 127.2413 -432.560476)
			(xy 127.2413 -432.044094) (xy 127.230616 -432.006448) (xy 127.219137 -431.929042) (xy 127.21844 -431.889916)
			(xy 115.605768 -431.889916) (xy 115.596243 -431.956613) (xy 115.564055 -432.124765) (xy 115.523953 -432.291207)
			(xy 115.476027 -432.455567) (xy 115.420385 -432.617477) (xy 115.35715 -432.776576) (xy 115.286464 -432.932508)
			(xy 115.208486 -433.084923) (xy 115.12339 -433.233482) (xy 115.031365 -433.377851) (xy 114.932619 -433.517709)
			(xy 114.82737 -433.652742) (xy 114.715856 -433.782648) (xy 114.598325 -433.907137) (xy 114.47504 -434.02593)
			(xy 114.346277 -434.138763) (xy 114.212324 -434.245381) (xy 114.07348 -434.345548) (xy 113.930056 -434.439039)
			(xy 113.843394 -434.48986) (xy 125.238002 -434.48986) (xy 125.2381 -434.475286) (xy 125.239749 -434.446185)
			(xy 125.241304 -434.431694) (xy 125.241304 -433.34813) (xy 125.239756 -433.333638) (xy 125.238106 -433.304538)
			(xy 125.238002 -433.289964) (xy 125.2381 -433.27539) (xy 125.239749 -433.246289) (xy 125.241304 -433.231798)
			(xy 125.241304 -432.618896) (xy 125.241713 -432.606787) (xy 125.249214 -432.583758) (xy 125.263477 -432.564185)
			(xy 125.283101 -432.549991) (xy 125.306155 -432.542571) (xy 125.318266 -432.542188) (xy 126.258066 -432.542188)
			(xy 126.270159 -432.542637) (xy 126.293166 -432.55009) (xy 126.312751 -432.56428) (xy 126.327001 -432.583821)
			(xy 126.334525 -432.606805) (xy 126.335028 -432.618896) (xy 126.335028 -435.16042) (xy 126.334601 -435.172527)
			(xy 126.3271 -435.19555) (xy 126.31284 -435.215121) (xy 126.293222 -435.229316) (xy 126.270174 -435.236741)
			(xy 126.258066 -435.237128) (xy 125.318266 -435.237128) (xy 125.306171 -435.236721) (xy 125.283164 -435.229251)
			(xy 125.263582 -435.21505) (xy 125.249334 -435.195502) (xy 125.241808 -435.172513) (xy 125.241304 -435.16042)
			(xy 125.241304 -434.548026) (xy 125.239756 -434.533534) (xy 125.238106 -434.504434) (xy 125.238002 -434.48986)
			(xy 113.843394 -434.48986) (xy 113.782372 -434.525645) (xy 113.630759 -434.605172) (xy 113.475556 -434.677443)
			(xy 113.396522 -434.710332) (xy 113.382851 -434.716444) (xy 113.359598 -434.735293) (xy 113.342813 -434.760077)
			(xy 113.333939 -434.788665) (xy 113.333741 -434.818598) (xy 113.342235 -434.847301) (xy 113.358691 -434.872305)
			(xy 113.369852 -434.88229) (xy 113.419298 -434.924299) (xy 113.513487 -435.013553) (xy 113.601975 -435.108462)
			(xy 113.684422 -435.208663) (xy 113.760513 -435.313772) (xy 113.829956 -435.423387) (xy 113.866512 -435.489858)
			(xy 127.237998 -435.489858) (xy 127.238095 -435.475284) (xy 127.239745 -435.446183) (xy 127.2413 -435.431692)
			(xy 127.2413 -434.348128) (xy 127.239752 -434.333636) (xy 127.238102 -434.304536) (xy 127.237998 -434.289962)
			(xy 127.238096 -434.275388) (xy 127.239745 -434.246287) (xy 127.2413 -434.231796) (xy 127.2413 -433.618894)
			(xy 127.241806 -433.606783) (xy 127.24929 -433.583746) (xy 127.263525 -433.564148) (xy 127.283117 -433.549905)
			(xy 127.306151 -433.542411) (xy 127.318262 -433.541932) (xy 128.258062 -433.541932) (xy 128.270182 -433.542392)
			(xy 128.293239 -433.549873) (xy 128.312854 -433.564115) (xy 128.327107 -433.583722) (xy 128.334601 -433.606774)
			(xy 128.335024 -433.618894) (xy 128.335024 -434.48986) (xy 129.237994 -434.48986) (xy 129.238092 -434.475286)
			(xy 129.239741 -434.446185) (xy 129.241296 -434.431694) (xy 129.241296 -433.34813) (xy 129.239748 -433.333638)
			(xy 129.238098 -433.304538) (xy 129.237994 -433.289964) (xy 129.238092 -433.27539) (xy 129.239741 -433.246289)
			(xy 129.241296 -433.231798) (xy 129.241296 -432.618896) (xy 129.241713 -432.606787) (xy 129.249213 -432.583761)
			(xy 129.263474 -432.564188) (xy 129.283096 -432.549993) (xy 129.306148 -432.542572) (xy 129.318258 -432.542188)
			(xy 130.258058 -432.542188) (xy 130.27015 -432.542644) (xy 130.293158 -432.550095) (xy 130.312742 -432.564283)
			(xy 130.326993 -432.583822) (xy 130.334517 -432.606805) (xy 130.33502 -432.618896) (xy 130.33502 -435.16042)
			(xy 130.334601 -435.172528) (xy 130.327099 -435.195552) (xy 130.312837 -435.215123) (xy 130.293217 -435.229318)
			(xy 130.270167 -435.236742) (xy 130.258058 -435.237128) (xy 129.318258 -435.237128) (xy 129.306163 -435.236728)
			(xy 129.283156 -435.229256) (xy 129.263574 -435.215053) (xy 129.249326 -435.195504) (xy 129.2418 -435.172514)
			(xy 129.241296 -435.16042) (xy 129.241296 -434.548026) (xy 129.239748 -434.533534) (xy 129.238098 -434.504434)
			(xy 129.237994 -434.48986) (xy 128.335024 -434.48986) (xy 128.335024 -435.489858) (xy 131.23799 -435.489858)
			(xy 131.238087 -435.475284) (xy 131.239737 -435.446183) (xy 131.241292 -435.431692) (xy 131.241292 -434.348128)
			(xy 131.239744 -434.333636) (xy 131.238094 -434.304536) (xy 131.23799 -434.289962) (xy 131.238088 -434.275388)
			(xy 131.239737 -434.246287) (xy 131.241292 -434.231796) (xy 131.241292 -433.618894) (xy 131.241806 -433.606784)
			(xy 131.249289 -433.583748) (xy 131.263522 -433.564151) (xy 131.283112 -433.549908) (xy 131.306144 -433.542412)
			(xy 131.318254 -433.541932) (xy 132.258054 -433.541932) (xy 132.270174 -433.542399) (xy 132.29323 -433.549878)
			(xy 132.312846 -433.564117) (xy 132.327098 -433.583723) (xy 132.334593 -433.606775) (xy 132.335016 -433.618894)
			(xy 132.335016 -434.48986) (xy 133.237986 -434.48986) (xy 133.238084 -434.475286) (xy 133.239733 -434.446185)
			(xy 133.241288 -434.431694) (xy 133.241288 -433.34813) (xy 133.23974 -433.333638) (xy 133.23809 -433.304538)
			(xy 133.237986 -433.289964) (xy 133.238084 -433.27539) (xy 133.239733 -433.246289) (xy 133.241288 -433.231798)
			(xy 133.241288 -432.618896) (xy 133.241713 -432.606788) (xy 133.249212 -432.583763) (xy 133.263472 -432.564191)
			(xy 133.283091 -432.549996) (xy 133.306141 -432.542573) (xy 133.31825 -432.542188) (xy 134.25805 -432.542188)
			(xy 134.270142 -432.542651) (xy 134.293149 -432.5501) (xy 134.312734 -432.564285) (xy 134.326984 -432.583823)
			(xy 134.334509 -432.606806) (xy 134.335012 -432.618896) (xy 134.335012 -435.16042) (xy 134.334601 -435.172529)
			(xy 134.327097 -435.195555) (xy 134.312834 -435.215126) (xy 134.293212 -435.229321) (xy 134.27016 -435.236743)
			(xy 134.25805 -435.237128) (xy 133.31825 -435.237128) (xy 133.30616 -435.23665) (xy 133.283155 -435.229203)
			(xy 133.263572 -435.21502) (xy 133.249321 -435.195487) (xy 133.241793 -435.172508) (xy 133.241288 -435.16042)
			(xy 133.241288 -434.548026) (xy 133.23974 -434.533534) (xy 133.23809 -434.504434) (xy 133.237986 -434.48986)
			(xy 132.335016 -434.48986) (xy 132.335016 -435.489858) (xy 135.237982 -435.489858) (xy 135.238079 -435.475284)
			(xy 135.239729 -435.446183) (xy 135.241284 -435.431692) (xy 135.241284 -434.348128) (xy 135.239736 -434.333636)
			(xy 135.238086 -434.304536) (xy 135.237982 -434.289962) (xy 135.23808 -434.275388) (xy 135.239729 -434.246287)
			(xy 135.241284 -434.231796) (xy 135.241284 -433.618894) (xy 135.241656 -433.606766) (xy 135.249155 -433.5837)
			(xy 135.263418 -433.564081) (xy 135.283046 -433.549831) (xy 135.306118 -433.542348) (xy 135.318246 -433.541932)
			(xy 136.258046 -433.541932) (xy 136.270162 -433.542372) (xy 136.293206 -433.549872) (xy 136.312807 -433.564122)
			(xy 136.327047 -433.58373) (xy 136.334534 -433.606777) (xy 136.335008 -433.618894) (xy 136.335008 -434.48986)
			(xy 137.237978 -434.48986) (xy 137.238076 -434.475286) (xy 137.239725 -434.446185) (xy 137.24128 -434.431694)
			(xy 137.24128 -433.34813) (xy 137.239732 -433.333638) (xy 137.238082 -433.304538) (xy 137.237978 -433.289964)
			(xy 137.238076 -433.27539) (xy 137.239726 -433.246289) (xy 137.24128 -433.231798) (xy 137.24128 -432.618896)
			(xy 137.241712 -432.606789) (xy 137.249211 -432.583765) (xy 137.263469 -432.564194) (xy 137.283086 -432.549998)
			(xy 137.306134 -432.542574) (xy 137.318242 -432.542188) (xy 138.258042 -432.542188) (xy 138.270139 -432.542572)
			(xy 138.293149 -432.550047) (xy 138.312732 -432.564253) (xy 138.326979 -432.583806) (xy 138.334502 -432.606801)
			(xy 138.335004 -432.618896) (xy 138.335004 -435.16042) (xy 138.334601 -435.17253) (xy 138.327096 -435.195557)
			(xy 138.312831 -435.215129) (xy 138.293207 -435.229323) (xy 138.270153 -435.236744) (xy 138.258042 -435.237128)
			(xy 137.318242 -435.237128) (xy 137.306151 -435.236656) (xy 137.283147 -435.229207) (xy 137.263563 -435.215023)
			(xy 137.249313 -435.195488) (xy 137.241785 -435.172509) (xy 137.24128 -435.16042) (xy 137.24128 -434.548026)
			(xy 137.239732 -434.533534) (xy 137.238082 -434.504434) (xy 137.237978 -434.48986) (xy 136.335008 -434.48986)
			(xy 136.335008 -435.489858) (xy 139.237974 -435.489858) (xy 139.238072 -435.475284) (xy 139.239721 -435.446183)
			(xy 139.241276 -435.431692) (xy 139.241276 -434.348128) (xy 139.239728 -434.333636) (xy 139.238078 -434.304536)
			(xy 139.237974 -434.289962) (xy 139.238072 -434.275388) (xy 139.239721 -434.246287) (xy 139.241276 -434.231796)
			(xy 139.241276 -433.618894) (xy 139.241656 -433.606767) (xy 139.249154 -433.583702) (xy 139.263415 -433.564084)
			(xy 139.283041 -433.549834) (xy 139.306111 -433.542349) (xy 139.318238 -433.541932) (xy 140.258038 -433.541932)
			(xy 140.270154 -433.542379) (xy 140.293197 -433.549876) (xy 140.312798 -433.564125) (xy 140.327038 -433.583731)
			(xy 140.334526 -433.606778) (xy 140.335 -433.618894) (xy 140.335 -434.48986) (xy 142.237968 -434.48986)
			(xy 142.238081 -434.474774) (xy 142.23986 -434.444656) (xy 142.241524 -434.429662) (xy 142.241524 -433.350162)
			(xy 142.239859 -433.335168) (xy 142.238078 -433.30505) (xy 142.237968 -433.289964) (xy 142.238081 -433.274878)
			(xy 142.23986 -433.24476) (xy 142.241524 -433.229766) (xy 142.241524 -432.618896) (xy 142.24191 -432.60681)
			(xy 142.249382 -432.583822) (xy 142.263594 -432.564268) (xy 142.283154 -432.550066) (xy 142.306146 -432.542604)
			(xy 142.318232 -432.542188) (xy 143.258032 -432.542188) (xy 143.270108 -432.542637) (xy 143.293075 -432.550108)
			(xy 143.312612 -432.564308) (xy 143.326805 -432.58385) (xy 143.334268 -432.60682) (xy 143.33474 -432.618896)
			(xy 143.33474 -435.16042) (xy 143.334253 -435.172492) (xy 143.326789 -435.195455) (xy 143.312597 -435.214989)
			(xy 143.293065 -435.229184) (xy 143.270104 -435.236651) (xy 143.258032 -435.237128) (xy 142.318232 -435.237128)
			(xy 142.306153 -435.23666) (xy 142.283175 -435.229204) (xy 142.263626 -435.215011) (xy 142.24942 -435.195472)
			(xy 142.241948 -435.172499) (xy 142.241524 -435.16042) (xy 142.241524 -434.550058) (xy 142.239858 -434.535064)
			(xy 142.238078 -434.504946) (xy 142.237968 -434.48986) (xy 140.335 -434.48986) (xy 140.335 -435.489858)
			(xy 144.237964 -435.489858) (xy 144.238077 -435.474772) (xy 144.239856 -435.444654) (xy 144.24152 -435.42966)
			(xy 144.24152 -434.35016) (xy 144.239855 -434.335166) (xy 144.238074 -434.305048) (xy 144.237964 -434.289962)
			(xy 144.238077 -434.274876) (xy 144.239856 -434.244758) (xy 144.24152 -434.229764) (xy 144.24152 -433.618894)
			(xy 144.242002 -433.606806) (xy 144.249458 -433.583809) (xy 144.263641 -433.564231) (xy 144.28317 -433.54998)
			(xy 144.306142 -433.542444) (xy 144.318228 -433.541932) (xy 145.258028 -433.541932) (xy 145.270142 -433.542293)
			(xy 145.293175 -433.549804) (xy 145.312751 -433.564079) (xy 145.326943 -433.583714) (xy 145.334357 -433.606779)
			(xy 145.334736 -433.618894) (xy 145.334736 -434.48986) (xy 146.23796 -434.48986) (xy 146.238073 -434.474774)
			(xy 146.239852 -434.444656) (xy 146.241516 -434.429662) (xy 146.241516 -433.350162) (xy 146.239851 -433.335168)
			(xy 146.23807 -433.30505) (xy 146.23796 -433.289964) (xy 146.238073 -433.274878) (xy 146.239852 -433.24476)
			(xy 146.241516 -433.229766) (xy 146.241516 -432.618896) (xy 146.241909 -432.606811) (xy 146.249381 -432.583824)
			(xy 146.263591 -432.564271) (xy 146.283149 -432.550068) (xy 146.306138 -432.542605) (xy 146.318224 -432.542188)
			(xy 147.258024 -432.542188) (xy 147.270099 -432.542644) (xy 147.293067 -432.550113) (xy 147.312603 -432.564311)
			(xy 147.326797 -432.583851) (xy 147.334259 -432.606821) (xy 147.334732 -432.618896) (xy 147.334732 -435.16042)
			(xy 147.334253 -435.172493) (xy 147.326788 -435.195457) (xy 147.312594 -435.214991) (xy 147.29306 -435.229186)
			(xy 147.270097 -435.236652) (xy 147.258024 -435.237128) (xy 146.318224 -435.237128) (xy 146.306145 -435.236667)
			(xy 146.283166 -435.229209) (xy 146.263617 -435.215014) (xy 146.249412 -435.195473) (xy 146.24194 -435.172499)
			(xy 146.241516 -435.16042) (xy 146.241516 -434.550058) (xy 146.23985 -434.535064) (xy 146.23807 -434.504946)
			(xy 146.23796 -434.48986) (xy 145.334736 -434.48986) (xy 145.334736 -435.489858) (xy 148.237956 -435.489858)
			(xy 148.238069 -435.474772) (xy 148.239848 -435.444654) (xy 148.241512 -435.42966) (xy 148.241512 -434.35016)
			(xy 148.239847 -434.335166) (xy 148.238066 -434.305048) (xy 148.237956 -434.289962) (xy 148.238069 -434.274876)
			(xy 148.239848 -434.244758) (xy 148.241512 -434.229764) (xy 148.241512 -433.618894) (xy 148.242002 -433.606807)
			(xy 148.249457 -433.583811) (xy 148.263639 -433.564234) (xy 148.283165 -433.549982) (xy 148.306135 -433.542445)
			(xy 148.31822 -433.541932) (xy 149.25802 -433.541932) (xy 149.270133 -433.5423) (xy 149.293167 -433.549808)
			(xy 149.312742 -433.564081) (xy 149.326935 -433.583715) (xy 149.334349 -433.606779) (xy 149.334728 -433.618894)
			(xy 149.334728 -434.48986) (xy 150.237952 -434.48986) (xy 150.238065 -434.474774) (xy 150.239844 -434.444656)
			(xy 150.241508 -434.429662) (xy 150.241508 -433.350162) (xy 150.239843 -433.335168) (xy 150.238062 -433.30505)
			(xy 150.237952 -433.289964) (xy 150.238065 -433.274878) (xy 150.239844 -433.24476) (xy 150.241508 -433.229766)
			(xy 150.241508 -432.618896) (xy 150.241909 -432.606811) (xy 150.24938 -432.583826) (xy 150.263588 -432.564274)
			(xy 150.283144 -432.550071) (xy 150.306131 -432.542606) (xy 150.318216 -432.542188) (xy 151.258016 -432.542188)
			(xy 151.270091 -432.542651) (xy 151.293058 -432.550117) (xy 151.312594 -432.564314) (xy 151.326788 -432.583853)
			(xy 151.334251 -432.606821) (xy 151.334724 -432.618896) (xy 151.334724 -435.16042) (xy 151.334253 -435.172494)
			(xy 151.326787 -435.195459) (xy 151.312591 -435.214994) (xy 151.293055 -435.229189) (xy 151.27009 -435.236654)
			(xy 151.258016 -435.237128) (xy 150.318216 -435.237128) (xy 150.306144 -435.236622) (xy 150.283181 -435.229167)
			(xy 150.263645 -435.21498) (xy 150.24945 -435.195451) (xy 150.241983 -435.172492) (xy 150.241508 -435.16042)
			(xy 150.241508 -434.550058) (xy 150.239842 -434.535064) (xy 150.238062 -434.504946) (xy 150.237952 -434.48986)
			(xy 149.334728 -434.48986) (xy 149.334728 -435.489858) (xy 152.237948 -435.489858) (xy 152.238061 -435.474772)
			(xy 152.23984 -435.444654) (xy 152.241504 -435.42966) (xy 152.241504 -434.35016) (xy 152.239838 -434.335166)
			(xy 152.238058 -434.305048) (xy 152.237948 -434.289962) (xy 152.238061 -434.274876) (xy 152.23984 -434.244758)
			(xy 152.241504 -434.229764) (xy 152.241504 -433.618894) (xy 152.242002 -433.606808) (xy 152.249456 -433.583813)
			(xy 152.263636 -433.564236) (xy 152.28316 -433.549985) (xy 152.306128 -433.542447) (xy 152.318212 -433.541932)
			(xy 153.258012 -433.541932) (xy 153.270125 -433.542306) (xy 153.293158 -433.549813) (xy 153.312734 -433.564084)
			(xy 153.326927 -433.583717) (xy 153.334341 -433.60678) (xy 153.33472 -433.618894) (xy 153.33472 -434.48986)
			(xy 154.237944 -434.48986) (xy 154.238057 -434.474774) (xy 154.239836 -434.444656) (xy 154.2415 -434.429662)
			(xy 154.2415 -433.350162) (xy 154.239835 -433.335168) (xy 154.238054 -433.30505) (xy 154.237944 -433.289964)
			(xy 154.238057 -433.274878) (xy 154.239836 -433.24476) (xy 154.2415 -433.229766) (xy 154.2415 -432.618896)
			(xy 154.241909 -432.606812) (xy 154.249379 -432.583828) (xy 154.263586 -432.564277) (xy 154.283139 -432.550073)
			(xy 154.306124 -432.542607) (xy 154.318208 -432.542188) (xy 155.258008 -432.542188) (xy 155.270083 -432.542657)
			(xy 155.293049 -432.550122) (xy 155.312586 -432.564317) (xy 155.32678 -432.583854) (xy 155.334243 -432.606821)
			(xy 155.334716 -432.618896) (xy 155.334716 -433.130695) (xy 197.035917 -433.130695) (xy 197.035917 -432.953425)
			(xy 197.04387 -432.776334) (xy 197.059761 -432.599778) (xy 197.083556 -432.424113) (xy 197.115209 -432.249692)
			(xy 197.154655 -432.076867) (xy 197.201815 -431.905986) (xy 197.256594 -431.737392) (xy 197.318882 -431.571427)
			(xy 197.388554 -431.408422) (xy 197.465468 -431.248708) (xy 197.549471 -431.092605) (xy 197.640392 -430.940428)
			(xy 197.738049 -430.792484) (xy 197.842246 -430.64907) (xy 197.952772 -430.510475) (xy 198.069404 -430.376978)
			(xy 198.191909 -430.248849) (xy 198.320038 -430.126344) (xy 198.453535 -430.009712) (xy 198.59213 -429.899186)
			(xy 198.735544 -429.794989) (xy 198.883488 -429.697332) (xy 199.035665 -429.606411) (xy 199.191768 -429.522408)
			(xy 199.351482 -429.445494) (xy 199.514487 -429.375822) (xy 199.680452 -429.313534) (xy 199.849046 -429.258755)
			(xy 200.019927 -429.211595) (xy 200.192752 -429.172149) (xy 200.367173 -429.140496) (xy 200.542838 -429.116701)
			(xy 200.719394 -429.10081) (xy 200.896485 -429.092857) (xy 201.073755 -429.092857) (xy 201.250846 -429.10081)
			(xy 201.427402 -429.116701) (xy 201.603067 -429.140496) (xy 201.777488 -429.172149) (xy 201.950313 -429.211595)
			(xy 202.121194 -429.258755) (xy 202.289788 -429.313534) (xy 202.455753 -429.375822) (xy 202.618758 -429.445494)
			(xy 202.778472 -429.522408) (xy 202.934575 -429.606411) (xy 203.086752 -429.697332) (xy 203.234696 -429.794989)
			(xy 203.37811 -429.899186) (xy 203.516705 -430.009712) (xy 203.650202 -430.126344) (xy 203.778331 -430.248849)
			(xy 203.900836 -430.376978) (xy 204.017468 -430.510475) (xy 204.127994 -430.64907) (xy 204.232191 -430.792484)
			(xy 204.329848 -430.940428) (xy 204.420769 -431.092605) (xy 204.504772 -431.248708) (xy 204.581686 -431.408422)
			(xy 204.651358 -431.571427) (xy 204.713646 -431.737392) (xy 204.768425 -431.905986) (xy 204.815585 -432.076867)
			(xy 204.855031 -432.249692) (xy 204.886684 -432.424113) (xy 204.910479 -432.599778) (xy 204.92637 -432.776334)
			(xy 204.934323 -432.953425) (xy 204.93482 -433.04206) (xy 204.934323 -433.130695) (xy 204.92637 -433.307786)
			(xy 204.910479 -433.484342) (xy 204.886684 -433.660007) (xy 204.855031 -433.834428) (xy 204.815585 -434.007253)
			(xy 204.768425 -434.178134) (xy 204.713646 -434.346728) (xy 204.651358 -434.512693) (xy 204.581686 -434.675698)
			(xy 204.504772 -434.835412) (xy 204.420769 -434.991515) (xy 204.329848 -435.143692) (xy 204.232191 -435.291636)
			(xy 204.127994 -435.43505) (xy 204.017468 -435.573645) (xy 203.900836 -435.707142) (xy 203.778331 -435.835271)
			(xy 203.650202 -435.957776) (xy 203.516705 -436.074408) (xy 203.37811 -436.184934) (xy 203.234696 -436.289131)
			(xy 203.086752 -436.386788) (xy 202.934575 -436.477709) (xy 202.778472 -436.561712) (xy 202.618758 -436.638626)
			(xy 202.455753 -436.708298) (xy 202.289788 -436.770586) (xy 202.121194 -436.825365) (xy 201.950313 -436.872525)
			(xy 201.777488 -436.911971) (xy 201.603067 -436.943624) (xy 201.427402 -436.967419) (xy 201.250846 -436.98331)
			(xy 201.073755 -436.991263) (xy 200.896485 -436.991263) (xy 200.719394 -436.98331) (xy 200.542838 -436.967419)
			(xy 200.367173 -436.943624) (xy 200.192752 -436.911971) (xy 200.019927 -436.872525) (xy 199.849046 -436.825365)
			(xy 199.680452 -436.770586) (xy 199.514487 -436.708298) (xy 199.351482 -436.638626) (xy 199.191768 -436.561712)
			(xy 199.035665 -436.477709) (xy 198.883488 -436.386788) (xy 198.735544 -436.289131) (xy 198.59213 -436.184934)
			(xy 198.453535 -436.074408) (xy 198.320038 -435.957776) (xy 198.191909 -435.835271) (xy 198.069404 -435.707142)
			(xy 197.952772 -435.573645) (xy 197.842246 -435.43505) (xy 197.738049 -435.291636) (xy 197.640392 -435.143692)
			(xy 197.549471 -434.991515) (xy 197.465468 -434.835412) (xy 197.388554 -434.675698) (xy 197.318882 -434.512693)
			(xy 197.256594 -434.346728) (xy 197.201815 -434.178134) (xy 197.154655 -434.007253) (xy 197.115209 -433.834428)
			(xy 197.083556 -433.660007) (xy 197.059761 -433.484342) (xy 197.04387 -433.307786) (xy 197.035917 -433.130695)
			(xy 155.334716 -433.130695) (xy 155.334716 -435.16042) (xy 155.334253 -435.172495) (xy 155.326786 -435.195461)
			(xy 155.312589 -435.214997) (xy 155.29305 -435.229191) (xy 155.270083 -435.236655) (xy 155.258008 -435.237128)
			(xy 154.318208 -435.237128) (xy 154.306136 -435.236629) (xy 154.283172 -435.229171) (xy 154.263637 -435.214983)
			(xy 154.249441 -435.195453) (xy 154.241975 -435.172492) (xy 154.2415 -435.16042) (xy 154.2415 -434.550058)
			(xy 154.239834 -434.535064) (xy 154.238054 -434.504946) (xy 154.237944 -434.48986) (xy 153.33472 -434.48986)
			(xy 153.33472 -435.489858) (xy 156.23794 -435.489858) (xy 156.238053 -435.474772) (xy 156.239832 -435.444654)
			(xy 156.241496 -435.42966) (xy 156.241496 -434.35016) (xy 156.23983 -434.335166) (xy 156.23805 -434.305048)
			(xy 156.23794 -434.289962) (xy 156.238053 -434.274876) (xy 156.239832 -434.244758) (xy 156.241496 -434.229764)
			(xy 156.241496 -433.618894) (xy 156.242002 -433.606809) (xy 156.249455 -433.583815) (xy 156.263633 -433.564239)
			(xy 156.283155 -433.549987) (xy 156.30612 -433.542448) (xy 156.318204 -433.541932) (xy 157.258004 -433.541932)
			(xy 157.270116 -433.542313) (xy 157.293149 -433.549818) (xy 157.312725 -433.564087) (xy 157.326918 -433.583718)
			(xy 157.334333 -433.60678) (xy 157.334712 -433.618894) (xy 157.334712 -436.160418) (xy 157.334307 -436.172513)
			(xy 157.32684 -436.195523) (xy 157.312639 -436.215106) (xy 157.293089 -436.229355) (xy 157.270098 -436.236878)
			(xy 157.258004 -436.23738) (xy 156.318204 -436.23738) (xy 156.306093 -436.23698) (xy 156.283063 -436.229479)
			(xy 156.263488 -436.215214) (xy 156.249294 -436.195588) (xy 156.241876 -436.17253) (xy 156.241496 -436.160418)
			(xy 156.241496 -435.550056) (xy 156.23983 -435.535062) (xy 156.23805 -435.504944) (xy 156.23794 -435.489858)
			(xy 153.33472 -435.489858) (xy 153.33472 -436.160418) (xy 153.334307 -436.172513) (xy 153.326841 -436.195521)
			(xy 153.312642 -436.215104) (xy 153.293094 -436.229352) (xy 153.270105 -436.236877) (xy 153.258012 -436.23738)
			(xy 152.318212 -436.23738) (xy 152.306102 -436.236973) (xy 152.283072 -436.229474) (xy 152.263497 -436.215211)
			(xy 152.249302 -436.195586) (xy 152.241885 -436.17253) (xy 152.241504 -436.160418) (xy 152.241504 -435.550056)
			(xy 152.239838 -435.535062) (xy 152.238058 -435.504944) (xy 152.237948 -435.489858) (xy 149.334728 -435.489858)
			(xy 149.334728 -436.160418) (xy 149.334308 -436.172512) (xy 149.326842 -436.195518) (xy 149.312645 -436.215101)
			(xy 149.293099 -436.22935) (xy 149.270112 -436.236876) (xy 149.25802 -436.23738) (xy 148.31822 -436.23738)
			(xy 148.30611 -436.236966) (xy 148.28308 -436.22947) (xy 148.263505 -436.215208) (xy 148.249311 -436.195585)
			(xy 148.241893 -436.172529) (xy 148.241512 -436.160418) (xy 148.241512 -435.550056) (xy 148.239846 -435.535062)
			(xy 148.238066 -435.504944) (xy 148.237956 -435.489858) (xy 145.334736 -435.489858) (xy 145.334736 -436.160418)
			(xy 145.334308 -436.172511) (xy 145.326843 -436.195516) (xy 145.312647 -436.215098) (xy 145.293104 -436.229347)
			(xy 145.27012 -436.236874) (xy 145.258028 -436.23738) (xy 144.318228 -436.23738) (xy 144.306119 -436.236959)
			(xy 144.283089 -436.229465) (xy 144.263514 -436.215206) (xy 144.249319 -436.195583) (xy 144.241901 -436.172529)
			(xy 144.24152 -436.160418) (xy 144.24152 -435.550056) (xy 144.239854 -435.535062) (xy 144.238074 -435.504944)
			(xy 144.237964 -435.489858) (xy 140.335 -435.489858) (xy 140.335 -436.160418) (xy 140.334504 -436.17253)
			(xy 140.327017 -436.195567) (xy 140.31278 -436.215165) (xy 140.293185 -436.229408) (xy 140.27015 -436.236901)
			(xy 140.258038 -436.23738) (xy 139.318238 -436.23738) (xy 139.306119 -436.236908) (xy 139.283064 -436.229428)
			(xy 139.26345 -436.21519) (xy 139.249197 -436.195586) (xy 139.241701 -436.172537) (xy 139.241276 -436.160418)
			(xy 139.241276 -435.548024) (xy 139.239728 -435.533532) (xy 139.238078 -435.504432) (xy 139.237974 -435.489858)
			(xy 136.335008 -435.489858) (xy 136.335008 -436.160418) (xy 136.334505 -436.172529) (xy 136.327018 -436.195565)
			(xy 136.312782 -436.215163) (xy 136.29319 -436.229405) (xy 136.270157 -436.2369) (xy 136.258046 -436.23738)
			(xy 135.318246 -436.23738) (xy 135.306127 -436.236901) (xy 135.283073 -436.229424) (xy 135.263459 -436.215187)
			(xy 135.249205 -436.195584) (xy 135.241709 -436.172536) (xy 135.241284 -436.160418) (xy 135.241284 -435.548024)
			(xy 135.239736 -435.533532) (xy 135.238086 -435.504432) (xy 135.237982 -435.489858) (xy 132.335016 -435.489858)
			(xy 132.335016 -436.160418) (xy 132.334654 -436.172546) (xy 132.327152 -436.195613) (xy 132.312886 -436.215232)
			(xy 132.293256 -436.229481) (xy 132.270183 -436.236965) (xy 132.258054 -436.23738) (xy 131.318254 -436.23738)
			(xy 131.306139 -436.236928) (xy 131.283097 -436.22943) (xy 131.263498 -436.215182) (xy 131.249257 -436.195578)
			(xy 131.241768 -436.172533) (xy 131.241292 -436.160418) (xy 131.241292 -435.548024) (xy 131.239744 -435.533532)
			(xy 131.238094 -435.504432) (xy 131.23799 -435.489858) (xy 128.335024 -435.489858) (xy 128.335024 -436.160418)
			(xy 128.334655 -436.172545) (xy 128.327153 -436.195611) (xy 128.312889 -436.215229) (xy 128.293261 -436.229478)
			(xy 128.27019 -436.236963) (xy 128.258062 -436.23738) (xy 127.318262 -436.23738) (xy 127.306147 -436.236921)
			(xy 127.283106 -436.229425) (xy 127.263506 -436.21518) (xy 127.249265 -436.195576) (xy 127.241776 -436.172533)
			(xy 127.2413 -436.160418) (xy 127.2413 -435.548024) (xy 127.239751 -435.533532) (xy 127.238102 -435.504432)
			(xy 127.237998 -435.489858) (xy 113.866512 -435.489858) (xy 113.892486 -435.537087) (xy 113.947862 -435.654438)
			(xy 113.995874 -435.77499) (xy 114.036336 -435.89828) (xy 114.069094 -436.023838) (xy 114.094022 -436.151181)
			(xy 114.111025 -436.279823) (xy 114.120038 -436.40927) (xy 114.121027 -436.539027) (xy 114.113986 -436.668596)
			(xy 114.098945 -436.797482) (xy 114.075959 -436.92519) (xy 114.045118 -437.051232) (xy 114.006538 -437.175125)
			(xy 113.960369 -437.296394) (xy 113.906786 -437.414574) (xy 113.845996 -437.529214) (xy 113.77823 -437.639874)
			(xy 113.703749 -437.74613) (xy 113.622838 -437.847575) (xy 113.535806 -437.943821) (xy 113.442988 -438.034499)
			(xy 113.378885 -438.089802) (xy 125.238002 -438.089802) (xy 125.238095 -438.075228) (xy 125.239748 -438.046127)
			(xy 125.241304 -438.031636) (xy 125.241304 -436.948072) (xy 125.239759 -436.93358) (xy 125.238107 -436.90448)
			(xy 125.238002 -436.889906) (xy 125.238095 -436.875332) (xy 125.239748 -436.846231) (xy 125.241304 -436.83174)
			(xy 125.241304 -436.218838) (xy 125.241792 -436.206721) (xy 125.249269 -436.183669) (xy 125.263505 -436.164056)
			(xy 125.283104 -436.149802) (xy 125.306149 -436.142303) (xy 125.318266 -436.141876) (xy 126.258066 -436.141876)
			(xy 126.270191 -436.142289) (xy 126.293255 -436.149777) (xy 126.312874 -436.164029) (xy 126.327125 -436.183649)
			(xy 126.334611 -436.206713) (xy 126.335028 -436.218838) (xy 126.335028 -438.760362) (xy 126.334607 -438.772486)
			(xy 126.327121 -438.79555) (xy 126.312871 -438.815168) (xy 126.293253 -438.829419) (xy 126.27019 -438.836907)
			(xy 126.258066 -438.837324) (xy 125.318266 -438.837324) (xy 125.306138 -438.836969) (xy 125.283071 -438.829462)
			(xy 125.263453 -438.815195) (xy 125.249205 -438.795564) (xy 125.24172 -438.772491) (xy 125.241304 -438.760362)
			(xy 125.241304 -438.147968) (xy 125.239759 -438.133476) (xy 125.238107 -438.104376) (xy 125.238002 -438.089802)
			(xy 113.378885 -438.089802) (xy 113.344738 -438.119261) (xy 113.241432 -438.197784) (xy 113.133467 -438.269766)
			(xy 113.021257 -438.334931) (xy 112.90523 -438.39303) (xy 112.785831 -438.443841) (xy 112.663518 -438.487169)
			(xy 112.538759 -438.522847) (xy 112.412032 -438.550739) (xy 112.283822 -438.570739) (xy 112.15462 -438.58277)
			(xy 112.024922 -438.586785) (xy 111.895224 -438.58277) (xy 111.766022 -438.570739) (xy 111.637812 -438.550739)
			(xy 111.511085 -438.522847) (xy 111.386326 -438.487169) (xy 111.264013 -438.443841) (xy 111.144614 -438.39303)
			(xy 111.028587 -438.334931) (xy 110.916377 -438.269766) (xy 110.808412 -438.197784) (xy 110.705106 -438.119261)
			(xy 110.606856 -438.034499) (xy 110.514038 -437.943821) (xy 110.427006 -437.847575) (xy 110.346095 -437.74613)
			(xy 110.271614 -437.639874) (xy 110.203848 -437.529214) (xy 110.143058 -437.414574) (xy 110.089475 -437.296394)
			(xy 110.043306 -437.175125) (xy 110.004726 -437.051232) (xy 109.973885 -436.92519) (xy 109.950899 -436.797482)
			(xy 109.935858 -436.668596) (xy 109.928817 -436.539027) (xy 109.929806 -436.40927) (xy 109.938819 -436.279823)
			(xy 109.955822 -436.151181) (xy 109.98075 -436.023838) (xy 110.013508 -435.89828) (xy 110.05397 -435.77499)
			(xy 110.101982 -435.654438) (xy 110.157358 -435.537087) (xy 110.219888 -435.423387) (xy 110.289331 -435.313772)
			(xy 110.365422 -435.208663) (xy 110.447869 -435.108462) (xy 110.536357 -435.013553) (xy 110.630546 -434.924299)
			(xy 110.679992 -434.88229) (xy 110.691093 -434.872254) (xy 110.707515 -434.847259) (xy 110.71599 -434.818578)
			(xy 110.71579 -434.788672) (xy 110.706933 -434.760107) (xy 110.690178 -434.735334) (xy 110.666963 -434.71648)
			(xy 110.653322 -434.710332) (xy 110.574304 -434.677407) (xy 110.419107 -434.605131) (xy 110.267499 -434.5256)
			(xy 110.119821 -434.438991) (xy 109.976402 -434.345497) (xy 109.837562 -434.245328) (xy 109.703613 -434.138709)
			(xy 109.574854 -434.025876) (xy 109.451573 -433.907083) (xy 109.334045 -433.782595) (xy 109.222533 -433.65269)
			(xy 109.117287 -433.517659) (xy 109.018541 -433.377804) (xy 108.926517 -433.233438) (xy 108.84142 -433.084883)
			(xy 108.763441 -432.932471) (xy 108.692754 -432.776543) (xy 108.629516 -432.617449) (xy 108.57387 -432.455542)
			(xy 108.52594 -432.291187) (xy 108.485833 -432.124749) (xy 108.453638 -431.956601) (xy 108.429428 -431.78712)
			(xy 108.413257 -431.616683) (xy 108.405161 -431.445673) (xy 108.40466 -431.360072) (xy 90.235024 -431.360072)
			(xy 90.235024 -432.560476) (xy 90.234563 -432.572581) (xy 90.227074 -432.595604) (xy 90.212823 -432.615175)
			(xy 90.193212 -432.629371) (xy 90.170168 -432.636797) (xy 90.158062 -432.637184) (xy 89.218262 -432.637184)
			(xy 89.206173 -432.636726) (xy 89.183175 -432.629261) (xy 89.163598 -432.615072) (xy 89.149348 -432.595538)
			(xy 89.141812 -432.572564) (xy 89.1413 -432.560476) (xy 89.1413 -431.948082) (xy 89.139756 -431.93359)
			(xy 89.138104 -431.90449) (xy 89.137998 -431.889916) (xy 86.235032 -431.889916) (xy 86.235032 -432.560476)
			(xy 86.234563 -432.57258) (xy 86.227075 -432.595601) (xy 86.212825 -432.615172) (xy 86.193217 -432.629369)
			(xy 86.170175 -432.636796) (xy 86.15807 -432.637184) (xy 85.21827 -432.637184) (xy 85.206181 -432.636719)
			(xy 85.183184 -432.629257) (xy 85.163606 -432.615069) (xy 85.149356 -432.595537) (xy 85.14182 -432.572563)
			(xy 85.141308 -432.560476) (xy 85.141308 -431.948082) (xy 85.139764 -431.93359) (xy 85.138112 -431.90449)
			(xy 85.138006 -431.889916) (xy 82.23504 -431.889916) (xy 82.23504 -432.560476) (xy 82.234564 -432.57258)
			(xy 82.227076 -432.595599) (xy 82.212828 -432.615169) (xy 82.193222 -432.629366) (xy 82.170183 -432.636795)
			(xy 82.158078 -432.637184) (xy 81.218278 -432.637184) (xy 81.20619 -432.636712) (xy 81.183192 -432.629252)
			(xy 81.163615 -432.615066) (xy 81.149364 -432.595535) (xy 81.141828 -432.572563) (xy 81.141316 -432.560476)
			(xy 81.141316 -431.948082) (xy 81.139772 -431.93359) (xy 81.13812 -431.90449) (xy 81.138014 -431.889916)
			(xy 78.235048 -431.889916) (xy 78.235048 -432.560476) (xy 78.234564 -432.572579) (xy 78.227077 -432.595597)
			(xy 78.212831 -432.615166) (xy 78.193227 -432.629364) (xy 78.17019 -432.636793) (xy 78.158086 -432.637184)
			(xy 77.218286 -432.637184) (xy 77.206198 -432.636705) (xy 77.183201 -432.629248) (xy 77.163623 -432.615063)
			(xy 77.149372 -432.595534) (xy 77.141836 -432.572562) (xy 77.141324 -432.560476) (xy 77.141324 -431.948082)
			(xy 77.13978 -431.93359) (xy 77.138128 -431.90449) (xy 77.138022 -431.889916) (xy 73.234804 -431.889916)
			(xy 73.234804 -432.560476) (xy 73.234367 -432.572558) (xy 73.226905 -432.59554) (xy 73.212706 -432.615091)
			(xy 73.193158 -432.629296) (xy 73.170178 -432.636764) (xy 73.158096 -432.637184) (xy 72.218296 -432.637184)
			(xy 72.206211 -432.636791) (xy 72.183224 -432.629319) (xy 72.163671 -432.615109) (xy 72.149468 -432.595551)
			(xy 72.142005 -432.572562) (xy 72.141588 -432.560476) (xy 72.141588 -431.950114) (xy 72.139918 -431.935121)
			(xy 72.138141 -431.905002) (xy 72.138032 -431.889916) (xy 69.234812 -431.889916) (xy 69.234812 -432.560476)
			(xy 69.234367 -432.572557) (xy 69.226906 -432.595538) (xy 69.212709 -432.615089) (xy 69.193163 -432.629294)
			(xy 69.170185 -432.636762) (xy 69.158104 -432.637184) (xy 68.218304 -432.637184) (xy 68.206219 -432.636784)
			(xy 68.183232 -432.629314) (xy 68.16368 -432.615106) (xy 68.149476 -432.59555) (xy 68.142013 -432.572561)
			(xy 68.141596 -432.560476) (xy 68.141596 -431.950114) (xy 68.139926 -431.935121) (xy 68.138149 -431.905002)
			(xy 68.13804 -431.889916) (xy 65.23482 -431.889916) (xy 65.23482 -432.560476) (xy 65.234367 -432.572556)
			(xy 65.226907 -432.595536) (xy 65.212711 -432.615086) (xy 65.193168 -432.629291) (xy 65.170192 -432.636761)
			(xy 65.158112 -432.637184) (xy 64.218312 -432.637184) (xy 64.206228 -432.636777) (xy 64.183241 -432.629309)
			(xy 64.163689 -432.615103) (xy 64.149485 -432.595548) (xy 64.142022 -432.572561) (xy 64.141604 -432.560476)
			(xy 64.141604 -431.950114) (xy 64.139934 -431.935121) (xy 64.138157 -431.905002) (xy 64.138048 -431.889916)
			(xy 61.234828 -431.889916) (xy 61.234828 -432.560476) (xy 61.234367 -432.572555) (xy 61.226909 -432.595534)
			(xy 61.212714 -432.615083) (xy 61.193173 -432.629288) (xy 61.170199 -432.63676) (xy 61.15812 -432.637184)
			(xy 60.21832 -432.637184) (xy 60.206236 -432.63677) (xy 60.18325 -432.629305) (xy 60.163697 -432.6151)
			(xy 60.149493 -432.595547) (xy 60.14203 -432.57256) (xy 60.141612 -432.560476) (xy 60.141612 -431.950114)
			(xy 60.139942 -431.935121) (xy 60.138165 -431.905002) (xy 60.138056 -431.889916) (xy 7.00913 -431.889916)
			(xy 7.00913 -434.48986) (xy 58.13806 -434.48986) (xy 58.138173 -434.474774) (xy 58.139952 -434.444656)
			(xy 58.141616 -434.429662) (xy 58.141616 -433.350162) (xy 58.139951 -433.335168) (xy 58.13817 -433.30505)
			(xy 58.13806 -433.289964) (xy 58.138173 -433.274878) (xy 58.139952 -433.24476) (xy 58.141616 -433.229766)
			(xy 58.141616 -432.618896) (xy 58.142009 -432.606811) (xy 58.149481 -432.583824) (xy 58.163691 -432.564271)
			(xy 58.183249 -432.550068) (xy 58.206238 -432.542605) (xy 58.218324 -432.542188) (xy 59.158124 -432.542188)
			(xy 59.170199 -432.542644) (xy 59.193167 -432.550113) (xy 59.212703 -432.564311) (xy 59.226897 -432.583851)
			(xy 59.234359 -432.606821) (xy 59.234832 -432.618896) (xy 59.234832 -435.16042) (xy 59.234353 -435.172493)
			(xy 59.226888 -435.195457) (xy 59.212694 -435.214991) (xy 59.19316 -435.229186) (xy 59.170197 -435.236652)
			(xy 59.158124 -435.237128) (xy 58.218324 -435.237128) (xy 58.206245 -435.236667) (xy 58.183266 -435.229209)
			(xy 58.163717 -435.215014) (xy 58.149512 -435.195473) (xy 58.14204 -435.172499) (xy 58.141616 -435.16042)
			(xy 58.141616 -434.550058) (xy 58.13995 -434.535064) (xy 58.13817 -434.504946) (xy 58.13806 -434.48986)
			(xy 7.00913 -434.48986) (xy 7.00913 -435.489858) (xy 60.138056 -435.489858) (xy 60.138169 -435.474772)
			(xy 60.139948 -435.444654) (xy 60.141612 -435.42966) (xy 60.141612 -434.35016) (xy 60.139947 -434.335166)
			(xy 60.138166 -434.305048) (xy 60.138056 -434.289962) (xy 60.138169 -434.274876) (xy 60.139948 -434.244758)
			(xy 60.141612 -434.229764) (xy 60.141612 -433.618894) (xy 60.142102 -433.606807) (xy 60.149557 -433.583811)
			(xy 60.163739 -433.564234) (xy 60.183265 -433.549982) (xy 60.206235 -433.542445) (xy 60.21832 -433.541932)
			(xy 61.15812 -433.541932) (xy 61.170233 -433.5423) (xy 61.193267 -433.549808) (xy 61.212842 -433.564081)
			(xy 61.227035 -433.583715) (xy 61.234449 -433.606779) (xy 61.234828 -433.618894) (xy 61.234828 -434.48986)
			(xy 62.138052 -434.48986) (xy 62.138165 -434.474774) (xy 62.139944 -434.444656) (xy 62.141608 -434.429662)
			(xy 62.141608 -433.350162) (xy 62.139943 -433.335168) (xy 62.138162 -433.30505) (xy 62.138052 -433.289964)
			(xy 62.138165 -433.274878) (xy 62.139944 -433.24476) (xy 62.141608 -433.229766) (xy 62.141608 -432.618896)
			(xy 62.142009 -432.606811) (xy 62.14948 -432.583826) (xy 62.163688 -432.564274) (xy 62.183244 -432.550071)
			(xy 62.206231 -432.542606) (xy 62.218316 -432.542188) (xy 63.158116 -432.542188) (xy 63.170191 -432.542651)
			(xy 63.193158 -432.550117) (xy 63.212694 -432.564314) (xy 63.226888 -432.583853) (xy 63.234351 -432.606821)
			(xy 63.234824 -432.618896) (xy 63.234824 -435.16042) (xy 63.234353 -435.172494) (xy 63.226887 -435.195459)
			(xy 63.212691 -435.214994) (xy 63.193155 -435.229189) (xy 63.17019 -435.236654) (xy 63.158116 -435.237128)
			(xy 62.218316 -435.237128) (xy 62.206244 -435.236622) (xy 62.183281 -435.229167) (xy 62.163745 -435.21498)
			(xy 62.14955 -435.195451) (xy 62.142083 -435.172492) (xy 62.141608 -435.16042) (xy 62.141608 -434.550058)
			(xy 62.139942 -434.535064) (xy 62.138162 -434.504946) (xy 62.138052 -434.48986) (xy 61.234828 -434.48986)
			(xy 61.234828 -435.489858) (xy 64.138048 -435.489858) (xy 64.138161 -435.474772) (xy 64.13994 -435.444654)
			(xy 64.141604 -435.42966) (xy 64.141604 -434.35016) (xy 64.139938 -434.335166) (xy 64.138158 -434.305048)
			(xy 64.138048 -434.289962) (xy 64.138161 -434.274876) (xy 64.13994 -434.244758) (xy 64.141604 -434.229764)
			(xy 64.141604 -433.618894) (xy 64.142102 -433.606808) (xy 64.149556 -433.583813) (xy 64.163736 -433.564236)
			(xy 64.18326 -433.549985) (xy 64.206228 -433.542447) (xy 64.218312 -433.541932) (xy 65.158112 -433.541932)
			(xy 65.170225 -433.542306) (xy 65.193258 -433.549813) (xy 65.212834 -433.564084) (xy 65.227027 -433.583717)
			(xy 65.234441 -433.60678) (xy 65.23482 -433.618894) (xy 65.23482 -434.48986) (xy 66.138044 -434.48986)
			(xy 66.138157 -434.474774) (xy 66.139936 -434.444656) (xy 66.1416 -434.429662) (xy 66.1416 -433.350162)
			(xy 66.139935 -433.335168) (xy 66.138154 -433.30505) (xy 66.138044 -433.289964) (xy 66.138157 -433.274878)
			(xy 66.139936 -433.24476) (xy 66.1416 -433.229766) (xy 66.1416 -432.618896) (xy 66.142009 -432.606812)
			(xy 66.149479 -432.583828) (xy 66.163686 -432.564277) (xy 66.183239 -432.550073) (xy 66.206224 -432.542607)
			(xy 66.218308 -432.542188) (xy 67.158108 -432.542188) (xy 67.170183 -432.542657) (xy 67.193149 -432.550122)
			(xy 67.212686 -432.564317) (xy 67.22688 -432.583854) (xy 67.234343 -432.606821) (xy 67.234816 -432.618896)
			(xy 67.234816 -435.16042) (xy 67.234353 -435.172495) (xy 67.226886 -435.195461) (xy 67.212689 -435.214997)
			(xy 67.19315 -435.229191) (xy 67.170183 -435.236655) (xy 67.158108 -435.237128) (xy 66.218308 -435.237128)
			(xy 66.206236 -435.236629) (xy 66.183272 -435.229171) (xy 66.163737 -435.214983) (xy 66.149541 -435.195453)
			(xy 66.142075 -435.172492) (xy 66.1416 -435.16042) (xy 66.1416 -434.550058) (xy 66.139934 -434.535064)
			(xy 66.138154 -434.504946) (xy 66.138044 -434.48986) (xy 65.23482 -434.48986) (xy 65.23482 -435.489858)
			(xy 68.13804 -435.489858) (xy 68.138153 -435.474772) (xy 68.139932 -435.444654) (xy 68.141596 -435.42966)
			(xy 68.141596 -434.35016) (xy 68.13993 -434.335166) (xy 68.13815 -434.305048) (xy 68.13804 -434.289962)
			(xy 68.138153 -434.274876) (xy 68.139932 -434.244758) (xy 68.141596 -434.229764) (xy 68.141596 -433.618894)
			(xy 68.142102 -433.606809) (xy 68.149555 -433.583815) (xy 68.163733 -433.564239) (xy 68.183255 -433.549987)
			(xy 68.20622 -433.542448) (xy 68.218304 -433.541932) (xy 69.158104 -433.541932) (xy 69.170216 -433.542313)
			(xy 69.193249 -433.549818) (xy 69.212825 -433.564087) (xy 69.227018 -433.583718) (xy 69.234433 -433.60678)
			(xy 69.234812 -433.618894) (xy 69.234812 -434.48986) (xy 70.138036 -434.48986) (xy 70.138151 -434.474775)
			(xy 70.13993 -434.444656) (xy 70.141592 -434.429662) (xy 70.141592 -433.350162) (xy 70.139927 -433.335168)
			(xy 70.138146 -433.30505) (xy 70.138036 -433.289964) (xy 70.138152 -433.274879) (xy 70.13993 -433.24476)
			(xy 70.141592 -433.229766) (xy 70.141592 -432.618896) (xy 70.142061 -432.606821) (xy 70.149524 -432.583854)
			(xy 70.16372 -432.564317) (xy 70.183258 -432.550123) (xy 70.206225 -432.54266) (xy 70.2183 -432.542188)
			(xy 71.1581 -432.542188) (xy 71.170174 -432.542664) (xy 71.193141 -432.550126) (xy 71.212677 -432.56432)
			(xy 71.226872 -432.583856) (xy 71.234335 -432.606822) (xy 71.234808 -432.618896) (xy 71.234808 -435.16042)
			(xy 71.234353 -435.172496) (xy 71.226885 -435.195463) (xy 71.212686 -435.215) (xy 71.193145 -435.229194)
			(xy 71.170176 -435.236656) (xy 71.1581 -435.237128) (xy 70.2183 -435.237128) (xy 70.206227 -435.236636)
			(xy 70.183264 -435.229176) (xy 70.163728 -435.214986) (xy 70.149533 -435.195454) (xy 70.142067 -435.172492)
			(xy 70.141592 -435.16042) (xy 70.141592 -434.550058) (xy 70.139926 -434.535064) (xy 70.138146 -434.504946)
			(xy 70.138036 -434.48986) (xy 69.234812 -434.48986) (xy 69.234812 -435.489858) (xy 72.138032 -435.489858)
			(xy 72.138147 -435.474773) (xy 72.139926 -435.444654) (xy 72.141588 -435.42966) (xy 72.141588 -434.35016)
			(xy 72.139922 -434.335166) (xy 72.138142 -434.305048) (xy 72.138032 -434.289962) (xy 72.138147 -434.274877)
			(xy 72.139926 -434.244758) (xy 72.141588 -434.229764) (xy 72.141588 -433.618894) (xy 72.142003 -433.606799)
			(xy 72.149468 -433.583791) (xy 72.163666 -433.564207) (xy 72.183213 -433.549958) (xy 72.206203 -433.542435)
			(xy 72.218296 -433.541932) (xy 73.158096 -433.541932) (xy 73.170208 -433.54232) (xy 73.193241 -433.549822)
			(xy 73.212817 -433.56409) (xy 73.22701 -433.58372) (xy 73.234425 -433.606781) (xy 73.234804 -433.618894)
			(xy 73.234804 -434.48986) (xy 75.138026 -434.48986) (xy 75.138124 -434.475286) (xy 75.139774 -434.446185)
			(xy 75.141328 -434.431694) (xy 75.141328 -433.34813) (xy 75.13978 -433.333638) (xy 75.13813 -433.304538)
			(xy 75.138026 -433.289964) (xy 75.138124 -433.27539) (xy 75.139774 -433.246289) (xy 75.141328 -433.231798)
			(xy 75.141328 -432.618896) (xy 75.141713 -432.606784) (xy 75.149217 -432.583752) (xy 75.163486 -432.564176)
			(xy 75.183116 -432.549983) (xy 75.206177 -432.542567) (xy 75.21829 -432.542188) (xy 76.15809 -432.542188)
			(xy 76.170184 -432.542617) (xy 76.193192 -432.550077) (xy 76.212776 -432.564271) (xy 76.227025 -432.583816)
			(xy 76.234549 -432.606804) (xy 76.235052 -432.618896) (xy 76.235052 -435.16042) (xy 76.234601 -435.172525)
			(xy 76.227103 -435.195544) (xy 76.212848 -435.215112) (xy 76.193237 -435.229308) (xy 76.170196 -435.236737)
			(xy 76.15809 -435.237128) (xy 75.21829 -435.237128) (xy 75.206197 -435.2367) (xy 75.183191 -435.229237)
			(xy 75.163608 -435.215041) (xy 75.149359 -435.195498) (xy 75.141833 -435.172512) (xy 75.141328 -435.16042)
			(xy 75.141328 -434.548026) (xy 75.13978 -434.533534) (xy 75.13813 -434.504434) (xy 75.138026 -434.48986)
			(xy 73.234804 -434.48986) (xy 73.234804 -435.489858) (xy 77.138022 -435.489858) (xy 77.13812 -435.475284)
			(xy 77.13977 -435.446183) (xy 77.141324 -435.431692) (xy 77.141324 -434.348128) (xy 77.139776 -434.333636)
			(xy 77.138126 -434.304536) (xy 77.138022 -434.289962) (xy 77.13812 -434.275388) (xy 77.13977 -434.246287)
			(xy 77.141324 -434.231796) (xy 77.141324 -433.618894) (xy 77.141807 -433.606781) (xy 77.149294 -433.58374)
			(xy 77.163534 -433.564139) (xy 77.183132 -433.549897) (xy 77.206173 -433.542408) (xy 77.218286 -433.541932)
			(xy 78.158086 -433.541932) (xy 78.170207 -433.542372) (xy 78.193265 -433.54986) (xy 78.21288 -433.564106)
			(xy 78.227131 -433.583717) (xy 78.234625 -433.606773) (xy 78.235048 -433.618894) (xy 78.235048 -434.48986)
			(xy 79.138018 -434.48986) (xy 79.138116 -434.475286) (xy 79.139766 -434.446185) (xy 79.14132 -434.431694)
			(xy 79.14132 -433.34813) (xy 79.139772 -433.333638) (xy 79.138122 -433.304538) (xy 79.138018 -433.289964)
			(xy 79.138116 -433.27539) (xy 79.139766 -433.246289) (xy 79.14132 -433.231798) (xy 79.14132 -432.618896)
			(xy 79.141713 -432.606785) (xy 79.149216 -432.583754) (xy 79.163483 -432.564179) (xy 79.183111 -432.549985)
			(xy 79.206169 -432.542568) (xy 79.218282 -432.542188) (xy 80.158082 -432.542188) (xy 80.170175 -432.542624)
			(xy 80.193183 -432.550081) (xy 80.212768 -432.564274) (xy 80.227017 -432.583818) (xy 80.234541 -432.606804)
			(xy 80.235044 -432.618896) (xy 80.235044 -435.16042) (xy 80.234601 -435.172526) (xy 80.227102 -435.195546)
			(xy 80.212845 -435.215115) (xy 80.193232 -435.22931) (xy 80.170189 -435.236739) (xy 80.158082 -435.237128)
			(xy 79.218282 -435.237128) (xy 79.206188 -435.236708) (xy 79.183182 -435.229242) (xy 79.163599 -435.215045)
			(xy 79.14935 -435.195499) (xy 79.141824 -435.172512) (xy 79.14132 -435.16042) (xy 79.14132 -434.548026)
			(xy 79.139772 -434.533534) (xy 79.138122 -434.504434) (xy 79.138018 -434.48986) (xy 78.235048 -434.48986)
			(xy 78.235048 -435.489858) (xy 81.138014 -435.489858) (xy 81.138111 -435.475284) (xy 81.139761 -435.446183)
			(xy 81.141316 -435.431692) (xy 81.141316 -434.348128) (xy 81.139768 -434.333636) (xy 81.138118 -434.304536)
			(xy 81.138014 -434.289962) (xy 81.138112 -434.275388) (xy 81.139761 -434.246287) (xy 81.141316 -434.231796)
			(xy 81.141316 -433.618894) (xy 81.141807 -433.606781) (xy 81.149293 -433.583742) (xy 81.163531 -433.564142)
			(xy 81.183127 -433.5499) (xy 81.206165 -433.542409) (xy 81.218278 -433.541932) (xy 82.158078 -433.541932)
			(xy 82.170199 -433.542379) (xy 82.193256 -433.549864) (xy 82.212871 -433.564109) (xy 82.227123 -433.583719)
			(xy 82.234617 -433.606773) (xy 82.23504 -433.618894) (xy 82.23504 -434.48986) (xy 83.13801 -434.48986)
			(xy 83.138107 -434.475286) (xy 83.139757 -434.446185) (xy 83.141312 -434.431694) (xy 83.141312 -433.34813)
			(xy 83.139764 -433.333638) (xy 83.138114 -433.304538) (xy 83.13801 -433.289964) (xy 83.138108 -433.27539)
			(xy 83.139757 -433.246289) (xy 83.141312 -433.231798) (xy 83.141312 -432.618896) (xy 83.141713 -432.606786)
			(xy 83.149215 -432.583756) (xy 83.16348 -432.564182) (xy 83.183106 -432.549988) (xy 83.206162 -432.542569)
			(xy 83.218274 -432.542188) (xy 84.158074 -432.542188) (xy 84.170167 -432.54263) (xy 84.193175 -432.550086)
			(xy 84.212759 -432.564277) (xy 84.227009 -432.583819) (xy 84.234533 -432.606804) (xy 84.235036 -432.618896)
			(xy 84.235036 -435.16042) (xy 84.234601 -435.172526) (xy 84.227101 -435.195548) (xy 84.212843 -435.215118)
			(xy 84.193227 -435.229313) (xy 84.170182 -435.23674) (xy 84.158074 -435.237128) (xy 83.218274 -435.237128)
			(xy 83.20618 -435.236714) (xy 83.183173 -435.229247) (xy 83.163591 -435.215047) (xy 83.149342 -435.195501)
			(xy 83.141816 -435.172513) (xy 83.141312 -435.16042) (xy 83.141312 -434.548026) (xy 83.139764 -434.533534)
			(xy 83.138114 -434.504434) (xy 83.13801 -434.48986) (xy 82.23504 -434.48986) (xy 82.23504 -435.489858)
			(xy 85.138006 -435.489858) (xy 85.138103 -435.475284) (xy 85.139753 -435.446183) (xy 85.141308 -435.431692)
			(xy 85.141308 -434.348128) (xy 85.13976 -434.333636) (xy 85.13811 -434.304536) (xy 85.138006 -434.289962)
			(xy 85.138104 -434.275388) (xy 85.139753 -434.246287) (xy 85.141308 -434.231796) (xy 85.141308 -433.618894)
			(xy 85.141806 -433.606782) (xy 85.149292 -433.583744) (xy 85.163528 -433.564145) (xy 85.183122 -433.549903)
			(xy 85.206158 -433.54241) (xy 85.21827 -433.541932) (xy 86.15807 -433.541932) (xy 86.170191 -433.542385)
			(xy 86.193247 -433.549869) (xy 86.212863 -433.564112) (xy 86.227115 -433.58372) (xy 86.234609 -433.606774)
			(xy 86.235032 -433.618894) (xy 86.235032 -434.48986) (xy 87.138002 -434.48986) (xy 87.1381 -434.475286)
			(xy 87.139749 -434.446185) (xy 87.141304 -434.431694) (xy 87.141304 -433.34813) (xy 87.139756 -433.333638)
			(xy 87.138106 -433.304538) (xy 87.138002 -433.289964) (xy 87.1381 -433.27539) (xy 87.139749 -433.246289)
			(xy 87.141304 -433.231798) (xy 87.141304 -432.618896) (xy 87.141713 -432.606787) (xy 87.149214 -432.583758)
			(xy 87.163477 -432.564185) (xy 87.183101 -432.549991) (xy 87.206155 -432.542571) (xy 87.218266 -432.542188)
			(xy 88.158066 -432.542188) (xy 88.170159 -432.542637) (xy 88.193166 -432.55009) (xy 88.212751 -432.56428)
			(xy 88.227001 -432.583821) (xy 88.234525 -432.606805) (xy 88.235028 -432.618896) (xy 88.235028 -435.16042)
			(xy 88.234601 -435.172527) (xy 88.2271 -435.19555) (xy 88.21284 -435.215121) (xy 88.193222 -435.229316)
			(xy 88.170174 -435.236741) (xy 88.158066 -435.237128) (xy 87.218266 -435.237128) (xy 87.206171 -435.236721)
			(xy 87.183164 -435.229251) (xy 87.163582 -435.21505) (xy 87.149334 -435.195502) (xy 87.141808 -435.172513)
			(xy 87.141304 -435.16042) (xy 87.141304 -434.548026) (xy 87.139756 -434.533534) (xy 87.138106 -434.504434)
			(xy 87.138002 -434.48986) (xy 86.235032 -434.48986) (xy 86.235032 -435.489858) (xy 89.137998 -435.489858)
			(xy 89.138095 -435.475284) (xy 89.139745 -435.446183) (xy 89.1413 -435.431692) (xy 89.1413 -434.348128)
			(xy 89.139752 -434.333636) (xy 89.138102 -434.304536) (xy 89.137998 -434.289962) (xy 89.138096 -434.275388)
			(xy 89.139745 -434.246287) (xy 89.1413 -434.231796) (xy 89.1413 -433.618894) (xy 89.141806 -433.606783)
			(xy 89.14929 -433.583746) (xy 89.163525 -433.564148) (xy 89.183117 -433.549905) (xy 89.206151 -433.542411)
			(xy 89.218262 -433.541932) (xy 90.158062 -433.541932) (xy 90.170182 -433.542392) (xy 90.193239 -433.549873)
			(xy 90.212854 -433.564115) (xy 90.227107 -433.583722) (xy 90.234601 -433.606774) (xy 90.235024 -433.618894)
			(xy 90.235024 -436.160418) (xy 90.234655 -436.172545) (xy 90.227153 -436.195611) (xy 90.212889 -436.215229)
			(xy 90.193261 -436.229478) (xy 90.17019 -436.236963) (xy 90.158062 -436.23738) (xy 89.218262 -436.23738)
			(xy 89.206147 -436.236921) (xy 89.183106 -436.229425) (xy 89.163506 -436.21518) (xy 89.149265 -436.195576)
			(xy 89.141776 -436.172533) (xy 89.1413 -436.160418) (xy 89.1413 -435.548024) (xy 89.139751 -435.533532)
			(xy 89.138102 -435.504432) (xy 89.137998 -435.489858) (xy 86.235032 -435.489858) (xy 86.235032 -436.160418)
			(xy 86.234655 -436.172545) (xy 86.227154 -436.195609) (xy 86.212892 -436.215226) (xy 86.193266 -436.229476)
			(xy 86.170197 -436.236962) (xy 86.15807 -436.23738) (xy 85.21827 -436.23738) (xy 85.206156 -436.236914)
			(xy 85.183114 -436.229421) (xy 85.163515 -436.215177) (xy 85.149274 -436.195575) (xy 85.141784 -436.172532)
			(xy 85.141308 -436.160418) (xy 85.141308 -435.548024) (xy 85.139759 -435.533532) (xy 85.13811 -435.504432)
			(xy 85.138006 -435.489858) (xy 82.23504 -435.489858) (xy 82.23504 -436.160418) (xy 82.234655 -436.172544)
			(xy 82.227155 -436.195607) (xy 82.212895 -436.215224) (xy 82.193271 -436.229473) (xy 82.170204 -436.236961)
			(xy 82.158078 -436.23738) (xy 81.218278 -436.23738) (xy 81.206164 -436.236907) (xy 81.183123 -436.229416)
			(xy 81.163523 -436.215174) (xy 81.149282 -436.195573) (xy 81.141792 -436.172532) (xy 81.141316 -436.160418)
			(xy 81.141316 -435.548024) (xy 81.139767 -435.533532) (xy 81.138118 -435.504432) (xy 81.138014 -435.489858)
			(xy 78.235048 -435.489858) (xy 78.235048 -436.160418) (xy 78.234604 -436.172535) (xy 78.22711 -436.195581)
			(xy 78.212861 -436.215184) (xy 78.193252 -436.229424) (xy 78.170203 -436.236909) (xy 78.158086 -436.23738)
			(xy 77.218286 -436.23738) (xy 77.206172 -436.236901) (xy 77.183132 -436.229412) (xy 77.163532 -436.215171)
			(xy 77.14929 -436.195572) (xy 77.1418 -436.172531) (xy 77.141324 -436.160418) (xy 77.141324 -435.548024)
			(xy 77.139775 -435.533532) (xy 77.138126 -435.504432) (xy 77.138022 -435.489858) (xy 73.234804 -435.489858)
			(xy 73.234804 -436.160418) (xy 73.234309 -436.172504) (xy 73.226853 -436.195498) (xy 73.212672 -436.215074)
			(xy 73.193147 -436.229325) (xy 73.17018 -436.236865) (xy 73.158096 -436.23738) (xy 72.218296 -436.23738)
			(xy 72.206185 -436.236987) (xy 72.183154 -436.229484) (xy 72.163579 -436.215217) (xy 72.149385 -436.195589)
			(xy 72.141968 -436.172531) (xy 72.141588 -436.160418) (xy 72.141588 -435.550056) (xy 72.139922 -435.535062)
			(xy 72.138142 -435.504944) (xy 72.138032 -435.489858) (xy 69.234812 -435.489858) (xy 69.234812 -436.160418)
			(xy 69.234407 -436.172513) (xy 69.22694 -436.195523) (xy 69.212739 -436.215106) (xy 69.193189 -436.229355)
			(xy 69.170198 -436.236878) (xy 69.158104 -436.23738) (xy 68.218304 -436.23738) (xy 68.206193 -436.23698)
			(xy 68.183163 -436.229479) (xy 68.163588 -436.215214) (xy 68.149394 -436.195588) (xy 68.141976 -436.17253)
			(xy 68.141596 -436.160418) (xy 68.141596 -435.550056) (xy 68.13993 -435.535062) (xy 68.13815 -435.504944)
			(xy 68.13804 -435.489858) (xy 65.23482 -435.489858) (xy 65.23482 -436.160418) (xy 65.234407 -436.172513)
			(xy 65.226941 -436.195521) (xy 65.212742 -436.215104) (xy 65.193194 -436.229352) (xy 65.170205 -436.236877)
			(xy 65.158112 -436.23738) (xy 64.218312 -436.23738) (xy 64.206202 -436.236973) (xy 64.183172 -436.229474)
			(xy 64.163597 -436.215211) (xy 64.149402 -436.195586) (xy 64.141985 -436.17253) (xy 64.141604 -436.160418)
			(xy 64.141604 -435.550056) (xy 64.139938 -435.535062) (xy 64.138158 -435.504944) (xy 64.138048 -435.489858)
			(xy 61.234828 -435.489858) (xy 61.234828 -436.160418) (xy 61.234408 -436.172512) (xy 61.226942 -436.195518)
			(xy 61.212745 -436.215101) (xy 61.193199 -436.22935) (xy 61.170212 -436.236876) (xy 61.15812 -436.23738)
			(xy 60.21832 -436.23738) (xy 60.20621 -436.236966) (xy 60.18318 -436.22947) (xy 60.163605 -436.215208)
			(xy 60.149411 -436.195585) (xy 60.141993 -436.172529) (xy 60.141612 -436.160418) (xy 60.141612 -435.550056)
			(xy 60.139946 -435.535062) (xy 60.138166 -435.504944) (xy 60.138056 -435.489858) (xy 7.00913 -435.489858)
			(xy 7.00913 -438.089802) (xy 58.13806 -438.089802) (xy 58.138177 -438.074717) (xy 58.139953 -438.044598)
			(xy 58.141616 -438.029604) (xy 58.141616 -436.950104) (xy 58.139946 -436.935111) (xy 58.138168 -436.904992)
			(xy 58.13806 -436.889906) (xy 58.138168 -436.87482) (xy 58.13995 -436.844702) (xy 58.141616 -436.829708)
			(xy 58.141616 -436.219092) (xy 58.142006 -436.207006) (xy 58.149479 -436.184019) (xy 58.16369 -436.164467)
			(xy 58.183248 -436.150264) (xy 58.206238 -436.142801) (xy 58.218324 -436.142384) (xy 59.158124 -436.142384)
			(xy 59.170199 -436.142844) (xy 59.193166 -436.150312) (xy 59.212701 -436.16451) (xy 59.226895 -436.184049)
			(xy 59.234359 -436.207017) (xy 59.234832 -436.219092) (xy 59.234832 -438.760616) (xy 59.23435 -438.772689)
			(xy 59.226886 -438.795653) (xy 59.212693 -438.815187) (xy 59.19316 -438.829382) (xy 59.170197 -438.836848)
			(xy 59.158124 -438.837324) (xy 58.218324 -438.837324) (xy 58.206244 -438.836867) (xy 58.183265 -438.829408)
			(xy 58.163716 -438.815213) (xy 58.14951 -438.795671) (xy 58.142039 -438.772696) (xy 58.141616 -438.760616)
			(xy 58.141616 -438.15) (xy 58.139945 -438.135007) (xy 58.138168 -438.104888) (xy 58.13806 -438.089802)
			(xy 7.00913 -438.089802) (xy 7.00913 -439.0898) (xy 60.138056 -439.0898) (xy 60.138173 -439.074715)
			(xy 60.139949 -439.044596) (xy 60.141612 -439.029602) (xy 60.141612 -437.950102) (xy 60.139941 -437.935109)
			(xy 60.138164 -437.90499) (xy 60.138056 -437.889904) (xy 60.138173 -437.874819) (xy 60.139949 -437.8447)
			(xy 60.141612 -437.829706) (xy 60.141612 -437.21909) (xy 60.142099 -437.207003) (xy 60.149555 -437.184007)
			(xy 60.163737 -437.164429) (xy 60.183265 -437.150178) (xy 60.206234 -437.142641) (xy 60.21832 -437.142128)
			(xy 61.15812 -437.142128) (xy 61.170233 -437.1425) (xy 61.193265 -437.150008) (xy 61.212841 -437.16428)
			(xy 61.227034 -437.183913) (xy 61.234449 -437.206976) (xy 61.234828 -437.21909) (xy 61.234828 -438.089802)
			(xy 62.138052 -438.089802) (xy 62.138169 -438.074717) (xy 62.139945 -438.044598) (xy 62.141608 -438.029604)
			(xy 62.141608 -436.950104) (xy 62.139938 -436.935111) (xy 62.13816 -436.904992) (xy 62.138052 -436.889906)
			(xy 62.13816 -436.87482) (xy 62.139942 -436.844702) (xy 62.141608 -436.829708) (xy 62.141608 -436.219092)
			(xy 62.142006 -436.207007) (xy 62.149478 -436.184021) (xy 62.163687 -436.16447) (xy 62.183243 -436.150267)
			(xy 62.206231 -436.142802) (xy 62.218316 -436.142384) (xy 63.158116 -436.142384) (xy 63.170191 -436.142851)
			(xy 63.193157 -436.150317) (xy 63.212693 -436.164513) (xy 63.226887 -436.18405) (xy 63.234351 -436.207017)
			(xy 63.234824 -436.219092) (xy 63.234824 -438.760616) (xy 63.23435 -438.77269) (xy 63.226885 -438.795655)
			(xy 63.21269 -438.81519) (xy 63.193155 -438.829385) (xy 63.17019 -438.83685) (xy 63.158116 -438.837324)
			(xy 62.218316 -438.837324) (xy 62.206244 -438.836822) (xy 62.18328 -438.829366) (xy 62.163744 -438.815179)
			(xy 62.149548 -438.795649) (xy 62.142083 -438.772688) (xy 62.141608 -438.760616) (xy 62.141608 -438.15)
			(xy 62.139937 -438.135007) (xy 62.13816 -438.104888) (xy 62.138052 -438.089802) (xy 61.234828 -438.089802)
			(xy 61.234828 -439.0898) (xy 64.138048 -439.0898) (xy 64.138165 -439.074715) (xy 64.139941 -439.044596)
			(xy 64.141604 -439.029602) (xy 64.141604 -437.950102) (xy 64.139933 -437.935109) (xy 64.138156 -437.90499)
			(xy 64.138048 -437.889904) (xy 64.138165 -437.874819) (xy 64.139941 -437.8447) (xy 64.141604 -437.829706)
			(xy 64.141604 -437.21909) (xy 64.142098 -437.207004) (xy 64.149553 -437.184009) (xy 64.163734 -437.164432)
			(xy 64.18326 -437.150181) (xy 64.206227 -437.142643) (xy 64.218312 -437.142128) (xy 65.158112 -437.142128)
			(xy 65.170224 -437.142506) (xy 65.193257 -437.150012) (xy 65.212832 -437.164283) (xy 65.227025 -437.183914)
			(xy 65.234441 -437.206976) (xy 65.23482 -437.21909) (xy 65.23482 -438.089802) (xy 66.138044 -438.089802)
			(xy 66.138161 -438.074717) (xy 66.139937 -438.044598) (xy 66.1416 -438.029604) (xy 66.1416 -436.950104)
			(xy 66.13993 -436.935111) (xy 66.138152 -436.904992) (xy 66.138044 -436.889906) (xy 66.138152 -436.87482)
			(xy 66.139934 -436.844702) (xy 66.1416 -436.829708) (xy 66.1416 -436.219092) (xy 66.142058 -436.207016)
			(xy 66.149523 -436.184047) (xy 66.163721 -436.16451) (xy 66.183262 -436.150316) (xy 66.206232 -436.142855)
			(xy 66.218308 -436.142384) (xy 67.158108 -436.142384) (xy 67.170182 -436.142857) (xy 67.193148 -436.150321)
			(xy 67.212684 -436.164516) (xy 67.226879 -436.184052) (xy 67.234343 -436.207018) (xy 67.234816 -436.219092)
			(xy 67.234816 -438.760616) (xy 67.234349 -438.772691) (xy 67.226883 -438.795657) (xy 67.212687 -438.815193)
			(xy 67.19315 -438.829387) (xy 67.170183 -438.836851) (xy 67.158108 -438.837324) (xy 66.218308 -438.837324)
			(xy 66.206235 -438.836829) (xy 66.183271 -438.829371) (xy 66.163735 -438.815182) (xy 66.14954 -438.79565)
			(xy 66.142075 -438.772688) (xy 66.1416 -438.760616) (xy 66.1416 -438.15) (xy 66.139929 -438.135007)
			(xy 66.138152 -438.104888) (xy 66.138044 -438.089802) (xy 65.23482 -438.089802) (xy 65.23482 -439.0898)
			(xy 68.13804 -439.0898) (xy 68.138157 -439.074715) (xy 68.139933 -439.044596) (xy 68.141596 -439.029602)
			(xy 68.141596 -437.950102) (xy 68.139925 -437.935109) (xy 68.138148 -437.90499) (xy 68.13804 -437.889904)
			(xy 68.138157 -437.874819) (xy 68.139933 -437.8447) (xy 68.141596 -437.829706) (xy 68.141596 -437.21909)
			(xy 68.142098 -437.207004) (xy 68.149552 -437.184011) (xy 68.163731 -437.164435) (xy 68.183255 -437.150183)
			(xy 68.20622 -437.142644) (xy 68.218304 -437.142128) (xy 69.158104 -437.142128) (xy 69.170216 -437.142513)
			(xy 69.193248 -437.150017) (xy 69.212824 -437.164286) (xy 69.227017 -437.183916) (xy 69.234433 -437.206977)
			(xy 69.234812 -437.21909) (xy 69.234812 -438.089802) (xy 70.138036 -438.089802) (xy 70.138153 -438.074717)
			(xy 70.139929 -438.044598) (xy 70.141592 -438.029604) (xy 70.141592 -436.950104) (xy 70.139922 -436.935111)
			(xy 70.138144 -436.904992) (xy 70.138036 -436.889906) (xy 70.138146 -436.87482) (xy 70.139928 -436.844702)
			(xy 70.141592 -436.829708) (xy 70.141592 -436.219092) (xy 70.142058 -436.207017) (xy 70.149522 -436.18405)
			(xy 70.163718 -436.164513) (xy 70.183257 -436.150319) (xy 70.206225 -436.142856) (xy 70.2183 -436.142384)
			(xy 71.1581 -436.142384) (xy 71.170174 -436.142864) (xy 71.19314 -436.150326) (xy 71.212676 -436.164518)
			(xy 71.226871 -436.184053) (xy 71.234335 -436.207018) (xy 71.234808 -436.219092) (xy 71.234808 -438.760616)
			(xy 71.234349 -438.772691) (xy 71.226882 -438.795659) (xy 71.212684 -438.815196) (xy 71.193145 -438.82939)
			(xy 71.170175 -438.836852) (xy 71.1581 -438.837324) (xy 70.2183 -438.837324) (xy 70.206227 -438.836836)
			(xy 70.183263 -438.829375) (xy 70.163727 -438.815184) (xy 70.149532 -438.795652) (xy 70.142067 -438.772689)
			(xy 70.141592 -438.760616) (xy 70.141592 -438.15) (xy 70.139921 -438.135007) (xy 70.138144 -438.104888)
			(xy 70.138036 -438.089802) (xy 69.234812 -438.089802) (xy 69.234812 -439.0898) (xy 72.138032 -439.0898)
			(xy 72.138151 -439.074715) (xy 72.139927 -439.044596) (xy 72.141588 -439.029602) (xy 72.141588 -437.950102)
			(xy 72.139917 -437.935109) (xy 72.13814 -437.90499) (xy 72.138032 -437.889904) (xy 72.138151 -437.874819)
			(xy 72.139927 -437.8447) (xy 72.141588 -437.829706) (xy 72.141588 -437.21909) (xy 72.142 -437.206995)
			(xy 72.149465 -437.183986) (xy 72.163664 -437.164402) (xy 72.183212 -437.150154) (xy 72.206202 -437.142631)
			(xy 72.218296 -437.142128) (xy 73.158096 -437.142128) (xy 73.170207 -437.14252) (xy 73.193239 -437.150022)
			(xy 73.212815 -437.164288) (xy 73.227009 -437.183917) (xy 73.234425 -437.206977) (xy 73.234804 -437.21909)
			(xy 73.234804 -438.089802) (xy 75.138026 -438.089802) (xy 75.138119 -438.075228) (xy 75.139772 -438.046127)
			(xy 75.141328 -438.031636) (xy 75.141328 -436.948072) (xy 75.139784 -436.93358) (xy 75.138131 -436.90448)
			(xy 75.138026 -436.889906) (xy 75.138119 -436.875332) (xy 75.139772 -436.846231) (xy 75.141328 -436.83174)
			(xy 75.141328 -436.219092) (xy 75.14171 -436.20698) (xy 75.149215 -436.183948) (xy 75.163484 -436.164372)
			(xy 75.183115 -436.150179) (xy 75.206176 -436.142763) (xy 75.21829 -436.142384) (xy 76.15809 -436.142384)
			(xy 76.170183 -436.142817) (xy 76.193191 -436.150276) (xy 76.212775 -436.16447) (xy 76.227024 -436.184014)
			(xy 76.234549 -436.207) (xy 76.235052 -436.219092) (xy 76.235052 -438.760616) (xy 76.234598 -438.772721)
			(xy 76.227101 -438.795739) (xy 76.212847 -438.815308) (xy 76.193237 -438.829504) (xy 76.170196 -438.836933)
			(xy 76.15809 -438.837324) (xy 75.21829 -438.837324) (xy 75.206196 -438.8369) (xy 75.183189 -438.829436)
			(xy 75.163607 -438.81524) (xy 75.149358 -438.795695) (xy 75.141832 -438.772708) (xy 75.141328 -438.760616)
			(xy 75.141328 -438.147968) (xy 75.139783 -438.133476) (xy 75.138131 -438.104376) (xy 75.138026 -438.089802)
			(xy 73.234804 -438.089802) (xy 73.234804 -439.0898) (xy 77.138022 -439.0898) (xy 77.138115 -439.075226)
			(xy 77.139768 -439.046125) (xy 77.141324 -439.031634) (xy 77.141324 -437.94807) (xy 77.139779 -437.933578)
			(xy 77.138127 -437.904478) (xy 77.138022 -437.889904) (xy 77.138115 -437.87533) (xy 77.139768 -437.846229)
			(xy 77.141324 -437.831738) (xy 77.141324 -437.21909) (xy 77.141803 -437.206976) (xy 77.149291 -437.183935)
			(xy 77.163532 -437.164335) (xy 77.183132 -437.150093) (xy 77.206172 -437.142604) (xy 77.218286 -437.142128)
			(xy 78.158086 -437.142128) (xy 78.170207 -437.142572) (xy 78.193264 -437.150059) (xy 78.212878 -437.164305)
			(xy 78.22713 -437.183915) (xy 78.234624 -437.206969) (xy 78.235048 -437.21909) (xy 78.235048 -438.089802)
			(xy 79.138018 -438.089802) (xy 79.138111 -438.075228) (xy 79.139764 -438.046127) (xy 79.14132 -438.031636)
			(xy 79.14132 -436.948072) (xy 79.139776 -436.93358) (xy 79.138123 -436.90448) (xy 79.138018 -436.889906)
			(xy 79.138111 -436.875332) (xy 79.139764 -436.846231) (xy 79.14132 -436.83174) (xy 79.14132 -436.219092)
			(xy 79.14171 -436.206981) (xy 79.149214 -436.18395) (xy 79.163481 -436.164375) (xy 79.18311 -436.150181)
			(xy 79.206169 -436.142764) (xy 79.218282 -436.142384) (xy 80.158082 -436.142384) (xy 80.170175 -436.142824)
			(xy 80.193182 -436.150281) (xy 80.212766 -436.164473) (xy 80.227016 -436.184015) (xy 80.234541 -436.207)
			(xy 80.235044 -436.219092) (xy 80.235044 -438.760616) (xy 80.234598 -438.772721) (xy 80.227099 -438.795742)
			(xy 80.212844 -438.815311) (xy 80.193232 -438.829506) (xy 80.170189 -438.836935) (xy 80.158082 -438.837324)
			(xy 79.218282 -438.837324) (xy 79.206188 -438.836907) (xy 79.183181 -438.829441) (xy 79.163598 -438.815243)
			(xy 79.149349 -438.795697) (xy 79.141824 -438.772709) (xy 79.14132 -438.760616) (xy 79.14132 -438.147968)
			(xy 79.139775 -438.133476) (xy 79.138123 -438.104376) (xy 79.138018 -438.089802) (xy 78.235048 -438.089802)
			(xy 78.235048 -439.0898) (xy 81.138014 -439.0898) (xy 81.138106 -439.075226) (xy 81.13976 -439.046125)
			(xy 81.141316 -439.031634) (xy 81.141316 -437.94807) (xy 81.139771 -437.933578) (xy 81.138119 -437.904478)
			(xy 81.138014 -437.889904) (xy 81.138107 -437.87533) (xy 81.13976 -437.846229) (xy 81.141316 -437.831738)
			(xy 81.141316 -437.21909) (xy 81.141803 -437.206977) (xy 81.14929 -437.183937) (xy 81.163529 -437.164338)
			(xy 81.183127 -437.150096) (xy 81.206165 -437.142605) (xy 81.218278 -437.142128) (xy 82.158078 -437.142128)
			(xy 82.170199 -437.142579) (xy 82.193255 -437.150064) (xy 82.21287 -437.164308) (xy 82.227122 -437.183916)
			(xy 82.234616 -437.20697) (xy 82.23504 -437.21909) (xy 82.23504 -438.089802) (xy 83.13801 -438.089802)
			(xy 83.138103 -438.075228) (xy 83.139756 -438.046127) (xy 83.141312 -438.031636) (xy 83.141312 -436.948072)
			(xy 83.139767 -436.93358) (xy 83.138115 -436.90448) (xy 83.13801 -436.889906) (xy 83.138103 -436.875332)
			(xy 83.139756 -436.846231) (xy 83.141312 -436.83174) (xy 83.141312 -436.219092) (xy 83.14171 -436.206981)
			(xy 83.149213 -436.183952) (xy 83.163479 -436.164378) (xy 83.183105 -436.150184) (xy 83.206162 -436.142765)
			(xy 83.218274 -436.142384) (xy 84.158074 -436.142384) (xy 84.170167 -436.14283) (xy 84.193174 -436.150285)
			(xy 84.212758 -436.164476) (xy 84.227008 -436.184017) (xy 84.234533 -436.207001) (xy 84.235036 -436.219092)
			(xy 84.235036 -438.760616) (xy 84.234598 -438.772722) (xy 84.227098 -438.795744) (xy 84.212841 -438.815313)
			(xy 84.193227 -438.829509) (xy 84.170181 -438.836936) (xy 84.158074 -438.837324) (xy 83.218274 -438.837324)
			(xy 83.206179 -438.836914) (xy 83.183172 -438.829446) (xy 83.163589 -438.815246) (xy 83.149341 -438.795698)
			(xy 83.141816 -438.772709) (xy 83.141312 -438.760616) (xy 83.141312 -438.147968) (xy 83.139767 -438.133476)
			(xy 83.138115 -438.104376) (xy 83.13801 -438.089802) (xy 82.23504 -438.089802) (xy 82.23504 -439.0898)
			(xy 85.138006 -439.0898) (xy 85.138098 -439.075226) (xy 85.139752 -439.046125) (xy 85.141308 -439.031634)
			(xy 85.141308 -437.94807) (xy 85.139763 -437.933578) (xy 85.138111 -437.904478) (xy 85.138006 -437.889904)
			(xy 85.138099 -437.87533) (xy 85.139752 -437.846229) (xy 85.141308 -437.831738) (xy 85.141308 -437.21909)
			(xy 85.141803 -437.206978) (xy 85.149289 -437.18394) (xy 85.163526 -437.164341) (xy 85.183122 -437.150098)
			(xy 85.206158 -437.142606) (xy 85.21827 -437.142128) (xy 86.15807 -437.142128) (xy 86.17019 -437.142585)
			(xy 86.193246 -437.150068) (xy 86.212861 -437.16431) (xy 86.227114 -437.183918) (xy 86.234608 -437.20697)
			(xy 86.235032 -437.21909) (xy 86.235032 -438.089802) (xy 87.138002 -438.089802) (xy 87.138095 -438.075228)
			(xy 87.139748 -438.046127) (xy 87.141304 -438.031636) (xy 87.141304 -436.948072) (xy 87.139759 -436.93358)
			(xy 87.138107 -436.90448) (xy 87.138002 -436.889906) (xy 87.138095 -436.875332) (xy 87.139748 -436.846231)
			(xy 87.141304 -436.83174) (xy 87.141304 -436.219092) (xy 87.141709 -436.206982) (xy 87.149212 -436.183954)
			(xy 87.163476 -436.164381) (xy 87.1831 -436.150186) (xy 87.206155 -436.142767) (xy 87.218266 -436.142384)
			(xy 88.158066 -436.142384) (xy 88.170158 -436.142837) (xy 88.193165 -436.15029) (xy 88.212749 -436.164478)
			(xy 88.227 -436.184018) (xy 88.234525 -436.207001) (xy 88.235028 -436.219092) (xy 88.235028 -438.760616)
			(xy 88.234598 -438.772723) (xy 88.227097 -438.795746) (xy 88.212838 -438.815316) (xy 88.193222 -438.829511)
			(xy 88.170174 -438.836937) (xy 88.158066 -438.837324) (xy 87.218266 -438.837324) (xy 87.206171 -438.836921)
			(xy 87.183163 -438.829451) (xy 87.163581 -438.815249) (xy 87.149333 -438.7957) (xy 87.141808 -438.77271)
			(xy 87.141304 -438.760616) (xy 87.141304 -438.147968) (xy 87.139759 -438.133476) (xy 87.138107 -438.104376)
			(xy 87.138002 -438.089802) (xy 86.235032 -438.089802) (xy 86.235032 -439.0898) (xy 89.137998 -439.0898)
			(xy 89.13809 -439.075226) (xy 89.139744 -439.046125) (xy 89.1413 -439.031634) (xy 89.1413 -437.94807)
			(xy 89.139755 -437.933578) (xy 89.138103 -437.904478) (xy 89.137998 -437.889904) (xy 89.138091 -437.87533)
			(xy 89.139744 -437.846229) (xy 89.1413 -437.831738) (xy 89.1413 -437.21909) (xy 89.141803 -437.206979)
			(xy 89.149288 -437.183942) (xy 89.163524 -437.164343) (xy 89.183117 -437.150101) (xy 89.206151 -437.142607)
			(xy 89.218262 -437.142128) (xy 90.158062 -437.142128) (xy 90.170182 -437.142592) (xy 90.193238 -437.150073)
			(xy 90.212853 -437.164313) (xy 90.227105 -437.183919) (xy 90.2346 -437.20697) (xy 90.235024 -437.21909)
			(xy 90.235024 -439.0898) (xy 127.237998 -439.0898) (xy 127.23809 -439.075226) (xy 127.239744 -439.046125)
			(xy 127.2413 -439.031634) (xy 127.2413 -437.94807) (xy 127.239755 -437.933578) (xy 127.238103 -437.904478)
			(xy 127.237998 -437.889904) (xy 127.238091 -437.87533) (xy 127.239744 -437.846229) (xy 127.2413 -437.831738)
			(xy 127.2413 -437.218836) (xy 127.241747 -437.206729) (xy 127.249237 -437.183703) (xy 127.26349 -437.164129)
			(xy 127.283106 -437.149933) (xy 127.306154 -437.142512) (xy 127.318262 -437.142128) (xy 128.258062 -437.142128)
			(xy 128.270148 -437.14264) (xy 128.293146 -437.150084) (xy 128.312725 -437.16426) (xy 128.326978 -437.183784)
			(xy 128.334513 -437.206752) (xy 128.335024 -437.218836) (xy 128.335024 -438.089802) (xy 129.237994 -438.089802)
			(xy 129.238087 -438.075228) (xy 129.23974 -438.046127) (xy 129.241296 -438.031636) (xy 129.241296 -436.948072)
			(xy 129.239752 -436.93358) (xy 129.238099 -436.90448) (xy 129.237994 -436.889906) (xy 129.238087 -436.875332)
			(xy 129.23974 -436.846231) (xy 129.241296 -436.83174) (xy 129.241296 -436.218838) (xy 129.241843 -436.20673)
			(xy 129.249315 -436.183695) (xy 129.263539 -436.164096) (xy 129.283123 -436.149852) (xy 129.30615 -436.142356)
			(xy 129.318258 -436.141876) (xy 130.258058 -436.141876) (xy 130.270182 -436.142296) (xy 130.293246 -436.149782)
			(xy 130.312865 -436.164032) (xy 130.327117 -436.18365) (xy 130.334603 -436.206714) (xy 130.33502 -436.218838)
			(xy 130.33502 -438.760362) (xy 130.334607 -438.772487) (xy 130.32712 -438.795552) (xy 130.312868 -438.815171)
			(xy 130.293248 -438.829422) (xy 130.270183 -438.836908) (xy 130.258058 -438.837324) (xy 129.318258 -438.837324)
			(xy 129.306137 -438.836923) (xy 129.283086 -438.82942) (xy 129.263482 -438.815161) (xy 129.249243 -438.795542)
			(xy 129.241764 -438.772483) (xy 129.241296 -438.760362) (xy 129.241296 -438.147968) (xy 129.239751 -438.133476)
			(xy 129.238099 -438.104376) (xy 129.237994 -438.089802) (xy 128.335024 -438.089802) (xy 128.335024 -439.0898)
			(xy 131.23799 -439.0898) (xy 131.238082 -439.075226) (xy 131.239736 -439.046125) (xy 131.241292 -439.031634)
			(xy 131.241292 -437.94807) (xy 131.239748 -437.933578) (xy 131.238095 -437.904478) (xy 131.23799 -437.889904)
			(xy 131.238083 -437.87533) (xy 131.239736 -437.846229) (xy 131.241292 -437.831738) (xy 131.241292 -437.218836)
			(xy 131.241747 -437.20673) (xy 131.249235 -437.183705) (xy 131.263487 -437.164132) (xy 131.283101 -437.149936)
			(xy 131.306147 -437.142513) (xy 131.318254 -437.142128) (xy 132.258054 -437.142128) (xy 132.27014 -437.142646)
			(xy 132.293137 -437.150089) (xy 132.312717 -437.164263) (xy 132.326969 -437.183785) (xy 132.334505 -437.206752)
			(xy 132.335016 -437.218836) (xy 132.335016 -438.089802) (xy 133.237986 -438.089802) (xy 133.238079 -438.075228)
			(xy 133.239732 -438.046127) (xy 133.241288 -438.031636) (xy 133.241288 -436.948072) (xy 133.239744 -436.93358)
			(xy 133.238091 -436.90448) (xy 133.237986 -436.889906) (xy 133.238079 -436.875332) (xy 133.239732 -436.846231)
			(xy 133.241288 -436.83174) (xy 133.241288 -436.218838) (xy 133.241843 -436.20673) (xy 133.249314 -436.183697)
			(xy 133.263536 -436.164099) (xy 133.283118 -436.149854) (xy 133.306143 -436.142357) (xy 133.31825 -436.141876)
			(xy 134.25805 -436.141876) (xy 134.270171 -436.14227) (xy 134.293222 -436.149775) (xy 134.312826 -436.164036)
			(xy 134.327065 -436.183657) (xy 134.334544 -436.206717) (xy 134.335012 -436.218838) (xy 134.335012 -438.760362)
			(xy 134.334457 -438.77247) (xy 134.326986 -438.795503) (xy 134.312764 -438.815101) (xy 134.293182 -438.829346)
			(xy 134.270157 -438.836843) (xy 134.25805 -438.837324) (xy 133.31825 -438.837324) (xy 133.306129 -438.83693)
			(xy 133.283078 -438.829425) (xy 133.263474 -438.815164) (xy 133.249235 -438.795543) (xy 133.241756 -438.772483)
			(xy 133.241288 -438.760362) (xy 133.241288 -438.147968) (xy 133.239743 -438.133476) (xy 133.238091 -438.104376)
			(xy 133.237986 -438.089802) (xy 132.335016 -438.089802) (xy 132.335016 -439.0898) (xy 135.237982 -439.0898)
			(xy 135.238075 -439.075226) (xy 135.239728 -439.046125) (xy 135.241284 -439.031634) (xy 135.241284 -437.94807)
			(xy 135.23974 -437.933578) (xy 135.238087 -437.904478) (xy 135.237982 -437.889904) (xy 135.238075 -437.87533)
			(xy 135.239728 -437.846229) (xy 135.241284 -437.831738) (xy 135.241284 -437.218836) (xy 135.241747 -437.206731)
			(xy 135.249234 -437.183707) (xy 135.263484 -437.164135) (xy 135.283096 -437.149939) (xy 135.30614 -437.142514)
			(xy 135.318246 -437.142128) (xy 136.258046 -437.142128) (xy 136.270137 -437.142568) (xy 136.293137 -437.150036)
			(xy 136.312715 -437.16423) (xy 136.326964 -437.183768) (xy 136.334497 -437.206747) (xy 136.335008 -437.218836)
			(xy 136.335008 -438.089802) (xy 137.237978 -438.089802) (xy 137.238071 -438.075228) (xy 137.239724 -438.046127)
			(xy 137.24128 -438.031636) (xy 137.24128 -436.948072) (xy 137.239736 -436.93358) (xy 137.238083 -436.90448)
			(xy 137.237978 -436.889906) (xy 137.238071 -436.875332) (xy 137.239724 -436.846231) (xy 137.24128 -436.83174)
			(xy 137.24128 -436.218838) (xy 137.241693 -436.206713) (xy 137.24918 -436.183648) (xy 137.263432 -436.164029)
			(xy 137.283052 -436.149778) (xy 137.306117 -436.142292) (xy 137.318242 -436.141876) (xy 138.258042 -436.141876)
			(xy 138.270163 -436.142277) (xy 138.293214 -436.14978) (xy 138.312818 -436.164039) (xy 138.327057 -436.183658)
			(xy 138.334536 -436.206717) (xy 138.335004 -436.218838) (xy 138.335004 -438.760362) (xy 138.334457 -438.77247)
			(xy 138.326985 -438.795505) (xy 138.312761 -438.815104) (xy 138.293177 -438.829348) (xy 138.27015 -438.836844)
			(xy 138.258042 -438.837324) (xy 137.318242 -438.837324) (xy 137.306118 -438.836904) (xy 137.283054 -438.829418)
			(xy 137.263435 -438.815168) (xy 137.249183 -438.79555) (xy 137.241697 -438.772486) (xy 137.24128 -438.760362)
			(xy 137.24128 -438.147968) (xy 137.239735 -438.133476) (xy 137.238083 -438.104376) (xy 137.237978 -438.089802)
			(xy 136.335008 -438.089802) (xy 136.335008 -439.0898) (xy 139.237974 -439.0898) (xy 139.238067 -439.075226)
			(xy 139.23972 -439.046125) (xy 139.241276 -439.031634) (xy 139.241276 -437.94807) (xy 139.239732 -437.933578)
			(xy 139.238079 -437.904478) (xy 139.237974 -437.889904) (xy 139.238067 -437.87533) (xy 139.23972 -437.846229)
			(xy 139.241276 -437.831738) (xy 139.241276 -437.218836) (xy 139.241747 -437.206731) (xy 139.249233 -437.183709)
			(xy 139.263482 -437.164138) (xy 139.283091 -437.149941) (xy 139.306132 -437.142515) (xy 139.318238 -437.142128)
			(xy 140.258038 -437.142128) (xy 140.270128 -437.142575) (xy 140.293128 -437.15004) (xy 140.312706 -437.164233)
			(xy 140.326956 -437.183769) (xy 140.334489 -437.206747) (xy 140.335 -437.218836) (xy 140.335 -438.089802)
			(xy 142.237968 -438.089802) (xy 142.238085 -438.074717) (xy 142.239861 -438.044598) (xy 142.241524 -438.029604)
			(xy 142.241524 -436.950104) (xy 142.239854 -436.935111) (xy 142.238076 -436.904992) (xy 142.237968 -436.889906)
			(xy 142.238076 -436.87482) (xy 142.239858 -436.844702) (xy 142.241524 -436.829708) (xy 142.241524 -436.218838)
			(xy 142.242039 -436.206752) (xy 142.249484 -436.183755) (xy 142.263658 -436.164176) (xy 142.283181 -436.149924)
			(xy 142.306148 -436.142388) (xy 142.318232 -436.141876) (xy 143.258032 -436.141876) (xy 143.27014 -436.142289)
			(xy 143.293164 -436.149794) (xy 143.312735 -436.164057) (xy 143.326929 -436.183678) (xy 143.334353 -436.206728)
			(xy 143.33474 -436.218838) (xy 143.33474 -438.760362) (xy 143.33426 -438.772452) (xy 143.326811 -438.795454)
			(xy 143.312629 -438.815037) (xy 143.293096 -438.829288) (xy 143.27012 -438.836817) (xy 143.258032 -438.837324)
			(xy 142.318232 -438.837324) (xy 142.306127 -438.836857) (xy 142.283105 -438.829369) (xy 142.263534 -438.81512)
			(xy 142.249337 -438.79551) (xy 142.241911 -438.772468) (xy 142.241524 -438.760362) (xy 142.241524 -438.15)
			(xy 142.239853 -438.135007) (xy 142.238076 -438.104888) (xy 142.237968 -438.089802) (xy 140.335 -438.089802)
			(xy 140.335 -439.0898) (xy 144.237964 -439.0898) (xy 144.23808 -439.074715) (xy 144.239857 -439.044596)
			(xy 144.24152 -439.029602) (xy 144.24152 -437.950102) (xy 144.239849 -437.935109) (xy 144.238072 -437.90499)
			(xy 144.237964 -437.889904) (xy 144.238081 -437.874819) (xy 144.239857 -437.8447) (xy 144.24152 -437.829706)
			(xy 144.24152 -437.218836) (xy 144.241944 -437.206752) (xy 144.249405 -437.183766) (xy 144.263607 -437.164213)
			(xy 144.283159 -437.150008) (xy 144.306144 -437.142545) (xy 144.318228 -437.142128) (xy 145.258028 -437.142128)
			(xy 145.270116 -437.142489) (xy 145.293106 -437.149969) (xy 145.312658 -437.164187) (xy 145.32686 -437.183752)
			(xy 145.334321 -437.206748) (xy 145.334736 -437.218836) (xy 145.334736 -438.089802) (xy 146.23796 -438.089802)
			(xy 146.238077 -438.074717) (xy 146.239853 -438.044598) (xy 146.241516 -438.029604) (xy 146.241516 -436.950104)
			(xy 146.239846 -436.935111) (xy 146.238068 -436.904992) (xy 146.23796 -436.889906) (xy 146.238068 -436.87482)
			(xy 146.23985 -436.844702) (xy 146.241516 -436.829708) (xy 146.241516 -436.218838) (xy 146.242039 -436.206753)
			(xy 146.249483 -436.183757) (xy 146.263656 -436.164179) (xy 146.283176 -436.149926) (xy 146.306141 -436.142389)
			(xy 146.318224 -436.141876) (xy 147.258024 -436.141876) (xy 147.270132 -436.142296) (xy 147.293156 -436.149799)
			(xy 147.312726 -436.16406) (xy 147.326921 -436.183679) (xy 147.334345 -436.206729) (xy 147.334732 -436.218838)
			(xy 147.334732 -438.760362) (xy 147.33426 -438.772452) (xy 147.32681 -438.795456) (xy 147.312626 -438.815039)
			(xy 147.293091 -438.82929) (xy 147.270113 -438.836818) (xy 147.258024 -438.837324) (xy 146.318224 -438.837324)
			(xy 146.306119 -438.836863) (xy 146.283096 -438.829374) (xy 146.263525 -438.815123) (xy 146.249329 -438.795512)
			(xy 146.241903 -438.772468) (xy 146.241516 -438.760362) (xy 146.241516 -438.15) (xy 146.239845 -438.135007)
			(xy 146.238068 -438.104888) (xy 146.23796 -438.089802) (xy 145.334736 -438.089802) (xy 145.334736 -439.0898)
			(xy 148.237956 -439.0898) (xy 148.238073 -439.074715) (xy 148.239849 -439.044596) (xy 148.241512 -439.029602)
			(xy 148.241512 -437.950102) (xy 148.239841 -437.935109) (xy 148.238064 -437.90499) (xy 148.237956 -437.889904)
			(xy 148.238073 -437.874819) (xy 148.239849 -437.8447) (xy 148.241512 -437.829706) (xy 148.241512 -437.218836)
			(xy 148.241944 -437.206753) (xy 148.249404 -437.183768) (xy 148.263604 -437.164216) (xy 148.283154 -437.150011)
			(xy 148.306137 -437.142546) (xy 148.31822 -437.142128) (xy 149.25802 -437.142128) (xy 149.270107 -437.142496)
			(xy 149.293097 -437.149974) (xy 149.31265 -437.16419) (xy 149.326852 -437.183753) (xy 149.334313 -437.206748)
			(xy 149.334728 -437.218836) (xy 149.334728 -438.089802) (xy 150.237952 -438.089802) (xy 150.238069 -438.074717)
			(xy 150.239845 -438.044598) (xy 150.241508 -438.029604) (xy 150.241508 -436.950104) (xy 150.239838 -436.935111)
			(xy 150.23806 -436.904992) (xy 150.237952 -436.889906) (xy 150.23806 -436.87482) (xy 150.239842 -436.844702)
			(xy 150.241508 -436.829708) (xy 150.241508 -436.218838) (xy 150.242039 -436.206754) (xy 150.249482 -436.18376)
			(xy 150.263653 -436.164182) (xy 150.283171 -436.149929) (xy 150.306134 -436.14239) (xy 150.318216 -436.141876)
			(xy 151.258016 -436.141876) (xy 151.270123 -436.142302) (xy 151.293147 -436.149803) (xy 151.312718 -436.164063)
			(xy 151.326913 -436.183681) (xy 151.334337 -436.206729) (xy 151.334724 -436.218838) (xy 151.334724 -438.760362)
			(xy 151.33426 -438.772453) (xy 151.326809 -438.795459) (xy 151.312623 -438.815042) (xy 151.293086 -438.829293)
			(xy 151.270106 -438.836819) (xy 151.258016 -438.837324) (xy 150.318216 -438.837324) (xy 150.30611 -438.83687)
			(xy 150.283088 -438.829378) (xy 150.263517 -438.815125) (xy 150.249321 -438.795513) (xy 150.241895 -438.772469)
			(xy 150.241508 -438.760362) (xy 150.241508 -438.15) (xy 150.239837 -438.135007) (xy 150.23806 -438.104888)
			(xy 150.237952 -438.089802) (xy 149.334728 -438.089802) (xy 149.334728 -439.0898) (xy 152.237948 -439.0898)
			(xy 152.238065 -439.074715) (xy 152.239841 -439.044596) (xy 152.241504 -439.029602) (xy 152.241504 -437.950102)
			(xy 152.239833 -437.935109) (xy 152.238056 -437.90499) (xy 152.237948 -437.889904) (xy 152.238065 -437.874819)
			(xy 152.239841 -437.8447) (xy 152.241504 -437.829706) (xy 152.241504 -437.218836) (xy 152.241944 -437.206754)
			(xy 152.249403 -437.18377) (xy 152.263601 -437.164218) (xy 152.283149 -437.150014) (xy 152.30613 -437.142547)
			(xy 152.318212 -437.142128) (xy 153.258012 -437.142128) (xy 153.270099 -437.142503) (xy 153.293088 -437.149978)
			(xy 153.312641 -437.164193) (xy 153.326844 -437.183755) (xy 153.334305 -437.206749) (xy 153.33472 -437.218836)
			(xy 153.33472 -438.089802) (xy 154.237944 -438.089802) (xy 154.238061 -438.074717) (xy 154.239837 -438.044598)
			(xy 154.2415 -438.029604) (xy 154.2415 -436.950104) (xy 154.23983 -436.935111) (xy 154.238052 -436.904992)
			(xy 154.237944 -436.889906) (xy 154.238052 -436.87482) (xy 154.239834 -436.844702) (xy 154.2415 -436.829708)
			(xy 154.2415 -436.218838) (xy 154.242039 -436.206754) (xy 154.24948 -436.183762) (xy 154.26365 -436.164185)
			(xy 154.283166 -436.149931) (xy 154.306126 -436.142391) (xy 154.318208 -436.141876) (xy 155.258008 -436.141876)
			(xy 155.270115 -436.142309) (xy 155.293138 -436.149808) (xy 155.312709 -436.164066) (xy 155.326905 -436.183682)
			(xy 155.334329 -436.20673) (xy 155.334716 -436.218838) (xy 155.334716 -438.760362) (xy 155.334259 -438.772454)
			(xy 155.326808 -438.795461) (xy 155.31262 -438.815045) (xy 155.293081 -438.829295) (xy 155.270098 -438.836821)
			(xy 155.258008 -438.837324) (xy 154.318208 -438.837324) (xy 154.306102 -438.836877) (xy 154.283079 -438.829383)
			(xy 154.263508 -438.815129) (xy 154.249312 -438.795515) (xy 154.241887 -438.772469) (xy 154.2415 -438.760362)
			(xy 154.2415 -438.15) (xy 154.239829 -438.135007) (xy 154.238052 -438.104888) (xy 154.237944 -438.089802)
			(xy 153.33472 -438.089802) (xy 153.33472 -439.0898) (xy 156.23794 -439.0898) (xy 156.238057 -439.074715)
			(xy 156.239833 -439.044596) (xy 156.241496 -439.029602) (xy 156.241496 -437.950102) (xy 156.239825 -437.935109)
			(xy 156.238048 -437.90499) (xy 156.23794 -437.889904) (xy 156.238057 -437.874819) (xy 156.239833 -437.8447)
			(xy 156.241496 -437.829706) (xy 156.241496 -437.218836) (xy 156.241943 -437.206755) (xy 156.249402 -437.183773)
			(xy 156.263599 -437.164221) (xy 156.283144 -437.150016) (xy 156.306123 -437.142548) (xy 156.318204 -437.142128)
			(xy 157.258004 -437.142128) (xy 157.270091 -437.14251) (xy 157.29308 -437.149983) (xy 157.312633 -437.164196)
			(xy 157.326836 -437.183756) (xy 157.334297 -437.206749) (xy 157.334712 -437.218836) (xy 157.334712 -438.089802)
			(xy 314.138056 -438.089802) (xy 314.138173 -438.074717) (xy 314.139949 -438.044598) (xy 314.141612 -438.029604)
			(xy 314.141612 -436.950104) (xy 314.139942 -436.935111) (xy 314.138164 -436.904992) (xy 314.138056 -436.889906)
			(xy 314.138164 -436.87482) (xy 314.139946 -436.844702) (xy 314.141612 -436.829708) (xy 314.141612 -436.219092)
			(xy 314.142006 -436.207007) (xy 314.149478 -436.18402) (xy 314.163688 -436.164469) (xy 314.183246 -436.150265)
			(xy 314.206235 -436.142802) (xy 314.21832 -436.142384) (xy 315.15812 -436.142384) (xy 315.170195 -436.142847)
			(xy 315.193161 -436.150314) (xy 315.212697 -436.164511) (xy 315.226891 -436.18405) (xy 315.234355 -436.207017)
			(xy 315.234828 -436.219092) (xy 315.234828 -438.760616) (xy 315.23435 -438.772689) (xy 315.226885 -438.795654)
			(xy 315.212691 -438.815189) (xy 315.193157 -438.829383) (xy 315.170193 -438.836849) (xy 315.15812 -438.837324)
			(xy 314.21832 -438.837324) (xy 314.20624 -438.83687) (xy 314.183261 -438.82941) (xy 314.163711 -438.815214)
			(xy 314.149506 -438.795672) (xy 314.142035 -438.772696) (xy 314.141612 -438.760616) (xy 314.141612 -438.15)
			(xy 314.139941 -438.135007) (xy 314.138164 -438.104888) (xy 314.138056 -438.089802) (xy 157.334712 -438.089802)
			(xy 157.334712 -439.0898) (xy 316.138052 -439.0898) (xy 316.138169 -439.074715) (xy 316.139945 -439.044596)
			(xy 316.141608 -439.029602) (xy 316.141608 -437.950102) (xy 316.139937 -437.935109) (xy 316.13816 -437.90499)
			(xy 316.138052 -437.889904) (xy 316.138169 -437.874819) (xy 316.139945 -437.8447) (xy 316.141608 -437.829706)
			(xy 316.141608 -437.21909) (xy 316.142098 -437.207003) (xy 316.149554 -437.184008) (xy 316.163736 -437.164431)
			(xy 316.183262 -437.150179) (xy 316.206231 -437.142642) (xy 316.218316 -437.142128) (xy 317.158116 -437.142128)
			(xy 317.170229 -437.142503) (xy 317.193261 -437.15001) (xy 317.212836 -437.164281) (xy 317.227029 -437.183914)
			(xy 317.234445 -437.206976) (xy 317.234824 -437.21909) (xy 317.234824 -438.089802) (xy 318.138048 -438.089802)
			(xy 318.138165 -438.074717) (xy 318.139941 -438.044598) (xy 318.141604 -438.029604) (xy 318.141604 -436.950104)
			(xy 318.139934 -436.935111) (xy 318.138156 -436.904992) (xy 318.138048 -436.889906) (xy 318.138156 -436.87482)
			(xy 318.139938 -436.844702) (xy 318.141604 -436.829708) (xy 318.141604 -436.219092) (xy 318.142006 -436.207008)
			(xy 318.149477 -436.184023) (xy 318.163686 -436.164471) (xy 318.183241 -436.150268) (xy 318.206228 -436.142803)
			(xy 318.218312 -436.142384) (xy 319.158112 -436.142384) (xy 319.170186 -436.142854) (xy 319.193153 -436.150319)
			(xy 319.212689 -436.164514) (xy 319.226883 -436.184051) (xy 319.234347 -436.207018) (xy 319.23482 -436.219092)
			(xy 319.23482 -438.760616) (xy 319.234349 -438.77269) (xy 319.226884 -438.795656) (xy 319.212689 -438.815191)
			(xy 319.193152 -438.829386) (xy 319.170186 -438.83685) (xy 319.158112 -438.837324) (xy 318.218312 -438.837324)
			(xy 318.20624 -438.836826) (xy 318.183276 -438.829369) (xy 318.16374 -438.81518) (xy 318.149544 -438.79565)
			(xy 318.142079 -438.772688) (xy 318.141604 -438.760616) (xy 318.141604 -438.15) (xy 318.139933 -438.135007)
			(xy 318.138156 -438.104888) (xy 318.138048 -438.089802) (xy 317.234824 -438.089802) (xy 317.234824 -439.0898)
			(xy 320.138044 -439.0898) (xy 320.138161 -439.074715) (xy 320.139937 -439.044596) (xy 320.1416 -439.029602)
			(xy 320.1416 -437.950102) (xy 320.139929 -437.935109) (xy 320.138152 -437.90499) (xy 320.138044 -437.889904)
			(xy 320.138161 -437.874819) (xy 320.139937 -437.8447) (xy 320.1416 -437.829706) (xy 320.1416 -437.21909)
			(xy 320.142098 -437.207004) (xy 320.149553 -437.18401) (xy 320.163733 -437.164434) (xy 320.183257 -437.150182)
			(xy 320.206224 -437.142643) (xy 320.218308 -437.142128) (xy 321.158108 -437.142128) (xy 321.17022 -437.14251)
			(xy 321.193252 -437.150015) (xy 321.212828 -437.164284) (xy 321.227021 -437.183915) (xy 321.234437 -437.206976)
			(xy 321.234816 -437.21909) (xy 321.234816 -438.089802) (xy 322.13804 -438.089802) (xy 322.138157 -438.074717)
			(xy 322.139933 -438.044598) (xy 322.141596 -438.029604) (xy 322.141596 -436.950104) (xy 322.139926 -436.935111)
			(xy 322.138148 -436.904992) (xy 322.13804 -436.889906) (xy 322.13815 -436.87482) (xy 322.139932 -436.844702)
			(xy 322.141596 -436.829708) (xy 322.141596 -436.219092) (xy 322.142058 -436.207017) (xy 322.149523 -436.184049)
			(xy 322.16372 -436.164511) (xy 322.183259 -436.150317) (xy 322.206229 -436.142856) (xy 322.218304 -436.142384)
			(xy 323.158104 -436.142384) (xy 323.170178 -436.142861) (xy 323.193144 -436.150323) (xy 323.21268 -436.164517)
			(xy 323.226875 -436.184053) (xy 323.234339 -436.207018) (xy 323.234812 -436.219092) (xy 323.234812 -438.760616)
			(xy 323.234349 -438.772691) (xy 323.226883 -438.795658) (xy 323.212686 -438.815194) (xy 323.193147 -438.829388)
			(xy 323.170179 -438.836851) (xy 323.158104 -438.837324) (xy 322.218304 -438.837324) (xy 322.206231 -438.836833)
			(xy 322.183267 -438.829373) (xy 322.163731 -438.815183) (xy 322.149536 -438.795651) (xy 322.142071 -438.772689)
			(xy 322.141596 -438.760616) (xy 322.141596 -438.15) (xy 322.139925 -438.135007) (xy 322.138148 -438.104888)
			(xy 322.13804 -438.089802) (xy 321.234816 -438.089802) (xy 321.234816 -439.0898) (xy 324.138036 -439.0898)
			(xy 324.138153 -439.074715) (xy 324.139929 -439.044596) (xy 324.141592 -439.029602) (xy 324.141592 -437.950102)
			(xy 324.139921 -437.935109) (xy 324.138144 -437.90499) (xy 324.138036 -437.889904) (xy 324.138153 -437.874819)
			(xy 324.139929 -437.8447) (xy 324.141592 -437.829706) (xy 324.141592 -437.21909) (xy 324.142098 -437.207005)
			(xy 324.149552 -437.184012) (xy 324.16373 -437.164436) (xy 324.183252 -437.150184) (xy 324.206217 -437.142644)
			(xy 324.2183 -437.142128) (xy 325.1581 -437.142128) (xy 325.170212 -437.142516) (xy 325.193244 -437.150019)
			(xy 325.212819 -437.164287) (xy 325.227013 -437.183916) (xy 325.234429 -437.206977) (xy 325.234808 -437.21909)
			(xy 325.234808 -438.089802) (xy 326.138032 -438.089802) (xy 326.138151 -438.074717) (xy 326.139927 -438.044598)
			(xy 326.141588 -438.029604) (xy 326.141588 -436.950104) (xy 326.139917 -436.935111) (xy 326.13814 -436.904992)
			(xy 326.138032 -436.889906) (xy 326.138142 -436.87482) (xy 326.139924 -436.844702) (xy 326.141588 -436.829708)
			(xy 326.141588 -436.219092) (xy 326.142057 -436.207017) (xy 326.149522 -436.184051) (xy 326.163717 -436.164514)
			(xy 326.183254 -436.15032) (xy 326.206221 -436.142857) (xy 326.218296 -436.142384) (xy 327.158096 -436.142384)
			(xy 327.17017 -436.142868) (xy 327.193135 -436.150328) (xy 327.212672 -436.16452) (xy 327.226867 -436.184054)
			(xy 327.234331 -436.207019) (xy 327.234804 -436.219092) (xy 327.234804 -438.760616) (xy 327.234349 -438.772692)
			(xy 327.226882 -438.79566) (xy 327.212683 -438.815197) (xy 327.193142 -438.829391) (xy 327.170172 -438.836852)
			(xy 327.158096 -438.837324) (xy 326.218296 -438.837324) (xy 326.206223 -438.836839) (xy 326.183258 -438.829378)
			(xy 326.163723 -438.815186) (xy 326.149528 -438.795652) (xy 326.142063 -438.772689) (xy 326.141588 -438.760616)
			(xy 326.141588 -438.15) (xy 326.139917 -438.135007) (xy 326.13814 -438.104888) (xy 326.138032 -438.089802)
			(xy 325.234808 -438.089802) (xy 325.234808 -439.0898) (xy 328.138028 -439.0898) (xy 328.138147 -439.074715)
			(xy 328.139923 -439.044596) (xy 328.141584 -439.029602) (xy 328.141584 -437.950102) (xy 328.139913 -437.935109)
			(xy 328.138136 -437.90499) (xy 328.138028 -437.889904) (xy 328.138147 -437.874819) (xy 328.139923 -437.8447)
			(xy 328.141584 -437.829706) (xy 328.141584 -437.21909) (xy 328.142 -437.206996) (xy 328.149465 -437.183987)
			(xy 328.163663 -437.164404) (xy 328.18321 -437.150155) (xy 328.206199 -437.142631) (xy 328.218292 -437.142128)
			(xy 329.158092 -437.142128) (xy 329.170203 -437.142523) (xy 329.193235 -437.150024) (xy 329.212811 -437.16429)
			(xy 329.227005 -437.183918) (xy 329.234421 -437.206977) (xy 329.2348 -437.21909) (xy 329.2348 -438.089802)
			(xy 331.138022 -438.089802) (xy 331.138115 -438.075228) (xy 331.139768 -438.046127) (xy 331.141324 -438.031636)
			(xy 331.141324 -436.948072) (xy 331.13978 -436.93358) (xy 331.138127 -436.90448) (xy 331.138022 -436.889906)
			(xy 331.138115 -436.875332) (xy 331.139768 -436.846231) (xy 331.141324 -436.83174) (xy 331.141324 -436.219092)
			(xy 331.14171 -436.20698) (xy 331.149214 -436.183949) (xy 331.163483 -436.164374) (xy 331.183112 -436.15018)
			(xy 331.206173 -436.142764) (xy 331.218286 -436.142384) (xy 332.158086 -436.142384) (xy 332.170179 -436.14282)
			(xy 332.193187 -436.150278) (xy 332.212771 -436.164471) (xy 332.22702 -436.184014) (xy 332.234545 -436.207)
			(xy 332.235048 -436.219092) (xy 332.235048 -438.760616) (xy 332.234598 -438.772721) (xy 332.2271 -438.795741)
			(xy 332.212845 -438.815309) (xy 332.193234 -438.829505) (xy 332.170192 -438.836934) (xy 332.158086 -438.837324)
			(xy 331.218286 -438.837324) (xy 331.206192 -438.836904) (xy 331.183185 -438.829439) (xy 331.163602 -438.815242)
			(xy 331.149353 -438.795696) (xy 331.141828 -438.772709) (xy 331.141324 -438.760616) (xy 331.141324 -438.147968)
			(xy 331.139779 -438.133476) (xy 331.138127 -438.104376) (xy 331.138022 -438.089802) (xy 329.2348 -438.089802)
			(xy 329.2348 -439.0898) (xy 333.138018 -439.0898) (xy 333.138111 -439.075226) (xy 333.139764 -439.046125)
			(xy 333.14132 -439.031634) (xy 333.14132 -437.94807) (xy 333.139775 -437.933578) (xy 333.138123 -437.904478)
			(xy 333.138018 -437.889904) (xy 333.138111 -437.87533) (xy 333.139764 -437.846229) (xy 333.14132 -437.831738)
			(xy 333.14132 -437.21909) (xy 333.141803 -437.206977) (xy 333.149291 -437.183936) (xy 333.163531 -437.164336)
			(xy 333.183129 -437.150095) (xy 333.206169 -437.142604) (xy 333.218282 -437.142128) (xy 334.158082 -437.142128)
			(xy 334.170203 -437.142575) (xy 334.193259 -437.150061) (xy 334.212874 -437.164306) (xy 334.227126 -437.183916)
			(xy 334.23462 -437.206969) (xy 334.235044 -437.21909) (xy 334.235044 -438.089802) (xy 335.138014 -438.089802)
			(xy 335.138106 -438.075228) (xy 335.13976 -438.046127) (xy 335.141316 -438.031636) (xy 335.141316 -436.948072)
			(xy 335.139772 -436.93358) (xy 335.138119 -436.90448) (xy 335.138014 -436.889906) (xy 335.138107 -436.875332)
			(xy 335.13976 -436.846231) (xy 335.141316 -436.83174) (xy 335.141316 -436.219092) (xy 335.14171 -436.206981)
			(xy 335.149213 -436.183951) (xy 335.16348 -436.164376) (xy 335.183107 -436.150183) (xy 335.206166 -436.142765)
			(xy 335.218278 -436.142384) (xy 336.158078 -436.142384) (xy 336.170171 -436.142827) (xy 336.193178 -436.150283)
			(xy 336.212762 -436.164474) (xy 336.227012 -436.184016) (xy 336.234537 -436.207001) (xy 336.23504 -436.219092)
			(xy 336.23504 -438.760616) (xy 336.234598 -438.772722) (xy 336.227099 -438.795743) (xy 336.212843 -438.815312)
			(xy 336.193229 -438.829508) (xy 336.170185 -438.836935) (xy 336.158078 -438.837324) (xy 335.218278 -438.837324)
			(xy 335.206184 -438.836911) (xy 335.183176 -438.829444) (xy 335.163594 -438.815245) (xy 335.149345 -438.795698)
			(xy 335.14182 -438.772709) (xy 335.141316 -438.760616) (xy 335.141316 -438.147968) (xy 335.139771 -438.133476)
			(xy 335.138119 -438.104376) (xy 335.138014 -438.089802) (xy 334.235044 -438.089802) (xy 334.235044 -439.0898)
			(xy 337.13801 -439.0898) (xy 337.138102 -439.075226) (xy 337.139756 -439.046125) (xy 337.141312 -439.031634)
			(xy 337.141312 -437.94807) (xy 337.139767 -437.933578) (xy 337.138115 -437.904478) (xy 337.13801 -437.889904)
			(xy 337.138103 -437.87533) (xy 337.139756 -437.846229) (xy 337.141312 -437.831738) (xy 337.141312 -437.21909)
			(xy 337.141803 -437.206978) (xy 337.14929 -437.183938) (xy 337.163528 -437.164339) (xy 337.183124 -437.150097)
			(xy 337.206162 -437.142606) (xy 337.218274 -437.142128) (xy 338.158074 -437.142128) (xy 338.170194 -437.142582)
			(xy 338.193251 -437.150066) (xy 338.212865 -437.164309) (xy 338.227118 -437.183917) (xy 338.234612 -437.20697)
			(xy 338.235036 -437.21909) (xy 338.235036 -438.089802) (xy 339.138006 -438.089802) (xy 339.138099 -438.075228)
			(xy 339.139752 -438.046127) (xy 339.141308 -438.031636) (xy 339.141308 -436.948072) (xy 339.139763 -436.93358)
			(xy 339.138111 -436.90448) (xy 339.138006 -436.889906) (xy 339.138099 -436.875332) (xy 339.139752 -436.846231)
			(xy 339.141308 -436.83174) (xy 339.141308 -436.219092) (xy 339.141709 -436.206982) (xy 339.149212 -436.183953)
			(xy 339.163477 -436.164379) (xy 339.183102 -436.150185) (xy 339.206158 -436.142766) (xy 339.21827 -436.142384)
			(xy 340.15807 -436.142384) (xy 340.170162 -436.142834) (xy 340.193169 -436.150288) (xy 340.212754 -436.164477)
			(xy 340.227004 -436.184017) (xy 340.234529 -436.207001) (xy 340.235032 -436.219092) (xy 340.235032 -438.760616)
			(xy 340.234598 -438.772723) (xy 340.227098 -438.795745) (xy 340.21284 -438.815315) (xy 340.193224 -438.82951)
			(xy 340.170178 -438.836936) (xy 340.15807 -438.837324) (xy 339.21827 -438.837324) (xy 339.206175 -438.836918)
			(xy 339.183168 -438.829448) (xy 339.163585 -438.815247) (xy 339.149337 -438.795699) (xy 339.141812 -438.77271)
			(xy 339.141308 -438.760616) (xy 339.141308 -438.147968) (xy 339.139763 -438.133476) (xy 339.138111 -438.104376)
			(xy 339.138006 -438.089802) (xy 338.235036 -438.089802) (xy 338.235036 -439.0898) (xy 341.138002 -439.0898)
			(xy 341.138094 -439.075226) (xy 341.139748 -439.046125) (xy 341.141304 -439.031634) (xy 341.141304 -437.94807)
			(xy 341.139759 -437.933578) (xy 341.138107 -437.904478) (xy 341.138002 -437.889904) (xy 341.138095 -437.87533)
			(xy 341.139748 -437.846229) (xy 341.141304 -437.831738) (xy 341.141304 -437.21909) (xy 341.141803 -437.206978)
			(xy 341.149289 -437.183941) (xy 341.163525 -437.164342) (xy 341.183119 -437.1501) (xy 341.206154 -437.142607)
			(xy 341.218266 -437.142128) (xy 342.158066 -437.142128) (xy 342.170186 -437.142589) (xy 342.193242 -437.15007)
			(xy 342.212857 -437.164312) (xy 342.22711 -437.183918) (xy 342.234604 -437.20697) (xy 342.235028 -437.21909)
			(xy 342.235028 -438.089802) (xy 343.137998 -438.089802) (xy 343.138091 -438.075228) (xy 343.139744 -438.046127)
			(xy 343.1413 -438.031636) (xy 343.1413 -436.948072) (xy 343.139755 -436.93358) (xy 343.138103 -436.90448)
			(xy 343.137998 -436.889906) (xy 343.138091 -436.875332) (xy 343.139744 -436.846231) (xy 343.1413 -436.83174)
			(xy 343.1413 -436.219092) (xy 343.141709 -436.206983) (xy 343.149211 -436.183955) (xy 343.163474 -436.164382)
			(xy 343.183097 -436.150188) (xy 343.206151 -436.142767) (xy 343.218262 -436.142384) (xy 344.158062 -436.142384)
			(xy 344.170154 -436.142841) (xy 344.193161 -436.150292) (xy 344.212745 -436.16448) (xy 344.226995 -436.184019)
			(xy 344.234521 -436.207002) (xy 344.235024 -436.219092) (xy 344.235024 -438.760616) (xy 344.234598 -438.772723)
			(xy 344.227097 -438.795747) (xy 344.212837 -438.815318) (xy 344.193219 -438.829513) (xy 344.170171 -438.836937)
			(xy 344.158062 -438.837324) (xy 343.218262 -438.837324) (xy 343.206167 -438.836924) (xy 343.183159 -438.829453)
			(xy 343.163577 -438.81525) (xy 343.149329 -438.795701) (xy 343.141804 -438.77271) (xy 343.1413 -438.760616)
			(xy 343.1413 -438.147968) (xy 343.139755 -438.133476) (xy 343.138103 -438.104376) (xy 343.137998 -438.089802)
			(xy 342.235028 -438.089802) (xy 342.235028 -439.0898) (xy 345.137994 -439.0898) (xy 345.138086 -439.075226)
			(xy 345.13974 -439.046125) (xy 345.141296 -439.031634) (xy 345.141296 -437.94807) (xy 345.139752 -437.933578)
			(xy 345.138099 -437.904478) (xy 345.137994 -437.889904) (xy 345.138087 -437.87533) (xy 345.13974 -437.846229)
			(xy 345.141296 -437.831738) (xy 345.141296 -437.21909) (xy 345.141803 -437.206979) (xy 345.149288 -437.183943)
			(xy 345.163522 -437.164345) (xy 345.183114 -437.150102) (xy 345.206147 -437.142608) (xy 345.218258 -437.142128)
			(xy 346.158058 -437.142128) (xy 346.170178 -437.142595) (xy 346.193233 -437.150075) (xy 346.212848 -437.164315)
			(xy 346.227101 -437.18392) (xy 346.234596 -437.206971) (xy 346.23502 -437.21909) (xy 346.23502 -439.0898)
			(xy 383.237994 -439.0898) (xy 383.238086 -439.075226) (xy 383.23974 -439.046125) (xy 383.241296 -439.031634)
			(xy 383.241296 -437.94807) (xy 383.239752 -437.933578) (xy 383.238099 -437.904478) (xy 383.237994 -437.889904)
			(xy 383.238087 -437.87533) (xy 383.23974 -437.846229) (xy 383.241296 -437.831738) (xy 383.241296 -437.218836)
			(xy 383.241747 -437.206729) (xy 383.249236 -437.183704) (xy 383.263489 -437.164131) (xy 383.283103 -437.149935)
			(xy 383.30615 -437.142512) (xy 383.318258 -437.142128) (xy 384.258058 -437.142128) (xy 384.270144 -437.142643)
			(xy 384.293141 -437.150087) (xy 384.312721 -437.164261) (xy 384.326973 -437.183784) (xy 384.334509 -437.206752)
			(xy 384.33502 -437.218836) (xy 384.33502 -438.089802) (xy 385.23799 -438.089802) (xy 385.238083 -438.075228)
			(xy 385.239736 -438.046127) (xy 385.241292 -438.031636) (xy 385.241292 -436.948072) (xy 385.239748 -436.93358)
			(xy 385.238095 -436.90448) (xy 385.23799 -436.889906) (xy 385.238083 -436.875332) (xy 385.239736 -436.846231)
			(xy 385.241292 -436.83174) (xy 385.241292 -436.218838) (xy 385.241843 -436.20673) (xy 385.249315 -436.183696)
			(xy 385.263538 -436.164097) (xy 385.28312 -436.149853) (xy 385.306147 -436.142357) (xy 385.318254 -436.141876)
			(xy 386.258054 -436.141876) (xy 386.270178 -436.1423) (xy 386.293242 -436.149784) (xy 386.312861 -436.164033)
			(xy 386.327113 -436.183651) (xy 386.334599 -436.206714) (xy 386.335016 -436.218838) (xy 386.335016 -438.760362)
			(xy 386.334607 -438.772487) (xy 386.32712 -438.795553) (xy 386.312867 -438.815173) (xy 386.293246 -438.829423)
			(xy 386.270179 -438.836908) (xy 386.258054 -438.837324) (xy 385.318254 -438.837324) (xy 385.306133 -438.836927)
			(xy 385.283082 -438.829422) (xy 385.263478 -438.815162) (xy 385.249239 -438.795543) (xy 385.24176 -438.772483)
			(xy 385.241292 -438.760362) (xy 385.241292 -438.147968) (xy 385.239747 -438.133476) (xy 385.238095 -438.104376)
			(xy 385.23799 -438.089802) (xy 384.33502 -438.089802) (xy 384.33502 -439.0898) (xy 387.237986 -439.0898)
			(xy 387.238078 -439.075226) (xy 387.239732 -439.046125) (xy 387.241288 -439.031634) (xy 387.241288 -437.94807)
			(xy 387.239744 -437.933578) (xy 387.238091 -437.904478) (xy 387.237986 -437.889904) (xy 387.238079 -437.87533)
			(xy 387.239732 -437.846229) (xy 387.241288 -437.831738) (xy 387.241288 -437.218836) (xy 387.241747 -437.20673)
			(xy 387.249235 -437.183706) (xy 387.263486 -437.164134) (xy 387.283098 -437.149937) (xy 387.306143 -437.142514)
			(xy 387.31825 -437.142128) (xy 388.25805 -437.142128) (xy 388.270136 -437.14265) (xy 388.293133 -437.150091)
			(xy 388.312713 -437.164264) (xy 388.326965 -437.183786) (xy 388.334501 -437.206752) (xy 388.335012 -437.218836)
			(xy 388.335012 -438.089802) (xy 389.237982 -438.089802) (xy 389.238075 -438.075228) (xy 389.239728 -438.046127)
			(xy 389.241284 -438.031636) (xy 389.241284 -436.948072) (xy 389.23974 -436.93358) (xy 389.238087 -436.90448)
			(xy 389.237982 -436.889906) (xy 389.238075 -436.875332) (xy 389.239728 -436.846231) (xy 389.241284 -436.83174)
			(xy 389.241284 -436.218838) (xy 389.241693 -436.206713) (xy 389.24918 -436.183647) (xy 389.263433 -436.164027)
			(xy 389.283054 -436.149777) (xy 389.306121 -436.142292) (xy 389.318246 -436.141876) (xy 390.258046 -436.141876)
			(xy 390.270167 -436.142273) (xy 390.293218 -436.149778) (xy 390.312822 -436.164038) (xy 390.327061 -436.183657)
			(xy 390.33454 -436.206717) (xy 390.335008 -436.218838) (xy 390.335008 -438.760362) (xy 390.334457 -438.77247)
			(xy 390.326985 -438.795504) (xy 390.312762 -438.815103) (xy 390.29318 -438.829347) (xy 390.270153 -438.836843)
			(xy 390.258046 -438.837324) (xy 389.318246 -438.837324) (xy 389.306122 -438.8369) (xy 389.283058 -438.829416)
			(xy 389.263439 -438.815167) (xy 389.249187 -438.795549) (xy 389.241701 -438.772486) (xy 389.241284 -438.760362)
			(xy 389.241284 -438.147968) (xy 389.239739 -438.133476) (xy 389.238087 -438.104376) (xy 389.237982 -438.089802)
			(xy 388.335012 -438.089802) (xy 388.335012 -439.0898) (xy 391.237978 -439.0898) (xy 391.238071 -439.075226)
			(xy 391.239724 -439.046125) (xy 391.24128 -439.031634) (xy 391.24128 -437.94807) (xy 391.239736 -437.933578)
			(xy 391.238083 -437.904478) (xy 391.237978 -437.889904) (xy 391.238071 -437.87533) (xy 391.239724 -437.846229)
			(xy 391.24128 -437.831738) (xy 391.24128 -437.218836) (xy 391.241747 -437.206731) (xy 391.249234 -437.183708)
			(xy 391.263483 -437.164136) (xy 391.283093 -437.14994) (xy 391.306136 -437.142515) (xy 391.318242 -437.142128)
			(xy 392.258042 -437.142128) (xy 392.270133 -437.142571) (xy 392.293133 -437.150038) (xy 392.312711 -437.164231)
			(xy 392.32696 -437.183768) (xy 392.334493 -437.206747) (xy 392.335004 -437.218836) (xy 392.335004 -438.089802)
			(xy 393.237974 -438.089802) (xy 393.238067 -438.075228) (xy 393.23972 -438.046127) (xy 393.241276 -438.031636)
			(xy 393.241276 -436.948072) (xy 393.239732 -436.93358) (xy 393.238079 -436.90448) (xy 393.237974 -436.889906)
			(xy 393.238067 -436.875332) (xy 393.23972 -436.846231) (xy 393.241276 -436.83174) (xy 393.241276 -436.218838)
			(xy 393.241693 -436.206713) (xy 393.249179 -436.183649) (xy 393.26343 -436.16403) (xy 393.283049 -436.149779)
			(xy 393.306113 -436.142293) (xy 393.318238 -436.141876) (xy 394.258038 -436.141876) (xy 394.270158 -436.14228)
			(xy 394.293209 -436.149782) (xy 394.312814 -436.16404) (xy 394.327053 -436.183659) (xy 394.334532 -436.206717)
			(xy 394.335 -436.218838) (xy 394.335 -438.760362) (xy 394.334457 -438.772471) (xy 394.326984 -438.795506)
			(xy 394.31276 -438.815106) (xy 394.293175 -438.82935) (xy 394.270146 -438.836845) (xy 394.258038 -438.837324)
			(xy 393.318238 -438.837324) (xy 393.306113 -438.836907) (xy 393.283049 -438.829421) (xy 393.26343 -438.81517)
			(xy 393.249179 -438.795551) (xy 393.241693 -438.772487) (xy 393.241276 -438.760362) (xy 393.241276 -438.147968)
			(xy 393.239731 -438.133476) (xy 393.238079 -438.104376) (xy 393.237974 -438.089802) (xy 392.335004 -438.089802)
			(xy 392.335004 -439.0898) (xy 395.23797 -439.0898) (xy 395.238063 -439.075226) (xy 395.239716 -439.046125)
			(xy 395.241272 -439.031634) (xy 395.241272 -437.94807) (xy 395.239728 -437.933578) (xy 395.238075 -437.904478)
			(xy 395.23797 -437.889904) (xy 395.238063 -437.87533) (xy 395.239716 -437.846229) (xy 395.241272 -437.831738)
			(xy 395.241272 -437.218836) (xy 395.241747 -437.206732) (xy 395.249233 -437.18371) (xy 395.26348 -437.164139)
			(xy 395.283088 -437.149942) (xy 395.306129 -437.142516) (xy 395.318234 -437.142128) (xy 396.258034 -437.142128)
			(xy 396.270124 -437.142578) (xy 396.293124 -437.150043) (xy 396.312702 -437.164234) (xy 396.326952 -437.18377)
			(xy 396.334485 -437.206747) (xy 396.334996 -437.218836) (xy 396.334996 -438.089802) (xy 398.237964 -438.089802)
			(xy 398.238081 -438.074717) (xy 398.239857 -438.044598) (xy 398.24152 -438.029604) (xy 398.24152 -436.950104)
			(xy 398.23985 -436.935111) (xy 398.238072 -436.904992) (xy 398.237964 -436.889906) (xy 398.238072 -436.87482)
			(xy 398.239854 -436.844702) (xy 398.24152 -436.829708) (xy 398.24152 -436.218838) (xy 398.242039 -436.206752)
			(xy 398.249483 -436.183756) (xy 398.263657 -436.164178) (xy 398.283179 -436.149925) (xy 398.306144 -436.142389)
			(xy 398.318228 -436.141876) (xy 399.258028 -436.141876) (xy 399.270136 -436.142292) (xy 399.29316 -436.149796)
			(xy 399.312731 -436.164059) (xy 399.326925 -436.183679) (xy 399.334349 -436.206729) (xy 399.334736 -436.218838)
			(xy 399.334736 -438.760362) (xy 399.33426 -438.772452) (xy 399.326811 -438.795455) (xy 399.312627 -438.815038)
			(xy 399.293094 -438.829289) (xy 399.270116 -438.836818) (xy 399.258028 -438.837324) (xy 398.318228 -438.837324)
			(xy 398.306123 -438.83686) (xy 398.283101 -438.829371) (xy 398.263529 -438.815121) (xy 398.249333 -438.795511)
			(xy 398.241907 -438.772468) (xy 398.24152 -438.760362) (xy 398.24152 -438.15) (xy 398.239849 -438.135007)
			(xy 398.238072 -438.104888) (xy 398.237964 -438.089802) (xy 396.334996 -438.089802) (xy 396.334996 -439.0898)
			(xy 400.23796 -439.0898) (xy 400.238077 -439.074715) (xy 400.239853 -439.044596) (xy 400.241516 -439.029602)
			(xy 400.241516 -437.950102) (xy 400.239845 -437.935109) (xy 400.238068 -437.90499) (xy 400.23796 -437.889904)
			(xy 400.238077 -437.874819) (xy 400.239853 -437.8447) (xy 400.241516 -437.829706) (xy 400.241516 -437.218836)
			(xy 400.241944 -437.206753) (xy 400.249404 -437.183767) (xy 400.263606 -437.164214) (xy 400.283156 -437.15001)
			(xy 400.306141 -437.142546) (xy 400.318224 -437.142128) (xy 401.258024 -437.142128) (xy 401.270112 -437.142493)
			(xy 401.293101 -437.149971) (xy 401.312654 -437.164189) (xy 401.326856 -437.183753) (xy 401.334317 -437.206748)
			(xy 401.334732 -437.218836) (xy 401.334732 -438.089802) (xy 402.237956 -438.089802) (xy 402.238073 -438.074717)
			(xy 402.239849 -438.044598) (xy 402.241512 -438.029604) (xy 402.241512 -436.950104) (xy 402.239842 -436.935111)
			(xy 402.238064 -436.904992) (xy 402.237956 -436.889906) (xy 402.238064 -436.87482) (xy 402.239846 -436.844702)
			(xy 402.241512 -436.829708) (xy 402.241512 -436.218838) (xy 402.242039 -436.206753) (xy 402.249482 -436.183758)
			(xy 402.263654 -436.16418) (xy 402.283174 -436.149928) (xy 402.306137 -436.14239) (xy 402.31822 -436.141876)
			(xy 403.25802 -436.141876) (xy 403.270128 -436.142299) (xy 403.293151 -436.149801) (xy 403.312722 -436.164062)
			(xy 403.326917 -436.18368) (xy 403.334341 -436.206729) (xy 403.334728 -436.218838) (xy 403.334728 -438.760362)
			(xy 403.33426 -438.772453) (xy 403.32681 -438.795458) (xy 403.312624 -438.815041) (xy 403.293089 -438.829292)
			(xy 403.270109 -438.836819) (xy 403.25802 -438.837324) (xy 402.31822 -438.837324) (xy 402.306115 -438.836867)
			(xy 402.283092 -438.829376) (xy 402.263521 -438.815124) (xy 402.249325 -438.795512) (xy 402.241899 -438.772469)
			(xy 402.241512 -438.760362) (xy 402.241512 -438.15) (xy 402.239841 -438.135007) (xy 402.238064 -438.104888)
			(xy 402.237956 -438.089802) (xy 401.334732 -438.089802) (xy 401.334732 -439.0898) (xy 404.237952 -439.0898)
			(xy 404.238069 -439.074715) (xy 404.239845 -439.044596) (xy 404.241508 -439.029602) (xy 404.241508 -437.950102)
			(xy 404.239837 -437.935109) (xy 404.23806 -437.90499) (xy 404.237952 -437.889904) (xy 404.238069 -437.874819)
			(xy 404.239845 -437.8447) (xy 404.241508 -437.829706) (xy 404.241508 -437.218836) (xy 404.241944 -437.206754)
			(xy 404.249403 -437.183769) (xy 404.263603 -437.164217) (xy 404.283151 -437.150012) (xy 404.306134 -437.142547)
			(xy 404.318216 -437.142128) (xy 405.258016 -437.142128) (xy 405.270103 -437.142499) (xy 405.293093 -437.149976)
			(xy 405.312646 -437.164191) (xy 405.326848 -437.183754) (xy 405.334309 -437.206749) (xy 405.334724 -437.218836)
			(xy 405.334724 -438.089802) (xy 406.237948 -438.089802) (xy 406.238065 -438.074717) (xy 406.239841 -438.044598)
			(xy 406.241504 -438.029604) (xy 406.241504 -436.950104) (xy 406.239834 -436.935111) (xy 406.238056 -436.904992)
			(xy 406.237948 -436.889906) (xy 406.238056 -436.87482) (xy 406.239838 -436.844702) (xy 406.241504 -436.829708)
			(xy 406.241504 -436.218838) (xy 406.242039 -436.206754) (xy 406.249481 -436.183761) (xy 406.263651 -436.164183)
			(xy 406.283168 -436.14993) (xy 406.30613 -436.142391) (xy 406.318212 -436.141876) (xy 407.258012 -436.141876)
			(xy 407.270119 -436.142306) (xy 407.293143 -436.149805) (xy 407.312714 -436.164064) (xy 407.326909 -436.183682)
			(xy 407.334333 -436.20673) (xy 407.33472 -436.218838) (xy 407.33472 -438.760362) (xy 407.33426 -438.772454)
			(xy 407.326808 -438.79546) (xy 407.312622 -438.815044) (xy 407.293084 -438.829294) (xy 407.270102 -438.83682)
			(xy 407.258012 -438.837324) (xy 406.318212 -438.837324) (xy 406.306106 -438.836874) (xy 406.283083 -438.82938)
			(xy 406.263512 -438.815127) (xy 406.249316 -438.795514) (xy 406.241891 -438.772469) (xy 406.241504 -438.760362)
			(xy 406.241504 -438.15) (xy 406.239833 -438.135007) (xy 406.238056 -438.104888) (xy 406.237948 -438.089802)
			(xy 405.334724 -438.089802) (xy 405.334724 -439.0898) (xy 408.237944 -439.0898) (xy 408.238061 -439.074715)
			(xy 408.239837 -439.044596) (xy 408.2415 -439.029602) (xy 408.2415 -437.950102) (xy 408.239829 -437.935109)
			(xy 408.238052 -437.90499) (xy 408.237944 -437.889904) (xy 408.238061 -437.874819) (xy 408.239837 -437.8447)
			(xy 408.2415 -437.829706) (xy 408.2415 -437.218836) (xy 408.241944 -437.206754) (xy 408.249402 -437.183771)
			(xy 408.2636 -437.16422) (xy 408.283146 -437.150015) (xy 408.306127 -437.142548) (xy 408.318208 -437.142128)
			(xy 409.258008 -437.142128) (xy 409.270095 -437.142506) (xy 409.293084 -437.14998) (xy 409.312637 -437.164194)
			(xy 409.32684 -437.183756) (xy 409.334301 -437.206749) (xy 409.334716 -437.218836) (xy 409.334716 -438.089802)
			(xy 410.23794 -438.089802) (xy 410.238057 -438.074717) (xy 410.239833 -438.044598) (xy 410.241496 -438.029604)
			(xy 410.241496 -436.950104) (xy 410.239826 -436.935111) (xy 410.238048 -436.904992) (xy 410.23794 -436.889906)
			(xy 410.23805 -436.87482) (xy 410.239832 -436.844702) (xy 410.241496 -436.829708) (xy 410.241496 -436.218838)
			(xy 410.242039 -436.206755) (xy 410.24948 -436.183763) (xy 410.263648 -436.164186) (xy 410.283163 -436.149933)
			(xy 410.306123 -436.142392) (xy 410.318204 -436.141876) (xy 411.258004 -436.141876) (xy 411.270111 -436.142312)
			(xy 411.293134 -436.14981) (xy 411.312705 -436.164067) (xy 411.3269 -436.183683) (xy 411.334325 -436.20673)
			(xy 411.334712 -436.218838) (xy 411.334712 -438.760362) (xy 411.334259 -438.772454) (xy 411.326807 -438.795462)
			(xy 411.312619 -438.815047) (xy 411.293079 -438.829297) (xy 411.270095 -438.836821) (xy 411.258004 -438.837324)
			(xy 410.318204 -438.837324) (xy 410.306098 -438.836881) (xy 410.283075 -438.829385) (xy 410.263503 -438.81513)
			(xy 410.249308 -438.795515) (xy 410.241883 -438.77247) (xy 410.241496 -438.760362) (xy 410.241496 -438.15)
			(xy 410.239825 -438.135007) (xy 410.238048 -438.104888) (xy 410.23794 -438.089802) (xy 409.334716 -438.089802)
			(xy 409.334716 -439.0898) (xy 412.237936 -439.0898) (xy 412.238053 -439.074715) (xy 412.239829 -439.044596)
			(xy 412.241492 -439.029602) (xy 412.241492 -437.950102) (xy 412.239821 -437.935109) (xy 412.238044 -437.90499)
			(xy 412.237936 -437.889904) (xy 412.238053 -437.874819) (xy 412.239829 -437.8447) (xy 412.241492 -437.829706)
			(xy 412.241492 -437.218836) (xy 412.241943 -437.206755) (xy 412.249401 -437.183774) (xy 412.263597 -437.164223)
			(xy 412.283141 -437.150017) (xy 412.306119 -437.142549) (xy 412.3182 -437.142128) (xy 413.258 -437.142128)
			(xy 413.270086 -437.142513) (xy 413.293075 -437.149985) (xy 413.312629 -437.164197) (xy 413.326832 -437.183757)
			(xy 413.334293 -437.206749) (xy 413.334708 -437.218836) (xy 413.334708 -439.76036) (xy 413.334253 -439.772441)
			(xy 413.326797 -439.795422) (xy 413.312601 -439.814973) (xy 413.293058 -439.829178) (xy 413.27008 -439.836647)
			(xy 413.258 -439.837068) (xy 412.3182 -439.837068) (xy 412.306113 -439.836687) (xy 412.283124 -439.829215)
			(xy 412.26357 -439.815002) (xy 412.249367 -439.79544) (xy 412.241907 -439.772447) (xy 412.241492 -439.76036)
			(xy 412.241492 -439.149998) (xy 412.239821 -439.135005) (xy 412.238044 -439.104886) (xy 412.237936 -439.0898)
			(xy 409.334716 -439.0898) (xy 409.334716 -439.76036) (xy 409.334253 -439.77244) (xy 409.326798 -439.79542)
			(xy 409.312604 -439.81497) (xy 409.293063 -439.829176) (xy 409.270088 -439.836646) (xy 409.258008 -439.837068)
			(xy 408.318208 -439.837068) (xy 408.306122 -439.83668) (xy 408.283132 -439.82921) (xy 408.263578 -439.814999)
			(xy 408.249375 -439.795439) (xy 408.241915 -439.772447) (xy 408.2415 -439.76036) (xy 408.2415 -439.149998)
			(xy 408.239829 -439.135005) (xy 408.238052 -439.104886) (xy 408.237944 -439.0898) (xy 405.334724 -439.0898)
			(xy 405.334724 -439.76036) (xy 405.334253 -439.772439) (xy 405.326799 -439.795418) (xy 405.312607 -439.814967)
			(xy 405.293068 -439.829173) (xy 405.270095 -439.836645) (xy 405.258016 -439.837068) (xy 404.318216 -439.837068)
			(xy 404.30613 -439.836673) (xy 404.283141 -439.829205) (xy 404.263587 -439.814996) (xy 404.249384 -439.795437)
			(xy 404.241923 -439.772446) (xy 404.241508 -439.76036) (xy 404.241508 -439.149998) (xy 404.239837 -439.135005)
			(xy 404.23806 -439.104886) (xy 404.237952 -439.0898) (xy 401.334732 -439.0898) (xy 401.334732 -439.76036)
			(xy 401.334254 -439.772438) (xy 401.3268 -439.795416) (xy 401.31261 -439.814964) (xy 401.293073 -439.829171)
			(xy 401.270102 -439.836644) (xy 401.258024 -439.837068) (xy 400.318224 -439.837068) (xy 400.306139 -439.836666)
			(xy 400.28315 -439.8292) (xy 400.263596 -439.814993) (xy 400.249392 -439.795436) (xy 400.241931 -439.772446)
			(xy 400.241516 -439.76036) (xy 400.241516 -439.149998) (xy 400.239845 -439.135005) (xy 400.238068 -439.104886)
			(xy 400.23796 -439.0898) (xy 396.334996 -439.0898) (xy 396.334996 -439.76036) (xy 396.334549 -439.772467)
			(xy 396.327061 -439.795494) (xy 396.312807 -439.815068) (xy 396.293191 -439.829264) (xy 396.270142 -439.836685)
			(xy 396.258034 -439.837068) (xy 395.318234 -439.837068) (xy 395.306147 -439.836564) (xy 395.283149 -439.829117)
			(xy 395.263569 -439.81494) (xy 395.249317 -439.795415) (xy 395.241783 -439.772445) (xy 395.241272 -439.76036)
			(xy 395.241272 -439.147966) (xy 395.239727 -439.133474) (xy 395.238075 -439.104374) (xy 395.23797 -439.0898)
			(xy 392.335004 -439.0898) (xy 392.335004 -439.76036) (xy 392.33455 -439.772466) (xy 392.327062 -439.795492)
			(xy 392.31281 -439.815065) (xy 392.293196 -439.829261) (xy 392.270149 -439.836684) (xy 392.258042 -439.837068)
			(xy 391.318242 -439.837068) (xy 391.306155 -439.836557) (xy 391.283157 -439.829113) (xy 391.263578 -439.814937)
			(xy 391.249325 -439.795413) (xy 391.241791 -439.772445) (xy 391.24128 -439.76036) (xy 391.24128 -439.147966)
			(xy 391.239735 -439.133474) (xy 391.238083 -439.104374) (xy 391.237978 -439.0898) (xy 388.335012 -439.0898)
			(xy 388.335012 -439.76036) (xy 388.33455 -439.772466) (xy 388.327063 -439.79549) (xy 388.312813 -439.815062)
			(xy 388.293201 -439.829259) (xy 388.270157 -439.836682) (xy 388.25805 -439.837068) (xy 387.31825 -439.837068)
			(xy 387.306164 -439.83655) (xy 387.283166 -439.829108) (xy 387.263586 -439.814935) (xy 387.249333 -439.795412)
			(xy 387.241799 -439.772444) (xy 387.241288 -439.76036) (xy 387.241288 -439.147966) (xy 387.239743 -439.133474)
			(xy 387.238091 -439.104374) (xy 387.237986 -439.0898) (xy 384.33502 -439.0898) (xy 384.33502 -439.76036)
			(xy 384.33455 -439.772465) (xy 384.327064 -439.795487) (xy 384.312816 -439.815059) (xy 384.293206 -439.829256)
			(xy 384.270164 -439.836681) (xy 384.258058 -439.837068) (xy 383.318258 -439.837068) (xy 383.306167 -439.836629)
			(xy 383.283166 -439.829161) (xy 383.263588 -439.814967) (xy 383.249338 -439.795429) (xy 383.241806 -439.77245)
			(xy 383.241296 -439.76036) (xy 383.241296 -439.147966) (xy 383.239751 -439.133474) (xy 383.238099 -439.104374)
			(xy 383.237994 -439.0898) (xy 346.23502 -439.0898) (xy 346.23502 -439.760614) (xy 346.234651 -439.772742)
			(xy 346.22715 -439.795808) (xy 346.212886 -439.815426) (xy 346.193258 -439.829675) (xy 346.170186 -439.83716)
			(xy 346.158058 -439.837576) (xy 345.218258 -439.837576) (xy 345.206143 -439.837124) (xy 345.1831 -439.829627)
			(xy 345.163501 -439.815379) (xy 345.14926 -439.795774) (xy 345.141771 -439.77273) (xy 345.141296 -439.760614)
			(xy 345.141296 -439.147966) (xy 345.139751 -439.133474) (xy 345.138099 -439.104374) (xy 345.137994 -439.0898)
			(xy 342.235028 -439.0898) (xy 342.235028 -439.760614) (xy 342.234651 -439.772741) (xy 342.227151 -439.795806)
			(xy 342.212889 -439.815424) (xy 342.193263 -439.829673) (xy 342.170193 -439.837159) (xy 342.158066 -439.837576)
			(xy 341.218266 -439.837576) (xy 341.206151 -439.837118) (xy 341.183109 -439.829623) (xy 341.163509 -439.815377)
			(xy 341.149268 -439.795773) (xy 341.141779 -439.772729) (xy 341.141304 -439.760614) (xy 341.141304 -439.147966)
			(xy 341.139759 -439.133474) (xy 341.138107 -439.104374) (xy 341.138002 -439.0898) (xy 338.235036 -439.0898)
			(xy 338.235036 -439.760614) (xy 338.234651 -439.77274) (xy 338.227152 -439.795804) (xy 338.212892 -439.815421)
			(xy 338.193268 -439.82967) (xy 338.1702 -439.837158) (xy 338.158074 -439.837576) (xy 337.218274 -439.837576)
			(xy 337.206159 -439.837111) (xy 337.183118 -439.829618) (xy 337.163518 -439.815374) (xy 337.149276 -439.795772)
			(xy 337.141787 -439.772729) (xy 337.141312 -439.760614) (xy 337.141312 -439.147966) (xy 337.139767 -439.133474)
			(xy 337.138115 -439.104374) (xy 337.13801 -439.0898) (xy 334.235044 -439.0898) (xy 334.235044 -439.760614)
			(xy 334.234651 -439.772739) (xy 334.227153 -439.795802) (xy 334.212895 -439.815418) (xy 334.193273 -439.829668)
			(xy 334.170207 -439.837157) (xy 334.158082 -439.837576) (xy 333.218282 -439.837576) (xy 333.206168 -439.837104)
			(xy 333.183126 -439.829614) (xy 333.163526 -439.815371) (xy 333.149285 -439.79577) (xy 333.141795 -439.772728)
			(xy 333.14132 -439.760614) (xy 333.14132 -439.147966) (xy 333.139775 -439.133474) (xy 333.138123 -439.104374)
			(xy 333.138018 -439.0898) (xy 329.2348 -439.0898) (xy 329.2348 -439.760614) (xy 329.234306 -439.7727)
			(xy 329.22685 -439.795695) (xy 329.212669 -439.815271) (xy 329.193144 -439.829523) (xy 329.170177 -439.837061)
			(xy 329.158092 -439.837576) (xy 328.218292 -439.837576) (xy 328.20618 -439.83719) (xy 328.183149 -439.829686)
			(xy 328.163574 -439.815417) (xy 328.14938 -439.795788) (xy 328.141964 -439.772727) (xy 328.141584 -439.760614)
			(xy 328.141584 -439.149998) (xy 328.139913 -439.135005) (xy 328.138136 -439.104886) (xy 328.138028 -439.0898)
			(xy 325.234808 -439.0898) (xy 325.234808 -439.760614) (xy 325.234306 -439.7727) (xy 325.226851 -439.795693)
			(xy 325.212672 -439.815268) (xy 325.193149 -439.82952) (xy 325.170184 -439.83706) (xy 325.1581 -439.837576)
			(xy 324.2183 -439.837576) (xy 324.206189 -439.837184) (xy 324.183157 -439.829681) (xy 324.163582 -439.815414)
			(xy 324.149388 -439.795786) (xy 324.141972 -439.772727) (xy 324.141592 -439.760614) (xy 324.141592 -439.149998)
			(xy 324.139921 -439.135005) (xy 324.138144 -439.104886) (xy 324.138036 -439.0898) (xy 321.234816 -439.0898)
			(xy 321.234816 -439.760614) (xy 321.234404 -439.772709) (xy 321.226938 -439.795717) (xy 321.212739 -439.815301)
			(xy 321.193191 -439.829549) (xy 321.170201 -439.837073) (xy 321.158108 -439.837576) (xy 320.218308 -439.837576)
			(xy 320.206197 -439.837177) (xy 320.183166 -439.829677) (xy 320.163591 -439.815412) (xy 320.149396 -439.795785)
			(xy 320.14198 -439.772726) (xy 320.1416 -439.760614) (xy 320.1416 -439.149998) (xy 320.139929 -439.135005)
			(xy 320.138152 -439.104886) (xy 320.138044 -439.0898) (xy 317.234824 -439.0898) (xy 317.234824 -439.760614)
			(xy 317.234404 -439.772708) (xy 317.226939 -439.795715) (xy 317.212742 -439.815298) (xy 317.193196 -439.829547)
			(xy 317.170209 -439.837072) (xy 317.158116 -439.837576) (xy 316.218316 -439.837576) (xy 316.206206 -439.83717)
			(xy 316.183175 -439.829672) (xy 316.163599 -439.815408) (xy 316.149405 -439.795783) (xy 316.141988 -439.772726)
			(xy 316.141608 -439.760614) (xy 316.141608 -439.149998) (xy 316.139937 -439.135005) (xy 316.13816 -439.104886)
			(xy 316.138052 -439.0898) (xy 157.334712 -439.0898) (xy 157.334712 -439.76036) (xy 157.334253 -439.77244)
			(xy 157.326797 -439.795421) (xy 157.312603 -439.814972) (xy 157.29306 -439.829177) (xy 157.270084 -439.836646)
			(xy 157.258004 -439.837068) (xy 156.318204 -439.837068) (xy 156.306117 -439.836684) (xy 156.283128 -439.829212)
			(xy 156.263574 -439.815) (xy 156.249371 -439.79544) (xy 156.241911 -439.772447) (xy 156.241496 -439.76036)
			(xy 156.241496 -439.149998) (xy 156.239825 -439.135005) (xy 156.238048 -439.104886) (xy 156.23794 -439.0898)
			(xy 153.33472 -439.0898) (xy 153.33472 -439.76036) (xy 153.334253 -439.772439) (xy 153.326798 -439.795419)
			(xy 153.312606 -439.814969) (xy 153.293065 -439.829175) (xy 153.270091 -439.836645) (xy 153.258012 -439.837068)
			(xy 152.318212 -439.837068) (xy 152.306126 -439.836676) (xy 152.283137 -439.829207) (xy 152.263583 -439.814997)
			(xy 152.24938 -439.795438) (xy 152.241919 -439.772446) (xy 152.241504 -439.76036) (xy 152.241504 -439.149998)
			(xy 152.239833 -439.135005) (xy 152.238056 -439.104886) (xy 152.237948 -439.0898) (xy 149.334728 -439.0898)
			(xy 149.334728 -439.76036) (xy 149.334254 -439.772439) (xy 149.326799 -439.795417) (xy 149.312609 -439.814966)
			(xy 149.29307 -439.829172) (xy 149.270098 -439.836644) (xy 149.25802 -439.837068) (xy 148.31822 -439.837068)
			(xy 148.306134 -439.83667) (xy 148.283146 -439.829203) (xy 148.263592 -439.814994) (xy 148.249388 -439.795437)
			(xy 148.241927 -439.772446) (xy 148.241512 -439.76036) (xy 148.241512 -439.149998) (xy 148.239841 -439.135005)
			(xy 148.238064 -439.104886) (xy 148.237956 -439.0898) (xy 145.334736 -439.0898) (xy 145.334736 -439.76036)
			(xy 145.334254 -439.772438) (xy 145.326801 -439.795415) (xy 145.312611 -439.814963) (xy 145.293075 -439.829169)
			(xy 145.270105 -439.836643) (xy 145.258028 -439.837068) (xy 144.318228 -439.837068) (xy 144.306143 -439.836663)
			(xy 144.283154 -439.829198) (xy 144.2636 -439.814991) (xy 144.249396 -439.795435) (xy 144.241935 -439.772445)
			(xy 144.24152 -439.76036) (xy 144.24152 -439.149998) (xy 144.239849 -439.135005) (xy 144.238072 -439.104886)
			(xy 144.237964 -439.0898) (xy 140.335 -439.0898) (xy 140.335 -439.76036) (xy 140.33455 -439.772467)
			(xy 140.327061 -439.795493) (xy 140.312808 -439.815067) (xy 140.293193 -439.829263) (xy 140.270146 -439.836684)
			(xy 140.258038 -439.837068) (xy 139.318238 -439.837068) (xy 139.306151 -439.83656) (xy 139.283153 -439.829115)
			(xy 139.263573 -439.814939) (xy 139.249321 -439.795414) (xy 139.241787 -439.772445) (xy 139.241276 -439.76036)
			(xy 139.241276 -439.147966) (xy 139.239731 -439.133474) (xy 139.238079 -439.104374) (xy 139.237974 -439.0898)
			(xy 136.335008 -439.0898) (xy 136.335008 -439.76036) (xy 136.33455 -439.772466) (xy 136.327062 -439.795491)
			(xy 136.312811 -439.815064) (xy 136.293199 -439.82926) (xy 136.270153 -439.836683) (xy 136.258046 -439.837068)
			(xy 135.318246 -439.837068) (xy 135.30616 -439.836554) (xy 135.283162 -439.829111) (xy 135.263582 -439.814936)
			(xy 135.249329 -439.795412) (xy 135.241795 -439.772444) (xy 135.241284 -439.76036) (xy 135.241284 -439.147966)
			(xy 135.239739 -439.133474) (xy 135.238087 -439.104374) (xy 135.237982 -439.0898) (xy 132.335016 -439.0898)
			(xy 132.335016 -439.76036) (xy 132.33455 -439.772465) (xy 132.327063 -439.795488) (xy 132.312814 -439.815061)
			(xy 132.293204 -439.829257) (xy 132.27016 -439.836682) (xy 132.258054 -439.837068) (xy 131.318254 -439.837068)
			(xy 131.306163 -439.836632) (xy 131.283162 -439.829164) (xy 131.263584 -439.814969) (xy 131.249334 -439.79543)
			(xy 131.241802 -439.77245) (xy 131.241292 -439.76036) (xy 131.241292 -439.147966) (xy 131.239747 -439.133474)
			(xy 131.238095 -439.104374) (xy 131.23799 -439.0898) (xy 128.335024 -439.0898) (xy 128.335024 -439.76036)
			(xy 128.33455 -439.772464) (xy 128.327064 -439.795486) (xy 128.312817 -439.815058) (xy 128.293209 -439.829255)
			(xy 128.270167 -439.836681) (xy 128.258062 -439.837068) (xy 127.318262 -439.837068) (xy 127.306171 -439.836625)
			(xy 127.283171 -439.829159) (xy 127.263592 -439.814966) (xy 127.249343 -439.795428) (xy 127.24181 -439.772449)
			(xy 127.2413 -439.76036) (xy 127.2413 -439.147966) (xy 127.239755 -439.133474) (xy 127.238103 -439.104374)
			(xy 127.237998 -439.0898) (xy 90.235024 -439.0898) (xy 90.235024 -439.760614) (xy 90.234651 -439.772741)
			(xy 90.22715 -439.795807) (xy 90.212888 -439.815425) (xy 90.19326 -439.829674) (xy 90.17019 -439.837159)
			(xy 90.158062 -439.837576) (xy 89.218262 -439.837576) (xy 89.206147 -439.837121) (xy 89.183105 -439.829625)
			(xy 89.163505 -439.815378) (xy 89.149264 -439.795774) (xy 89.141775 -439.772729) (xy 89.1413 -439.760614)
			(xy 89.1413 -439.147966) (xy 89.139755 -439.133474) (xy 89.138103 -439.104374) (xy 89.137998 -439.0898)
			(xy 86.235032 -439.0898) (xy 86.235032 -439.760614) (xy 86.234651 -439.77274) (xy 86.227152 -439.795805)
			(xy 86.212891 -439.815422) (xy 86.193265 -439.829672) (xy 86.170197 -439.837158) (xy 86.15807 -439.837576)
			(xy 85.21827 -439.837576) (xy 85.206155 -439.837114) (xy 85.183113 -439.82962) (xy 85.163513 -439.815375)
			(xy 85.149272 -439.795772) (xy 85.141783 -439.772729) (xy 85.141308 -439.760614) (xy 85.141308 -439.147966)
			(xy 85.139763 -439.133474) (xy 85.138111 -439.104374) (xy 85.138006 -439.0898) (xy 82.23504 -439.0898)
			(xy 82.23504 -439.760614) (xy 82.234651 -439.77274) (xy 82.227153 -439.795803) (xy 82.212894 -439.815419)
			(xy 82.19327 -439.829669) (xy 82.170204 -439.837157) (xy 82.158078 -439.837576) (xy 81.218278 -439.837576)
			(xy 81.206164 -439.837107) (xy 81.183122 -439.829616) (xy 81.163522 -439.815372) (xy 81.149281 -439.795771)
			(xy 81.141791 -439.772728) (xy 81.141316 -439.760614) (xy 81.141316 -439.147966) (xy 81.139771 -439.133474)
			(xy 81.138119 -439.104374) (xy 81.138014 -439.0898) (xy 78.235048 -439.0898) (xy 78.235048 -439.760614)
			(xy 78.2346 -439.772731) (xy 78.227107 -439.795777) (xy 78.21286 -439.81538) (xy 78.193252 -439.82962)
			(xy 78.170203 -439.837105) (xy 78.158086 -439.837576) (xy 77.218286 -439.837576) (xy 77.206172 -439.837101)
			(xy 77.183131 -439.829611) (xy 77.16353 -439.81537) (xy 77.149289 -439.795769) (xy 77.141799 -439.772728)
			(xy 77.141324 -439.760614) (xy 77.141324 -439.147966) (xy 77.139779 -439.133474) (xy 77.138127 -439.104374)
			(xy 77.138022 -439.0898) (xy 73.234804 -439.0898) (xy 73.234804 -439.760614) (xy 73.234306 -439.7727)
			(xy 73.22685 -439.795694) (xy 73.21267 -439.81527) (xy 73.193146 -439.829521) (xy 73.17018 -439.837061)
			(xy 73.158096 -439.837576) (xy 72.218296 -439.837576) (xy 72.206185 -439.837187) (xy 72.183153 -439.829683)
			(xy 72.163578 -439.815416) (xy 72.149384 -439.795787) (xy 72.141968 -439.772727) (xy 72.141588 -439.760614)
			(xy 72.141588 -439.149998) (xy 72.139917 -439.135005) (xy 72.13814 -439.104886) (xy 72.138032 -439.0898)
			(xy 69.234812 -439.0898) (xy 69.234812 -439.760614) (xy 69.234404 -439.772709) (xy 69.226938 -439.795718)
			(xy 69.212737 -439.815302) (xy 69.193189 -439.829551) (xy 69.170198 -439.837074) (xy 69.158104 -439.837576)
			(xy 68.218304 -439.837576) (xy 68.206193 -439.83718) (xy 68.183162 -439.829679) (xy 68.163586 -439.815413)
			(xy 68.149392 -439.795785) (xy 68.141976 -439.772727) (xy 68.141596 -439.760614) (xy 68.141596 -439.149998)
			(xy 68.139925 -439.135005) (xy 68.138148 -439.104886) (xy 68.13804 -439.0898) (xy 65.23482 -439.0898)
			(xy 65.23482 -439.760614) (xy 65.234404 -439.772708) (xy 65.226939 -439.795716) (xy 65.21274 -439.815299)
			(xy 65.193194 -439.829548) (xy 65.170205 -439.837073) (xy 65.158112 -439.837576) (xy 64.218312 -439.837576)
			(xy 64.206201 -439.837173) (xy 64.18317 -439.829674) (xy 64.163595 -439.81541) (xy 64.149401 -439.795784)
			(xy 64.141984 -439.772726) (xy 64.141604 -439.760614) (xy 64.141604 -439.149998) (xy 64.139933 -439.135005)
			(xy 64.138156 -439.104886) (xy 64.138048 -439.0898) (xy 61.234828 -439.0898) (xy 61.234828 -439.760614)
			(xy 61.234404 -439.772708) (xy 61.22694 -439.795714) (xy 61.212743 -439.815297) (xy 61.193199 -439.829546)
			(xy 61.170212 -439.837072) (xy 61.15812 -439.837576) (xy 60.21832 -439.837576) (xy 60.20621 -439.837166)
			(xy 60.183179 -439.829669) (xy 60.163604 -439.815407) (xy 60.149409 -439.795782) (xy 60.141992 -439.772726)
			(xy 60.141612 -439.760614) (xy 60.141612 -439.149998) (xy 60.139941 -439.135005) (xy 60.138164 -439.104886)
			(xy 60.138056 -439.0898) (xy 7.00913 -439.0898) (xy 7.00913 -439.989976) (xy 7.009638 -440.045746)
			(xy 7.017973 -440.156973) (xy 7.034597 -440.267266) (xy 7.059417 -440.376009) (xy 7.092293 -440.482593)
			(xy 7.133043 -440.586422) (xy 7.181438 -440.686915) (xy 7.237207 -440.783511) (xy 7.300039 -440.87567)
			(xy 7.369583 -440.962874) (xy 7.445449 -441.044639) (xy 7.527212 -441.120505) (xy 7.614417 -441.190048)
			(xy 7.706575 -441.252881) (xy 7.803171 -441.30865) (xy 7.903664 -441.357045) (xy 8.007493 -441.397795)
			(xy 8.114077 -441.430672) (xy 8.22282 -441.455492) (xy 8.333113 -441.472116) (xy 8.44434 -441.480451)
			(xy 8.50011 -441.480956) (xy 194.495928 -441.480956)
		)
		(stroke
			(width 0)
			(type solid)
		)
		(fill yes)
		(layer "In7.Cu")
		(net "GND")
	)
	(gr_line
		(start 184.879488 -406.620726)
		(end 185.209688 -406.950926)
		(stroke
			(width 0.635)
			(type default)
		)
		(layer "In7.Cu")
	)
	(gr_line
		(start 184.879488 -400.685254)
		(end 184.879488 -406.620726)
		(stroke
			(width 0.635)
			(type default)
		)
		(layer "In7.Cu")
	)
	(gr_line
		(start 185.006488 -413.164528)
		(end 185.006488 -408.491182)
		(stroke
			(width 0.635)
			(type default)
		)
		(layer "In7.Cu")
	)
	(gr_line
		(start 185.209688 -408.287982)
		(end 185.006488 -408.491182)
		(stroke
			(width 0.635)
			(type default)
		)
		(layer "In7.Cu")
	)
	(gr_line
		(start 185.209688 -406.950926)
		(end 185.209688 -408.287982)
		(stroke
			(width 0.635)
			(type default)
		)
		(layer "In7.Cu")
	)
	(gr_line
		(start 188.73343 -400.685254)
		(end 184.879488 -400.685254)
		(stroke
			(width 0.635)
			(type default)
		)
		(layer "In7.Cu")
	)
	(gr_line
		(start 188.93536 -403.657054)
		(end 188.93536 -400.890232)
		(stroke
			(width 0.635)
			(type default)
		)
		(layer "In7.Cu")
	)
	(gr_line
		(start 188.93536 -400.890232)
		(end 188.73343 -400.685254)
		(stroke
			(width 0.635)
			(type default)
		)
		(layer "In7.Cu")
	)
	(gr_line
		(start 189.11316 -403.834854)
		(end 188.93536 -403.657054)
		(stroke
			(width 0.635)
			(type default)
		)
		(layer "In7.Cu")
	)
	(gr_line
		(start 189.46876 -403.834854)
		(end 189.11316 -403.834854)
		(stroke
			(width 0.635)
			(type default)
		)
		(layer "In7.Cu")
	)
	(gr_line
		(start 189.680088 -404.477982)
		(end 189.680088 -404.046182)
		(stroke
			(width 0.635)
			(type default)
		)
		(layer "In7.Cu")
	)
	(gr_line
		(start 189.680088 -404.046182)
		(end 189.46876 -403.834854)
		(stroke
			(width 0.635)
			(type default)
		)
		(layer "In7.Cu")
	)
	(gr_line
		(start 190.870332 -405.66848)
		(end 189.680088 -404.477982)
		(stroke
			(width 0.635)
			(type default)
		)
		(layer "In7.Cu")
	)
	(gr_line
		(start 192.77076 -420.9288)
		(end 185.006488 -413.164528)
		(stroke
			(width 0.635)
			(type default)
		)
		(layer "In7.Cu")
	)
	(gr_line
		(start 196.969888 -405.66848)
		(end 190.870332 -405.66848)
		(stroke
			(width 0.635)
			(type default)
		)
		(layer "In7.Cu")
	)
	(gr_line
		(start 197.416928 -420.9288)
		(end 192.77076 -420.9288)
		(stroke
			(width 0.635)
			(type default)
		)
		(layer "In7.Cu")
	)
	(gr_line
		(start 198.15048 -404.487888)
		(end 196.969888 -405.66848)
		(stroke
			(width 0.635)
			(type default)
		)
		(layer "In7.Cu")
	)
	(gr_line
		(start 198.15048 -400.893788)
		(end 198.15048 -404.487888)
		(stroke
			(width 0.635)
			(type default)
		)
		(layer "In7.Cu")
	)
	(gr_line
		(start 198.341488 -400.70278)
		(end 198.15048 -400.893788)
		(stroke
			(width 0.635)
			(type default)
		)
		(layer "In7.Cu")
	)
	(gr_line
		(start 201.995532 -400.70278)
		(end 198.341488 -400.70278)
		(stroke
			(width 0.635)
			(type default)
		)
		(layer "In7.Cu")
	)
	(gr_line
		(start 202.19416 -404.462488)
		(end 202.19416 -400.901408)
		(stroke
			(width 0.635)
			(type default)
		)
		(layer "In7.Cu")
	)
	(gr_line
		(start 202.19416 -400.901408)
		(end 201.995532 -400.70278)
		(stroke
			(width 0.635)
			(type default)
		)
		(layer "In7.Cu")
	)
	(gr_line
		(start 202.380088 -407.607008)
		(end 202.380088 -404.648416)
		(stroke
			(width 0.635)
			(type default)
		)
		(layer "In7.Cu")
	)
	(gr_line
		(start 202.380088 -404.648416)
		(end 202.19416 -404.462488)
		(stroke
			(width 0.635)
			(type default)
		)
		(layer "In7.Cu")
	)
	(gr_line
		(start 204.16012 -409.38704)
		(end 202.380088 -407.607008)
		(stroke
			(width 0.635)
			(type default)
		)
		(layer "In7.Cu")
	)
	(gr_line
		(start 206.17434 -435.523132)
		(end 207.503268 -436.85206)
		(stroke
			(width 0.635)
			(type default)
		)
		(layer "In7.Cu")
	)
	(gr_line
		(start 206.17434 -429.686212)
		(end 197.416928 -420.9288)
		(stroke
			(width 0.635)
			(type default)
		)
		(layer "In7.Cu")
	)
	(gr_line
		(start 206.17434 -429.686212)
		(end 206.17434 -435.523132)
		(stroke
			(width 0.635)
			(type default)
		)
		(layer "In7.Cu")
	)
	(gr_line
		(start 206.545688 -409.38704)
		(end 204.16012 -409.38704)
		(stroke
			(width 0.635)
			(type default)
		)
		(layer "In7.Cu")
	)
	(gr_line
		(start 207.503268 -436.85206)
		(end 228.909372 -436.85206)
		(stroke
			(width 0.635)
			(type default)
		)
		(layer "In7.Cu")
	)
	(gr_line
		(start 208.628488 -407.30424)
		(end 206.545688 -409.38704)
		(stroke
			(width 0.635)
			(type default)
		)
		(layer "In7.Cu")
	)
	(gr_line
		(start 208.628488 -404.642828)
		(end 208.628488 -407.30424)
		(stroke
			(width 0.635)
			(type default)
		)
		(layer "In7.Cu")
	)
	(gr_line
		(start 208.81848 -404.452836)
		(end 208.628488 -404.642828)
		(stroke
			(width 0.635)
			(type default)
		)
		(layer "In7.Cu")
	)
	(gr_line
		(start 208.81848 -400.893788)
		(end 208.81848 -404.452836)
		(stroke
			(width 0.635)
			(type default)
		)
		(layer "In7.Cu")
	)
	(gr_line
		(start 209.009488 -400.70278)
		(end 208.81848 -400.893788)
		(stroke
			(width 0.635)
			(type default)
		)
		(layer "In7.Cu")
	)
	(gr_line
		(start 212.668612 -400.70278)
		(end 209.009488 -400.70278)
		(stroke
			(width 0.635)
			(type default)
		)
		(layer "In7.Cu")
	)
	(gr_line
		(start 212.85962 -404.485348)
		(end 212.85962 -400.893788)
		(stroke
			(width 0.635)
			(type default)
		)
		(layer "In7.Cu")
	)
	(gr_line
		(start 212.85962 -400.893788)
		(end 212.668612 -400.70278)
		(stroke
			(width 0.635)
			(type default)
		)
		(layer "In7.Cu")
	)
	(gr_line
		(start 213.03742 -407.525728)
		(end 213.03742 -404.663148)
		(stroke
			(width 0.635)
			(type default)
		)
		(layer "In7.Cu")
	)
	(gr_line
		(start 213.03742 -404.663148)
		(end 212.85962 -404.485348)
		(stroke
			(width 0.635)
			(type default)
		)
		(layer "In7.Cu")
	)
	(gr_line
		(start 214.794592 -409.2829)
		(end 213.03742 -407.525728)
		(stroke
			(width 0.635)
			(type default)
		)
		(layer "In7.Cu")
	)
	(gr_line
		(start 217.272616 -409.2829)
		(end 214.794592 -409.2829)
		(stroke
			(width 0.635)
			(type default)
		)
		(layer "In7.Cu")
	)
	(gr_line
		(start 219.296488 -407.259028)
		(end 217.272616 -409.2829)
		(stroke
			(width 0.635)
			(type default)
		)
		(layer "In7.Cu")
	)
	(gr_line
		(start 219.296488 -404.673308)
		(end 219.296488 -407.259028)
		(stroke
			(width 0.635)
			(type default)
		)
		(layer "In7.Cu")
	)
	(gr_line
		(start 219.47886 -404.490936)
		(end 219.296488 -404.673308)
		(stroke
			(width 0.635)
			(type default)
		)
		(layer "In7.Cu")
	)
	(gr_line
		(start 219.47886 -400.906488)
		(end 219.47886 -404.490936)
		(stroke
			(width 0.635)
			(type default)
		)
		(layer "In7.Cu")
	)
	(gr_line
		(start 219.682568 -400.70278)
		(end 219.47886 -400.906488)
		(stroke
			(width 0.635)
			(type default)
		)
		(layer "In7.Cu")
	)
	(gr_line
		(start 223.323912 -400.70278)
		(end 219.682568 -400.70278)
		(stroke
			(width 0.635)
			(type default)
		)
		(layer "In7.Cu")
	)
	(gr_line
		(start 223.53524 -404.47976)
		(end 223.53524 -400.914108)
		(stroke
			(width 0.635)
			(type default)
		)
		(layer "In7.Cu")
	)
	(gr_line
		(start 223.53524 -400.914108)
		(end 223.323912 -400.70278)
		(stroke
			(width 0.635)
			(type default)
		)
		(layer "In7.Cu")
	)
	(gr_line
		(start 223.716088 -407.403808)
		(end 223.716088 -404.660608)
		(stroke
			(width 0.635)
			(type default)
		)
		(layer "In7.Cu")
	)
	(gr_line
		(start 223.716088 -404.660608)
		(end 223.53524 -404.47976)
		(stroke
			(width 0.635)
			(type default)
		)
		(layer "In7.Cu")
	)
	(gr_line
		(start 225.70694 -409.39466)
		(end 223.716088 -407.403808)
		(stroke
			(width 0.635)
			(type default)
		)
		(layer "In7.Cu")
	)
	(gr_line
		(start 227.935028 -409.39466)
		(end 225.70694 -409.39466)
		(stroke
			(width 0.635)
			(type default)
		)
		(layer "In7.Cu")
	)
	(gr_line
		(start 228.909372 -436.85206)
		(end 230.69804 -435.063392)
		(stroke
			(width 0.635)
			(type default)
		)
		(layer "In7.Cu")
	)
	(gr_line
		(start 229.939088 -407.3906)
		(end 227.935028 -409.39466)
		(stroke
			(width 0.635)
			(type default)
		)
		(layer "In7.Cu")
	)
	(gr_line
		(start 229.939088 -404.678388)
		(end 229.939088 -407.3906)
		(stroke
			(width 0.635)
			(type default)
		)
		(layer "In7.Cu")
	)
	(gr_line
		(start 230.14432 -404.473156)
		(end 229.939088 -404.678388)
		(stroke
			(width 0.635)
			(type default)
		)
		(layer "In7.Cu")
	)
	(gr_line
		(start 230.14432 -400.901408)
		(end 230.14432 -404.473156)
		(stroke
			(width 0.635)
			(type default)
		)
		(layer "In7.Cu")
	)
	(gr_line
		(start 230.345488 -400.70024)
		(end 230.14432 -400.901408)
		(stroke
			(width 0.635)
			(type default)
		)
		(layer "In7.Cu")
	)
	(gr_line
		(start 230.69804 -423.4688)
		(end 230.69804 -435.063392)
		(stroke
			(width 0.635)
			(type default)
		)
		(layer "In7.Cu")
	)
	(gr_line
		(start 233.20756 -420.95928)
		(end 230.69804 -423.4688)
		(stroke
			(width 0.635)
			(type default)
		)
		(layer "In7.Cu")
	)
	(gr_line
		(start 233.996992 -400.70024)
		(end 230.345488 -400.70024)
		(stroke
			(width 0.635)
			(type default)
		)
		(layer "In7.Cu")
	)
	(gr_line
		(start 234.19816 -404.477728)
		(end 234.19816 -400.901408)
		(stroke
			(width 0.635)
			(type default)
		)
		(layer "In7.Cu")
	)
	(gr_line
		(start 234.19816 -400.901408)
		(end 233.996992 -400.70024)
		(stroke
			(width 0.635)
			(type default)
		)
		(layer "In7.Cu")
	)
	(gr_line
		(start 235.520992 -405.80056)
		(end 234.19816 -404.477728)
		(stroke
			(width 0.635)
			(type default)
		)
		(layer "In7.Cu")
	)
	(gr_line
		(start 237.746032 -405.80056)
		(end 235.520992 -405.80056)
		(stroke
			(width 0.635)
			(type default)
		)
		(layer "In7.Cu")
	)
	(gr_line
		(start 239.10036 -406.737312)
		(end 238.682784 -406.737312)
		(stroke
			(width 0.635)
			(type default)
		)
		(layer "In7.Cu")
	)
	(gr_line
		(start 239.3315 -406.506172)
		(end 239.10036 -406.737312)
		(stroke
			(width 0.635)
			(type default)
		)
		(layer "In7.Cu")
	)
	(gr_arc
		(start 239.3315 -406.506172)
		(mid 239.359619 -406.647264)
		(end 239.439704 -406.766776)
		(stroke
			(width 0.635)
			(type default)
		)
		(layer "In7.Cu")
	)
	(gr_line
		(start 239.3315 -397.839946)
		(end 239.3315 -406.506172)
		(stroke
			(width 0.635)
			(type default)
		)
		(layer "In7.Cu")
	)
	(gr_line
		(start 239.387634 -397.701516)
		(end 239.3315 -397.839946)
		(stroke
			(width 0.635)
			(type default)
		)
		(layer "In7.Cu")
	)
	(gr_line
		(start 239.439704 -406.766776)
		(end 239.663224 -406.990296)
		(stroke
			(width 0.635)
			(type default)
		)
		(layer "In7.Cu")
	)
	(gr_line
		(start 239.441482 -397.649446)
		(end 239.387634 -397.701516)
		(stroke
			(width 0.635)
			(type default)
		)
		(layer "In7.Cu")
	)
	(gr_arc
		(start 239.663224 -406.990296)
		(mid 239.782747 -407.070378)
		(end 239.923828 -407.0985)
		(stroke
			(width 0.635)
			(type default)
		)
		(layer "In7.Cu")
	)
	(gr_line
		(start 239.699292 -407.75382)
		(end 237.746032 -405.80056)
		(stroke
			(width 0.635)
			(type default)
		)
		(layer "In7.Cu")
	)
	(gr_line
		(start 239.699292 -407.75382)
		(end 240.057432 -407.39568)
		(stroke
			(width 0.635)
			(type default)
		)
		(layer "In7.Cu")
	)
	(gr_line
		(start 239.917224 -397.173704)
		(end 239.441482 -397.649446)
		(stroke
			(width 0.635)
			(type default)
		)
		(layer "In7.Cu")
	)
	(gr_line
		(start 239.923828 -407.0985)
		(end 273.791172 -407.0985)
		(stroke
			(width 0.635)
			(type default)
		)
		(layer "In7.Cu")
	)
	(gr_line
		(start 240.057432 -407.39568)
		(end 273.646392 -407.39568)
		(stroke
			(width 0.635)
			(type default)
		)
		(layer "In7.Cu")
	)
	(gr_arc
		(start 240.177828 -397.0655)
		(mid 240.036774 -397.093687)
		(end 239.917224 -397.173704)
		(stroke
			(width 0.635)
			(type default)
		)
		(layer "In7.Cu")
	)
	(gr_line
		(start 270.481552 -420.95928)
		(end 233.20756 -420.95928)
		(stroke
			(width 0.635)
			(type default)
		)
		(layer "In7.Cu")
	)
	(gr_line
		(start 273.646392 -407.39568)
		(end 274.051776 -406.990296)
		(stroke
			(width 0.635)
			(type default)
		)
		(layer "In7.Cu")
	)
	(gr_arc
		(start 273.791172 -407.0985)
		(mid 273.932264 -407.070381)
		(end 274.051776 -406.990296)
		(stroke
			(width 0.635)
			(type default)
		)
		(layer "In7.Cu")
	)
	(gr_line
		(start 274.051776 -407.33472)
		(end 274.470876 -407.75382)
		(stroke
			(width 0.635)
			(type default)
		)
		(layer "In7.Cu")
	)
	(gr_line
		(start 274.051776 -406.990296)
		(end 274.051776 -407.33472)
		(stroke
			(width 0.635)
			(type default)
		)
		(layer "In7.Cu")
	)
	(gr_line
		(start 274.051776 -406.990296)
		(end 274.529296 -406.512776)
		(stroke
			(width 0.635)
			(type default)
		)
		(layer "In7.Cu")
	)
	(gr_line
		(start 274.117054 -397.0655)
		(end 240.177828 -397.0655)
		(stroke
			(width 0.635)
			(type default)
		)
		(layer "In7.Cu")
	)
	(gr_line
		(start 274.255484 -397.121634)
		(end 274.117054 -397.0655)
		(stroke
			(width 0.635)
			(type default)
		)
		(layer "In7.Cu")
	)
	(gr_line
		(start 274.307554 -397.175482)
		(end 274.255484 -397.121634)
		(stroke
			(width 0.635)
			(type default)
		)
		(layer "In7.Cu")
	)
	(gr_arc
		(start 274.529296 -406.512776)
		(mid 274.609378 -406.393253)
		(end 274.6375 -406.252172)
		(stroke
			(width 0.635)
			(type default)
		)
		(layer "In7.Cu")
	)
	(gr_line
		(start 274.529296 -397.397224)
		(end 274.307554 -397.175482)
		(stroke
			(width 0.635)
			(type default)
		)
		(layer "In7.Cu")
	)
	(gr_line
		(start 274.6375 -406.252172)
		(end 274.6375 -397.657828)
		(stroke
			(width 0.635)
			(type default)
		)
		(layer "In7.Cu")
	)
	(gr_arc
		(start 274.6375 -397.657828)
		(mid 274.609313 -397.516774)
		(end 274.529296 -397.397224)
		(stroke
			(width 0.635)
			(type default)
		)
		(layer "In7.Cu")
	)
	(gr_line
		(start 275.0693 -405.960072)
		(end 275.351748 -406.24252)
		(stroke
			(width 0.635)
			(type default)
		)
		(layer "In7.Cu")
	)
	(gr_line
		(start 275.0693 -397.505428)
		(end 275.0693 -405.960072)
		(stroke
			(width 0.635)
			(type default)
		)
		(layer "In7.Cu")
	)
	(gr_line
		(start 275.351748 -406.24252)
		(end 278.143208 -406.24252)
		(stroke
			(width 0.635)
			(type default)
		)
		(layer "In7.Cu")
	)
	(gr_line
		(start 275.509228 -397.0655)
		(end 275.0693 -397.505428)
		(stroke
			(width 0.635)
			(type default)
		)
		(layer "In7.Cu")
	)
	(gr_line
		(start 275.680932 -415.7599)
		(end 270.481552 -420.95928)
		(stroke
			(width 0.635)
			(type default)
		)
		(layer "In7.Cu")
	)
	(gr_line
		(start 278.143208 -406.24252)
		(end 278.145748 -406.23998)
		(stroke
			(width 0.635)
			(type default)
		)
		(layer "In7.Cu")
	)
	(gr_line
		(start 278.145748 -406.23998)
		(end 281.037792 -406.23998)
		(stroke
			(width 0.635)
			(type default)
		)
		(layer "In7.Cu")
	)
	(gr_line
		(start 279.927812 -415.7599)
		(end 275.680932 -415.7599)
		(stroke
			(width 0.635)
			(type default)
		)
		(layer "In7.Cu")
	)
	(gr_line
		(start 279.927812 -415.7599)
		(end 280.51506 -415.172652)
		(stroke
			(width 0.635)
			(type default)
		)
		(layer "In7.Cu")
	)
	(gr_line
		(start 280.100532 -407.75382)
		(end 239.699292 -407.75382)
		(stroke
			(width 0.635)
			(type default)
		)
		(layer "In7.Cu")
	)
	(gr_line
		(start 280.51506 -415.172652)
		(end 280.51506 -408.168348)
		(stroke
			(width 0.635)
			(type default)
		)
		(layer "In7.Cu")
	)
	(gr_line
		(start 280.51506 -408.168348)
		(end 280.100532 -407.75382)
		(stroke
			(width 0.635)
			(type default)
		)
		(layer "In7.Cu")
	)
	(gr_line
		(start 280.83764 -397.0655)
		(end 275.509228 -397.0655)
		(stroke
			(width 0.635)
			(type default)
		)
		(layer "In7.Cu")
	)
	(gr_line
		(start 281.037792 -406.23998)
		(end 281.369008 -405.908764)
		(stroke
			(width 0.635)
			(type default)
		)
		(layer "In7.Cu")
	)
	(gr_line
		(start 281.369008 -405.908764)
		(end 281.369008 -397.596868)
		(stroke
			(width 0.635)
			(type default)
		)
		(layer "In7.Cu")
	)
	(gr_line
		(start 281.369008 -397.596868)
		(end 280.83764 -397.0655)
		(stroke
			(width 0.635)
			(type default)
		)
		(layer "In7.Cu")
	)
	(gr_arc
		(start 0 -77.671676)
		(mid 0.152221 -78.436944)
		(end 0.585724 -79.085694)
		(stroke
			(width 3.048)
			(type default)
		)
		(layer "In8.Cu")
	)
	(gr_line
		(start 0 -13.780008)
		(end 0 -77.671676)
		(stroke
			(width 3.048)
			(type default)
		)
		(layer "In8.Cu")
	)
	(gr_poly
		(pts
			(arc
				(start 278.10841 -405.924766)
				(mid 278.127045 -405.923069)
				(end 278.145748 -405.92248)
			)
			(xy 280.90622 -405.92248) (xy 281.051508 -405.777192) (xy 281.051508 -397.72844) (xy 280.706068 -397.383)
			(xy 275.6408 -397.383) (xy 275.3868 -397.637) (xy 275.3868 -405.8285) (xy 275.48332 -405.92502) (xy 278.105616 -405.92502)
		)
		(stroke
			(width 0)
			(type solid)
		)
		(fill yes)
		(layer "In8.Cu")
		(net "P12V_MAIN_R_0")
	)
	(gr_poly
		(pts
			(arc
				(start 273.791172 -406.781)
				(mid 273.810393 -406.777119)
				(end 273.826732 -406.766268)
			)
			(xy 274.30476 -406.28824) (xy 274.32 -406.274016) (xy 274.32 -397.635984) (xy 274.30476 -397.62176)
			(xy 274.083018 -397.400018) (xy 274.067016 -397.383) (xy 240.155984 -397.383) (xy 240.14176 -397.39824)
			(xy 239.666018 -397.873982) (xy 239.665764 -397.874236) (xy 239.649 -397.889984) (xy 239.649 -406.528016)
			(xy 239.66424 -406.54224) (xy 239.88776 -406.76576) (xy 239.901984 -406.781)
		)
		(stroke
			(width 0)
			(type solid)
		)
		(fill yes)
		(layer "In8.Cu")
		(net "P12V_MAIN_R")
	)
	(gr_poly
		(pts
			(arc
				(start 256.998724 -319.05575)
				(mid 257.087919 -319.012511)
				(end 257.185922 -318.997584)
			)
			(arc
				(start 257.185922 -318.997584)
				(mid 257.283945 -319.012445)
				(end 257.37312 -319.05575)
			)
			(xy 272.12417 -319.05575)
			(arc
				(start 272.135092 -319.050162)
				(mid 272.285714 -319.013839)
				(end 272.436336 -319.050162)
			)
			(xy 272.447258 -319.05575)
			(arc
				(start 279.576022 -319.05575)
				(mid 279.794716 -318.9732)
				(end 280.01341 -319.05575)
			)
			(xy 284.231842 -319.05575) (xy 284.3276 -318.959992)
			(arc
				(start 284.3276 -218.785948)
				(mid 284.34695 -218.688761)
				(end 284.402022 -218.60637)
			)
			(arc
				(start 285.002732 -218.00566)
				(mid 285.085109 -217.950554)
				(end 285.18231 -217.931238)
			)
			(xy 317.515494 -217.931238) (xy 318.06388 -217.382852) (xy 318.06388 -194.823588) (xy 317.627762 -194.38747)
			(xy 254.680974 -194.38747) (xy 254.052578 -195.015866) (xy 254.052578 -318.788542) (xy 254.072898 -318.80683)
			(arc
				(start 254.275844 -319.009776)
				(mid 254.390698 -318.933818)
				(end 254.52578 -318.90716)
			)
			(arc
				(start 254.52578 -318.90716)
				(mid 254.688389 -318.946485)
				(end 254.815086 -319.05575)
			)
		)
		(stroke
			(width 0)
			(type solid)
		)
		(fill yes)
		(layer "In8.Cu")
		(net "GND")
	)
	(gr_poly
		(pts
			(arc
				(start 183.53405 -319.555114)
				(mid 183.8198 -319.388535)
				(end 184.10555 -319.555114)
			)
			(arc
				(start 187.5663 -319.555114)
				(mid 187.883546 -319.360511)
				(end 188.200792 -319.555114)
			)
			(arc
				(start 195.1101 -319.555114)
				(mid 195.427346 -319.360511)
				(end 195.744592 -319.555114)
			)
			(xy 198.872094 -319.555114)
			(arc
				(start 198.875142 -319.55486)
				(mid 198.895043 -319.55299)
				(end 198.91502 -319.55232)
			)
			(arc
				(start 198.91502 -319.55232)
				(mid 198.934998 -319.552975)
				(end 198.954898 -319.55486)
			)
			(xy 198.957946 -319.555114)
			(arc
				(start 202.6539 -319.555114)
				(mid 202.971146 -319.360511)
				(end 203.288392 -319.555114)
			)
			(arc
				(start 206.07401 -319.555114)
				(mid 206.35976 -319.388535)
				(end 206.64551 -319.555114)
			)
			(arc
				(start 210.1977 -319.555114)
				(mid 210.514946 -319.360511)
				(end 210.832192 -319.555114)
			)
			(arc
				(start 214.329264 -319.555114)
				(mid 214.615014 -319.388535)
				(end 214.900764 -319.555114)
			)
			(xy 217.212418 -319.555114) (xy 217.21445 -319.553082)
			(arc
				(start 217.49258 -319.274952)
				(mid 217.515215 -319.254866)
				(end 217.540078 -319.237614)
			)
			(xy 217.540078 -194.530726) (xy 216.210642 -193.20129)
			(arc
				(start 170.460416 -193.20129)
				(mid 170.123612 -193.403534)
				(end 169.786808 -193.20129)
			)
			(arc
				(start 153.360628 -193.20129)
				(mid 153.281041 -193.239736)
				(end 153.261568 -193.326004)
			)
			(arc
				(start 153.261568 -193.326004)
				(mid 153.268596 -193.366247)
				(end 153.270966 -193.40703)
			)
			(arc
				(start 153.270966 -193.40703)
				(mid 153.187269 -193.636296)
				(end 152.975564 -193.757804)
			)
			(xy 152.9334 -193.76517) (xy 152.9334 -194.423792)
			(arc
				(start 154.577796 -196.068188)
				(mid 154.632902 -196.150565)
				(end 154.652218 -196.247766)
			)
			(xy 154.652218 -214.137494) (xy 155.054554 -214.53983)
			(arc
				(start 180.581808 -214.53983)
				(mid 180.678995 -214.55918)
				(end 180.761386 -214.614252)
			)
			(arc
				(start 181.35092 -215.203786)
				(mid 181.406026 -215.286163)
				(end 181.425342 -215.383364)
			)
			(xy 181.425342 -319.240662) (xy 181.441598 -319.255648) (xy 181.741064 -319.555114)
		)
		(stroke
			(width 0)
			(type solid)
		)
		(fill yes)
		(layer "In8.Cu")
		(net "GND")
	)
	(gr_poly
		(pts
			(arc
				(start 121.60377 -350.005142)
				(mid 121.686147 -349.950036)
				(end 121.783348 -349.93072)
			)
			(xy 139.60094 -349.93072) (xy 142.946374 -346.585286) (xy 142.946374 -343.084912) (xy 142.792196 -342.930734)
			(xy 138.234674 -342.930734) (xy 138.131804 -343.03335) (xy 138.131804 -345.364562) (xy 138.701272 -345.933522)
			(xy 138.701272 -348.339156) (xy 138.351514 -348.68866) (xy 134.272274 -348.68866) (xy 133.699504 -348.11589)
			(xy 133.699504 -339.350858) (xy 133.69925 -339.35035) (xy 133.69925 -339.339428) (xy 133.69925 -339.328506)
			(xy 133.699504 -339.327998) (xy 133.699504 -337.535774) (xy 133.499098 -337.335368) (xy 129.971292 -337.335368)
			(xy 129.971292 -340.01329) (xy 130.699764 -340.741508) (xy 130.699764 -342.499188) (xy 130.329686 -342.869012)
			(arc
				(start 130.326384 -342.882982)
				(mid 130.191372 -343.124398)
				(end 129.949956 -343.25941)
			)
			(xy 129.935986 -343.262712) (xy 129.85623 -343.342468) (xy 126.24435 -343.342468) (xy 125.424184 -342.522556)
			(xy 125.424184 -334.012032) (xy 125.34011 -333.927704) (xy 121.837704 -333.927704) (xy 121.800112 -333.96555)
			(xy 121.800112 -335.994756) (xy 122.508264 -336.702908) (xy 122.508264 -339.336888) (xy 121.912634 -339.932772)
			(xy 118.247668 -339.932772) (xy 117.248432 -338.933282) (xy 117.248432 -334.00365) (xy 117.173502 -333.92872)
			(xy 113.694718 -333.92872) (xy 113.657888 -333.96555) (xy 113.657888 -335.956402) (xy 114.303048 -336.601054)
			(xy 114.303048 -339.241384) (xy 113.963958 -339.58022)
			(arc
				(start 113.96091 -339.585554)
				(mid 113.883362 -339.685298)
				(end 113.783618 -339.762846)
			)
			(xy 113.778284 -339.765894) (xy 113.77295 -339.771228) (xy 113.768886 -339.771228)
			(arc
				(start 113.757964 -339.77707)
				(mid 113.644305 -339.819717)
				(end 113.523776 -339.83422)
			)
			(arc
				(start 113.523776 -339.83422)
				(mid 113.397367 -339.818193)
				(end 113.27892 -339.771228)
			)
			(arc
				(start 110.72876 -339.771228)
				(mid 110.611104 -339.81745)
				(end 110.485682 -339.833204)
			)
			(arc
				(start 110.485682 -339.833204)
				(mid 110.366124 -339.819011)
				(end 110.253272 -339.77707)
			)
			(xy 110.24235 -339.771228) (xy 110.007146 -339.771228) (xy 108.878116 -338.642198) (xy 108.878116 -337.528408)
			(xy 109.130592 -337.275932) (xy 109.130592 -334.03794) (xy 109.020864 -333.928212) (xy 105.537254 -333.928212)
			(xy 105.47604 -333.989172) (xy 105.47604 -335.978246) (xy 106.281728 -336.78368) (xy 106.281728 -339.288882)
			(xy 106.169714 -339.40115)
			(arc
				(start 106.165904 -339.41131)
				(mid 106.048757 -339.593883)
				(end 105.866184 -339.71103)
			)
			(xy 105.856024 -339.71484) (xy 105.77576 -339.795104) (xy 102.611174 -339.795104)
			(arc
				(start 102.601522 -339.799422)
				(mid 102.500563 -339.832106)
				(end 102.39502 -339.84311)
			)
			(arc
				(start 102.39502 -339.84311)
				(mid 102.28948 -339.832091)
				(end 102.188518 -339.799422)
			)
			(xy 102.178866 -339.795104) (xy 101.870764 -339.795104) (xy 100.865432 -338.789772) (xy 100.865432 -333.983838)
			(xy 100.811584 -333.929736) (xy 97.369376 -333.929736) (xy 97.317052 -333.982314) (xy 97.317052 -335.940908)
			(xy 98.242628 -336.866484) (xy 98.242628 -339.002116) (xy 97.482406 -339.762592)
			(arc
				(start 94.438978 -339.762592)
				(mid 94.324046 -339.80625)
				(end 94.201996 -339.821012)
			)
			(arc
				(start 94.201996 -339.821012)
				(mid 94.079955 -339.806213)
				(end 93.965014 -339.762592)
			)
			(xy 93.118686 -339.762592) (xy 92.792804 -339.436456) (xy 92.792804 -337.40217) (xy 92.749116 -337.358736)
			(xy 89.179908 -337.358736) (xy 89.178892 -337.359498) (xy 89.178892 -339.601556) (xy 89.84234 -340.26475)
			(xy 89.84234 -342.433656) (xy 89.516966 -342.75903)
			(arc
				(start 89.513664 -342.773)
				(mid 89.378941 -343.013181)
				(end 89.13876 -343.147904)
			)
			(xy 89.12479 -343.151206) (xy 88.648794 -343.627456) (xy 85.091016 -343.627456) (xy 84.615782 -343.151968)
			(xy 81.064354 -343.151968) (xy 80.968596 -343.247726) (xy 80.968596 -345.179904) (xy 83.13674 -347.348048)
			(xy 83.13674 -348.797118) (xy 83.342734 -349.002858)
			(arc
				(start 85.83295 -349.002858)
				(mid 85.930137 -349.022208)
				(end 86.012528 -349.07728)
			)
			(xy 88.356948 -351.4217) (xy 95.743014 -351.4217) (xy 96.179894 -350.98482)
			(arc
				(start 96.175322 -350.958912)
				(mid 96.171492 -350.928794)
				(end 96.170242 -350.89846)
			)
			(arc
				(start 96.170242 -350.89846)
				(mid 96.274544 -350.646654)
				(end 96.52635 -350.542352)
			)
			(arc
				(start 96.52635 -350.542352)
				(mid 96.556684 -350.543603)
				(end 96.586802 -350.547432)
			)
			(xy 96.61271 -350.552004)
			(arc
				(start 97.54235 -349.622364)
				(mid 97.624727 -349.567258)
				(end 97.721928 -349.547942)
			)
			(arc
				(start 113.672874 -349.547942)
				(mid 113.770061 -349.567292)
				(end 113.852452 -349.622364)
			)
			(xy 115.860576 -351.630488) (xy 119.978424 -351.630488)
		)
		(stroke
			(width 0)
			(type solid)
		)
		(fill yes)
		(layer "In8.Cu")
		(net "SW_P12V_PVCCIN_CPU1_FLT")
	)
	(gr_poly
		(pts
			(arc
				(start 369.54587 -349.997522)
				(mid 369.628247 -349.942416)
				(end 369.725448 -349.9231)
			)
			(xy 387.54812 -349.9231) (xy 390.501124 -346.970096)
			(arc
				(start 390.488932 -346.939108)
				(mid 390.469342 -346.870863)
				(end 390.46277 -346.80017)
			)
			(arc
				(start 390.46277 -346.80017)
				(mid 390.571742 -346.533201)
				(end 390.836404 -346.418662)
			)
			(arc
				(start 390.836404 -346.418662)
				(mid 390.871674 -346.403429)
				(end 390.886188 -346.367862)
			)
			(xy 390.886188 -343.084658) (xy 390.73201 -342.93048) (xy 386.174488 -342.93048) (xy 386.071872 -343.033096)
			(xy 386.071872 -345.364308) (xy 386.640832 -345.933268) (xy 386.640832 -348.338902) (xy 386.291328 -348.68866)
			(xy 382.212088 -348.68866) (xy 381.639064 -348.115636) (xy 381.639064 -339.35035) (xy 381.639064 -339.339428)
			(xy 381.639064 -337.53552) (xy 381.438912 -337.335368) (xy 377.910852 -337.335368) (xy 377.910852 -340.013036)
			(xy 378.639324 -340.741254) (xy 378.639324 -342.498934) (xy 378.284232 -342.854026)
			(arc
				(start 378.280676 -342.86571)
				(mid 378.155654 -343.071142)
				(end 377.950222 -343.196164)
			)
			(xy 377.938538 -343.19972) (xy 377.796044 -343.342468) (xy 374.184164 -343.342468) (xy 373.364252 -342.522302)
			(xy 373.364252 -334.011778) (xy 373.279924 -333.927704) (xy 369.777518 -333.927704) (xy 369.739672 -333.965296)
			(xy 369.739672 -335.994502) (xy 370.448332 -336.702654) (xy 370.448332 -339.336634) (xy 369.852448 -339.932264)
			(xy 366.187482 -339.932264) (xy 365.187992 -338.933028) (xy 365.187992 -334.003396) (xy 365.113316 -333.92872)
			(xy 361.634532 -333.92872) (xy 361.597956 -333.965296) (xy 361.597956 -335.956148) (xy 362.242608 -336.6008)
			(xy 362.242608 -339.24113) (xy 362.077254 -339.406738)
			(arc
				(start 362.073444 -339.415374)
				(mid 361.968277 -339.568525)
				(end 361.815126 -339.673692)
			)
			(xy 361.80649 -339.677502) (xy 361.712764 -339.771228)
			(arc
				(start 358.669082 -339.771228)
				(mid 358.55118 -339.817513)
				(end 358.425496 -339.833204)
			)
			(arc
				(start 358.425496 -339.833204)
				(mid 358.305662 -339.818944)
				(end 358.192578 -339.776816)
			)
			(xy 358.181656 -339.771228) (xy 357.94696 -339.771228) (xy 356.817676 -338.641944) (xy 356.817676 -337.528154)
			(xy 357.07066 -337.275678) (xy 357.07066 -334.037686) (xy 356.960678 -333.927704) (xy 353.477068 -333.927704)
			(xy 353.416108 -333.988918) (xy 353.416108 -335.977992) (xy 354.221796 -336.783426) (xy 354.221796 -339.288628)
			(xy 354.056188 -339.453982)
			(arc
				(start 354.052378 -339.462618)
				(mid 353.94683 -339.616658)
				(end 353.79279 -339.722206)
			)
			(xy 353.784154 -339.726016) (xy 353.715574 -339.794596) (xy 350.551496 -339.794596)
			(arc
				(start 350.541844 -339.799168)
				(mid 350.44065 -339.832022)
				(end 350.334834 -339.84311)
			)
			(arc
				(start 350.334834 -339.84311)
				(mid 350.229016 -339.832032)
				(end 350.127824 -339.799168)
			)
			(xy 350.118172 -339.794596) (xy 349.810578 -339.794596) (xy 348.8055 -338.789518) (xy 348.8055 -333.983584)
			(xy 348.751398 -333.929736) (xy 345.30919 -333.929736) (xy 345.256612 -333.98206) (xy 345.256612 -335.940654)
			(xy 346.182696 -336.86623) (xy 346.182696 -339.001862) (xy 345.42222 -339.762084)
			(arc
				(start 342.3793 -339.762084)
				(mid 342.264149 -339.806019)
				(end 342.14181 -339.821012)
			)
			(arc
				(start 342.14181 -339.821012)
				(mid 342.019457 -339.806073)
				(end 341.90432 -339.762084)
			)
			(xy 340.9315 -339.762084) (xy 340.605364 -339.436202) (xy 340.605364 -337.401916) (xy 340.56193 -337.358228)
			(xy 337.119722 -337.358228) (xy 337.11896 -337.359244) (xy 337.11896 -339.601302) (xy 337.782408 -340.264496)
			(xy 337.782408 -342.433402) (xy 337.613244 -342.602566) (xy 337.615022 -342.62568)
			(arc
				(start 337.616292 -342.663272)
				(mid 337.467353 -343.022841)
				(end 337.107784 -343.17178)
			)
			(xy 337.070192 -343.17051) (xy 337.047078 -343.168732) (xy 336.588608 -343.626948) (xy 333.03083 -343.626948)
			(xy 332.555596 -343.15146) (xy 329.004168 -343.15146) (xy 328.908156 -343.247472) (xy 328.908156 -343.512902)
			(xy 328.90841 -343.514172) (xy 328.909172 -343.542874) (xy 328.90841 -343.571576) (xy 328.908156 -343.572846)
			(xy 328.908156 -344.935302) (xy 328.90841 -344.936572) (xy 328.909172 -344.965274) (xy 328.90841 -344.993976)
			(xy 328.908156 -344.995246) (xy 328.908156 -345.17965) (xy 331.076808 -347.347794) (xy 331.076808 -348.796864)
			(xy 331.282548 -349.002604)
			(arc
				(start 333.772764 -349.002604)
				(mid 333.869951 -349.021954)
				(end 333.952342 -349.077026)
			)
			(xy 336.296762 -351.421446) (xy 343.682828 -351.421446)
			(arc
				(start 345.482164 -349.62211)
				(mid 345.564541 -349.567004)
				(end 345.661742 -349.547688)
			)
			(arc
				(start 361.442 -349.547688)
				(mid 361.539187 -349.567038)
				(end 361.621578 -349.62211)
			)
			(xy 363.695996 -351.696528) (xy 367.846864 -351.696528)
		)
		(stroke
			(width 0)
			(type solid)
		)
		(fill yes)
		(layer "In8.Cu")
		(net "SW_P12V_PVCCIN_CPU0_FLT")
	)
	(gr_poly
		(pts
			(xy 230.38054 -434.93182)
			(arc
				(start 230.38054 -423.4688)
				(mid 230.404693 -423.347284)
				(end 230.473504 -423.244264)
			)
			(arc
				(start 232.983024 -420.734744)
				(mid 233.086056 -420.665963)
				(end 233.20756 -420.64178)
			)
			(xy 270.34998 -420.64178)
			(arc
				(start 275.456396 -415.535364)
				(mid 275.559428 -415.466583)
				(end 275.680932 -415.4424)
			)
			(xy 279.79624 -415.4424) (xy 280.19756 -415.04108) (xy 280.19756 -408.29992) (xy 279.96896 -408.07132)
			(arc
				(start 239.699292 -408.07132)
				(mid 239.577776 -408.047167)
				(end 239.474756 -407.978356)
			)
			(xy 237.61446 -406.11806)
			(arc
				(start 235.520992 -406.11806)
				(mid 235.399476 -406.093907)
				(end 235.296456 -406.025096)
			)
			(arc
				(start 233.973624 -404.702264)
				(mid 233.904843 -404.599232)
				(end 233.88066 -404.477728)
			)
			(xy 233.88066 -401.03298) (xy 233.86542 -401.01774) (xy 230.47706 -401.01774) (xy 230.46182 -401.03298)
			(arc
				(start 230.46182 -404.473156)
				(mid 230.437667 -404.594672)
				(end 230.368856 -404.697692)
			)
			(xy 230.256588 -404.80996)
			(arc
				(start 230.256588 -407.3906)
				(mid 230.232435 -407.512116)
				(end 230.163624 -407.615136)
			)
			(arc
				(start 228.159564 -409.619196)
				(mid 228.056532 -409.687977)
				(end 227.935028 -409.71216)
			)
			(arc
				(start 225.70694 -409.71216)
				(mid 225.585424 -409.688007)
				(end 225.482404 -409.619196)
			)
			(arc
				(start 223.491552 -407.628344)
				(mid 223.422771 -407.525312)
				(end 223.398588 -407.403808)
			)
			(xy 223.398588 -404.79218)
			(arc
				(start 223.310704 -404.704296)
				(mid 223.241923 -404.601264)
				(end 223.21774 -404.47976)
			)
			(xy 223.21774 -401.04568) (xy 223.19234 -401.02028) (xy 219.81414 -401.02028) (xy 219.79636 -401.03806)
			(arc
				(start 219.79636 -404.490936)
				(mid 219.772207 -404.612452)
				(end 219.703396 -404.715472)
			)
			(xy 219.613988 -404.80488)
			(arc
				(start 219.613988 -407.259028)
				(mid 219.589835 -407.380544)
				(end 219.521024 -407.483564)
			)
			(arc
				(start 217.497152 -409.507436)
				(mid 217.39412 -409.576217)
				(end 217.272616 -409.6004)
			)
			(arc
				(start 214.794592 -409.6004)
				(mid 214.673076 -409.576247)
				(end 214.570056 -409.507436)
			)
			(arc
				(start 212.812884 -407.750264)
				(mid 212.744103 -407.647232)
				(end 212.71992 -407.525728)
			)
			(xy 212.71992 -404.79472)
			(arc
				(start 212.635084 -404.709884)
				(mid 212.566303 -404.606852)
				(end 212.54212 -404.485348)
			)
			(xy 212.54212 -401.02536) (xy 212.53704 -401.02028) (xy 209.14106 -401.02028) (xy 209.13598 -401.02536)
			(arc
				(start 209.13598 -404.452836)
				(mid 209.111827 -404.574352)
				(end 209.043016 -404.677372)
			)
			(xy 208.945988 -404.7744)
			(arc
				(start 208.945988 -407.30424)
				(mid 208.921835 -407.425756)
				(end 208.853024 -407.528776)
			)
			(arc
				(start 206.770224 -409.611576)
				(mid 206.667192 -409.680357)
				(end 206.545688 -409.70454)
			)
			(arc
				(start 204.16012 -409.70454)
				(mid 204.038604 -409.680387)
				(end 203.935584 -409.611576)
			)
			(arc
				(start 202.155552 -407.831544)
				(mid 202.086771 -407.728512)
				(end 202.062588 -407.607008)
			)
			(xy 202.062588 -404.779988)
			(arc
				(start 201.969624 -404.687024)
				(mid 201.900843 -404.583992)
				(end 201.87666 -404.462488)
			)
			(xy 201.87666 -401.03298) (xy 201.86396 -401.02028) (xy 198.47306 -401.02028) (xy 198.46798 -401.02536)
			(arc
				(start 198.46798 -404.487888)
				(mid 198.443827 -404.609404)
				(end 198.375016 -404.712424)
			)
			(arc
				(start 197.194424 -405.893016)
				(mid 197.091392 -405.961797)
				(end 196.969888 -405.98598)
			)
			(arc
				(start 190.870332 -405.98598)
				(mid 190.748816 -405.961827)
				(end 190.645796 -405.893016)
			)
			(arc
				(start 189.455552 -404.702518)
				(mid 189.386771 -404.599486)
				(end 189.362588 -404.477982)
			)
			(xy 189.362588 -404.177754) (xy 189.337188 -404.152354)
			(arc
				(start 189.11316 -404.152354)
				(mid 188.991644 -404.128201)
				(end 188.888624 -404.05939)
			)
			(arc
				(start 188.710824 -403.88159)
				(mid 188.642043 -403.778558)
				(end 188.61786 -403.657054)
			)
			(xy 188.61786 -401.02028) (xy 188.600588 -401.002754) (xy 185.196988 -401.002754) (xy 185.196988 -406.489154)
			(arc
				(start 185.434224 -406.72639)
				(mid 185.480227 -406.78458)
				(end 185.51144 -406.851866)
			)
			(arc
				(start 185.51144 -406.851866)
				(mid 185.548193 -406.942536)
				(end 185.560716 -407.039572)
			)
			(arc
				(start 185.560716 -407.039572)
				(mid 185.553298 -407.114694)
				(end 185.531252 -407.186892)
			)
			(xy 185.527188 -407.19629)
			(arc
				(start 185.527188 -408.287982)
				(mid 185.503035 -408.409498)
				(end 185.434224 -408.512518)
			)
			(xy 185.323988 -408.622754) (xy 185.323988 -413.048196) (xy 192.854072 -420.57828)
			(arc
				(start 197.383908 -420.57828)
				(mid 197.505424 -420.602433)
				(end 197.608444 -420.671244)
			)
			(arc
				(start 206.398876 -429.461676)
				(mid 206.467657 -429.564708)
				(end 206.49184 -429.686212)
			)
			(xy 206.49184 -435.39156) (xy 207.63484 -436.53456) (xy 228.7778 -436.53456)
		)
		(stroke
			(width 0)
			(type solid)
		)
		(fill yes)
		(layer "In8.Cu")
		(net "P12V_PSU")
	)
	(gr_poly
		(pts
			(xy 13.1318 -318.266826) (xy 13.148732 -318.245178) (xy 13.188136 -318.206868) (xy 13.232958 -318.175068)
			(xy 13.282134 -318.150532) (xy 13.334497 -318.133844) (xy 13.388801 -318.1254) (xy 13.443759 -318.1254)
			(xy 13.498063 -318.133844) (xy 13.550426 -318.150532) (xy 13.599602 -318.175068) (xy 13.644424 -318.206868)
			(xy 13.683828 -318.245178) (xy 13.70076 -318.266826) (xy 21.256244 -318.266826) (xy 21.266658 -318.261746)
			(xy 21.290828 -318.250656) (xy 21.341657 -318.235027) (xy 21.394247 -318.227149) (xy 21.420836 -318.226694)
			(xy 21.44742 -318.227193) (xy 21.499999 -318.235096) (xy 21.550824 -318.250708) (xy 21.575014 -318.261746)
			(xy 21.585428 -318.266826) (xy 30.647386 -318.266826) (xy 31.232602 -317.68161) (xy 31.235142 -317.67907)
			(xy 31.235142 -219.006166) (xy 31.235717 -218.981207) (xy 31.245463 -218.93225) (xy 31.264573 -218.886135)
			(xy 31.292314 -218.844635) (xy 31.309564 -218.826588) (xy 31.548578 -218.587574) (xy 31.548578 -218.566492)
			(xy 31.549098 -218.540729) (xy 31.557185 -218.489841) (xy 31.573126 -218.440843) (xy 31.59653 -218.394938)
			(xy 31.626822 -218.353256) (xy 31.663256 -218.316822) (xy 31.704938 -218.28653) (xy 31.750843 -218.263126)
			(xy 31.799841 -218.247185) (xy 31.850729 -218.239098) (xy 31.876492 -218.238578) (xy 31.897574 -218.238578)
			(xy 31.991808 -218.144344) (xy 32.009849 -218.127082) (xy 32.051342 -218.099321) (xy 32.097459 -218.080202)
			(xy 32.146424 -218.070463) (xy 32.171386 -218.069922) (xy 60.33389 -218.069922) (xy 60.88634 -217.517472)
			(xy 60.88634 -169.977816) (xy 60.885832 -169.974514) (xy 60.883965 -169.958183) (xy 60.883958 -169.925312)
			(xy 60.885832 -169.908982) (xy 60.88634 -169.90568) (xy 60.88634 -162.320478) (xy 60.88253 -162.31108)
			(xy 60.872572 -162.285308) (xy 60.859842 -162.231546) (xy 60.855568 -162.176463) (xy 60.859853 -162.121381)
			(xy 60.872594 -162.067622) (xy 60.88253 -162.04184) (xy 60.88634 -162.032442) (xy 60.88634 -160.372298)
			(xy 60.88253 -160.3629) (xy 60.87257 -160.337128) (xy 60.859837 -160.283365) (xy 60.85556 -160.228281)
			(xy 60.859843 -160.173198) (xy 60.872582 -160.119437) (xy 60.88253 -160.09366) (xy 60.88634 -160.084262)
			(xy 60.88634 -159.711898) (xy 60.88253 -159.7025) (xy 60.87257 -159.676728) (xy 60.859837 -159.622965)
			(xy 60.85556 -159.567881) (xy 60.859843 -159.512798) (xy 60.872582 -159.459037) (xy 60.88253 -159.43326)
			(xy 60.88634 -159.423862) (xy 60.88634 -153.684478) (xy 60.88253 -153.67508) (xy 60.872572 -153.649308)
			(xy 60.859842 -153.595546) (xy 60.855568 -153.540463) (xy 60.859853 -153.485381) (xy 60.872594 -153.431622)
			(xy 60.88253 -153.40584) (xy 60.88634 -153.396442) (xy 60.88634 -151.736298) (xy 60.88253 -151.7269)
			(xy 60.87257 -151.701128) (xy 60.859837 -151.647365) (xy 60.85556 -151.592281) (xy 60.859843 -151.537198)
			(xy 60.872582 -151.483437) (xy 60.88253 -151.45766) (xy 60.88634 -151.448262) (xy 60.88634 -151.075898)
			(xy 60.88253 -151.0665) (xy 60.87257 -151.040728) (xy 60.859837 -150.986965) (xy 60.85556 -150.931881)
			(xy 60.859843 -150.876798) (xy 60.872582 -150.823037) (xy 60.88253 -150.79726) (xy 60.88634 -150.787862)
			(xy 60.88634 -145.048478) (xy 60.88253 -145.03908) (xy 60.872572 -145.013308) (xy 60.859842 -144.959546)
			(xy 60.855568 -144.904463) (xy 60.859853 -144.849381) (xy 60.872594 -144.795622) (xy 60.88253 -144.76984)
			(xy 60.88634 -144.760442) (xy 60.88634 -139.294616) (xy 60.345574 -138.75385) (xy 49.916334 -138.75385)
			(xy 49.392078 -139.278106) (xy 49.392078 -153.3017) (xy 49.423828 -153.3144) (xy 49.448211 -153.324722)
			(xy 49.493875 -153.351521) (xy 49.535069 -153.384785) (xy 49.570885 -153.42378) (xy 49.600534 -153.467647)
			(xy 49.623362 -153.51542) (xy 49.638867 -153.566046) (xy 49.646708 -153.618409) (xy 49.64671 -153.671356)
			(xy 49.638875 -153.723721) (xy 49.623375 -153.774348) (xy 49.600551 -153.822123) (xy 49.570906 -153.865993)
			(xy 49.535094 -153.904992) (xy 49.493903 -153.938259) (xy 49.448242 -153.965063) (xy 49.423828 -153.975308)
			(xy 49.392078 -153.988008) (xy 49.392078 -157.887162) (xy 49.391461 -157.912116) (xy 49.381712 -157.961063)
			(xy 49.362602 -158.007167) (xy 49.334865 -158.048658) (xy 49.317656 -158.06674) (xy 48.11903 -159.265366)
			(xy 48.100988 -159.282622) (xy 48.059492 -159.310373) (xy 48.013375 -159.32948) (xy 47.964412 -159.339206)
			(xy 47.939452 -159.339788) (xy 17.885156 -159.339788) (xy 15.4559 -161.769044) (xy 15.430139 -161.870778)
			(xy 15.424197 -161.891218) (xy 43.40429 -161.891218) (xy 43.408291 -161.803402) (xy 43.420261 -161.716314)
			(xy 43.4401 -161.630675) (xy 43.467645 -161.547195) (xy 43.502668 -161.466566) (xy 43.544877 -161.389456)
			(xy 43.593923 -161.316503) (xy 43.6494 -161.248312) (xy 43.710848 -161.185449) (xy 43.777758 -161.128434)
			(xy 43.849575 -161.07774) (xy 43.925705 -161.033787) (xy 44.005516 -160.996938) (xy 44.088347 -160.9675)
			(xy 44.173512 -160.945716) (xy 44.260306 -160.931767) (xy 44.348008 -160.925768) (xy 44.435892 -160.927769)
			(xy 44.52323 -160.937753) (xy 44.609298 -160.955638) (xy 44.693383 -160.981276) (xy 44.774789 -161.014454)
			(xy 44.85284 -161.054897) (xy 44.92689 -161.10227) (xy 44.996326 -161.15618) (xy 45.060572 -161.216181)
			(xy 45.119095 -161.281776) (xy 45.171411 -161.352421) (xy 45.217086 -161.42753) (xy 45.255741 -161.506482)
			(xy 45.287058 -161.588622) (xy 45.310775 -161.673269) (xy 45.326696 -161.759722) (xy 45.33469 -161.847265)
			(xy 45.33519 -161.891218) (xy 45.33469 -161.935171) (xy 45.326696 -162.022714) (xy 45.310775 -162.109167)
			(xy 45.287058 -162.193814) (xy 45.255741 -162.275954) (xy 45.217086 -162.354906) (xy 45.171411 -162.430015)
			(xy 45.119095 -162.50066) (xy 45.060572 -162.566255) (xy 44.996326 -162.626256) (xy 44.92689 -162.680166)
			(xy 44.85284 -162.727539) (xy 44.774789 -162.767982) (xy 44.693383 -162.80116) (xy 44.609298 -162.826798)
			(xy 44.52323 -162.844683) (xy 44.435892 -162.854667) (xy 44.348008 -162.856668) (xy 44.260306 -162.850669)
			(xy 44.173512 -162.83672) (xy 44.088347 -162.814936) (xy 44.005516 -162.785498) (xy 43.925705 -162.748649)
			(xy 43.849575 -162.704696) (xy 43.777758 -162.654002) (xy 43.710848 -162.596987) (xy 43.6494 -162.534124)
			(xy 43.593923 -162.465933) (xy 43.544877 -162.39298) (xy 43.502668 -162.31587) (xy 43.467645 -162.235241)
			(xy 43.4401 -162.151761) (xy 43.420261 -162.066122) (xy 43.408291 -161.979034) (xy 43.40429 -161.891218)
			(xy 15.424197 -161.891218) (xy 15.37155 -162.072322) (xy 15.304985 -162.271375) (xy 15.23055 -162.46762)
			(xy 15.14836 -162.660746) (xy 15.058549 -162.850447) (xy 14.961256 -163.036423) (xy 14.856638 -163.218378)
			(xy 14.744859 -163.396024) (xy 14.626097 -163.56908) (xy 14.50054 -163.737271) (xy 14.368387 -163.900331)
			(xy 14.229849 -164.058) (xy 14.085143 -164.21003) (xy 13.9345 -164.356178) (xy 13.778159 -164.496215)
			(xy 13.616367 -164.629916) (xy 13.44938 -164.757071) (xy 13.277465 -164.877478) (xy 13.189458 -164.934646)
			(xy 13.189458 -169.801794) (xy 43.330122 -169.801794) (xy 43.334123 -169.713978) (xy 43.346093 -169.62689)
			(xy 43.365932 -169.541251) (xy 43.393477 -169.457771) (xy 43.4285 -169.377142) (xy 43.470709 -169.300032)
			(xy 43.519755 -169.227079) (xy 43.575232 -169.158888) (xy 43.63668 -169.096025) (xy 43.70359 -169.03901)
			(xy 43.775407 -168.988316) (xy 43.851537 -168.944363) (xy 43.931348 -168.907514) (xy 44.014179 -168.878076)
			(xy 44.099344 -168.856292) (xy 44.186138 -168.842343) (xy 44.27384 -168.836344) (xy 44.361724 -168.838345)
			(xy 44.449062 -168.848329) (xy 44.53513 -168.866214) (xy 44.619215 -168.891852) (xy 44.700621 -168.92503)
			(xy 44.778672 -168.965473) (xy 44.852722 -169.012846) (xy 44.922158 -169.066756) (xy 44.986404 -169.126757)
			(xy 45.044927 -169.192352) (xy 45.097243 -169.262997) (xy 45.142918 -169.338106) (xy 45.181573 -169.417058)
			(xy 45.21289 -169.499198) (xy 45.236607 -169.583845) (xy 45.252528 -169.670298) (xy 45.260522 -169.757841)
			(xy 45.261022 -169.801794) (xy 45.260522 -169.845747) (xy 45.252528 -169.93329) (xy 45.236607 -170.019743)
			(xy 45.21289 -170.10439) (xy 45.181573 -170.18653) (xy 45.142918 -170.265482) (xy 45.097243 -170.340591)
			(xy 45.044927 -170.411236) (xy 44.986404 -170.476831) (xy 44.922158 -170.536832) (xy 44.852722 -170.590742)
			(xy 44.778672 -170.638115) (xy 44.700621 -170.678558) (xy 44.619215 -170.711736) (xy 44.53513 -170.737374)
			(xy 44.449062 -170.755259) (xy 44.361724 -170.765243) (xy 44.27384 -170.767244) (xy 44.186138 -170.761245)
			(xy 44.099344 -170.747296) (xy 44.014179 -170.725512) (xy 43.931348 -170.696074) (xy 43.851537 -170.659225)
			(xy 43.775407 -170.615272) (xy 43.70359 -170.564578) (xy 43.63668 -170.507563) (xy 43.575232 -170.4447)
			(xy 43.519755 -170.376509) (xy 43.470709 -170.303556) (xy 43.4285 -170.226446) (xy 43.393477 -170.145817)
			(xy 43.365932 -170.062337) (xy 43.346093 -169.976698) (xy 43.334123 -169.88961) (xy 43.330122 -169.801794)
			(xy 13.189458 -169.801794) (xy 13.189458 -175.83404) (xy 23.37714 -175.83404) (xy 23.381229 -175.778158)
			(xy 23.393412 -175.723468) (xy 23.413428 -175.671134) (xy 23.440851 -175.622272) (xy 23.475096 -175.577924)
			(xy 23.515432 -175.539034) (xy 23.561002 -175.506432) (xy 23.610833 -175.480813) (xy 23.663863 -175.462721)
			(xy 23.718961 -175.452544) (xy 23.774955 -175.450498) (xy 23.83065 -175.456626) (xy 23.884859 -175.470798)
			(xy 23.936427 -175.492712) (xy 23.984255 -175.521901) (xy 24.027323 -175.557742) (xy 24.064713 -175.599472)
			(xy 24.095629 -175.646202) (xy 24.119412 -175.696935) (xy 24.135554 -175.750591) (xy 24.143713 -175.806025)
			(xy 24.144224 -175.83404) (xy 24.143713 -175.862055) (xy 24.135554 -175.917489) (xy 24.119412 -175.971145)
			(xy 24.095629 -176.021878) (xy 24.064713 -176.068608) (xy 24.027323 -176.110338) (xy 23.984255 -176.146179)
			(xy 23.936427 -176.175368) (xy 23.884859 -176.197282) (xy 23.83065 -176.211454) (xy 23.774955 -176.217582)
			(xy 23.718961 -176.215536) (xy 23.663863 -176.205359) (xy 23.610833 -176.187267) (xy 23.561002 -176.161648)
			(xy 23.515432 -176.129046) (xy 23.475096 -176.090156) (xy 23.440851 -176.045808) (xy 23.413428 -175.996946)
			(xy 23.393412 -175.944612) (xy 23.381229 -175.889922) (xy 23.37714 -175.83404) (xy 13.189458 -175.83404)
			(xy 13.189458 -176.65065) (xy 13.189076 -176.670705) (xy 13.182766 -176.710316) (xy 13.170309 -176.748444)
			(xy 13.161518 -176.766474) (xy 7.358888 -188.091064) (xy 6.760972 -189.26556) (xy 6.759448 -189.268354)
			(xy 6.615938 -189.541658) (xy 6.615938 -194.36334) (xy 6.617716 -194.369944) (xy 6.623434 -194.392628)
			(xy 6.629553 -194.439009) (xy 6.629908 -194.4624) (xy 6.629535 -194.48579) (xy 6.623416 -194.532168)
			(xy 6.617716 -194.554856) (xy 6.615938 -194.56146) (xy 6.615938 -317.725298) (xy 7.157466 -318.266826)
		)
		(stroke
			(width 0)
			(type solid)
		)
		(fill yes)
		(layer "In8.Cu")
		(net "GND")
	)
	(gr_poly
		(pts
			(xy 193.607436 -440.465972) (xy 193.630444 -440.405446) (xy 193.683164 -440.287163) (xy 193.743337 -440.172493)
			(xy 193.810717 -440.061903) (xy 193.885029 -439.955847) (xy 193.965968 -439.854758) (xy 194.053203 -439.759049)
			(xy 194.146378 -439.669112) (xy 194.245112 -439.585316) (xy 194.349 -439.508002) (xy 194.457617 -439.437487)
			(xy 194.57052 -439.37406) (xy 194.687247 -439.317979) (xy 194.80732 -439.269475) (xy 194.930248 -439.228745)
			(xy 195.055527 -439.195957) (xy 195.182647 -439.171243) (xy 195.311086 -439.154707) (xy 195.44032 -439.146414)
			(xy 195.50507 -439.145934) (xy 276.314916 -439.145934) (xy 276.379667 -439.146447) (xy 276.508904 -439.154722)
			(xy 276.637348 -439.171243) (xy 276.764472 -439.195942) (xy 276.889757 -439.22872) (xy 277.01269 -439.26944)
			(xy 277.132768 -439.317938) (xy 277.2495 -439.374014) (xy 277.362407 -439.437438) (xy 277.471028 -439.507952)
			(xy 277.574918 -439.585267) (xy 277.673652 -439.669066) (xy 277.766826 -439.759006) (xy 277.854059 -439.85472)
			(xy 277.934994 -439.955815) (xy 278.009299 -440.061879) (xy 278.076671 -440.172476) (xy 278.136833 -440.287155)
			(xy 278.18954 -440.405445) (xy 278.21255 -440.465972) (xy 309.545736 -440.465972) (xy 309.96636 -440.045348)
			(xy 309.96636 -416.488372) (xy 308.96814 -415.490152) (xy 280.646632 -415.490152) (xy 280.152348 -415.984436)
			(xy 280.13435 -416.001722) (xy 280.093968 -416.031034) (xy 280.049502 -416.053677) (xy 280.002045 -416.069094)
			(xy 279.952761 -416.076908) (xy 279.927812 -416.0774) (xy 275.812504 -416.0774) (xy 270.706088 -421.183816)
			(xy 270.688089 -421.2011) (xy 270.647706 -421.23041) (xy 270.60324 -421.253053) (xy 270.555784 -421.268472)
			(xy 270.506501 -421.27629) (xy 270.481552 -421.27678) (xy 233.339132 -421.27678) (xy 231.01554 -423.600372)
			(xy 231.01554 -433.130695) (xy 266.885917 -433.130695) (xy 266.885917 -432.953425) (xy 266.89387 -432.776334)
			(xy 266.909761 -432.599778) (xy 266.933556 -432.424113) (xy 266.965209 -432.249692) (xy 267.004655 -432.076867)
			(xy 267.051815 -431.905986) (xy 267.106594 -431.737392) (xy 267.168882 -431.571427) (xy 267.238554 -431.408422)
			(xy 267.315468 -431.248708) (xy 267.399471 -431.092605) (xy 267.490392 -430.940428) (xy 267.588049 -430.792484)
			(xy 267.692246 -430.64907) (xy 267.802772 -430.510475) (xy 267.919404 -430.376978) (xy 268.041909 -430.248849)
			(xy 268.170038 -430.126344) (xy 268.303535 -430.009712) (xy 268.44213 -429.899186) (xy 268.585544 -429.794989)
			(xy 268.733488 -429.697332) (xy 268.885665 -429.606411) (xy 269.041768 -429.522408) (xy 269.201482 -429.445494)
			(xy 269.364487 -429.375822) (xy 269.530452 -429.313534) (xy 269.699046 -429.258755) (xy 269.869927 -429.211595)
			(xy 270.042752 -429.172149) (xy 270.217173 -429.140496) (xy 270.392838 -429.116701) (xy 270.569394 -429.10081)
			(xy 270.746485 -429.092857) (xy 270.923755 -429.092857) (xy 271.100846 -429.10081) (xy 271.277402 -429.116701)
			(xy 271.453067 -429.140496) (xy 271.627488 -429.172149) (xy 271.800313 -429.211595) (xy 271.971194 -429.258755)
			(xy 272.139788 -429.313534) (xy 272.305753 -429.375822) (xy 272.468758 -429.445494) (xy 272.628472 -429.522408)
			(xy 272.784575 -429.606411) (xy 272.936752 -429.697332) (xy 273.084696 -429.794989) (xy 273.22811 -429.899186)
			(xy 273.366705 -430.009712) (xy 273.500202 -430.126344) (xy 273.628331 -430.248849) (xy 273.750836 -430.376978)
			(xy 273.867468 -430.510475) (xy 273.977994 -430.64907) (xy 274.082191 -430.792484) (xy 274.179848 -430.940428)
			(xy 274.270769 -431.092605) (xy 274.354772 -431.248708) (xy 274.431686 -431.408422) (xy 274.501358 -431.571427)
			(xy 274.563646 -431.737392) (xy 274.618425 -431.905986) (xy 274.665585 -432.076867) (xy 274.705031 -432.249692)
			(xy 274.736684 -432.424113) (xy 274.760479 -432.599778) (xy 274.77637 -432.776334) (xy 274.784323 -432.953425)
			(xy 274.78482 -433.04206) (xy 274.784323 -433.130695) (xy 274.77637 -433.307786) (xy 274.760479 -433.484342)
			(xy 274.736684 -433.660007) (xy 274.705031 -433.834428) (xy 274.665585 -434.007253) (xy 274.618425 -434.178134)
			(xy 274.563646 -434.346728) (xy 274.501358 -434.512693) (xy 274.431686 -434.675698) (xy 274.354772 -434.835412)
			(xy 274.270769 -434.991515) (xy 274.179848 -435.143692) (xy 274.082191 -435.291636) (xy 273.977994 -435.43505)
			(xy 273.867468 -435.573645) (xy 273.750836 -435.707142) (xy 273.628331 -435.835271) (xy 273.500202 -435.957776)
			(xy 273.366705 -436.074408) (xy 273.22811 -436.184934) (xy 273.084696 -436.289131) (xy 272.936752 -436.386788)
			(xy 272.784575 -436.477709) (xy 272.628472 -436.561712) (xy 272.468758 -436.638626) (xy 272.305753 -436.708298)
			(xy 272.139788 -436.770586) (xy 271.971194 -436.825365) (xy 271.800313 -436.872525) (xy 271.627488 -436.911971)
			(xy 271.453067 -436.943624) (xy 271.277402 -436.967419) (xy 271.100846 -436.98331) (xy 270.923755 -436.991263)
			(xy 270.746485 -436.991263) (xy 270.569394 -436.98331) (xy 270.392838 -436.967419) (xy 270.217173 -436.943624)
			(xy 270.042752 -436.911971) (xy 269.869927 -436.872525) (xy 269.699046 -436.825365) (xy 269.530452 -436.770586)
			(xy 269.364487 -436.708298) (xy 269.201482 -436.638626) (xy 269.041768 -436.561712) (xy 268.885665 -436.477709)
			(xy 268.733488 -436.386788) (xy 268.585544 -436.289131) (xy 268.44213 -436.184934) (xy 268.303535 -436.074408)
			(xy 268.170038 -435.957776) (xy 268.041909 -435.835271) (xy 267.919404 -435.707142) (xy 267.802772 -435.573645)
			(xy 267.692246 -435.43505) (xy 267.588049 -435.291636) (xy 267.490392 -435.143692) (xy 267.399471 -434.991515)
			(xy 267.315468 -434.835412) (xy 267.238554 -434.675698) (xy 267.168882 -434.512693) (xy 267.106594 -434.346728)
			(xy 267.051815 -434.178134) (xy 267.004655 -434.007253) (xy 266.965209 -433.834428) (xy 266.933556 -433.660007)
			(xy 266.909761 -433.484342) (xy 266.89387 -433.307786) (xy 266.885917 -433.130695) (xy 231.01554 -433.130695)
			(xy 231.01554 -435.063392) (xy 231.015051 -435.088342) (xy 231.007247 -435.137627) (xy 230.99183 -435.185086)
			(xy 230.96918 -435.229548) (xy 230.939853 -435.269921) (xy 230.922576 -435.287928) (xy 229.133908 -437.076596)
			(xy 229.115908 -437.093876) (xy 229.075523 -437.123178) (xy 229.031056 -437.145811) (xy 228.9836 -437.161219)
			(xy 228.934319 -437.169025) (xy 228.909372 -437.16956) (xy 207.503268 -437.16956) (xy 207.478316 -437.169076)
			(xy 207.429025 -437.161281) (xy 207.38156 -437.145871) (xy 207.33709 -437.123227) (xy 207.29671 -437.093905)
			(xy 207.278732 -437.076596) (xy 205.949804 -435.747668) (xy 205.93252 -435.729669) (xy 205.903211 -435.689286)
			(xy 205.88057 -435.64482) (xy 205.865152 -435.597363) (xy 205.857337 -435.548081) (xy 205.85684 -435.523132)
			(xy 205.85684 -429.817784) (xy 197.252336 -421.21328) (xy 192.7225 -421.21328) (xy 192.69755 -421.212791)
			(xy 192.648264 -421.204987) (xy 192.600806 -421.18957) (xy 192.556342 -421.166921) (xy 192.515968 -421.137596)
			(xy 192.497964 -421.120316) (xy 185.70448 -414.326832) (xy 181.345586 -414.326832) (xy 181.342538 -414.327086)
			(xy 181.332666 -414.328145) (xy 181.312842 -414.329286) (xy 181.302914 -414.329372) (xy 181.292986 -414.32928)
			(xy 181.273163 -414.328136) (xy 181.26329 -414.327086) (xy 181.260242 -414.326832) (xy 180.598826 -414.326832)
			(xy 180.591206 -414.329118) (xy 180.565269 -414.336788) (xy 180.511822 -414.345084) (xy 180.48478 -414.345628)
			(xy 180.457734 -414.345125) (xy 180.40428 -414.336837) (xy 180.378354 -414.329118) (xy 180.370734 -414.326832)
			(xy 170.59656 -414.326832) (xy 167.90924 -417.014152) (xy 167.90924 -433.130695) (xy 197.035917 -433.130695)
			(xy 197.035917 -432.953425) (xy 197.04387 -432.776334) (xy 197.059761 -432.599778) (xy 197.083556 -432.424113)
			(xy 197.115209 -432.249692) (xy 197.154655 -432.076867) (xy 197.201815 -431.905986) (xy 197.256594 -431.737392)
			(xy 197.318882 -431.571427) (xy 197.388554 -431.408422) (xy 197.465468 -431.248708) (xy 197.549471 -431.092605)
			(xy 197.640392 -430.940428) (xy 197.738049 -430.792484) (xy 197.842246 -430.64907) (xy 197.952772 -430.510475)
			(xy 198.069404 -430.376978) (xy 198.191909 -430.248849) (xy 198.320038 -430.126344) (xy 198.453535 -430.009712)
			(xy 198.59213 -429.899186) (xy 198.735544 -429.794989) (xy 198.883488 -429.697332) (xy 199.035665 -429.606411)
			(xy 199.191768 -429.522408) (xy 199.351482 -429.445494) (xy 199.514487 -429.375822) (xy 199.680452 -429.313534)
			(xy 199.849046 -429.258755) (xy 200.019927 -429.211595) (xy 200.192752 -429.172149) (xy 200.367173 -429.140496)
			(xy 200.542838 -429.116701) (xy 200.719394 -429.10081) (xy 200.896485 -429.092857) (xy 201.073755 -429.092857)
			(xy 201.250846 -429.10081) (xy 201.427402 -429.116701) (xy 201.603067 -429.140496) (xy 201.777488 -429.172149)
			(xy 201.950313 -429.211595) (xy 202.121194 -429.258755) (xy 202.289788 -429.313534) (xy 202.455753 -429.375822)
			(xy 202.618758 -429.445494) (xy 202.778472 -429.522408) (xy 202.934575 -429.606411) (xy 203.086752 -429.697332)
			(xy 203.234696 -429.794989) (xy 203.37811 -429.899186) (xy 203.516705 -430.009712) (xy 203.650202 -430.126344)
			(xy 203.778331 -430.248849) (xy 203.900836 -430.376978) (xy 204.017468 -430.510475) (xy 204.127994 -430.64907)
			(xy 204.232191 -430.792484) (xy 204.329848 -430.940428) (xy 204.420769 -431.092605) (xy 204.504772 -431.248708)
			(xy 204.581686 -431.408422) (xy 204.651358 -431.571427) (xy 204.713646 -431.737392) (xy 204.768425 -431.905986)
			(xy 204.815585 -432.076867) (xy 204.855031 -432.249692) (xy 204.886684 -432.424113) (xy 204.910479 -432.599778)
			(xy 204.92637 -432.776334) (xy 204.934323 -432.953425) (xy 204.93482 -433.04206) (xy 204.934323 -433.130695)
			(xy 204.92637 -433.307786) (xy 204.910479 -433.484342) (xy 204.886684 -433.660007) (xy 204.855031 -433.834428)
			(xy 204.815585 -434.007253) (xy 204.768425 -434.178134) (xy 204.713646 -434.346728) (xy 204.651358 -434.512693)
			(xy 204.581686 -434.675698) (xy 204.504772 -434.835412) (xy 204.420769 -434.991515) (xy 204.329848 -435.143692)
			(xy 204.232191 -435.291636) (xy 204.127994 -435.43505) (xy 204.017468 -435.573645) (xy 203.900836 -435.707142)
			(xy 203.778331 -435.835271) (xy 203.650202 -435.957776) (xy 203.516705 -436.074408) (xy 203.37811 -436.184934)
			(xy 203.234696 -436.289131) (xy 203.086752 -436.386788) (xy 202.934575 -436.477709) (xy 202.778472 -436.561712)
			(xy 202.618758 -436.638626) (xy 202.455753 -436.708298) (xy 202.289788 -436.770586) (xy 202.121194 -436.825365)
			(xy 201.950313 -436.872525) (xy 201.777488 -436.911971) (xy 201.603067 -436.943624) (xy 201.427402 -436.967419)
			(xy 201.250846 -436.98331) (xy 201.073755 -436.991263) (xy 200.896485 -436.991263) (xy 200.719394 -436.98331)
			(xy 200.542838 -436.967419) (xy 200.367173 -436.943624) (xy 200.192752 -436.911971) (xy 200.019927 -436.872525)
			(xy 199.849046 -436.825365) (xy 199.680452 -436.770586) (xy 199.514487 -436.708298) (xy 199.351482 -436.638626)
			(xy 199.191768 -436.561712) (xy 199.035665 -436.477709) (xy 198.883488 -436.386788) (xy 198.735544 -436.289131)
			(xy 198.59213 -436.184934) (xy 198.453535 -436.074408) (xy 198.320038 -435.957776) (xy 198.191909 -435.835271)
			(xy 198.069404 -435.707142) (xy 197.952772 -435.573645) (xy 197.842246 -435.43505) (xy 197.738049 -435.291636)
			(xy 197.640392 -435.143692) (xy 197.549471 -434.991515) (xy 197.465468 -434.835412) (xy 197.388554 -434.675698)
			(xy 197.318882 -434.512693) (xy 197.256594 -434.346728) (xy 197.201815 -434.178134) (xy 197.154655 -434.007253)
			(xy 197.115209 -433.834428) (xy 197.083556 -433.660007) (xy 197.059761 -433.484342) (xy 197.04387 -433.307786)
			(xy 197.035917 -433.130695) (xy 167.90924 -433.130695) (xy 167.90924 -439.925968) (xy 168.449244 -440.465972)
		)
		(stroke
			(width 0)
			(type solid)
		)
		(fill yes)
		(layer "In8.Cu")
		(net "GND")
	)
	(gr_poly
		(pts
			(xy 531.7998 -462.520284) (xy 531.855607 -462.519775) (xy 531.96691 -462.511434) (xy 532.077278 -462.494798)
			(xy 532.186094 -462.469962) (xy 532.29275 -462.437062) (xy 532.396649 -462.396285) (xy 532.49721 -462.347857)
			(xy 532.593871 -462.292049) (xy 532.686092 -462.229174) (xy 532.773355 -462.159583) (xy 532.855174 -462.083666)
			(xy 532.931091 -462.001846) (xy 533.000681 -461.914582) (xy 533.063556 -461.822361) (xy 533.119362 -461.7257)
			(xy 533.16779 -461.625138) (xy 533.208566 -461.521239) (xy 533.241465 -461.414583) (xy 533.266301 -461.305766)
			(xy 533.282935 -461.195398) (xy 533.291275 -461.084095) (xy 533.291796 -461.028288) (xy 533.291796 -455.0283)
			(xy 533.291274 -454.972493) (xy 533.282933 -454.861191) (xy 533.266298 -454.750824) (xy 533.241462 -454.642008)
			(xy 533.208563 -454.535353) (xy 533.167786 -454.431454) (xy 533.119358 -454.330893) (xy 533.063551 -454.234233)
			(xy 533.000677 -454.142013) (xy 532.931086 -454.054749) (xy 532.85517 -453.97293) (xy 532.773351 -453.897014)
			(xy 532.686087 -453.827423) (xy 532.593867 -453.764549) (xy 532.497207 -453.708742) (xy 532.396646 -453.660314)
			(xy 532.292747 -453.619537) (xy 532.186092 -453.586638) (xy 532.077276 -453.561802) (xy 531.966909 -453.545167)
			(xy 531.855607 -453.536826) (xy 531.7998 -453.536304) (xy 516.019796 -453.536304) (xy 515.949442 -453.535811)
			(xy 515.808956 -453.527921) (xy 515.669133 -453.512166) (xy 515.530414 -453.488597) (xy 515.393234 -453.457286)
			(xy 515.258026 -453.418334) (xy 515.125215 -453.371861) (xy 514.995218 -453.318014) (xy 514.868445 -453.256963)
			(xy 514.745294 -453.188901) (xy 514.626154 -453.11404) (xy 514.511398 -453.032616) (xy 514.401389 -452.944887)
			(xy 514.296471 -452.851127) (xy 514.196976 -452.751632) (xy 514.103216 -452.646714) (xy 514.015486 -452.536705)
			(xy 513.934063 -452.421949) (xy 513.859201 -452.302809) (xy 513.791138 -452.179659) (xy 513.730087 -452.052886)
			(xy 513.676241 -451.922889) (xy 513.629768 -451.790078) (xy 513.590815 -451.65487) (xy 513.559504 -451.51769)
			(xy 513.535934 -451.378971) (xy 513.520179 -451.239148) (xy 513.512289 -451.098662) (xy 513.5118 -451.028308)
			(xy 513.5118 -312.408316) (xy 513.512284 -312.337962) (xy 513.520173 -312.197474) (xy 513.535926 -312.05765)
			(xy 513.559495 -311.91893) (xy 513.590805 -311.781749) (xy 513.629757 -311.646539) (xy 513.676229 -311.513726)
			(xy 513.730076 -311.383728) (xy 513.791126 -311.256954) (xy 513.859189 -311.133802) (xy 513.93405 -311.01466)
			(xy 514.015474 -310.899903) (xy 514.103203 -310.789893) (xy 514.196964 -310.684974) (xy 514.296459 -310.585477)
			(xy 514.401377 -310.491716) (xy 514.511387 -310.403986) (xy 514.626144 -310.322561) (xy 514.745285 -310.247699)
			(xy 514.868436 -310.179635) (xy 514.99521 -310.118584) (xy 515.125208 -310.064737) (xy 515.25802 -310.018263)
			(xy 515.393229 -309.97931) (xy 515.53041 -309.947999) (xy 515.669131 -309.924429) (xy 515.808954 -309.908674)
			(xy 515.949442 -309.900784) (xy 516.019796 -309.90032) (xy 531.7998 -309.90032) (xy 531.855607 -309.899798)
			(xy 531.96691 -309.891457) (xy 532.077278 -309.874822) (xy 532.186094 -309.849986) (xy 532.292751 -309.817087)
			(xy 532.39665 -309.77631) (xy 532.497211 -309.727883) (xy 532.593873 -309.672076) (xy 532.686094 -309.609202)
			(xy 532.773358 -309.539612) (xy 532.855178 -309.463695) (xy 532.931096 -309.381876) (xy 533.000687 -309.294613)
			(xy 533.063563 -309.202393) (xy 533.119372 -309.105733) (xy 533.167801 -309.005172) (xy 533.208579 -308.901273)
			(xy 533.24148 -308.794618) (xy 533.266318 -308.685802) (xy 533.282955 -308.575434) (xy 533.291297 -308.464131)
			(xy 533.291796 -308.408324) (xy 533.291796 10.40003) (xy 533.291273 10.455836) (xy 533.28293 10.567137)
			(xy 533.266293 10.677502) (xy 533.241455 10.786316) (xy 533.208555 10.89297) (xy 533.167777 10.996866)
			(xy 533.119348 11.097425) (xy 533.063541 11.194084) (xy 533.000666 11.286302) (xy 532.931076 11.373563)
			(xy 532.855159 11.45538) (xy 532.77334 11.531295) (xy 532.686078 11.600884) (xy 532.593858 11.663757)
			(xy 532.497199 11.719562) (xy 532.396639 11.767989) (xy 532.292741 11.808765) (xy 532.186087 11.841663)
			(xy 532.077273 11.866499) (xy 531.966907 11.883134) (xy 531.855606 11.891474) (xy 531.7998 11.892026)
			(xy 475.799912 11.892026) (xy 475.744104 11.891505) (xy 475.632801 11.883165) (xy 475.522432 11.86653)
			(xy 475.413615 11.841695) (xy 475.306958 11.808796) (xy 475.203057 11.76802) (xy 475.102495 11.719593)
			(xy 475.005832 11.663786) (xy 474.91361 11.600912) (xy 474.826345 11.531322) (xy 474.744524 11.455406)
			(xy 474.668605 11.373587) (xy 474.599013 11.286323) (xy 474.536136 11.194103) (xy 474.480327 11.097442)
			(xy 474.431897 10.996881) (xy 474.391117 10.892982) (xy 474.358216 10.786326) (xy 474.333378 10.677509)
			(xy 474.31674 10.567141) (xy 474.308397 10.455838) (xy 474.307916 10.40003) (xy 474.307916 7.335466)
			(xy 526.704041 7.335466) (xy 526.704041 7.464606) (xy 526.711991 7.593501) (xy 526.727861 7.721661)
			(xy 526.75159 7.848602) (xy 526.783089 7.973841) (xy 526.822238 8.096904) (xy 526.868889 8.217323)
			(xy 526.922864 8.334642) (xy 526.983959 8.448416) (xy 527.051942 8.558213) (xy 527.126556 8.663616)
			(xy 527.207517 8.764226) (xy 527.294517 8.859661) (xy 527.387228 8.94956) (xy 527.485298 9.033581)
			(xy 527.588353 9.111405) (xy 527.696004 9.182737) (xy 527.807843 9.247307) (xy 527.923444 9.304869)
			(xy 528.042369 9.355206) (xy 528.164168 9.398126) (xy 528.288378 9.433467) (xy 528.414527 9.461094)
			(xy 528.542139 9.480903) (xy 528.670728 9.492819) (xy 528.799806 9.496796) (xy 528.928884 9.492819)
			(xy 529.057473 9.480903) (xy 529.185085 9.461094) (xy 529.311234 9.433467) (xy 529.435444 9.398126)
			(xy 529.557243 9.355206) (xy 529.676168 9.304869) (xy 529.791769 9.247307) (xy 529.903608 9.182737)
			(xy 530.011259 9.111405) (xy 530.114314 9.033581) (xy 530.212384 8.94956) (xy 530.305095 8.859661)
			(xy 530.392095 8.764226) (xy 530.473056 8.663616) (xy 530.54767 8.558213) (xy 530.615653 8.448416)
			(xy 530.676748 8.334642) (xy 530.730723 8.217323) (xy 530.777374 8.096904) (xy 530.816523 7.973841)
			(xy 530.848022 7.848602) (xy 530.871751 7.721661) (xy 530.887621 7.593501) (xy 530.895571 7.464606)
			(xy 530.896068 7.400036) (xy 530.895571 7.335466) (xy 530.887621 7.206571) (xy 530.871751 7.078411)
			(xy 530.848022 6.95147) (xy 530.816523 6.826231) (xy 530.777374 6.703168) (xy 530.730723 6.582749)
			(xy 530.676748 6.46543) (xy 530.615653 6.351656) (xy 530.54767 6.241859) (xy 530.473056 6.136456)
			(xy 530.392095 6.035846) (xy 530.305095 5.940411) (xy 530.212384 5.850512) (xy 530.114314 5.766491)
			(xy 530.011259 5.688667) (xy 529.903608 5.617335) (xy 529.791769 5.552765) (xy 529.676168 5.495203)
			(xy 529.557243 5.444866) (xy 529.435444 5.401946) (xy 529.311234 5.366605) (xy 529.185085 5.338978)
			(xy 529.057473 5.319169) (xy 528.928884 5.307253) (xy 528.799806 5.303277) (xy 528.670728 5.307253)
			(xy 528.542139 5.319169) (xy 528.414527 5.338978) (xy 528.288378 5.366605) (xy 528.164168 5.401946)
			(xy 528.042369 5.444866) (xy 527.923444 5.495203) (xy 527.807843 5.552765) (xy 527.696004 5.617335)
			(xy 527.588353 5.688667) (xy 527.485298 5.766491) (xy 527.387228 5.850512) (xy 527.294517 5.940411)
			(xy 527.207517 6.035846) (xy 527.126556 6.136456) (xy 527.051942 6.241859) (xy 526.983959 6.351656)
			(xy 526.922864 6.46543) (xy 526.868889 6.582749) (xy 526.822238 6.703168) (xy 526.783089 6.826231)
			(xy 526.75159 6.95147) (xy 526.727861 7.078411) (xy 526.711991 7.206571) (xy 526.704041 7.335466)
			(xy 474.307916 7.335466) (xy 474.307916 -77.67193) (xy 474.307428 -77.765094) (xy 474.299715 -77.951262)
			(xy 474.284317 -78.136953) (xy 474.261258 -78.321849) (xy 474.23058 -78.505634) (xy 474.192333 -78.687994)
			(xy 474.146584 -78.868619) (xy 474.093411 -79.047199) (xy 474.032904 -79.223429) (xy 473.965167 -79.397008)
			(xy 473.890315 -79.56764) (xy 473.808477 -79.735034) (xy 473.719792 -79.898903) (xy 473.624411 -80.058968)
			(xy 473.522498 -80.214955) (xy 473.414227 -80.366597) (xy 473.299782 -80.513637) (xy 473.17936 -80.655821)
			(xy 473.053165 -80.792909) (xy 472.987624 -80.859122) (xy 471.245184 -82.601562) (xy 471.207836 -82.63956)
			(xy 471.138049 -82.720082) (xy 471.074185 -82.805378) (xy 471.01657 -82.895014) (xy 470.965496 -82.988531)
			(xy 470.921226 -83.085455) (xy 470.883983 -83.18529) (xy 470.853958 -83.287527) (xy 470.831304 -83.391646)
			(xy 470.816136 -83.497117) (xy 470.808532 -83.6034) (xy 470.80805 -83.656678) (xy 470.80805 -404.871936)
			(xy 470.807562 -404.9651) (xy 470.799849 -405.151268) (xy 470.78445 -405.336959) (xy 470.761392 -405.521855)
			(xy 470.730713 -405.70564) (xy 470.692467 -405.888001) (xy 470.646718 -406.068625) (xy 470.593544 -406.247205)
			(xy 470.533038 -406.423435) (xy 470.465301 -406.597015) (xy 470.39045 -406.767647) (xy 470.308612 -406.935041)
			(xy 470.219927 -407.098911) (xy 470.124547 -407.258976) (xy 470.022634 -407.414963) (xy 469.914363 -407.566606)
			(xy 469.799919 -407.713645) (xy 469.679497 -407.855831) (xy 469.553302 -407.992919) (xy 469.487758 -408.059128)
			(xy 468.244936 -409.30195) (xy 468.207612 -409.339964) (xy 468.137859 -409.4205) (xy 468.074028 -409.505805)
			(xy 468.016443 -409.595446) (xy 467.965398 -409.688966) (xy 467.921153 -409.785888) (xy 467.883933 -409.885719)
			(xy 467.853928 -409.98795) (xy 467.831291 -410.092061) (xy 467.816137 -410.197522) (xy 467.808543 -410.303794)
			(xy 467.808056 -410.357066) (xy 467.808056 -439.989976) (xy 467.808577 -440.045784) (xy 467.816916 -440.157089)
			(xy 467.83355 -440.267459) (xy 467.858385 -440.376277) (xy 467.891282 -440.482936) (xy 467.932058 -440.586837)
			(xy 467.980485 -440.687401) (xy 468.036291 -440.784065) (xy 468.099165 -440.876289) (xy 468.168754 -440.963556)
			(xy 468.244671 -441.045378) (xy 468.32649 -441.121299) (xy 468.413753 -441.190893) (xy 468.505974 -441.253771)
			(xy 468.602635 -441.309582) (xy 468.703197 -441.358013) (xy 468.807096 -441.398794) (xy 468.913753 -441.431697)
			(xy 469.02257 -441.456537) (xy 469.13294 -441.473176) (xy 469.244244 -441.48152) (xy 469.300052 -441.481972)
			(xy 471.79992 -441.481972) (xy 471.870274 -441.482466) (xy 472.01076 -441.490356) (xy 472.150582 -441.506112)
			(xy 472.289302 -441.529682) (xy 472.426481 -441.560993) (xy 472.561689 -441.599946) (xy 472.6945 -441.646419)
			(xy 472.824497 -441.700266) (xy 472.95127 -441.761317) (xy 473.07442 -441.82938) (xy 473.19356 -441.904241)
			(xy 473.308316 -441.985664) (xy 473.418325 -442.073394) (xy 473.523243 -442.167153) (xy 473.622738 -442.266648)
			(xy 473.716499 -442.371565) (xy 473.804229 -442.481575) (xy 473.885652 -442.59633) (xy 473.960514 -442.71547)
			(xy 474.028578 -442.83862) (xy 474.089629 -442.965392) (xy 474.143476 -443.095389) (xy 474.18995 -443.2282)
			(xy 474.228904 -443.363407) (xy 474.260216 -443.500587) (xy 474.283787 -443.639306) (xy 474.299543 -443.779128)
			(xy 474.307434 -443.919614) (xy 474.307916 -443.989968) (xy 474.307916 -458.092864) (xy 526.704041 -458.092864)
			(xy 526.704041 -457.963724) (xy 526.711991 -457.834829) (xy 526.727861 -457.706669) (xy 526.75159 -457.579728)
			(xy 526.783089 -457.454489) (xy 526.822238 -457.331426) (xy 526.868889 -457.211007) (xy 526.922864 -457.093688)
			(xy 526.983959 -456.979914) (xy 527.051942 -456.870117) (xy 527.126556 -456.764714) (xy 527.207517 -456.664104)
			(xy 527.294517 -456.568669) (xy 527.387228 -456.47877) (xy 527.485298 -456.394749) (xy 527.588353 -456.316925)
			(xy 527.696004 -456.245593) (xy 527.807843 -456.181023) (xy 527.923444 -456.123461) (xy 528.042369 -456.073124)
			(xy 528.164168 -456.030204) (xy 528.288378 -455.994863) (xy 528.414527 -455.967236) (xy 528.542139 -455.947427)
			(xy 528.670728 -455.935511) (xy 528.799806 -455.931535) (xy 528.928884 -455.935511) (xy 529.057473 -455.947427)
			(xy 529.185085 -455.967236) (xy 529.311234 -455.994863) (xy 529.435444 -456.030204) (xy 529.557243 -456.073124)
			(xy 529.676168 -456.123461) (xy 529.791769 -456.181023) (xy 529.903608 -456.245593) (xy 530.011259 -456.316925)
			(xy 530.114314 -456.394749) (xy 530.212384 -456.47877) (xy 530.305095 -456.568669) (xy 530.392095 -456.664104)
			(xy 530.473056 -456.764714) (xy 530.54767 -456.870117) (xy 530.615653 -456.979914) (xy 530.676748 -457.093688)
			(xy 530.730723 -457.211007) (xy 530.777374 -457.331426) (xy 530.816523 -457.454489) (xy 530.848022 -457.579728)
			(xy 530.871751 -457.706669) (xy 530.887621 -457.834829) (xy 530.895571 -457.963724) (xy 530.896068 -458.028294)
			(xy 530.895571 -458.092864) (xy 530.887621 -458.221759) (xy 530.871751 -458.349919) (xy 530.848022 -458.47686)
			(xy 530.816523 -458.602099) (xy 530.777374 -458.725162) (xy 530.730723 -458.845581) (xy 530.676748 -458.9629)
			(xy 530.615653 -459.076674) (xy 530.54767 -459.186471) (xy 530.473056 -459.291874) (xy 530.392095 -459.392484)
			(xy 530.305095 -459.487919) (xy 530.212384 -459.577818) (xy 530.114314 -459.661839) (xy 530.011259 -459.739663)
			(xy 529.903608 -459.810995) (xy 529.791769 -459.875565) (xy 529.676168 -459.933127) (xy 529.557243 -459.983464)
			(xy 529.435444 -460.026384) (xy 529.311234 -460.061725) (xy 529.185085 -460.089352) (xy 529.057473 -460.109161)
			(xy 528.928884 -460.121077) (xy 528.799806 -460.125054) (xy 528.670728 -460.121077) (xy 528.542139 -460.109161)
			(xy 528.414527 -460.089352) (xy 528.288378 -460.061725) (xy 528.164168 -460.026384) (xy 528.042369 -459.983464)
			(xy 527.923444 -459.933127) (xy 527.807843 -459.875565) (xy 527.696004 -459.810995) (xy 527.588353 -459.739663)
			(xy 527.485298 -459.661839) (xy 527.387228 -459.577818) (xy 527.294517 -459.487919) (xy 527.207517 -459.392484)
			(xy 527.126556 -459.291874) (xy 527.051942 -459.186471) (xy 526.983959 -459.076674) (xy 526.922864 -458.9629)
			(xy 526.868889 -458.845581) (xy 526.822238 -458.725162) (xy 526.783089 -458.602099) (xy 526.75159 -458.47686)
			(xy 526.727861 -458.349919) (xy 526.711991 -458.221759) (xy 526.704041 -458.092864) (xy 474.307916 -458.092864)
			(xy 474.307916 -461.028288) (xy 474.308425 -461.084096) (xy 474.316765 -461.195399) (xy 474.3334 -461.305768)
			(xy 474.358236 -461.414584) (xy 474.391134 -461.521241) (xy 474.431912 -461.625141) (xy 474.480339 -461.725703)
			(xy 474.536147 -461.822365) (xy 474.599022 -461.914586) (xy 474.668612 -462.00185) (xy 474.74453 -462.08367)
			(xy 474.82635 -462.159588) (xy 474.913614 -462.229178) (xy 475.005835 -462.292053) (xy 475.102497 -462.347861)
			(xy 475.203059 -462.396288) (xy 475.306959 -462.437066) (xy 475.413616 -462.469964) (xy 475.522432 -462.4948)
			(xy 475.632801 -462.511435) (xy 475.744104 -462.519775) (xy 475.799912 -462.520284)
		)
		(stroke
			(width 0)
			(type solid)
		)
		(fill yes)
		(layer "In8.Cu")
		(net "T1_GND")
	)
	(gr_poly
		(pts
			(xy 82.873596 -348.800166) (xy 82.87766 -348.790006) (xy 82.878676 -348.787466) (xy 82.882486 -348.778068)
			(xy 82.882486 -347.453458)
			(arc
				(start 80.751172 -345.322398)
				(mid 80.723787 -345.281364)
				(end 80.714088 -345.23299)
			)
			(arc
				(start 80.714088 -343.19464)
				(mid 80.723769 -343.146259)
				(end 80.751172 -343.105232)
			)
			(arc
				(start 80.92186 -342.934544)
				(mid 80.962894 -342.907159)
				(end 81.011268 -342.89746)
			)
			(arc
				(start 84.668868 -342.89746)
				(mid 84.717249 -342.907141)
				(end 84.758276 -342.934544)
			)
			(xy 85.196426 -343.372948) (xy 88.543384 -343.372948) (xy 89.588086 -342.328246) (xy 89.588086 -340.37016)
			(arc
				(start 88.961722 -339.74405)
				(mid 88.934337 -339.703016)
				(end 88.924638 -339.654642)
			)
			(arc
				(start 88.924638 -337.306412)
				(mid 88.934319 -337.258031)
				(end 88.961722 -337.217004)
			)
			(arc
				(start 89.037414 -337.141312)
				(mid 89.078448 -337.113927)
				(end 89.126822 -337.104228)
			)
			(arc
				(start 92.802202 -337.104228)
				(mid 92.850583 -337.113909)
				(end 92.89161 -337.141312)
			)
			(arc
				(start 93.009974 -337.259676)
				(mid 93.037359 -337.30071)
				(end 93.047058 -337.349084)
			)
			(xy 93.047058 -339.331046) (xy 93.224096 -339.508084) (xy 97.376996 -339.508084) (xy 97.988374 -338.896706)
			(xy 97.988374 -336.971894)
			(arc
				(start 97.099628 -336.083402)
				(mid 97.072243 -336.042368)
				(end 97.062544 -335.993994)
			)
			(arc
				(start 97.062544 -333.929228)
				(mid 97.072225 -333.880847)
				(end 97.099628 -333.83982)
			)
			(arc
				(start 97.226882 -333.712566)
				(mid 97.267916 -333.685181)
				(end 97.31629 -333.675482)
			)
			(arc
				(start 100.86467 -333.675482)
				(mid 100.913051 -333.685163)
				(end 100.954078 -333.712566)
			)
			(arc
				(start 101.082856 -333.841344)
				(mid 101.110241 -333.882378)
				(end 101.11994 -333.930752)
			)
			(arc
				(start 101.11994 -335.44637)
				(mid 101.174662 -335.572917)
				(end 101.193346 -335.709514)
			)
			(arc
				(start 101.193346 -335.709514)
				(mid 101.176327 -335.839718)
				(end 101.126544 -335.961228)
			)
			(xy 101.11994 -335.973166) (xy 101.11994 -336.182462)
			(arc
				(start 101.126544 -336.1944)
				(mid 101.176338 -336.315907)
				(end 101.193346 -336.446114)
			)
			(arc
				(start 101.193346 -336.446114)
				(mid 101.176327 -336.576318)
				(end 101.126544 -336.697828)
			)
			(xy 101.11994 -336.709766) (xy 101.11994 -336.919062)
			(arc
				(start 101.126544 -336.931)
				(mid 101.176338 -337.052507)
				(end 101.193346 -337.182714)
			)
			(arc
				(start 101.193346 -337.182714)
				(mid 101.174647 -337.319307)
				(end 101.11994 -337.445858)
			)
			(xy 101.11994 -338.684362) (xy 101.976174 -339.540596) (xy 105.67035 -339.540596) (xy 106.027474 -339.183472)
			(xy 106.027474 -336.88909)
			(arc
				(start 105.25887 -336.12074)
				(mid 105.231485 -336.079706)
				(end 105.221786 -336.031332)
			)
			(arc
				(start 105.221786 -333.936086)
				(mid 105.231467 -333.887705)
				(end 105.25887 -333.846678)
			)
			(arc
				(start 105.39476 -333.710788)
				(mid 105.435794 -333.683403)
				(end 105.484168 -333.673704)
			)
			(arc
				(start 109.07395 -333.673704)
				(mid 109.122331 -333.683385)
				(end 109.163358 -333.710788)
			)
			(arc
				(start 109.348016 -333.895446)
				(mid 109.375401 -333.93648)
				(end 109.3851 -333.984854)
			)
			(arc
				(start 109.3851 -337.329018)
				(mid 109.375419 -337.377399)
				(end 109.348016 -337.418426)
			)
			(xy 109.13237 -337.633818) (xy 109.13237 -338.536788) (xy 110.112556 -339.516974) (xy 113.66754 -339.516974)
			(xy 114.04854 -339.135974) (xy 114.04854 -336.706464)
			(arc
				(start 113.440718 -336.098896)
				(mid 113.413333 -336.057862)
				(end 113.403634 -336.009488)
			)
			(arc
				(start 113.403634 -333.912464)
				(mid 113.413315 -333.864083)
				(end 113.440718 -333.823056)
			)
			(arc
				(start 113.552224 -333.71155)
				(mid 113.593258 -333.684165)
				(end 113.641632 -333.674466)
			)
			(arc
				(start 117.226588 -333.674466)
				(mid 117.274969 -333.684147)
				(end 117.315996 -333.71155)
			)
			(arc
				(start 117.465602 -333.861156)
				(mid 117.492987 -333.90219)
				(end 117.502686 -333.950564)
			)
			(xy 117.502686 -335.601056)
			(arc
				(start 117.503702 -335.606136)
				(mid 117.511686 -335.657552)
				(end 117.51437 -335.709514)
			)
			(arc
				(start 117.51437 -335.709514)
				(mid 117.511682 -335.761476)
				(end 117.503702 -335.812892)
			)
			(xy 117.502686 -335.817972) (xy 117.502686 -336.337656)
			(arc
				(start 117.503702 -336.342736)
				(mid 117.511686 -336.394152)
				(end 117.51437 -336.446114)
			)
			(arc
				(start 117.51437 -336.446114)
				(mid 117.511682 -336.498076)
				(end 117.503702 -336.549492)
			)
			(xy 117.502686 -336.554572) (xy 117.502686 -337.074256)
			(arc
				(start 117.503702 -337.079336)
				(mid 117.511686 -337.130752)
				(end 117.51437 -337.182714)
			)
			(arc
				(start 117.51437 -337.182714)
				(mid 117.511682 -337.234676)
				(end 117.503702 -337.286092)
			)
			(xy 117.502686 -337.291172) (xy 117.502686 -338.827872) (xy 118.353078 -339.678264) (xy 121.807224 -339.678264)
			(xy 122.25401 -339.231478) (xy 122.25401 -336.808318)
			(arc
				(start 121.582688 -336.13725)
				(mid 121.555303 -336.096216)
				(end 121.545604 -336.047842)
			)
			(arc
				(start 121.545604 -333.912464)
				(mid 121.555285 -333.864083)
				(end 121.582688 -333.823056)
			)
			(arc
				(start 121.69521 -333.710534)
				(mid 121.736244 -333.683149)
				(end 121.784618 -333.67345)
			)
			(arc
				(start 125.393196 -333.67345)
				(mid 125.441577 -333.683131)
				(end 125.482604 -333.710534)
			)
			(arc
				(start 125.641608 -333.869538)
				(mid 125.668993 -333.910572)
				(end 125.678692 -333.958946)
			)
			(xy 125.678692 -335.8007)
			(arc
				(start 125.68047 -335.807558)
				(mid 125.694708 -335.875612)
				(end 125.69952 -335.944972)
			)
			(arc
				(start 125.69952 -335.944972)
				(mid 125.694698 -336.014331)
				(end 125.68047 -336.082386)
			)
			(xy 125.678692 -336.089244) (xy 125.678692 -336.5373)
			(arc
				(start 125.68047 -336.544158)
				(mid 125.694708 -336.612212)
				(end 125.69952 -336.681572)
			)
			(arc
				(start 125.69952 -336.681572)
				(mid 125.694698 -336.750931)
				(end 125.68047 -336.818986)
			)
			(xy 125.678692 -336.825844) (xy 125.678692 -337.2739)
			(arc
				(start 125.68047 -337.280758)
				(mid 125.694708 -337.348812)
				(end 125.69952 -337.418172)
			)
			(arc
				(start 125.69952 -337.418172)
				(mid 125.694698 -337.487531)
				(end 125.68047 -337.555586)
			)
			(xy 125.678692 -337.562444) (xy 125.678692 -342.417146) (xy 126.34976 -343.088214) (xy 129.75082 -343.088214)
			(xy 130.445256 -342.393778) (xy 130.445256 -340.846918)
			(arc
				(start 129.753868 -340.155784)
				(mid 129.726483 -340.11475)
				(end 129.716784 -340.066376)
			)
			(arc
				(start 129.716784 -337.276694)
				(mid 129.726465 -337.228313)
				(end 129.753868 -337.187286)
			)
			(arc
				(start 129.822956 -337.118198)
				(mid 129.86399 -337.090813)
				(end 129.912364 -337.081114)
			)
			(arc
				(start 133.552184 -337.081114)
				(mid 133.600565 -337.090795)
				(end 133.641592 -337.118198)
			)
			(arc
				(start 133.916674 -337.39328)
				(mid 133.944059 -337.434314)
				(end 133.953758 -337.482688)
			)
			(xy 133.953758 -348.01048) (xy 134.377684 -348.434406) (xy 138.246104 -348.434406) (xy 138.446764 -348.233746)
			(xy 138.446764 -346.038932)
			(arc
				(start 137.914634 -345.507056)
				(mid 137.887249 -345.466022)
				(end 137.87755 -345.417648)
			)
			(xy 137.87755 -343.045034) (xy 137.76325 -342.930734)
			(arc
				(start 136.400794 -342.930734)
				(mid 136.303607 -342.911384)
				(end 136.221216 -342.856312)
			)
			(arc
				(start 135.53186 -342.166956)
				(mid 135.476754 -342.084579)
				(end 135.457438 -341.987378)
			)
			(xy 135.457438 -341.874602)
			(arc
				(start 135.455152 -341.867236)
				(mid 135.444102 -341.817612)
				(end 135.44042 -341.766906)
			)
			(arc
				(start 135.44042 -341.766906)
				(mid 135.444105 -341.716201)
				(end 135.455152 -341.666576)
			)
			(xy 135.457438 -341.65921) (xy 135.457438 -341.085424)
			(arc
				(start 135.455152 -341.078058)
				(mid 135.444102 -341.028434)
				(end 135.44042 -340.977728)
			)
			(arc
				(start 135.44042 -340.977728)
				(mid 135.444105 -340.927023)
				(end 135.455152 -340.877398)
			)
			(xy 135.457438 -340.870032) (xy 135.457438 -336.021172) (xy 134.240524 -334.804258)
			(arc
				(start 127.83947 -334.804258)
				(mid 127.742283 -334.784908)
				(end 127.659892 -334.729836)
			)
			(arc
				(start 127.08128 -334.151224)
				(mid 127.026174 -334.068847)
				(end 127.006858 -333.971646)
			)
			(xy 127.006858 -331.753464) (xy 126.689612 -331.436218) (xy 125.05944 -331.436218)
			(arc
				(start 125.055884 -331.436726)
				(mid 125.031683 -331.439198)
				(end 125.00737 -331.440028)
			)
			(arc
				(start 125.00737 -331.440028)
				(mid 124.983056 -331.439214)
				(end 124.958856 -331.436726)
			)
			(xy 124.9553 -331.436218) (xy 124.39904 -331.436218)
			(arc
				(start 124.395484 -331.436726)
				(mid 124.371283 -331.439198)
				(end 124.34697 -331.440028)
			)
			(arc
				(start 124.34697 -331.440028)
				(mid 124.322656 -331.439214)
				(end 124.298456 -331.436726)
			)
			(xy 124.2949 -331.436218)
			(arc
				(start 117.351302 -331.436218)
				(mid 117.075458 -331.566986)
				(end 116.799614 -331.436218)
			)
			(arc
				(start 116.690902 -331.436218)
				(mid 116.415058 -331.566986)
				(end 116.139214 -331.436218)
			)
			(xy 108.738416 -331.436218)
			(arc
				(start 108.73486 -331.436726)
				(mid 108.710659 -331.439198)
				(end 108.686346 -331.440028)
			)
			(arc
				(start 108.686346 -331.440028)
				(mid 108.662032 -331.439214)
				(end 108.637832 -331.436726)
			)
			(xy 108.634276 -331.436218) (xy 108.078016 -331.436218)
			(arc
				(start 108.07446 -331.436726)
				(mid 108.050259 -331.439198)
				(end 108.025946 -331.440028)
			)
			(arc
				(start 108.025946 -331.440028)
				(mid 108.001632 -331.439214)
				(end 107.977432 -331.436726)
			)
			(xy 107.973876 -331.436218) (xy 100.577904 -331.436218)
			(arc
				(start 100.574348 -331.436726)
				(mid 100.550147 -331.439198)
				(end 100.525834 -331.440028)
			)
			(arc
				(start 100.525834 -331.440028)
				(mid 100.50152 -331.439214)
				(end 100.47732 -331.436726)
			)
			(xy 100.473764 -331.436218) (xy 99.917504 -331.436218)
			(arc
				(start 99.913948 -331.436726)
				(mid 99.889747 -331.439198)
				(end 99.865434 -331.440028)
			)
			(arc
				(start 99.865434 -331.440028)
				(mid 99.84112 -331.439214)
				(end 99.81692 -331.436726)
			)
			(xy 99.813364 -331.436218) (xy 93.35262 -331.436218)
			(arc
				(start 91.982798 -332.80604)
				(mid 91.953115 -332.873608)
				(end 91.976956 -332.943454)
			)
			(arc
				(start 91.976956 -332.943454)
				(mid 92.039339 -333.050946)
				(end 92.06103 -333.173324)
			)
			(arc
				(start 92.06103 -333.173324)
				(mid 92.032516 -333.312898)
				(end 91.951556 -333.430118)
			)
			(arc
				(start 91.951556 -333.430118)
				(mid 91.920235 -333.503524)
				(end 91.951556 -333.57693)
			)
			(arc
				(start 91.951556 -333.57693)
				(mid 92.032534 -333.694142)
				(end 92.06103 -333.833724)
			)
			(arc
				(start 92.06103 -333.833724)
				(mid 91.975434 -334.065318)
				(end 91.759786 -334.185514)
			)
			(arc
				(start 91.759786 -334.185514)
				(mid 91.72999 -334.201568)
				(end 91.71686 -334.232758)
			)
			(arc
				(start 91.71686 -334.232758)
				(mid 91.695079 -334.322096)
				(end 91.642946 -334.397858)
			)
			(arc
				(start 91.296236 -334.744568)
				(mid 91.213859 -334.799674)
				(end 91.116658 -334.81899)
			)
			(xy 85.856318 -334.81899) (xy 83.860386 -336.814922)
			(arc
				(start 83.87334 -336.846418)
				(mid 83.893658 -336.913276)
				(end 83.900518 -336.982816)
			)
			(arc
				(start 83.900518 -336.982816)
				(mid 83.867692 -337.132407)
				(end 83.775042 -337.254342)
			)
			(xy 83.757008 -337.269582) (xy 83.757008 -337.35645)
			(arc
				(start 83.775042 -337.37169)
				(mid 83.86765 -337.493644)
				(end 83.900518 -337.643216)
			)
			(arc
				(start 83.900518 -337.643216)
				(mid 83.867692 -337.792807)
				(end 83.775042 -337.914742)
			)
			(xy 83.757008 -337.929982) (xy 83.757008 -338.01685)
			(arc
				(start 83.775042 -338.03209)
				(mid 83.86765 -338.154044)
				(end 83.900518 -338.303616)
			)
			(arc
				(start 83.900518 -338.303616)
				(mid 83.867692 -338.453207)
				(end 83.775042 -338.575142)
			)
			(xy 83.757008 -338.590382) (xy 83.757008 -338.67725)
			(arc
				(start 83.775042 -338.69249)
				(mid 83.86765 -338.814444)
				(end 83.900518 -338.964016)
			)
			(arc
				(start 83.900518 -338.964016)
				(mid 83.867692 -339.113607)
				(end 83.775042 -339.235542)
			)
			(xy 83.757008 -339.250782) (xy 83.757008 -339.33765)
			(arc
				(start 83.775042 -339.35289)
				(mid 83.86765 -339.474844)
				(end 83.900518 -339.624416)
			)
			(arc
				(start 83.900518 -339.624416)
				(mid 83.862554 -339.784467)
				(end 83.756754 -339.91042)
			)
			(arc
				(start 83.756754 -339.91042)
				(mid 83.740308 -340.014995)
				(end 83.682586 -340.103714)
			)
			(arc
				(start 83.30311 -340.48319)
				(mid 83.220733 -340.538296)
				(end 83.123532 -340.557612)
			)
			(xy 77.319124 -340.557612) (xy 76.52004 -341.356696) (xy 76.52004 -347.482414) (xy 78.040484 -349.002858)
			(xy 82.670904 -349.002858)
		)
		(stroke
			(width 0)
			(type solid)
		)
		(fill yes)
		(layer "In8.Cu")
		(net "GND")
	)
	(gr_poly
		(pts
			(xy 330.81341 -348.799912) (xy 330.817474 -348.789752) (xy 330.81849 -348.787212) (xy 330.8223 -348.777814)
			(xy 330.8223 -347.453204)
			(arc
				(start 328.690986 -345.322144)
				(mid 328.663601 -345.28111)
				(end 328.653902 -345.232736)
			)
			(arc
				(start 328.653902 -343.194386)
				(mid 328.663583 -343.146005)
				(end 328.690986 -343.104978)
			)
			(arc
				(start 328.861674 -342.93429)
				(mid 328.902708 -342.906905)
				(end 328.951082 -342.897206)
			)
			(arc
				(start 332.608682 -342.897206)
				(mid 332.657063 -342.906887)
				(end 332.69809 -342.93429)
			)
			(xy 333.13624 -343.372694) (xy 336.483198 -343.372694) (xy 337.5279 -342.327992) (xy 337.5279 -340.369906)
			(arc
				(start 336.901536 -339.743796)
				(mid 336.874151 -339.702762)
				(end 336.864452 -339.654388)
			)
			(arc
				(start 336.864452 -337.306158)
				(mid 336.874133 -337.257777)
				(end 336.901536 -337.21675)
			)
			(arc
				(start 336.977228 -337.141058)
				(mid 337.018262 -337.113673)
				(end 337.066636 -337.103974)
			)
			(arc
				(start 340.615016 -337.103974)
				(mid 340.663397 -337.113655)
				(end 340.704424 -337.141058)
			)
			(arc
				(start 340.822788 -337.259422)
				(mid 340.850173 -337.300456)
				(end 340.859872 -337.34883)
			)
			(arc
				(start 340.859872 -338.807552)
				(mid 340.922879 -339.052662)
				(end 340.859872 -339.297772)
			)
			(xy 340.859872 -339.330792) (xy 341.03691 -339.50783) (xy 345.31681 -339.50783) (xy 345.928188 -338.896452)
			(xy 345.928188 -336.97164)
			(arc
				(start 345.039442 -336.083148)
				(mid 345.012057 -336.042114)
				(end 345.002358 -335.99374)
			)
			(arc
				(start 345.002358 -333.928974)
				(mid 345.012039 -333.880593)
				(end 345.039442 -333.839566)
			)
			(arc
				(start 345.166696 -333.712312)
				(mid 345.20773 -333.684927)
				(end 345.256104 -333.675228)
			)
			(arc
				(start 348.804484 -333.675228)
				(mid 348.852865 -333.684909)
				(end 348.893892 -333.712312)
			)
			(arc
				(start 349.02267 -333.84109)
				(mid 349.050055 -333.882124)
				(end 349.059754 -333.930498)
			)
			(arc
				(start 349.059754 -335.44637)
				(mid 349.114476 -335.572917)
				(end 349.13316 -335.709514)
			)
			(arc
				(start 349.13316 -335.709514)
				(mid 349.116141 -335.839718)
				(end 349.066358 -335.961228)
			)
			(xy 349.059754 -335.973166) (xy 349.059754 -336.182462)
			(arc
				(start 349.066358 -336.1944)
				(mid 349.116152 -336.315907)
				(end 349.13316 -336.446114)
			)
			(arc
				(start 349.13316 -336.446114)
				(mid 349.116141 -336.576318)
				(end 349.066358 -336.697828)
			)
			(xy 349.059754 -336.709766) (xy 349.059754 -336.919062)
			(arc
				(start 349.066358 -336.931)
				(mid 349.116152 -337.052507)
				(end 349.13316 -337.182714)
			)
			(arc
				(start 349.13316 -337.182714)
				(mid 349.114461 -337.319307)
				(end 349.059754 -337.445858)
			)
			(xy 349.059754 -338.684108) (xy 349.915988 -339.540342) (xy 353.610164 -339.540342) (xy 353.967288 -339.183218)
			(xy 353.967288 -336.888836)
			(arc
				(start 353.198684 -336.120486)
				(mid 353.171299 -336.079452)
				(end 353.1616 -336.031078)
			)
			(arc
				(start 353.1616 -333.935832)
				(mid 353.171281 -333.887451)
				(end 353.198684 -333.846424)
			)
			(arc
				(start 353.334574 -333.710534)
				(mid 353.375608 -333.683149)
				(end 353.423982 -333.67345)
			)
			(arc
				(start 357.013764 -333.67345)
				(mid 357.062145 -333.683131)
				(end 357.103172 -333.710534)
			)
			(arc
				(start 357.28783 -333.895192)
				(mid 357.315215 -333.936226)
				(end 357.324914 -333.9846)
			)
			(arc
				(start 357.324914 -337.328764)
				(mid 357.315233 -337.377145)
				(end 357.28783 -337.418172)
			)
			(xy 357.072184 -337.633564) (xy 357.072184 -338.536534) (xy 358.05237 -339.51672) (xy 361.607354 -339.51672)
			(xy 361.988354 -339.13572) (xy 361.988354 -336.70621)
			(arc
				(start 361.380532 -336.098642)
				(mid 361.353147 -336.057608)
				(end 361.343448 -336.009234)
			)
			(arc
				(start 361.343448 -333.91221)
				(mid 361.353129 -333.863829)
				(end 361.380532 -333.822802)
			)
			(arc
				(start 361.492038 -333.711296)
				(mid 361.533072 -333.683911)
				(end 361.581446 -333.674212)
			)
			(arc
				(start 365.166402 -333.674212)
				(mid 365.214783 -333.683893)
				(end 365.25581 -333.711296)
			)
			(arc
				(start 365.405416 -333.860902)
				(mid 365.432801 -333.901936)
				(end 365.4425 -333.95031)
			)
			(xy 365.4425 -335.601056)
			(arc
				(start 365.443516 -335.606136)
				(mid 365.4515 -335.657552)
				(end 365.454184 -335.709514)
			)
			(arc
				(start 365.454184 -335.709514)
				(mid 365.451496 -335.761476)
				(end 365.443516 -335.812892)
			)
			(xy 365.4425 -335.817972) (xy 365.4425 -336.337656)
			(arc
				(start 365.443516 -336.342736)
				(mid 365.4515 -336.394152)
				(end 365.454184 -336.446114)
			)
			(arc
				(start 365.454184 -336.446114)
				(mid 365.451496 -336.498076)
				(end 365.443516 -336.549492)
			)
			(xy 365.4425 -336.554572) (xy 365.4425 -337.074256)
			(arc
				(start 365.443516 -337.079336)
				(mid 365.4515 -337.130752)
				(end 365.454184 -337.182714)
			)
			(arc
				(start 365.454184 -337.182714)
				(mid 365.451496 -337.234676)
				(end 365.443516 -337.286092)
			)
			(xy 365.4425 -337.291172) (xy 365.4425 -338.827618) (xy 366.292892 -339.67801) (xy 369.747038 -339.67801)
			(xy 370.193824 -339.231224) (xy 370.193824 -336.808064)
			(arc
				(start 369.522502 -336.136996)
				(mid 369.495117 -336.095962)
				(end 369.485418 -336.047588)
			)
			(arc
				(start 369.485418 -333.91221)
				(mid 369.495099 -333.863829)
				(end 369.522502 -333.822802)
			)
			(arc
				(start 369.635024 -333.71028)
				(mid 369.676058 -333.682895)
				(end 369.724432 -333.673196)
			)
			(arc
				(start 373.33301 -333.673196)
				(mid 373.381391 -333.682877)
				(end 373.422418 -333.71028)
			)
			(arc
				(start 373.581422 -333.869284)
				(mid 373.608807 -333.910318)
				(end 373.618506 -333.958692)
			)
			(xy 373.618506 -335.8007)
			(arc
				(start 373.620284 -335.807558)
				(mid 373.634522 -335.875612)
				(end 373.639334 -335.944972)
			)
			(arc
				(start 373.639334 -335.944972)
				(mid 373.634512 -336.014331)
				(end 373.620284 -336.082386)
			)
			(xy 373.618506 -336.089244) (xy 373.618506 -336.5373)
			(arc
				(start 373.620284 -336.544158)
				(mid 373.634522 -336.612212)
				(end 373.639334 -336.681572)
			)
			(arc
				(start 373.639334 -336.681572)
				(mid 373.634512 -336.750931)
				(end 373.620284 -336.818986)
			)
			(xy 373.618506 -336.825844) (xy 373.618506 -337.2739)
			(arc
				(start 373.620284 -337.280758)
				(mid 373.634522 -337.348812)
				(end 373.639334 -337.418172)
			)
			(arc
				(start 373.639334 -337.418172)
				(mid 373.634512 -337.487531)
				(end 373.620284 -337.555586)
			)
			(xy 373.618506 -337.562444) (xy 373.618506 -342.416892) (xy 374.289574 -343.08796) (xy 377.690634 -343.08796)
			(xy 378.38507 -342.393524) (xy 378.38507 -340.846664)
			(arc
				(start 377.693682 -340.15553)
				(mid 377.666297 -340.114496)
				(end 377.656598 -340.066122)
			)
			(arc
				(start 377.656598 -337.27644)
				(mid 377.666279 -337.228059)
				(end 377.693682 -337.187032)
			)
			(arc
				(start 377.76277 -337.117944)
				(mid 377.803804 -337.090559)
				(end 377.852178 -337.08086)
			)
			(arc
				(start 381.491998 -337.08086)
				(mid 381.540379 -337.090541)
				(end 381.581406 -337.117944)
			)
			(arc
				(start 381.856488 -337.393026)
				(mid 381.883873 -337.43406)
				(end 381.893572 -337.482434)
			)
			(xy 381.893572 -348.010226) (xy 382.317498 -348.434152) (xy 386.185918 -348.434152) (xy 386.386578 -348.233492)
			(xy 386.386578 -346.038678)
			(arc
				(start 385.854448 -345.506802)
				(mid 385.827063 -345.465768)
				(end 385.817364 -345.417394)
			)
			(xy 385.817364 -343.04478) (xy 385.703064 -342.93048)
			(arc
				(start 384.340608 -342.93048)
				(mid 384.243421 -342.91113)
				(end 384.16103 -342.856058)
			)
			(arc
				(start 383.471674 -342.166702)
				(mid 383.416568 -342.084325)
				(end 383.397252 -341.987124)
			)
			(xy 383.397252 -341.874602)
			(arc
				(start 383.394966 -341.867236)
				(mid 383.383916 -341.817612)
				(end 383.380234 -341.766906)
			)
			(arc
				(start 383.380234 -341.766906)
				(mid 383.383919 -341.716201)
				(end 383.394966 -341.666576)
			)
			(xy 383.397252 -341.65921) (xy 383.397252 -341.085424)
			(arc
				(start 383.394966 -341.078058)
				(mid 383.383916 -341.028434)
				(end 383.380234 -340.977728)
			)
			(arc
				(start 383.380234 -340.977728)
				(mid 383.383919 -340.927023)
				(end 383.394966 -340.877398)
			)
			(xy 383.397252 -340.870032) (xy 383.397252 -336.020918) (xy 382.180338 -334.804004)
			(arc
				(start 375.779284 -334.804004)
				(mid 375.682097 -334.784654)
				(end 375.599706 -334.729582)
			)
			(arc
				(start 375.021094 -334.15097)
				(mid 374.965988 -334.068593)
				(end 374.946672 -333.971392)
			)
			(xy 374.946672 -331.75321) (xy 374.629426 -331.435964) (xy 373.001032 -331.435964)
			(arc
				(start 372.997476 -331.436472)
				(mid 372.972393 -331.439148)
				(end 372.947184 -331.440028)
			)
			(arc
				(start 372.947184 -331.440028)
				(mid 372.921976 -331.439135)
				(end 372.896892 -331.436472)
			)
			(xy 372.893336 -331.435964) (xy 372.340632 -331.435964)
			(arc
				(start 372.337076 -331.436472)
				(mid 372.311993 -331.439148)
				(end 372.286784 -331.440028)
			)
			(arc
				(start 372.286784 -331.440028)
				(mid 372.261576 -331.439135)
				(end 372.236492 -331.436472)
			)
			(xy 372.232936 -331.435964)
			(arc
				(start 365.356394 -331.435964)
				(mid 365.225585 -331.57103)
				(end 365.044228 -331.620622)
			)
			(arc
				(start 365.044228 -331.620622)
				(mid 364.904654 -331.592108)
				(end 364.787434 -331.511148)
			)
			(arc
				(start 364.787434 -331.511148)
				(mid 364.714028 -331.479827)
				(end 364.640622 -331.511148)
			)
			(arc
				(start 364.640622 -331.511148)
				(mid 364.52341 -331.592126)
				(end 364.383828 -331.620622)
			)
			(arc
				(start 364.383828 -331.620622)
				(mid 364.202492 -331.570994)
				(end 364.071662 -331.435964)
			)
			(xy 356.680008 -331.435964)
			(arc
				(start 356.676452 -331.436472)
				(mid 356.651369 -331.439148)
				(end 356.62616 -331.440028)
			)
			(arc
				(start 356.62616 -331.440028)
				(mid 356.600952 -331.439135)
				(end 356.575868 -331.436472)
			)
			(xy 356.572312 -331.435964) (xy 356.019608 -331.435964)
			(arc
				(start 356.016052 -331.436472)
				(mid 355.990969 -331.439148)
				(end 355.96576 -331.440028)
			)
			(arc
				(start 355.96576 -331.440028)
				(mid 355.940552 -331.439135)
				(end 355.915468 -331.436472)
			)
			(xy 355.911912 -331.435964) (xy 348.519496 -331.435964)
			(arc
				(start 348.51594 -331.436472)
				(mid 348.490857 -331.439148)
				(end 348.465648 -331.440028)
			)
			(arc
				(start 348.465648 -331.440028)
				(mid 348.44044 -331.439135)
				(end 348.415356 -331.436472)
			)
			(xy 348.4118 -331.435964) (xy 347.859096 -331.435964)
			(arc
				(start 347.85554 -331.436472)
				(mid 347.830457 -331.439148)
				(end 347.805248 -331.440028)
			)
			(arc
				(start 347.805248 -331.440028)
				(mid 347.78004 -331.439135)
				(end 347.754956 -331.436472)
			)
			(xy 347.7514 -331.435964) (xy 341.292434 -331.435964)
			(arc
				(start 339.922358 -332.80604)
				(mid 339.892843 -332.87363)
				(end 339.91677 -332.943454)
			)
			(arc
				(start 339.91677 -332.943454)
				(mid 339.979153 -333.050946)
				(end 340.000844 -333.173324)
			)
			(arc
				(start 340.000844 -333.173324)
				(mid 339.97233 -333.312898)
				(end 339.89137 -333.430118)
			)
			(arc
				(start 339.89137 -333.430118)
				(mid 339.860049 -333.503524)
				(end 339.89137 -333.57693)
			)
			(arc
				(start 339.89137 -333.57693)
				(mid 339.972348 -333.694142)
				(end 340.000844 -333.833724)
			)
			(arc
				(start 340.000844 -333.833724)
				(mid 339.915248 -334.065318)
				(end 339.6996 -334.185514)
			)
			(arc
				(start 339.6996 -334.185514)
				(mid 339.669804 -334.201568)
				(end 339.656674 -334.232758)
			)
			(arc
				(start 339.656674 -334.232758)
				(mid 339.634854 -334.321964)
				(end 339.58276 -334.397604)
			)
			(arc
				(start 339.23605 -334.744314)
				(mid 339.153673 -334.79942)
				(end 339.056472 -334.818736)
			)
			(xy 333.796132 -334.818736) (xy 331.799946 -336.814922)
			(arc
				(start 331.813154 -336.846164)
				(mid 331.833482 -336.913149)
				(end 331.840332 -336.982816)
			)
			(arc
				(start 331.840332 -336.982816)
				(mid 331.807506 -337.132407)
				(end 331.714856 -337.254342)
			)
			(xy 331.696822 -337.269582) (xy 331.696822 -337.35645)
			(arc
				(start 331.714856 -337.37169)
				(mid 331.807464 -337.493644)
				(end 331.840332 -337.643216)
			)
			(arc
				(start 331.840332 -337.643216)
				(mid 331.807506 -337.792807)
				(end 331.714856 -337.914742)
			)
			(xy 331.696822 -337.929982) (xy 331.696822 -338.01685)
			(arc
				(start 331.714856 -338.03209)
				(mid 331.807464 -338.154044)
				(end 331.840332 -338.303616)
			)
			(arc
				(start 331.840332 -338.303616)
				(mid 331.807506 -338.453207)
				(end 331.714856 -338.575142)
			)
			(xy 331.696822 -338.590382) (xy 331.696822 -338.67725)
			(arc
				(start 331.714856 -338.69249)
				(mid 331.807464 -338.814444)
				(end 331.840332 -338.964016)
			)
			(arc
				(start 331.840332 -338.964016)
				(mid 331.807506 -339.113607)
				(end 331.714856 -339.235542)
			)
			(xy 331.696822 -339.250782) (xy 331.696822 -339.33765)
			(arc
				(start 331.714856 -339.35289)
				(mid 331.807464 -339.474844)
				(end 331.840332 -339.624416)
			)
			(arc
				(start 331.840332 -339.624416)
				(mid 331.802368 -339.784467)
				(end 331.696568 -339.91042)
			)
			(arc
				(start 331.696568 -339.91042)
				(mid 331.680064 -340.014855)
				(end 331.6224 -340.10346)
			)
			(arc
				(start 331.242924 -340.482936)
				(mid 331.160547 -340.538042)
				(end 331.063346 -340.557358)
			)
			(arc
				(start 325.450962 -340.557358)
				(mid 325.322658 -340.674316)
				(end 325.15429 -340.716616)
			)
			(xy 325.126096 -340.7156) (xy 325.102728 -340.713568) (xy 324.459854 -341.356442) (xy 324.459854 -345.813888)
			(arc
				(start 324.489572 -345.827604)
				(mid 324.711852 -346.174314)
				(end 324.489572 -346.521024)
			)
			(xy 324.459854 -346.53474) (xy 324.459854 -347.48216) (xy 325.980298 -349.002604) (xy 330.610718 -349.002604)
		)
		(stroke
			(width 0)
			(type solid)
		)
		(fill yes)
		(layer "In8.Cu")
		(net "GND")
	)
	(gr_poly
		(pts
			(xy 329.0062 -82.153252) (xy 329.0062 -80.507586) (xy 328.978768 -80.493362) (xy 328.954418 -80.480076)
			(xy 328.909492 -80.44754) (xy 328.869748 -80.408845) (xy 328.836022 -80.364806) (xy 328.809024 -80.31635)
			(xy 328.789323 -80.264497) (xy 328.777333 -80.210339) (xy 328.773306 -80.155016) (xy 328.777328 -80.099692)
			(xy 328.789314 -80.045533) (xy 328.809011 -79.993679) (xy 328.836005 -79.94522) (xy 328.869727 -79.901179)
			(xy 328.909468 -79.862481) (xy 328.954391 -79.829941) (xy 328.978768 -79.816706) (xy 329.0062 -79.802482)
			(xy 329.0062 -76.594208) (xy 329.00565 -76.579087) (xy 328.996799 -76.550168) (xy 328.979871 -76.525107)
			(xy 328.956347 -76.506099) (xy 328.92829 -76.49481) (xy 328.898158 -76.492229) (xy 328.883264 -76.494894)
			(xy 328.863435 -76.498846) (xy 328.823218 -76.503043) (xy 328.803 -76.503276) (xy 327.9394 -76.503276)
			(xy 327.912151 -76.50279) (xy 327.858208 -76.495034) (xy 327.805918 -76.47968) (xy 327.756345 -76.457041)
			(xy 327.710498 -76.427577) (xy 327.669311 -76.391889) (xy 327.633623 -76.350702) (xy 327.604159 -76.304855)
			(xy 327.58152 -76.255282) (xy 327.566166 -76.202992) (xy 327.55841 -76.149049) (xy 327.55841 -76.094551)
			(xy 327.566166 -76.040608) (xy 327.58152 -75.988318) (xy 327.604159 -75.938745) (xy 327.633623 -75.892898)
			(xy 327.669311 -75.851711) (xy 327.710498 -75.816023) (xy 327.756345 -75.786559) (xy 327.805918 -75.76392)
			(xy 327.858208 -75.748566) (xy 327.912151 -75.74081) (xy 327.9394 -75.74026) (xy 328.803 -75.74026)
			(xy 328.823218 -75.740484) (xy 328.863436 -75.744683) (xy 328.883264 -75.748642) (xy 328.898161 -75.751278)
			(xy 328.928289 -75.748698) (xy 328.956342 -75.737412) (xy 328.979864 -75.718411) (xy 328.996795 -75.693358)
			(xy 329.005653 -75.664447) (xy 329.0062 -75.649328) (xy 329.0062 -57.648348) (xy 329.006816 -57.623393)
			(xy 329.016563 -57.574445) (xy 329.03567 -57.528338) (xy 329.063405 -57.486844) (xy 329.080622 -57.46877)
			(xy 329.791822 -56.75757) (xy 329.809862 -56.740308) (xy 329.851355 -56.712546) (xy 329.897473 -56.693427)
			(xy 329.946438 -56.68369) (xy 329.9714 -56.683148) (xy 330.794106 -56.683148) (xy 330.81112 -56.663084)
			(xy 330.850045 -56.627699) (xy 330.89375 -56.59842) (xy 330.941284 -56.575886) (xy 330.991614 -56.560586)
			(xy 331.043648 -56.552851) (xy 331.096252 -56.552851) (xy 331.148286 -56.560586) (xy 331.198616 -56.575886)
			(xy 331.24615 -56.59842) (xy 331.289855 -56.627699) (xy 331.32878 -56.663084) (xy 331.345794 -56.683148)
			(xy 332.420468 -56.683148) (xy 332.437482 -56.663084) (xy 332.476407 -56.627699) (xy 332.520112 -56.59842)
			(xy 332.567646 -56.575886) (xy 332.617976 -56.560586) (xy 332.67001 -56.552851) (xy 332.722614 -56.552851)
			(xy 332.774648 -56.560586) (xy 332.824978 -56.575886) (xy 332.872512 -56.59842) (xy 332.916217 -56.627699)
			(xy 332.955142 -56.663084) (xy 332.972156 -56.683148) (xy 335.677764 -56.683148) (xy 335.694778 -56.663084)
			(xy 335.733703 -56.627699) (xy 335.777408 -56.59842) (xy 335.824942 -56.575886) (xy 335.875272 -56.560586)
			(xy 335.927306 -56.552851) (xy 335.97991 -56.552851) (xy 336.031944 -56.560586) (xy 336.082274 -56.575886)
			(xy 336.129808 -56.59842) (xy 336.173513 -56.627699) (xy 336.212438 -56.663084) (xy 336.229452 -56.683148)
			(xy 337.30565 -56.683148) (xy 337.322664 -56.663084) (xy 337.361589 -56.627699) (xy 337.405294 -56.59842)
			(xy 337.452828 -56.575886) (xy 337.503158 -56.560586) (xy 337.555192 -56.552851) (xy 337.607796 -56.552851)
			(xy 337.65983 -56.560586) (xy 337.71016 -56.575886) (xy 337.757694 -56.59842) (xy 337.801399 -56.627699)
			(xy 337.840324 -56.663084) (xy 337.857338 -56.683148) (xy 337.96097 -56.683148) (xy 337.974705 -56.682702)
			(xy 338.001182 -56.675389) (xy 338.024753 -56.661283) (xy 338.043711 -56.641405) (xy 338.056686 -56.617193)
			(xy 338.062738 -56.590399) (xy 338.061429 -56.562961) (xy 338.05749 -56.549798) (xy 338.049185 -56.522738)
			(xy 338.040246 -56.466847) (xy 338.03971 -56.438546) (xy 338.040227 -56.410559) (xy 338.048977 -56.355273)
			(xy 338.066269 -56.302036) (xy 338.091677 -56.252161) (xy 338.124576 -56.206875) (xy 338.164154 -56.167294)
			(xy 338.209437 -56.134392) (xy 338.259311 -56.10898) (xy 338.312545 -56.091684) (xy 338.367831 -56.082929)
			(xy 338.395818 -56.082438) (xy 338.422867 -56.082939) (xy 338.476341 -56.091128) (xy 338.527956 -56.107331)
			(xy 338.576517 -56.131171) (xy 338.599018 -56.146192) (xy 338.63407 -56.170322) (xy 338.709 -56.095392)
			(xy 338.709 -49.950878) (xy 338.686043 -49.935677) (xy 338.644679 -49.899341) (xy 338.609401 -49.857071)
			(xy 338.581051 -49.809874) (xy 338.560304 -49.758875) (xy 338.547655 -49.705291) (xy 338.543405 -49.650398)
			(xy 338.547655 -49.595505) (xy 338.560305 -49.541921) (xy 338.581053 -49.490922) (xy 338.609404 -49.443726)
			(xy 338.644682 -49.401456) (xy 338.686047 -49.365121) (xy 338.709 -49.349914) (xy 338.709 -45.150278)
			(xy 338.686043 -45.135077) (xy 338.644679 -45.098741) (xy 338.609401 -45.056471) (xy 338.581051 -45.009274)
			(xy 338.560304 -44.958275) (xy 338.547655 -44.904691) (xy 338.543405 -44.849798) (xy 338.547655 -44.794905)
			(xy 338.560305 -44.741321) (xy 338.581053 -44.690322) (xy 338.609404 -44.643126) (xy 338.644682 -44.600856)
			(xy 338.686047 -44.564521) (xy 338.709 -44.549314) (xy 338.709 -42.843704) (xy 338.535772 -42.670476)
			(xy 338.506308 -42.680128) (xy 338.479479 -42.688277) (xy 338.424106 -42.697076) (xy 338.396072 -42.697654)
			(xy 338.368635 -42.697145) (xy 338.314413 -42.688722) (xy 338.262124 -42.67208) (xy 338.213008 -42.647613)
			(xy 338.168226 -42.6159) (xy 338.128841 -42.577692) (xy 338.095784 -42.533894) (xy 338.082382 -42.509948)
			(xy 335.454498 -42.509948) (xy 335.441088 -42.533893) (xy 335.408044 -42.577708) (xy 335.368666 -42.615932)
			(xy 335.323887 -42.647659) (xy 335.274769 -42.672136) (xy 335.222476 -42.688784) (xy 335.168248 -42.697208)
			(xy 335.113368 -42.697208) (xy 335.05914 -42.688784) (xy 335.006847 -42.672136) (xy 334.957729 -42.647659)
			(xy 334.91295 -42.615932) (xy 334.873572 -42.577708) (xy 334.840528 -42.533893) (xy 334.827118 -42.509948)
			(xy 333.824072 -42.509948) (xy 333.810662 -42.533893) (xy 333.777618 -42.577708) (xy 333.73824 -42.615932)
			(xy 333.693461 -42.647659) (xy 333.644343 -42.672136) (xy 333.59205 -42.688784) (xy 333.537822 -42.697208)
			(xy 333.482942 -42.697208) (xy 333.428714 -42.688784) (xy 333.376421 -42.672136) (xy 333.327303 -42.647659)
			(xy 333.282524 -42.615932) (xy 333.243146 -42.577708) (xy 333.210102 -42.533893) (xy 333.196692 -42.509948)
			(xy 332.195678 -42.509948) (xy 332.182268 -42.533893) (xy 332.149224 -42.577708) (xy 332.109846 -42.615932)
			(xy 332.065067 -42.647659) (xy 332.015949 -42.672136) (xy 331.963656 -42.688784) (xy 331.909428 -42.697208)
			(xy 331.854548 -42.697208) (xy 331.80032 -42.688784) (xy 331.748027 -42.672136) (xy 331.698909 -42.647659)
			(xy 331.65413 -42.615932) (xy 331.614752 -42.577708) (xy 331.581708 -42.533893) (xy 331.568298 -42.509948)
			(xy 330.567538 -42.509948) (xy 330.554128 -42.533893) (xy 330.521084 -42.577708) (xy 330.481706 -42.615932)
			(xy 330.436927 -42.647659) (xy 330.387809 -42.672136) (xy 330.335516 -42.688784) (xy 330.281288 -42.697208)
			(xy 330.226408 -42.697208) (xy 330.17218 -42.688784) (xy 330.119887 -42.672136) (xy 330.070769 -42.647659)
			(xy 330.02599 -42.615932) (xy 329.986612 -42.577708) (xy 329.953568 -42.533893) (xy 329.940158 -42.509948)
			(xy 328.939398 -42.509948) (xy 328.925988 -42.533893) (xy 328.892944 -42.577708) (xy 328.853566 -42.615932)
			(xy 328.808787 -42.647659) (xy 328.759669 -42.672136) (xy 328.707376 -42.688784) (xy 328.653148 -42.697208)
			(xy 328.598268 -42.697208) (xy 328.54404 -42.688784) (xy 328.491747 -42.672136) (xy 328.442629 -42.647659)
			(xy 328.39785 -42.615932) (xy 328.358472 -42.577708) (xy 328.325428 -42.533893) (xy 328.312018 -42.509948)
			(xy 323.123052 -42.509948) (xy 323.11467 -42.512996) (xy 323.089553 -42.521622) (xy 323.0376 -42.532632)
			(xy 322.984622 -42.536326) (xy 322.931644 -42.532632) (xy 322.879691 -42.521622) (xy 322.854574 -42.512996)
			(xy 322.846192 -42.509948) (xy 274.526756 -42.509948) (xy 274.25396 -42.782744) (xy 274.25396 -55.908448)
			(xy 274.253384 -55.933406) (xy 274.243636 -55.982362) (xy 274.224523 -56.028475) (xy 274.196782 -56.069973)
			(xy 274.179538 -56.088026) (xy 272.4912 -57.776364) (xy 272.4912 -74.760836) (xy 287.494472 -74.760836)
			(xy 287.494472 -66.060828) (xy 287.494977 -65.955304) (xy 287.503061 -65.74441) (xy 287.519217 -65.533981)
			(xy 287.54342 -65.324324) (xy 287.575637 -65.115749) (xy 287.615819 -64.908561) (xy 287.663907 -64.703064)
			(xy 287.719831 -64.49956) (xy 287.783508 -64.298347) (xy 287.854846 -64.09972) (xy 287.93374 -63.903972)
			(xy 288.020073 -63.71139) (xy 288.11372 -63.522255) (xy 288.214542 -63.336846) (xy 288.322392 -63.155435)
			(xy 288.437111 -62.978288) (xy 288.558531 -62.805666) (xy 288.686474 -62.63782) (xy 288.820752 -62.474998)
			(xy 288.961168 -62.317439) (xy 289.107516 -62.165374) (xy 289.259581 -62.019026) (xy 289.41714 -61.87861)
			(xy 289.579962 -61.744332) (xy 289.747808 -61.616389) (xy 289.92043 -61.494969) (xy 290.097577 -61.38025)
			(xy 290.278988 -61.2724) (xy 290.464397 -61.171578) (xy 290.653532 -61.077931) (xy 290.846114 -60.991598)
			(xy 291.041862 -60.912704) (xy 291.240489 -60.841366) (xy 291.441702 -60.777689) (xy 291.645206 -60.721765)
			(xy 291.850703 -60.673677) (xy 292.057891 -60.633495) (xy 292.266466 -60.601278) (xy 292.476123 -60.577075)
			(xy 292.686552 -60.560919) (xy 292.897446 -60.552835) (xy 293.108494 -60.552835) (xy 293.319388 -60.560919)
			(xy 293.529817 -60.577075) (xy 293.739474 -60.601278) (xy 293.948049 -60.633495) (xy 294.155237 -60.673677)
			(xy 294.360734 -60.721765) (xy 294.564238 -60.777689) (xy 294.765451 -60.841366) (xy 294.964078 -60.912704)
			(xy 295.159826 -60.991598) (xy 295.352408 -61.077931) (xy 295.541543 -61.171578) (xy 295.726952 -61.2724)
			(xy 295.908363 -61.38025) (xy 296.08551 -61.494969) (xy 296.258132 -61.616389) (xy 296.425978 -61.744332)
			(xy 296.5888 -61.87861) (xy 296.746359 -62.019026) (xy 296.898424 -62.165374) (xy 297.044772 -62.317439)
			(xy 297.185188 -62.474998) (xy 297.319466 -62.63782) (xy 297.447409 -62.805666) (xy 297.568829 -62.978288)
			(xy 297.683548 -63.155435) (xy 297.791398 -63.336846) (xy 297.89222 -63.522255) (xy 297.985867 -63.71139)
			(xy 298.0722 -63.903972) (xy 298.151094 -64.09972) (xy 298.222432 -64.298347) (xy 298.286109 -64.49956)
			(xy 298.342033 -64.703064) (xy 298.390121 -64.908561) (xy 298.396302 -64.940434) (xy 325.410068 -64.940434)
			(xy 325.410068 -64.076834) (xy 325.410554 -64.049565) (xy 325.418316 -63.995581) (xy 325.433681 -63.943251)
			(xy 325.456338 -63.893641) (xy 325.485824 -63.84776) (xy 325.521539 -63.806543) (xy 325.562756 -63.770828)
			(xy 325.608637 -63.741342) (xy 325.658247 -63.718685) (xy 325.710577 -63.70332) (xy 325.764561 -63.695558)
			(xy 325.819099 -63.695558) (xy 325.873083 -63.70332) (xy 325.925413 -63.718685) (xy 325.975023 -63.741342)
			(xy 326.020904 -63.770828) (xy 326.062121 -63.806543) (xy 326.097836 -63.84776) (xy 326.127322 -63.893641)
			(xy 326.149979 -63.943251) (xy 326.165344 -63.995581) (xy 326.173106 -64.049565) (xy 326.173592 -64.076834)
			(xy 326.173592 -64.940434) (xy 326.173106 -64.967703) (xy 326.165344 -65.021687) (xy 326.149979 -65.074017)
			(xy 326.127322 -65.123627) (xy 326.097836 -65.169508) (xy 326.062121 -65.210725) (xy 326.020904 -65.24644)
			(xy 325.975023 -65.275926) (xy 325.925413 -65.298583) (xy 325.873083 -65.313948) (xy 325.819099 -65.32171)
			(xy 325.764561 -65.32171) (xy 325.710577 -65.313948) (xy 325.658247 -65.298583) (xy 325.608637 -65.275926)
			(xy 325.562756 -65.24644) (xy 325.521539 -65.210725) (xy 325.485824 -65.169508) (xy 325.456338 -65.123627)
			(xy 325.433681 -65.074017) (xy 325.418316 -65.021687) (xy 325.410554 -64.967703) (xy 325.410068 -64.940434)
			(xy 298.396302 -64.940434) (xy 298.430303 -65.115749) (xy 298.46252 -65.324324) (xy 298.486723 -65.533981)
			(xy 298.502879 -65.74441) (xy 298.510963 -65.955304) (xy 298.511468 -66.060828) (xy 298.511468 -68.449952)
			(xy 314.840884 -68.449952) (xy 314.844867 -68.321934) (xy 314.856802 -68.194412) (xy 314.876641 -68.067878)
			(xy 314.904308 -67.942822) (xy 314.939697 -67.819729) (xy 314.98267 -67.699073) (xy 315.033061 -67.581323)
			(xy 315.090675 -67.466933) (xy 315.155289 -67.356346) (xy 315.226653 -67.24999) (xy 315.304491 -67.148277)
			(xy 315.388502 -67.051599) (xy 315.478361 -66.960332) (xy 315.57372 -66.874827) (xy 315.674211 -66.795417)
			(xy 315.779444 -66.722407) (xy 315.889013 -66.656081) (xy 316.002493 -66.596695) (xy 316.119445 -66.544479)
			(xy 316.239418 -66.499635) (xy 316.361946 -66.462337) (xy 316.486557 -66.432728) (xy 316.612766 -66.410923)
			(xy 316.740088 -66.397007) (xy 316.868028 -66.391033) (xy 316.996092 -66.393025) (xy 317.123785 -66.402975)
			(xy 317.250612 -66.420844) (xy 317.376083 -66.446563) (xy 317.499712 -66.480033) (xy 317.621021 -66.521124)
			(xy 317.739541 -66.569678) (xy 317.854813 -66.625506) (xy 317.966391 -66.688392) (xy 318.073844 -66.758094)
			(xy 318.176756 -66.834341) (xy 318.274728 -66.916838) (xy 318.367382 -67.005267) (xy 318.454359 -67.099285)
			(xy 318.535323 -67.198528) (xy 318.60996 -67.302613) (xy 318.677982 -67.411137) (xy 318.739126 -67.52368)
			(xy 318.793154 -67.639806) (xy 318.839859 -67.759067) (xy 318.879059 -67.881) (xy 318.910602 -68.005135)
			(xy 318.934367 -68.130991) (xy 318.950261 -68.25808) (xy 318.958224 -68.385912) (xy 318.958722 -68.449952)
			(xy 318.958224 -68.513992) (xy 318.950261 -68.641824) (xy 318.934367 -68.768913) (xy 318.910602 -68.894769)
			(xy 318.879059 -69.018904) (xy 318.839859 -69.140837) (xy 318.793154 -69.260098) (xy 318.739126 -69.376224)
			(xy 318.677982 -69.488767) (xy 318.60996 -69.597291) (xy 318.535323 -69.701376) (xy 318.454359 -69.800619)
			(xy 318.367382 -69.894637) (xy 318.274728 -69.983066) (xy 318.176756 -70.065563) (xy 318.073844 -70.14181)
			(xy 317.966391 -70.211512) (xy 317.854813 -70.274398) (xy 317.739541 -70.330226) (xy 317.621021 -70.37878)
			(xy 317.499712 -70.419871) (xy 317.376083 -70.453341) (xy 317.250612 -70.47906) (xy 317.123785 -70.496929)
			(xy 316.996092 -70.506879) (xy 316.868028 -70.508871) (xy 316.740088 -70.502897) (xy 316.612766 -70.488981)
			(xy 316.486557 -70.467176) (xy 316.361946 -70.437567) (xy 316.239418 -70.400269) (xy 316.119445 -70.355425)
			(xy 316.002493 -70.303209) (xy 315.889013 -70.243823) (xy 315.779444 -70.177497) (xy 315.674211 -70.104487)
			(xy 315.57372 -70.025077) (xy 315.478361 -69.939572) (xy 315.388502 -69.848305) (xy 315.304491 -69.751627)
			(xy 315.226653 -69.649914) (xy 315.155289 -69.543558) (xy 315.090675 -69.432971) (xy 315.033061 -69.318581)
			(xy 314.98267 -69.200831) (xy 314.939697 -69.080175) (xy 314.904308 -68.957082) (xy 314.876641 -68.832026)
			(xy 314.856802 -68.705492) (xy 314.844867 -68.57797) (xy 314.840884 -68.449952) (xy 298.511468 -68.449952)
			(xy 298.511468 -74.617072) (xy 327.277726 -74.617072) (xy 327.281813 -74.561227) (xy 327.293988 -74.506573)
			(xy 327.31399 -74.454274) (xy 327.341395 -74.405445) (xy 327.375617 -74.361126) (xy 327.415927 -74.322262)
			(xy 327.461466 -74.289681) (xy 327.511264 -74.264078) (xy 327.564259 -74.245999) (xy 327.619321 -74.235828)
			(xy 327.675278 -74.233783) (xy 327.730936 -74.239908) (xy 327.785109 -74.25407) (xy 327.836643 -74.27597)
			(xy 327.884439 -74.305139) (xy 327.927478 -74.340957) (xy 327.964844 -74.38266) (xy 327.99574 -74.429358)
			(xy 328.019507 -74.480058) (xy 328.035639 -74.533678) (xy 328.043791 -74.589075) (xy 328.044302 -74.617072)
			(xy 328.043791 -74.645069) (xy 328.035639 -74.700466) (xy 328.019507 -74.754086) (xy 327.99574 -74.804786)
			(xy 327.964844 -74.851484) (xy 327.927478 -74.893187) (xy 327.884439 -74.929005) (xy 327.836643 -74.958174)
			(xy 327.785109 -74.980074) (xy 327.730936 -74.994236) (xy 327.675278 -75.000361) (xy 327.619321 -74.998316)
			(xy 327.564259 -74.988145) (xy 327.511264 -74.970066) (xy 327.461466 -74.944463) (xy 327.415927 -74.911882)
			(xy 327.375617 -74.873018) (xy 327.341395 -74.828699) (xy 327.31399 -74.77987) (xy 327.293988 -74.727571)
			(xy 327.281813 -74.672917) (xy 327.277726 -74.617072) (xy 298.511468 -74.617072) (xy 298.511468 -74.760836)
			(xy 298.510963 -74.86636) (xy 298.502879 -75.077254) (xy 298.486723 -75.287683) (xy 298.46252 -75.49734)
			(xy 298.430303 -75.705915) (xy 298.390121 -75.913103) (xy 298.342033 -76.1186) (xy 298.286109 -76.322104)
			(xy 298.222432 -76.523317) (xy 298.151094 -76.721944) (xy 298.0722 -76.917692) (xy 297.985867 -77.110274)
			(xy 297.89222 -77.299409) (xy 297.791398 -77.484818) (xy 297.683548 -77.666229) (xy 297.568829 -77.843376)
			(xy 297.447409 -78.015998) (xy 297.319466 -78.183844) (xy 297.185188 -78.346666) (xy 297.044772 -78.504225)
			(xy 296.898424 -78.65629) (xy 296.746359 -78.802638) (xy 296.5888 -78.943054) (xy 296.425978 -79.077332)
			(xy 296.258132 -79.205275) (xy 296.08551 -79.326695) (xy 295.908363 -79.441414) (xy 295.726952 -79.549264)
			(xy 295.541543 -79.650086) (xy 295.352408 -79.743733) (xy 295.159826 -79.830066) (xy 294.964078 -79.90896)
			(xy 294.765451 -79.980298) (xy 294.564238 -80.043975) (xy 294.360734 -80.099899) (xy 294.155237 -80.147987)
			(xy 293.948049 -80.188169) (xy 293.739474 -80.220386) (xy 293.529817 -80.244589) (xy 293.319388 -80.260745)
			(xy 293.108494 -80.268829) (xy 292.897446 -80.268829) (xy 292.686552 -80.260745) (xy 292.476123 -80.244589)
			(xy 292.266466 -80.220386) (xy 292.057891 -80.188169) (xy 291.850703 -80.147987) (xy 291.645206 -80.099899)
			(xy 291.441702 -80.043975) (xy 291.240489 -79.980298) (xy 291.041862 -79.90896) (xy 290.846114 -79.830066)
			(xy 290.653532 -79.743733) (xy 290.464397 -79.650086) (xy 290.278988 -79.549264) (xy 290.097577 -79.441414)
			(xy 289.92043 -79.326695) (xy 289.747808 -79.205275) (xy 289.579962 -79.077332) (xy 289.41714 -78.943054)
			(xy 289.259581 -78.802638) (xy 289.107516 -78.65629) (xy 288.961168 -78.504225) (xy 288.820752 -78.346666)
			(xy 288.686474 -78.183844) (xy 288.558531 -78.015998) (xy 288.437111 -77.843376) (xy 288.322392 -77.666229)
			(xy 288.214542 -77.484818) (xy 288.11372 -77.299409) (xy 288.020073 -77.110274) (xy 287.93374 -76.917692)
			(xy 287.854846 -76.721944) (xy 287.783508 -76.523317) (xy 287.719831 -76.322104) (xy 287.663907 -76.1186)
			(xy 287.615819 -75.913103) (xy 287.575637 -75.705915) (xy 287.54342 -75.49734) (xy 287.519217 -75.287683)
			(xy 287.503061 -75.077254) (xy 287.494977 -74.86636) (xy 287.494472 -74.760836) (xy 272.4912 -74.760836)
			(xy 272.4912 -82.066892) (xy 274.140676 -83.716368) (xy 327.443084 -83.716368)
		)
		(stroke
			(width 0)
			(type solid)
		)
		(fill yes)
		(layer "In8.Cu")
		(net "P1V05_PCH_AUX")
	)
	(gr_poly
		(pts
			(xy 432.338226 -312.588402) (xy 432.348597 -312.587192) (xy 432.369441 -312.58592) (xy 432.379882 -312.585862)
			(xy 432.390323 -312.585918) (xy 432.411167 -312.587187) (xy 432.421538 -312.588402) (xy 432.42484 -312.58891)
			(xy 434.544724 -312.58891) (xy 434.548026 -312.588402) (xy 434.558397 -312.587192) (xy 434.579241 -312.58592)
			(xy 434.589682 -312.585862) (xy 434.600123 -312.585918) (xy 434.620967 -312.587187) (xy 434.631338 -312.588402)
			(xy 434.63464 -312.58891) (xy 435.806596 -312.58891) (xy 435.823614 -312.588402) (xy 435.840632 -312.58891)
			(xy 439.878724 -312.58891) (xy 439.882026 -312.588402) (xy 439.892397 -312.587192) (xy 439.913241 -312.58592)
			(xy 439.923682 -312.585862) (xy 439.934123 -312.585918) (xy 439.954967 -312.587187) (xy 439.965338 -312.588402)
			(xy 439.96864 -312.58891) (xy 442.088524 -312.58891) (xy 442.091826 -312.588402) (xy 442.102197 -312.587192)
			(xy 442.123041 -312.58592) (xy 442.133482 -312.585862) (xy 442.143923 -312.585918) (xy 442.164767 -312.587187)
			(xy 442.175138 -312.588402) (xy 442.17844 -312.58891) (xy 442.476382 -312.58891) (xy 443.092078 -311.973214)
			(xy 443.092078 -311.399936) (xy 443.078983 -311.379491) (xy 443.058283 -311.335576) (xy 443.04423 -311.289104)
			(xy 443.037127 -311.241077) (xy 443.037127 -311.192527) (xy 443.044229 -311.144499) (xy 443.058282 -311.098027)
			(xy 443.078981 -311.054111) (xy 443.092078 -311.033668) (xy 443.092078 -309.699914) (xy 443.078985 -309.679469)
			(xy 443.058288 -309.635554) (xy 443.044238 -309.589084) (xy 443.037138 -309.541057) (xy 443.03714 -309.492509)
			(xy 443.044245 -309.444484) (xy 443.0583 -309.398015) (xy 443.079001 -309.354101) (xy 443.092078 -309.333646)
			(xy 443.092078 -307.999892) (xy 443.078986 -307.979448) (xy 443.058292 -307.935533) (xy 443.044246 -307.889063)
			(xy 443.037149 -307.841038) (xy 443.037154 -307.792492) (xy 443.044261 -307.744469) (xy 443.058318 -307.698002)
			(xy 443.079021 -307.654091) (xy 443.092078 -307.633624) (xy 443.092078 -306.29987) (xy 443.078981 -306.279425)
			(xy 443.058275 -306.235509) (xy 443.044218 -306.189036) (xy 443.03711 -306.141006) (xy 443.037106 -306.092454)
			(xy 443.044205 -306.044423) (xy 443.058254 -305.997947) (xy 443.078951 -305.954027) (xy 443.092078 -305.933602)
			(xy 443.092078 -304.599848) (xy 443.078982 -304.579403) (xy 443.05828 -304.535487) (xy 443.044226 -304.489015)
			(xy 443.037121 -304.440987) (xy 443.037119 -304.392436) (xy 443.044221 -304.344407) (xy 443.058272 -304.297934)
			(xy 443.078971 -304.254017) (xy 443.092078 -304.23358) (xy 443.092078 -302.049942) (xy 443.078983 -302.029497)
			(xy 443.058282 -301.985582) (xy 443.044228 -301.93911) (xy 443.037124 -301.891082) (xy 443.037123 -301.842531)
			(xy 443.044225 -301.794503) (xy 443.058277 -301.748031) (xy 443.078976 -301.704114) (xy 443.092078 -301.683674)
			(xy 443.092078 -300.34992) (xy 443.078984 -300.329475) (xy 443.058286 -300.28556) (xy 443.044236 -300.239089)
			(xy 443.037135 -300.191063) (xy 443.037137 -300.142514) (xy 443.044241 -300.094488) (xy 443.058295 -300.048018)
			(xy 443.078996 -300.004104) (xy 443.092078 -299.983652) (xy 443.092078 -298.649898) (xy 443.078986 -298.629454)
			(xy 443.058291 -298.585539) (xy 443.044244 -298.539069) (xy 443.037146 -298.491043) (xy 443.03715 -298.442497)
			(xy 443.044257 -298.394473) (xy 443.058313 -298.348005) (xy 443.079015 -298.304094) (xy 443.092078 -298.28363)
			(xy 443.092078 -296.949876) (xy 443.07898 -296.929431) (xy 443.058274 -296.885515) (xy 443.044216 -296.839041)
			(xy 443.037107 -296.791011) (xy 443.037102 -296.742458) (xy 443.0442 -296.694427) (xy 443.058249 -296.647951)
			(xy 443.078946 -296.60403) (xy 443.092078 -296.583608) (xy 443.092078 -295.249854) (xy 443.078982 -295.229409)
			(xy 443.058279 -295.185493) (xy 443.044224 -295.139021) (xy 443.037118 -295.090992) (xy 443.037116 -295.042441)
			(xy 443.044216 -294.994412) (xy 443.058267 -294.947938) (xy 443.078965 -294.90402) (xy 443.092078 -294.883586)
			(xy 443.092078 -292.699948) (xy 443.078982 -292.679503) (xy 443.05828 -292.635587) (xy 443.044226 -292.589115)
			(xy 443.037121 -292.541087) (xy 443.037119 -292.492536) (xy 443.044221 -292.444507) (xy 443.058272 -292.398034)
			(xy 443.078971 -292.354117) (xy 443.092078 -292.33368) (xy 443.092078 -290.999926) (xy 443.078984 -290.979481)
			(xy 443.058285 -290.935566) (xy 443.044234 -290.889095) (xy 443.037132 -290.841068) (xy 443.037133 -290.792519)
			(xy 443.044237 -290.744492) (xy 443.05829 -290.698022) (xy 443.07899 -290.654107) (xy 443.092078 -290.633658)
			(xy 443.092078 -289.299904) (xy 443.078985 -289.27946) (xy 443.05829 -289.235544) (xy 443.044241 -289.189074)
			(xy 443.037143 -289.141049) (xy 443.037146 -289.092501) (xy 443.044252 -289.044477) (xy 443.058308 -288.998009)
			(xy 443.07901 -288.954097) (xy 443.092078 -288.933636) (xy 443.092078 -287.599882) (xy 443.07898 -287.579437)
			(xy 443.058273 -287.535521) (xy 443.044214 -287.489047) (xy 443.037104 -287.441017) (xy 443.037099 -287.392463)
			(xy 443.044196 -287.344431) (xy 443.058244 -287.297954) (xy 443.07894 -287.254032) (xy 443.092078 -287.233614)
			(xy 443.092078 -285.89986) (xy 443.078981 -285.879415) (xy 443.058278 -285.835499) (xy 443.044221 -285.789027)
			(xy 443.037115 -285.740998) (xy 443.037112 -285.692446) (xy 443.044212 -285.644416) (xy 443.058262 -285.597941)
			(xy 443.07896 -285.554022) (xy 443.092078 -285.533592) (xy 443.092078 -283.3497) (xy 443.078986 -283.329256)
			(xy 443.058291 -283.285341) (xy 443.044243 -283.23887) (xy 443.037145 -283.190845) (xy 443.037149 -283.142298)
			(xy 443.044255 -283.094274) (xy 443.058311 -283.047807) (xy 443.079014 -283.003895) (xy 443.092078 -282.983432)
			(xy 443.092078 -281.649932) (xy 443.078983 -281.629487) (xy 443.058284 -281.585572) (xy 443.044231 -281.5391)
			(xy 443.037129 -281.491073) (xy 443.037129 -281.442524) (xy 443.044232 -281.394496) (xy 443.058285 -281.348025)
			(xy 443.078985 -281.30411) (xy 443.092078 -281.283664) (xy 443.092078 -279.94991) (xy 443.078985 -279.929465)
			(xy 443.058288 -279.88555) (xy 443.044239 -279.83908) (xy 443.03714 -279.791054) (xy 443.037143 -279.742506)
			(xy 443.044248 -279.694481) (xy 443.058303 -279.648012) (xy 443.079005 -279.6041) (xy 443.092078 -279.583642)
			(xy 443.092078 -278.249888) (xy 443.078987 -278.229444) (xy 443.058293 -278.185529) (xy 443.044247 -278.139059)
			(xy 443.037151 -278.091035) (xy 443.037156 -278.042489) (xy 443.044264 -277.994466) (xy 443.058321 -277.948)
			(xy 443.079024 -277.90409) (xy 443.092078 -277.88362) (xy 443.092078 -276.549866) (xy 443.078981 -276.529421)
			(xy 443.058276 -276.485505) (xy 443.044219 -276.439032) (xy 443.037112 -276.391003) (xy 443.037108 -276.34245)
			(xy 443.044208 -276.29442) (xy 443.058257 -276.247945) (xy 443.078955 -276.204025) (xy 443.092078 -276.183598)
			(xy 443.092078 -273.999706) (xy 443.078985 -273.979262) (xy 443.058289 -273.935346) (xy 443.044241 -273.888876)
			(xy 443.037142 -273.84085) (xy 443.037145 -273.792303) (xy 443.044251 -273.744278) (xy 443.058306 -273.69781)
			(xy 443.079008 -273.653898) (xy 443.092078 -273.633438) (xy 443.092078 -272.299938) (xy 443.078983 -272.279493)
			(xy 443.058282 -272.235578) (xy 443.044229 -272.189106) (xy 443.037126 -272.141078) (xy 443.037126 -272.092528)
			(xy 443.044228 -272.044501) (xy 443.05828 -271.998029) (xy 443.07898 -271.954112) (xy 443.092078 -271.93367)
			(xy 443.092078 -270.599916) (xy 443.078985 -270.579471) (xy 443.058287 -270.535556) (xy 443.044237 -270.489085)
			(xy 443.037137 -270.441059) (xy 443.037139 -270.392511) (xy 443.044244 -270.344485) (xy 443.058298 -270.298016)
			(xy 443.078999 -270.254102) (xy 443.092078 -270.233648) (xy 443.092078 -268.899894) (xy 443.078986 -268.87945)
			(xy 443.058292 -268.835535) (xy 443.044245 -268.789065) (xy 443.037148 -268.74104) (xy 443.037153 -268.692494)
			(xy 443.04426 -268.64447) (xy 443.058316 -268.598003) (xy 443.079019 -268.554092) (xy 443.092078 -268.533626)
			(xy 443.092078 -268.045184) (xy 443.07785 -268.022243) (xy 443.056283 -267.97276) (xy 443.043104 -267.920415)
			(xy 443.038669 -267.866618) (xy 443.043098 -267.812822) (xy 443.056271 -267.760475) (xy 443.077832 -267.71099)
			(xy 443.092078 -267.68806) (xy 443.092078 -267.199872) (xy 443.07898 -267.179427) (xy 443.058275 -267.135511)
			(xy 443.044217 -267.089038) (xy 443.037109 -267.041008) (xy 443.037105 -266.992455) (xy 443.044203 -266.944424)
			(xy 443.058252 -266.897948) (xy 443.078949 -266.854028) (xy 443.092078 -266.833604) (xy 443.092078 -265.49985)
			(xy 443.078982 -265.479405) (xy 443.05828 -265.435489) (xy 443.044225 -265.389017) (xy 443.03712 -265.340989)
			(xy 443.037118 -265.292438) (xy 443.044219 -265.244409) (xy 443.05827 -265.197935) (xy 443.078969 -265.154018)
			(xy 443.092078 -265.133582) (xy 443.092078 -263.799828) (xy 443.078984 -263.779383) (xy 443.058285 -263.735468)
			(xy 443.044233 -263.688997) (xy 443.037131 -263.64097) (xy 443.037132 -263.59242) (xy 443.044235 -263.544394)
			(xy 443.058288 -263.497923) (xy 443.078989 -263.454008) (xy 443.092078 -263.43356) (xy 443.092078 -262.099806)
			(xy 443.078985 -262.079362) (xy 443.058289 -262.035446) (xy 443.044241 -261.988976) (xy 443.037142 -261.94095)
			(xy 443.037145 -261.892403) (xy 443.044251 -261.844378) (xy 443.058306 -261.79791) (xy 443.079008 -261.753998)
			(xy 443.092078 -261.733538) (xy 443.092078 -260.399784) (xy 443.07898 -260.379339) (xy 443.058272 -260.335423)
			(xy 443.044213 -260.288949) (xy 443.037103 -260.240918) (xy 443.037097 -260.192365) (xy 443.044195 -260.144332)
			(xy 443.058242 -260.097855) (xy 443.078939 -260.053933) (xy 443.092078 -260.033516) (xy 443.092078 -258.699762)
			(xy 443.078981 -258.679317) (xy 443.058277 -258.635401) (xy 443.044221 -258.588928) (xy 443.037114 -258.540899)
			(xy 443.037111 -258.492347) (xy 443.04421 -258.444317) (xy 443.05826 -258.397842) (xy 443.078958 -258.353923)
			(xy 443.092078 -258.333494) (xy 443.092078 -251.899928) (xy 443.078984 -251.879483) (xy 443.058285 -251.835568)
			(xy 443.044233 -251.789097) (xy 443.037131 -251.74107) (xy 443.037132 -251.69252) (xy 443.044235 -251.644494)
			(xy 443.058288 -251.598023) (xy 443.078989 -251.554108) (xy 443.092078 -251.53366) (xy 443.092078 -250.199906)
			(xy 443.078985 -250.179462) (xy 443.058289 -250.135546) (xy 443.044241 -250.089076) (xy 443.037142 -250.04105)
			(xy 443.037145 -249.992503) (xy 443.044251 -249.944478) (xy 443.058306 -249.89801) (xy 443.079008 -249.854098)
			(xy 443.092078 -249.833638) (xy 443.092078 -248.499884) (xy 443.07898 -248.479439) (xy 443.058272 -248.435523)
			(xy 443.044213 -248.389049) (xy 443.037103 -248.341018) (xy 443.037097 -248.292465) (xy 443.044195 -248.244432)
			(xy 443.058242 -248.197955) (xy 443.078939 -248.154033) (xy 443.092078 -248.133616) (xy 443.092078 -246.799862)
			(xy 443.078981 -246.779417) (xy 443.058277 -246.735501) (xy 443.044221 -246.689028) (xy 443.037114 -246.640999)
			(xy 443.037111 -246.592447) (xy 443.04421 -246.544417) (xy 443.05826 -246.497942) (xy 443.078958 -246.454023)
			(xy 443.092078 -246.433594) (xy 443.092078 -245.945152) (xy 443.077853 -245.922211) (xy 443.05629 -245.872729)
			(xy 443.043117 -245.820385) (xy 443.038687 -245.766592) (xy 443.043119 -245.712798) (xy 443.056296 -245.660455)
			(xy 443.077861 -245.610974) (xy 443.092078 -245.588028) (xy 443.092078 -245.09984) (xy 443.078983 -245.079395)
			(xy 443.058282 -245.03548) (xy 443.044229 -244.989008) (xy 443.037125 -244.94098) (xy 443.037124 -244.89243)
			(xy 443.044226 -244.844402) (xy 443.058278 -244.79793) (xy 443.078978 -244.754013) (xy 443.092078 -244.733572)
			(xy 443.092078 -244.24513) (xy 443.077854 -244.222189) (xy 443.056296 -244.172708) (xy 443.043126 -244.120365)
			(xy 443.038699 -244.066573) (xy 443.043134 -244.012782) (xy 443.056313 -243.960441) (xy 443.07788 -243.910964)
			(xy 443.092078 -243.888006) (xy 443.092078 -243.395246) (xy 443.077853 -243.372305) (xy 443.056292 -243.322823)
			(xy 443.043119 -243.27048) (xy 443.03869 -243.216687) (xy 443.043124 -243.162894) (xy 443.056301 -243.110551)
			(xy 443.077866 -243.061071) (xy 443.092078 -243.038122) (xy 443.092078 -242.549934) (xy 443.078983 -242.529489)
			(xy 443.058283 -242.485574) (xy 443.044231 -242.439102) (xy 443.037128 -242.391075) (xy 443.037128 -242.342525)
			(xy 443.044231 -242.294498) (xy 443.058283 -242.248026) (xy 443.078983 -242.204111) (xy 443.092078 -242.183666)
			(xy 443.092078 -240.849912) (xy 443.078985 -240.829467) (xy 443.058288 -240.785552) (xy 443.044239 -240.739082)
			(xy 443.037139 -240.691056) (xy 443.037142 -240.642508) (xy 443.044247 -240.594483) (xy 443.058301 -240.548013)
			(xy 443.079003 -240.504101) (xy 443.092078 -240.483644) (xy 443.092078 -239.14989) (xy 443.078986 -239.129446)
			(xy 443.058293 -239.085531) (xy 443.044247 -239.039061) (xy 443.03715 -238.991037) (xy 443.037155 -238.94249)
			(xy 443.044263 -238.894467) (xy 443.058319 -238.848001) (xy 443.079022 -238.804091) (xy 443.092078 -238.783622)
			(xy 443.092078 -236.59973) (xy 443.078984 -236.579285) (xy 443.058284 -236.53537) (xy 443.044232 -236.488899)
			(xy 443.03713 -236.440871) (xy 443.03713 -236.392322) (xy 443.044234 -236.344295) (xy 443.058287 -236.297824)
			(xy 443.078987 -236.253909) (xy 443.092078 -236.233462) (xy 443.092078 -234.899708) (xy 443.078985 -234.879264)
			(xy 443.058289 -234.835348) (xy 443.04424 -234.788878) (xy 443.037141 -234.740852) (xy 443.037144 -234.692305)
			(xy 443.04425 -234.64428) (xy 443.058304 -234.597811) (xy 443.079006 -234.553899) (xy 443.092078 -234.53344)
			(xy 443.092078 -233.19994) (xy 443.078983 -233.179495) (xy 443.058282 -233.13558) (xy 443.044229 -233.089108)
			(xy 443.037125 -233.04108) (xy 443.037124 -232.99253) (xy 443.044226 -232.944502) (xy 443.058278 -232.89803)
			(xy 443.078978 -232.854113) (xy 443.092078 -232.833672) (xy 443.092078 -231.499918) (xy 443.078984 -231.479473)
			(xy 443.058287 -231.435558) (xy 443.044236 -231.389087) (xy 443.037136 -231.341061) (xy 443.037138 -231.292512)
			(xy 443.044242 -231.244487) (xy 443.058296 -231.198017) (xy 443.078998 -231.154103) (xy 443.092078 -231.13365)
			(xy 443.092078 -229.799896) (xy 443.078986 -229.779452) (xy 443.058292 -229.735537) (xy 443.044244 -229.689067)
			(xy 443.037147 -229.641042) (xy 443.037151 -229.592495) (xy 443.044258 -229.544471) (xy 443.058314 -229.498004)
			(xy 443.079017 -229.454093) (xy 443.092078 -229.433628) (xy 443.092078 -227.249736) (xy 443.078983 -227.229291)
			(xy 443.058283 -227.185376) (xy 443.04423 -227.138904) (xy 443.037127 -227.090877) (xy 443.037127 -227.042327)
			(xy 443.044229 -226.994299) (xy 443.058282 -226.947827) (xy 443.078981 -226.903911) (xy 443.092078 -226.883468)
			(xy 443.092078 -225.549714) (xy 443.078985 -225.529269) (xy 443.058288 -225.485354) (xy 443.044238 -225.438884)
			(xy 443.037138 -225.390857) (xy 443.03714 -225.342309) (xy 443.044245 -225.294284) (xy 443.0583 -225.247815)
			(xy 443.079001 -225.203901) (xy 443.092078 -225.183446) (xy 443.092078 -223.849692) (xy 443.078986 -223.829248)
			(xy 443.058292 -223.785333) (xy 443.044246 -223.738863) (xy 443.037149 -223.690838) (xy 443.037154 -223.642292)
			(xy 443.044261 -223.594269) (xy 443.058318 -223.547802) (xy 443.079021 -223.503891) (xy 443.092078 -223.483424)
			(xy 443.092078 -222.149924) (xy 443.078984 -222.129479) (xy 443.058285 -222.085564) (xy 443.044234 -222.039093)
			(xy 443.037133 -221.991066) (xy 443.037134 -221.942517) (xy 443.044238 -221.894491) (xy 443.058291 -221.84802)
			(xy 443.078992 -221.804106) (xy 443.092078 -221.783656) (xy 443.092078 -220.449902) (xy 443.078986 -220.429458)
			(xy 443.05829 -220.385543) (xy 443.044242 -220.339072) (xy 443.037144 -220.291047) (xy 443.037148 -220.2425)
			(xy 443.044254 -220.194476) (xy 443.058309 -220.148008) (xy 443.079012 -220.104096) (xy 443.092078 -220.083634)
			(xy 443.092078 -217.899742) (xy 443.078983 -217.879297) (xy 443.058282 -217.835382) (xy 443.044228 -217.78891)
			(xy 443.037124 -217.740882) (xy 443.037123 -217.692331) (xy 443.044225 -217.644303) (xy 443.058277 -217.597831)
			(xy 443.078976 -217.553914) (xy 443.092078 -217.533474) (xy 443.092078 -216.19972) (xy 443.078984 -216.179275)
			(xy 443.058286 -216.13536) (xy 443.044236 -216.088889) (xy 443.037135 -216.040863) (xy 443.037137 -215.992314)
			(xy 443.044241 -215.944288) (xy 443.058295 -215.897818) (xy 443.078996 -215.853904) (xy 443.092078 -215.833452)
			(xy 443.092078 -214.499698) (xy 443.078986 -214.479254) (xy 443.058291 -214.435339) (xy 443.044244 -214.388869)
			(xy 443.037146 -214.340843) (xy 443.03715 -214.292297) (xy 443.044257 -214.244273) (xy 443.058313 -214.197805)
			(xy 443.079015 -214.153894) (xy 443.092078 -214.13343) (xy 443.092078 -212.79993) (xy 443.078984 -212.779485)
			(xy 443.058284 -212.73557) (xy 443.044232 -212.689099) (xy 443.03713 -212.641071) (xy 443.03713 -212.592522)
			(xy 443.044234 -212.544495) (xy 443.058287 -212.498024) (xy 443.078987 -212.454109) (xy 443.092078 -212.433662)
			(xy 443.092078 -211.099908) (xy 443.078985 -211.079464) (xy 443.058289 -211.035548) (xy 443.04424 -210.989078)
			(xy 443.037141 -210.941052) (xy 443.037144 -210.892505) (xy 443.04425 -210.84448) (xy 443.058304 -210.798011)
			(xy 443.079006 -210.754099) (xy 443.092078 -210.73364) (xy 443.092078 -208.549748) (xy 443.078982 -208.529303)
			(xy 443.05828 -208.485387) (xy 443.044226 -208.438915) (xy 443.037121 -208.390887) (xy 443.037119 -208.342336)
			(xy 443.044221 -208.294307) (xy 443.058272 -208.247834) (xy 443.078971 -208.203917) (xy 443.092078 -208.18348)
			(xy 443.092078 -206.849726) (xy 443.078984 -206.829281) (xy 443.058285 -206.785366) (xy 443.044234 -206.738895)
			(xy 443.037132 -206.690868) (xy 443.037133 -206.642319) (xy 443.044237 -206.594292) (xy 443.05829 -206.547822)
			(xy 443.07899 -206.503907) (xy 443.092078 -206.483458) (xy 443.092078 -205.149704) (xy 443.078985 -205.12926)
			(xy 443.05829 -205.085344) (xy 443.044241 -205.038874) (xy 443.037143 -204.990849) (xy 443.037146 -204.942301)
			(xy 443.044252 -204.894277) (xy 443.058308 -204.847809) (xy 443.07901 -204.803897) (xy 443.092078 -204.783436)
			(xy 443.092078 -203.449936) (xy 443.078983 -203.429491) (xy 443.058283 -203.385576) (xy 443.04423 -203.339104)
			(xy 443.037127 -203.291077) (xy 443.037127 -203.242527) (xy 443.044229 -203.194499) (xy 443.058282 -203.148027)
			(xy 443.078981 -203.104111) (xy 443.092078 -203.083668) (xy 443.092078 -201.749914) (xy 443.078985 -201.729469)
			(xy 443.058288 -201.685554) (xy 443.044238 -201.639084) (xy 443.037138 -201.591057) (xy 443.03714 -201.542509)
			(xy 443.044245 -201.494484) (xy 443.0583 -201.448015) (xy 443.079001 -201.404101) (xy 443.092078 -201.383646)
			(xy 443.092078 -199.199754) (xy 443.078982 -199.179309) (xy 443.058279 -199.135393) (xy 443.044224 -199.088921)
			(xy 443.037118 -199.040892) (xy 443.037116 -198.992341) (xy 443.044216 -198.944312) (xy 443.058267 -198.897838)
			(xy 443.078965 -198.85392) (xy 443.092078 -198.833486) (xy 443.092078 -197.499732) (xy 443.078983 -197.479287)
			(xy 443.058284 -197.435372) (xy 443.044231 -197.3889) (xy 443.037129 -197.340873) (xy 443.037129 -197.292324)
			(xy 443.044232 -197.244296) (xy 443.058285 -197.197825) (xy 443.078985 -197.15391) (xy 443.092078 -197.133464)
			(xy 443.092078 -195.79971) (xy 443.078985 -195.779265) (xy 443.058288 -195.73535) (xy 443.044239 -195.68888)
			(xy 443.03714 -195.640854) (xy 443.037143 -195.592306) (xy 443.044248 -195.544281) (xy 443.058303 -195.497812)
			(xy 443.079005 -195.4539) (xy 443.092078 -195.433442) (xy 443.092078 -194.992498) (xy 443.075233 -194.971148)
			(xy 443.047543 -194.924346) (xy 443.027292 -194.873877) (xy 443.01495 -194.820916) (xy 443.010804 -194.766694)
			(xy 443.014952 -194.712472) (xy 443.027296 -194.659511) (xy 443.047549 -194.609043) (xy 443.07524 -194.562242)
			(xy 443.092078 -194.540886) (xy 443.092078 -170.642026) (xy 442.595762 -170.14571) (xy 428.295308 -170.14571)
			(xy 428.285148 -170.183048) (xy 428.273602 -170.223103) (xy 428.243837 -170.300973) (xy 428.20671 -170.375614)
			(xy 428.162568 -170.446333) (xy 428.111821 -170.512472) (xy 428.05494 -170.573417) (xy 427.992453 -170.6286)
			(xy 427.924943 -170.677509) (xy 427.853037 -170.719689) (xy 427.777402 -170.754748) (xy 427.698743 -170.78236)
			(xy 427.61779 -170.802268) (xy 427.535296 -170.814288) (xy 427.452028 -170.818307) (xy 427.36876 -170.814288)
			(xy 427.286266 -170.802268) (xy 427.205313 -170.78236) (xy 427.126654 -170.754748) (xy 427.051019 -170.719689)
			(xy 426.979113 -170.677509) (xy 426.911603 -170.6286) (xy 426.849116 -170.573417) (xy 426.792235 -170.512472)
			(xy 426.741488 -170.446333) (xy 426.697346 -170.375614) (xy 426.660219 -170.300973) (xy 426.630454 -170.223103)
			(xy 426.618908 -170.183048) (xy 426.608748 -170.14571) (xy 421.489632 -170.14571) (xy 421.464678 -170.145092)
			(xy 421.415731 -170.135344) (xy 421.369626 -170.116235) (xy 421.328134 -170.088499) (xy 421.310054 -170.071288)
			(xy 420.87673 -169.637964) (xy 420.859471 -169.619922) (xy 420.831716 -169.578428) (xy 420.812603 -169.53231)
			(xy 420.80287 -169.483347) (xy 420.802308 -169.458386) (xy 420.802308 -162.494468) (xy 420.8018 -162.490404)
			(xy 420.799797 -162.47684) (xy 420.797637 -162.449504) (xy 420.797482 -162.435794) (xy 420.797644 -162.422084)
			(xy 420.799803 -162.394749) (xy 420.8018 -162.381184) (xy 420.802308 -162.37712) (xy 420.802308 -157.980634)
			(xy 420.774368 -157.96641) (xy 420.751078 -157.954233) (xy 420.708045 -157.924065) (xy 420.669916 -157.887897)
			(xy 420.637521 -157.846515) (xy 420.611562 -157.800819) (xy 420.592606 -157.751803) (xy 420.581063 -157.700532)
			(xy 420.577185 -157.648122) (xy 420.581057 -157.59571) (xy 420.592593 -157.544438) (xy 420.611544 -157.49542)
			(xy 420.637497 -157.449721) (xy 420.669887 -157.408335) (xy 420.708012 -157.372162) (xy 420.751041 -157.341989)
			(xy 420.774368 -157.329886) (xy 420.802308 -157.315662) (xy 420.802308 -155.594812) (xy 420.76497 -155.584652)
			(xy 420.738503 -155.576832) (xy 420.687982 -155.554621) (xy 420.641189 -155.525364) (xy 420.599099 -155.489669)
			(xy 420.562591 -155.448284) (xy 420.532426 -155.402069) (xy 420.509234 -155.351992) (xy 420.493499 -155.299095)
			(xy 420.48555 -155.244483) (xy 420.485551 -155.189296) (xy 420.493504 -155.134684) (xy 420.509242 -155.081788)
			(xy 420.532436 -155.031712) (xy 420.562604 -154.985499) (xy 420.599114 -154.944116) (xy 420.641206 -154.908424)
			(xy 420.688001 -154.879169) (xy 420.738523 -154.856961) (xy 420.76497 -154.849068) (xy 420.802308 -154.838908)
			(xy 420.802308 -150.879556) (xy 420.801871 -150.865957) (xy 420.794685 -150.839724) (xy 420.780833 -150.816317)
			(xy 420.761296 -150.797393) (xy 420.73746 -150.784293) (xy 420.711012 -150.777946) (xy 420.697406 -150.777956)
			(xy 420.684452 -150.77821) (xy 420.657203 -150.777721) (xy 420.60326 -150.769959) (xy 420.550971 -150.7546)
			(xy 420.5014 -150.731956) (xy 420.455555 -150.702488) (xy 420.414371 -150.666797) (xy 420.378684 -150.625608)
			(xy 420.349222 -150.57976) (xy 420.326584 -150.530186) (xy 420.311231 -150.477895) (xy 420.303476 -150.423951)
			(xy 420.302944 -150.396702) (xy 420.303368 -150.371243) (xy 420.310147 -150.320778) (xy 420.323584 -150.271665)
			(xy 420.343441 -150.224779) (xy 420.35603 -150.202646) (xy 420.376096 -150.168864) (xy 418.822378 -148.615146)
			(xy 410.957268 -148.615146) (xy 410.951788 -148.622299) (xy 410.939968 -148.635903) (xy 410.933646 -148.642324)
			(xy 410.474668 -149.101302) (xy 410.474668 -164.785548) (xy 410.504386 -164.79901) (xy 410.528949 -164.810713)
			(xy 410.574506 -164.840455) (xy 410.615011 -164.876779) (xy 410.64952 -164.918841) (xy 410.677231 -164.965662)
			(xy 410.697498 -165.016153) (xy 410.709851 -165.069139) (xy 410.714003 -165.123387) (xy 410.709855 -165.177635)
			(xy 410.697506 -165.230622) (xy 410.677242 -165.281114) (xy 410.649535 -165.327937) (xy 410.615029 -165.370002)
			(xy 410.574527 -165.406329) (xy 410.528972 -165.436075) (xy 410.504386 -165.447726) (xy 410.474668 -165.461188)
			(xy 410.474668 -166.733728) (xy 410.504386 -166.74719) (xy 410.527433 -166.758116) (xy 410.570409 -166.785584)
			(xy 410.609026 -166.818902) (xy 410.642493 -166.85739) (xy 410.670127 -166.90026) (xy 410.69136 -166.946634)
			(xy 410.70576 -166.995563) (xy 410.713031 -167.046046) (xy 410.713428 -167.071548) (xy 410.712877 -167.10025)
			(xy 410.703657 -167.15691) (xy 410.685463 -167.211355) (xy 410.658768 -167.262175) (xy 410.624263 -167.308052)
			(xy 410.603954 -167.328342) (xy 410.594382 -167.338136) (xy 410.580367 -167.361651) (xy 410.573103 -167.388045)
			(xy 410.573112 -167.415421) (xy 410.580393 -167.44181) (xy 410.594423 -167.465316) (xy 410.603954 -167.475154)
			(xy 410.624291 -167.49542) (xy 410.658805 -167.541298) (xy 410.685505 -167.592123) (xy 410.703696 -167.646575)
			(xy 410.712907 -167.703242) (xy 410.713428 -167.731948) (xy 410.712989 -167.757447) (xy 410.705709 -167.807922)
			(xy 410.691307 -167.856844) (xy 410.670075 -167.903211) (xy 410.642447 -167.946078) (xy 410.60899 -167.984566)
			(xy 410.570386 -168.01789) (xy 410.527424 -168.045368) (xy 410.504386 -168.056306) (xy 410.474668 -168.069768)
			(xy 410.474668 -173.421548) (xy 410.504386 -173.43501) (xy 410.528949 -173.446713) (xy 410.574506 -173.476455)
			(xy 410.615011 -173.512779) (xy 410.64952 -173.554841) (xy 410.677231 -173.601662) (xy 410.697498 -173.652153)
			(xy 410.709851 -173.705139) (xy 410.714003 -173.759387) (xy 410.709855 -173.813635) (xy 410.697506 -173.866622)
			(xy 410.677242 -173.917114) (xy 410.649535 -173.963937) (xy 410.615029 -174.006002) (xy 410.574527 -174.042329)
			(xy 410.528972 -174.072075) (xy 410.504386 -174.083726) (xy 410.474668 -174.097188) (xy 410.474668 -175.369728)
			(xy 410.504386 -175.38319) (xy 410.527433 -175.394116) (xy 410.570409 -175.421584) (xy 410.609026 -175.454902)
			(xy 410.642493 -175.49339) (xy 410.670127 -175.53626) (xy 410.69136 -175.582634) (xy 410.695605 -175.597058)
			(xy 434.095902 -175.597058) (xy 434.099991 -175.541176) (xy 434.112174 -175.486486) (xy 434.13219 -175.434152)
			(xy 434.159613 -175.38529) (xy 434.193858 -175.340942) (xy 434.234194 -175.302052) (xy 434.279764 -175.26945)
			(xy 434.329595 -175.243831) (xy 434.382625 -175.225739) (xy 434.437723 -175.215562) (xy 434.493717 -175.213516)
			(xy 434.549412 -175.219644) (xy 434.603621 -175.233816) (xy 434.655189 -175.25573) (xy 434.703017 -175.284919)
			(xy 434.746085 -175.32076) (xy 434.783475 -175.36249) (xy 434.814391 -175.40922) (xy 434.838174 -175.459953)
			(xy 434.854316 -175.513609) (xy 434.862475 -175.569043) (xy 434.862986 -175.597058) (xy 434.862475 -175.625073)
			(xy 434.854316 -175.680507) (xy 434.838174 -175.734163) (xy 434.814391 -175.784896) (xy 434.783475 -175.831626)
			(xy 434.746085 -175.873356) (xy 434.703017 -175.909197) (xy 434.655189 -175.938386) (xy 434.603621 -175.9603)
			(xy 434.549412 -175.974472) (xy 434.493717 -175.9806) (xy 434.437723 -175.978554) (xy 434.382625 -175.968377)
			(xy 434.329595 -175.950285) (xy 434.279764 -175.924666) (xy 434.234194 -175.892064) (xy 434.193858 -175.853174)
			(xy 434.159613 -175.808826) (xy 434.13219 -175.759964) (xy 434.112174 -175.70763) (xy 434.099991 -175.65294)
			(xy 434.095902 -175.597058) (xy 410.695605 -175.597058) (xy 410.70576 -175.631563) (xy 410.713031 -175.682046)
			(xy 410.713428 -175.707548) (xy 410.712877 -175.73625) (xy 410.703657 -175.79291) (xy 410.685463 -175.847355)
			(xy 410.658768 -175.898175) (xy 410.624263 -175.944052) (xy 410.603954 -175.964342) (xy 410.594382 -175.974136)
			(xy 410.580367 -175.997651) (xy 410.573103 -176.024045) (xy 410.573112 -176.051421) (xy 410.580393 -176.07781)
			(xy 410.594423 -176.101316) (xy 410.603954 -176.111154) (xy 410.624291 -176.13142) (xy 410.658805 -176.177298)
			(xy 410.685505 -176.228123) (xy 410.703696 -176.282575) (xy 410.712907 -176.339242) (xy 410.713428 -176.367948)
			(xy 410.712989 -176.393447) (xy 410.705709 -176.443922) (xy 410.691307 -176.492844) (xy 410.670075 -176.539211)
			(xy 410.642447 -176.582078) (xy 410.60899 -176.620566) (xy 410.570386 -176.65389) (xy 410.527424 -176.681368)
			(xy 410.504386 -176.692306) (xy 410.474668 -176.705768) (xy 410.474668 -182.057548) (xy 410.504386 -182.07101)
			(xy 410.528949 -182.082713) (xy 410.574506 -182.112455) (xy 410.615011 -182.148779) (xy 410.64952 -182.190841)
			(xy 410.677231 -182.237662) (xy 410.697498 -182.288153) (xy 410.709851 -182.341139) (xy 410.714003 -182.395387)
			(xy 410.709855 -182.449635) (xy 410.697506 -182.502622) (xy 410.677242 -182.553114) (xy 410.649535 -182.599937)
			(xy 410.615029 -182.642002) (xy 410.574527 -182.678329) (xy 410.528972 -182.708075) (xy 410.504386 -182.719726)
			(xy 410.474668 -182.733188) (xy 410.474668 -191.864488) (xy 410.489551 -191.887992) (xy 410.513089 -191.938396)
			(xy 410.529061 -191.991683) (xy 410.53713 -192.046724) (xy 410.537125 -192.102353) (xy 410.529045 -192.157392)
			(xy 410.513061 -192.210676) (xy 410.489513 -192.261076) (xy 410.474668 -192.284604) (xy 410.474668 -213.993984)
			(xy 411.02534 -214.544656) (xy 428.490634 -214.544656) (xy 428.515593 -214.545231) (xy 428.564549 -214.554977)
			(xy 428.610664 -214.574089) (xy 428.652162 -214.60183) (xy 428.670212 -214.619078) (xy 429.290734 -215.2396)
			(xy 429.30799 -215.257643) (xy 429.335739 -215.299138) (xy 429.354843 -215.345256) (xy 429.364564 -215.394218)
			(xy 429.365156 -215.419178) (xy 429.365156 -312.226706) (xy 429.38827 -312.241946) (xy 429.399376 -312.249351)
			(xy 429.420118 -312.266153) (xy 429.429672 -312.275474) (xy 429.743108 -312.58891) (xy 432.334924 -312.58891)
		)
		(stroke
			(width 0)
			(type solid)
		)
		(fill yes)
		(layer "In8.Cu")
		(net "GND")
	)
	(gr_poly
		(pts
			(xy 358.994964 -362.3056) (xy 359.004511 -362.279475) (xy 359.030096 -362.230089) (xy 359.06258 -362.18494)
			(xy 359.101275 -362.144987) (xy 359.145361 -362.111075) (xy 359.193904 -362.083924) (xy 359.245875 -362.064108)
			(xy 359.300171 -362.052048) (xy 359.355644 -362.048) (xy 359.411117 -362.052048) (xy 359.465413 -362.064108)
			(xy 359.517384 -362.083924) (xy 359.565927 -362.111075) (xy 359.610013 -362.144987) (xy 359.648708 -362.18494)
			(xy 359.681192 -362.230089) (xy 359.706777 -362.279475) (xy 359.716324 -362.3056) (xy 359.728008 -362.33989)
			(xy 363.395514 -362.33989) (xy 363.416832 -362.320662) (xy 363.464161 -362.288172) (xy 363.515824 -362.263141)
			(xy 363.570654 -362.246132) (xy 363.627414 -362.237531) (xy 363.684822 -362.237531) (xy 363.741582 -362.246132)
			(xy 363.796412 -362.263141) (xy 363.848075 -362.288172) (xy 363.895404 -362.320662) (xy 363.916722 -362.33989)
			(xy 383.885186 -362.33989) (xy 383.908491 -362.32533) (xy 383.9584 -362.302338) (xy 384.011095 -362.286757)
			(xy 384.065482 -362.27891) (xy 384.092958 -362.278422) (xy 384.120431 -362.278909) (xy 384.174807 -362.286798)
			(xy 384.227493 -362.302391) (xy 384.277405 -362.325366) (xy 384.30073 -362.33989) (xy 414.451292 -362.33989)
			(xy 414.474454 -362.324944) (xy 414.524249 -362.301303) (xy 414.576982 -362.28525) (xy 414.631503 -362.277135)
			(xy 414.686625 -362.277135) (xy 414.741146 -362.28525) (xy 414.793879 -362.301303) (xy 414.843674 -362.324944)
			(xy 414.866836 -362.33989) (xy 415.078672 -362.33989) (xy 415.101834 -362.324944) (xy 415.151629 -362.301303)
			(xy 415.204362 -362.28525) (xy 415.258883 -362.277135) (xy 415.314005 -362.277135) (xy 415.368526 -362.28525)
			(xy 415.421259 -362.301303) (xy 415.471054 -362.324944) (xy 415.494216 -362.33989) (xy 415.695892 -362.33989)
			(xy 415.719054 -362.324944) (xy 415.768849 -362.301303) (xy 415.821582 -362.28525) (xy 415.876103 -362.277135)
			(xy 415.931225 -362.277135) (xy 415.985746 -362.28525) (xy 416.038479 -362.301303) (xy 416.088274 -362.324944)
			(xy 416.111436 -362.33989) (xy 424.139614 -362.33989) (xy 424.162776 -362.324944) (xy 424.212571 -362.301303)
			(xy 424.265304 -362.28525) (xy 424.319825 -362.277135) (xy 424.374947 -362.277135) (xy 424.429468 -362.28525)
			(xy 424.482201 -362.301303) (xy 424.531996 -362.324944) (xy 424.555158 -362.33989) (xy 424.766994 -362.33989)
			(xy 424.790156 -362.324944) (xy 424.839951 -362.301303) (xy 424.892684 -362.28525) (xy 424.947205 -362.277135)
			(xy 425.002327 -362.277135) (xy 425.056848 -362.28525) (xy 425.109581 -362.301303) (xy 425.159376 -362.324944)
			(xy 425.182538 -362.33989) (xy 425.384214 -362.33989) (xy 425.407376 -362.324944) (xy 425.457171 -362.301303)
			(xy 425.509904 -362.28525) (xy 425.564425 -362.277135) (xy 425.619547 -362.277135) (xy 425.674068 -362.28525)
			(xy 425.726801 -362.301303) (xy 425.776596 -362.324944) (xy 425.799758 -362.33989) (xy 440.642502 -362.33989)
			(xy 445.131698 -357.850694) (xy 445.131698 -335.80959) (xy 445.13231 -335.784634) (xy 445.14205 -335.735681)
			(xy 445.161152 -335.689568) (xy 445.188883 -335.648068) (xy 445.20612 -335.630012) (xy 445.80302 -335.033112)
			(xy 445.821059 -335.015847) (xy 445.86255 -334.98808) (xy 445.908669 -334.968958) (xy 445.957635 -334.959219)
			(xy 445.982598 -334.95869) (xy 453.503792 -334.95869) (xy 453.960738 -334.501744) (xy 453.960738 -329.171046)
			(xy 453.02424 -328.234548) (xy 453.006982 -328.216506) (xy 452.979228 -328.175012) (xy 452.960117 -328.128894)
			(xy 452.950387 -328.079931) (xy 452.949818 -328.05497) (xy 452.949818 -327.83653) (xy 452.913405 -327.812576)
			(xy 452.844846 -327.758748) (xy 452.78172 -327.698642) (xy 452.724598 -327.632803) (xy 452.673999 -327.561828)
			(xy 452.630383 -327.48636) (xy 452.594145 -327.407086) (xy 452.565613 -327.324723) (xy 452.545047 -327.240019)
			(xy 452.532633 -327.153742) (xy 452.528484 -327.066676) (xy 452.532638 -326.97961) (xy 452.545056 -326.893335)
			(xy 452.565626 -326.808632) (xy 452.594162 -326.72627) (xy 452.630405 -326.646997) (xy 452.674025 -326.571532)
			(xy 452.724627 -326.500559) (xy 452.781752 -326.434723) (xy 452.844882 -326.37462) (xy 452.913444 -326.320797)
			(xy 452.949818 -326.296782) (xy 452.949818 -322.292726) (xy 452.765922 -322.10883) (xy 429.695356 -322.10883)
			(xy 429.381412 -322.422774) (xy 429.365156 -322.43776) (xy 429.365156 -323.256148) (xy 429.370744 -323.26707)
			(xy 429.383075 -323.292329) (xy 429.400506 -323.345765) (xy 429.409333 -323.401275) (xy 429.409336 -323.457482)
			(xy 429.400516 -323.512993) (xy 429.383092 -323.566431) (xy 429.370744 -323.591682) (xy 429.365156 -323.602604)
			(xy 429.365156 -328.8919) (xy 430.000156 -329.5269) (xy 430.017411 -329.544943) (xy 430.045157 -329.586439)
			(xy 430.06426 -329.632557) (xy 430.073981 -329.681519) (xy 430.074578 -329.706478) (xy 430.074578 -351.27819)
			(xy 430.073958 -351.303143) (xy 430.064205 -351.352087) (xy 430.045091 -351.398188) (xy 430.017351 -351.439674)
			(xy 430.000156 -351.457768) (xy 429.532796 -351.925128) (xy 429.514754 -351.942384) (xy 429.473259 -351.970133)
			(xy 429.42714 -351.989236) (xy 429.378178 -351.998958) (xy 429.353218 -351.99955) (xy 408.285696 -351.99955)
			(xy 408.260736 -351.998978) (xy 408.211776 -351.989237) (xy 408.165658 -351.97013) (xy 408.124154 -351.942391)
			(xy 408.106118 -351.925128) (xy 396.385034 -340.204044) (xy 396.367777 -340.186002) (xy 396.340024 -340.144507)
			(xy 396.320914 -340.098389) (xy 396.311185 -340.049426) (xy 396.310612 -340.024466) (xy 396.310612 -330.92644)
			(xy 396.045182 -330.66101) (xy 382.934718 -330.66101) (xy 382.909765 -330.660391) (xy 382.860819 -330.65064)
			(xy 382.814716 -330.631529) (xy 382.773225 -330.603793) (xy 382.75514 -330.586588) (xy 378.930408 -326.761856)
			(xy 375.186956 -326.761856) (xy 375.161998 -326.76128) (xy 375.113042 -326.751533) (xy 375.066928 -326.732421)
			(xy 375.02543 -326.704679) (xy 375.007378 -326.687434) (xy 373.483378 -325.163434) (xy 373.466119 -325.145393)
			(xy 373.438363 -325.103899) (xy 373.419252 -325.057781) (xy 373.409523 -325.008817) (xy 373.408956 -324.983856)
			(xy 373.408956 -323.742812) (xy 372.8974 -323.231256) (xy 342.077548 -323.231256) (xy 339.385656 -325.923148)
			(xy 339.367615 -325.940407) (xy 339.326121 -325.968164) (xy 339.280003 -325.987277) (xy 339.231039 -325.997009)
			(xy 339.206078 -325.99757) (xy 336.705194 -325.99757) (xy 330.024994 -332.67777) (xy 330.00695 -332.695023)
			(xy 329.965454 -332.722768) (xy 329.919336 -332.741868) (xy 329.870375 -332.751587) (xy 329.845416 -332.752192)
			(xy 318.953896 -332.752192) (xy 318.650874 -333.055214) (xy 318.650874 -338.704428) (xy 318.672557 -338.722634)
			(xy 318.710821 -338.764362) (xy 318.742494 -338.81129) (xy 318.766877 -338.862386) (xy 318.783436 -338.916527)
			(xy 318.791805 -338.972521) (xy 318.7918 -339.029137) (xy 318.783423 -339.08513) (xy 318.766856 -339.139268)
			(xy 318.742465 -339.19036) (xy 318.710785 -339.237283) (xy 318.672514 -339.279005) (xy 318.650874 -339.297264)
			(xy 318.650874 -344.98494) (xy 323.686468 -344.98494) (xy 323.686468 -344.928854) (xy 323.694682 -344.873372)
			(xy 323.710932 -344.819691) (xy 323.734868 -344.768969) (xy 323.765973 -344.722299) (xy 323.803578 -344.680687)
			(xy 323.846871 -344.64503) (xy 323.894919 -344.616098) (xy 323.920612 -344.604848) (xy 323.951854 -344.59164)
			(xy 323.951854 -341.251286) (xy 323.952386 -341.226323) (xy 323.962126 -341.177358) (xy 323.981247 -341.13124)
			(xy 324.009013 -341.089748) (xy 324.026276 -341.071708) (xy 324.774052 -340.323932) (xy 324.776592 -340.306914)
			(xy 324.780876 -340.279961) (xy 324.796164 -340.227571) (xy 324.81876 -340.177894) (xy 324.848205 -340.131944)
			(xy 324.883897 -340.090659) (xy 324.925108 -340.054881) (xy 324.970997 -340.025341) (xy 325.020627 -340.002641)
			(xy 325.072985 -339.987245) (xy 325.127003 -339.979467) (xy 325.15429 -339.979) (xy 325.183729 -339.979554)
			(xy 325.241906 -339.988609) (xy 325.298002 -340.006489) (xy 325.350688 -340.032772) (xy 325.375016 -340.049358)
			(xy 330.95819 -340.049358) (xy 331.168756 -339.838792) (xy 331.153178 -339.814953) (xy 331.128525 -339.76362)
			(xy 331.111763 -339.709197) (xy 331.103265 -339.652889) (xy 331.102716 -339.624416) (xy 331.10315 -339.598276)
			(xy 331.110302 -339.546488) (xy 331.124461 -339.496163) (xy 331.145361 -339.448243) (xy 331.172611 -339.403626)
			(xy 331.188822 -339.383116) (xy 331.188822 -339.205316) (xy 331.170877 -339.182472) (xy 331.141358 -339.132442)
			(xy 331.119771 -339.078513) (xy 331.106614 -339.021933) (xy 331.102194 -338.964012) (xy 331.106611 -338.906091)
			(xy 331.119763 -338.849511) (xy 331.141347 -338.795581) (xy 331.170862 -338.745549) (xy 331.188822 -338.722716)
			(xy 331.188822 -338.544916) (xy 331.170877 -338.522072) (xy 331.141358 -338.472042) (xy 331.119771 -338.418113)
			(xy 331.106614 -338.361533) (xy 331.102194 -338.303612) (xy 331.106611 -338.245691) (xy 331.119763 -338.189111)
			(xy 331.141347 -338.135181) (xy 331.170862 -338.085149) (xy 331.188822 -338.062316) (xy 331.188822 -337.884516)
			(xy 331.170877 -337.861672) (xy 331.141358 -337.811642) (xy 331.119771 -337.757713) (xy 331.106614 -337.701133)
			(xy 331.102194 -337.643212) (xy 331.106611 -337.585291) (xy 331.119763 -337.528711) (xy 331.141347 -337.474781)
			(xy 331.170862 -337.424749) (xy 331.188822 -337.401916) (xy 331.188822 -337.224116) (xy 331.172625 -337.203594)
			(xy 331.145364 -337.158985) (xy 331.124457 -337.111069) (xy 331.110297 -337.060744) (xy 331.103148 -337.008956)
			(xy 331.102716 -336.982816) (xy 331.103231 -336.954112) (xy 331.11183 -336.897352) (xy 331.128837 -336.842522)
			(xy 331.153868 -336.790859) (xy 331.186357 -336.743529) (xy 331.205586 -336.722212) (xy 331.215747 -336.697496)
			(xy 331.244819 -336.652668) (xy 331.263244 -336.633312) (xy 333.511398 -334.385158) (xy 333.52944 -334.367902)
			(xy 333.570942 -334.340163) (xy 333.617058 -334.321054) (xy 333.666017 -334.31131) (xy 333.690976 -334.310736)
			(xy 338.951316 -334.310736) (xy 339.149182 -334.11287) (xy 339.149182 -332.96606) (xy 339.149752 -332.941099)
			(xy 339.159479 -332.892135) (xy 339.178589 -332.846016) (xy 339.206345 -332.804523) (xy 339.223604 -332.786482)
			(xy 339.310218 -332.699868) (xy 339.296248 -332.667864) (xy 339.285823 -332.643378) (xy 339.271124 -332.592229)
			(xy 339.263686 -332.539533) (xy 339.263228 -332.512924) (xy 339.263678 -332.48567) (xy 339.271432 -332.431717)
			(xy 339.286787 -332.379417) (xy 339.30943 -332.329834) (xy 339.338898 -332.283979) (xy 339.374594 -332.242785)
			(xy 339.415789 -332.207091) (xy 339.461645 -332.177624) (xy 339.511228 -332.154983) (xy 339.563529 -332.13963)
			(xy 339.617482 -332.131877) (xy 339.644736 -332.131416) (xy 339.671343 -332.131908) (xy 339.724033 -332.139352)
			(xy 339.775181 -332.154036) (xy 339.799676 -332.164436) (xy 339.83168 -332.178406) (xy 339.970618 -332.039468)
			(xy 339.956648 -332.007464) (xy 339.946223 -331.982978) (xy 339.931524 -331.931829) (xy 339.924086 -331.879133)
			(xy 339.923628 -331.852524) (xy 339.924078 -331.82527) (xy 339.931832 -331.771317) (xy 339.947187 -331.719017)
			(xy 339.96983 -331.669434) (xy 339.999298 -331.623579) (xy 340.034994 -331.582385) (xy 340.076189 -331.546691)
			(xy 340.122045 -331.517224) (xy 340.171628 -331.494583) (xy 340.223929 -331.47923) (xy 340.277882 -331.471477)
			(xy 340.305136 -331.471016) (xy 340.331743 -331.471508) (xy 340.384433 -331.478952) (xy 340.435581 -331.493636)
			(xy 340.460076 -331.504036) (xy 340.49208 -331.518006) (xy 341.0077 -331.002386) (xy 341.025756 -330.985149)
			(xy 341.067257 -330.957419) (xy 341.113369 -330.938318) (xy 341.162322 -330.928577) (xy 341.187278 -330.927964)
			(xy 347.457014 -330.927964) (xy 347.468663 -330.903128) (xy 347.498038 -330.856799) (xy 347.533743 -330.815153)
			(xy 347.575042 -330.779047) (xy 347.621085 -330.749226) (xy 347.670923 -330.726303) (xy 347.723529 -330.710751)
			(xy 347.77782 -330.702891) (xy 347.805248 -330.702412) (xy 347.833988 -330.702903) (xy 347.890817 -330.711533)
			(xy 347.945708 -330.728591) (xy 347.99742 -330.75369) (xy 348.04478 -330.786262) (xy 348.066106 -330.805536)
			(xy 348.07764 -330.815608) (xy 348.105186 -330.82895) (xy 348.135448 -330.833535) (xy 348.16571 -330.82895)
			(xy 348.193256 -330.815608) (xy 348.20479 -330.805536) (xy 348.226097 -330.786242) (xy 348.273465 -330.753679)
			(xy 348.325181 -330.728591) (xy 348.380076 -330.711546) (xy 348.436908 -330.702929) (xy 348.465648 -330.702412)
			(xy 348.493079 -330.702892) (xy 348.547376 -330.710731) (xy 348.599991 -330.726269) (xy 348.649835 -330.749187)
			(xy 348.695882 -330.779009) (xy 348.737181 -330.815122) (xy 348.772878 -330.85678) (xy 348.802239 -330.903123)
			(xy 348.813882 -330.927964) (xy 349.19158 -330.927964) (xy 349.204534 -330.896722) (xy 349.215764 -330.87098)
			(xy 349.244675 -330.822833) (xy 349.280332 -330.779445) (xy 349.321966 -330.741754) (xy 349.368676 -330.710574)
			(xy 349.419452 -330.68658) (xy 349.473198 -330.670289) (xy 349.528752 -330.662055) (xy 349.584912 -330.662055)
			(xy 349.640466 -330.670289) (xy 349.694212 -330.68658) (xy 349.744988 -330.710574) (xy 349.791698 -330.741754)
			(xy 349.833332 -330.779445) (xy 349.868989 -330.822833) (xy 349.8979 -330.87098) (xy 349.90913 -330.896722)
			(xy 349.922084 -330.927964) (xy 355.617526 -330.927964) (xy 355.629165 -330.903123) (xy 355.658542 -330.856794)
			(xy 355.694248 -330.815148) (xy 355.735549 -330.779042) (xy 355.781593 -330.749222) (xy 355.831432 -330.7263)
			(xy 355.88404 -330.710749) (xy 355.938331 -330.70289) (xy 355.96576 -330.702412) (xy 355.9945 -330.702896)
			(xy 356.05133 -330.711528) (xy 356.106221 -330.728587) (xy 356.157932 -330.753687) (xy 356.205293 -330.786261)
			(xy 356.226618 -330.805536) (xy 356.238152 -330.815608) (xy 356.265698 -330.82895) (xy 356.29596 -330.833535)
			(xy 356.326222 -330.82895) (xy 356.353768 -330.815608) (xy 356.365302 -330.805536) (xy 356.386645 -330.786284)
			(xy 356.434003 -330.753715) (xy 356.48571 -330.728619) (xy 356.540598 -330.711564) (xy 356.597422 -330.702936)
			(xy 356.62616 -330.702412) (xy 356.653591 -330.702882) (xy 356.707889 -330.710723) (xy 356.760504 -330.726263)
			(xy 356.810348 -330.749181) (xy 356.856395 -330.779005) (xy 356.897693 -330.815119) (xy 356.933391 -330.856778)
			(xy 356.962751 -330.903122) (xy 356.974394 -330.927964) (xy 357.352092 -330.927964) (xy 357.365046 -330.896722)
			(xy 357.376276 -330.87098) (xy 357.405187 -330.822833) (xy 357.440844 -330.779445) (xy 357.482478 -330.741754)
			(xy 357.529188 -330.710574) (xy 357.579964 -330.68658) (xy 357.63371 -330.670289) (xy 357.689264 -330.662055)
			(xy 357.745424 -330.662055) (xy 357.800978 -330.670289) (xy 357.854724 -330.68658) (xy 357.9055 -330.710574)
			(xy 357.95221 -330.741754) (xy 357.993844 -330.779445) (xy 358.029501 -330.822833) (xy 358.058412 -330.87098)
			(xy 358.069642 -330.896722) (xy 358.082596 -330.927964) (xy 364.203742 -330.927964) (xy 364.21441 -330.92263)
			(xy 364.240887 -330.910141) (xy 364.296705 -330.892499) (xy 364.354558 -330.883568) (xy 364.383828 -330.883006)
			(xy 364.413101 -330.883534) (xy 364.470965 -330.892443) (xy 364.526781 -330.910109) (xy 364.553246 -330.92263)
			(xy 364.563914 -330.927964) (xy 364.864142 -330.927964) (xy 364.87481 -330.92263) (xy 364.901287 -330.910141)
			(xy 364.957105 -330.892499) (xy 365.014958 -330.883568) (xy 365.044228 -330.883006) (xy 365.073501 -330.883534)
			(xy 365.131365 -330.892443) (xy 365.187181 -330.910109) (xy 365.213646 -330.92263) (xy 365.224314 -330.927964)
			(xy 371.93855 -330.927964) (xy 371.95017 -330.903114) (xy 371.979549 -330.856784) (xy 372.015258 -330.815138)
			(xy 372.056562 -330.779033) (xy 372.102609 -330.749213) (xy 372.152451 -330.726293) (xy 372.20506 -330.710744)
			(xy 372.259354 -330.702888) (xy 372.286784 -330.702412) (xy 372.315523 -330.702942) (xy 372.37235 -330.711563)
			(xy 372.427241 -330.728611) (xy 372.478953 -330.753701) (xy 372.526315 -330.786266) (xy 372.547642 -330.805536)
			(xy 372.559176 -330.815608) (xy 372.586722 -330.82895) (xy 372.616984 -330.833535) (xy 372.647246 -330.82895)
			(xy 372.674792 -330.815608) (xy 372.686326 -330.805536) (xy 372.707659 -330.786273) (xy 372.75502 -330.753705)
			(xy 372.80673 -330.728612) (xy 372.861619 -330.711559) (xy 372.918445 -330.702934) (xy 372.947184 -330.702412)
			(xy 372.974616 -330.702861) (xy 373.028915 -330.710706) (xy 373.08153 -330.726249) (xy 373.131375 -330.749171)
			(xy 373.177421 -330.778997) (xy 373.218719 -330.815114) (xy 373.254416 -330.856775) (xy 373.283775 -330.903121)
			(xy 373.295418 -330.927964) (xy 374.734582 -330.927964) (xy 374.759544 -330.928513) (xy 374.808509 -330.938247)
			(xy 374.854627 -330.957363) (xy 374.89612 -330.985124) (xy 374.91416 -331.002386) (xy 375.38025 -331.468476)
			(xy 375.397497 -331.486526) (xy 375.425237 -331.528025) (xy 375.444349 -331.574139) (xy 375.454096 -331.623096)
			(xy 375.454672 -331.648054) (xy 375.454672 -333.866236) (xy 375.88444 -334.296004) (xy 382.285494 -334.296004)
			(xy 382.310457 -334.296534) (xy 382.359423 -334.306273) (xy 382.405542 -334.325394) (xy 382.447033 -334.353161)
			(xy 382.465072 -334.370426) (xy 383.83083 -335.736184) (xy 383.848077 -335.754234) (xy 383.875819 -335.795733)
			(xy 383.89493 -335.841847) (xy 383.904677 -335.890803) (xy 383.905252 -335.915762) (xy 383.905252 -340.650322)
			(xy 383.9285 -340.663408) (xy 383.971273 -340.69529) (xy 384.009062 -340.732948) (xy 384.041093 -340.775611)
			(xy 384.066711 -340.822406) (xy 384.085393 -340.872377) (xy 384.096757 -340.924501) (xy 384.100569 -340.977713)
			(xy 384.096753 -341.030925) (xy 384.085386 -341.083049) (xy 384.0667 -341.133018) (xy 384.041078 -341.179812)
			(xy 384.009044 -341.222472) (xy 383.971253 -341.260127) (xy 383.928477 -341.292007) (xy 383.905252 -341.305134)
			(xy 383.905252 -341.4395) (xy 383.930114 -341.453609) (xy 383.975601 -341.488226) (xy 384.015265 -341.529387)
			(xy 384.048175 -341.576125) (xy 384.073558 -341.627341) (xy 384.090818 -341.681835) (xy 384.09955 -341.738325)
			(xy 384.10007 -341.766906) (xy 384.099658 -341.791727) (xy 384.093028 -341.840924) (xy 384.079924 -341.888805)
			(xy 384.060581 -341.934523) (xy 384.035339 -341.977269) (xy 384.020314 -341.99703) (xy 384.445764 -342.42248)
			(xy 384.749802 -342.42248) (xy 384.763518 -342.393778) (xy 384.775286 -342.370472) (xy 384.804372 -342.327115)
			(xy 384.839223 -342.288242) (xy 384.879158 -342.254612) (xy 384.923396 -342.226884) (xy 384.97107 -342.205601)
			(xy 385.021248 -342.191179) (xy 385.072947 -342.1839) (xy 385.099052 -342.183466) (xy 385.127758 -342.183957)
			(xy 385.184489 -342.192777) (xy 385.239194 -342.210199) (xy 385.290577 -342.235812) (xy 385.33742 -342.269007)
			(xy 385.358386 -342.288622) (xy 385.370061 -342.299161) (xy 385.39819 -342.313195) (xy 385.429252 -342.318024)
			(xy 385.460314 -342.313195) (xy 385.488443 -342.299161) (xy 385.500118 -342.288622) (xy 385.521111 -342.269039)
			(xy 385.567948 -342.235848) (xy 385.619326 -342.210239) (xy 385.674025 -342.192819) (xy 385.730749 -342.184)
			(xy 385.759452 -342.183466) (xy 385.785554 -342.183928) (xy 385.837247 -342.191216) (xy 385.887419 -342.205643)
			(xy 385.935088 -342.226926) (xy 385.979323 -342.254649) (xy 386.019258 -342.288271) (xy 386.054115 -342.327134)
			(xy 386.08321 -342.370479) (xy 386.094986 -342.393778) (xy 386.108702 -342.42248) (xy 387.555486 -342.42248)
			(xy 387.569456 -342.394032) (xy 387.582071 -342.369304) (xy 387.61352 -342.32356) (xy 387.65141 -342.282991)
			(xy 387.694904 -342.248497) (xy 387.743036 -342.220842) (xy 387.79474 -342.200639) (xy 387.848871 -342.188335)
			(xy 387.904228 -342.184203) (xy 387.959585 -342.188335) (xy 388.013716 -342.200639) (xy 388.06542 -342.220842)
			(xy 388.113552 -342.248497) (xy 388.157046 -342.282991) (xy 388.194936 -342.32356) (xy 388.226385 -342.369304)
			(xy 388.239 -342.394032) (xy 388.25297 -342.42248) (xy 390.837166 -342.42248) (xy 390.862128 -342.423034)
			(xy 390.911093 -342.432766) (xy 390.957211 -342.451881) (xy 390.998704 -342.479641) (xy 391.016744 -342.496902)
			(xy 391.319766 -342.799924) (xy 391.336959 -342.81802) (xy 391.364699 -342.859506) (xy 391.383813 -342.905606)
			(xy 391.393567 -342.954549) (xy 391.394188 -342.979502) (xy 391.394188 -346.690188) (xy 391.393628 -346.715149)
			(xy 391.383895 -346.764113) (xy 391.364781 -346.81023) (xy 391.337025 -346.851724) (xy 391.319766 -346.869766)
			(xy 387.832854 -350.356678) (xy 387.81477 -350.373884) (xy 387.773279 -350.401621) (xy 387.727176 -350.420731)
			(xy 387.67823 -350.430481) (xy 387.653276 -350.4311) (xy 369.830604 -350.4311) (xy 368.131598 -352.130106)
			(xy 368.113542 -352.147343) (xy 368.072041 -352.175073) (xy 368.025929 -352.194175) (xy 367.976976 -352.203915)
			(xy 367.95202 -352.204528) (xy 363.59084 -352.204528) (xy 363.565879 -352.203968) (xy 363.516914 -352.194237)
			(xy 363.470796 -352.175124) (xy 363.429303 -352.147366) (xy 363.411262 -352.130106) (xy 361.336844 -350.055688)
			(xy 345.766898 -350.055688) (xy 343.967562 -351.855024) (xy 343.949491 -351.872248) (xy 343.908 -351.899994)
			(xy 343.861892 -351.919112) (xy 343.812941 -351.928867) (xy 343.787984 -351.929446) (xy 336.191606 -351.929446)
			(xy 336.166644 -351.928902) (xy 336.117679 -351.919166) (xy 336.071561 -351.900048) (xy 336.030068 -351.872286)
			(xy 336.012028 -351.855024) (xy 333.667608 -349.510604) (xy 325.875142 -349.510604) (xy 325.85018 -349.510049)
			(xy 325.801215 -349.500318) (xy 325.755097 -349.481204) (xy 325.713604 -349.453443) (xy 325.695564 -349.436182)
			(xy 324.026276 -347.766894) (xy 324.00902 -347.748852) (xy 323.981279 -347.707351) (xy 323.96217 -347.661234)
			(xy 323.952427 -347.612275) (xy 323.951854 -347.587316) (xy 323.951854 -346.222574) (xy 323.9516 -346.219526)
			(xy 323.950306 -346.208268) (xy 323.948909 -346.185646) (xy 323.948806 -346.174314) (xy 323.948919 -346.162982)
			(xy 323.950318 -346.140362) (xy 323.9516 -346.129102) (xy 323.951854 -346.126054) (xy 323.951854 -345.322144)
			(xy 323.920612 -345.308936) (xy 323.894914 -345.297699) (xy 323.846866 -345.268766) (xy 323.803574 -345.233109)
			(xy 323.76597 -345.191497) (xy 323.734865 -345.144826) (xy 323.71093 -345.094103) (xy 323.69468 -345.040422)
			(xy 323.686468 -344.98494) (xy 318.650874 -344.98494) (xy 318.650874 -350.660462) (xy 318.650297 -350.68542)
			(xy 318.640547 -350.734374) (xy 318.621433 -350.780486) (xy 318.593691 -350.821983) (xy 318.576452 -350.84004)
			(xy 317.23965 -352.176842) (xy 317.221609 -352.194101) (xy 317.180115 -352.221858) (xy 317.133997 -352.24097)
			(xy 317.085033 -352.250701) (xy 317.060072 -352.251264) (xy 284.973776 -352.251264) (xy 284.948817 -352.25069)
			(xy 284.899858 -352.240946) (xy 284.853742 -352.221837) (xy 284.81224 -352.194098) (xy 284.794198 -352.176842)
			(xy 283.970222 -351.352866) (xy 283.952958 -351.334827) (xy 283.925192 -351.293335) (xy 283.906072 -351.247217)
			(xy 283.896335 -351.198251) (xy 283.8958 -351.173288) (xy 283.8958 -319.662048) (xy 283.895872 -319.652101)
			(xy 283.897395 -319.632265) (xy 283.898848 -319.622424) (xy 283.89961 -319.618614) (xy 283.89961 -319.56375)
			(xy 280.038302 -319.56375) (xy 280.018384 -319.581738) (xy 279.974154 -319.612134) (xy 279.925865 -319.635554)
			(xy 279.874611 -319.651468) (xy 279.82155 -319.659516) (xy 279.767882 -319.659516) (xy 279.714821 -319.651468)
			(xy 279.663567 -319.635554) (xy 279.615278 -319.612134) (xy 279.571048 -319.581738) (xy 279.55113 -319.56375)
			(xy 272.566384 -319.56375) (xy 272.549403 -319.584687) (xy 272.510198 -319.621686) (xy 272.465865 -319.652353)
			(xy 272.417416 -319.675989) (xy 272.365958 -319.692052) (xy 272.312667 -319.700177) (xy 272.258761 -319.700177)
			(xy 272.20547 -319.692052) (xy 272.154012 -319.675989) (xy 272.105563 -319.652353) (xy 272.06123 -319.621686)
			(xy 272.022025 -319.584687) (xy 272.005044 -319.56375) (xy 265.06932 -319.56375) (xy 265.05705 -319.586801)
			(xy 265.026787 -319.629356) (xy 264.990633 -319.667035) (xy 264.949365 -319.699031) (xy 264.903867 -319.724657)
			(xy 264.855114 -319.743364) (xy 264.804152 -319.754751) (xy 264.752074 -319.758575) (xy 264.699996 -319.754751)
			(xy 264.649034 -319.743364) (xy 264.600281 -319.724657) (xy 264.554783 -319.699031) (xy 264.513515 -319.667035)
			(xy 264.477361 -319.629356) (xy 264.447098 -319.586801) (xy 264.434828 -319.56375) (xy 257.45313 -319.56375)
			(xy 257.434575 -319.584035) (xy 257.392326 -319.619205) (xy 257.345173 -319.647466) (xy 257.294239 -319.668146)
			(xy 257.240731 -319.680753) (xy 257.185922 -319.684989) (xy 257.131113 -319.680753) (xy 257.077605 -319.668146)
			(xy 257.026671 -319.647466) (xy 256.979518 -319.619205) (xy 256.937269 -319.584035) (xy 256.918714 -319.56375)
			(xy 254.716788 -319.56375) (xy 254.695277 -319.576912) (xy 254.649334 -319.597701) (xy 254.600916 -319.611799)
			(xy 254.550994 -319.618925) (xy 254.52578 -319.619376) (xy 254.502205 -319.618993) (xy 254.455469 -319.612768)
			(xy 254.409963 -319.600429) (xy 254.366483 -319.582192) (xy 254.345948 -319.570608) (xy 254.334264 -319.56375)
			(xy 254.277114 -319.56375) (xy 254.052578 -319.788286) (xy 254.052578 -353.603129) (xy 326.814684 -353.603129)
			(xy 326.814684 -353.446511) (xy 326.822747 -353.290099) (xy 326.838851 -353.13431) (xy 326.862953 -352.979557)
			(xy 326.89499 -352.82625) (xy 326.934876 -352.674795) (xy 326.982506 -352.525594) (xy 327.037754 -352.379043)
			(xy 327.100472 -352.23553) (xy 327.170496 -352.095436) (xy 327.247638 -351.959133) (xy 327.331695 -351.826982)
			(xy 327.422443 -351.699333) (xy 327.519643 -351.576525) (xy 327.623035 -351.458884) (xy 327.732346 -351.34672)
			(xy 327.847287 -351.240333) (xy 327.967551 -351.140004) (xy 328.092821 -351.045999) (xy 328.222764 -350.958568)
			(xy 328.357036 -350.877941) (xy 328.495281 -350.804334) (xy 328.637131 -350.737941) (xy 328.782211 -350.678938)
			(xy 328.930136 -350.627482) (xy 329.080513 -350.58371) (xy 329.232945 -350.547736) (xy 329.387026 -350.519657)
			(xy 329.542349 -350.499548) (xy 329.698501 -350.487461) (xy 329.855068 -350.483428) (xy 330.011635 -350.487461)
			(xy 330.167787 -350.499548) (xy 330.32311 -350.519657) (xy 330.477191 -350.547736) (xy 330.629623 -350.58371)
			(xy 330.78 -350.627482) (xy 330.927925 -350.678938) (xy 331.073005 -350.737941) (xy 331.214855 -350.804334)
			(xy 331.3531 -350.877941) (xy 331.487372 -350.958568) (xy 331.617315 -351.045999) (xy 331.742585 -351.140004)
			(xy 331.862849 -351.240333) (xy 331.97779 -351.34672) (xy 332.087101 -351.458884) (xy 332.190493 -351.576525)
			(xy 332.287693 -351.699333) (xy 332.378441 -351.826982) (xy 332.462498 -351.959133) (xy 332.53964 -352.095436)
			(xy 332.609664 -352.23553) (xy 332.672382 -352.379043) (xy 332.72763 -352.525594) (xy 332.77526 -352.674795)
			(xy 332.815146 -352.82625) (xy 332.847183 -352.979557) (xy 332.871285 -353.13431) (xy 332.887389 -353.290099)
			(xy 332.895452 -353.446511) (xy 332.895956 -353.52482) (xy 332.895452 -353.603129) (xy 332.887389 -353.759541)
			(xy 332.871285 -353.91533) (xy 332.847183 -354.070083) (xy 332.815146 -354.22339) (xy 332.77526 -354.374845)
			(xy 332.731089 -354.513211) (xy 381.418588 -354.513211) (xy 381.418588 -354.356593) (xy 381.426651 -354.200181)
			(xy 381.442755 -354.044392) (xy 381.466857 -353.889639) (xy 381.498894 -353.736332) (xy 381.53878 -353.584877)
			(xy 381.58641 -353.435676) (xy 381.641658 -353.289125) (xy 381.704376 -353.145612) (xy 381.7744 -353.005518)
			(xy 381.851542 -352.869215) (xy 381.935599 -352.737064) (xy 382.026347 -352.609415) (xy 382.123547 -352.486607)
			(xy 382.226939 -352.368966) (xy 382.33625 -352.256802) (xy 382.451191 -352.150415) (xy 382.571455 -352.050086)
			(xy 382.696725 -351.956081) (xy 382.826668 -351.86865) (xy 382.96094 -351.788023) (xy 383.099185 -351.714416)
			(xy 383.241035 -351.648023) (xy 383.386115 -351.58902) (xy 383.53404 -351.537564) (xy 383.684417 -351.493792)
			(xy 383.836849 -351.457818) (xy 383.99093 -351.429739) (xy 384.146253 -351.40963) (xy 384.302405 -351.397543)
			(xy 384.458972 -351.39351) (xy 384.615539 -351.397543) (xy 384.771691 -351.40963) (xy 384.927014 -351.429739)
			(xy 385.081095 -351.457818) (xy 385.233527 -351.493792) (xy 385.383904 -351.537564) (xy 385.531829 -351.58902)
			(xy 385.676909 -351.648023) (xy 385.818759 -351.714416) (xy 385.957004 -351.788023) (xy 386.091276 -351.86865)
			(xy 386.221219 -351.956081) (xy 386.346489 -352.050086) (xy 386.466753 -352.150415) (xy 386.581694 -352.256802)
			(xy 386.691005 -352.368966) (xy 386.794397 -352.486607) (xy 386.891597 -352.609415) (xy 386.982345 -352.737064)
			(xy 387.066402 -352.869215) (xy 387.143544 -353.005518) (xy 387.213568 -353.145612) (xy 387.276286 -353.289125)
			(xy 387.331534 -353.435676) (xy 387.379164 -353.584877) (xy 387.41905 -353.736332) (xy 387.451087 -353.889639)
			(xy 387.475189 -354.044392) (xy 387.491293 -354.200181) (xy 387.499356 -354.356593) (xy 387.49986 -354.434902)
			(xy 387.499356 -354.513211) (xy 387.491293 -354.669623) (xy 387.475189 -354.825412) (xy 387.451087 -354.980165)
			(xy 387.41905 -355.133472) (xy 387.379164 -355.284927) (xy 387.331534 -355.434128) (xy 387.276286 -355.580679)
			(xy 387.213568 -355.724192) (xy 387.143544 -355.864286) (xy 387.066402 -356.000589) (xy 386.982345 -356.13274)
			(xy 386.891597 -356.260389) (xy 386.794397 -356.383197) (xy 386.691005 -356.500838) (xy 386.581694 -356.613002)
			(xy 386.466753 -356.719389) (xy 386.346489 -356.819718) (xy 386.221219 -356.913723) (xy 386.091276 -357.001154)
			(xy 385.957004 -357.081781) (xy 385.818759 -357.155388) (xy 385.676909 -357.221781) (xy 385.531829 -357.280784)
			(xy 385.383904 -357.33224) (xy 385.233527 -357.376012) (xy 385.081095 -357.411986) (xy 384.927014 -357.440065)
			(xy 384.771691 -357.460174) (xy 384.615539 -357.472261) (xy 384.458972 -357.476294) (xy 384.302405 -357.472261)
			(xy 384.146253 -357.460174) (xy 383.99093 -357.440065) (xy 383.836849 -357.411986) (xy 383.684417 -357.376012)
			(xy 383.53404 -357.33224) (xy 383.386115 -357.280784) (xy 383.241035 -357.221781) (xy 383.099185 -357.155388)
			(xy 382.96094 -357.081781) (xy 382.826668 -357.001154) (xy 382.696725 -356.913723) (xy 382.571455 -356.819718)
			(xy 382.451191 -356.719389) (xy 382.33625 -356.613002) (xy 382.226939 -356.500838) (xy 382.123547 -356.383197)
			(xy 382.026347 -356.260389) (xy 381.935599 -356.13274) (xy 381.851542 -356.000589) (xy 381.7744 -355.864286)
			(xy 381.704376 -355.724192) (xy 381.641658 -355.580679) (xy 381.58641 -355.434128) (xy 381.53878 -355.284927)
			(xy 381.498894 -355.133472) (xy 381.466857 -354.980165) (xy 381.442755 -354.825412) (xy 381.426651 -354.669623)
			(xy 381.418588 -354.513211) (xy 332.731089 -354.513211) (xy 332.72763 -354.524046) (xy 332.672382 -354.670597)
			(xy 332.609664 -354.81411) (xy 332.53964 -354.954204) (xy 332.462498 -355.090507) (xy 332.378441 -355.222658)
			(xy 332.287693 -355.350307) (xy 332.190493 -355.473115) (xy 332.087101 -355.590756) (xy 331.97779 -355.70292)
			(xy 331.862849 -355.809307) (xy 331.742585 -355.909636) (xy 331.617315 -356.003641) (xy 331.487372 -356.091072)
			(xy 331.3531 -356.171699) (xy 331.214855 -356.245306) (xy 331.073005 -356.311699) (xy 330.927925 -356.370702)
			(xy 330.78 -356.422158) (xy 330.629623 -356.46593) (xy 330.477191 -356.501904) (xy 330.32311 -356.529983)
			(xy 330.167787 -356.550092) (xy 330.011635 -356.562179) (xy 329.855068 -356.566212) (xy 329.698501 -356.562179)
			(xy 329.542349 -356.550092) (xy 329.387026 -356.529983) (xy 329.232945 -356.501904) (xy 329.080513 -356.46593)
			(xy 328.930136 -356.422158) (xy 328.782211 -356.370702) (xy 328.637131 -356.311699) (xy 328.495281 -356.245306)
			(xy 328.357036 -356.171699) (xy 328.222764 -356.091072) (xy 328.092821 -356.003641) (xy 327.967551 -355.909636)
			(xy 327.847287 -355.809307) (xy 327.732346 -355.70292) (xy 327.623035 -355.590756) (xy 327.519643 -355.473115)
			(xy 327.422443 -355.350307) (xy 327.331695 -355.222658) (xy 327.247638 -355.090507) (xy 327.170496 -354.954204)
			(xy 327.100472 -354.81411) (xy 327.037754 -354.670597) (xy 326.982506 -354.524046) (xy 326.934876 -354.374845)
			(xy 326.89499 -354.22339) (xy 326.862953 -354.070083) (xy 326.838851 -353.91533) (xy 326.822747 -353.759541)
			(xy 326.814684 -353.603129) (xy 254.052578 -353.603129) (xy 254.052578 -354.45827) (xy 255.68529 -356.090982)
			(xy 255.71831 -356.074218) (xy 255.811197 -356.027133) (xy 256.000112 -355.939442) (xy 256.192344 -355.859282)
			(xy 256.387592 -355.786776) (xy 256.585551 -355.722038) (xy 256.785912 -355.66517) (xy 256.988364 -355.616259)
			(xy 257.192589 -355.575383) (xy 257.398269 -355.542605) (xy 257.605083 -355.517976) (xy 257.812709 -355.501535)
			(xy 258.020822 -355.493307) (xy 258.12496 -355.492812) (xy 258.22846 -355.493313) (xy 258.4353 -355.501438)
			(xy 258.641662 -355.517678) (xy 258.847226 -355.542006) (xy 259.051678 -355.574387) (xy 259.2547 -355.614769)
			(xy 259.455981 -355.663091) (xy 259.655209 -355.719278) (xy 259.852078 -355.783244) (xy 260.046283 -355.854889)
			(xy 260.237526 -355.934103) (xy 260.425512 -356.020765) (xy 260.60995 -356.11474) (xy 260.790557 -356.215884)
			(xy 260.967054 -356.32404) (xy 261.139168 -356.439042) (xy 261.306634 -356.560713) (xy 261.469195 -356.688865)
			(xy 261.626599 -356.8233) (xy 261.778604 -356.963811) (xy 261.924975 -357.110182) (xy 262.065487 -357.262186)
			(xy 262.199923 -357.419589) (xy 262.328075 -357.58215) (xy 262.449746 -357.749616) (xy 262.564749 -357.92173)
			(xy 262.672906 -358.098226) (xy 262.774051 -358.278832) (xy 262.868027 -358.46327) (xy 262.954689 -358.651255)
			(xy 263.033904 -358.842498) (xy 263.10555 -359.036704) (xy 263.169516 -359.233572) (xy 263.225704 -359.4328)
			(xy 263.274026 -359.63408) (xy 263.314409 -359.837103) (xy 263.346791 -360.041554) (xy 263.37112 -360.247119)
			(xy 263.387361 -360.45348) (xy 263.395487 -360.66032) (xy 263.395968 -360.76382) (xy 263.395411 -360.873327)
			(xy 263.386334 -361.092152) (xy 263.368176 -361.310411) (xy 263.340969 -361.527727) (xy 263.304758 -361.743727)
			(xy 263.259608 -361.958035) (xy 263.233154 -362.0643) (xy 263.229844 -362.079421) (xy 263.231488 -362.110317)
			(xy 263.242296 -362.139306) (xy 263.261281 -362.163736) (xy 263.286703 -362.18137) (xy 263.316236 -362.190593)
			(xy 263.331706 -362.191046) (xy 283.056838 -362.191046) (xy 283.06903 -362.158026) (xy 283.078966 -362.132613)
			(xy 283.10506 -362.08469) (xy 283.137715 -362.040974) (xy 283.176266 -362.002357) (xy 283.219925 -361.969626)
			(xy 283.267801 -361.943448) (xy 283.318919 -361.924359) (xy 283.372235 -361.912748) (xy 283.426662 -361.908851)
			(xy 283.481089 -361.912748) (xy 283.534405 -361.924359) (xy 283.585523 -361.943448) (xy 283.633399 -361.969626)
			(xy 283.677058 -362.002357) (xy 283.715609 -362.040974) (xy 283.748264 -362.08469) (xy 283.774358 -362.132613)
			(xy 283.784294 -362.158026) (xy 283.796486 -362.191046) (xy 287.84677 -362.191046) (xy 287.864499 -362.168322)
			(xy 287.905778 -362.1281) (xy 287.952751 -362.094705) (xy 288.004302 -362.068932) (xy 288.059204 -362.051395)
			(xy 288.116149 -362.04251) (xy 288.144966 -362.041948) (xy 288.171863 -362.042439) (xy 288.225093 -362.05021)
			(xy 288.276653 -362.065552) (xy 288.325472 -362.088146) (xy 288.370536 -362.117523) (xy 288.41091 -362.153073)
			(xy 288.428684 -362.173266) (xy 288.443924 -362.191046) (xy 288.506408 -362.191046) (xy 288.521648 -362.173266)
			(xy 288.539423 -362.153073) (xy 288.579789 -362.117511) (xy 288.62485 -362.088126) (xy 288.673671 -362.065531)
			(xy 288.725235 -362.050194) (xy 288.778468 -362.042435) (xy 288.805366 -362.041948) (xy 288.834186 -362.042484)
			(xy 288.891139 -362.051353) (xy 288.946046 -362.068887) (xy 288.9976 -362.094665) (xy 289.044569 -362.128074)
			(xy 289.085835 -362.168317) (xy 289.103562 -362.191046) (xy 290.675822 -362.191046) (xy 290.693594 -362.16946)
			(xy 290.734509 -362.13135) (xy 290.780659 -362.099782) (xy 290.831008 -362.075465) (xy 290.884425 -362.058943)
			(xy 290.939711 -362.050588) (xy 290.995625 -362.050588) (xy 291.050911 -362.058943) (xy 291.104328 -362.075465)
			(xy 291.154677 -362.099782) (xy 291.200827 -362.13135) (xy 291.241742 -362.16946) (xy 291.259514 -362.191046)
			(xy 297.535092 -362.191046) (xy 297.552822 -362.168323) (xy 297.594101 -362.128104) (xy 297.641075 -362.094712)
			(xy 297.692626 -362.068942) (xy 297.747527 -362.051408) (xy 297.804472 -362.042526) (xy 297.833288 -362.041948)
			(xy 297.860184 -362.042441) (xy 297.913412 -362.050214) (xy 297.96497 -362.065558) (xy 298.013787 -362.088155)
			(xy 298.058849 -362.117533) (xy 298.09922 -362.153084) (xy 298.117006 -362.173266) (xy 298.132246 -362.191046)
			(xy 298.19473 -362.191046) (xy 298.20997 -362.173266) (xy 298.227746 -362.153074) (xy 298.268112 -362.117514)
			(xy 298.313174 -362.088133) (xy 298.361995 -362.06554) (xy 298.413558 -362.050206) (xy 298.466791 -362.04245)
			(xy 298.493688 -362.041948) (xy 298.522507 -362.042485) (xy 298.579458 -362.051358) (xy 298.634363 -362.068894)
			(xy 298.685914 -362.094674) (xy 298.732881 -362.128084) (xy 298.774144 -362.168327) (xy 298.791884 -362.191046)
			(xy 300.364144 -362.191046) (xy 300.381916 -362.16946) (xy 300.422831 -362.13135) (xy 300.468981 -362.099782)
			(xy 300.51933 -362.075465) (xy 300.572747 -362.058943) (xy 300.628033 -362.050588) (xy 300.683947 -362.050588)
			(xy 300.739233 -362.058943) (xy 300.79265 -362.075465) (xy 300.842999 -362.099782) (xy 300.889149 -362.13135)
			(xy 300.930064 -362.16946) (xy 300.947836 -362.191046) (xy 331.121766 -362.191046) (xy 337.70062 -355.612192)
			(xy 337.718659 -355.594928) (xy 337.760151 -355.567163) (xy 337.80627 -355.548043) (xy 337.855235 -355.538305)
			(xy 337.880198 -355.53777) (xy 347.547692 -355.53777) (xy 347.572645 -355.53839) (xy 347.62159 -355.548142)
			(xy 347.667693 -355.567253) (xy 347.709183 -355.594989) (xy 347.72727 -355.612192) (xy 353.248214 -361.133136)
			(xy 369.3861 -361.133136) (xy 369.390189 -361.077254) (xy 369.402372 -361.022564) (xy 369.422388 -360.97023)
			(xy 369.449811 -360.921368) (xy 369.484056 -360.87702) (xy 369.524392 -360.83813) (xy 369.569962 -360.805528)
			(xy 369.619793 -360.779909) (xy 369.672823 -360.761817) (xy 369.727921 -360.75164) (xy 369.783915 -360.749594)
			(xy 369.83961 -360.755722) (xy 369.893819 -360.769894) (xy 369.945387 -360.791808) (xy 369.993215 -360.820997)
			(xy 370.036283 -360.856838) (xy 370.073673 -360.898568) (xy 370.104589 -360.945298) (xy 370.128372 -360.996031)
			(xy 370.144514 -361.049687) (xy 370.152673 -361.105121) (xy 370.153184 -361.133136) (xy 370.152673 -361.161151)
			(xy 370.144514 -361.216585) (xy 370.128372 -361.270241) (xy 370.104589 -361.320974) (xy 370.073673 -361.367704)
			(xy 370.036283 -361.409434) (xy 369.993215 -361.445275) (xy 369.945387 -361.474464) (xy 369.893819 -361.496378)
			(xy 369.83961 -361.51055) (xy 369.783915 -361.516678) (xy 369.727921 -361.514632) (xy 369.672823 -361.504455)
			(xy 369.619793 -361.486363) (xy 369.569962 -361.460744) (xy 369.524392 -361.428142) (xy 369.484056 -361.389252)
			(xy 369.449811 -361.344904) (xy 369.422388 -361.296042) (xy 369.402372 -361.243708) (xy 369.390189 -361.189018)
			(xy 369.3861 -361.133136) (xy 353.248214 -361.133136) (xy 354.098352 -361.983274) (xy 354.10902 -361.987084)
			(xy 354.135593 -361.997018) (xy 354.185697 -362.02362) (xy 354.23131 -362.057348) (xy 354.271425 -362.097459)
			(xy 354.305159 -362.143068) (xy 354.331765 -362.19317) (xy 354.341684 -362.219748) (xy 354.345494 -362.230416)
			(xy 354.454968 -362.33989) (xy 358.98328 -362.33989)
		)
		(stroke
			(width 0)
			(type solid)
		)
		(fill yes)
		(layer "In8.Cu")
		(net "P12V_S3_AUX_CPU0_NVDIMM")
	)
	(gr_poly
		(pts
			(xy 146.160236 -361.335828) (xy 146.182855 -361.322453) (xy 146.230985 -361.301361) (xy 146.281554 -361.287074)
			(xy 146.333606 -361.279863) (xy 146.386154 -361.279863) (xy 146.438206 -361.287074) (xy 146.488775 -361.301361)
			(xy 146.536905 -361.322453) (xy 146.559524 -361.335828) (xy 175.211994 -361.335828) (xy 175.225501 -361.312178)
			(xy 175.258191 -361.268616) (xy 175.29674 -361.230144) (xy 175.340366 -361.197541) (xy 175.388183 -361.17147)
			(xy 175.439221 -361.15246) (xy 175.492442 -361.140898) (xy 175.546766 -361.137017) (xy 175.60109 -361.140898)
			(xy 175.654311 -361.15246) (xy 175.705349 -361.17147) (xy 175.753166 -361.197541) (xy 175.796792 -361.230144)
			(xy 175.835341 -361.268616) (xy 175.868031 -361.312178) (xy 175.881538 -361.335828) (xy 175.973994 -361.335828)
			(xy 175.988499 -361.310502) (xy 176.024 -361.264181) (xy 176.066136 -361.223802) (xy 176.113926 -361.190304)
			(xy 176.166256 -361.164467) (xy 176.221908 -361.146894) (xy 176.279586 -361.137994) (xy 176.308766 -361.137454)
			(xy 176.335082 -361.13789) (xy 176.387215 -361.145123) (xy 176.437855 -361.159469) (xy 176.486035 -361.180656)
			(xy 176.508664 -361.194096) (xy 176.520532 -361.20085) (xy 176.546755 -361.208435) (xy 176.574049 -361.208811)
			(xy 176.600471 -361.201953) (xy 176.624136 -361.188348) (xy 176.643359 -361.168967) (xy 176.650396 -361.157266)
			(xy 176.664994 -361.132331) (xy 176.700537 -361.086779) (xy 176.742544 -361.047108) (xy 176.790052 -361.014225)
			(xy 176.841977 -360.988883) (xy 176.897128 -360.971661) (xy 176.954247 -360.962953) (xy 176.983136 -360.962448)
			(xy 177.012051 -360.962985) (xy 177.069218 -360.971717) (xy 177.124412 -360.988977) (xy 177.17637 -361.014368)
			(xy 177.223901 -361.047309) (xy 177.265917 -361.087046) (xy 177.284126 -361.109514) (xy 177.294023 -361.121319)
			(xy 177.319347 -361.138838) (xy 177.34874 -361.148014) (xy 177.379532 -361.148014) (xy 177.408925 -361.138838)
			(xy 177.434249 -361.121319) (xy 177.444146 -361.109514) (xy 177.462336 -361.087028) (xy 177.504352 -361.047287)
			(xy 177.551886 -361.014344) (xy 177.603848 -360.988954) (xy 177.659047 -360.971699) (xy 177.716219 -360.962974)
			(xy 177.745136 -360.962448) (xy 177.772501 -360.962921) (xy 177.826667 -360.970746) (xy 177.879161 -360.98623)
			(xy 177.928903 -361.009055) (xy 177.974874 -361.038753) (xy 178.01613 -361.074714) (xy 178.051824 -361.116202)
			(xy 178.081225 -361.162363) (xy 178.103728 -361.212252) (xy 178.118873 -361.264844) (xy 178.123088 -361.291886)
			(xy 178.129184 -361.335828) (xy 191.528446 -361.335828) (xy 191.539622 -361.300268) (xy 191.54802 -361.275335)
			(xy 191.571153 -361.228084) (xy 191.601032 -361.184783) (xy 191.636998 -361.146388) (xy 191.678256 -361.113747)
			(xy 191.723897 -361.08758) (xy 191.772911 -361.068465) (xy 191.824216 -361.056825) (xy 191.87668 -361.052916)
			(xy 191.929144 -361.056825) (xy 191.980449 -361.068465) (xy 192.029463 -361.08758) (xy 192.075104 -361.113747)
			(xy 192.116362 -361.146388) (xy 192.152328 -361.184783) (xy 192.182207 -361.228084) (xy 192.20534 -361.275335)
			(xy 192.213738 -361.300268) (xy 192.224914 -361.335828) (xy 208.322926 -361.335828) (xy 208.336993 -361.335385)
			(xy 208.36406 -361.327715) (xy 208.388001 -361.31294) (xy 208.406992 -361.292185) (xy 208.419587 -361.267029)
			(xy 208.424827 -361.239388) (xy 208.424018 -361.225338) (xy 208.414574 -361.110193) (xy 208.404537 -360.87935)
			(xy 208.403952 -360.76382) (xy 208.40446 -360.66032) (xy 208.412586 -360.45348) (xy 208.428826 -360.247118)
			(xy 208.453155 -360.041553) (xy 208.485536 -359.837102) (xy 208.525919 -359.63408) (xy 208.574241 -359.432799)
			(xy 208.630429 -359.233571) (xy 208.694394 -359.036702) (xy 208.766039 -358.842496) (xy 208.845254 -358.651253)
			(xy 208.931915 -358.463267) (xy 209.02589 -358.278829) (xy 209.127034 -358.098222) (xy 209.23519 -357.921725)
			(xy 209.350192 -357.749611) (xy 209.471862 -357.582144) (xy 209.600014 -357.419583) (xy 209.734449 -357.262178)
			(xy 209.874959 -357.110173) (xy 210.021329 -356.963801) (xy 210.173333 -356.823288) (xy 210.330736 -356.688852)
			(xy 210.493296 -356.560699) (xy 210.660761 -356.439026) (xy 210.832875 -356.324022) (xy 211.00937 -356.215864)
			(xy 211.189976 -356.114719) (xy 211.374413 -356.020741) (xy 211.562398 -355.934078) (xy 211.753641 -355.854861)
			(xy 211.947845 -355.783214) (xy 212.144713 -355.719246) (xy 212.343941 -355.663056) (xy 212.545221 -355.614732)
			(xy 212.748243 -355.574347) (xy 212.952694 -355.541963) (xy 213.158259 -355.517632) (xy 213.36462 -355.501389)
			(xy 213.57146 -355.493261) (xy 213.67496 -355.492812) (xy 213.775383 -355.493279) (xy 213.976085 -355.500918)
			(xy 214.176349 -355.516197) (xy 214.375886 -355.539095) (xy 214.574406 -355.569578) (xy 214.77162 -355.607602)
			(xy 214.967243 -355.653112) (xy 215.16099 -355.706041) (xy 215.352579 -355.766313) (xy 215.541734 -355.833841)
			(xy 215.728178 -355.908526) (xy 215.911642 -355.990259) (xy 216.091859 -356.078923) (xy 216.268567 -356.174388)
			(xy 216.441509 -356.276516) (xy 216.610436 -356.385159) (xy 216.775101 -356.500158) (xy 216.935265 -356.621347)
			(xy 217.013282 -356.68458) (xy 217.048842 -356.71379) (xy 217.540078 -356.222554) (xy 217.540078 -320.063114)
			(xy 210.597496 -320.063114) (xy 210.592162 -320.064384) (xy 210.573101 -320.068318) (xy 210.534407 -320.072514)
			(xy 210.514946 -320.072766) (xy 210.495484 -320.072537) (xy 210.456787 -320.068341) (xy 210.43773 -320.064384)
			(xy 210.432396 -320.063114) (xy 203.053696 -320.063114) (xy 203.048362 -320.064384) (xy 203.029301 -320.068318)
			(xy 202.990607 -320.072514) (xy 202.971146 -320.072766) (xy 202.951684 -320.072537) (xy 202.912987 -320.068341)
			(xy 202.89393 -320.064384) (xy 202.888596 -320.063114) (xy 199.187562 -320.063114) (xy 199.173416 -320.083441)
			(xy 199.14 -320.11999) (xy 199.101468 -320.151098) (xy 199.058697 -320.176059) (xy 199.012659 -320.194305)
			(xy 198.964401 -320.205422) (xy 198.91502 -320.209155) (xy 198.865639 -320.205422) (xy 198.817381 -320.194305)
			(xy 198.771343 -320.176059) (xy 198.728572 -320.151098) (xy 198.69004 -320.11999) (xy 198.656624 -320.083441)
			(xy 198.642478 -320.063114) (xy 195.509896 -320.063114) (xy 195.504562 -320.064384) (xy 195.485501 -320.068318)
			(xy 195.446807 -320.072514) (xy 195.427346 -320.072766) (xy 195.407884 -320.072537) (xy 195.369187 -320.068341)
			(xy 195.35013 -320.064384) (xy 195.344796 -320.063114) (xy 187.966096 -320.063114) (xy 187.960762 -320.064384)
			(xy 187.941701 -320.068318) (xy 187.903007 -320.072514) (xy 187.883546 -320.072766) (xy 187.864084 -320.072537)
			(xy 187.825387 -320.068341) (xy 187.80633 -320.064384) (xy 187.800996 -320.063114) (xy 181.769512 -320.063114)
			(xy 181.441598 -320.391028) (xy 181.425342 -320.406014) (xy 181.425342 -323.261736) (xy 181.43093 -323.272658)
			(xy 181.443185 -323.297849) (xy 181.460502 -323.351124) (xy 181.469272 -323.406452) (xy 181.469278 -323.46247)
			(xy 181.460521 -323.5178) (xy 181.443215 -323.571078) (xy 181.43093 -323.596254) (xy 181.425342 -323.607176)
			(xy 181.425342 -325.690484) (xy 181.457092 -325.703184) (xy 181.483165 -325.714263) (xy 181.531985 -325.742998)
			(xy 181.57602 -325.778636) (xy 181.614302 -325.820393) (xy 181.645989 -325.867351) (xy 181.670384 -325.918479)
			(xy 181.686951 -325.972651) (xy 181.695327 -326.028678) (xy 181.695327 -326.085327) (xy 181.68695 -326.141353)
			(xy 181.670382 -326.195525) (xy 181.645986 -326.246652) (xy 181.614299 -326.29361) (xy 181.576017 -326.335367)
			(xy 181.531982 -326.371004) (xy 181.483161 -326.399739) (xy 181.457092 -326.410828) (xy 181.425342 -326.423528)
			(xy 181.425342 -327.393554) (xy 182.126636 -328.094848) (xy 185.60034 -328.094848) (xy 185.625299 -328.095423)
			(xy 185.674255 -328.10517) (xy 185.720369 -328.124282) (xy 185.761867 -328.152024) (xy 185.779918 -328.16927)
			(xy 186.513978 -328.90333) (xy 186.531242 -328.921369) (xy 186.559009 -328.96286) (xy 186.57813 -329.008979)
			(xy 186.587867 -329.057945) (xy 186.5884 -329.082908) (xy 186.5884 -340.853268) (xy 186.587782 -340.878222)
			(xy 186.578033 -340.927169) (xy 186.558924 -340.973274) (xy 186.531188 -341.014765) (xy 186.513978 -341.032846)
			(xy 185.345578 -342.201246) (xy 185.32938 -342.216787) (xy 185.292573 -342.242475) (xy 185.251823 -342.261291)
			(xy 185.2084 -342.272651) (xy 185.186066 -342.274906) (xy 185.165256 -342.292053) (xy 185.119715 -342.320924)
			(xy 185.070558 -342.343084) (xy 185.018767 -342.358089) (xy 184.965377 -342.36564) (xy 184.938416 -342.366092)
			(xy 184.913287 -342.365692) (xy 184.863465 -342.359093) (xy 184.81494 -342.346008) (xy 184.768555 -342.326663)
			(xy 184.725113 -342.301393) (xy 184.70499 -342.286336) (xy 184.691274 -342.275668) (xy 184.550558 -342.275668)
			(xy 184.536842 -342.286336) (xy 184.51672 -342.301392) (xy 184.473274 -342.326653) (xy 184.426888 -342.345993)
			(xy 184.378365 -342.359075) (xy 184.328544 -342.365674) (xy 184.303416 -342.366092) (xy 184.276586 -342.365637)
			(xy 184.223455 -342.358122) (xy 184.1719 -342.343238) (xy 184.12294 -342.321277) (xy 184.077539 -342.292674)
			(xy 184.056782 -342.275668) (xy 183.90235 -342.275668) (xy 183.881585 -342.292664) (xy 183.836188 -342.321274)
			(xy 183.78723 -342.343241) (xy 183.735677 -342.35813) (xy 183.682546 -342.365649) (xy 183.628886 -342.365649)
			(xy 183.575755 -342.35813) (xy 183.524202 -342.343241) (xy 183.475244 -342.321274) (xy 183.429847 -342.292664)
			(xy 183.409082 -342.275668) (xy 180.113432 -342.275668) (xy 180.092667 -342.292664) (xy 180.04727 -342.321274)
			(xy 179.998312 -342.343241) (xy 179.946759 -342.35813) (xy 179.893628 -342.365649) (xy 179.839968 -342.365649)
			(xy 179.786837 -342.35813) (xy 179.735284 -342.343241) (xy 179.686326 -342.321274) (xy 179.640929 -342.292664)
			(xy 179.620164 -342.275668) (xy 179.465732 -342.275668) (xy 179.444967 -342.292663) (xy 179.39957 -342.321269)
			(xy 179.350611 -342.343229) (xy 179.299058 -342.35811) (xy 179.245927 -342.365617) (xy 179.219098 -342.366092)
			(xy 179.19397 -342.365691) (xy 179.144148 -342.35909) (xy 179.095625 -342.346003) (xy 179.049241 -342.326656)
			(xy 179.0058 -342.301384) (xy 178.985672 -342.286336) (xy 178.971956 -342.275668) (xy 178.83124 -342.275668)
			(xy 178.817524 -342.286336) (xy 178.797402 -342.301391) (xy 178.753956 -342.32665) (xy 178.707569 -342.345987)
			(xy 178.659046 -342.359068) (xy 178.609226 -342.365665) (xy 178.584098 -342.366092) (xy 178.557268 -342.365636)
			(xy 178.504138 -342.358119) (xy 178.452585 -342.343232) (xy 178.403627 -342.32127) (xy 178.358227 -342.292666)
			(xy 178.337464 -342.275668) (xy 175.406304 -342.275668) (xy 175.38554 -342.292667) (xy 175.340145 -342.321282)
			(xy 175.291187 -342.343251) (xy 175.239633 -342.358141) (xy 175.186501 -342.365658) (xy 175.15967 -342.366092)
			(xy 175.134542 -342.365689) (xy 175.084722 -342.359085) (xy 175.036201 -342.345995) (xy 174.98982 -342.326645)
			(xy 174.946382 -342.301372) (xy 174.926244 -342.286336) (xy 174.912528 -342.275668) (xy 174.771812 -342.275668)
			(xy 174.758096 -342.286336) (xy 174.737975 -342.301395) (xy 174.69453 -342.326662) (xy 174.648145 -342.346008)
			(xy 174.599621 -342.359097) (xy 174.549799 -342.365704) (xy 174.52467 -342.366092) (xy 174.497841 -342.365634)
			(xy 174.444713 -342.358113) (xy 174.393162 -342.343224) (xy 174.344206 -342.321259) (xy 174.298809 -342.292653)
			(xy 174.278036 -342.275668) (xy 174.123604 -342.275668) (xy 174.102839 -342.292664) (xy 174.057442 -342.321274)
			(xy 174.008484 -342.343241) (xy 173.956931 -342.35813) (xy 173.9038 -342.365649) (xy 173.85014 -342.365649)
			(xy 173.797009 -342.35813) (xy 173.745456 -342.343241) (xy 173.696498 -342.321274) (xy 173.651101 -342.292664)
			(xy 173.630336 -342.275668) (xy 170.436032 -342.275668) (xy 170.415267 -342.292664) (xy 170.36987 -342.321274)
			(xy 170.320912 -342.343241) (xy 170.269359 -342.35813) (xy 170.216228 -342.365649) (xy 170.162568 -342.365649)
			(xy 170.109437 -342.35813) (xy 170.057884 -342.343241) (xy 170.008926 -342.321274) (xy 169.963529 -342.292664)
			(xy 169.942764 -342.275668) (xy 169.788332 -342.275668) (xy 169.767567 -342.292663) (xy 169.72217 -342.321269)
			(xy 169.673211 -342.343229) (xy 169.621658 -342.35811) (xy 169.568527 -342.365617) (xy 169.541698 -342.366092)
			(xy 169.51657 -342.365691) (xy 169.466748 -342.35909) (xy 169.418225 -342.346003) (xy 169.371841 -342.326656)
			(xy 169.3284 -342.301384) (xy 169.308272 -342.286336) (xy 169.294556 -342.275668) (xy 169.15384 -342.275668)
			(xy 169.140124 -342.286336) (xy 169.120002 -342.301391) (xy 169.076556 -342.32665) (xy 169.030169 -342.345987)
			(xy 168.981646 -342.359068) (xy 168.931826 -342.365665) (xy 168.906698 -342.366092) (xy 168.879868 -342.365636)
			(xy 168.826738 -342.358119) (xy 168.775185 -342.343232) (xy 168.726227 -342.32127) (xy 168.680827 -342.292666)
			(xy 168.660064 -342.275668) (xy 149.83714 -342.275668) (xy 149.812182 -342.275091) (xy 149.763227 -342.265341)
			(xy 149.717116 -342.246228) (xy 149.675619 -342.218485) (xy 149.657562 -342.201246) (xy 148.44522 -340.988904)
			(xy 148.427961 -340.970863) (xy 148.400205 -340.92937) (xy 148.381096 -340.883251) (xy 148.371372 -340.834287)
			(xy 148.370798 -340.809326) (xy 148.370798 -332.386686) (xy 147.902422 -331.91831) (xy 134.257542 -331.91831)
			(xy 134.232588 -331.917693) (xy 134.183639 -331.907946) (xy 134.137533 -331.888838) (xy 134.096039 -331.861104)
			(xy 134.077964 -331.843888) (xy 133.646164 -331.412088) (xy 133.628902 -331.394048) (xy 133.601138 -331.352555)
			(xy 133.582019 -331.306437) (xy 133.57228 -331.257472) (xy 133.571742 -331.23251) (xy 133.571742 -329.000866)
			(xy 131.332986 -326.76211) (xy 127.247142 -326.76211) (xy 127.222188 -326.761493) (xy 127.173239 -326.751746)
			(xy 127.127133 -326.732638) (xy 127.085639 -326.704904) (xy 127.067564 -326.687688) (xy 125.543564 -325.163688)
			(xy 125.526302 -325.145648) (xy 125.498538 -325.104155) (xy 125.479419 -325.058037) (xy 125.46968 -325.009072)
			(xy 125.469142 -324.98411) (xy 125.469142 -323.743066) (xy 124.957586 -323.23151) (xy 93.367098 -323.23151)
			(xy 93.033342 -323.565266) (xy 93.033342 -325.13651) (xy 93.03277 -325.16147) (xy 93.023027 -325.210429)
			(xy 93.003919 -325.256546) (xy 92.976179 -325.298048) (xy 92.95892 -325.316088) (xy 91.63812 -326.636888)
			(xy 91.620079 -326.654148) (xy 91.578586 -326.681905) (xy 91.532468 -326.701016) (xy 91.483503 -326.710744)
			(xy 91.458542 -326.71131) (xy 85.874098 -326.71131) (xy 85.108542 -327.476866) (xy 85.108542 -329.290426)
			(xy 85.107968 -329.315385) (xy 85.098223 -329.364343) (xy 85.079112 -329.410458) (xy 85.051371 -329.451957)
			(xy 85.03412 -329.470004) (xy 83.772756 -330.731368) (xy 83.754714 -330.748626) (xy 83.71322 -330.776381)
			(xy 83.667102 -330.795492) (xy 83.618139 -330.805223) (xy 83.593178 -330.80579) (xy 80.078834 -330.80579)
			(xy 76.240894 -334.64373) (xy 76.222851 -334.660985) (xy 76.181356 -334.688734) (xy 76.135238 -334.707837)
			(xy 76.086276 -334.717558) (xy 76.061316 -334.718152) (xy 68.036186 -334.718152) (xy 59.101736 -343.652602)
			(xy 59.083695 -343.669862) (xy 59.042202 -343.697621) (xy 58.996084 -343.716733) (xy 58.947119 -343.726464)
			(xy 58.922158 -343.727024) (xy 38.225476 -343.727024) (xy 38.20052 -343.72641) (xy 38.151568 -343.716669)
			(xy 38.105456 -343.697567) (xy 38.063957 -343.669836) (xy 38.045898 -343.652602) (xy 36.120832 -341.727536)
			(xy 36.103575 -341.709494) (xy 36.075824 -341.667999) (xy 36.056716 -341.621881) (xy 36.046989 -341.572918)
			(xy 36.04641 -341.547958) (xy 36.04641 -323.43725) (xy 31.383986 -318.774826) (xy 29.346398 -318.774826)
			(xy 29.333444 -318.806068) (xy 29.322944 -318.830086) (xy 29.295929 -318.875005) (xy 29.262624 -318.915482)
			(xy 29.223748 -318.950642) (xy 29.18014 -318.979726) (xy 29.132741 -319.002107) (xy 29.082574 -319.017301)
			(xy 29.030723 -319.024981) (xy 28.978305 -319.024981) (xy 28.926454 -319.017301) (xy 28.876287 -319.002107)
			(xy 28.828888 -318.979726) (xy 28.78528 -318.950642) (xy 28.746404 -318.915482) (xy 28.713099 -318.875005)
			(xy 28.686084 -318.830086) (xy 28.675584 -318.806068) (xy 28.66263 -318.774826) (xy 21.72081 -318.774826)
			(xy 21.705574 -318.797659) (xy 21.669216 -318.838781) (xy 21.626982 -318.873842) (xy 21.579871 -318.90201)
			(xy 21.528997 -318.922621) (xy 21.475564 -318.935185) (xy 21.420836 -318.939407) (xy 21.366108 -318.935185)
			(xy 21.312675 -318.922621) (xy 21.261801 -318.90201) (xy 21.21469 -318.873842) (xy 21.172456 -318.838781)
			(xy 21.136098 -318.797659) (xy 21.120862 -318.774826) (xy 13.617448 -318.774826) (xy 13.595111 -318.789524)
			(xy 13.546964 -318.812776) (xy 13.495882 -318.828573) (xy 13.443014 -318.836562) (xy 13.389546 -318.836562)
			(xy 13.336678 -318.828573) (xy 13.285596 -318.812776) (xy 13.237449 -318.789524) (xy 13.215112 -318.774826)
			(xy 7.493254 -318.774826) (xy 7.480104 -318.775244) (xy 7.45468 -318.781972) (xy 7.431818 -318.794971)
			(xy 7.413034 -318.813379) (xy 7.399574 -318.835973) (xy 7.392332 -318.861255) (xy 7.391654 -318.874394)
			(xy 7.390548 -318.901984) (xy 7.380867 -318.956344) (xy 7.36291 -319.008558) (xy 7.337108 -319.057374)
			(xy 7.304079 -319.101621) (xy 7.264616 -319.14024) (xy 7.219664 -319.172303) (xy 7.170301 -319.197042)
			(xy 7.117711 -319.213864) (xy 7.063154 -319.222366) (xy 7.035546 -319.222882) (xy 7.009082 -319.222421)
			(xy 6.956731 -319.214622) (xy 6.906117 -319.199145) (xy 6.858358 -319.176333) (xy 6.836156 -319.161922)
			(xy 6.801612 -319.1383) (xy 6.615938 -319.323974) (xy 6.615938 -327.65365) (xy 6.61543 -327.668128)
			(xy 6.61543 -334.888586) (xy 8.902954 -337.17611) (xy 22.328378 -337.17611) (xy 22.353331 -337.176729)
			(xy 22.402277 -337.18648) (xy 22.44838 -337.205591) (xy 22.489869 -337.233329) (xy 22.507956 -337.250532)
			(xy 25.248616 -339.991192) (xy 25.265873 -340.009234) (xy 25.293626 -340.050728) (xy 25.312732 -340.096846)
			(xy 25.322456 -340.14581) (xy 25.323038 -340.17077) (xy 25.323038 -347.58757) (xy 76.01204 -347.58757)
			(xy 76.01204 -341.25154) (xy 76.012609 -341.226579) (xy 76.022338 -341.177616) (xy 76.041449 -341.131498)
			(xy 76.069203 -341.090003) (xy 76.086462 -341.071962) (xy 77.03439 -340.124034) (xy 77.052458 -340.106809)
			(xy 77.093953 -340.079076) (xy 77.140062 -340.05997) (xy 77.189013 -340.050227) (xy 77.213968 -340.049612)
			(xy 83.018376 -340.049612) (xy 83.227672 -339.840316) (xy 83.209384 -339.807042) (xy 83.194759 -339.778848)
			(xy 83.174048 -339.718808) (xy 83.163538 -339.656172) (xy 83.162902 -339.624416) (xy 83.163339 -339.598276)
			(xy 83.170491 -339.546489) (xy 83.184649 -339.496163) (xy 83.205549 -339.448243) (xy 83.232797 -339.403627)
			(xy 83.249008 -339.383116) (xy 83.249008 -339.205316) (xy 83.231063 -339.182471) (xy 83.201546 -339.132441)
			(xy 83.179959 -339.078512) (xy 83.166803 -339.021933) (xy 83.162383 -338.964012) (xy 83.1668 -338.906092)
			(xy 83.179952 -338.849512) (xy 83.201535 -338.795581) (xy 83.231049 -338.745549) (xy 83.249008 -338.722716)
			(xy 83.249008 -338.544916) (xy 83.231063 -338.522071) (xy 83.201546 -338.472041) (xy 83.179959 -338.418112)
			(xy 83.166803 -338.361533) (xy 83.162383 -338.303612) (xy 83.1668 -338.245692) (xy 83.179952 -338.189112)
			(xy 83.201535 -338.135181) (xy 83.231049 -338.085149) (xy 83.249008 -338.062316) (xy 83.249008 -337.884516)
			(xy 83.231063 -337.861671) (xy 83.201546 -337.811641) (xy 83.179959 -337.757712) (xy 83.166803 -337.701133)
			(xy 83.162383 -337.643212) (xy 83.1668 -337.585292) (xy 83.179952 -337.528712) (xy 83.201535 -337.474781)
			(xy 83.231049 -337.424749) (xy 83.249008 -337.401916) (xy 83.249008 -337.224116) (xy 83.232809 -337.203596)
			(xy 83.205549 -337.158986) (xy 83.184643 -337.111069) (xy 83.170482 -337.060744) (xy 83.163334 -337.008956)
			(xy 83.162902 -336.982816) (xy 83.163435 -336.954077) (xy 83.172055 -336.89725) (xy 83.189103 -336.84236)
			(xy 83.214193 -336.790648) (xy 83.246756 -336.743285) (xy 83.266026 -336.721958) (xy 83.276197 -336.697407)
			(xy 83.305145 -336.652851) (xy 83.32343 -336.633566) (xy 85.571584 -334.385412) (xy 85.589651 -334.368187)
			(xy 85.631147 -334.340454) (xy 85.677257 -334.321349) (xy 85.726207 -334.311605) (xy 85.751162 -334.31099)
			(xy 91.011502 -334.31099) (xy 91.209368 -334.113124) (xy 91.209368 -332.966314) (xy 91.209913 -332.941352)
			(xy 91.219648 -332.892387) (xy 91.238766 -332.846268) (xy 91.266528 -332.804776) (xy 91.28379 -332.786736)
			(xy 91.370658 -332.699868) (xy 91.356434 -332.668118) (xy 91.345999 -332.64359) (xy 91.331289 -332.592358)
			(xy 91.32386 -332.539575) (xy 91.323414 -332.512924) (xy 91.323878 -332.485671) (xy 91.331632 -332.431719)
			(xy 91.346986 -332.379419) (xy 91.369627 -332.329838) (xy 91.399095 -332.283984) (xy 91.434789 -332.24279)
			(xy 91.475982 -332.207096) (xy 91.521836 -332.177628) (xy 91.571418 -332.154987) (xy 91.623717 -332.139632)
			(xy 91.677669 -332.131878) (xy 91.704922 -332.131416) (xy 91.731574 -332.131859) (xy 91.784357 -332.139286)
			(xy 91.835592 -332.153992) (xy 91.860116 -332.164436) (xy 91.891866 -332.17866) (xy 92.031058 -332.039468)
			(xy 92.016834 -332.007718) (xy 92.006399 -331.98319) (xy 91.991689 -331.931958) (xy 91.98426 -331.879175)
			(xy 91.983814 -331.852524) (xy 91.984278 -331.825271) (xy 91.992032 -331.771319) (xy 92.007386 -331.719019)
			(xy 92.030027 -331.669438) (xy 92.059495 -331.623584) (xy 92.095189 -331.58239) (xy 92.136382 -331.546696)
			(xy 92.182236 -331.517228) (xy 92.231818 -331.494587) (xy 92.284117 -331.479232) (xy 92.338069 -331.471478)
			(xy 92.365322 -331.471016) (xy 92.391974 -331.471459) (xy 92.444757 -331.478886) (xy 92.495992 -331.493592)
			(xy 92.520516 -331.504036) (xy 92.552266 -331.51826) (xy 93.078046 -330.99248) (xy 93.08084 -330.976732)
			(xy 93.085958 -330.950582) (xy 93.102415 -330.899904) (xy 93.125766 -330.85201) (xy 93.155556 -330.807832)
			(xy 93.191206 -330.768231) (xy 93.23202 -330.733978) (xy 93.277205 -330.705739) (xy 93.325881 -330.684065)
			(xy 93.3771 -330.669377) (xy 93.429864 -330.661961) (xy 93.456506 -330.661518) (xy 93.484601 -330.662034)
			(xy 93.540183 -330.670269) (xy 93.593954 -330.686575) (xy 93.644748 -330.710599) (xy 93.691465 -330.741819)
			(xy 93.733093 -330.77956) (xy 93.768729 -330.823003) (xy 93.7976 -330.871207) (xy 93.808804 -330.896976)
			(xy 93.822012 -330.928218) (xy 99.5172 -330.928218) (xy 99.528821 -330.903354) (xy 99.558162 -330.856972)
			(xy 99.593848 -330.815275) (xy 99.635142 -330.779124) (xy 99.681192 -330.749265) (xy 99.731046 -330.726315)
			(xy 99.783675 -330.710749) (xy 99.837992 -330.702887) (xy 99.865434 -330.702412) (xy 99.894174 -330.702912)
			(xy 99.951002 -330.71154) (xy 100.005894 -330.728595) (xy 100.057605 -330.753692) (xy 100.104966 -330.786263)
			(xy 100.126292 -330.805536) (xy 100.137826 -330.815608) (xy 100.165372 -330.82895) (xy 100.195634 -330.833535)
			(xy 100.225896 -330.82895) (xy 100.253442 -330.815608) (xy 100.264976 -330.805536) (xy 100.286289 -330.786249)
			(xy 100.333655 -330.753685) (xy 100.38537 -330.728596) (xy 100.440264 -330.711549) (xy 100.497094 -330.70293)
			(xy 100.525834 -330.702412) (xy 100.553274 -330.702873) (xy 100.607585 -330.710753) (xy 100.660208 -330.726333)
			(xy 100.710056 -330.749289) (xy 100.756101 -330.77915) (xy 100.797394 -330.815299) (xy 100.833083 -330.856989)
			(xy 100.862432 -330.903363) (xy 100.874068 -330.928218) (xy 101.251512 -330.928218) (xy 101.26472 -330.896976)
			(xy 101.275926 -330.871207) (xy 101.3048 -330.823003) (xy 101.340436 -330.779559) (xy 101.382063 -330.741816)
			(xy 101.428779 -330.71059) (xy 101.479571 -330.68656) (xy 101.533341 -330.670244) (xy 101.588923 -330.661997)
			(xy 101.645113 -330.661997) (xy 101.700695 -330.670244) (xy 101.754465 -330.68656) (xy 101.805257 -330.71059)
			(xy 101.851973 -330.741816) (xy 101.8936 -330.779559) (xy 101.929236 -330.823003) (xy 101.95811 -330.871207)
			(xy 101.969316 -330.896976) (xy 101.982524 -330.928218) (xy 107.677712 -330.928218) (xy 107.689324 -330.90335)
			(xy 107.718665 -330.856967) (xy 107.754353 -330.81527) (xy 107.795649 -330.779119) (xy 107.8417 -330.749261)
			(xy 107.891556 -330.726312) (xy 107.944186 -330.710747) (xy 107.998504 -330.702886) (xy 108.025946 -330.702412)
			(xy 108.054686 -330.702905) (xy 108.111515 -330.711534) (xy 108.166406 -330.728591) (xy 108.218117 -330.75369)
			(xy 108.265478 -330.786262) (xy 108.286804 -330.805536) (xy 108.298338 -330.815608) (xy 108.325884 -330.82895)
			(xy 108.356146 -330.833535) (xy 108.386408 -330.82895) (xy 108.413954 -330.815608) (xy 108.425488 -330.805536)
			(xy 108.446796 -330.786243) (xy 108.494163 -330.75368) (xy 108.54588 -330.728592) (xy 108.600775 -330.711546)
			(xy 108.657606 -330.70293) (xy 108.686346 -330.702412) (xy 108.713786 -330.702863) (xy 108.768098 -330.710745)
			(xy 108.820721 -330.726326) (xy 108.870569 -330.749284) (xy 108.916614 -330.779146) (xy 108.957907 -330.815296)
			(xy 108.993596 -330.856988) (xy 109.022944 -330.903362) (xy 109.03458 -330.928218) (xy 109.412024 -330.928218)
			(xy 109.425232 -330.896976) (xy 109.436438 -330.871207) (xy 109.465312 -330.823003) (xy 109.500948 -330.779559)
			(xy 109.542575 -330.741816) (xy 109.589291 -330.71059) (xy 109.640083 -330.68656) (xy 109.693853 -330.670244)
			(xy 109.749435 -330.661997) (xy 109.805625 -330.661997) (xy 109.861207 -330.670244) (xy 109.914977 -330.68656)
			(xy 109.965769 -330.71059) (xy 110.012485 -330.741816) (xy 110.054112 -330.779559) (xy 110.089748 -330.823003)
			(xy 110.118622 -330.871207) (xy 110.129828 -330.896976) (xy 110.143036 -330.928218) (xy 116.158772 -330.928218)
			(xy 116.179943 -330.909717) (xy 116.226699 -330.878494) (xy 116.277528 -330.854465) (xy 116.331332 -330.838152)
			(xy 116.386947 -330.829906) (xy 116.443169 -330.829906) (xy 116.498784 -330.838152) (xy 116.552588 -330.854465)
			(xy 116.603417 -330.878494) (xy 116.650173 -330.909717) (xy 116.671344 -330.928218) (xy 116.819172 -330.928218)
			(xy 116.840343 -330.909717) (xy 116.887099 -330.878494) (xy 116.937928 -330.854465) (xy 116.991732 -330.838152)
			(xy 117.047347 -330.829906) (xy 117.103569 -330.829906) (xy 117.159184 -330.838152) (xy 117.212988 -330.854465)
			(xy 117.263817 -330.878494) (xy 117.310573 -330.909717) (xy 117.331744 -330.928218) (xy 123.998736 -330.928218)
			(xy 124.010329 -330.90334) (xy 124.039673 -330.856957) (xy 124.075363 -330.81526) (xy 124.116661 -330.77911)
			(xy 124.162715 -330.749252) (xy 124.212574 -330.726305) (xy 124.265207 -330.710742) (xy 124.319527 -330.702884)
			(xy 124.34697 -330.702412) (xy 124.375708 -330.702951) (xy 124.432535 -330.711569) (xy 124.487426 -330.728616)
			(xy 124.539138 -330.753704) (xy 124.586501 -330.786266) (xy 124.607828 -330.805536) (xy 124.619362 -330.815608)
			(xy 124.646908 -330.82895) (xy 124.67717 -330.833535) (xy 124.707432 -330.82895) (xy 124.734978 -330.815608)
			(xy 124.746512 -330.805536) (xy 124.767851 -330.786279) (xy 124.81521 -330.753711) (xy 124.866918 -330.728616)
			(xy 124.921807 -330.711562) (xy 124.978632 -330.702935) (xy 125.00737 -330.702412) (xy 125.034811 -330.702843)
			(xy 125.089124 -330.710728) (xy 125.141747 -330.726312) (xy 125.191595 -330.749274) (xy 125.23764 -330.779138)
			(xy 125.278933 -330.815291) (xy 125.314621 -330.856985) (xy 125.343968 -330.903361) (xy 125.355604 -330.928218)
			(xy 126.794768 -330.928218) (xy 126.819729 -330.928789) (xy 126.868692 -330.938518) (xy 126.91481 -330.957628)
			(xy 126.956304 -330.985382) (xy 126.974346 -331.00264) (xy 127.440436 -331.46873) (xy 127.457658 -331.486802)
			(xy 127.485404 -331.528293) (xy 127.504522 -331.5744) (xy 127.514278 -331.623351) (xy 127.514858 -331.648308)
			(xy 127.514858 -333.86649) (xy 127.944626 -334.296258) (xy 134.34568 -334.296258) (xy 134.370642 -334.29681)
			(xy 134.419606 -334.306543) (xy 134.465725 -334.325659) (xy 134.507218 -334.353419) (xy 134.525258 -334.37068)
			(xy 135.891016 -335.736438) (xy 135.908224 -335.75452) (xy 135.935959 -335.796012) (xy 135.955068 -335.842116)
			(xy 135.964819 -335.891062) (xy 135.965438 -335.916016) (xy 135.965438 -340.650322) (xy 135.988681 -340.663411)
			(xy 136.031446 -340.695299) (xy 136.069226 -340.732959) (xy 136.101249 -340.775622) (xy 136.126861 -340.822416)
			(xy 136.145538 -340.872384) (xy 136.156899 -340.924505) (xy 136.16071 -340.977713) (xy 136.156895 -341.030921)
			(xy 136.145531 -341.083041) (xy 136.12685 -341.133008) (xy 136.101235 -341.1798) (xy 136.069208 -341.222461)
			(xy 136.031426 -341.260119) (xy 135.988659 -341.292003) (xy 135.965438 -341.305134) (xy 135.965438 -341.4395)
			(xy 135.990297 -341.453614) (xy 136.035784 -341.48823) (xy 136.075449 -341.52939) (xy 136.108359 -341.576126)
			(xy 136.133743 -341.627342) (xy 136.151004 -341.681835) (xy 136.159736 -341.738325) (xy 136.160256 -341.766906)
			(xy 136.159837 -341.791752) (xy 136.153232 -341.841002) (xy 136.140141 -341.888937) (xy 136.120795 -341.934708)
			(xy 136.095537 -341.977501) (xy 136.0805 -341.997284) (xy 136.50595 -342.422734) (xy 136.809734 -342.422734)
			(xy 136.823704 -342.394032) (xy 136.83542 -342.370687) (xy 136.864487 -342.327287) (xy 136.899329 -342.288372)
			(xy 136.939265 -342.254704) (xy 136.983511 -342.226943) (xy 137.0312 -342.205633) (xy 137.081398 -342.191192)
			(xy 137.133121 -342.183903) (xy 137.159238 -342.183466) (xy 137.187944 -342.183966) (xy 137.244674 -342.192783)
			(xy 137.299379 -342.210204) (xy 137.350762 -342.235814) (xy 137.397605 -342.269008) (xy 137.418572 -342.288622)
			(xy 137.430247 -342.299161) (xy 137.458376 -342.313195) (xy 137.489438 -342.318024) (xy 137.5205 -342.313195)
			(xy 137.548629 -342.299161) (xy 137.560304 -342.288622) (xy 137.58126 -342.268998) (xy 137.628108 -342.235812)
			(xy 137.679494 -342.210211) (xy 137.734201 -342.192801) (xy 137.790933 -342.183994) (xy 137.819638 -342.183466)
			(xy 137.845754 -342.183883) (xy 137.897474 -342.191182) (xy 137.947667 -342.205631) (xy 137.995352 -342.226948)
			(xy 138.039592 -342.254715) (xy 138.079522 -342.288387) (xy 138.114358 -342.327305) (xy 138.143419 -342.370706)
			(xy 138.155172 -342.394032) (xy 138.169142 -342.422734) (xy 139.615418 -342.422734) (xy 139.629388 -342.394286)
			(xy 139.642007 -342.369532) (xy 139.673471 -342.32374) (xy 139.711387 -342.283127) (xy 139.754912 -342.248595)
			(xy 139.803083 -342.220909) (xy 139.85483 -342.200682) (xy 139.909008 -342.188364) (xy 139.964414 -342.184228)
			(xy 140.01982 -342.188364) (xy 140.073998 -342.200682) (xy 140.125745 -342.220909) (xy 140.173916 -342.248595)
			(xy 140.217441 -342.283127) (xy 140.255357 -342.32374) (xy 140.286821 -342.369532) (xy 140.29944 -342.394286)
			(xy 140.31341 -342.422734) (xy 142.897352 -342.422734) (xy 142.922312 -342.42331) (xy 142.971276 -342.433037)
			(xy 143.017394 -342.452145) (xy 143.058888 -342.479898) (xy 143.07693 -342.497156) (xy 143.379952 -342.800178)
			(xy 143.3972 -342.818227) (xy 143.42494 -342.859727) (xy 143.444051 -342.905841) (xy 143.453799 -342.954797)
			(xy 143.454374 -342.979756) (xy 143.454374 -346.690442) (xy 143.45379 -346.715402) (xy 143.444065 -346.764365)
			(xy 143.424959 -346.810483) (xy 143.397208 -346.851978) (xy 143.379952 -346.87002) (xy 139.885674 -350.364298)
			(xy 139.867584 -350.381498) (xy 139.826095 -350.409235) (xy 139.779993 -350.428347) (xy 139.731049 -350.438099)
			(xy 139.706096 -350.43872) (xy 121.888504 -350.43872) (xy 120.263158 -352.064066) (xy 120.24507 -352.081268)
			(xy 120.203581 -352.109006) (xy 120.157479 -352.128118) (xy 120.108533 -352.137869) (xy 120.08358 -352.138488)
			(xy 115.75542 -352.138488) (xy 115.730459 -352.137923) (xy 115.681496 -352.128191) (xy 115.635378 -352.10908)
			(xy 115.593884 -352.081324) (xy 115.575842 -352.064066) (xy 113.567718 -350.055942) (xy 97.827084 -350.055942)
			(xy 96.898206 -350.98482) (xy 96.89465 -350.998028) (xy 96.886668 -351.025318) (xy 96.863856 -351.077395)
			(xy 96.833569 -351.12551) (xy 96.796476 -351.168598) (xy 96.753399 -351.205703) (xy 96.705293 -351.236004)
			(xy 96.653222 -351.258831) (xy 96.625918 -351.26676) (xy 96.61271 -351.270316) (xy 96.027748 -351.855278)
			(xy 96.009666 -351.872487) (xy 95.968175 -351.900223) (xy 95.92207 -351.919333) (xy 95.873124 -351.929082)
			(xy 95.84817 -351.9297) (xy 88.251792 -351.9297) (xy 88.226829 -351.929178) (xy 88.177862 -351.919437)
			(xy 88.131743 -351.900313) (xy 88.090252 -351.872544) (xy 88.072214 -351.855278) (xy 85.727794 -349.510858)
			(xy 77.935328 -349.510858) (xy 77.910367 -349.510297) (xy 77.861403 -349.500565) (xy 77.815285 -349.481453)
			(xy 77.773791 -349.453696) (xy 77.75575 -349.436436) (xy 76.086462 -347.767148) (xy 76.069229 -347.749086)
			(xy 76.041485 -347.707591) (xy 76.02237 -347.661481) (xy 76.012618 -347.612527) (xy 76.01204 -347.58757)
			(xy 25.323038 -347.58757) (xy 25.323038 -347.8149) (xy 31.111267 -353.603129) (xy 78.874616 -353.603129)
			(xy 78.874616 -353.446511) (xy 78.882679 -353.290099) (xy 78.898783 -353.13431) (xy 78.922885 -352.979557)
			(xy 78.954922 -352.82625) (xy 78.994808 -352.674795) (xy 79.042438 -352.525594) (xy 79.097686 -352.379043)
			(xy 79.160404 -352.23553) (xy 79.230428 -352.095436) (xy 79.30757 -351.959133) (xy 79.391627 -351.826982)
			(xy 79.482375 -351.699333) (xy 79.579575 -351.576525) (xy 79.682967 -351.458884) (xy 79.792278 -351.34672)
			(xy 79.907219 -351.240333) (xy 80.027483 -351.140004) (xy 80.152753 -351.045999) (xy 80.282696 -350.958568)
			(xy 80.416968 -350.877941) (xy 80.555213 -350.804334) (xy 80.697063 -350.737941) (xy 80.842143 -350.678938)
			(xy 80.990068 -350.627482) (xy 81.140445 -350.58371) (xy 81.292877 -350.547736) (xy 81.446958 -350.519657)
			(xy 81.602281 -350.499548) (xy 81.758433 -350.487461) (xy 81.915 -350.483428) (xy 82.071567 -350.487461)
			(xy 82.227719 -350.499548) (xy 82.383042 -350.519657) (xy 82.537123 -350.547736) (xy 82.689555 -350.58371)
			(xy 82.839932 -350.627482) (xy 82.987857 -350.678938) (xy 83.132937 -350.737941) (xy 83.274787 -350.804334)
			(xy 83.413032 -350.877941) (xy 83.547304 -350.958568) (xy 83.677247 -351.045999) (xy 83.802517 -351.140004)
			(xy 83.922781 -351.240333) (xy 84.037722 -351.34672) (xy 84.147033 -351.458884) (xy 84.250425 -351.576525)
			(xy 84.347625 -351.699333) (xy 84.438373 -351.826982) (xy 84.52243 -351.959133) (xy 84.599572 -352.095436)
			(xy 84.669596 -352.23553) (xy 84.732314 -352.379043) (xy 84.787562 -352.525594) (xy 84.835192 -352.674795)
			(xy 84.875078 -352.82625) (xy 84.907115 -352.979557) (xy 84.931217 -353.13431) (xy 84.947321 -353.290099)
			(xy 84.955384 -353.446511) (xy 84.955888 -353.52482) (xy 84.955384 -353.603129) (xy 84.947321 -353.759541)
			(xy 84.931217 -353.91533) (xy 84.907115 -354.070083) (xy 84.875078 -354.22339) (xy 84.835192 -354.374845)
			(xy 84.791021 -354.513211) (xy 133.478774 -354.513211) (xy 133.478774 -354.356593) (xy 133.486837 -354.200181)
			(xy 133.502941 -354.044392) (xy 133.527043 -353.889639) (xy 133.55908 -353.736332) (xy 133.598966 -353.584877)
			(xy 133.646596 -353.435676) (xy 133.701844 -353.289125) (xy 133.764562 -353.145612) (xy 133.834586 -353.005518)
			(xy 133.911728 -352.869215) (xy 133.995785 -352.737064) (xy 134.086533 -352.609415) (xy 134.183733 -352.486607)
			(xy 134.287125 -352.368966) (xy 134.396436 -352.256802) (xy 134.511377 -352.150415) (xy 134.631641 -352.050086)
			(xy 134.756911 -351.956081) (xy 134.886854 -351.86865) (xy 135.021126 -351.788023) (xy 135.159371 -351.714416)
			(xy 135.301221 -351.648023) (xy 135.446301 -351.58902) (xy 135.594226 -351.537564) (xy 135.744603 -351.493792)
			(xy 135.897035 -351.457818) (xy 136.051116 -351.429739) (xy 136.206439 -351.40963) (xy 136.362591 -351.397543)
			(xy 136.519158 -351.39351) (xy 136.675725 -351.397543) (xy 136.831877 -351.40963) (xy 136.9872 -351.429739)
			(xy 137.141281 -351.457818) (xy 137.293713 -351.493792) (xy 137.44409 -351.537564) (xy 137.592015 -351.58902)
			(xy 137.737095 -351.648023) (xy 137.878945 -351.714416) (xy 138.01719 -351.788023) (xy 138.151462 -351.86865)
			(xy 138.281405 -351.956081) (xy 138.406675 -352.050086) (xy 138.526939 -352.150415) (xy 138.64188 -352.256802)
			(xy 138.751191 -352.368966) (xy 138.854583 -352.486607) (xy 138.951783 -352.609415) (xy 139.042531 -352.737064)
			(xy 139.126588 -352.869215) (xy 139.20373 -353.005518) (xy 139.273754 -353.145612) (xy 139.336472 -353.289125)
			(xy 139.39172 -353.435676) (xy 139.43935 -353.584877) (xy 139.479236 -353.736332) (xy 139.511273 -353.889639)
			(xy 139.535375 -354.044392) (xy 139.551479 -354.200181) (xy 139.559542 -354.356593) (xy 139.560046 -354.434902)
			(xy 139.559542 -354.513211) (xy 139.551479 -354.669623) (xy 139.535375 -354.825412) (xy 139.511273 -354.980165)
			(xy 139.479236 -355.133472) (xy 139.43935 -355.284927) (xy 139.39172 -355.434128) (xy 139.336472 -355.580679)
			(xy 139.273754 -355.724192) (xy 139.20373 -355.864286) (xy 139.126588 -356.000589) (xy 139.042531 -356.13274)
			(xy 138.951783 -356.260389) (xy 138.854583 -356.383197) (xy 138.751191 -356.500838) (xy 138.64188 -356.613002)
			(xy 138.526939 -356.719389) (xy 138.406675 -356.819718) (xy 138.281405 -356.913723) (xy 138.151462 -357.001154)
			(xy 138.01719 -357.081781) (xy 137.878945 -357.155388) (xy 137.737095 -357.221781) (xy 137.592015 -357.280784)
			(xy 137.44409 -357.33224) (xy 137.293713 -357.376012) (xy 137.141281 -357.411986) (xy 136.9872 -357.440065)
			(xy 136.831877 -357.460174) (xy 136.675725 -357.472261) (xy 136.519158 -357.476294) (xy 136.362591 -357.472261)
			(xy 136.206439 -357.460174) (xy 136.051116 -357.440065) (xy 135.897035 -357.411986) (xy 135.744603 -357.376012)
			(xy 135.594226 -357.33224) (xy 135.446301 -357.280784) (xy 135.301221 -357.221781) (xy 135.159371 -357.155388)
			(xy 135.021126 -357.081781) (xy 134.886854 -357.001154) (xy 134.756911 -356.913723) (xy 134.631641 -356.819718)
			(xy 134.511377 -356.719389) (xy 134.396436 -356.613002) (xy 134.287125 -356.500838) (xy 134.183733 -356.383197)
			(xy 134.086533 -356.260389) (xy 133.995785 -356.13274) (xy 133.911728 -356.000589) (xy 133.834586 -355.864286)
			(xy 133.764562 -355.724192) (xy 133.701844 -355.580679) (xy 133.646596 -355.434128) (xy 133.598966 -355.284927)
			(xy 133.55908 -355.133472) (xy 133.527043 -354.980165) (xy 133.502941 -354.825412) (xy 133.486837 -354.669623)
			(xy 133.478774 -354.513211) (xy 84.791021 -354.513211) (xy 84.787562 -354.524046) (xy 84.732314 -354.670597)
			(xy 84.669596 -354.81411) (xy 84.599572 -354.954204) (xy 84.52243 -355.090507) (xy 84.438373 -355.222658)
			(xy 84.347625 -355.350307) (xy 84.250425 -355.473115) (xy 84.147033 -355.590756) (xy 84.037722 -355.70292)
			(xy 83.922781 -355.809307) (xy 83.802517 -355.909636) (xy 83.677247 -356.003641) (xy 83.547304 -356.091072)
			(xy 83.413032 -356.171699) (xy 83.274787 -356.245306) (xy 83.132937 -356.311699) (xy 82.987857 -356.370702)
			(xy 82.839932 -356.422158) (xy 82.689555 -356.46593) (xy 82.537123 -356.501904) (xy 82.383042 -356.529983)
			(xy 82.227719 -356.550092) (xy 82.071567 -356.562179) (xy 81.915 -356.566212) (xy 81.758433 -356.562179)
			(xy 81.602281 -356.550092) (xy 81.446958 -356.529983) (xy 81.292877 -356.501904) (xy 81.140445 -356.46593)
			(xy 80.990068 -356.422158) (xy 80.842143 -356.370702) (xy 80.697063 -356.311699) (xy 80.555213 -356.245306)
			(xy 80.416968 -356.171699) (xy 80.282696 -356.091072) (xy 80.152753 -356.003641) (xy 80.027483 -355.909636)
			(xy 79.907219 -355.809307) (xy 79.792278 -355.70292) (xy 79.682967 -355.590756) (xy 79.579575 -355.473115)
			(xy 79.482375 -355.350307) (xy 79.391627 -355.222658) (xy 79.30757 -355.090507) (xy 79.230428 -354.954204)
			(xy 79.160404 -354.81411) (xy 79.097686 -354.670597) (xy 79.042438 -354.524046) (xy 78.994808 -354.374845)
			(xy 78.954922 -354.22339) (xy 78.922885 -354.070083) (xy 78.898783 -353.91533) (xy 78.882679 -353.759541)
			(xy 78.874616 -353.603129) (xy 31.111267 -353.603129) (xy 37.087048 -359.57891) (xy 56.728614 -359.57891)
			(xy 56.739536 -359.573068) (xy 56.766887 -359.559549) (xy 56.824818 -359.540419) (xy 56.885054 -359.530743)
			(xy 56.915558 -359.530142) (xy 56.946065 -359.530715) (xy 57.006308 -359.540381) (xy 57.064241 -359.55952)
			(xy 57.09158 -359.573068) (xy 57.102502 -359.57891) (xy 85.812122 -359.57891) (xy 87.080598 -358.310434)
			(xy 87.080598 -355.68763) (xy 87.081216 -355.662676) (xy 87.090965 -355.613729) (xy 87.110075 -355.567625)
			(xy 87.137811 -355.526134) (xy 87.15502 -355.508052) (xy 88.04148 -354.621592) (xy 88.059521 -354.604333)
			(xy 88.101015 -354.576578) (xy 88.147133 -354.557469) (xy 88.196097 -354.547742) (xy 88.221058 -354.54717)
			(xy 101.689662 -354.54717) (xy 101.714616 -354.547787) (xy 101.763565 -354.557534) (xy 101.809672 -354.576641)
			(xy 101.851166 -354.604375) (xy 101.86924 -354.621592) (xy 104.562402 -357.314754) (xy 104.572054 -357.318564)
			(xy 104.597413 -357.32908) (xy 104.645069 -357.356335) (xy 104.688327 -357.390136) (xy 104.726297 -357.429786)
			(xy 104.758193 -357.474468) (xy 104.77119 -357.49865) (xy 112.964214 -357.49865) (xy 112.974374 -357.461312)
			(xy 112.982097 -357.434727) (xy 113.004162 -357.383954) (xy 113.033336 -357.336905) (xy 113.069007 -357.294569)
			(xy 113.110425 -357.257836) (xy 113.156719 -357.227477) (xy 113.206916 -357.204132) (xy 113.259961 -357.188291)
			(xy 113.31474 -357.180286) (xy 113.3701 -357.180286) (xy 113.424879 -357.188291) (xy 113.477924 -357.204132)
			(xy 113.528121 -357.227477) (xy 113.574415 -357.257836) (xy 113.615833 -357.294569) (xy 113.651504 -357.336905)
			(xy 113.680678 -357.383954) (xy 113.702743 -357.434727) (xy 113.710466 -357.461312) (xy 113.720626 -357.49865)
			(xy 127.523748 -357.49865) (xy 127.530352 -357.455724) (xy 127.535004 -357.429115) (xy 127.550824 -357.377468)
			(xy 127.573771 -357.328568) (xy 127.603384 -357.283394) (xy 127.639073 -357.242847) (xy 127.680124 -357.207739)
			(xy 127.725715 -357.178771) (xy 127.774937 -357.156523) (xy 127.826804 -357.141439) (xy 127.88028 -357.133821)
			(xy 127.934296 -357.133821) (xy 127.987772 -357.141439) (xy 128.039639 -357.156523) (xy 128.088861 -357.178771)
			(xy 128.134452 -357.207739) (xy 128.175503 -357.242847) (xy 128.211192 -357.283394) (xy 128.240805 -357.328568)
			(xy 128.263752 -357.377468) (xy 128.279572 -357.429115) (xy 128.284224 -357.455724) (xy 128.290828 -357.49865)
			(xy 128.981962 -357.49865) (xy 129.00692 -357.499227) (xy 129.055874 -357.508978) (xy 129.101984 -357.528093)
			(xy 129.143479 -357.555837) (xy 129.16154 -357.573072) (xy 129.33299 -357.744522) (xy 129.344928 -357.748332)
			(xy 129.369533 -357.756653) (xy 129.416408 -357.779026) (xy 129.459814 -357.807551) (xy 129.49895 -357.8417)
			(xy 129.533092 -357.880842) (xy 129.561609 -357.924254) (xy 129.583973 -357.971133) (xy 129.592324 -357.995728)
			(xy 129.596134 -358.007666) (xy 132.924296 -361.335828)
		)
		(stroke
			(width 0)
			(type solid)
		)
		(fill yes)
		(layer "In8.Cu")
		(net "P12V_S3_AUX_CPU1_NVDIMM")
	)
	(gr_poly
		(pts
			(xy 336.42046 -325.563992) (xy 336.438501 -325.546732) (xy 336.479994 -325.518973) (xy 336.526112 -325.49986)
			(xy 336.575077 -325.49013) (xy 336.600038 -325.48957) (xy 339.100922 -325.48957) (xy 341.792814 -322.797678)
			(xy 341.810854 -322.780415) (xy 341.852346 -322.75265) (xy 341.898464 -322.73353) (xy 341.947429 -322.723791)
			(xy 341.972392 -322.723256) (xy 373.002556 -322.723256) (xy 373.027514 -322.723833) (xy 373.076468 -322.733583)
			(xy 373.122579 -322.752697) (xy 373.164075 -322.780441) (xy 373.182134 -322.797678) (xy 373.842534 -323.458078)
			(xy 373.859792 -323.47612) (xy 373.887544 -323.517614) (xy 373.906652 -323.563732) (xy 373.916378 -323.612696)
			(xy 373.916956 -323.637656) (xy 373.916956 -324.8787) (xy 375.292112 -326.253856) (xy 379.035564 -326.253856)
			(xy 379.060522 -326.254434) (xy 379.109475 -326.264185) (xy 379.155585 -326.2833) (xy 379.19708 -326.311045)
			(xy 379.215142 -326.328278) (xy 383.039874 -330.15301) (xy 392.275822 -330.15301) (xy 392.609578 -329.819254)
			(xy 392.609578 -296.321226) (xy 385.612894 -289.324542) (xy 381.76962 -289.324542) (xy 381.5969 -289.651186)
			(xy 381.606806 -289.673792) (xy 381.61571 -289.694883) (xy 381.628263 -289.73891) (xy 381.634597 -289.784251)
			(xy 381.635 -289.807142) (xy 381.634492 -289.833029) (xy 381.626393 -289.884167) (xy 381.610394 -289.933407)
			(xy 381.586888 -289.979539) (xy 381.556456 -290.021426) (xy 381.519846 -290.058036) (xy 381.477959 -290.088468)
			(xy 381.431827 -290.111974) (xy 381.382587 -290.127973) (xy 381.331449 -290.136072) (xy 381.279675 -290.136072)
			(xy 381.228537 -290.127973) (xy 381.179297 -290.111974) (xy 381.133165 -290.088468) (xy 381.091278 -290.058036)
			(xy 381.054668 -290.021426) (xy 381.024236 -289.979539) (xy 381.00073 -289.933407) (xy 380.984731 -289.884167)
			(xy 380.976632 -289.833029) (xy 380.976124 -289.807142) (xy 380.976593 -289.78171) (xy 380.984403 -289.731448)
			(xy 380.999846 -289.682984) (xy 381.022553 -289.637469) (xy 381.051985 -289.595984) (xy 381.087443 -289.559516)
			(xy 381.128084 -289.52893) (xy 381.172943 -289.504953) (xy 381.220954 -289.488156) (xy 381.245872 -289.483038)
			(xy 381.270002 -289.478466) (xy 381.312166 -289.398964) (xy 381.316594 -289.389446) (xy 381.318133 -289.368533)
			(xy 381.311187 -289.348747) (xy 381.296915 -289.333384) (xy 381.277693 -289.325003) (xy 381.267208 -289.324542)
			(xy 379.89002 -289.324542) (xy 379.7173 -289.651186) (xy 379.727206 -289.673792) (xy 379.73611 -289.694883)
			(xy 379.748663 -289.73891) (xy 379.754997 -289.784251) (xy 379.7554 -289.807142) (xy 379.754892 -289.833029)
			(xy 379.746793 -289.884167) (xy 379.730794 -289.933407) (xy 379.707288 -289.979539) (xy 379.676856 -290.021426)
			(xy 379.640246 -290.058036) (xy 379.598359 -290.088468) (xy 379.552227 -290.111974) (xy 379.502987 -290.127973)
			(xy 379.451849 -290.136072) (xy 379.400075 -290.136072) (xy 379.348937 -290.127973) (xy 379.299697 -290.111974)
			(xy 379.253565 -290.088468) (xy 379.211678 -290.058036) (xy 379.175068 -290.021426) (xy 379.144636 -289.979539)
			(xy 379.12113 -289.933407) (xy 379.105131 -289.884167) (xy 379.097032 -289.833029) (xy 379.096524 -289.807142)
			(xy 379.096993 -289.78171) (xy 379.104803 -289.731448) (xy 379.120246 -289.682984) (xy 379.142953 -289.637469)
			(xy 379.172385 -289.595984) (xy 379.207843 -289.559516) (xy 379.248484 -289.52893) (xy 379.293343 -289.504953)
			(xy 379.341354 -289.488156) (xy 379.366272 -289.483038) (xy 379.390402 -289.478466) (xy 379.432566 -289.398964)
			(xy 379.436994 -289.389446) (xy 379.438533 -289.368533) (xy 379.431587 -289.348747) (xy 379.417315 -289.333384)
			(xy 379.398093 -289.325003) (xy 379.387608 -289.324542) (xy 378.01042 -289.324542) (xy 377.8377 -289.651186)
			(xy 377.847606 -289.673792) (xy 377.85651 -289.694883) (xy 377.869063 -289.73891) (xy 377.875397 -289.784251)
			(xy 377.8758 -289.807142) (xy 377.875292 -289.833029) (xy 377.867193 -289.884167) (xy 377.851194 -289.933407)
			(xy 377.827688 -289.979539) (xy 377.797256 -290.021426) (xy 377.760646 -290.058036) (xy 377.718759 -290.088468)
			(xy 377.672627 -290.111974) (xy 377.623387 -290.127973) (xy 377.572249 -290.136072) (xy 377.520475 -290.136072)
			(xy 377.469337 -290.127973) (xy 377.420097 -290.111974) (xy 377.373965 -290.088468) (xy 377.332078 -290.058036)
			(xy 377.295468 -290.021426) (xy 377.265036 -289.979539) (xy 377.24153 -289.933407) (xy 377.225531 -289.884167)
			(xy 377.217432 -289.833029) (xy 377.216924 -289.807142) (xy 377.217393 -289.78171) (xy 377.225203 -289.731448)
			(xy 377.240646 -289.682984) (xy 377.263353 -289.637469) (xy 377.292785 -289.595984) (xy 377.328243 -289.559516)
			(xy 377.368884 -289.52893) (xy 377.413743 -289.504953) (xy 377.461754 -289.488156) (xy 377.486672 -289.483038)
			(xy 377.510802 -289.478466) (xy 377.552966 -289.398964) (xy 377.557394 -289.389446) (xy 377.558933 -289.368533)
			(xy 377.551987 -289.348747) (xy 377.537715 -289.333384) (xy 377.518493 -289.325003) (xy 377.508008 -289.324542)
			(xy 376.13082 -289.324542) (xy 375.9581 -289.651186) (xy 375.968006 -289.673792) (xy 375.97691 -289.694883)
			(xy 375.989463 -289.73891) (xy 375.995797 -289.784251) (xy 375.9962 -289.807142) (xy 375.995692 -289.833029)
			(xy 375.987593 -289.884167) (xy 375.971594 -289.933407) (xy 375.948088 -289.979539) (xy 375.917656 -290.021426)
			(xy 375.881046 -290.058036) (xy 375.839159 -290.088468) (xy 375.793027 -290.111974) (xy 375.743787 -290.127973)
			(xy 375.692649 -290.136072) (xy 375.640875 -290.136072) (xy 375.589737 -290.127973) (xy 375.540497 -290.111974)
			(xy 375.494365 -290.088468) (xy 375.452478 -290.058036) (xy 375.415868 -290.021426) (xy 375.385436 -289.979539)
			(xy 375.36193 -289.933407) (xy 375.345931 -289.884167) (xy 375.337832 -289.833029) (xy 375.337324 -289.807142)
			(xy 375.337793 -289.78171) (xy 375.345603 -289.731448) (xy 375.361046 -289.682984) (xy 375.383753 -289.637469)
			(xy 375.413185 -289.595984) (xy 375.448643 -289.559516) (xy 375.489284 -289.52893) (xy 375.534143 -289.504953)
			(xy 375.582154 -289.488156) (xy 375.607072 -289.483038) (xy 375.631202 -289.478466) (xy 375.673366 -289.398964)
			(xy 375.677794 -289.389446) (xy 375.679333 -289.368533) (xy 375.672387 -289.348747) (xy 375.658115 -289.333384)
			(xy 375.638893 -289.325003) (xy 375.628408 -289.324542) (xy 374.25122 -289.324542) (xy 374.0785 -289.651186)
			(xy 374.088406 -289.673792) (xy 374.09731 -289.694883) (xy 374.109863 -289.73891) (xy 374.116197 -289.784251)
			(xy 374.1166 -289.807142) (xy 374.116092 -289.833029) (xy 374.107993 -289.884167) (xy 374.091994 -289.933407)
			(xy 374.068488 -289.979539) (xy 374.038056 -290.021426) (xy 374.001446 -290.058036) (xy 373.959559 -290.088468)
			(xy 373.913427 -290.111974) (xy 373.864187 -290.127973) (xy 373.813049 -290.136072) (xy 373.761275 -290.136072)
			(xy 373.710137 -290.127973) (xy 373.660897 -290.111974) (xy 373.614765 -290.088468) (xy 373.572878 -290.058036)
			(xy 373.536268 -290.021426) (xy 373.505836 -289.979539) (xy 373.48233 -289.933407) (xy 373.466331 -289.884167)
			(xy 373.458232 -289.833029) (xy 373.457724 -289.807142) (xy 373.458193 -289.78171) (xy 373.466003 -289.731448)
			(xy 373.481446 -289.682984) (xy 373.504153 -289.637469) (xy 373.533585 -289.595984) (xy 373.569043 -289.559516)
			(xy 373.609684 -289.52893) (xy 373.654543 -289.504953) (xy 373.702554 -289.488156) (xy 373.727472 -289.483038)
			(xy 373.751602 -289.478466) (xy 373.793766 -289.398964) (xy 373.798194 -289.389446) (xy 373.799733 -289.368533)
			(xy 373.792787 -289.348747) (xy 373.778515 -289.333384) (xy 373.759293 -289.325003) (xy 373.748808 -289.324542)
			(xy 372.37162 -289.324542) (xy 372.1989 -289.651186) (xy 372.208806 -289.673792) (xy 372.21771 -289.694883)
			(xy 372.230263 -289.73891) (xy 372.236597 -289.784251) (xy 372.237 -289.807142) (xy 372.236492 -289.833029)
			(xy 372.228393 -289.884167) (xy 372.212394 -289.933407) (xy 372.188888 -289.979539) (xy 372.158456 -290.021426)
			(xy 372.121846 -290.058036) (xy 372.079959 -290.088468) (xy 372.033827 -290.111974) (xy 371.984587 -290.127973)
			(xy 371.933449 -290.136072) (xy 371.881675 -290.136072) (xy 371.830537 -290.127973) (xy 371.781297 -290.111974)
			(xy 371.735165 -290.088468) (xy 371.693278 -290.058036) (xy 371.656668 -290.021426) (xy 371.626236 -289.979539)
			(xy 371.60273 -289.933407) (xy 371.586731 -289.884167) (xy 371.578632 -289.833029) (xy 371.578124 -289.807142)
			(xy 371.578593 -289.78171) (xy 371.586403 -289.731448) (xy 371.601846 -289.682984) (xy 371.624553 -289.637469)
			(xy 371.653985 -289.595984) (xy 371.689443 -289.559516) (xy 371.730084 -289.52893) (xy 371.774943 -289.504953)
			(xy 371.822954 -289.488156) (xy 371.847872 -289.483038) (xy 371.872002 -289.478466) (xy 371.914166 -289.398964)
			(xy 371.918594 -289.389446) (xy 371.920133 -289.368533) (xy 371.913187 -289.348747) (xy 371.898915 -289.333384)
			(xy 371.879693 -289.325003) (xy 371.869208 -289.324542) (xy 370.49202 -289.324542) (xy 370.3193 -289.651186)
			(xy 370.329206 -289.673792) (xy 370.33811 -289.694883) (xy 370.350663 -289.73891) (xy 370.356997 -289.784251)
			(xy 370.3574 -289.807142) (xy 370.356892 -289.833029) (xy 370.348793 -289.884167) (xy 370.332794 -289.933407)
			(xy 370.309288 -289.979539) (xy 370.278856 -290.021426) (xy 370.242246 -290.058036) (xy 370.200359 -290.088468)
			(xy 370.154227 -290.111974) (xy 370.104987 -290.127973) (xy 370.053849 -290.136072) (xy 370.002075 -290.136072)
			(xy 369.950937 -290.127973) (xy 369.901697 -290.111974) (xy 369.855565 -290.088468) (xy 369.813678 -290.058036)
			(xy 369.777068 -290.021426) (xy 369.746636 -289.979539) (xy 369.72313 -289.933407) (xy 369.707131 -289.884167)
			(xy 369.699032 -289.833029) (xy 369.698524 -289.807142) (xy 369.698993 -289.78171) (xy 369.706803 -289.731448)
			(xy 369.722246 -289.682984) (xy 369.744953 -289.637469) (xy 369.774385 -289.595984) (xy 369.809843 -289.559516)
			(xy 369.850484 -289.52893) (xy 369.895343 -289.504953) (xy 369.943354 -289.488156) (xy 369.968272 -289.483038)
			(xy 369.992402 -289.478466) (xy 370.034566 -289.398964) (xy 370.038994 -289.389446) (xy 370.040533 -289.368533)
			(xy 370.033587 -289.348747) (xy 370.019315 -289.333384) (xy 370.000093 -289.325003) (xy 369.989608 -289.324542)
			(xy 369.702334 -289.324542) (xy 369.677377 -289.323964) (xy 369.628423 -289.314213) (xy 369.582313 -289.295097)
			(xy 369.54082 -289.267352) (xy 369.522756 -289.25012) (xy 369.51666 -289.244024) (xy 369.490475 -289.240179)
			(xy 369.43971 -289.225225) (xy 369.391989 -289.202346) (xy 369.348542 -289.172129) (xy 369.310486 -289.135354)
			(xy 369.278801 -289.092966) (xy 369.254302 -289.046056) (xy 369.23762 -288.995832) (xy 369.229185 -288.943587)
			(xy 369.228624 -288.917126) (xy 369.229026 -288.895857) (xy 369.234637 -288.853689) (xy 369.2398 -288.833052)
			(xy 369.245134 -288.812732) (xy 369.023646 -288.426906) (xy 369.003326 -288.421572) (xy 368.977374 -288.414082)
			(xy 368.928158 -288.391827) (xy 368.883228 -288.36185) (xy 368.843785 -288.32495) (xy 368.810882 -288.282116)
			(xy 368.785401 -288.234492) (xy 368.768022 -288.183351) (xy 368.75921 -288.130062) (xy 368.758724 -288.103056)
			(xy 368.759113 -288.080934) (xy 368.765099 -288.037095) (xy 368.770662 -288.01568) (xy 368.77625 -287.99536)
			(xy 368.55654 -287.612328) (xy 368.535966 -287.606994) (xy 368.509929 -287.599682) (xy 368.46051 -287.577725)
			(xy 368.415361 -287.547961) (xy 368.375704 -287.511195) (xy 368.342614 -287.468424) (xy 368.316986 -287.420805)
			(xy 368.299514 -287.369628) (xy 368.290671 -287.316279) (xy 368.290094 -287.28924) (xy 368.290471 -287.26659)
			(xy 368.296712 -287.221722) (xy 368.30254 -287.199832) (xy 368.308382 -287.179258) (xy 368.091212 -286.800798)
			(xy 368.07013 -286.795464) (xy 368.046556 -286.789252) (xy 368.001422 -286.770828) (xy 367.959496 -286.745953)
			(xy 367.921694 -286.71517) (xy 367.888843 -286.679152) (xy 367.861659 -286.638685) (xy 367.840738 -286.594653)
			(xy 367.826534 -286.548018) (xy 367.81936 -286.499799) (xy 367.818924 -286.475424) (xy 367.819343 -286.451585)
			(xy 367.826228 -286.404408) (xy 367.83264 -286.381444) (xy 367.83899 -286.360616) (xy 367.624868 -285.987236)
			(xy 367.603278 -285.982156) (xy 367.579479 -285.976115) (xy 367.533867 -285.957942) (xy 367.491458 -285.9332)
			(xy 367.453193 -285.902435) (xy 367.419919 -285.86633) (xy 367.392374 -285.825686) (xy 367.371169 -285.781402)
			(xy 367.356772 -285.734462) (xy 367.349505 -285.685904) (xy 367.349024 -285.661354) (xy 367.349404 -285.636658)
			(xy 367.356672 -285.587807) (xy 367.363502 -285.564072) (xy 367.370106 -285.54299) (xy 367.158524 -285.173928)
			(xy 367.13668 -285.169102) (xy 367.112633 -285.163273) (xy 367.066503 -285.145381) (xy 367.023569 -285.120789)
			(xy 366.984797 -285.090051) (xy 366.95106 -285.053858) (xy 366.923116 -285.013026) (xy 366.901595 -284.968473)
			(xy 366.886982 -284.921203) (xy 366.879604 -284.872277) (xy 366.879124 -284.847538) (xy 366.879637 -284.822097)
			(xy 366.887554 -284.771833) (xy 366.894872 -284.747462) (xy 366.90173 -284.726126) (xy 366.691164 -284.35935)
			(xy 366.66932 -284.354524) (xy 366.645201 -284.348851) (xy 366.598895 -284.331228) (xy 366.555765 -284.306842)
			(xy 366.516792 -284.27625) (xy 366.482861 -284.240145) (xy 366.454744 -284.199349) (xy 366.43308 -284.15479)
			(xy 366.418363 -284.10748) (xy 366.410925 -284.058495) (xy 366.410494 -284.033722) (xy 366.410988 -284.007751)
			(xy 366.419152 -283.956454) (xy 366.42675 -283.931614) (xy 366.433862 -283.910278) (xy 366.22482 -283.545788)
			(xy 366.202468 -283.541216) (xy 366.178157 -283.535703) (xy 366.131437 -283.51832) (xy 366.087883 -283.494073)
			(xy 366.048495 -283.463519) (xy 366.014181 -283.427361) (xy 365.985728 -283.38643) (xy 365.963791 -283.341668)
			(xy 365.948874 -283.294103) (xy 365.941321 -283.24483) (xy 365.940848 -283.219906) (xy 365.941399 -283.193195)
			(xy 365.950084 -283.140483) (xy 365.95812 -283.115004) (xy 365.965486 -283.093414) (xy 365.758476 -282.732226)
			(xy 365.735616 -282.727908) (xy 365.711086 -282.722561) (xy 365.663899 -282.705423) (xy 365.619868 -282.681307)
			(xy 365.580019 -282.650773) (xy 365.545278 -282.614532) (xy 365.516454 -282.573428) (xy 365.494218 -282.528419)
			(xy 365.479088 -282.48055) (xy 365.471415 -282.430937) (xy 365.470948 -282.405836) (xy 365.47151 -282.378318)
			(xy 365.480707 -282.324055) (xy 365.489236 -282.297886) (xy 365.496856 -282.276042) (xy 365.291878 -281.918918)
			(xy 365.269018 -281.9146) (xy 365.244244 -281.909504) (xy 365.196537 -281.89271) (xy 365.151971 -281.868796)
			(xy 365.111602 -281.838327) (xy 365.076386 -281.802026) (xy 365.047156 -281.760751) (xy 365.024604 -281.71548)
			(xy 365.009266 -281.667286) (xy 365.001503 -281.617308) (xy 365.001048 -281.59202) (xy 365.001644 -281.563695)
			(xy 365.011347 -281.507883) (xy 365.020352 -281.481022) (xy 365.028226 -281.459178) (xy 364.825534 -281.10561)
			(xy 364.802166 -281.101292) (xy 364.777185 -281.096381) (xy 364.729027 -281.07987) (xy 364.683997 -281.056121)
			(xy 364.643173 -281.025705) (xy 364.607535 -280.989349) (xy 364.577938 -280.947927) (xy 364.555091 -280.902432)
			(xy 364.539543 -280.853955) (xy 364.531667 -280.803659) (xy 364.531148 -280.778204) (xy 364.531774 -280.749135)
			(xy 364.541993 -280.691901) (xy 364.551468 -280.664412) (xy 364.55985 -280.64206) (xy 364.358936 -280.291794)
			(xy 364.335314 -280.28773) (xy 364.310121 -280.283014) (xy 364.261502 -280.266799) (xy 364.215994 -280.243225)
			(xy 364.174704 -280.212864) (xy 364.138634 -280.176454) (xy 364.108661 -280.134881) (xy 364.085514 -280.089154)
			(xy 364.069756 -280.040385) (xy 364.06177 -279.98976) (xy 364.061248 -279.964134) (xy 364.061874 -279.934316)
			(xy 364.072606 -279.875654) (xy 364.082584 -279.847548) (xy 364.09122 -279.824942) (xy 363.892592 -279.478232)
			(xy 363.868462 -279.474422) (xy 363.843038 -279.469942) (xy 363.793922 -279.45405) (xy 363.747899 -279.430667)
			(xy 363.706103 -279.400369) (xy 363.669563 -279.363904) (xy 363.639181 -279.322169) (xy 363.615705 -279.276193)
			(xy 363.599713 -279.22711) (xy 363.5916 -279.176129) (xy 363.591094 -279.150318) (xy 363.591505 -279.126669)
			(xy 363.598288 -279.079859) (xy 363.611716 -279.034507) (xy 363.631511 -278.99155) (xy 363.657264 -278.951878)
			(xy 363.688442 -278.91631) (xy 363.706156 -278.900636) (xy 363.706156 -277.771606) (xy 363.686917 -277.754463)
			(xy 363.6535 -277.715241) (xy 363.626619 -277.671282) (xy 363.606933 -277.623663) (xy 363.594926 -277.573555)
			(xy 363.590892 -277.522186) (xy 363.59493 -277.470817) (xy 363.606942 -277.420709) (xy 363.626632 -277.373093)
			(xy 363.653517 -277.329135) (xy 363.686937 -277.289917) (xy 363.706156 -277.27275) (xy 363.706156 -276.144482)
			(xy 363.686869 -276.127337) (xy 363.653364 -276.088094) (xy 363.626409 -276.044093) (xy 363.606667 -275.996418)
			(xy 363.594624 -275.946242) (xy 363.590576 -275.8948) (xy 363.594624 -275.843358) (xy 363.606667 -275.793182)
			(xy 363.626409 -275.745507) (xy 363.653364 -275.701506) (xy 363.686869 -275.662263) (xy 363.706156 -275.645118)
			(xy 363.706156 -274.516342) (xy 363.686914 -274.499199) (xy 363.653491 -274.459977) (xy 363.626604 -274.416015)
			(xy 363.606914 -274.368394) (xy 363.594902 -274.318282) (xy 363.590864 -274.266909) (xy 363.594899 -274.215536)
			(xy 363.606908 -274.165423) (xy 363.626596 -274.117801) (xy 363.65348 -274.073838) (xy 363.686901 -274.034613)
			(xy 363.706156 -274.017486) (xy 363.706156 -272.888964) (xy 363.686871 -272.871819) (xy 363.653369 -272.832576)
			(xy 363.626416 -272.788576) (xy 363.606677 -272.740902) (xy 363.594636 -272.690728) (xy 363.590591 -272.639288)
			(xy 363.59464 -272.587849) (xy 363.606684 -272.537675) (xy 363.626427 -272.490003) (xy 363.653383 -272.446005)
			(xy 363.686888 -272.406764) (xy 363.706156 -272.3896) (xy 363.706156 -271.261078) (xy 363.68687 -271.243933)
			(xy 363.653365 -271.20469) (xy 363.626411 -271.160689) (xy 363.606669 -271.113014) (xy 363.594627 -271.062839)
			(xy 363.59058 -271.011397) (xy 363.594627 -270.959956) (xy 363.606671 -270.909781) (xy 363.626413 -270.862106)
			(xy 363.653368 -270.818106) (xy 363.686873 -270.778863) (xy 363.706156 -270.761714) (xy 363.706156 -269.633192)
			(xy 363.686868 -269.616047) (xy 363.653362 -269.576803) (xy 363.626405 -269.532802) (xy 363.606662 -269.485126)
			(xy 363.594618 -269.43495) (xy 363.590569 -269.383507) (xy 363.594615 -269.332063) (xy 363.606658 -269.281886)
			(xy 363.626399 -269.23421) (xy 363.653354 -269.190207) (xy 363.686859 -269.150962) (xy 363.706156 -269.133828)
			(xy 363.706156 -268.00556) (xy 363.686871 -267.988415) (xy 363.65337 -267.949172) (xy 363.626418 -267.905172)
			(xy 363.606679 -267.857499) (xy 363.594639 -267.807325) (xy 363.590594 -267.755886) (xy 363.594643 -267.704447)
			(xy 363.606688 -267.654274) (xy 363.626431 -267.606602) (xy 363.653387 -267.562605) (xy 363.686892 -267.523365)
			(xy 363.706156 -267.506196) (xy 363.706156 -266.377928) (xy 363.686866 -266.360783) (xy 363.653353 -266.321538)
			(xy 363.626391 -266.277535) (xy 363.606643 -266.229857) (xy 363.594594 -266.179677) (xy 363.590541 -266.12823)
			(xy 363.594585 -266.076782) (xy 363.606624 -266.0266) (xy 363.626364 -265.978918) (xy 363.653318 -265.93491)
			(xy 363.686823 -265.895659) (xy 363.706156 -265.878564) (xy 363.706156 -264.750042) (xy 363.686873 -264.732897)
			(xy 363.653374 -264.693654) (xy 363.626425 -264.649656) (xy 363.606688 -264.601984) (xy 363.59465 -264.551811)
			(xy 363.590607 -264.500374) (xy 363.594659 -264.448937) (xy 363.606704 -264.398767) (xy 363.626448 -264.351098)
			(xy 363.653405 -264.307103) (xy 363.686909 -264.267866) (xy 363.706156 -264.250678) (xy 363.706156 -261.179056)
			(xy 363.706732 -261.154098) (xy 363.71648 -261.105142) (xy 363.735592 -261.059029) (xy 363.763335 -261.017532)
			(xy 363.780578 -260.999478) (xy 364.440978 -260.339078) (xy 364.45902 -260.32182) (xy 364.500514 -260.294066)
			(xy 364.546632 -260.274957) (xy 364.595595 -260.265231) (xy 364.620556 -260.264656) (xy 368.5032 -260.264656)
			(xy 368.662966 -260.10489) (xy 368.673467 -260.093672) (xy 368.687778 -260.066495) (xy 368.69335 -260.03629)
			(xy 368.689678 -260.005796) (xy 368.677094 -259.977778) (xy 368.667284 -259.965952) (xy 368.651949 -259.947902)
			(xy 368.626092 -259.908222) (xy 368.60621 -259.865236) (xy 368.592717 -259.819838) (xy 368.585893 -259.772971)
			(xy 368.585496 -259.74929) (xy 368.585968 -259.72394) (xy 368.593766 -259.673844) (xy 368.609175 -259.625544)
			(xy 368.631828 -259.580187) (xy 368.661186 -259.538853) (xy 368.696552 -259.502525) (xy 368.737083 -259.472068)
			(xy 368.759232 -259.45973) (xy 368.786156 -259.445252) (xy 368.786156 -258.754118) (xy 368.759486 -258.73964)
			(xy 368.737595 -258.727222) (xy 368.697564 -258.69672) (xy 368.662659 -258.660464) (xy 368.633698 -258.619304)
			(xy 368.611361 -258.574205) (xy 368.59617 -258.526225) (xy 368.588483 -258.476488) (xy 368.58848 -258.42616)
			(xy 368.59616 -258.376422) (xy 368.611343 -258.328439) (xy 368.633674 -258.283337) (xy 368.662628 -258.242173)
			(xy 368.697528 -258.205912) (xy 368.737555 -258.175404) (xy 368.759486 -258.16306) (xy 368.786156 -258.148582)
			(xy 368.786156 -257.585718) (xy 368.759486 -257.57124) (xy 368.737615 -257.558798) (xy 368.697601 -257.528295)
			(xy 368.662711 -257.492042) (xy 368.633762 -257.450889) (xy 368.611434 -257.4058) (xy 368.596248 -257.357832)
			(xy 368.588562 -257.308107) (xy 368.588036 -257.28295) (xy 368.588566 -257.256569) (xy 368.597011 -257.204486)
			(xy 368.613676 -257.154423) (xy 368.638132 -257.10767) (xy 368.669749 -257.065429) (xy 368.688366 -257.04673)
			(xy 368.697788 -257.036999) (xy 368.711589 -257.013702) (xy 368.718791 -256.9876) (xy 368.718887 -256.960523)
			(xy 368.711872 -256.934369) (xy 368.698238 -256.910975) (xy 368.688874 -256.901188) (xy 368.670585 -256.882532)
			(xy 368.639566 -256.840497) (xy 368.615595 -256.79408) (xy 368.599279 -256.744452) (xy 368.59103 -256.692867)
			(xy 368.590576 -256.666746) (xy 368.591049 -256.641747) (xy 368.598638 -256.592328) (xy 368.613632 -256.54463)
			(xy 368.635685 -256.499758) (xy 368.664286 -256.458748) (xy 368.698775 -256.422548) (xy 368.738353 -256.391997)
			(xy 368.759994 -256.379472) (xy 368.786156 -256.364994) (xy 368.786156 -255.833118) (xy 368.759486 -255.81864)
			(xy 368.737615 -255.806198) (xy 368.697601 -255.775695) (xy 368.662711 -255.739442) (xy 368.633762 -255.698289)
			(xy 368.611434 -255.6532) (xy 368.596248 -255.605232) (xy 368.588562 -255.555507) (xy 368.588036 -255.53035)
			(xy 368.588495 -255.505822) (xy 368.595801 -255.457312) (xy 368.610242 -255.410429) (xy 368.631498 -255.366216)
			(xy 368.659095 -255.325658) (xy 368.675412 -255.307338) (xy 368.685412 -255.295827) (xy 368.698651 -255.268374)
			(xy 368.703207 -255.238237) (xy 368.698673 -255.208097) (xy 368.685453 -255.180634) (xy 368.675412 -255.169162)
			(xy 368.659078 -255.150856) (xy 368.631472 -255.1103) (xy 368.610216 -255.066084) (xy 368.595784 -255.019196)
			(xy 368.588498 -254.97068) (xy 368.588036 -254.94615) (xy 368.58849 -254.920987) (xy 368.596168 -254.871249)
			(xy 368.611352 -254.823268) (xy 368.633686 -254.778168) (xy 368.662645 -254.737008) (xy 368.69755 -254.700753)
			(xy 368.737583 -254.670255) (xy 368.759486 -254.65786) (xy 368.786156 -254.643382) (xy 368.786156 -253.496318)
			(xy 368.759486 -253.48184) (xy 368.737615 -253.469398) (xy 368.697601 -253.438895) (xy 368.662711 -253.402642)
			(xy 368.633762 -253.361489) (xy 368.611434 -253.3164) (xy 368.596248 -253.268432) (xy 368.588562 -253.218707)
			(xy 368.588036 -253.19355) (xy 368.588495 -253.169022) (xy 368.595801 -253.120512) (xy 368.610242 -253.073629)
			(xy 368.631498 -253.029416) (xy 368.659095 -252.988858) (xy 368.675412 -252.970538) (xy 368.685412 -252.959027)
			(xy 368.698651 -252.931574) (xy 368.703207 -252.901437) (xy 368.698673 -252.871297) (xy 368.685453 -252.843834)
			(xy 368.675412 -252.832362) (xy 368.659078 -252.814056) (xy 368.631472 -252.7735) (xy 368.610216 -252.729284)
			(xy 368.595784 -252.682396) (xy 368.588498 -252.63388) (xy 368.588036 -252.60935) (xy 368.58849 -252.584187)
			(xy 368.596168 -252.534449) (xy 368.611352 -252.486468) (xy 368.633686 -252.441368) (xy 368.662645 -252.400208)
			(xy 368.69755 -252.363953) (xy 368.737583 -252.333455) (xy 368.759486 -252.32106) (xy 368.786156 -252.306582)
			(xy 368.786156 -251.743718) (xy 368.759486 -251.72924) (xy 368.737615 -251.716798) (xy 368.697601 -251.686295)
			(xy 368.662711 -251.650042) (xy 368.633762 -251.608889) (xy 368.611434 -251.5638) (xy 368.596248 -251.515832)
			(xy 368.588562 -251.466107) (xy 368.588036 -251.44095) (xy 368.588495 -251.416422) (xy 368.595801 -251.367912)
			(xy 368.610242 -251.321029) (xy 368.631498 -251.276816) (xy 368.659095 -251.236258) (xy 368.675412 -251.217938)
			(xy 368.685412 -251.206427) (xy 368.698651 -251.178974) (xy 368.703207 -251.148837) (xy 368.698673 -251.118697)
			(xy 368.685453 -251.091234) (xy 368.675412 -251.079762) (xy 368.659078 -251.061456) (xy 368.631472 -251.0209)
			(xy 368.610216 -250.976684) (xy 368.595784 -250.929796) (xy 368.588498 -250.88128) (xy 368.588036 -250.85675)
			(xy 368.58849 -250.831587) (xy 368.596168 -250.781849) (xy 368.611352 -250.733868) (xy 368.633686 -250.688768)
			(xy 368.662645 -250.647608) (xy 368.69755 -250.611353) (xy 368.737583 -250.580855) (xy 368.759486 -250.56846)
			(xy 368.786156 -250.553982) (xy 368.786156 -249.402346) (xy 368.764083 -249.391179) (xy 368.723279 -249.363214)
			(xy 368.687134 -249.329443) (xy 368.656465 -249.290631) (xy 368.631967 -249.247657) (xy 368.614195 -249.201493)
			(xy 368.60355 -249.153186) (xy 368.601498 -249.128534) (xy 368.600228 -249.109484) (xy 366.549178 -247.058434)
			(xy 366.531919 -247.040393) (xy 366.504163 -246.998899) (xy 366.485052 -246.952781) (xy 366.475323 -246.903817)
			(xy 366.474756 -246.878856) (xy 366.474756 -244.897656) (xy 366.475332 -244.872698) (xy 366.48508 -244.823742)
			(xy 366.504192 -244.777629) (xy 366.531935 -244.736132) (xy 366.549178 -244.718078) (xy 367.844578 -243.422678)
			(xy 367.86262 -243.40542) (xy 367.904114 -243.377666) (xy 367.950232 -243.358557) (xy 367.999195 -243.348831)
			(xy 368.024156 -243.348256) (xy 368.5794 -243.348256) (xy 368.709956 -243.2177) (xy 368.709956 -242.589812)
			(xy 368.3 -242.179856) (xy 365.687356 -242.179856) (xy 365.662398 -242.17928) (xy 365.613442 -242.169533)
			(xy 365.567328 -242.150421) (xy 365.52583 -242.122679) (xy 365.507778 -242.105434) (xy 363.602778 -240.200434)
			(xy 363.585519 -240.182393) (xy 363.557763 -240.140899) (xy 363.538652 -240.094781) (xy 363.528923 -240.045817)
			(xy 363.528356 -240.020856) (xy 363.528356 -238.703612) (xy 363.1692 -238.344456) (xy 362.237274 -238.344456)
			(xy 362.22305 -238.372396) (xy 362.211008 -238.395396) (xy 362.180779 -238.437603) (xy 362.144279 -238.47452)
			(xy 362.102418 -238.505225) (xy 362.056241 -238.528951) (xy 362.006904 -238.545106) (xy 361.955637 -238.553285)
			(xy 361.903723 -238.553285) (xy 361.852456 -238.545106) (xy 361.803119 -238.528951) (xy 361.756942 -238.505225)
			(xy 361.715081 -238.47452) (xy 361.678581 -238.437603) (xy 361.648352 -238.395396) (xy 361.63631 -238.372396)
			(xy 361.622086 -238.344456) (xy 361.297474 -238.344456) (xy 361.28325 -238.372396) (xy 361.271208 -238.395396)
			(xy 361.240979 -238.437603) (xy 361.204479 -238.47452) (xy 361.162618 -238.505225) (xy 361.116441 -238.528951)
			(xy 361.067104 -238.545106) (xy 361.015837 -238.553285) (xy 360.963923 -238.553285) (xy 360.912656 -238.545106)
			(xy 360.863319 -238.528951) (xy 360.817142 -238.505225) (xy 360.775281 -238.47452) (xy 360.738781 -238.437603)
			(xy 360.708552 -238.395396) (xy 360.69651 -238.372396) (xy 360.682286 -238.344456) (xy 360.357674 -238.344456)
			(xy 360.34345 -238.372396) (xy 360.331408 -238.395396) (xy 360.301179 -238.437603) (xy 360.264679 -238.47452)
			(xy 360.222818 -238.505225) (xy 360.176641 -238.528951) (xy 360.127304 -238.545106) (xy 360.076037 -238.553285)
			(xy 360.024123 -238.553285) (xy 359.972856 -238.545106) (xy 359.923519 -238.528951) (xy 359.877342 -238.505225)
			(xy 359.835481 -238.47452) (xy 359.798981 -238.437603) (xy 359.768752 -238.395396) (xy 359.75671 -238.372396)
			(xy 359.742486 -238.344456) (xy 359.417874 -238.344456) (xy 359.40365 -238.372396) (xy 359.391608 -238.395396)
			(xy 359.361379 -238.437603) (xy 359.324879 -238.47452) (xy 359.283018 -238.505225) (xy 359.236841 -238.528951)
			(xy 359.187504 -238.545106) (xy 359.136237 -238.553285) (xy 359.084323 -238.553285) (xy 359.033056 -238.545106)
			(xy 358.983719 -238.528951) (xy 358.937542 -238.505225) (xy 358.895681 -238.47452) (xy 358.859181 -238.437603)
			(xy 358.828952 -238.395396) (xy 358.81691 -238.372396) (xy 358.802686 -238.344456) (xy 358.478074 -238.344456)
			(xy 358.46385 -238.372396) (xy 358.451808 -238.395396) (xy 358.421579 -238.437603) (xy 358.385079 -238.47452)
			(xy 358.343218 -238.505225) (xy 358.297041 -238.528951) (xy 358.247704 -238.545106) (xy 358.196437 -238.553285)
			(xy 358.144523 -238.553285) (xy 358.093256 -238.545106) (xy 358.043919 -238.528951) (xy 357.997742 -238.505225)
			(xy 357.955881 -238.47452) (xy 357.919381 -238.437603) (xy 357.889152 -238.395396) (xy 357.87711 -238.372396)
			(xy 357.862886 -238.344456) (xy 357.538274 -238.344456) (xy 357.52405 -238.372396) (xy 357.512008 -238.395396)
			(xy 357.481779 -238.437603) (xy 357.445279 -238.47452) (xy 357.403418 -238.505225) (xy 357.357241 -238.528951)
			(xy 357.307904 -238.545106) (xy 357.256637 -238.553285) (xy 357.204723 -238.553285) (xy 357.153456 -238.545106)
			(xy 357.104119 -238.528951) (xy 357.057942 -238.505225) (xy 357.016081 -238.47452) (xy 356.979581 -238.437603)
			(xy 356.949352 -238.395396) (xy 356.93731 -238.372396) (xy 356.923086 -238.344456) (xy 352.432112 -238.344456)
			(xy 351.234756 -239.541812) (xy 351.234756 -245.2243) (xy 351.619312 -245.608856) (xy 352.733356 -245.608856)
			(xy 352.758314 -245.609433) (xy 352.807268 -245.619183) (xy 352.853379 -245.638297) (xy 352.894875 -245.666041)
			(xy 352.912934 -245.683278) (xy 353.243134 -246.013478) (xy 353.260392 -246.03152) (xy 353.288144 -246.073014)
			(xy 353.307252 -246.119132) (xy 353.316978 -246.168096) (xy 353.317556 -246.193056) (xy 353.317556 -246.36603)
			(xy 353.344226 -246.380508) (xy 353.366236 -246.392881) (xy 353.406504 -246.423341) (xy 353.441628 -246.459612)
			(xy 353.470778 -246.500838) (xy 353.493265 -246.546045) (xy 353.508558 -246.594163) (xy 353.516296 -246.644058)
			(xy 353.516296 -246.694548) (xy 353.508557 -246.744442) (xy 353.493263 -246.792561) (xy 353.470775 -246.837767)
			(xy 353.441624 -246.878992) (xy 353.4065 -246.915263) (xy 353.366231 -246.945722) (xy 353.344226 -246.958104)
			(xy 353.317556 -246.972582) (xy 353.317556 -247.386856) (xy 353.316979 -247.411814) (xy 353.30723 -247.460769)
			(xy 353.288116 -247.50688) (xy 353.260373 -247.548377) (xy 353.243134 -247.566434) (xy 352.608134 -248.201434)
			(xy 352.590093 -248.218693) (xy 352.548599 -248.246447) (xy 352.50248 -248.265557) (xy 352.453517 -248.275286)
			(xy 352.428556 -248.275856) (xy 351.619312 -248.275856) (xy 351.285556 -248.609612) (xy 351.285556 -255.908302)
			(xy 351.60331 -256.226056) (xy 352.682556 -256.226056) (xy 352.707514 -256.226633) (xy 352.756468 -256.236383)
			(xy 352.802579 -256.255497) (xy 352.844075 -256.283241) (xy 352.862134 -256.300478) (xy 353.370134 -256.808478)
			(xy 353.387392 -256.82652) (xy 353.415144 -256.868014) (xy 353.434252 -256.914132) (xy 353.443978 -256.963096)
			(xy 353.444556 -256.988056) (xy 353.444556 -257.366008) (xy 353.482148 -257.375914) (xy 353.506415 -257.382944)
			(xy 353.552599 -257.403424) (xy 353.595101 -257.430737) (xy 353.632917 -257.464238) (xy 353.665155 -257.503136)
			(xy 353.691054 -257.546514) (xy 353.710003 -257.593347) (xy 353.721554 -257.64253) (xy 353.725434 -257.692902)
			(xy 353.721553 -257.743273) (xy 353.710002 -257.792456) (xy 353.691053 -257.839289) (xy 353.665153 -257.882666)
			(xy 353.632915 -257.921565) (xy 353.595098 -257.955065) (xy 353.552596 -257.982378) (xy 353.506412 -258.002857)
			(xy 353.482148 -258.009898) (xy 353.444556 -258.019804) (xy 353.444556 -260.3881) (xy 353.616514 -260.560058)
			(xy 355.569012 -260.560058) (xy 355.593972 -260.560631) (xy 355.642931 -260.570373) (xy 355.689048 -260.589482)
			(xy 355.730549 -260.617222) (xy 355.74859 -260.63448) (xy 356.017322 -260.903212) (xy 356.034585 -260.921252)
			(xy 356.06235 -260.962744) (xy 356.081471 -261.008862) (xy 356.09121 -261.057827) (xy 356.091744 -261.08279)
			(xy 356.091744 -261.442962) (xy 356.091167 -261.46792) (xy 356.081416 -261.516873) (xy 356.062301 -261.562984)
			(xy 356.034556 -261.604478) (xy 356.017322 -261.62254) (xy 355.676708 -261.963154) (xy 355.658665 -261.980409)
			(xy 355.61717 -262.008158) (xy 355.571052 -262.027261) (xy 355.52209 -262.036984) (xy 355.49713 -262.037576)
			(xy 355.294184 -262.037576) (xy 355.108764 -262.222996) (xy 355.108764 -263.499346) (xy 356.24643 -264.637012)
			(xy 356.263693 -264.655052) (xy 356.291457 -264.696544) (xy 356.310577 -264.742662) (xy 356.320316 -264.791628)
			(xy 356.320852 -264.81659) (xy 356.320852 -273.453098) (xy 356.541324 -273.453098) (xy 356.541832 -273.427211)
			(xy 356.549931 -273.376073) (xy 356.56593 -273.326833) (xy 356.589436 -273.280701) (xy 356.619868 -273.238814)
			(xy 356.656478 -273.202204) (xy 356.698365 -273.171772) (xy 356.744497 -273.148266) (xy 356.793737 -273.132267)
			(xy 356.844875 -273.124168) (xy 356.896649 -273.124168) (xy 356.947787 -273.132267) (xy 356.997027 -273.148266)
			(xy 357.043159 -273.171772) (xy 357.085046 -273.202204) (xy 357.121656 -273.238814) (xy 357.152088 -273.280701)
			(xy 357.175594 -273.326833) (xy 357.191593 -273.376073) (xy 357.199692 -273.427211) (xy 357.2002 -273.453098)
			(xy 357.19967 -273.480806) (xy 357.190475 -273.535453) (xy 357.181912 -273.56181) (xy 357.174292 -273.583654)
			(xy 357.37927 -273.938746) (xy 357.40213 -273.943064) (xy 357.426938 -273.948232) (xy 357.474677 -273.965225)
			(xy 357.519254 -273.989322) (xy 357.559619 -274.019956) (xy 357.594821 -274.056405) (xy 357.624032 -274.097811)
			(xy 357.646564 -274.143199) (xy 357.661886 -274.191501) (xy 357.669637 -274.241577) (xy 357.6701 -274.266914)
			(xy 357.669592 -274.292801) (xy 357.661493 -274.343939) (xy 357.645494 -274.393179) (xy 357.621988 -274.439311)
			(xy 357.591556 -274.481198) (xy 357.554946 -274.517808) (xy 357.513059 -274.54824) (xy 357.466927 -274.571746)
			(xy 357.417687 -274.587745) (xy 357.366549 -274.595844) (xy 357.314775 -274.595844) (xy 357.263637 -274.587745)
			(xy 357.214397 -274.571746) (xy 357.168265 -274.54824) (xy 357.126378 -274.517808) (xy 357.089768 -274.481198)
			(xy 357.059336 -274.439311) (xy 357.03583 -274.393179) (xy 357.019831 -274.343939) (xy 357.011732 -274.292801)
			(xy 357.011224 -274.266914) (xy 357.011756 -274.239206) (xy 357.020949 -274.184559) (xy 357.029512 -274.158202)
			(xy 357.037386 -274.136104) (xy 356.832408 -273.781266) (xy 356.809548 -273.776948) (xy 356.784736 -273.771741)
			(xy 356.73696 -273.75479) (xy 356.692344 -273.730722) (xy 356.651938 -273.700106) (xy 356.616698 -273.663665)
			(xy 356.587453 -273.622257) (xy 356.564893 -273.576859) (xy 356.549551 -273.528542) (xy 356.541789 -273.478445)
			(xy 356.541324 -273.453098) (xy 356.320852 -273.453098) (xy 356.320852 -275.360892) (xy 356.439724 -275.566632)
			(xy 356.462584 -275.57095) (xy 356.487395 -275.576139) (xy 356.535155 -275.593113) (xy 356.579755 -275.617196)
			(xy 356.620145 -275.64782) (xy 356.655372 -275.684264) (xy 356.684609 -275.725669) (xy 356.707164 -275.771061)
			(xy 356.722509 -275.819369) (xy 356.73028 -275.869457) (xy 356.730808 -275.8948) (xy 356.730345 -275.919893)
			(xy 356.72275 -275.969502) (xy 356.70772 -276.017384) (xy 356.685602 -276.062434) (xy 356.656909 -276.103609)
			(xy 356.622304 -276.139957) (xy 356.582587 -276.170636) (xy 356.538677 -276.194938) (xy 356.49159 -276.212301)
			(xy 356.442414 -276.222322) (xy 356.417372 -276.223984) (xy 356.401951 -276.22532) (xy 356.372938 -276.236066)
			(xy 356.34846 -276.254989) (xy 356.330753 -276.28036) (xy 356.321432 -276.309862) (xy 356.320852 -276.32533)
			(xy 356.320852 -276.708616) (xy 356.541324 -276.708616) (xy 356.541802 -276.683281) (xy 356.549553 -276.633207)
			(xy 356.564874 -276.584909) (xy 356.587406 -276.539525) (xy 356.616616 -276.498122) (xy 356.651818 -276.461676)
			(xy 356.692181 -276.431046) (xy 356.736757 -276.406953) (xy 356.784494 -276.389964) (xy 356.809294 -276.384766)
			(xy 356.832154 -276.380448) (xy 357.037132 -276.02561) (xy 357.029258 -276.003766) (xy 357.020612 -275.977358)
			(xy 357.011292 -275.922582) (xy 357.010716 -275.8948) (xy 357.011224 -275.868893) (xy 357.01933 -275.817716)
			(xy 357.035342 -275.768437) (xy 357.058865 -275.72227) (xy 357.089321 -275.680351) (xy 357.125959 -275.643713)
			(xy 357.167878 -275.613257) (xy 357.214045 -275.589734) (xy 357.263324 -275.573722) (xy 357.314501 -275.565616)
			(xy 357.366315 -275.565616) (xy 357.417492 -275.573722) (xy 357.466771 -275.589734) (xy 357.512938 -275.613257)
			(xy 357.554857 -275.643713) (xy 357.591495 -275.680351) (xy 357.621951 -275.72227) (xy 357.645474 -275.768437)
			(xy 357.661486 -275.817716) (xy 357.669592 -275.868893) (xy 357.6701 -275.8948) (xy 357.669579 -275.920144)
			(xy 357.661807 -275.970232) (xy 357.646462 -276.018541) (xy 357.623906 -276.063932) (xy 357.594669 -276.105338)
			(xy 357.55944 -276.141782) (xy 357.519049 -276.172406) (xy 357.474448 -276.196488) (xy 357.426687 -276.213462)
			(xy 357.401876 -276.21865) (xy 357.379016 -276.222968) (xy 357.174038 -276.577806) (xy 357.181912 -276.599904)
			(xy 357.190474 -276.626262) (xy 357.199672 -276.680908) (xy 357.2002 -276.708616) (xy 357.199692 -276.734503)
			(xy 357.191593 -276.785641) (xy 357.175594 -276.834881) (xy 357.152088 -276.881013) (xy 357.121656 -276.9229)
			(xy 357.085046 -276.95951) (xy 357.043159 -276.989942) (xy 356.997027 -277.013448) (xy 356.947787 -277.029447)
			(xy 356.896649 -277.037546) (xy 356.844875 -277.037546) (xy 356.793737 -277.029447) (xy 356.744497 -277.013448)
			(xy 356.698365 -276.989942) (xy 356.656478 -276.95951) (xy 356.619868 -276.9229) (xy 356.589436 -276.881013)
			(xy 356.56593 -276.834881) (xy 356.549931 -276.785641) (xy 356.541832 -276.734503) (xy 356.541324 -276.708616)
			(xy 356.320852 -276.708616) (xy 356.320852 -277.091902) (xy 356.321388 -277.107385) (xy 356.330653 -277.136932)
			(xy 356.348358 -277.162336) (xy 356.372872 -277.181256) (xy 356.401934 -277.191946) (xy 356.417372 -277.193248)
			(xy 356.441444 -277.194906) (xy 356.488765 -277.204333) (xy 356.534208 -277.22055) (xy 356.576807 -277.24321)
			(xy 356.615652 -277.271831) (xy 356.649916 -277.305802) (xy 356.664768 -277.32482) (xy 357.076756 -277.32482)
			(xy 357.092427 -277.304681) (xy 357.128935 -277.26903) (xy 357.170499 -277.239429) (xy 357.216128 -277.216585)
			(xy 357.264731 -277.201044) (xy 357.315148 -277.193177) (xy 357.340662 -277.19274) (xy 357.366571 -277.193219)
			(xy 357.417751 -277.20132) (xy 357.467034 -277.217328) (xy 357.513206 -277.240849) (xy 357.555129 -277.271303)
			(xy 357.591772 -277.307942) (xy 357.622231 -277.349862) (xy 357.645758 -277.396031) (xy 357.661771 -277.445312)
			(xy 357.669878 -277.496491) (xy 357.669878 -277.548309) (xy 357.661771 -277.599488) (xy 357.645758 -277.648769)
			(xy 357.622231 -277.694938) (xy 357.591772 -277.736858) (xy 357.555129 -277.773497) (xy 357.513206 -277.803951)
			(xy 357.467034 -277.827472) (xy 357.417751 -277.84348) (xy 357.366571 -277.851581) (xy 357.340662 -277.852124)
			(xy 357.315151 -277.851644) (xy 357.264739 -277.843779) (xy 357.21614 -277.828242) (xy 357.170514 -277.805404)
			(xy 357.128951 -277.775811) (xy 357.092443 -277.740168) (xy 357.076756 -277.720044) (xy 356.664768 -277.720044)
			(xy 356.649971 -277.739111) (xy 356.615721 -277.773116) (xy 356.576873 -277.801756) (xy 356.534261 -277.824416)
			(xy 356.488796 -277.840612) (xy 356.441453 -277.849996) (xy 356.417372 -277.851616) (xy 356.401953 -277.852952)
			(xy 356.372944 -277.8637) (xy 356.348472 -277.882624) (xy 356.330771 -277.907995) (xy 356.32146 -277.937496)
			(xy 356.320852 -277.952962) (xy 356.320852 -280.004774) (xy 356.320274 -280.029731) (xy 356.310521 -280.078684)
			(xy 356.291405 -280.124793) (xy 356.26366 -280.166287) (xy 356.24643 -280.184352) (xy 355.769164 -280.661618)
			(xy 355.777292 -280.690066) (xy 355.782886 -280.711669) (xy 355.788871 -280.755891) (xy 355.78923 -280.778204)
			(xy 355.78875 -280.803992) (xy 355.78068 -280.854934) (xy 355.764741 -280.903986) (xy 355.741323 -280.94994)
			(xy 355.711005 -280.991665) (xy 355.674533 -281.028132) (xy 355.632804 -281.058445) (xy 355.586847 -281.081857)
			(xy 355.537793 -281.09779) (xy 355.48685 -281.105853) (xy 355.461062 -281.106372) (xy 355.438748 -281.106031)
			(xy 355.394525 -281.100039) (xy 355.372924 -281.094434) (xy 355.344476 -281.086306) (xy 354.484178 -281.946604)
			(xy 354.55987 -282.077668) (xy 354.58273 -282.081986) (xy 354.607532 -282.087184) (xy 354.655272 -282.104174)
			(xy 354.69985 -282.128267) (xy 354.740218 -282.158896) (xy 354.775426 -282.195341) (xy 354.804643 -282.236743)
			(xy 354.827182 -282.282127) (xy 354.842514 -282.330425) (xy 354.850275 -282.3805) (xy 354.8507 -282.405836)
			(xy 354.85019 -282.431729) (xy 354.842088 -282.482877) (xy 354.826089 -282.53213) (xy 354.802586 -282.578276)
			(xy 354.772157 -282.620179) (xy 354.735551 -282.65681) (xy 354.693669 -282.687267) (xy 354.647539 -282.710802)
			(xy 354.598297 -282.726835) (xy 354.547155 -282.734972) (xy 354.521262 -282.735528) (xy 354.495573 -282.735034)
			(xy 354.444817 -282.727056) (xy 354.395914 -282.7113) (xy 354.350048 -282.688147) (xy 354.308329 -282.658158)
			(xy 354.271769 -282.62206) (xy 354.241252 -282.580726) (xy 354.217519 -282.535158) (xy 354.201142 -282.486459)
			(xy 354.196396 -282.461208) (xy 354.193633 -282.447564) (xy 354.181724 -282.422412) (xy 354.16347 -282.401407)
			(xy 354.140225 -282.386107) (xy 354.113714 -282.377646) (xy 354.085903 -282.376654) (xy 354.058856 -282.383204)
			(xy 354.03458 -282.396809) (xy 354.024438 -282.406344) (xy 353.875086 -282.555696) (xy 353.87153 -282.5623)
			(xy 353.859771 -282.583185) (xy 353.831142 -282.621623) (xy 353.797247 -282.655508) (xy 353.758801 -282.684125)
			(xy 353.737926 -282.695904) (xy 353.731322 -282.69946) (xy 353.515676 -282.915106) (xy 353.415092 -283.089096)
			(xy 353.422966 -283.111194) (xy 353.43159 -283.137542) (xy 353.440912 -283.192189) (xy 353.441508 -283.219906)
			(xy 353.441025 -283.245807) (xy 353.432916 -283.29697) (xy 353.4169 -283.346234) (xy 353.393369 -283.392383)
			(xy 353.362906 -283.434281) (xy 353.32626 -283.470895) (xy 353.284336 -283.501321) (xy 353.238166 -283.524811)
			(xy 353.188888 -283.540784) (xy 353.137717 -283.548848) (xy 353.111816 -283.549344) (xy 353.086439 -283.548877)
			(xy 353.036286 -283.541093) (xy 352.987921 -283.525708) (xy 352.965004 -283.5148) (xy 352.932238 -283.498544)
			(xy 352.560128 -283.870654) (xy 352.560128 -288.168334) (xy 352.559513 -288.19329) (xy 352.549771 -288.242241)
			(xy 352.530667 -288.288351) (xy 352.502936 -288.32985) (xy 352.485706 -288.347912) (xy 352.017076 -288.816542)
			(xy 352.023426 -288.84372) (xy 352.027333 -288.86182) (xy 352.031534 -288.898611) (xy 352.031808 -288.917126)
			(xy 352.031324 -288.943026) (xy 352.023212 -288.994187) (xy 352.007194 -289.043448) (xy 351.983663 -289.089595)
			(xy 351.953199 -289.13149) (xy 351.916554 -289.168101) (xy 351.87463 -289.198525) (xy 351.828461 -289.222013)
			(xy 351.779185 -289.237985) (xy 351.728016 -289.246048) (xy 351.702116 -289.246564) (xy 351.676757 -289.246153)
			(xy 351.626622 -289.238495) (xy 351.602294 -289.231324) (xy 351.584431 -289.247316) (xy 351.54394 -289.27298)
			(xy 351.499363 -289.290617) (xy 351.452273 -289.299603) (xy 351.428304 -289.300158) (xy 351.34169 -289.300158)
			(xy 351.326722 -289.300686) (xy 351.298069 -289.309353) (xy 351.273151 -289.325942) (xy 351.2541 -289.349033)
			(xy 351.242548 -289.376649) (xy 351.239484 -289.406428) (xy 351.245169 -289.435818) (xy 351.251774 -289.449256)
			(xy 351.267522 -289.478466) (xy 351.291652 -289.483038) (xy 351.31657 -289.488131) (xy 351.364563 -289.50496)
			(xy 351.409403 -289.528957) (xy 351.450027 -289.559553) (xy 351.485472 -289.596024) (xy 351.514898 -289.637504)
			(xy 351.537608 -289.68301) (xy 351.553061 -289.731463) (xy 351.560893 -289.781713) (xy 351.5614 -289.807142)
			(xy 367.818924 -289.807142) (xy 367.819411 -289.781712) (xy 367.827244 -289.73146) (xy 367.842699 -289.683005)
			(xy 367.86541 -289.637498) (xy 367.894839 -289.596018) (xy 367.930287 -289.559547) (xy 367.970914 -289.528951)
			(xy 368.015757 -289.504956) (xy 368.063753 -289.48813) (xy 368.088672 -289.483038) (xy 368.112802 -289.478466)
			(xy 368.327178 -289.073082) (xy 368.317272 -289.050476) (xy 368.308309 -289.029398) (xy 368.295664 -288.985377)
			(xy 368.289249 -288.940026) (xy 368.288824 -288.917126) (xy 368.289332 -288.891219) (xy 368.297438 -288.840042)
			(xy 368.31345 -288.790763) (xy 368.336973 -288.744596) (xy 368.367429 -288.702677) (xy 368.404067 -288.666039)
			(xy 368.445986 -288.635583) (xy 368.492153 -288.61206) (xy 368.541432 -288.596048) (xy 368.592609 -288.587942)
			(xy 368.644423 -288.587942) (xy 368.6956 -288.596048) (xy 368.744879 -288.61206) (xy 368.791046 -288.635583)
			(xy 368.832965 -288.666039) (xy 368.869603 -288.702677) (xy 368.900059 -288.744596) (xy 368.923582 -288.790763)
			(xy 368.939594 -288.840042) (xy 368.9477 -288.891219) (xy 368.948208 -288.917126) (xy 368.947753 -288.942575)
			(xy 368.939949 -288.992871) (xy 368.924499 -289.041367) (xy 368.901771 -289.086909) (xy 368.872307 -289.128411)
			(xy 368.836809 -289.164887) (xy 368.796121 -289.195466) (xy 368.751213 -289.21942) (xy 368.703153 -289.23618)
			(xy 368.678206 -289.24123) (xy 368.654076 -289.245802) (xy 368.4397 -289.651186) (xy 368.449606 -289.673792)
			(xy 368.458528 -289.694877) (xy 368.471078 -289.738907) (xy 368.47741 -289.78425) (xy 368.4778 -289.807142)
			(xy 368.477292 -289.833029) (xy 368.469193 -289.884167) (xy 368.453194 -289.933407) (xy 368.429688 -289.979539)
			(xy 368.399256 -290.021426) (xy 368.362646 -290.058036) (xy 368.320759 -290.088468) (xy 368.274627 -290.111974)
			(xy 368.225387 -290.127973) (xy 368.174249 -290.136072) (xy 368.122475 -290.136072) (xy 368.071337 -290.127973)
			(xy 368.022097 -290.111974) (xy 367.975965 -290.088468) (xy 367.934078 -290.058036) (xy 367.897468 -290.021426)
			(xy 367.867036 -289.979539) (xy 367.84353 -289.933407) (xy 367.827531 -289.884167) (xy 367.819432 -289.833029)
			(xy 367.818924 -289.807142) (xy 351.5614 -289.807142) (xy 351.560892 -289.833029) (xy 351.552793 -289.884167)
			(xy 351.536794 -289.933407) (xy 351.513288 -289.979539) (xy 351.482856 -290.021426) (xy 351.446246 -290.058036)
			(xy 351.404359 -290.088468) (xy 351.358227 -290.111974) (xy 351.308987 -290.127973) (xy 351.257849 -290.136072)
			(xy 351.206075 -290.136072) (xy 351.154937 -290.127973) (xy 351.105697 -290.111974) (xy 351.059565 -290.088468)
			(xy 351.017678 -290.058036) (xy 350.981068 -290.021426) (xy 350.950636 -289.979539) (xy 350.92713 -289.933407)
			(xy 350.911131 -289.884167) (xy 350.903032 -289.833029) (xy 350.902524 -289.807142) (xy 350.902903 -289.784208)
			(xy 350.909231 -289.738781) (xy 350.9218 -289.69467) (xy 350.930718 -289.673538) (xy 350.940624 -289.650932)
			(xy 350.755712 -289.300158) (xy 349.46209 -289.300158) (xy 349.447122 -289.300686) (xy 349.418469 -289.309353)
			(xy 349.393551 -289.325942) (xy 349.3745 -289.349033) (xy 349.362948 -289.376649) (xy 349.359884 -289.406428)
			(xy 349.365569 -289.435818) (xy 349.372174 -289.449256) (xy 349.387922 -289.478466) (xy 349.412052 -289.483038)
			(xy 349.43697 -289.488131) (xy 349.484963 -289.50496) (xy 349.529803 -289.528957) (xy 349.570427 -289.559553)
			(xy 349.605872 -289.596024) (xy 349.635298 -289.637504) (xy 349.658008 -289.68301) (xy 349.673461 -289.731463)
			(xy 349.681293 -289.781713) (xy 349.6818 -289.807142) (xy 349.681292 -289.833029) (xy 349.673193 -289.884167)
			(xy 349.657194 -289.933407) (xy 349.633688 -289.979539) (xy 349.603256 -290.021426) (xy 349.566646 -290.058036)
			(xy 349.524759 -290.088468) (xy 349.478627 -290.111974) (xy 349.429387 -290.127973) (xy 349.378249 -290.136072)
			(xy 349.326475 -290.136072) (xy 349.275337 -290.127973) (xy 349.226097 -290.111974) (xy 349.179965 -290.088468)
			(xy 349.138078 -290.058036) (xy 349.101468 -290.021426) (xy 349.071036 -289.979539) (xy 349.04753 -289.933407)
			(xy 349.031531 -289.884167) (xy 349.023432 -289.833029) (xy 349.022924 -289.807142) (xy 349.023303 -289.784208)
			(xy 349.029631 -289.738781) (xy 349.0422 -289.69467) (xy 349.051118 -289.673538) (xy 349.061024 -289.650932)
			(xy 348.876112 -289.300158) (xy 347.58249 -289.300158) (xy 347.567522 -289.300686) (xy 347.538869 -289.309353)
			(xy 347.513951 -289.325942) (xy 347.4949 -289.349033) (xy 347.483348 -289.376649) (xy 347.480284 -289.406428)
			(xy 347.485969 -289.435818) (xy 347.492574 -289.449256) (xy 347.508322 -289.478466) (xy 347.532452 -289.483038)
			(xy 347.55737 -289.488131) (xy 347.605363 -289.50496) (xy 347.650203 -289.528957) (xy 347.690827 -289.559553)
			(xy 347.726272 -289.596024) (xy 347.755698 -289.637504) (xy 347.778408 -289.68301) (xy 347.793861 -289.731463)
			(xy 347.801693 -289.781713) (xy 347.8022 -289.807142) (xy 347.801692 -289.833029) (xy 347.793593 -289.884167)
			(xy 347.777594 -289.933407) (xy 347.754088 -289.979539) (xy 347.723656 -290.021426) (xy 347.687046 -290.058036)
			(xy 347.645159 -290.088468) (xy 347.599027 -290.111974) (xy 347.549787 -290.127973) (xy 347.498649 -290.136072)
			(xy 347.446875 -290.136072) (xy 347.395737 -290.127973) (xy 347.346497 -290.111974) (xy 347.300365 -290.088468)
			(xy 347.258478 -290.058036) (xy 347.221868 -290.021426) (xy 347.191436 -289.979539) (xy 347.16793 -289.933407)
			(xy 347.151931 -289.884167) (xy 347.143832 -289.833029) (xy 347.143324 -289.807142) (xy 347.143703 -289.784208)
			(xy 347.150031 -289.738781) (xy 347.1626 -289.69467) (xy 347.171518 -289.673538) (xy 347.181424 -289.650932)
			(xy 346.996512 -289.300158) (xy 345.70289 -289.300158) (xy 345.687922 -289.300686) (xy 345.659269 -289.309353)
			(xy 345.634351 -289.325942) (xy 345.6153 -289.349033) (xy 345.603748 -289.376649) (xy 345.600684 -289.406428)
			(xy 345.606369 -289.435818) (xy 345.612974 -289.449256) (xy 345.628722 -289.478466) (xy 345.652852 -289.483038)
			(xy 345.67777 -289.488131) (xy 345.725763 -289.50496) (xy 345.770603 -289.528957) (xy 345.811227 -289.559553)
			(xy 345.846672 -289.596024) (xy 345.876098 -289.637504) (xy 345.898808 -289.68301) (xy 345.914261 -289.731463)
			(xy 345.922093 -289.781713) (xy 345.9226 -289.807142) (xy 345.922092 -289.833029) (xy 345.913993 -289.884167)
			(xy 345.897994 -289.933407) (xy 345.874488 -289.979539) (xy 345.844056 -290.021426) (xy 345.807446 -290.058036)
			(xy 345.765559 -290.088468) (xy 345.719427 -290.111974) (xy 345.670187 -290.127973) (xy 345.619049 -290.136072)
			(xy 345.567275 -290.136072) (xy 345.516137 -290.127973) (xy 345.466897 -290.111974) (xy 345.420765 -290.088468)
			(xy 345.378878 -290.058036) (xy 345.342268 -290.021426) (xy 345.311836 -289.979539) (xy 345.28833 -289.933407)
			(xy 345.272331 -289.884167) (xy 345.264232 -289.833029) (xy 345.263724 -289.807142) (xy 345.264103 -289.784208)
			(xy 345.270431 -289.738781) (xy 345.283 -289.69467) (xy 345.291918 -289.673538) (xy 345.301824 -289.650932)
			(xy 345.116912 -289.300158) (xy 343.82329 -289.300158) (xy 343.808322 -289.300686) (xy 343.779669 -289.309353)
			(xy 343.754751 -289.325942) (xy 343.7357 -289.349033) (xy 343.724148 -289.376649) (xy 343.721084 -289.406428)
			(xy 343.726769 -289.435818) (xy 343.733374 -289.449256) (xy 343.749122 -289.478466) (xy 343.773252 -289.483038)
			(xy 343.79817 -289.488131) (xy 343.846163 -289.50496) (xy 343.891003 -289.528957) (xy 343.931627 -289.559553)
			(xy 343.967072 -289.596024) (xy 343.996498 -289.637504) (xy 344.019208 -289.68301) (xy 344.034661 -289.731463)
			(xy 344.042493 -289.781713) (xy 344.043 -289.807142) (xy 344.042492 -289.833029) (xy 344.034393 -289.884167)
			(xy 344.018394 -289.933407) (xy 343.994888 -289.979539) (xy 343.964456 -290.021426) (xy 343.927846 -290.058036)
			(xy 343.885959 -290.088468) (xy 343.839827 -290.111974) (xy 343.790587 -290.127973) (xy 343.739449 -290.136072)
			(xy 343.687675 -290.136072) (xy 343.636537 -290.127973) (xy 343.587297 -290.111974) (xy 343.541165 -290.088468)
			(xy 343.499278 -290.058036) (xy 343.462668 -290.021426) (xy 343.432236 -289.979539) (xy 343.40873 -289.933407)
			(xy 343.392731 -289.884167) (xy 343.384632 -289.833029) (xy 343.384124 -289.807142) (xy 343.384503 -289.784208)
			(xy 343.390831 -289.738781) (xy 343.4034 -289.69467) (xy 343.412318 -289.673538) (xy 343.422224 -289.650932)
			(xy 343.237312 -289.300158) (xy 341.94369 -289.300158) (xy 341.928722 -289.300686) (xy 341.900069 -289.309353)
			(xy 341.875151 -289.325942) (xy 341.8561 -289.349033) (xy 341.844548 -289.376649) (xy 341.841484 -289.406428)
			(xy 341.847169 -289.435818) (xy 341.853774 -289.449256) (xy 341.869522 -289.478466) (xy 341.893652 -289.483038)
			(xy 341.91857 -289.488131) (xy 341.966563 -289.50496) (xy 342.011403 -289.528957) (xy 342.052027 -289.559553)
			(xy 342.087472 -289.596024) (xy 342.116898 -289.637504) (xy 342.139608 -289.68301) (xy 342.155061 -289.731463)
			(xy 342.162893 -289.781713) (xy 342.1634 -289.807142) (xy 342.162892 -289.833029) (xy 342.154793 -289.884167)
			(xy 342.138794 -289.933407) (xy 342.115288 -289.979539) (xy 342.084856 -290.021426) (xy 342.048246 -290.058036)
			(xy 342.006359 -290.088468) (xy 341.960227 -290.111974) (xy 341.910987 -290.127973) (xy 341.859849 -290.136072)
			(xy 341.808075 -290.136072) (xy 341.756937 -290.127973) (xy 341.707697 -290.111974) (xy 341.661565 -290.088468)
			(xy 341.619678 -290.058036) (xy 341.583068 -290.021426) (xy 341.552636 -289.979539) (xy 341.52913 -289.933407)
			(xy 341.513131 -289.884167) (xy 341.505032 -289.833029) (xy 341.504524 -289.807142) (xy 341.504903 -289.784208)
			(xy 341.511231 -289.738781) (xy 341.5238 -289.69467) (xy 341.532718 -289.673538) (xy 341.542624 -289.650932)
			(xy 341.357712 -289.300158) (xy 340.06409 -289.300158) (xy 340.049122 -289.300686) (xy 340.020469 -289.309353)
			(xy 339.995551 -289.325942) (xy 339.9765 -289.349033) (xy 339.964948 -289.376649) (xy 339.961884 -289.406428)
			(xy 339.967569 -289.435818) (xy 339.974174 -289.449256) (xy 339.989922 -289.478466) (xy 340.014052 -289.483038)
			(xy 340.03897 -289.488131) (xy 340.086963 -289.50496) (xy 340.131803 -289.528957) (xy 340.172427 -289.559553)
			(xy 340.207872 -289.596024) (xy 340.237298 -289.637504) (xy 340.260008 -289.68301) (xy 340.275461 -289.731463)
			(xy 340.283293 -289.781713) (xy 340.2838 -289.807142) (xy 340.283292 -289.833029) (xy 340.275193 -289.884167)
			(xy 340.259194 -289.933407) (xy 340.235688 -289.979539) (xy 340.205256 -290.021426) (xy 340.168646 -290.058036)
			(xy 340.126759 -290.088468) (xy 340.080627 -290.111974) (xy 340.031387 -290.127973) (xy 339.980249 -290.136072)
			(xy 339.928475 -290.136072) (xy 339.877337 -290.127973) (xy 339.828097 -290.111974) (xy 339.781965 -290.088468)
			(xy 339.740078 -290.058036) (xy 339.703468 -290.021426) (xy 339.673036 -289.979539) (xy 339.64953 -289.933407)
			(xy 339.633531 -289.884167) (xy 339.625432 -289.833029) (xy 339.624924 -289.807142) (xy 339.625303 -289.784208)
			(xy 339.631631 -289.738781) (xy 339.6442 -289.69467) (xy 339.653118 -289.673538) (xy 339.663024 -289.650932)
			(xy 339.478112 -289.300158) (xy 330.402946 -289.300158) (xy 322.729098 -296.974006) (xy 322.729098 -297.515026)
			(xy 336.155548 -297.515026) (xy 336.159529 -297.382006) (xy 336.171458 -297.249461) (xy 336.191293 -297.117868)
			(xy 336.218962 -296.987696) (xy 336.254366 -296.859411) (xy 336.297379 -296.733474) (xy 336.347846 -296.610335)
			(xy 336.405587 -296.490434) (xy 336.470396 -296.374201) (xy 336.54204 -296.262051) (xy 336.620262 -296.154387)
			(xy 336.704783 -296.051594) (xy 336.795301 -295.954039) (xy 336.89149 -295.862073) (xy 336.993008 -295.776023)
			(xy 337.099489 -295.696199) (xy 337.210554 -295.622886) (xy 337.325805 -295.556346) (xy 337.444829 -295.496817)
			(xy 337.5672 -295.444513) (xy 337.692479 -295.399621) (xy 337.82022 -295.362302) (xy 337.949963 -295.332689)
			(xy 338.081245 -295.310888) (xy 338.213596 -295.296978) (xy 338.346542 -295.291007) (xy 338.479607 -295.292998)
			(xy 338.612315 -295.302943) (xy 338.744191 -295.320807) (xy 338.874762 -295.346525) (xy 339.003562 -295.380006)
			(xy 339.130128 -295.42113) (xy 339.254009 -295.46975) (xy 339.37476 -295.525691) (xy 339.49195 -295.588753)
			(xy 339.605159 -295.658711) (xy 339.713981 -295.735315) (xy 339.818027 -295.818289) (xy 339.916925 -295.907337)
			(xy 340.01032 -296.00214) (xy 340.097878 -296.102358) (xy 340.179287 -296.207634) (xy 340.254253 -296.31759)
			(xy 340.32251 -296.431832) (xy 340.383812 -296.549952) (xy 340.437941 -296.671527) (xy 340.484702 -296.796121)
			(xy 340.523928 -296.923289) (xy 340.555478 -297.052575) (xy 340.579241 -297.183516) (xy 340.59513 -297.315644)
			(xy 340.603088 -297.448486) (xy 340.603586 -297.515026) (xy 379.13565 -297.515026) (xy 379.139631 -297.382006)
			(xy 379.15156 -297.249461) (xy 379.171395 -297.117868) (xy 379.199064 -296.987696) (xy 379.234468 -296.859411)
			(xy 379.277481 -296.733474) (xy 379.327948 -296.610335) (xy 379.385689 -296.490434) (xy 379.450498 -296.374201)
			(xy 379.522142 -296.262051) (xy 379.600364 -296.154387) (xy 379.684885 -296.051594) (xy 379.775403 -295.954039)
			(xy 379.871592 -295.862073) (xy 379.97311 -295.776023) (xy 380.079591 -295.696199) (xy 380.190656 -295.622886)
			(xy 380.305907 -295.556346) (xy 380.424931 -295.496817) (xy 380.547302 -295.444513) (xy 380.672581 -295.399621)
			(xy 380.800322 -295.362302) (xy 380.930065 -295.332689) (xy 381.061347 -295.310888) (xy 381.193698 -295.296978)
			(xy 381.326644 -295.291007) (xy 381.459709 -295.292998) (xy 381.592417 -295.302943) (xy 381.724293 -295.320807)
			(xy 381.854864 -295.346525) (xy 381.983664 -295.380006) (xy 382.11023 -295.42113) (xy 382.234111 -295.46975)
			(xy 382.354862 -295.525691) (xy 382.472052 -295.588753) (xy 382.585261 -295.658711) (xy 382.694083 -295.735315)
			(xy 382.798129 -295.818289) (xy 382.897027 -295.907337) (xy 382.990422 -296.00214) (xy 383.07798 -296.102358)
			(xy 383.159389 -296.207634) (xy 383.234355 -296.31759) (xy 383.302612 -296.431832) (xy 383.363914 -296.549952)
			(xy 383.418043 -296.671527) (xy 383.464804 -296.796121) (xy 383.50403 -296.923289) (xy 383.53558 -297.052575)
			(xy 383.559343 -297.183516) (xy 383.575232 -297.315644) (xy 383.58319 -297.448486) (xy 383.583688 -297.515026)
			(xy 383.58319 -297.581566) (xy 383.575232 -297.714408) (xy 383.559343 -297.846536) (xy 383.53558 -297.977477)
			(xy 383.50403 -298.106763) (xy 383.464804 -298.233931) (xy 383.418043 -298.358525) (xy 383.363914 -298.4801)
			(xy 383.302612 -298.59822) (xy 383.234355 -298.712462) (xy 383.159389 -298.822418) (xy 383.07798 -298.927694)
			(xy 382.990422 -299.027912) (xy 382.897027 -299.122715) (xy 382.798129 -299.211763) (xy 382.694083 -299.294737)
			(xy 382.585261 -299.371341) (xy 382.472052 -299.441299) (xy 382.354862 -299.504361) (xy 382.234111 -299.560302)
			(xy 382.11023 -299.608922) (xy 381.983664 -299.650046) (xy 381.854864 -299.683527) (xy 381.724293 -299.709245)
			(xy 381.592417 -299.727109) (xy 381.459709 -299.737054) (xy 381.326644 -299.739045) (xy 381.193698 -299.733074)
			(xy 381.061347 -299.719164) (xy 380.930065 -299.697363) (xy 380.800322 -299.66775) (xy 380.672581 -299.630431)
			(xy 380.547302 -299.585539) (xy 380.424931 -299.533235) (xy 380.305907 -299.473706) (xy 380.190656 -299.407166)
			(xy 380.079591 -299.333853) (xy 379.97311 -299.254029) (xy 379.871592 -299.167979) (xy 379.775403 -299.076013)
			(xy 379.684885 -298.978458) (xy 379.600364 -298.875665) (xy 379.522142 -298.768001) (xy 379.450498 -298.655851)
			(xy 379.385689 -298.539618) (xy 379.327948 -298.419717) (xy 379.277481 -298.296578) (xy 379.234468 -298.170641)
			(xy 379.199064 -298.042356) (xy 379.171395 -297.912184) (xy 379.15156 -297.780591) (xy 379.139631 -297.648046)
			(xy 379.13565 -297.515026) (xy 340.603586 -297.515026) (xy 340.603088 -297.581566) (xy 340.59513 -297.714408)
			(xy 340.579241 -297.846536) (xy 340.555478 -297.977477) (xy 340.523928 -298.106763) (xy 340.484702 -298.233931)
			(xy 340.437941 -298.358525) (xy 340.383812 -298.4801) (xy 340.32251 -298.59822) (xy 340.254253 -298.712462)
			(xy 340.179287 -298.822418) (xy 340.097878 -298.927694) (xy 340.01032 -299.027912) (xy 339.916925 -299.122715)
			(xy 339.818027 -299.211763) (xy 339.713981 -299.294737) (xy 339.605159 -299.371341) (xy 339.49195 -299.441299)
			(xy 339.37476 -299.504361) (xy 339.254009 -299.560302) (xy 339.130128 -299.608922) (xy 339.003562 -299.650046)
			(xy 338.874762 -299.683527) (xy 338.744191 -299.709245) (xy 338.612315 -299.727109) (xy 338.479607 -299.737054)
			(xy 338.346542 -299.739045) (xy 338.213596 -299.733074) (xy 338.081245 -299.719164) (xy 337.949963 -299.697363)
			(xy 337.82022 -299.66775) (xy 337.692479 -299.630431) (xy 337.5672 -299.585539) (xy 337.444829 -299.533235)
			(xy 337.325805 -299.473706) (xy 337.210554 -299.407166) (xy 337.099489 -299.333853) (xy 336.993008 -299.254029)
			(xy 336.89149 -299.167979) (xy 336.795301 -299.076013) (xy 336.704783 -298.978458) (xy 336.620262 -298.875665)
			(xy 336.54204 -298.768001) (xy 336.470396 -298.655851) (xy 336.405587 -298.539618) (xy 336.347846 -298.419717)
			(xy 336.297379 -298.296578) (xy 336.254366 -298.170641) (xy 336.218962 -298.042356) (xy 336.191293 -297.912184)
			(xy 336.171458 -297.780591) (xy 336.159529 -297.648046) (xy 336.155548 -297.515026) (xy 322.729098 -297.515026)
			(xy 322.729098 -331.869034) (xy 323.104256 -332.244192) (xy 329.74026 -332.244192)
		)
		(stroke
			(width 0)
			(type solid)
		)
		(fill yes)
		(layer "In8.Cu")
		(net "PVCCIN_CPU0")
	)
	(gr_poly
		(pts
			(xy 79.7941 -330.372212) (xy 79.812141 -330.354954) (xy 79.853635 -330.3272) (xy 79.899754 -330.308092)
			(xy 79.948718 -330.298368) (xy 79.973678 -330.29779) (xy 83.488022 -330.29779) (xy 84.600542 -329.18527)
			(xy 84.600542 -327.37171) (xy 84.601122 -327.346753) (xy 84.610877 -327.297802) (xy 84.629995 -327.251695)
			(xy 84.657741 -327.210203) (xy 84.674964 -327.192132) (xy 85.589364 -326.277732) (xy 85.607406 -326.260475)
			(xy 85.648901 -326.232724) (xy 85.695019 -326.213616) (xy 85.743982 -326.203889) (xy 85.768942 -326.20331)
			(xy 91.353386 -326.20331) (xy 92.525342 -325.031354) (xy 92.525342 -323.46011) (xy 92.525922 -323.435153)
			(xy 92.535677 -323.386202) (xy 92.554795 -323.340095) (xy 92.582541 -323.298603) (xy 92.599764 -323.280532)
			(xy 93.082364 -322.797932) (xy 93.100406 -322.780675) (xy 93.141901 -322.752924) (xy 93.188019 -322.733816)
			(xy 93.236982 -322.724089) (xy 93.261942 -322.72351) (xy 125.062742 -322.72351) (xy 125.087697 -322.724126)
			(xy 125.136646 -322.73387) (xy 125.182754 -322.752977) (xy 125.224248 -322.780712) (xy 125.24232 -322.797932)
			(xy 125.90272 -323.458332) (xy 125.919982 -323.476372) (xy 125.947744 -323.517865) (xy 125.966861 -323.563983)
			(xy 125.976596 -323.612948) (xy 125.977142 -323.63791) (xy 125.977142 -324.878954) (xy 127.352298 -326.25411)
			(xy 131.438142 -326.25411) (xy 131.463097 -326.254726) (xy 131.512046 -326.26447) (xy 131.558154 -326.283577)
			(xy 131.599648 -326.311312) (xy 131.61772 -326.328532) (xy 134.00532 -328.716132) (xy 134.022582 -328.734172)
			(xy 134.050344 -328.775665) (xy 134.069461 -328.821783) (xy 134.079196 -328.870748) (xy 134.079742 -328.89571)
			(xy 134.079742 -331.127354) (xy 134.362698 -331.41031) (xy 144.253204 -331.41031) (xy 144.258469 -331.403506)
			(xy 144.269783 -331.390542) (xy 144.27581 -331.384402) (xy 144.626838 -331.033374) (xy 144.626838 -296.608246)
			(xy 137.343388 -289.324796) (xy 133.829298 -289.324796) (xy 133.656832 -289.651186) (xy 133.666738 -289.673792)
			(xy 133.675642 -289.694884) (xy 133.688193 -289.738911) (xy 133.694526 -289.784251) (xy 133.694932 -289.807142)
			(xy 133.694424 -289.833029) (xy 133.686325 -289.884167) (xy 133.670326 -289.933407) (xy 133.64682 -289.979539)
			(xy 133.616388 -290.021426) (xy 133.579778 -290.058036) (xy 133.537891 -290.088468) (xy 133.491759 -290.111974)
			(xy 133.442519 -290.127973) (xy 133.391381 -290.136072) (xy 133.339607 -290.136072) (xy 133.288469 -290.127973)
			(xy 133.239229 -290.111974) (xy 133.193097 -290.088468) (xy 133.15121 -290.058036) (xy 133.1146 -290.021426)
			(xy 133.084168 -289.979539) (xy 133.060662 -289.933407) (xy 133.044663 -289.884167) (xy 133.036564 -289.833029)
			(xy 133.036056 -289.807142) (xy 133.036525 -289.781708) (xy 133.044335 -289.731443) (xy 133.059776 -289.682976)
			(xy 133.082481 -289.637456) (xy 133.111911 -289.595967) (xy 133.147367 -289.559492) (xy 133.188007 -289.528899)
			(xy 133.232865 -289.504913) (xy 133.280876 -289.488106) (xy 133.305804 -289.483038) (xy 133.329934 -289.478466)
			(xy 133.371844 -289.399218) (xy 133.376263 -289.389706) (xy 133.377788 -289.368811) (xy 133.370838 -289.349046)
			(xy 133.356571 -289.333703) (xy 133.337362 -289.325338) (xy 133.326886 -289.324796) (xy 131.949698 -289.324796)
			(xy 131.777232 -289.651186) (xy 131.787138 -289.673792) (xy 131.796042 -289.694884) (xy 131.808593 -289.738911)
			(xy 131.814926 -289.784251) (xy 131.815332 -289.807142) (xy 131.814824 -289.833029) (xy 131.806725 -289.884167)
			(xy 131.790726 -289.933407) (xy 131.76722 -289.979539) (xy 131.736788 -290.021426) (xy 131.700178 -290.058036)
			(xy 131.658291 -290.088468) (xy 131.612159 -290.111974) (xy 131.562919 -290.127973) (xy 131.511781 -290.136072)
			(xy 131.460007 -290.136072) (xy 131.408869 -290.127973) (xy 131.359629 -290.111974) (xy 131.313497 -290.088468)
			(xy 131.27161 -290.058036) (xy 131.235 -290.021426) (xy 131.204568 -289.979539) (xy 131.181062 -289.933407)
			(xy 131.165063 -289.884167) (xy 131.156964 -289.833029) (xy 131.156456 -289.807142) (xy 131.156925 -289.781708)
			(xy 131.164735 -289.731443) (xy 131.180176 -289.682976) (xy 131.202881 -289.637456) (xy 131.232311 -289.595967)
			(xy 131.267767 -289.559492) (xy 131.308407 -289.528899) (xy 131.353265 -289.504913) (xy 131.401276 -289.488106)
			(xy 131.426204 -289.483038) (xy 131.450334 -289.478466) (xy 131.492244 -289.399218) (xy 131.496663 -289.389706)
			(xy 131.498188 -289.368811) (xy 131.491238 -289.349046) (xy 131.476971 -289.333703) (xy 131.457762 -289.325338)
			(xy 131.447286 -289.324796) (xy 130.070098 -289.324796) (xy 129.897632 -289.651186) (xy 129.907538 -289.673792)
			(xy 129.916442 -289.694884) (xy 129.928993 -289.738911) (xy 129.935326 -289.784251) (xy 129.935732 -289.807142)
			(xy 129.935224 -289.833029) (xy 129.927125 -289.884167) (xy 129.911126 -289.933407) (xy 129.88762 -289.979539)
			(xy 129.857188 -290.021426) (xy 129.820578 -290.058036) (xy 129.778691 -290.088468) (xy 129.732559 -290.111974)
			(xy 129.683319 -290.127973) (xy 129.632181 -290.136072) (xy 129.580407 -290.136072) (xy 129.529269 -290.127973)
			(xy 129.480029 -290.111974) (xy 129.433897 -290.088468) (xy 129.39201 -290.058036) (xy 129.3554 -290.021426)
			(xy 129.324968 -289.979539) (xy 129.301462 -289.933407) (xy 129.285463 -289.884167) (xy 129.277364 -289.833029)
			(xy 129.276856 -289.807142) (xy 129.277325 -289.781708) (xy 129.285135 -289.731443) (xy 129.300576 -289.682976)
			(xy 129.323281 -289.637456) (xy 129.352711 -289.595967) (xy 129.388167 -289.559492) (xy 129.428807 -289.528899)
			(xy 129.473665 -289.504913) (xy 129.521676 -289.488106) (xy 129.546604 -289.483038) (xy 129.570734 -289.478466)
			(xy 129.612644 -289.399218) (xy 129.617063 -289.389706) (xy 129.618588 -289.368811) (xy 129.611638 -289.349046)
			(xy 129.597371 -289.333703) (xy 129.578162 -289.325338) (xy 129.567686 -289.324796) (xy 128.190498 -289.324796)
			(xy 128.018032 -289.651186) (xy 128.027938 -289.673792) (xy 128.036842 -289.694884) (xy 128.049393 -289.738911)
			(xy 128.055726 -289.784251) (xy 128.056132 -289.807142) (xy 128.055624 -289.833029) (xy 128.047525 -289.884167)
			(xy 128.031526 -289.933407) (xy 128.00802 -289.979539) (xy 127.977588 -290.021426) (xy 127.940978 -290.058036)
			(xy 127.899091 -290.088468) (xy 127.852959 -290.111974) (xy 127.803719 -290.127973) (xy 127.752581 -290.136072)
			(xy 127.700807 -290.136072) (xy 127.649669 -290.127973) (xy 127.600429 -290.111974) (xy 127.554297 -290.088468)
			(xy 127.51241 -290.058036) (xy 127.4758 -290.021426) (xy 127.445368 -289.979539) (xy 127.421862 -289.933407)
			(xy 127.405863 -289.884167) (xy 127.397764 -289.833029) (xy 127.397256 -289.807142) (xy 127.397725 -289.781708)
			(xy 127.405535 -289.731443) (xy 127.420976 -289.682976) (xy 127.443681 -289.637456) (xy 127.473111 -289.595967)
			(xy 127.508567 -289.559492) (xy 127.549207 -289.528899) (xy 127.594065 -289.504913) (xy 127.642076 -289.488106)
			(xy 127.667004 -289.483038) (xy 127.691134 -289.478466) (xy 127.733044 -289.399218) (xy 127.737463 -289.389706)
			(xy 127.738988 -289.368811) (xy 127.732038 -289.349046) (xy 127.717771 -289.333703) (xy 127.698562 -289.325338)
			(xy 127.688086 -289.324796) (xy 126.310898 -289.324796) (xy 126.138432 -289.651186) (xy 126.148338 -289.673792)
			(xy 126.157242 -289.694884) (xy 126.169793 -289.738911) (xy 126.176126 -289.784251) (xy 126.176532 -289.807142)
			(xy 126.176024 -289.833029) (xy 126.167925 -289.884167) (xy 126.151926 -289.933407) (xy 126.12842 -289.979539)
			(xy 126.097988 -290.021426) (xy 126.061378 -290.058036) (xy 126.019491 -290.088468) (xy 125.973359 -290.111974)
			(xy 125.924119 -290.127973) (xy 125.872981 -290.136072) (xy 125.821207 -290.136072) (xy 125.770069 -290.127973)
			(xy 125.720829 -290.111974) (xy 125.674697 -290.088468) (xy 125.63281 -290.058036) (xy 125.5962 -290.021426)
			(xy 125.565768 -289.979539) (xy 125.542262 -289.933407) (xy 125.526263 -289.884167) (xy 125.518164 -289.833029)
			(xy 125.517656 -289.807142) (xy 125.518125 -289.781708) (xy 125.525935 -289.731443) (xy 125.541376 -289.682976)
			(xy 125.564081 -289.637456) (xy 125.593511 -289.595967) (xy 125.628967 -289.559492) (xy 125.669607 -289.528899)
			(xy 125.714465 -289.504913) (xy 125.762476 -289.488106) (xy 125.787404 -289.483038) (xy 125.811534 -289.478466)
			(xy 125.853444 -289.399218) (xy 125.857863 -289.389706) (xy 125.859388 -289.368811) (xy 125.852438 -289.349046)
			(xy 125.838171 -289.333703) (xy 125.818962 -289.325338) (xy 125.808486 -289.324796) (xy 124.431298 -289.324796)
			(xy 124.258832 -289.651186) (xy 124.268738 -289.673792) (xy 124.277642 -289.694884) (xy 124.290193 -289.738911)
			(xy 124.296526 -289.784251) (xy 124.296932 -289.807142) (xy 124.296424 -289.833029) (xy 124.288325 -289.884167)
			(xy 124.272326 -289.933407) (xy 124.24882 -289.979539) (xy 124.218388 -290.021426) (xy 124.181778 -290.058036)
			(xy 124.139891 -290.088468) (xy 124.093759 -290.111974) (xy 124.044519 -290.127973) (xy 123.993381 -290.136072)
			(xy 123.941607 -290.136072) (xy 123.890469 -290.127973) (xy 123.841229 -290.111974) (xy 123.795097 -290.088468)
			(xy 123.75321 -290.058036) (xy 123.7166 -290.021426) (xy 123.686168 -289.979539) (xy 123.662662 -289.933407)
			(xy 123.646663 -289.884167) (xy 123.638564 -289.833029) (xy 123.638056 -289.807142) (xy 123.638525 -289.781708)
			(xy 123.646335 -289.731443) (xy 123.661776 -289.682976) (xy 123.684481 -289.637456) (xy 123.713911 -289.595967)
			(xy 123.749367 -289.559492) (xy 123.790007 -289.528899) (xy 123.834865 -289.504913) (xy 123.882876 -289.488106)
			(xy 123.907804 -289.483038) (xy 123.931934 -289.478466) (xy 123.973844 -289.399218) (xy 123.978263 -289.389706)
			(xy 123.979788 -289.368811) (xy 123.972838 -289.349046) (xy 123.958571 -289.333703) (xy 123.939362 -289.325338)
			(xy 123.928886 -289.324796) (xy 122.551698 -289.324796) (xy 122.379232 -289.651186) (xy 122.389138 -289.673792)
			(xy 122.398042 -289.694884) (xy 122.410593 -289.738911) (xy 122.416926 -289.784251) (xy 122.417332 -289.807142)
			(xy 122.416824 -289.833029) (xy 122.408725 -289.884167) (xy 122.392726 -289.933407) (xy 122.36922 -289.979539)
			(xy 122.338788 -290.021426) (xy 122.302178 -290.058036) (xy 122.260291 -290.088468) (xy 122.214159 -290.111974)
			(xy 122.164919 -290.127973) (xy 122.113781 -290.136072) (xy 122.062007 -290.136072) (xy 122.010869 -290.127973)
			(xy 121.961629 -290.111974) (xy 121.915497 -290.088468) (xy 121.87361 -290.058036) (xy 121.837 -290.021426)
			(xy 121.806568 -289.979539) (xy 121.783062 -289.933407) (xy 121.767063 -289.884167) (xy 121.758964 -289.833029)
			(xy 121.758456 -289.807142) (xy 121.758925 -289.781708) (xy 121.766735 -289.731443) (xy 121.782176 -289.682976)
			(xy 121.804881 -289.637456) (xy 121.834311 -289.595967) (xy 121.869767 -289.559492) (xy 121.910407 -289.528899)
			(xy 121.955265 -289.504913) (xy 122.003276 -289.488106) (xy 122.028204 -289.483038) (xy 122.052334 -289.478466)
			(xy 122.094244 -289.399218) (xy 122.098663 -289.389706) (xy 122.100188 -289.368811) (xy 122.093238 -289.349046)
			(xy 122.078971 -289.333703) (xy 122.059762 -289.325338) (xy 122.049286 -289.324796) (xy 121.76252 -289.324796)
			(xy 121.737567 -289.324177) (xy 121.688621 -289.314426) (xy 121.642518 -289.295315) (xy 121.601029 -289.267577)
			(xy 121.582942 -289.250374) (xy 121.576592 -289.244024) (xy 121.550405 -289.240181) (xy 121.499636 -289.225231)
			(xy 121.451911 -289.202354) (xy 121.40846 -289.172138) (xy 121.3704 -289.135363) (xy 121.338711 -289.092974)
			(xy 121.314209 -289.046062) (xy 121.297525 -288.995836) (xy 121.289089 -288.943589) (xy 121.288556 -288.917126)
			(xy 121.288944 -288.895793) (xy 121.294555 -288.853497) (xy 121.299732 -288.832798) (xy 121.305066 -288.812732)
			(xy 121.083832 -288.426906) (xy 121.063258 -288.421572) (xy 121.03731 -288.414077) (xy 120.988103 -288.391817)
			(xy 120.943182 -288.361835) (xy 120.903747 -288.324935) (xy 120.870852 -288.282101) (xy 120.845376 -288.23448)
			(xy 120.828002 -288.183344) (xy 120.819192 -288.13006) (xy 120.818656 -288.103056) (xy 120.819045 -288.080934)
			(xy 120.825029 -288.037094) (xy 120.830594 -288.01568) (xy 120.836182 -287.995106) (xy 120.616726 -287.612328)
			(xy 120.595898 -287.606994) (xy 120.569859 -287.599684) (xy 120.520436 -287.57773) (xy 120.475283 -287.547968)
			(xy 120.435622 -287.511203) (xy 120.402528 -287.468431) (xy 120.376897 -287.420811) (xy 120.359423 -287.369632)
			(xy 120.35058 -287.31628) (xy 120.350026 -287.28924) (xy 120.350403 -287.26659) (xy 120.356645 -287.221723)
			(xy 120.362472 -287.199832) (xy 120.368314 -287.179258) (xy 120.151398 -286.800798) (xy 120.130062 -286.795464)
			(xy 120.106492 -286.789248) (xy 120.061365 -286.770818) (xy 120.019447 -286.745939) (xy 119.981654 -286.715154)
			(xy 119.94881 -286.679136) (xy 119.921633 -286.63867) (xy 119.900716 -286.594641) (xy 119.886516 -286.548011)
			(xy 119.879343 -286.499797) (xy 119.878856 -286.475424) (xy 119.879275 -286.451585) (xy 119.886161 -286.404408)
			(xy 119.892572 -286.381444) (xy 119.898922 -286.360616) (xy 119.6848 -285.987236) (xy 119.663464 -285.982156)
			(xy 119.639649 -285.976128) (xy 119.594 -285.957977) (xy 119.551553 -285.93325) (xy 119.513247 -285.902495)
			(xy 119.479932 -285.866393) (xy 119.452347 -285.825745) (xy 119.431102 -285.781452) (xy 119.416669 -285.734495)
			(xy 119.409367 -285.685916) (xy 119.408956 -285.661354) (xy 119.409336 -285.636658) (xy 119.416602 -285.587807)
			(xy 119.423434 -285.564072) (xy 119.430038 -285.54299) (xy 119.218456 -285.173928) (xy 119.196612 -285.169102)
			(xy 119.172564 -285.163275) (xy 119.12643 -285.145385) (xy 119.083492 -285.120795) (xy 119.044716 -285.090058)
			(xy 119.010975 -285.053866) (xy 118.983028 -285.013033) (xy 118.961505 -284.968479) (xy 118.94689 -284.921206)
			(xy 118.939511 -284.872279) (xy 118.939056 -284.847538) (xy 118.939551 -284.822033) (xy 118.947462 -284.771639)
			(xy 118.954804 -284.747208) (xy 118.961662 -284.725872) (xy 118.75135 -284.35935) (xy 118.729252 -284.354524)
			(xy 118.705131 -284.348853) (xy 118.658821 -284.331233) (xy 118.615687 -284.306849) (xy 118.57671 -284.276258)
			(xy 118.542776 -284.240153) (xy 118.514656 -284.199356) (xy 118.49299 -284.154796) (xy 118.47827 -284.107484)
			(xy 118.470832 -284.058496) (xy 118.470426 -284.033722) (xy 118.47092 -284.007751) (xy 118.479082 -283.956453)
			(xy 118.486682 -283.931614) (xy 118.493794 -283.910024) (xy 118.285006 -283.546042) (xy 118.262654 -283.541216)
			(xy 118.238329 -283.535715) (xy 118.19158 -283.518352) (xy 118.147995 -283.494119) (xy 118.108576 -283.463573)
			(xy 118.07423 -283.427416) (xy 118.045747 -283.386482) (xy 118.023783 -283.34171) (xy 118.008842 -283.294131)
			(xy 118.001269 -283.24484) (xy 118.00078 -283.219906) (xy 118.001331 -283.193195) (xy 118.010017 -283.140484)
			(xy 118.018052 -283.115004) (xy 118.025418 -283.09316) (xy 117.818408 -282.732226) (xy 117.795802 -282.727908)
			(xy 117.771245 -282.722601) (xy 117.723997 -282.705524) (xy 117.679905 -282.681445) (xy 117.639997 -282.650927)
			(xy 117.605208 -282.614682) (xy 117.57635 -282.573559) (xy 117.554097 -282.528517) (xy 117.53897 -282.480609)
			(xy 117.531322 -282.430956) (xy 117.53088 -282.405836) (xy 117.531442 -282.378318) (xy 117.540641 -282.324056)
			(xy 117.549168 -282.297886) (xy 117.556788 -282.276042) (xy 117.352064 -281.918918) (xy 117.32895 -281.9146)
			(xy 117.30418 -281.909499) (xy 117.256481 -281.892699) (xy 117.211924 -281.86878) (xy 117.171563 -281.83831)
			(xy 117.136355 -281.802008) (xy 117.107131 -281.760735) (xy 117.084586 -281.715468) (xy 117.069251 -281.667278)
			(xy 117.06149 -281.617306) (xy 117.06098 -281.59202) (xy 117.061576 -281.563696) (xy 117.07128 -281.507884)
			(xy 117.080284 -281.481022) (xy 117.088158 -281.458924) (xy 116.885466 -281.10561) (xy 116.862098 -281.101292)
			(xy 116.837115 -281.096383) (xy 116.788954 -281.079875) (xy 116.743919 -281.056129) (xy 116.703091 -281.025713)
			(xy 116.667449 -280.989358) (xy 116.637849 -280.947935) (xy 116.615 -280.902438) (xy 116.59945 -280.853959)
			(xy 116.591573 -280.80366) (xy 116.59108 -280.778204) (xy 116.591694 -280.749072) (xy 116.601923 -280.691713)
			(xy 116.6114 -280.664158) (xy 116.619782 -280.64206) (xy 116.418868 -280.291794) (xy 116.395246 -280.28773)
			(xy 116.370051 -280.283016) (xy 116.321429 -280.266804) (xy 116.275917 -280.243232) (xy 116.234622 -280.212872)
			(xy 116.198548 -280.176463) (xy 116.168572 -280.134888) (xy 116.145423 -280.08916) (xy 116.129663 -280.040389)
			(xy 116.121675 -279.989761) (xy 116.12118 -279.964134) (xy 116.121861 -279.934243) (xy 116.132719 -279.875453)
			(xy 116.14277 -279.847294) (xy 116.151152 -279.824942) (xy 115.952524 -279.478232) (xy 115.928394 -279.474422)
			(xy 115.902968 -279.469945) (xy 115.853849 -279.454056) (xy 115.807821 -279.430675) (xy 115.766021 -279.400378)
			(xy 115.729477 -279.363912) (xy 115.699092 -279.322177) (xy 115.675613 -279.276199) (xy 115.659619 -279.227114)
			(xy 115.651505 -279.17613) (xy 115.651026 -279.150318) (xy 115.65144 -279.126656) (xy 115.658238 -279.079824)
			(xy 115.671697 -279.034456) (xy 115.691537 -278.991492) (xy 115.717346 -278.951826) (xy 115.748587 -278.916282)
			(xy 115.766342 -278.900636) (xy 115.766342 -277.77186) (xy 115.747058 -277.754715) (xy 115.713558 -277.715471)
			(xy 115.686607 -277.671471) (xy 115.666869 -277.623798) (xy 115.654829 -277.573625) (xy 115.650785 -277.522186)
			(xy 115.654834 -277.470747) (xy 115.666878 -277.420575) (xy 115.68662 -277.372903) (xy 115.713575 -277.328906)
			(xy 115.747078 -277.289665) (xy 115.766342 -277.272496) (xy 115.766342 -276.144482) (xy 115.746997 -276.127379)
			(xy 115.713412 -276.088161) (xy 115.686389 -276.044164) (xy 115.666595 -275.996475) (xy 115.65452 -275.946274)
			(xy 115.650461 -275.8948) (xy 115.65452 -275.843326) (xy 115.666595 -275.793125) (xy 115.686389 -275.745436)
			(xy 115.713412 -275.701439) (xy 115.746997 -275.662221) (xy 115.766342 -275.645118) (xy 115.766342 -274.516596)
			(xy 115.747055 -274.499451) (xy 115.713549 -274.460206) (xy 115.686593 -274.416205) (xy 115.66685 -274.368529)
			(xy 115.654806 -274.318352) (xy 115.650757 -274.266909) (xy 115.654803 -274.215466) (xy 115.666844 -274.165288)
			(xy 115.686585 -274.117612) (xy 115.713538 -274.073608) (xy 115.747042 -274.034362) (xy 115.766342 -274.017232)
			(xy 115.766342 -272.888964) (xy 115.746998 -272.871861) (xy 115.713417 -272.832643) (xy 115.686396 -272.788647)
			(xy 115.666605 -272.74096) (xy 115.654531 -272.69076) (xy 115.650475 -272.639288) (xy 115.654535 -272.587817)
			(xy 115.666612 -272.537618) (xy 115.686407 -272.489932) (xy 115.71343 -272.445938) (xy 115.747015 -272.406722)
			(xy 115.766342 -272.3896) (xy 115.766342 -271.261078) (xy 115.746997 -271.243975) (xy 115.713413 -271.204757)
			(xy 115.686391 -271.16076) (xy 115.666597 -271.113072) (xy 115.654522 -271.062871) (xy 115.650464 -271.011397)
			(xy 115.654523 -270.959924) (xy 115.666599 -270.909723) (xy 115.686393 -270.862035) (xy 115.713416 -270.818039)
			(xy 115.747001 -270.778821) (xy 115.766342 -270.761714) (xy 115.766342 -269.633192) (xy 115.746996 -269.616089)
			(xy 115.71341 -269.576871) (xy 115.686385 -269.532873) (xy 115.66659 -269.485184) (xy 115.654513 -269.434981)
			(xy 115.650453 -269.383506) (xy 115.654511 -269.332032) (xy 115.666586 -269.281829) (xy 115.686379 -269.234139)
			(xy 115.713402 -269.19014) (xy 115.746987 -269.15092) (xy 115.766342 -269.133828) (xy 115.766342 -268.00556)
			(xy 115.746999 -267.988457) (xy 115.713417 -267.94924) (xy 115.686398 -267.905243) (xy 115.666607 -267.857556)
			(xy 115.654534 -267.807357) (xy 115.650478 -267.755886) (xy 115.654538 -267.704415) (xy 115.666615 -267.654216)
			(xy 115.68641 -267.606531) (xy 115.713434 -267.562537) (xy 115.747019 -267.523322) (xy 115.766342 -267.506196)
			(xy 115.766342 -266.377928) (xy 115.746993 -266.360825) (xy 115.713402 -266.321606) (xy 115.686371 -266.277606)
			(xy 115.666571 -266.229914) (xy 115.65449 -266.179709) (xy 115.650426 -266.12823) (xy 115.65448 -266.07675)
			(xy 115.666553 -266.026542) (xy 115.686344 -265.978847) (xy 115.713366 -265.934843) (xy 115.746951 -265.895617)
			(xy 115.766342 -265.878564) (xy 115.766342 -264.750042) (xy 115.747 -264.732939) (xy 115.713422 -264.693722)
			(xy 115.686404 -264.649727) (xy 115.666616 -264.602041) (xy 115.654546 -264.551843) (xy 115.650491 -264.500374)
			(xy 115.654554 -264.448905) (xy 115.666632 -264.39871) (xy 115.686428 -264.351027) (xy 115.713452 -264.307036)
			(xy 115.747037 -264.267824) (xy 115.766342 -264.250678) (xy 115.766342 -261.17931) (xy 115.766922 -261.154353)
			(xy 115.776677 -261.105402) (xy 115.795795 -261.059295) (xy 115.823541 -261.017803) (xy 115.840764 -260.999732)
			(xy 116.501164 -260.339332) (xy 116.519206 -260.322075) (xy 116.560701 -260.294324) (xy 116.606819 -260.275216)
			(xy 116.655782 -260.265489) (xy 116.680742 -260.26491) (xy 120.563386 -260.26491) (xy 120.723152 -260.105144)
			(xy 120.733639 -260.093922) (xy 120.747924 -260.066749) (xy 120.753479 -260.036556) (xy 120.749802 -260.006077)
			(xy 120.737224 -259.978072) (xy 120.72747 -259.966206) (xy 120.712138 -259.948155) (xy 120.686288 -259.908474)
			(xy 120.666413 -259.865487) (xy 120.652926 -259.820089) (xy 120.646109 -259.773223) (xy 120.645682 -259.749544)
			(xy 120.64615 -259.724194) (xy 120.653943 -259.674095) (xy 120.669348 -259.625791) (xy 120.692001 -259.580432)
			(xy 120.721361 -259.539098) (xy 120.75673 -259.502771) (xy 120.797265 -259.472317) (xy 120.819418 -259.459984)
			(xy 120.846342 -259.445506) (xy 120.846342 -258.754372) (xy 120.819672 -258.739894) (xy 120.797785 -258.727475)
			(xy 120.757763 -258.696974) (xy 120.722866 -258.660719) (xy 120.693913 -258.619562) (xy 120.671582 -258.574468)
			(xy 120.656398 -258.526493) (xy 120.648715 -258.476762) (xy 120.648715 -258.426442) (xy 120.656397 -258.376711)
			(xy 120.671581 -258.328736) (xy 120.693911 -258.283641) (xy 120.722863 -258.242484) (xy 120.75776 -258.206229)
			(xy 120.797782 -258.175727) (xy 120.819672 -258.163314) (xy 120.846342 -258.148836) (xy 120.846342 -257.585972)
			(xy 120.819672 -257.571494) (xy 120.7978 -257.559052) (xy 120.757782 -257.52855) (xy 120.722887 -257.492298)
			(xy 120.693933 -257.451146) (xy 120.671598 -257.406057) (xy 120.656406 -257.358088) (xy 120.648712 -257.308363)
			(xy 120.648222 -257.283204) (xy 120.648748 -257.256822) (xy 120.657187 -257.204736) (xy 120.673849 -257.154671)
			(xy 120.698305 -257.107915) (xy 120.729924 -257.065674) (xy 120.748552 -257.046984) (xy 120.757969 -257.037253)
			(xy 120.77176 -257.01396) (xy 120.778952 -256.987864) (xy 120.77904 -256.960794) (xy 120.772018 -256.934652)
			(xy 120.758378 -256.911269) (xy 120.74906 -256.901442) (xy 120.730775 -256.882785) (xy 120.699762 -256.840748)
			(xy 120.6758 -256.79433) (xy 120.659491 -256.744703) (xy 120.651249 -256.693119) (xy 120.650762 -256.667)
			(xy 120.651231 -256.641999) (xy 120.658813 -256.592574) (xy 120.673801 -256.54487) (xy 120.695849 -256.499991)
			(xy 120.724447 -256.458973) (xy 120.758934 -256.422766) (xy 120.798512 -256.392207) (xy 120.82018 -256.379726)
			(xy 120.846342 -256.365248) (xy 120.846342 -255.833372) (xy 120.819672 -255.818894) (xy 120.7978 -255.806452)
			(xy 120.757782 -255.77595) (xy 120.722887 -255.739698) (xy 120.693933 -255.698546) (xy 120.671598 -255.653457)
			(xy 120.656406 -255.605488) (xy 120.648712 -255.555763) (xy 120.648222 -255.530604) (xy 120.648677 -255.506074)
			(xy 120.655976 -255.45756) (xy 120.670411 -255.410672) (xy 120.691661 -255.366453) (xy 120.719253 -255.325888)
			(xy 120.735598 -255.307592) (xy 120.745592 -255.296082) (xy 120.75882 -255.268633) (xy 120.763365 -255.238503)
			(xy 120.758822 -255.208373) (xy 120.745596 -255.180923) (xy 120.735598 -255.169416) (xy 120.719261 -255.15111)
			(xy 120.69165 -255.110556) (xy 120.670388 -255.066341) (xy 120.655949 -255.019452) (xy 120.648655 -254.970935)
			(xy 120.648222 -254.946404) (xy 120.64868 -254.921242) (xy 120.656363 -254.871509) (xy 120.671552 -254.823532)
			(xy 120.693888 -254.778437) (xy 120.722849 -254.737282) (xy 120.757754 -254.701031) (xy 120.797786 -254.670536)
			(xy 120.819672 -254.658114) (xy 120.846342 -254.643636) (xy 120.846342 -253.496572) (xy 120.819672 -253.482094)
			(xy 120.7978 -253.469652) (xy 120.757782 -253.43915) (xy 120.722887 -253.402898) (xy 120.693933 -253.361746)
			(xy 120.671598 -253.316657) (xy 120.656406 -253.268688) (xy 120.648712 -253.218963) (xy 120.648222 -253.193804)
			(xy 120.648677 -253.169274) (xy 120.655976 -253.12076) (xy 120.670411 -253.073872) (xy 120.691661 -253.029653)
			(xy 120.719253 -252.989088) (xy 120.735598 -252.970792) (xy 120.745592 -252.959282) (xy 120.75882 -252.931833)
			(xy 120.763365 -252.901703) (xy 120.758822 -252.871573) (xy 120.745596 -252.844123) (xy 120.735598 -252.832616)
			(xy 120.719261 -252.81431) (xy 120.69165 -252.773756) (xy 120.670388 -252.729541) (xy 120.655949 -252.682652)
			(xy 120.648655 -252.634135) (xy 120.648222 -252.609604) (xy 120.64868 -252.584442) (xy 120.656363 -252.534709)
			(xy 120.671552 -252.486732) (xy 120.693888 -252.441637) (xy 120.722849 -252.400482) (xy 120.757754 -252.364231)
			(xy 120.797786 -252.333736) (xy 120.819672 -252.321314) (xy 120.846342 -252.306836) (xy 120.846342 -251.743972)
			(xy 120.819672 -251.729494) (xy 120.7978 -251.717052) (xy 120.757782 -251.68655) (xy 120.722887 -251.650298)
			(xy 120.693933 -251.609146) (xy 120.671598 -251.564057) (xy 120.656406 -251.516088) (xy 120.648712 -251.466363)
			(xy 120.648222 -251.441204) (xy 120.648677 -251.416674) (xy 120.655976 -251.36816) (xy 120.670411 -251.321272)
			(xy 120.691661 -251.277053) (xy 120.719253 -251.236488) (xy 120.735598 -251.218192) (xy 120.745592 -251.206682)
			(xy 120.75882 -251.179233) (xy 120.763365 -251.149103) (xy 120.758822 -251.118973) (xy 120.745596 -251.091523)
			(xy 120.735598 -251.080016) (xy 120.719261 -251.06171) (xy 120.69165 -251.021156) (xy 120.670388 -250.976941)
			(xy 120.655949 -250.930052) (xy 120.648655 -250.881535) (xy 120.648222 -250.857004) (xy 120.64868 -250.831842)
			(xy 120.656363 -250.782109) (xy 120.671552 -250.734132) (xy 120.693888 -250.689037) (xy 120.722849 -250.647882)
			(xy 120.757754 -250.611631) (xy 120.797786 -250.581136) (xy 120.819672 -250.568714) (xy 120.846342 -250.554236)
			(xy 120.846342 -249.422666) (xy 120.796812 -249.373136) (xy 120.793764 -249.371104) (xy 120.774457 -249.356263)
			(xy 120.740026 -249.32183) (xy 120.725184 -249.302524) (xy 120.723152 -249.299476) (xy 118.438422 -247.014746)
			(xy 118.432027 -247.008203) (xy 118.420078 -246.994347) (xy 118.414546 -246.98706) (xy 118.389751 -246.985197)
			(xy 118.341103 -246.97493) (xy 118.294559 -246.957442) (xy 118.251186 -246.933133) (xy 118.211977 -246.90256)
			(xy 118.177827 -246.866423) (xy 118.14952 -246.825547) (xy 118.127702 -246.780869) (xy 118.112874 -246.733412)
			(xy 118.105374 -246.68426) (xy 118.10492 -246.6594) (xy 118.105405 -246.633766) (xy 118.11336 -246.58312)
			(xy 118.12909 -246.534326) (xy 118.152215 -246.488571) (xy 118.182171 -246.446966) (xy 118.21823 -246.410525)
			(xy 118.259516 -246.380131) (xy 118.305025 -246.356525) (xy 118.329202 -246.347996) (xy 118.364 -246.336566)
			(xy 118.364 -245.068852) (xy 118.364616 -245.043897) (xy 118.374362 -244.994948) (xy 118.393469 -244.948841)
			(xy 118.421203 -244.907347) (xy 118.438422 -244.889274) (xy 119.904764 -243.422932) (xy 119.922806 -243.405675)
			(xy 119.964301 -243.377924) (xy 120.010419 -243.358816) (xy 120.059382 -243.349089) (xy 120.084342 -243.34851)
			(xy 120.639586 -243.34851) (xy 120.770142 -243.217954) (xy 120.770142 -242.590066) (xy 120.360186 -242.18011)
			(xy 117.747542 -242.18011) (xy 117.722588 -242.179493) (xy 117.673639 -242.169746) (xy 117.627533 -242.150638)
			(xy 117.586039 -242.122904) (xy 117.567964 -242.105688) (xy 115.662964 -240.200688) (xy 115.645702 -240.182648)
			(xy 115.617938 -240.141155) (xy 115.598819 -240.095037) (xy 115.58908 -240.046072) (xy 115.588542 -240.02111)
			(xy 115.588542 -238.703866) (xy 115.229386 -238.34471) (xy 114.29746 -238.34471) (xy 114.283236 -238.37265)
			(xy 114.271194 -238.39565) (xy 114.240965 -238.437857) (xy 114.204465 -238.474774) (xy 114.162604 -238.505479)
			(xy 114.116427 -238.529205) (xy 114.06709 -238.54536) (xy 114.015823 -238.553539) (xy 113.963909 -238.553539)
			(xy 113.912642 -238.54536) (xy 113.863305 -238.529205) (xy 113.817128 -238.505479) (xy 113.775267 -238.474774)
			(xy 113.738767 -238.437857) (xy 113.708538 -238.39565) (xy 113.696496 -238.37265) (xy 113.682272 -238.34471)
			(xy 113.35766 -238.34471) (xy 113.343436 -238.37265) (xy 113.331394 -238.39565) (xy 113.301165 -238.437857)
			(xy 113.264665 -238.474774) (xy 113.222804 -238.505479) (xy 113.176627 -238.529205) (xy 113.12729 -238.54536)
			(xy 113.076023 -238.553539) (xy 113.024109 -238.553539) (xy 112.972842 -238.54536) (xy 112.923505 -238.529205)
			(xy 112.877328 -238.505479) (xy 112.835467 -238.474774) (xy 112.798967 -238.437857) (xy 112.768738 -238.39565)
			(xy 112.756696 -238.37265) (xy 112.742472 -238.34471) (xy 112.41786 -238.34471) (xy 112.403636 -238.37265)
			(xy 112.391594 -238.39565) (xy 112.361365 -238.437857) (xy 112.324865 -238.474774) (xy 112.283004 -238.505479)
			(xy 112.236827 -238.529205) (xy 112.18749 -238.54536) (xy 112.136223 -238.553539) (xy 112.084309 -238.553539)
			(xy 112.033042 -238.54536) (xy 111.983705 -238.529205) (xy 111.937528 -238.505479) (xy 111.895667 -238.474774)
			(xy 111.859167 -238.437857) (xy 111.828938 -238.39565) (xy 111.816896 -238.37265) (xy 111.802672 -238.34471)
			(xy 111.47806 -238.34471) (xy 111.463836 -238.37265) (xy 111.451794 -238.39565) (xy 111.421565 -238.437857)
			(xy 111.385065 -238.474774) (xy 111.343204 -238.505479) (xy 111.297027 -238.529205) (xy 111.24769 -238.54536)
			(xy 111.196423 -238.553539) (xy 111.144509 -238.553539) (xy 111.093242 -238.54536) (xy 111.043905 -238.529205)
			(xy 110.997728 -238.505479) (xy 110.955867 -238.474774) (xy 110.919367 -238.437857) (xy 110.889138 -238.39565)
			(xy 110.877096 -238.37265) (xy 110.862872 -238.34471) (xy 110.53826 -238.34471) (xy 110.524036 -238.37265)
			(xy 110.511994 -238.39565) (xy 110.481765 -238.437857) (xy 110.445265 -238.474774) (xy 110.403404 -238.505479)
			(xy 110.357227 -238.529205) (xy 110.30789 -238.54536) (xy 110.256623 -238.553539) (xy 110.204709 -238.553539)
			(xy 110.153442 -238.54536) (xy 110.104105 -238.529205) (xy 110.057928 -238.505479) (xy 110.016067 -238.474774)
			(xy 109.979567 -238.437857) (xy 109.949338 -238.39565) (xy 109.937296 -238.37265) (xy 109.923072 -238.34471)
			(xy 109.59846 -238.34471) (xy 109.584236 -238.37265) (xy 109.572194 -238.39565) (xy 109.541965 -238.437857)
			(xy 109.505465 -238.474774) (xy 109.463604 -238.505479) (xy 109.417427 -238.529205) (xy 109.36809 -238.54536)
			(xy 109.316823 -238.553539) (xy 109.264909 -238.553539) (xy 109.213642 -238.54536) (xy 109.164305 -238.529205)
			(xy 109.118128 -238.505479) (xy 109.076267 -238.474774) (xy 109.039767 -238.437857) (xy 109.009538 -238.39565)
			(xy 108.997496 -238.37265) (xy 108.983272 -238.34471) (xy 104.492298 -238.34471) (xy 103.294942 -239.542066)
			(xy 103.294942 -245.224554) (xy 103.679498 -245.60911) (xy 104.793542 -245.60911) (xy 104.818497 -245.609726)
			(xy 104.867446 -245.61947) (xy 104.913554 -245.638577) (xy 104.955048 -245.666312) (xy 104.97312 -245.683532)
			(xy 105.30332 -246.013732) (xy 105.320582 -246.031772) (xy 105.348344 -246.073265) (xy 105.367461 -246.119383)
			(xy 105.377196 -246.168348) (xy 105.377742 -246.19331) (xy 105.377742 -246.366284) (xy 105.404412 -246.380762)
			(xy 105.426426 -246.393135) (xy 105.466703 -246.423595) (xy 105.501835 -246.459868) (xy 105.530993 -246.501097)
			(xy 105.553487 -246.546308) (xy 105.568786 -246.594432) (xy 105.576528 -246.644332) (xy 105.576531 -246.69483)
			(xy 105.568794 -246.744731) (xy 105.553501 -246.792857) (xy 105.531012 -246.838071) (xy 105.501859 -246.879303)
			(xy 105.466731 -246.91558) (xy 105.426458 -246.946045) (xy 105.404412 -246.958358) (xy 105.377742 -246.972836)
			(xy 105.377742 -247.38711) (xy 105.37717 -247.41207) (xy 105.367427 -247.461029) (xy 105.348319 -247.507146)
			(xy 105.320579 -247.548648) (xy 105.30332 -247.566688) (xy 104.66832 -248.201688) (xy 104.650279 -248.218948)
			(xy 104.608786 -248.246705) (xy 104.562668 -248.265816) (xy 104.513703 -248.275544) (xy 104.488742 -248.27611)
			(xy 103.679498 -248.27611) (xy 103.345742 -248.609866) (xy 103.345742 -255.908556) (xy 103.663496 -256.22631)
			(xy 104.742742 -256.22631) (xy 104.767697 -256.226926) (xy 104.816646 -256.23667) (xy 104.862754 -256.255777)
			(xy 104.904248 -256.283512) (xy 104.92232 -256.300732) (xy 105.43032 -256.808732) (xy 105.447582 -256.826772)
			(xy 105.475344 -256.868265) (xy 105.494461 -256.914383) (xy 105.504196 -256.963348) (xy 105.504742 -256.98831)
			(xy 105.504742 -257.366262) (xy 105.542334 -257.376168) (xy 105.5666 -257.383203) (xy 105.61278 -257.403692)
			(xy 105.655278 -257.431012) (xy 105.693091 -257.464518) (xy 105.725325 -257.50342) (xy 105.751222 -257.5468)
			(xy 105.770169 -257.593634) (xy 105.781719 -257.642817) (xy 105.785601 -257.69319) (xy 105.781723 -257.743562)
			(xy 105.770175 -257.792746) (xy 105.751231 -257.839582) (xy 105.725337 -257.882963) (xy 105.693105 -257.921867)
			(xy 105.655295 -257.955376) (xy 105.612799 -257.982698) (xy 105.56662 -258.00319) (xy 105.542334 -258.010152)
			(xy 105.504742 -258.020058) (xy 105.504742 -260.388354) (xy 105.6767 -260.560312) (xy 107.629198 -260.560312)
			(xy 107.654151 -260.560933) (xy 107.703094 -260.570687) (xy 107.749194 -260.589801) (xy 107.79068 -260.617541)
			(xy 107.808776 -260.634734) (xy 108.077508 -260.903466) (xy 108.094768 -260.921507) (xy 108.122525 -260.963)
			(xy 108.141637 -261.009119) (xy 108.151367 -261.058083) (xy 108.15193 -261.083044) (xy 108.15193 -261.443216)
			(xy 108.151317 -261.468172) (xy 108.141578 -261.517125) (xy 108.122476 -261.563238) (xy 108.094747 -261.60474)
			(xy 108.077508 -261.622794) (xy 107.736894 -261.963408) (xy 107.718852 -261.980665) (xy 107.677358 -262.008416)
			(xy 107.631239 -262.02752) (xy 107.582276 -262.037242) (xy 107.557316 -262.03783) (xy 107.35437 -262.03783)
			(xy 107.16895 -262.22325) (xy 107.16895 -263.4996) (xy 108.306616 -264.637266) (xy 108.323876 -264.655307)
			(xy 108.351632 -264.6968) (xy 108.370744 -264.742919) (xy 108.380473 -264.791883) (xy 108.381038 -264.816844)
			(xy 108.381038 -273.453098) (xy 108.601256 -273.453098) (xy 108.601764 -273.427211) (xy 108.609863 -273.376073)
			(xy 108.625862 -273.326833) (xy 108.649368 -273.280701) (xy 108.6798 -273.238814) (xy 108.71641 -273.202204)
			(xy 108.758297 -273.171772) (xy 108.804429 -273.148266) (xy 108.853669 -273.132267) (xy 108.904807 -273.124168)
			(xy 108.956581 -273.124168) (xy 109.007719 -273.132267) (xy 109.056959 -273.148266) (xy 109.103091 -273.171772)
			(xy 109.144978 -273.202204) (xy 109.181588 -273.238814) (xy 109.21202 -273.280701) (xy 109.235526 -273.326833)
			(xy 109.251525 -273.376073) (xy 109.259624 -273.427211) (xy 109.260132 -273.453098) (xy 109.259601 -273.480806)
			(xy 109.250407 -273.535453) (xy 109.241844 -273.56181) (xy 109.234224 -273.583654) (xy 109.439202 -273.938746)
			(xy 109.462062 -273.943064) (xy 109.486859 -273.948281) (xy 109.534598 -273.965264) (xy 109.579176 -273.989353)
			(xy 109.619543 -274.019979) (xy 109.654747 -274.056422) (xy 109.683961 -274.097824) (xy 109.706494 -274.143208)
			(xy 109.721817 -274.191505) (xy 109.729569 -274.241579) (xy 109.730032 -274.266914) (xy 109.729524 -274.292801)
			(xy 109.721425 -274.343939) (xy 109.705426 -274.393179) (xy 109.68192 -274.439311) (xy 109.651488 -274.481198)
			(xy 109.614878 -274.517808) (xy 109.572991 -274.54824) (xy 109.526859 -274.571746) (xy 109.477619 -274.587745)
			(xy 109.426481 -274.595844) (xy 109.374707 -274.595844) (xy 109.323569 -274.587745) (xy 109.274329 -274.571746)
			(xy 109.228197 -274.54824) (xy 109.18631 -274.517808) (xy 109.1497 -274.481198) (xy 109.119268 -274.439311)
			(xy 109.095762 -274.393179) (xy 109.079763 -274.343939) (xy 109.071664 -274.292801) (xy 109.071156 -274.266914)
			(xy 109.071691 -274.239206) (xy 109.080883 -274.184559) (xy 109.089444 -274.158202) (xy 109.097318 -274.136104)
			(xy 108.89234 -273.781266) (xy 108.86948 -273.776948) (xy 108.844673 -273.771718) (xy 108.796897 -273.754771)
			(xy 108.75228 -273.730708) (xy 108.711874 -273.700095) (xy 108.676632 -273.663656) (xy 108.647386 -273.622251)
			(xy 108.624826 -273.576855) (xy 108.609484 -273.528539) (xy 108.601721 -273.478444) (xy 108.601256 -273.453098)
			(xy 108.381038 -273.453098) (xy 108.381038 -275.3614) (xy 108.499656 -275.566632) (xy 108.522516 -275.57095)
			(xy 108.547331 -275.576134) (xy 108.595099 -275.593102) (xy 108.639707 -275.617181) (xy 108.680106 -275.647803)
			(xy 108.715341 -275.684246) (xy 108.744584 -275.725654) (xy 108.767146 -275.771048) (xy 108.782494 -275.819361)
			(xy 108.790267 -275.869454) (xy 108.79074 -275.8948) (xy 108.790278 -275.919881) (xy 108.782691 -275.969467)
			(xy 108.767676 -276.01733) (xy 108.745581 -276.062364) (xy 108.716915 -276.10353) (xy 108.682342 -276.139875)
			(xy 108.64266 -276.170561) (xy 108.598785 -276.194878) (xy 108.551732 -276.212265) (xy 108.502588 -276.22232)
			(xy 108.477558 -276.223984) (xy 108.462128 -276.225308) (xy 108.433093 -276.236041) (xy 108.408593 -276.254961)
			(xy 108.390868 -276.280339) (xy 108.381538 -276.309854) (xy 108.381038 -276.32533) (xy 108.381038 -276.708616)
			(xy 108.601256 -276.708616) (xy 108.601789 -276.683284) (xy 108.609538 -276.633215) (xy 108.624856 -276.584922)
			(xy 108.647381 -276.53954) (xy 108.676585 -276.498139) (xy 108.711779 -276.461694) (xy 108.752134 -276.431062)
			(xy 108.796701 -276.406964) (xy 108.844429 -276.389968) (xy 108.869226 -276.384766) (xy 108.892086 -276.380448)
			(xy 109.097064 -276.02561) (xy 109.08919 -276.003766) (xy 109.080545 -275.977358) (xy 109.071224 -275.922582)
			(xy 109.070648 -275.8948) (xy 109.071156 -275.868893) (xy 109.079262 -275.817716) (xy 109.095274 -275.768437)
			(xy 109.118797 -275.72227) (xy 109.149253 -275.680351) (xy 109.185891 -275.643713) (xy 109.22781 -275.613257)
			(xy 109.273977 -275.589734) (xy 109.323256 -275.573722) (xy 109.374433 -275.565616) (xy 109.426247 -275.565616)
			(xy 109.477424 -275.573722) (xy 109.526703 -275.589734) (xy 109.57287 -275.613257) (xy 109.614789 -275.643713)
			(xy 109.651427 -275.680351) (xy 109.681883 -275.72227) (xy 109.705406 -275.768437) (xy 109.721418 -275.817716)
			(xy 109.729524 -275.868893) (xy 109.730032 -275.8948) (xy 109.729566 -275.920146) (xy 109.721792 -275.97024)
			(xy 109.706443 -276.018553) (xy 109.683881 -276.063948) (xy 109.654638 -276.105356) (xy 109.619401 -276.1418)
			(xy 109.579002 -276.172421) (xy 109.534392 -276.196499) (xy 109.486623 -276.213466) (xy 109.461808 -276.21865)
			(xy 109.438948 -276.222968) (xy 109.23397 -276.577806) (xy 109.241844 -276.599904) (xy 109.250407 -276.626262)
			(xy 109.259604 -276.680908) (xy 109.260132 -276.708616) (xy 109.259624 -276.734503) (xy 109.251525 -276.785641)
			(xy 109.235526 -276.834881) (xy 109.21202 -276.881013) (xy 109.181588 -276.9229) (xy 109.144978 -276.95951)
			(xy 109.103091 -276.989942) (xy 109.056959 -277.013448) (xy 109.007719 -277.029447) (xy 108.956581 -277.037546)
			(xy 108.904807 -277.037546) (xy 108.853669 -277.029447) (xy 108.804429 -277.013448) (xy 108.758297 -276.989942)
			(xy 108.71641 -276.95951) (xy 108.6798 -276.9229) (xy 108.649368 -276.881013) (xy 108.625862 -276.834881)
			(xy 108.609863 -276.785641) (xy 108.601764 -276.734503) (xy 108.601256 -276.708616) (xy 108.381038 -276.708616)
			(xy 108.381038 -277.091902) (xy 108.381574 -277.107386) (xy 108.390838 -277.136935) (xy 108.408543 -277.162341)
			(xy 108.433057 -277.181263) (xy 108.462119 -277.191957) (xy 108.477558 -277.193248) (xy 108.501611 -277.194917)
			(xy 108.548892 -277.204359) (xy 108.594296 -277.220578) (xy 108.636857 -277.243231) (xy 108.67567 -277.271834)
			(xy 108.709909 -277.30578) (xy 108.7247 -277.32482) (xy 109.136688 -277.32482) (xy 109.15236 -277.304683)
			(xy 109.188869 -277.269036) (xy 109.230434 -277.239439) (xy 109.276062 -277.216599) (xy 109.324665 -277.201063)
			(xy 109.375081 -277.1932) (xy 109.400594 -277.19274) (xy 109.426501 -277.193221) (xy 109.477678 -277.201326)
			(xy 109.526956 -277.217337) (xy 109.573124 -277.24086) (xy 109.615043 -277.271315) (xy 109.651681 -277.307953)
			(xy 109.682137 -277.349871) (xy 109.705661 -277.396038) (xy 109.721672 -277.445316) (xy 109.729778 -277.496493)
			(xy 109.729778 -277.548307) (xy 109.721672 -277.599484) (xy 109.705661 -277.648762) (xy 109.682137 -277.694929)
			(xy 109.651681 -277.736847) (xy 109.615043 -277.773485) (xy 109.573124 -277.80394) (xy 109.526956 -277.827463)
			(xy 109.477678 -277.843474) (xy 109.426501 -277.851579) (xy 109.400594 -277.852124) (xy 109.375082 -277.851647)
			(xy 109.324667 -277.843786) (xy 109.276065 -277.828252) (xy 109.230435 -277.805417) (xy 109.188868 -277.775825)
			(xy 109.152356 -277.740183) (xy 109.136688 -277.720044) (xy 108.7247 -277.720044) (xy 108.709917 -277.739097)
			(xy 108.675703 -277.773079) (xy 108.636897 -277.801708) (xy 108.594331 -277.824369) (xy 108.548914 -277.840578)
			(xy 108.501618 -277.849989) (xy 108.477558 -277.851616) (xy 108.46213 -277.85294) (xy 108.433099 -277.863674)
			(xy 108.408605 -277.882595) (xy 108.390887 -277.907973) (xy 108.381565 -277.937488) (xy 108.381038 -277.952962)
			(xy 108.381038 -280.005028) (xy 108.380424 -280.029984) (xy 108.370683 -280.078936) (xy 108.351581 -280.125048)
			(xy 108.323851 -280.166548) (xy 108.306616 -280.184606) (xy 107.82935 -280.661872) (xy 107.837224 -280.690574)
			(xy 107.842791 -280.712053) (xy 107.848775 -280.756019) (xy 107.849162 -280.778204) (xy 107.848682 -280.803993)
			(xy 107.840613 -280.854937) (xy 107.824674 -280.903991) (xy 107.801257 -280.949947) (xy 107.770939 -280.991675)
			(xy 107.734467 -281.028146) (xy 107.692739 -281.058462) (xy 107.646781 -281.081878) (xy 107.597727 -281.097815)
			(xy 107.546783 -281.105883) (xy 107.520994 -281.106372) (xy 107.498807 -281.106008) (xy 107.454839 -281.100019)
			(xy 107.433364 -281.094434) (xy 107.404662 -281.08656) (xy 106.544364 -281.946858) (xy 106.619802 -282.077668)
			(xy 106.642662 -282.081986) (xy 106.667462 -282.087186) (xy 106.715198 -282.104179) (xy 106.759773 -282.128274)
			(xy 106.800137 -282.158905) (xy 106.83534 -282.195349) (xy 106.864554 -282.23675) (xy 106.887091 -282.282133)
			(xy 106.902421 -282.330428) (xy 106.910182 -282.380501) (xy 106.910632 -282.405836) (xy 106.910122 -282.43173)
			(xy 106.902021 -282.48288) (xy 106.886022 -282.532135) (xy 106.862519 -282.578283) (xy 106.832091 -282.620189)
			(xy 106.795486 -282.656823) (xy 106.753603 -282.687284) (xy 106.707474 -282.710823) (xy 106.658232 -282.72686)
			(xy 106.607088 -282.735002) (xy 106.581194 -282.735528) (xy 106.555515 -282.735044) (xy 106.504776 -282.727091)
			(xy 106.455885 -282.711362) (xy 106.410027 -282.688239) (xy 106.368311 -282.658281) (xy 106.331748 -282.622214)
			(xy 106.301223 -282.580911) (xy 106.277476 -282.535373) (xy 106.261081 -282.486701) (xy 106.256328 -282.461462)
			(xy 106.253493 -282.447854) (xy 106.241546 -282.422769) (xy 106.223279 -282.401833) (xy 106.200044 -282.386598)
			(xy 106.173562 -282.378192) (xy 106.145794 -282.377236) (xy 106.118796 -282.383803) (xy 106.094569 -282.397405)
			(xy 106.08437 -282.406852) (xy 105.93451 -282.556712) (xy 105.930954 -282.563316) (xy 105.919276 -282.583925)
			(xy 105.890919 -282.621865) (xy 105.857422 -282.655356) (xy 105.819477 -282.683707) (xy 105.798874 -282.695396)
			(xy 105.79227 -282.698952) (xy 105.574846 -282.916376) (xy 105.475024 -283.089096) (xy 105.482898 -283.111194)
			(xy 105.491524 -283.137542) (xy 105.500848 -283.192189) (xy 105.50144 -283.219906) (xy 105.500957 -283.245808)
			(xy 105.492849 -283.296973) (xy 105.476832 -283.346239) (xy 105.453303 -283.392391) (xy 105.42284 -283.434291)
			(xy 105.386195 -283.470908) (xy 105.34427 -283.501338) (xy 105.2981 -283.524831) (xy 105.248822 -283.540809)
			(xy 105.19765 -283.548878) (xy 105.171748 -283.549344) (xy 105.146424 -283.548898) (xy 105.096369 -283.541177)
			(xy 105.048088 -283.52588) (xy 105.02519 -283.515054) (xy 104.992424 -283.498798) (xy 104.620314 -283.870908)
			(xy 104.620314 -288.168588) (xy 104.619694 -288.193541) (xy 104.609943 -288.242486) (xy 104.590831 -288.288589)
			(xy 104.563094 -288.330079) (xy 104.545892 -288.348166) (xy 104.077262 -288.816796) (xy 104.083358 -288.844228)
			(xy 104.087233 -288.862204) (xy 104.091432 -288.898739) (xy 104.09174 -288.917126) (xy 104.091256 -288.943027)
			(xy 104.083145 -288.99419) (xy 104.067126 -289.043453) (xy 104.043596 -289.089602) (xy 104.013133 -289.1315)
			(xy 103.976488 -289.168113) (xy 103.934564 -289.198541) (xy 103.888395 -289.222033) (xy 103.839119 -289.23801)
			(xy 103.787949 -289.246078) (xy 103.762048 -289.246564) (xy 103.736753 -289.246138) (xy 103.686747 -289.238477)
			(xy 103.66248 -289.231324) (xy 103.64464 -289.247364) (xy 103.60417 -289.273116) (xy 103.559587 -289.290815)
			(xy 103.512474 -289.299833) (xy 103.48849 -289.300412) (xy 103.401876 -289.300412) (xy 103.386914 -289.300941)
			(xy 103.358274 -289.30961) (xy 103.333369 -289.326198) (xy 103.314332 -289.349285) (xy 103.302793 -289.376894)
			(xy 103.299739 -289.406661) (xy 103.305433 -289.436037) (xy 103.31196 -289.44951) (xy 103.327454 -289.478466)
			(xy 103.351584 -289.483038) (xy 103.3765 -289.488133) (xy 103.424489 -289.504965) (xy 103.469325 -289.528964)
			(xy 103.509945 -289.559562) (xy 103.545387 -289.596032) (xy 103.57481 -289.637512) (xy 103.597516 -289.683016)
			(xy 103.612968 -289.731466) (xy 103.620799 -289.781715) (xy 103.621332 -289.807142) (xy 119.878856 -289.807142)
			(xy 119.879399 -289.781715) (xy 119.887229 -289.731468) (xy 119.90268 -289.683018) (xy 119.925386 -289.637514)
			(xy 119.954808 -289.596036) (xy 119.990248 -289.559565) (xy 120.030867 -289.528967) (xy 120.075701 -289.504967)
			(xy 120.123688 -289.488134) (xy 120.148604 -289.483038) (xy 120.172734 -289.478466) (xy 120.38711 -289.073082)
			(xy 120.377204 -289.050476) (xy 120.368243 -289.029398) (xy 120.355596 -288.985377) (xy 120.349182 -288.940026)
			(xy 120.348756 -288.917126) (xy 120.349264 -288.891219) (xy 120.35737 -288.840042) (xy 120.373382 -288.790763)
			(xy 120.396905 -288.744596) (xy 120.427361 -288.702677) (xy 120.463999 -288.666039) (xy 120.505918 -288.635583)
			(xy 120.552085 -288.61206) (xy 120.601364 -288.596048) (xy 120.652541 -288.587942) (xy 120.704355 -288.587942)
			(xy 120.755532 -288.596048) (xy 120.804811 -288.61206) (xy 120.850978 -288.635583) (xy 120.892897 -288.666039)
			(xy 120.929535 -288.702677) (xy 120.959991 -288.744596) (xy 120.983514 -288.790763) (xy 120.999526 -288.840042)
			(xy 121.007632 -288.891219) (xy 121.00814 -288.917126) (xy 121.007659 -288.942574) (xy 120.999856 -288.992867)
			(xy 120.984408 -289.041361) (xy 120.961683 -289.086901) (xy 120.932222 -289.128403) (xy 120.896727 -289.164878)
			(xy 120.856043 -289.195458) (xy 120.811139 -289.219415) (xy 120.763084 -289.236178) (xy 120.738138 -289.24123)
			(xy 120.714008 -289.245802) (xy 120.499632 -289.651186) (xy 120.509538 -289.673792) (xy 120.518456 -289.694878)
			(xy 120.531008 -289.738907) (xy 120.537342 -289.78425) (xy 120.537732 -289.807142) (xy 120.537224 -289.833029)
			(xy 120.529125 -289.884167) (xy 120.513126 -289.933407) (xy 120.48962 -289.979539) (xy 120.459188 -290.021426)
			(xy 120.422578 -290.058036) (xy 120.380691 -290.088468) (xy 120.334559 -290.111974) (xy 120.285319 -290.127973)
			(xy 120.234181 -290.136072) (xy 120.182407 -290.136072) (xy 120.131269 -290.127973) (xy 120.082029 -290.111974)
			(xy 120.035897 -290.088468) (xy 119.99401 -290.058036) (xy 119.9574 -290.021426) (xy 119.926968 -289.979539)
			(xy 119.903462 -289.933407) (xy 119.887463 -289.884167) (xy 119.879364 -289.833029) (xy 119.878856 -289.807142)
			(xy 103.621332 -289.807142) (xy 103.620824 -289.833029) (xy 103.612725 -289.884167) (xy 103.596726 -289.933407)
			(xy 103.57322 -289.979539) (xy 103.542788 -290.021426) (xy 103.506178 -290.058036) (xy 103.464291 -290.088468)
			(xy 103.418159 -290.111974) (xy 103.368919 -290.127973) (xy 103.317781 -290.136072) (xy 103.266007 -290.136072)
			(xy 103.214869 -290.127973) (xy 103.165629 -290.111974) (xy 103.119497 -290.088468) (xy 103.07761 -290.058036)
			(xy 103.041 -290.021426) (xy 103.010568 -289.979539) (xy 102.987062 -289.933407) (xy 102.971063 -289.884167)
			(xy 102.962964 -289.833029) (xy 102.962456 -289.807142) (xy 102.962835 -289.784209) (xy 102.969164 -289.738781)
			(xy 102.981734 -289.694671) (xy 102.99065 -289.673538) (xy 103.000556 -289.650932) (xy 102.815644 -289.300412)
			(xy 101.522276 -289.300412) (xy 101.507314 -289.300941) (xy 101.478674 -289.30961) (xy 101.453769 -289.326198)
			(xy 101.434732 -289.349285) (xy 101.423193 -289.376894) (xy 101.420139 -289.406661) (xy 101.425833 -289.436037)
			(xy 101.43236 -289.44951) (xy 101.447854 -289.478466) (xy 101.471984 -289.483038) (xy 101.4969 -289.488133)
			(xy 101.544889 -289.504965) (xy 101.589725 -289.528964) (xy 101.630345 -289.559562) (xy 101.665787 -289.596032)
			(xy 101.69521 -289.637512) (xy 101.717916 -289.683016) (xy 101.733368 -289.731466) (xy 101.741199 -289.781715)
			(xy 101.741732 -289.807142) (xy 101.741224 -289.833029) (xy 101.733125 -289.884167) (xy 101.717126 -289.933407)
			(xy 101.69362 -289.979539) (xy 101.663188 -290.021426) (xy 101.626578 -290.058036) (xy 101.584691 -290.088468)
			(xy 101.538559 -290.111974) (xy 101.489319 -290.127973) (xy 101.438181 -290.136072) (xy 101.386407 -290.136072)
			(xy 101.335269 -290.127973) (xy 101.286029 -290.111974) (xy 101.239897 -290.088468) (xy 101.19801 -290.058036)
			(xy 101.1614 -290.021426) (xy 101.130968 -289.979539) (xy 101.107462 -289.933407) (xy 101.091463 -289.884167)
			(xy 101.083364 -289.833029) (xy 101.082856 -289.807142) (xy 101.083235 -289.784209) (xy 101.089564 -289.738781)
			(xy 101.102134 -289.694671) (xy 101.11105 -289.673538) (xy 101.120956 -289.650932) (xy 100.936044 -289.300412)
			(xy 99.642676 -289.300412) (xy 99.627714 -289.300941) (xy 99.599074 -289.30961) (xy 99.574169 -289.326198)
			(xy 99.555132 -289.349285) (xy 99.543593 -289.376894) (xy 99.540539 -289.406661) (xy 99.546233 -289.436037)
			(xy 99.55276 -289.44951) (xy 99.568254 -289.478466) (xy 99.592384 -289.483038) (xy 99.6173 -289.488133)
			(xy 99.665289 -289.504965) (xy 99.710125 -289.528964) (xy 99.750745 -289.559562) (xy 99.786187 -289.596032)
			(xy 99.81561 -289.637512) (xy 99.838316 -289.683016) (xy 99.853768 -289.731466) (xy 99.861599 -289.781715)
			(xy 99.862132 -289.807142) (xy 99.861624 -289.833029) (xy 99.853525 -289.884167) (xy 99.837526 -289.933407)
			(xy 99.81402 -289.979539) (xy 99.783588 -290.021426) (xy 99.746978 -290.058036) (xy 99.705091 -290.088468)
			(xy 99.658959 -290.111974) (xy 99.609719 -290.127973) (xy 99.558581 -290.136072) (xy 99.506807 -290.136072)
			(xy 99.455669 -290.127973) (xy 99.406429 -290.111974) (xy 99.360297 -290.088468) (xy 99.31841 -290.058036)
			(xy 99.2818 -290.021426) (xy 99.251368 -289.979539) (xy 99.227862 -289.933407) (xy 99.211863 -289.884167)
			(xy 99.203764 -289.833029) (xy 99.203256 -289.807142) (xy 99.203635 -289.784209) (xy 99.209964 -289.738781)
			(xy 99.222534 -289.694671) (xy 99.23145 -289.673538) (xy 99.241356 -289.650932) (xy 99.056444 -289.300412)
			(xy 97.763076 -289.300412) (xy 97.748114 -289.300941) (xy 97.719474 -289.30961) (xy 97.694569 -289.326198)
			(xy 97.675532 -289.349285) (xy 97.663993 -289.376894) (xy 97.660939 -289.406661) (xy 97.666633 -289.436037)
			(xy 97.67316 -289.44951) (xy 97.688654 -289.478466) (xy 97.712784 -289.483038) (xy 97.7377 -289.488133)
			(xy 97.785689 -289.504965) (xy 97.830525 -289.528964) (xy 97.871145 -289.559562) (xy 97.906587 -289.596032)
			(xy 97.93601 -289.637512) (xy 97.958716 -289.683016) (xy 97.974168 -289.731466) (xy 97.981999 -289.781715)
			(xy 97.982532 -289.807142) (xy 97.982024 -289.833029) (xy 97.973925 -289.884167) (xy 97.957926 -289.933407)
			(xy 97.93442 -289.979539) (xy 97.903988 -290.021426) (xy 97.867378 -290.058036) (xy 97.825491 -290.088468)
			(xy 97.779359 -290.111974) (xy 97.730119 -290.127973) (xy 97.678981 -290.136072) (xy 97.627207 -290.136072)
			(xy 97.576069 -290.127973) (xy 97.526829 -290.111974) (xy 97.480697 -290.088468) (xy 97.43881 -290.058036)
			(xy 97.4022 -290.021426) (xy 97.371768 -289.979539) (xy 97.348262 -289.933407) (xy 97.332263 -289.884167)
			(xy 97.324164 -289.833029) (xy 97.323656 -289.807142) (xy 97.324035 -289.784209) (xy 97.330364 -289.738781)
			(xy 97.342934 -289.694671) (xy 97.35185 -289.673538) (xy 97.361756 -289.650932) (xy 97.176844 -289.300412)
			(xy 95.883476 -289.300412) (xy 95.868514 -289.300941) (xy 95.839874 -289.30961) (xy 95.814969 -289.326198)
			(xy 95.795932 -289.349285) (xy 95.784393 -289.376894) (xy 95.781339 -289.406661) (xy 95.787033 -289.436037)
			(xy 95.79356 -289.44951) (xy 95.809054 -289.478466) (xy 95.833184 -289.483038) (xy 95.8581 -289.488133)
			(xy 95.906089 -289.504965) (xy 95.950925 -289.528964) (xy 95.991545 -289.559562) (xy 96.026987 -289.596032)
			(xy 96.05641 -289.637512) (xy 96.079116 -289.683016) (xy 96.094568 -289.731466) (xy 96.102399 -289.781715)
			(xy 96.102932 -289.807142) (xy 96.102424 -289.833029) (xy 96.094325 -289.884167) (xy 96.078326 -289.933407)
			(xy 96.05482 -289.979539) (xy 96.024388 -290.021426) (xy 95.987778 -290.058036) (xy 95.945891 -290.088468)
			(xy 95.899759 -290.111974) (xy 95.850519 -290.127973) (xy 95.799381 -290.136072) (xy 95.747607 -290.136072)
			(xy 95.696469 -290.127973) (xy 95.647229 -290.111974) (xy 95.601097 -290.088468) (xy 95.55921 -290.058036)
			(xy 95.5226 -290.021426) (xy 95.492168 -289.979539) (xy 95.468662 -289.933407) (xy 95.452663 -289.884167)
			(xy 95.444564 -289.833029) (xy 95.444056 -289.807142) (xy 95.444435 -289.784209) (xy 95.450764 -289.738781)
			(xy 95.463334 -289.694671) (xy 95.47225 -289.673538) (xy 95.482156 -289.650932) (xy 95.297244 -289.300412)
			(xy 94.003876 -289.300412) (xy 93.988914 -289.300941) (xy 93.960274 -289.30961) (xy 93.935369 -289.326198)
			(xy 93.916332 -289.349285) (xy 93.904793 -289.376894) (xy 93.901739 -289.406661) (xy 93.907433 -289.436037)
			(xy 93.91396 -289.44951) (xy 93.929454 -289.478466) (xy 93.953584 -289.483038) (xy 93.9785 -289.488133)
			(xy 94.026489 -289.504965) (xy 94.071325 -289.528964) (xy 94.111945 -289.559562) (xy 94.147387 -289.596032)
			(xy 94.17681 -289.637512) (xy 94.199516 -289.683016) (xy 94.214968 -289.731466) (xy 94.222799 -289.781715)
			(xy 94.223332 -289.807142) (xy 94.222824 -289.833029) (xy 94.214725 -289.884167) (xy 94.198726 -289.933407)
			(xy 94.17522 -289.979539) (xy 94.144788 -290.021426) (xy 94.108178 -290.058036) (xy 94.066291 -290.088468)
			(xy 94.020159 -290.111974) (xy 93.970919 -290.127973) (xy 93.919781 -290.136072) (xy 93.868007 -290.136072)
			(xy 93.816869 -290.127973) (xy 93.767629 -290.111974) (xy 93.721497 -290.088468) (xy 93.67961 -290.058036)
			(xy 93.643 -290.021426) (xy 93.612568 -289.979539) (xy 93.589062 -289.933407) (xy 93.573063 -289.884167)
			(xy 93.564964 -289.833029) (xy 93.564456 -289.807142) (xy 93.564835 -289.784209) (xy 93.571164 -289.738781)
			(xy 93.583734 -289.694671) (xy 93.59265 -289.673538) (xy 93.602556 -289.650932) (xy 93.417644 -289.300412)
			(xy 92.124276 -289.300412) (xy 92.109314 -289.300941) (xy 92.080674 -289.30961) (xy 92.055769 -289.326198)
			(xy 92.036732 -289.349285) (xy 92.025193 -289.376894) (xy 92.022139 -289.406661) (xy 92.027833 -289.436037)
			(xy 92.03436 -289.44951) (xy 92.049854 -289.478466) (xy 92.073984 -289.483038) (xy 92.0989 -289.488133)
			(xy 92.146889 -289.504965) (xy 92.191725 -289.528964) (xy 92.232345 -289.559562) (xy 92.267787 -289.596032)
			(xy 92.29721 -289.637512) (xy 92.319916 -289.683016) (xy 92.335368 -289.731466) (xy 92.343199 -289.781715)
			(xy 92.343732 -289.807142) (xy 92.343224 -289.833029) (xy 92.335125 -289.884167) (xy 92.319126 -289.933407)
			(xy 92.29562 -289.979539) (xy 92.265188 -290.021426) (xy 92.228578 -290.058036) (xy 92.186691 -290.088468)
			(xy 92.140559 -290.111974) (xy 92.091319 -290.127973) (xy 92.040181 -290.136072) (xy 91.988407 -290.136072)
			(xy 91.937269 -290.127973) (xy 91.888029 -290.111974) (xy 91.841897 -290.088468) (xy 91.80001 -290.058036)
			(xy 91.7634 -290.021426) (xy 91.732968 -289.979539) (xy 91.709462 -289.933407) (xy 91.693463 -289.884167)
			(xy 91.685364 -289.833029) (xy 91.684856 -289.807142) (xy 91.685235 -289.784209) (xy 91.691564 -289.738781)
			(xy 91.704134 -289.694671) (xy 91.71305 -289.673538) (xy 91.722956 -289.650932) (xy 91.538044 -289.300412)
			(xy 80.263492 -289.300412) (xy 72.968358 -296.595546) (xy 72.968358 -297.515026) (xy 88.21548 -297.515026)
			(xy 88.219461 -297.382006) (xy 88.23139 -297.249461) (xy 88.251225 -297.117868) (xy 88.278894 -296.987696)
			(xy 88.314298 -296.859411) (xy 88.357311 -296.733474) (xy 88.407778 -296.610335) (xy 88.465519 -296.490434)
			(xy 88.530328 -296.374201) (xy 88.601972 -296.262051) (xy 88.680194 -296.154387) (xy 88.764715 -296.051594)
			(xy 88.855233 -295.954039) (xy 88.951422 -295.862073) (xy 89.05294 -295.776023) (xy 89.159421 -295.696199)
			(xy 89.270486 -295.622886) (xy 89.385737 -295.556346) (xy 89.504761 -295.496817) (xy 89.627132 -295.444513)
			(xy 89.752411 -295.399621) (xy 89.880152 -295.362302) (xy 90.009895 -295.332689) (xy 90.141177 -295.310888)
			(xy 90.273528 -295.296978) (xy 90.406474 -295.291007) (xy 90.539539 -295.292998) (xy 90.672247 -295.302943)
			(xy 90.804123 -295.320807) (xy 90.934694 -295.346525) (xy 91.063494 -295.380006) (xy 91.19006 -295.42113)
			(xy 91.313941 -295.46975) (xy 91.434692 -295.525691) (xy 91.551882 -295.588753) (xy 91.665091 -295.658711)
			(xy 91.773913 -295.735315) (xy 91.877959 -295.818289) (xy 91.976857 -295.907337) (xy 92.070252 -296.00214)
			(xy 92.15781 -296.102358) (xy 92.239219 -296.207634) (xy 92.314185 -296.31759) (xy 92.382442 -296.431832)
			(xy 92.443744 -296.549952) (xy 92.497873 -296.671527) (xy 92.544634 -296.796121) (xy 92.58386 -296.923289)
			(xy 92.61541 -297.052575) (xy 92.639173 -297.183516) (xy 92.655062 -297.315644) (xy 92.66302 -297.448486)
			(xy 92.663518 -297.515026) (xy 131.195582 -297.515026) (xy 131.199563 -297.382006) (xy 131.211492 -297.249461)
			(xy 131.231327 -297.117868) (xy 131.258996 -296.987696) (xy 131.2944 -296.859411) (xy 131.337413 -296.733474)
			(xy 131.38788 -296.610335) (xy 131.445621 -296.490434) (xy 131.51043 -296.374201) (xy 131.582074 -296.262051)
			(xy 131.660296 -296.154387) (xy 131.744817 -296.051594) (xy 131.835335 -295.954039) (xy 131.931524 -295.862073)
			(xy 132.033042 -295.776023) (xy 132.139523 -295.696199) (xy 132.250588 -295.622886) (xy 132.365839 -295.556346)
			(xy 132.484863 -295.496817) (xy 132.607234 -295.444513) (xy 132.732513 -295.399621) (xy 132.860254 -295.362302)
			(xy 132.989997 -295.332689) (xy 133.121279 -295.310888) (xy 133.25363 -295.296978) (xy 133.386576 -295.291007)
			(xy 133.519641 -295.292998) (xy 133.652349 -295.302943) (xy 133.784225 -295.320807) (xy 133.914796 -295.346525)
			(xy 134.043596 -295.380006) (xy 134.170162 -295.42113) (xy 134.294043 -295.46975) (xy 134.414794 -295.525691)
			(xy 134.531984 -295.588753) (xy 134.645193 -295.658711) (xy 134.754015 -295.735315) (xy 134.858061 -295.818289)
			(xy 134.956959 -295.907337) (xy 135.050354 -296.00214) (xy 135.137912 -296.102358) (xy 135.219321 -296.207634)
			(xy 135.294287 -296.31759) (xy 135.362544 -296.431832) (xy 135.423846 -296.549952) (xy 135.477975 -296.671527)
			(xy 135.524736 -296.796121) (xy 135.563962 -296.923289) (xy 135.595512 -297.052575) (xy 135.619275 -297.183516)
			(xy 135.635164 -297.315644) (xy 135.643122 -297.448486) (xy 135.64362 -297.515026) (xy 135.643122 -297.581566)
			(xy 135.635164 -297.714408) (xy 135.619275 -297.846536) (xy 135.595512 -297.977477) (xy 135.563962 -298.106763)
			(xy 135.524736 -298.233931) (xy 135.477975 -298.358525) (xy 135.423846 -298.4801) (xy 135.362544 -298.59822)
			(xy 135.294287 -298.712462) (xy 135.219321 -298.822418) (xy 135.137912 -298.927694) (xy 135.050354 -299.027912)
			(xy 134.956959 -299.122715) (xy 134.858061 -299.211763) (xy 134.754015 -299.294737) (xy 134.645193 -299.371341)
			(xy 134.531984 -299.441299) (xy 134.414794 -299.504361) (xy 134.294043 -299.560302) (xy 134.170162 -299.608922)
			(xy 134.043596 -299.650046) (xy 133.914796 -299.683527) (xy 133.784225 -299.709245) (xy 133.652349 -299.727109)
			(xy 133.519641 -299.737054) (xy 133.386576 -299.739045) (xy 133.25363 -299.733074) (xy 133.121279 -299.719164)
			(xy 132.989997 -299.697363) (xy 132.860254 -299.66775) (xy 132.732513 -299.630431) (xy 132.607234 -299.585539)
			(xy 132.484863 -299.533235) (xy 132.365839 -299.473706) (xy 132.250588 -299.407166) (xy 132.139523 -299.333853)
			(xy 132.033042 -299.254029) (xy 131.931524 -299.167979) (xy 131.835335 -299.076013) (xy 131.744817 -298.978458)
			(xy 131.660296 -298.875665) (xy 131.582074 -298.768001) (xy 131.51043 -298.655851) (xy 131.445621 -298.539618)
			(xy 131.38788 -298.419717) (xy 131.337413 -298.296578) (xy 131.2944 -298.170641) (xy 131.258996 -298.042356)
			(xy 131.231327 -297.912184) (xy 131.211492 -297.780591) (xy 131.199563 -297.648046) (xy 131.195582 -297.515026)
			(xy 92.663518 -297.515026) (xy 92.66302 -297.581566) (xy 92.655062 -297.714408) (xy 92.639173 -297.846536)
			(xy 92.61541 -297.977477) (xy 92.58386 -298.106763) (xy 92.544634 -298.233931) (xy 92.497873 -298.358525)
			(xy 92.443744 -298.4801) (xy 92.382442 -298.59822) (xy 92.314185 -298.712462) (xy 92.239219 -298.822418)
			(xy 92.15781 -298.927694) (xy 92.070252 -299.027912) (xy 91.976857 -299.122715) (xy 91.877959 -299.211763)
			(xy 91.773913 -299.294737) (xy 91.665091 -299.371341) (xy 91.551882 -299.441299) (xy 91.434692 -299.504361)
			(xy 91.313941 -299.560302) (xy 91.19006 -299.608922) (xy 91.063494 -299.650046) (xy 90.934694 -299.683527)
			(xy 90.804123 -299.709245) (xy 90.672247 -299.727109) (xy 90.539539 -299.737054) (xy 90.406474 -299.739045)
			(xy 90.273528 -299.733074) (xy 90.141177 -299.719164) (xy 90.009895 -299.697363) (xy 89.880152 -299.66775)
			(xy 89.752411 -299.630431) (xy 89.627132 -299.585539) (xy 89.504761 -299.533235) (xy 89.385737 -299.473706)
			(xy 89.270486 -299.407166) (xy 89.159421 -299.333853) (xy 89.05294 -299.254029) (xy 88.951422 -299.167979)
			(xy 88.855233 -299.076013) (xy 88.764715 -298.978458) (xy 88.680194 -298.875665) (xy 88.601972 -298.768001)
			(xy 88.530328 -298.655851) (xy 88.465519 -298.539618) (xy 88.407778 -298.419717) (xy 88.357311 -298.296578)
			(xy 88.314298 -298.170641) (xy 88.278894 -298.042356) (xy 88.251225 -297.912184) (xy 88.23139 -297.780591)
			(xy 88.219461 -297.648046) (xy 88.21548 -297.515026) (xy 72.968358 -297.515026) (xy 72.968358 -333.883254)
			(xy 73.295256 -334.210152) (xy 75.95616 -334.210152)
		)
		(stroke
			(width 0)
			(type solid)
		)
		(fill yes)
		(layer "In8.Cu")
		(net "PVCCIN_CPU1")
	)
)
